(kicad_pcb
	(version 20260206)
	(generator "pcbnew")
	(generator_version "10.0")
	(general
		(thickness 1.6)
		(legacy_teardrops no)
	)
	(paper "A4")
	(layers
		(0 "F.Cu" signal "TOP")
		(4 "In1.Cu" signal "GND")
		(6 "In2.Cu" signal "IN1")
		(8 "In3.Cu" signal "GND1")
		(10 "In4.Cu" signal "IN2")
		(12 "In5.Cu" signal "GND2")
		(14 "In6.Cu" signal "IN3")
		(16 "In7.Cu" signal "GND3")
		(18 "In8.Cu" signal "VCC")
		(20 "In9.Cu" signal "VCC1")
		(22 "In10.Cu" signal "GND4")
		(24 "In11.Cu" signal "IN4")
		(26 "In12.Cu" signal "GND5")
		(28 "In13.Cu" signal "IN5")
		(30 "In14.Cu" signal "GND6")
		(32 "In15.Cu" signal "IN6")
		(34 "In16.Cu" signal "GND7")
		(2 "B.Cu" signal "BOTTOM")
		(9 "F.Adhes" user "F.Adhesive")
		(11 "B.Adhes" user "B.Adhesive")
		(13 "F.Paste" user "Package Geometry/Pastemask Top")
		(15 "B.Paste" user "Package Geometry/Pastemask Bottom")
		(5 "F.SilkS" user "Ref Des/Silkscreen Top")
		(7 "B.SilkS" user "Ref Des/Silkscreen Bottom")
		(1 "F.Mask" user "Board Geometry/Soldermask Top")
		(3 "B.Mask" user "Board Geometry/Soldermask Bottom")
		(17 "Dwgs.User" user "User.Drawings")
		(19 "Cmts.User" user "User.Comments")
		(21 "Eco1.User" user "User.Eco1")
		(23 "Eco2.User" user "User.Eco2")
		(25 "Edge.Cuts" user "Board Geometry/Outline")
		(27 "Margin" user)
		(31 "F.CrtYd" user "Package Geometry/Place Bound Top")
		(29 "B.CrtYd" user "Package Geometry/Place Bound Bottom")
		(35 "F.Fab" user "Ref Des/Assembly Top")
		(33 "B.Fab" user "Ref Des/Assembly Bottom")
	)
	(setup
		(pad_to_mask_clearance 0)
		(allow_soldermask_bridges_in_footprints no)
		(tenting
			(front yes)
			(back yes)
		)
		(covering
			(front no)
			(back no)
		)
		(plugging
			(front no)
			(back no)
		)
		(capping no)
		(filling no)
		(pcbplotparams
			(layerselection 0x00000000_00000000_55555555_5755f5ff)
			(plot_on_all_layers_selection 0x00000000_00000000_00000000_00000000)
			(disableapertmacros no)
			(usegerberextensions no)
			(usegerberattributes yes)
			(usegerberadvancedattributes yes)
			(creategerberjobfile yes)
			(dashed_line_dash_ratio 12)
			(dashed_line_gap_ratio 3)
			(svgprecision 4)
			(plotframeref no)
			(mode 1)
			(useauxorigin no)
			(pdf_front_fp_property_popups yes)
			(pdf_back_fp_property_popups yes)
			(pdf_metadata yes)
			(pdf_single_document no)
			(dxfpolygonmode yes)
			(dxfimperialunits yes)
			(dxfusepcbnewfont yes)
			(psnegative no)
			(psa4output no)
			(plot_black_and_white yes)
			(sketchpadsonfab no)
			(plotpadnumbers no)
			(hidednponfab no)
			(sketchdnponfab yes)
			(crossoutdnponfab yes)
			(subtractmaskfromsilk no)
			(outputformat 1)
			(mirror no)
			(drillshape 1)
			(scaleselection 1)
			(outputdirectory "")
		)
	)
	(gr_poly
		(pts
			(xy 194.445128 -441.480956) (xy 194.455142 -441.480531) (xy 194.473642 -441.472854) (xy 194.487795 -441.458682)
			(xy 194.495445 -441.440171) (xy 194.495928 -441.430156) (xy 194.495928 -441.17006) (xy 194.49641 -441.126022)
			(xy 194.50409 -441.03828) (xy 194.519387 -440.951542) (xy 194.542185 -440.866466) (xy 194.572311 -440.783702)
			(xy 194.609536 -440.703878) (xy 194.653576 -440.627602) (xy 194.704095 -440.555454) (xy 194.760711 -440.487984)
			(xy 194.822991 -440.425704) (xy 194.890462 -440.369089) (xy 194.96261 -440.31857) (xy 195.038887 -440.274531)
			(xy 195.118711 -440.237308) (xy 195.201476 -440.207182) (xy 195.286551 -440.184385) (xy 195.37329 -440.169088)
			(xy 195.461032 -440.16141) (xy 195.50507 -440.160918) (xy 276.314916 -440.160918) (xy 276.358955 -440.161399)
			(xy 276.446699 -440.169077) (xy 276.533439 -440.184372) (xy 276.618516 -440.207169) (xy 276.701283 -440.237294)
			(xy 276.781109 -440.274518) (xy 276.857388 -440.318557) (xy 276.929538 -440.369076) (xy 276.99701 -440.425692)
			(xy 277.059292 -440.487972) (xy 277.115909 -440.555443) (xy 277.16643 -440.627592) (xy 277.210471 -440.703869)
			(xy 277.247697 -440.783695) (xy 277.277823 -440.866461) (xy 277.300622 -440.951538) (xy 277.31592 -441.038278)
			(xy 277.3236 -441.126021) (xy 277.324058 -441.17006) (xy 277.324058 -441.430156) (xy 277.324469 -441.440186)
			(xy 277.33213 -441.458725) (xy 277.346302 -441.472922) (xy 277.364828 -441.480614) (xy 277.374858 -441.480956)
			(xy 463.300064 -441.480956) (xy 463.355834 -441.480449) (xy 463.467062 -441.472116) (xy 463.577357 -441.455494)
			(xy 463.686101 -441.430676) (xy 463.792686 -441.397801) (xy 463.896517 -441.357052) (xy 463.997011 -441.308658)
			(xy 464.093608 -441.252889) (xy 464.185768 -441.190057) (xy 464.272974 -441.120513) (xy 464.354739 -441.044647)
			(xy 464.430606 -440.962883) (xy 464.50015 -440.875677) (xy 464.562982 -440.783519) (xy 464.618752 -440.686922)
			(xy 464.667147 -440.586428) (xy 464.707897 -440.482598) (xy 464.740773 -440.376013) (xy 464.765592 -440.267269)
			(xy 464.782215 -440.156974) (xy 464.790548 -440.045746) (xy 464.791044 -439.989976) (xy 464.791044 -409.528264)
			(xy 464.791546 -409.457891) (xy 464.799454 -409.317366) (xy 464.815227 -409.177505) (xy 464.838815 -409.038749)
			(xy 464.870143 -408.901532) (xy 464.909113 -408.766288) (xy 464.955604 -408.633441) (xy 465.009467 -408.503408)
			(xy 465.070535 -408.376599) (xy 465.138615 -408.253413) (xy 465.213493 -408.134236) (xy 465.294933 -408.019444)
			(xy 465.38268 -407.909398) (xy 465.476458 -407.804443) (xy 465.525866 -407.754328) (xy 467.354412 -405.925782)
			(xy 467.391703 -405.887819) (xy 467.461396 -405.807388) (xy 467.525176 -405.722192) (xy 467.582717 -405.632663)
			(xy 467.633725 -405.539259) (xy 467.677942 -405.442454) (xy 467.715142 -405.342742) (xy 467.745135 -405.240631)
			(xy 467.767768 -405.136641) (xy 467.782928 -405.031301) (xy 467.790535 -404.925148) (xy 467.791038 -404.871936)
			(xy 467.791038 -82.82813) (xy 467.791541 -82.757757) (xy 467.799451 -82.617233) (xy 467.815226 -82.477373)
			(xy 467.838815 -82.338618) (xy 467.870145 -82.201402) (xy 467.909116 -82.066159) (xy 467.955608 -81.933313)
			(xy 468.009473 -81.803282) (xy 468.070541 -81.676474) (xy 468.138622 -81.553289) (xy 468.213501 -81.434114)
			(xy 468.294942 -81.319323) (xy 468.382689 -81.209278) (xy 468.476467 -81.104324) (xy 468.52586 -81.054194)
			(xy 470.854278 -78.725776) (xy 470.891569 -78.687813) (xy 470.961264 -78.607383) (xy 471.025045 -78.522187)
			(xy 471.082586 -78.432659) (xy 471.133596 -78.339255) (xy 471.177813 -78.24245) (xy 471.215013 -78.142738)
			(xy 471.245007 -78.040626) (xy 471.267641 -77.936636) (xy 471.2828 -77.831296) (xy 471.290407 -77.725143)
			(xy 471.290904 -77.67193) (xy 471.290904 -13.780008) (xy 471.290383 -13.724238) (xy 471.282048 -13.613011)
			(xy 471.265425 -13.502718) (xy 471.240606 -13.393975) (xy 471.20773 -13.287391) (xy 471.166981 -13.183562)
			(xy 471.118587 -13.083068) (xy 471.062818 -12.986472) (xy 470.999987 -12.894314) (xy 470.930444 -12.807108)
			(xy 470.854579 -12.725344) (xy 470.772816 -12.649477) (xy 470.685612 -12.579932) (xy 470.593455 -12.517099)
			(xy 470.49686 -12.461328) (xy 470.396367 -12.412932) (xy 470.292539 -12.372181) (xy 470.185956 -12.339303)
			(xy 470.077214 -12.314481) (xy 469.966921 -12.297855) (xy 469.855694 -12.289518) (xy 469.799924 -12.289028)
			(xy 458.20203 -12.289028) (xy 458.131647 -12.288544) (xy 457.991102 -12.280653) (xy 457.85122 -12.264894)
			(xy 457.712443 -12.241316) (xy 457.575205 -12.209994) (xy 457.43994 -12.171027) (xy 457.307072 -12.124536)
			(xy 457.177021 -12.070668) (xy 457.050194 -12.009593) (xy 456.926991 -11.941503) (xy 456.8078 -11.866612)
			(xy 456.692996 -11.785156) (xy 456.582939 -11.69739) (xy 456.477977 -11.603592) (xy 456.378439 -11.504056)
			(xy 456.284639 -11.399096) (xy 456.196872 -11.289041) (xy 456.115413 -11.174238) (xy 456.04052 -11.055048)
			(xy 455.972428 -10.931847) (xy 455.911351 -10.805021) (xy 455.857481 -10.674971) (xy 455.810987 -10.542104)
			(xy 455.772017 -10.406839) (xy 455.740693 -10.269603) (xy 455.717113 -10.130825) (xy 455.701351 -9.990944)
			(xy 455.693457 -9.850399) (xy 455.693018 -9.780016) (xy 455.693018 -0.559816) (xy 455.692533 -0.549805)
			(xy 455.684877 -0.531304) (xy 455.670724 -0.517142) (xy 455.652229 -0.509474) (xy 455.642218 -0.509016)
			(xy 388.161784 -0.509016) (xy 388.15178 -0.509507) (xy 388.133296 -0.51717) (xy 388.119152 -0.531323)
			(xy 388.111501 -0.549811) (xy 388.110984 -0.559816) (xy 388.110984 -5.169916) (xy 388.849623 -5.169916)
			(xy 388.85363 -5.081961) (xy 388.865619 -4.994736) (xy 388.88549 -4.908962) (xy 388.913078 -4.82535)
			(xy 388.948156 -4.744593) (xy 388.990432 -4.667361) (xy 389.039555 -4.594293) (xy 389.09512 -4.525995)
			(xy 389.156665 -4.463033) (xy 389.223681 -4.405928) (xy 389.295611 -4.355154) (xy 389.371861 -4.311131)
			(xy 389.451799 -4.274224) (xy 389.534761 -4.244739) (xy 389.62006 -4.222921) (xy 389.70699 -4.20895)
			(xy 389.794831 -4.202941) (xy 389.882854 -4.204945) (xy 389.97033 -4.214946) (xy 390.056534 -4.232859)
			(xy 390.140752 -4.258537) (xy 390.222286 -4.291767) (xy 390.300461 -4.332274) (xy 390.374628 -4.379722)
			(xy 390.444173 -4.433717) (xy 390.50852 -4.493813) (xy 390.567136 -4.559512) (xy 390.619534 -4.630268)
			(xy 390.665281 -4.705496) (xy 390.703998 -4.784572) (xy 390.735364 -4.866842) (xy 390.759118 -4.951623)
			(xy 390.766309 -4.990667) (xy 394.939038 -4.990667) (xy 394.939038 -4.936133) (xy 394.946799 -4.882155)
			(xy 394.962162 -4.82983) (xy 394.984815 -4.780224) (xy 395.014296 -4.734346) (xy 395.050007 -4.693131)
			(xy 395.091219 -4.657417) (xy 395.137094 -4.627931) (xy 395.186698 -4.605274) (xy 395.239021 -4.589906)
			(xy 395.292999 -4.582141) (xy 395.320266 -4.581652) (xy 396.183866 -4.581652) (xy 396.21114 -4.582085)
			(xy 396.265132 -4.589844) (xy 396.317471 -4.605208) (xy 396.36709 -4.627864) (xy 396.41298 -4.657352)
			(xy 396.454205 -4.693071) (xy 396.489928 -4.734293) (xy 396.51942 -4.78018) (xy 396.542081 -4.829797)
			(xy 396.557449 -4.882135) (xy 396.565212 -4.936126) (xy 396.565212 -4.99067) (xy 398.538915 -4.99067)
			(xy 398.538915 -4.93613) (xy 398.546678 -4.882144) (xy 398.562044 -4.829813) (xy 398.584701 -4.780201)
			(xy 398.614188 -4.734318) (xy 398.649905 -4.6931) (xy 398.691125 -4.657383) (xy 398.737008 -4.627897)
			(xy 398.78662 -4.605241) (xy 398.838952 -4.589876) (xy 398.892938 -4.582115) (xy 398.920208 -4.581652)
			(xy 399.783808 -4.581652) (xy 399.811078 -4.582111) (xy 399.865063 -4.589874) (xy 399.917393 -4.60524)
			(xy 399.967004 -4.627898) (xy 400.012886 -4.657385) (xy 400.054104 -4.693102) (xy 400.08982 -4.734321)
			(xy 400.119306 -4.780203) (xy 400.141962 -4.829814) (xy 400.157328 -4.882145) (xy 400.16509 -4.93613)
			(xy 400.16509 -4.990666) (xy 402.138938 -4.990666) (xy 402.138938 -4.936134) (xy 402.146698 -4.882157)
			(xy 402.162061 -4.829833) (xy 402.184712 -4.780228) (xy 402.214192 -4.734351) (xy 402.249901 -4.693136)
			(xy 402.291111 -4.657422) (xy 402.336984 -4.627936) (xy 402.386586 -4.605278) (xy 402.438908 -4.589909)
			(xy 402.492884 -4.582142) (xy 402.52015 -4.581652) (xy 403.38375 -4.581652) (xy 403.411024 -4.582084)
			(xy 403.465019 -4.589841) (xy 403.517359 -4.605203) (xy 403.56698 -4.627859) (xy 403.612872 -4.657346)
			(xy 403.6541 -4.693065) (xy 403.689824 -4.734288) (xy 403.719317 -4.780176) (xy 403.741979 -4.829794)
			(xy 403.757349 -4.882132) (xy 403.765112 -4.936126) (xy 403.765112 -4.990672) (xy 405.739016 -4.990672)
			(xy 405.739016 -4.936128) (xy 405.746779 -4.882139) (xy 405.762147 -4.829805) (xy 405.784807 -4.78019)
			(xy 405.814298 -4.734306) (xy 405.850019 -4.693086) (xy 405.891243 -4.65737) (xy 405.937131 -4.627885)
			(xy 405.986748 -4.605231) (xy 406.039084 -4.589869) (xy 406.093074 -4.582112) (xy 406.120346 -4.581652)
			(xy 406.983946 -4.581652) (xy 407.011214 -4.582114) (xy 407.065195 -4.589881) (xy 407.117521 -4.605251)
			(xy 407.167127 -4.62791) (xy 407.213004 -4.657399) (xy 407.254217 -4.693115) (xy 407.289929 -4.734333)
			(xy 407.319412 -4.780213) (xy 407.342065 -4.829822) (xy 407.357429 -4.88215) (xy 407.36519 -4.936132)
			(xy 407.36519 -4.990668) (xy 407.36519 -4.99067) (xy 414.849015 -4.99067) (xy 414.849015 -4.93613)
			(xy 414.856778 -4.882144) (xy 414.872144 -4.829812) (xy 414.894801 -4.7802) (xy 414.924289 -4.734318)
			(xy 414.960006 -4.693099) (xy 415.001226 -4.657383) (xy 415.047109 -4.627896) (xy 415.096722 -4.60524)
			(xy 415.149054 -4.589875) (xy 415.20304 -4.582115) (xy 415.23031 -4.581652) (xy 416.09391 -4.581652)
			(xy 416.12118 -4.582111) (xy 416.175164 -4.589874) (xy 416.227495 -4.605241) (xy 416.277105 -4.627899)
			(xy 416.322987 -4.657386) (xy 416.364205 -4.693102) (xy 416.39992 -4.734321) (xy 416.429406 -4.780203)
			(xy 416.452062 -4.829815) (xy 416.467428 -4.882145) (xy 416.47519 -4.93613) (xy 416.47519 -4.990666)
			(xy 418.449038 -4.990666) (xy 418.449038 -4.936134) (xy 418.456798 -4.882156) (xy 418.472161 -4.829833)
			(xy 418.494813 -4.780227) (xy 418.524293 -4.734351) (xy 418.560002 -4.693136) (xy 418.601212 -4.657422)
			(xy 418.647085 -4.627936) (xy 418.696688 -4.605278) (xy 418.749009 -4.589909) (xy 418.802986 -4.582142)
			(xy 418.830252 -4.581652) (xy 419.693852 -4.581652) (xy 419.721126 -4.582084) (xy 419.77512 -4.589841)
			(xy 419.827461 -4.605204) (xy 419.877082 -4.627859) (xy 419.922973 -4.657347) (xy 419.9642 -4.693066)
			(xy 419.999924 -4.734288) (xy 420.029418 -4.780176) (xy 420.052079 -4.829794) (xy 420.067449 -4.882133)
			(xy 420.075212 -4.936126) (xy 420.075212 -4.990672) (xy 426.059016 -4.990672) (xy 426.059016 -4.936128)
			(xy 426.066779 -4.882139) (xy 426.082147 -4.829805) (xy 426.104807 -4.78019) (xy 426.134298 -4.734306)
			(xy 426.170019 -4.693086) (xy 426.211243 -4.65737) (xy 426.257131 -4.627885) (xy 426.306748 -4.605231)
			(xy 426.359084 -4.589869) (xy 426.413074 -4.582112) (xy 426.440346 -4.581652) (xy 427.303946 -4.581652)
			(xy 427.331214 -4.582114) (xy 427.385195 -4.589881) (xy 427.437521 -4.605251) (xy 427.487127 -4.62791)
			(xy 427.533004 -4.657399) (xy 427.574217 -4.693115) (xy 427.609929 -4.734333) (xy 427.639412 -4.780213)
			(xy 427.662065 -4.829822) (xy 427.677429 -4.88215) (xy 427.68519 -4.936132) (xy 427.68519 -4.990668)
			(xy 429.659038 -4.990668) (xy 429.659038 -4.936132) (xy 429.666799 -4.882152) (xy 429.682164 -4.829825)
			(xy 429.704818 -4.780217) (xy 429.734302 -4.734339) (xy 429.770014 -4.693123) (xy 429.811229 -4.657409)
			(xy 429.857107 -4.627924) (xy 429.906714 -4.605268) (xy 429.95904 -4.589902) (xy 430.01302 -4.582139)
			(xy 430.040288 -4.581652) (xy 430.903888 -4.581652) (xy 430.931161 -4.582087) (xy 430.985151 -4.589848)
			(xy 431.037487 -4.605214) (xy 431.087103 -4.627871) (xy 431.13299 -4.65736) (xy 431.174213 -4.693078)
			(xy 431.209933 -4.7343) (xy 431.239423 -4.780186) (xy 431.262082 -4.829802) (xy 431.27745 -4.882138)
			(xy 431.285212 -4.936127) (xy 431.285212 -4.990673) (xy 431.27745 -5.044662) (xy 431.262082 -5.096998)
			(xy 431.239423 -5.146614) (xy 431.209933 -5.1925) (xy 431.174213 -5.233722) (xy 431.13299 -5.26944)
			(xy 431.087103 -5.298929) (xy 431.037487 -5.321586) (xy 430.985151 -5.336952) (xy 430.931161 -5.344713)
			(xy 430.903888 -5.345176) (xy 430.040288 -5.345176) (xy 430.01302 -5.344661) (xy 429.95904 -5.336898)
			(xy 429.906714 -5.321532) (xy 429.857107 -5.298876) (xy 429.811229 -5.269391) (xy 429.770014 -5.233677)
			(xy 429.734302 -5.192461) (xy 429.704818 -5.146583) (xy 429.682164 -5.096975) (xy 429.666799 -5.044648)
			(xy 429.659038 -4.990668) (xy 427.68519 -4.990668) (xy 427.677429 -5.04465) (xy 427.662065 -5.096978)
			(xy 427.639412 -5.146587) (xy 427.609929 -5.192467) (xy 427.574217 -5.233685) (xy 427.533004 -5.269401)
			(xy 427.487127 -5.29889) (xy 427.437521 -5.321549) (xy 427.385195 -5.336919) (xy 427.331214 -5.344686)
			(xy 427.303946 -5.345176) (xy 426.440346 -5.345176) (xy 426.413074 -5.344688) (xy 426.359084 -5.336931)
			(xy 426.306748 -5.321569) (xy 426.257131 -5.298915) (xy 426.211243 -5.26943) (xy 426.170019 -5.233714)
			(xy 426.134298 -5.192494) (xy 426.104807 -5.14661) (xy 426.082147 -5.096995) (xy 426.066779 -5.044661)
			(xy 426.059016 -4.990672) (xy 420.075212 -4.990672) (xy 420.075212 -4.990674) (xy 420.067449 -5.044667)
			(xy 420.052079 -5.097006) (xy 420.029418 -5.146624) (xy 419.999924 -5.192512) (xy 419.9642 -5.233734)
			(xy 419.922973 -5.269453) (xy 419.877082 -5.298941) (xy 419.827461 -5.321596) (xy 419.77512 -5.336959)
			(xy 419.721126 -5.344716) (xy 419.693852 -5.345176) (xy 418.830252 -5.345176) (xy 418.802986 -5.344658)
			(xy 418.749009 -5.336891) (xy 418.696688 -5.321522) (xy 418.647085 -5.298864) (xy 418.601212 -5.269378)
			(xy 418.560002 -5.233664) (xy 418.524293 -5.192449) (xy 418.494813 -5.146573) (xy 418.472161 -5.096967)
			(xy 418.456798 -5.044644) (xy 418.449038 -4.990666) (xy 416.47519 -4.990666) (xy 416.47519 -4.99067)
			(xy 416.467428 -5.044655) (xy 416.452062 -5.096985) (xy 416.429406 -5.146597) (xy 416.39992 -5.192479)
			(xy 416.364205 -5.233698) (xy 416.322987 -5.269414) (xy 416.277105 -5.298901) (xy 416.227495 -5.321559)
			(xy 416.175164 -5.336926) (xy 416.12118 -5.344689) (xy 416.09391 -5.345176) (xy 415.23031 -5.345176)
			(xy 415.20304 -5.344685) (xy 415.149054 -5.336925) (xy 415.096722 -5.32156) (xy 415.047109 -5.298904)
			(xy 415.001226 -5.269417) (xy 414.960006 -5.233701) (xy 414.924289 -5.192482) (xy 414.894801 -5.1466)
			(xy 414.872144 -5.096988) (xy 414.856778 -5.044656) (xy 414.849015 -4.99067) (xy 407.36519 -4.99067)
			(xy 407.357429 -5.04465) (xy 407.342065 -5.096978) (xy 407.319412 -5.146587) (xy 407.289929 -5.192467)
			(xy 407.254217 -5.233685) (xy 407.213004 -5.269401) (xy 407.167127 -5.29889) (xy 407.117521 -5.321549)
			(xy 407.065195 -5.336919) (xy 407.011214 -5.344686) (xy 406.983946 -5.345176) (xy 406.120346 -5.345176)
			(xy 406.093074 -5.344688) (xy 406.039084 -5.336931) (xy 405.986748 -5.321569) (xy 405.937131 -5.298915)
			(xy 405.891243 -5.26943) (xy 405.850019 -5.233714) (xy 405.814298 -5.192494) (xy 405.784807 -5.14661)
			(xy 405.762147 -5.096995) (xy 405.746779 -5.044661) (xy 405.739016 -4.990672) (xy 403.765112 -4.990672)
			(xy 403.765112 -4.990674) (xy 403.757349 -5.044668) (xy 403.741979 -5.097006) (xy 403.719317 -5.146624)
			(xy 403.689824 -5.192512) (xy 403.6541 -5.233735) (xy 403.612872 -5.269454) (xy 403.56698 -5.298941)
			(xy 403.517359 -5.321597) (xy 403.465019 -5.336959) (xy 403.411024 -5.344716) (xy 403.38375 -5.345176)
			(xy 402.52015 -5.345176) (xy 402.492884 -5.344658) (xy 402.438908 -5.336891) (xy 402.386586 -5.321522)
			(xy 402.336984 -5.298864) (xy 402.291111 -5.269378) (xy 402.249901 -5.233664) (xy 402.214192 -5.192449)
			(xy 402.184712 -5.146572) (xy 402.162061 -5.096967) (xy 402.146698 -5.044643) (xy 402.138938 -4.990666)
			(xy 400.16509 -4.990666) (xy 400.16509 -4.99067) (xy 400.157328 -5.044655) (xy 400.141962 -5.096986)
			(xy 400.119306 -5.146597) (xy 400.08982 -5.192479) (xy 400.054104 -5.233698) (xy 400.012886 -5.269415)
			(xy 399.967004 -5.298902) (xy 399.917393 -5.32156) (xy 399.865063 -5.336926) (xy 399.811078 -5.344689)
			(xy 399.783808 -5.345176) (xy 398.920208 -5.345176) (xy 398.892938 -5.344685) (xy 398.838952 -5.336924)
			(xy 398.78662 -5.321559) (xy 398.737008 -5.298903) (xy 398.691125 -5.269417) (xy 398.649905 -5.2337)
			(xy 398.614188 -5.192482) (xy 398.584701 -5.146599) (xy 398.562044 -5.096987) (xy 398.546678 -5.044656)
			(xy 398.538915 -4.99067) (xy 396.565212 -4.99067) (xy 396.565212 -4.990674) (xy 396.557449 -5.044665)
			(xy 396.542081 -5.097003) (xy 396.51942 -5.14662) (xy 396.489928 -5.192507) (xy 396.454205 -5.233729)
			(xy 396.41298 -5.269448) (xy 396.36709 -5.298936) (xy 396.317471 -5.321592) (xy 396.265132 -5.336956)
			(xy 396.21114 -5.344715) (xy 396.183866 -5.345176) (xy 395.320266 -5.345176) (xy 395.292999 -5.344659)
			(xy 395.239021 -5.336894) (xy 395.186698 -5.321526) (xy 395.137094 -5.298869) (xy 395.091219 -5.269383)
			(xy 395.050007 -5.233669) (xy 395.014296 -5.192454) (xy 394.984815 -5.146576) (xy 394.962162 -5.09697)
			(xy 394.946799 -5.044645) (xy 394.939038 -4.990667) (xy 390.766309 -4.990667) (xy 390.775065 -5.038212)
			(xy 390.783071 -5.125893) (xy 390.783572 -5.169916) (xy 390.783071 -5.213939) (xy 390.775065 -5.30162)
			(xy 390.759118 -5.388209) (xy 390.735364 -5.47299) (xy 390.703998 -5.55526) (xy 390.665281 -5.634336)
			(xy 390.619534 -5.709564) (xy 390.567136 -5.78032) (xy 390.50852 -5.846019) (xy 390.444173 -5.906115)
			(xy 390.374628 -5.96011) (xy 390.300461 -6.007558) (xy 390.222286 -6.048065) (xy 390.140752 -6.081295)
			(xy 390.056534 -6.106973) (xy 389.97033 -6.124886) (xy 389.882854 -6.134887) (xy 389.794831 -6.136891)
			(xy 389.70699 -6.130882) (xy 389.62006 -6.116911) (xy 389.534761 -6.095093) (xy 389.451799 -6.065608)
			(xy 389.371861 -6.028701) (xy 389.295611 -5.984678) (xy 389.223681 -5.933904) (xy 389.156665 -5.876799)
			(xy 389.09512 -5.813837) (xy 389.039555 -5.745539) (xy 388.990432 -5.672471) (xy 388.948156 -5.595239)
			(xy 388.913078 -5.514482) (xy 388.88549 -5.43087) (xy 388.865619 -5.345096) (xy 388.85363 -5.257871)
			(xy 388.849623 -5.169916) (xy 388.110984 -5.169916) (xy 388.110984 -6.169914) (xy 453.015103 -6.169914)
			(xy 453.019108 -6.082006) (xy 453.031091 -5.994826) (xy 453.050951 -5.909097) (xy 453.078526 -5.825529)
			(xy 453.113585 -5.744815) (xy 453.155838 -5.667623) (xy 453.204936 -5.594594) (xy 453.260472 -5.526332)
			(xy 453.321984 -5.463402) (xy 453.388965 -5.406328) (xy 453.460858 -5.35558) (xy 453.537067 -5.31158)
			(xy 453.616962 -5.274693) (xy 453.699881 -5.245224) (xy 453.785136 -5.223417) (xy 453.87202 -5.209453)
			(xy 453.959814 -5.203447) (xy 454.047791 -5.205451) (xy 454.135221 -5.215446) (xy 454.22138 -5.23335)
			(xy 454.305554 -5.259014) (xy 454.387045 -5.292227) (xy 454.465179 -5.332713) (xy 454.539307 -5.380135)
			(xy 454.608815 -5.434102) (xy 454.673129 -5.494167) (xy 454.731713 -5.559831) (xy 454.784084 -5.63055)
			(xy 454.829807 -5.705738) (xy 454.868504 -5.784773) (xy 454.899853 -5.866999) (xy 454.923595 -5.951735)
			(xy 454.939533 -6.038279) (xy 454.947535 -6.125914) (xy 454.948036 -6.169914) (xy 454.947535 -6.213914)
			(xy 454.939533 -6.301549) (xy 454.923595 -6.388093) (xy 454.899853 -6.472829) (xy 454.868504 -6.555055)
			(xy 454.829807 -6.63409) (xy 454.784084 -6.709278) (xy 454.731713 -6.779997) (xy 454.673129 -6.845661)
			(xy 454.608815 -6.905726) (xy 454.539307 -6.959693) (xy 454.465179 -7.007115) (xy 454.387045 -7.047601)
			(xy 454.305554 -7.080814) (xy 454.22138 -7.106478) (xy 454.135221 -7.124382) (xy 454.047791 -7.134377)
			(xy 453.959814 -7.136381) (xy 453.87202 -7.130375) (xy 453.785136 -7.116411) (xy 453.699881 -7.094604)
			(xy 453.616962 -7.065135) (xy 453.537067 -7.028248) (xy 453.460858 -6.984248) (xy 453.388965 -6.9335)
			(xy 453.321984 -6.876426) (xy 453.260472 -6.813496) (xy 453.204936 -6.745234) (xy 453.155838 -6.672205)
			(xy 453.113585 -6.595013) (xy 453.078526 -6.514299) (xy 453.050951 -6.430731) (xy 453.031091 -6.345002)
			(xy 453.019108 -6.257822) (xy 453.015103 -6.169914) (xy 388.110984 -6.169914) (xy 388.110984 -6.752472)
			(xy 393.134283 -6.752472) (xy 393.134283 -6.697928) (xy 393.142045 -6.643939) (xy 393.157412 -6.591604)
			(xy 393.18007 -6.541988) (xy 393.209559 -6.496103) (xy 393.245278 -6.454881) (xy 393.286499 -6.419161)
			(xy 393.332385 -6.389672) (xy 393.382 -6.367013) (xy 393.434335 -6.351646) (xy 393.488324 -6.343883)
			(xy 393.515596 -6.343396) (xy 394.379196 -6.343396) (xy 394.406464 -6.343943) (xy 394.460446 -6.351704)
			(xy 394.512773 -6.367068) (xy 394.562381 -6.389723) (xy 394.60826 -6.419207) (xy 394.649476 -6.454921)
			(xy 394.68519 -6.496136) (xy 394.714675 -6.542015) (xy 394.73733 -6.591623) (xy 394.752695 -6.643951)
			(xy 394.760457 -6.697932) (xy 394.760457 -6.752468) (xy 394.760456 -6.752476) (xy 396.73416 -6.752476)
			(xy 396.73416 -6.697924) (xy 396.741924 -6.643928) (xy 396.757294 -6.591587) (xy 396.779956 -6.541966)
			(xy 396.809451 -6.496075) (xy 396.845176 -6.454849) (xy 396.886405 -6.419128) (xy 396.932299 -6.389638)
			(xy 396.981922 -6.36698) (xy 397.034265 -6.351616) (xy 397.088262 -6.343857) (xy 397.115538 -6.343396)
			(xy 397.979138 -6.343396) (xy 398.006403 -6.343969) (xy 398.060376 -6.351734) (xy 398.112695 -6.367101)
			(xy 398.162295 -6.389757) (xy 398.208166 -6.419241) (xy 398.249375 -6.454952) (xy 398.285082 -6.496164)
			(xy 398.314561 -6.542038) (xy 398.337212 -6.59164) (xy 398.352574 -6.643961) (xy 398.360334 -6.697935)
			(xy 398.360334 -6.752465) (xy 398.360333 -6.752471) (xy 400.334182 -6.752471) (xy 400.334182 -6.697929)
			(xy 400.341944 -6.643941) (xy 400.35731 -6.591607) (xy 400.379968 -6.541993) (xy 400.409455 -6.496108)
			(xy 400.445172 -6.454886) (xy 400.486392 -6.419167) (xy 400.532275 -6.389677) (xy 400.581888 -6.367017)
			(xy 400.634221 -6.351649) (xy 400.688209 -6.343884) (xy 400.71548 -6.343396) (xy 401.57908 -6.343396)
			(xy 401.606349 -6.343942) (xy 401.660332 -6.351701) (xy 401.712661 -6.367064) (xy 401.762272 -6.389718)
			(xy 401.808153 -6.419202) (xy 401.849371 -6.454915) (xy 401.885086 -6.496131) (xy 401.914573 -6.542011)
			(xy 401.937229 -6.59162) (xy 401.952595 -6.643948) (xy 401.960357 -6.697931) (xy 401.960357 -6.752469)
			(xy 401.960357 -6.752471) (xy 403.934382 -6.752471) (xy 403.934382 -6.697929) (xy 403.942144 -6.643941)
			(xy 403.95751 -6.591608) (xy 403.980167 -6.541994) (xy 404.009654 -6.496109) (xy 404.045371 -6.454888)
			(xy 404.08659 -6.419168) (xy 404.132473 -6.389679) (xy 404.182085 -6.367019) (xy 404.234418 -6.351649)
			(xy 404.288405 -6.343884) (xy 404.315676 -6.343396) (xy 405.179276 -6.343396) (xy 405.206545 -6.343942)
			(xy 405.260529 -6.3517) (xy 405.312858 -6.367063) (xy 405.362469 -6.389716) (xy 405.408351 -6.4192)
			(xy 405.449569 -6.454914) (xy 405.485285 -6.49613) (xy 405.514772 -6.54201) (xy 405.537429 -6.591619)
			(xy 405.552795 -6.643948) (xy 405.560557 -6.697931) (xy 405.560557 -6.752469) (xy 405.560556 -6.752476)
			(xy 413.04426 -6.752476) (xy 413.04426 -6.697924) (xy 413.052024 -6.643928) (xy 413.067394 -6.591586)
			(xy 413.090057 -6.541965) (xy 413.119551 -6.496074) (xy 413.155277 -6.454849) (xy 413.196506 -6.419127)
			(xy 413.2424 -6.389638) (xy 413.292024 -6.36698) (xy 413.344367 -6.351615) (xy 413.398364 -6.343857)
			(xy 413.42564 -6.343396) (xy 414.28924 -6.343396) (xy 414.316504 -6.343969) (xy 414.370478 -6.351734)
			(xy 414.422797 -6.367102) (xy 414.472397 -6.389758) (xy 414.518267 -6.419241) (xy 414.559476 -6.454953)
			(xy 414.595183 -6.496165) (xy 414.624662 -6.542039) (xy 414.647312 -6.591641) (xy 414.662674 -6.643961)
			(xy 414.670434 -6.697935) (xy 414.670434 -6.752465) (xy 414.670433 -6.752472) (xy 416.644282 -6.752472)
			(xy 416.644282 -6.697928) (xy 416.652045 -6.64394) (xy 416.667411 -6.591607) (xy 416.690068 -6.541992)
			(xy 416.719555 -6.496107) (xy 416.755273 -6.454885) (xy 416.796493 -6.419166) (xy 416.842376 -6.389677)
			(xy 416.89199 -6.367017) (xy 416.944323 -6.351648) (xy 416.99831 -6.343884) (xy 417.025582 -6.343396)
			(xy 417.889182 -6.343396) (xy 417.916451 -6.343942) (xy 417.970434 -6.351701) (xy 418.022763 -6.367064)
			(xy 418.072373 -6.389718) (xy 418.118254 -6.419202) (xy 418.159471 -6.454916) (xy 418.195187 -6.496132)
			(xy 418.224673 -6.542011) (xy 418.247329 -6.59162) (xy 418.262695 -6.643949) (xy 418.270457 -6.697931)
			(xy 418.270457 -6.752469) (xy 418.270457 -6.752471) (xy 424.254382 -6.752471) (xy 424.254382 -6.697929)
			(xy 424.262144 -6.643941) (xy 424.27751 -6.591608) (xy 424.300167 -6.541994) (xy 424.329654 -6.496109)
			(xy 424.365371 -6.454888) (xy 424.40659 -6.419168) (xy 424.452473 -6.389679) (xy 424.502085 -6.367019)
			(xy 424.554418 -6.351649) (xy 424.608405 -6.343884) (xy 424.635676 -6.343396) (xy 425.499276 -6.343396)
			(xy 425.526545 -6.343942) (xy 425.580529 -6.3517) (xy 425.632858 -6.367063) (xy 425.682469 -6.389716)
			(xy 425.728351 -6.4192) (xy 425.769569 -6.454914) (xy 425.805285 -6.49613) (xy 425.834772 -6.54201)
			(xy 425.857429 -6.591619) (xy 425.872795 -6.643948) (xy 425.880557 -6.697931) (xy 425.880557 -6.752469)
			(xy 425.880556 -6.752475) (xy 427.85426 -6.752475) (xy 427.85426 -6.697925) (xy 427.862023 -6.643931)
			(xy 427.877392 -6.591591) (xy 427.900053 -6.541971) (xy 427.929546 -6.496082) (xy 427.965269 -6.454856)
			(xy 428.006496 -6.419135) (xy 428.052387 -6.389645) (xy 428.102008 -6.366986) (xy 428.154348 -6.351619)
			(xy 428.208343 -6.343858) (xy 428.235618 -6.343396) (xy 429.099218 -6.343396) (xy 429.126484 -6.343968)
			(xy 429.180459 -6.35173) (xy 429.232781 -6.367096) (xy 429.282383 -6.38975) (xy 429.328257 -6.419234)
			(xy 429.369468 -6.454945) (xy 429.405177 -6.496157) (xy 429.434658 -6.542032) (xy 429.457311 -6.591636)
			(xy 429.472673 -6.643958) (xy 429.480434 -6.697934) (xy 429.480434 -6.752466) (xy 429.479412 -6.759571)
			(xy 431.465194 -6.759571) (xy 431.465194 -6.705029) (xy 431.472956 -6.651043) (xy 431.488322 -6.598711)
			(xy 431.510979 -6.549098) (xy 431.540465 -6.503214) (xy 431.576181 -6.461994) (xy 431.6174 -6.426276)
			(xy 431.663282 -6.396787) (xy 431.712894 -6.374128) (xy 431.765225 -6.35876) (xy 431.819211 -6.350996)
			(xy 431.846482 -6.350508) (xy 432.710082 -6.350508) (xy 432.737352 -6.35103) (xy 432.791336 -6.35879)
			(xy 432.843667 -6.374153) (xy 432.893279 -6.396808) (xy 432.939161 -6.426293) (xy 432.98038 -6.462007)
			(xy 433.016096 -6.503225) (xy 433.045583 -6.549106) (xy 433.068241 -6.598716) (xy 433.083607 -6.651046)
			(xy 433.091369 -6.70503) (xy 433.091369 -6.75247) (xy 445.449182 -6.75247) (xy 445.449182 -6.69793)
			(xy 445.456944 -6.643944) (xy 445.472308 -6.591613) (xy 445.494963 -6.542001) (xy 445.524448 -6.496117)
			(xy 445.560162 -6.454896) (xy 445.601379 -6.419177) (xy 445.647258 -6.389686) (xy 445.696868 -6.367025)
			(xy 445.749198 -6.351654) (xy 445.803182 -6.343886) (xy 445.830452 -6.343396) (xy 446.694052 -6.343396)
			(xy 446.721322 -6.34394) (xy 446.775308 -6.351696) (xy 446.827641 -6.367056) (xy 446.877255 -6.389709)
			(xy 446.923139 -6.419192) (xy 446.964361 -6.454905) (xy 447.00008 -6.496122) (xy 447.029568 -6.542003)
			(xy 447.052227 -6.591614) (xy 447.067594 -6.643945) (xy 447.075356 -6.69793) (xy 447.075356 -6.75247)
			(xy 447.067594 -6.806455) (xy 447.052227 -6.858786) (xy 447.029568 -6.908397) (xy 447.000079 -6.954278)
			(xy 446.964361 -6.995495) (xy 446.923139 -7.031208) (xy 446.877255 -7.060691) (xy 446.827641 -7.083344)
			(xy 446.775308 -7.098704) (xy 446.721322 -7.10646) (xy 446.694052 -7.10692) (xy 445.830452 -7.10692)
			(xy 445.803182 -7.106514) (xy 445.749198 -7.098746) (xy 445.696868 -7.083375) (xy 445.647258 -7.060714)
			(xy 445.601378 -7.031223) (xy 445.560162 -6.995504) (xy 445.524448 -6.954283) (xy 445.494963 -6.908399)
			(xy 445.472308 -6.858787) (xy 445.456944 -6.806455) (xy 445.449182 -6.75247) (xy 433.091369 -6.75247)
			(xy 433.091369 -6.75957) (xy 433.083607 -6.813554) (xy 433.068241 -6.865884) (xy 433.045583 -6.915494)
			(xy 433.016096 -6.961375) (xy 432.98038 -7.002593) (xy 432.939161 -7.038307) (xy 432.893279 -7.067792)
			(xy 432.843667 -7.090447) (xy 432.791336 -7.10581) (xy 432.737352 -7.11357) (xy 432.710082 -7.114032)
			(xy 431.846482 -7.114032) (xy 431.819211 -7.113604) (xy 431.765225 -7.10584) (xy 431.712894 -7.090472)
			(xy 431.663282 -7.067813) (xy 431.6174 -7.038324) (xy 431.576181 -7.002606) (xy 431.540465 -6.961386)
			(xy 431.510979 -6.915502) (xy 431.488322 -6.865889) (xy 431.472956 -6.813557) (xy 431.465194 -6.759571)
			(xy 429.479412 -6.759571) (xy 429.472673 -6.806442) (xy 429.457311 -6.858764) (xy 429.434658 -6.908368)
			(xy 429.405177 -6.954243) (xy 429.369468 -6.995455) (xy 429.328257 -7.031166) (xy 429.282383 -7.06065)
			(xy 429.232781 -7.083304) (xy 429.180459 -7.09867) (xy 429.126484 -7.106432) (xy 429.099218 -7.10692)
			(xy 428.235618 -7.10692) (xy 428.208343 -7.106542) (xy 428.154348 -7.098781) (xy 428.102008 -7.083414)
			(xy 428.052387 -7.060755) (xy 428.006496 -7.031265) (xy 427.965269 -6.995544) (xy 427.929546 -6.954318)
			(xy 427.900053 -6.908429) (xy 427.877392 -6.858809) (xy 427.862023 -6.806469) (xy 427.85426 -6.752475)
			(xy 425.880556 -6.752475) (xy 425.872795 -6.806452) (xy 425.857429 -6.858781) (xy 425.834772 -6.90839)
			(xy 425.805285 -6.95427) (xy 425.769569 -6.995486) (xy 425.728351 -7.0312) (xy 425.682469 -7.060684)
			(xy 425.632858 -7.083337) (xy 425.580529 -7.0987) (xy 425.526545 -7.106458) (xy 425.499276 -7.10692)
			(xy 424.635676 -7.10692) (xy 424.608405 -7.106516) (xy 424.554418 -7.098751) (xy 424.502085 -7.083381)
			(xy 424.452473 -7.060721) (xy 424.40659 -7.031232) (xy 424.365371 -6.995512) (xy 424.329654 -6.954291)
			(xy 424.300167 -6.908406) (xy 424.27751 -6.858792) (xy 424.262144 -6.806459) (xy 424.254382 -6.752471)
			(xy 418.270457 -6.752471) (xy 418.262695 -6.806451) (xy 418.247329 -6.85878) (xy 418.224673 -6.908389)
			(xy 418.195187 -6.954268) (xy 418.159471 -6.995484) (xy 418.118254 -7.031198) (xy 418.072373 -7.060682)
			(xy 418.022763 -7.083336) (xy 417.970434 -7.098699) (xy 417.916451 -7.106458) (xy 417.889182 -7.10692)
			(xy 417.025582 -7.10692) (xy 416.99831 -7.106516) (xy 416.944323 -7.098752) (xy 416.89199 -7.083383)
			(xy 416.842376 -7.060723) (xy 416.796493 -7.031234) (xy 416.755273 -6.995515) (xy 416.719555 -6.954293)
			(xy 416.690068 -6.908408) (xy 416.667411 -6.858793) (xy 416.652045 -6.806459) (xy 416.644282 -6.752472)
			(xy 414.670433 -6.752472) (xy 414.662674 -6.806439) (xy 414.647312 -6.858759) (xy 414.624662 -6.908361)
			(xy 414.595183 -6.954235) (xy 414.559476 -6.995447) (xy 414.518267 -7.031159) (xy 414.472397 -7.060642)
			(xy 414.422797 -7.083298) (xy 414.370478 -7.098666) (xy 414.316505 -7.106431) (xy 414.28924 -7.10692)
			(xy 413.42564 -7.10692) (xy 413.398364 -7.106543) (xy 413.344367 -7.098785) (xy 413.292024 -7.08342)
			(xy 413.2424 -7.060762) (xy 413.196506 -7.031273) (xy 413.155277 -6.995551) (xy 413.119551 -6.954326)
			(xy 413.090057 -6.908435) (xy 413.067394 -6.858814) (xy 413.052024 -6.806472) (xy 413.04426 -6.752476)
			(xy 405.560556 -6.752476) (xy 405.552795 -6.806452) (xy 405.537429 -6.858781) (xy 405.514772 -6.90839)
			(xy 405.485285 -6.95427) (xy 405.449569 -6.995486) (xy 405.408351 -7.0312) (xy 405.362469 -7.060684)
			(xy 405.312858 -7.083337) (xy 405.260529 -7.0987) (xy 405.206545 -7.106458) (xy 405.179276 -7.10692)
			(xy 404.315676 -7.10692) (xy 404.288405 -7.106516) (xy 404.234418 -7.098751) (xy 404.182085 -7.083381)
			(xy 404.132473 -7.060721) (xy 404.08659 -7.031232) (xy 404.045371 -6.995512) (xy 404.009654 -6.954291)
			(xy 403.980167 -6.908406) (xy 403.95751 -6.858792) (xy 403.942144 -6.806459) (xy 403.934382 -6.752471)
			(xy 401.960357 -6.752471) (xy 401.952595 -6.806452) (xy 401.937229 -6.85878) (xy 401.914573 -6.908389)
			(xy 401.885086 -6.954269) (xy 401.849371 -6.995485) (xy 401.808153 -7.031198) (xy 401.762272 -7.060682)
			(xy 401.712661 -7.083336) (xy 401.660332 -7.098699) (xy 401.606349 -7.106458) (xy 401.57908 -7.10692)
			(xy 400.71548 -7.10692) (xy 400.688209 -7.106516) (xy 400.634221 -7.098751) (xy 400.581888 -7.083383)
			(xy 400.532275 -7.060723) (xy 400.486392 -7.031233) (xy 400.445172 -6.995514) (xy 400.409455 -6.954292)
			(xy 400.379968 -6.908407) (xy 400.35731 -6.858793) (xy 400.341944 -6.806459) (xy 400.334182 -6.752471)
			(xy 398.360333 -6.752471) (xy 398.352574 -6.806439) (xy 398.337212 -6.85876) (xy 398.314561 -6.908362)
			(xy 398.285082 -6.954236) (xy 398.249375 -6.995448) (xy 398.208166 -7.031159) (xy 398.162295 -7.060643)
			(xy 398.112695 -7.083299) (xy 398.060376 -7.098666) (xy 398.006403 -7.106431) (xy 397.979138 -7.10692)
			(xy 397.115538 -7.10692) (xy 397.088262 -7.106543) (xy 397.034265 -7.098784) (xy 396.981922 -7.08342)
			(xy 396.932299 -7.060762) (xy 396.886405 -7.031272) (xy 396.845176 -6.995551) (xy 396.809451 -6.954325)
			(xy 396.779956 -6.908434) (xy 396.757294 -6.858813) (xy 396.741924 -6.806472) (xy 396.73416 -6.752476)
			(xy 394.760456 -6.752476) (xy 394.752695 -6.806449) (xy 394.73733 -6.858777) (xy 394.714675 -6.908385)
			(xy 394.68519 -6.954264) (xy 394.649476 -6.995479) (xy 394.60826 -7.031193) (xy 394.562381 -7.060677)
			(xy 394.512773 -7.083332) (xy 394.460446 -7.098696) (xy 394.406464 -7.106457) (xy 394.379196 -7.10692)
			(xy 393.515596 -7.10692) (xy 393.488324 -7.106517) (xy 393.434335 -7.098754) (xy 393.382 -7.083387)
			(xy 393.332385 -7.060728) (xy 393.286499 -7.031239) (xy 393.245278 -6.995519) (xy 393.209559 -6.954297)
			(xy 393.18007 -6.908412) (xy 393.157412 -6.858796) (xy 393.142045 -6.806461) (xy 393.134283 -6.752472)
			(xy 388.110984 -6.752472) (xy 388.110984 -8.98017) (xy 391.665968 -8.98017) (xy 391.665968 -7.67461)
			(xy 391.666369 -7.662485) (xy 391.673862 -7.639421) (xy 391.688118 -7.619803) (xy 391.707739 -7.605553)
			(xy 391.730805 -7.598066) (xy 391.74293 -7.597648) (xy 392.55827 -7.597648) (xy 392.570392 -7.598086)
			(xy 392.593452 -7.605571) (xy 392.613068 -7.619818) (xy 392.62732 -7.63943) (xy 392.634811 -7.662488)
			(xy 392.635232 -7.67461) (xy 392.635232 -8.98017) (xy 392.634814 -8.992294) (xy 392.627326 -9.015357)
			(xy 392.613075 -9.034975) (xy 392.593457 -9.049226) (xy 392.570394 -9.056714) (xy 392.55827 -9.057132)
			(xy 391.74293 -9.057132) (xy 391.730806 -9.056714) (xy 391.707743 -9.049226) (xy 391.688125 -9.034975)
			(xy 391.673874 -9.015357) (xy 391.666386 -8.992294) (xy 391.665968 -8.98017) (xy 388.110984 -8.98017)
			(xy 388.110984 -9.071864) (xy 393.351512 -9.071864) (xy 393.351512 -7.672324) (xy 393.351981 -7.660274)
			(xy 393.359408 -7.637347) (xy 393.373546 -7.61783) (xy 393.393016 -7.603626) (xy 393.415918 -7.596121)
			(xy 393.427966 -7.595616) (xy 394.465048 -7.595616) (xy 394.477127 -7.596024) (xy 394.5001 -7.603502)
			(xy 394.519639 -7.617713) (xy 394.533831 -7.637264) (xy 394.541288 -7.660244) (xy 394.541756 -7.672324)
			(xy 394.541756 -9.071864) (xy 395.151356 -9.071864) (xy 395.151356 -7.672324) (xy 395.15188 -7.660279)
			(xy 395.1593 -7.637362) (xy 395.173426 -7.61785) (xy 395.192881 -7.603644) (xy 395.215767 -7.596129)
			(xy 395.22781 -7.595616) (xy 396.264892 -7.595616) (xy 396.276977 -7.59602) (xy 396.299963 -7.603488)
			(xy 396.319516 -7.617695) (xy 396.333719 -7.637251) (xy 396.341183 -7.660239) (xy 396.3416 -7.672324)
			(xy 396.3416 -9.071864) (xy 396.951708 -9.071864) (xy 396.951708 -7.672324) (xy 396.952133 -7.660241)
			(xy 396.959596 -7.637256) (xy 396.973799 -7.617704) (xy 396.993349 -7.6035) (xy 397.016333 -7.596035)
			(xy 397.028416 -7.595616) (xy 398.06499 -7.595616) (xy 398.077077 -7.596116) (xy 398.100073 -7.603567)
			(xy 398.119651 -7.617746) (xy 398.133903 -7.637271) (xy 398.141439 -7.660239) (xy 398.141952 -7.672324)
			(xy 398.141952 -9.071864) (xy 398.751552 -9.071864) (xy 398.751552 -7.672324) (xy 398.752079 -7.66028)
			(xy 398.7595 -7.637363) (xy 398.773625 -7.617851) (xy 398.793078 -7.603645) (xy 398.815964 -7.59613)
			(xy 398.828006 -7.595616) (xy 399.865088 -7.595616) (xy 399.877172 -7.596023) (xy 399.900159 -7.603491)
			(xy 399.919711 -7.617697) (xy 399.933915 -7.637252) (xy 399.941378 -7.660239) (xy 399.941796 -7.672324)
			(xy 399.941796 -9.071864) (xy 400.551396 -9.071864) (xy 400.551396 -7.672324) (xy 400.55188 -7.660275)
			(xy 400.559306 -7.637351) (xy 400.573441 -7.617836) (xy 400.592906 -7.603631) (xy 400.615803 -7.596124)
			(xy 400.62785 -7.595616) (xy 401.664932 -7.595616) (xy 401.677011 -7.596037) (xy 401.699983 -7.603511)
			(xy 401.719522 -7.617718) (xy 401.733714 -7.637267) (xy 401.741172 -7.660245) (xy 401.74164 -7.672324)
			(xy 401.74164 -9.071864) (xy 402.351748 -9.071864) (xy 402.351748 -7.672324) (xy 402.352284 -7.660255)
			(xy 402.359734 -7.637296) (xy 402.373914 -7.617762) (xy 402.393435 -7.603566) (xy 402.416387 -7.596095)
			(xy 402.428456 -7.595616) (xy 403.46503 -7.595616) (xy 403.477119 -7.596081) (xy 403.500116 -7.603543)
			(xy 403.519694 -7.617731) (xy 403.533944 -7.637263) (xy 403.54148 -7.660237) (xy 403.541992 -7.672324)
			(xy 403.541992 -9.071864) (xy 404.151592 -9.071864) (xy 404.151592 -7.672324) (xy 404.152033 -7.660243)
			(xy 404.159494 -7.637261) (xy 404.173693 -7.61771) (xy 404.193239 -7.603505) (xy 404.216219 -7.596037)
			(xy 404.2283 -7.595616) (xy 405.264874 -7.595616) (xy 405.27696 -7.596129) (xy 405.299956 -7.603576)
			(xy 405.319534 -7.617751) (xy 405.333786 -7.637274) (xy 405.341323 -7.66024) (xy 405.341836 -7.672324)
			(xy 405.341836 -9.071864) (xy 405.951436 -9.071864) (xy 405.951436 -7.672324) (xy 405.951881 -7.660272)
			(xy 405.959311 -7.637341) (xy 405.973455 -7.617821) (xy 405.992931 -7.603618) (xy 406.015839 -7.596118)
			(xy 406.02789 -7.595616) (xy 407.064972 -7.595616) (xy 407.077056 -7.596037) (xy 407.100041 -7.6035)
			(xy 407.119594 -7.617703) (xy 407.133798 -7.637255) (xy 407.141262 -7.66024) (xy 407.14168 -7.672324)
			(xy 407.14168 -9.071864) (xy 413.261556 -9.071864) (xy 413.261556 -7.672324) (xy 413.26208 -7.660279)
			(xy 413.2695 -7.637362) (xy 413.283626 -7.61785) (xy 413.303081 -7.603644) (xy 413.325967 -7.596129)
			(xy 413.33801 -7.595616) (xy 414.375092 -7.595616) (xy 414.387177 -7.59602) (xy 414.410163 -7.603488)
			(xy 414.429716 -7.617695) (xy 414.443919 -7.637251) (xy 414.451383 -7.660239) (xy 414.4518 -7.672324)
			(xy 414.4518 -9.071864) (xy 415.061908 -9.071864) (xy 415.061908 -7.672324) (xy 415.062333 -7.660241)
			(xy 415.069796 -7.637256) (xy 415.083999 -7.617704) (xy 415.103549 -7.6035) (xy 415.126533 -7.596035)
			(xy 415.138616 -7.595616) (xy 416.17519 -7.595616) (xy 416.187277 -7.596116) (xy 416.210273 -7.603567)
			(xy 416.229851 -7.617746) (xy 416.244103 -7.637271) (xy 416.251639 -7.660239) (xy 416.252152 -7.672324)
			(xy 416.252152 -9.071864) (xy 416.861752 -9.071864) (xy 416.861752 -7.672324) (xy 416.862279 -7.66028)
			(xy 416.8697 -7.637363) (xy 416.883825 -7.617851) (xy 416.903278 -7.603645) (xy 416.926164 -7.59613)
			(xy 416.938206 -7.595616) (xy 417.975288 -7.595616) (xy 417.987372 -7.596023) (xy 418.010359 -7.603491)
			(xy 418.029911 -7.617697) (xy 418.044115 -7.637252) (xy 418.051578 -7.660239) (xy 418.051996 -7.672324)
			(xy 418.051996 -9.071864) (xy 418.661596 -9.071864) (xy 418.661596 -7.672324) (xy 418.66208 -7.660275)
			(xy 418.669506 -7.637351) (xy 418.683641 -7.617836) (xy 418.703106 -7.603631) (xy 418.726003 -7.596124)
			(xy 418.73805 -7.595616) (xy 419.775132 -7.595616) (xy 419.787211 -7.596037) (xy 419.810183 -7.603511)
			(xy 419.829722 -7.617718) (xy 419.843914 -7.637267) (xy 419.851372 -7.660245) (xy 419.85184 -7.672324)
			(xy 419.85184 -9.071864) (xy 424.471592 -9.071864) (xy 424.471592 -7.672324) (xy 424.47208 -7.660276)
			(xy 424.479505 -7.637352) (xy 424.493639 -7.617837) (xy 424.513103 -7.603632) (xy 424.536 -7.596124)
			(xy 424.548046 -7.595616) (xy 425.585128 -7.595616) (xy 425.597206 -7.59604) (xy 425.620179 -7.603514)
			(xy 425.639717 -7.61772) (xy 425.65391 -7.637268) (xy 425.661368 -7.660245) (xy 425.661836 -7.672324)
			(xy 425.661836 -9.071864) (xy 426.271944 -9.071864) (xy 426.271944 -7.672324) (xy 426.272484 -7.660255)
			(xy 426.279934 -7.637297) (xy 426.294113 -7.617764) (xy 426.313633 -7.603567) (xy 426.336584 -7.596095)
			(xy 426.348652 -7.595616) (xy 427.385226 -7.595616) (xy 427.397315 -7.596085) (xy 427.420312 -7.603546)
			(xy 427.439889 -7.617733) (xy 427.45414 -7.637264) (xy 427.461676 -7.660237) (xy 427.462188 -7.672324)
			(xy 427.462188 -9.071864) (xy 428.071788 -9.071864) (xy 428.071788 -7.672324) (xy 428.07228 -7.660276)
			(xy 428.079705 -7.637353) (xy 428.093838 -7.617838) (xy 428.113301 -7.603634) (xy 428.136196 -7.596125)
			(xy 428.148242 -7.595616) (xy 429.185324 -7.595616) (xy 429.197402 -7.596044) (xy 429.220374 -7.603516)
			(xy 429.239913 -7.617721) (xy 429.254106 -7.637269) (xy 429.261563 -7.660246) (xy 429.262032 -7.672324)
			(xy 429.262032 -9.071864) (xy 429.871632 -9.071864) (xy 429.871632 -7.672324) (xy 429.872081 -7.660272)
			(xy 429.879511 -7.637342) (xy 429.893653 -7.617823) (xy 429.913128 -7.60362) (xy 429.936035 -7.596119)
			(xy 429.948086 -7.595616) (xy 430.985168 -7.595616) (xy 430.997251 -7.59604) (xy 431.020237 -7.603502)
			(xy 431.03979 -7.617704) (xy 431.053994 -7.637256) (xy 431.061458 -7.660241) (xy 431.061876 -7.672324)
			(xy 431.061876 -9.071864) (xy 431.671476 -9.071864) (xy 431.671476 -7.672324) (xy 431.67198 -7.660277)
			(xy 431.679403 -7.637357) (xy 431.693533 -7.617843) (xy 431.712993 -7.603638) (xy 431.735885 -7.596127)
			(xy 431.74793 -7.595616) (xy 432.785012 -7.595616) (xy 432.797098 -7.596003) (xy 432.820085 -7.603476)
			(xy 432.839637 -7.617688) (xy 432.85384 -7.637247) (xy 432.861303 -7.660238) (xy 432.86172 -7.672324)
			(xy 432.86172 -9.071864) (xy 445.666876 -9.071864) (xy 445.666876 -7.672324) (xy 445.667333 -7.660244)
			(xy 445.674792 -7.637265) (xy 445.688987 -7.617716) (xy 445.708529 -7.60351) (xy 445.731504 -7.596039)
			(xy 445.743584 -7.595616) (xy 446.780158 -7.595616) (xy 446.792243 -7.596143) (xy 446.815238 -7.603585)
			(xy 446.834817 -7.617757) (xy 446.84907 -7.637277) (xy 446.856607 -7.660241) (xy 446.85712 -7.672324)
			(xy 446.85712 -9.071864) (xy 446.85661 -9.08391) (xy 446.849189 -9.106831) (xy 446.835061 -9.126346)
			(xy 446.815602 -9.140551) (xy 446.79271 -9.148062) (xy 446.780666 -9.148572) (xy 445.743584 -9.148572)
			(xy 445.731497 -9.148201) (xy 445.708507 -9.140724) (xy 445.688954 -9.126509) (xy 445.674752 -9.106946)
			(xy 445.667291 -9.083951) (xy 445.666876 -9.071864) (xy 432.86172 -9.071864) (xy 432.861257 -9.083944)
			(xy 432.853801 -9.106923) (xy 432.839607 -9.126473) (xy 432.820066 -9.140679) (xy 432.797091 -9.148149)
			(xy 432.785012 -9.148572) (xy 431.748438 -9.148572) (xy 431.736352 -9.14806) (xy 431.713354 -9.140616)
			(xy 431.693775 -9.12644) (xy 431.679522 -9.106916) (xy 431.671987 -9.083948) (xy 431.671476 -9.071864)
			(xy 431.061876 -9.071864) (xy 431.061456 -9.083948) (xy 431.053995 -9.106935) (xy 431.039791 -9.126489)
			(xy 431.020239 -9.140693) (xy 430.997252 -9.148155) (xy 430.985168 -9.148572) (xy 429.948594 -9.148572)
			(xy 429.936505 -9.148098) (xy 429.913507 -9.140641) (xy 429.893928 -9.126456) (xy 429.879677 -9.106925)
			(xy 429.872143 -9.083951) (xy 429.871632 -9.071864) (xy 429.262032 -9.071864) (xy 429.261557 -9.083942)
			(xy 429.254102 -9.10692) (xy 429.239911 -9.126469) (xy 429.220374 -9.140675) (xy 429.197402 -9.148148)
			(xy 429.185324 -9.148572) (xy 428.14875 -9.148572) (xy 428.136664 -9.14805) (xy 428.113667 -9.140609)
			(xy 428.094087 -9.126436) (xy 428.079835 -9.106914) (xy 428.072299 -9.083948) (xy 428.071788 -9.071864)
			(xy 427.462188 -9.071864) (xy 427.461709 -9.083914) (xy 427.454285 -9.10684) (xy 427.44015 -9.126357)
			(xy 427.420682 -9.140562) (xy 427.397782 -9.148066) (xy 427.385734 -9.148572) (xy 426.348652 -9.148572)
			(xy 426.336571 -9.148176) (xy 426.313596 -9.140696) (xy 426.294057 -9.126483) (xy 426.279865 -9.106928)
			(xy 426.272411 -9.083945) (xy 426.271944 -9.071864) (xy 425.661836 -9.071864) (xy 425.661357 -9.083942)
			(xy 425.653903 -9.106919) (xy 425.639713 -9.126467) (xy 425.620176 -9.140674) (xy 425.597206 -9.148147)
			(xy 425.585128 -9.148572) (xy 424.548554 -9.148572) (xy 424.536463 -9.148132) (xy 424.513463 -9.140664)
			(xy 424.493885 -9.12647) (xy 424.479636 -9.106932) (xy 424.472103 -9.083953) (xy 424.471592 -9.071864)
			(xy 419.85184 -9.071864) (xy 419.851357 -9.083942) (xy 419.843903 -9.106918) (xy 419.829714 -9.126466)
			(xy 419.810179 -9.140672) (xy 419.787209 -9.148146) (xy 419.775132 -9.148572) (xy 418.738558 -9.148572)
			(xy 418.726467 -9.148129) (xy 418.703467 -9.140662) (xy 418.683889 -9.126469) (xy 418.66964 -9.106932)
			(xy 418.662107 -9.083953) (xy 418.661596 -9.071864) (xy 418.051996 -9.071864) (xy 418.051556 -9.083946)
			(xy 418.044097 -9.10693) (xy 418.029899 -9.126482) (xy 418.010351 -9.140686) (xy 417.98737 -9.148153)
			(xy 417.975288 -9.148572) (xy 416.938714 -9.148572) (xy 416.926626 -9.148081) (xy 416.903628 -9.140629)
			(xy 416.884049 -9.126449) (xy 416.869798 -9.106921) (xy 416.862263 -9.08395) (xy 416.861752 -9.071864)
			(xy 416.252152 -9.071864) (xy 416.25161 -9.083907) (xy 416.244194 -9.106823) (xy 416.230072 -9.126335)
			(xy 416.210622 -9.140541) (xy 416.187739 -9.148057) (xy 416.175698 -9.148572) (xy 415.138616 -9.148572)
			(xy 415.126531 -9.148173) (xy 415.103542 -9.140705) (xy 415.083989 -9.126497) (xy 415.069785 -9.10694)
			(xy 415.062324 -9.08395) (xy 415.061908 -9.071864) (xy 414.4518 -9.071864) (xy 414.451356 -9.083946)
			(xy 414.443898 -9.106929) (xy 414.4297 -9.12648) (xy 414.410154 -9.140685) (xy 414.387173 -9.148152)
			(xy 414.375092 -9.148572) (xy 413.338518 -9.148572) (xy 413.326431 -9.148077) (xy 413.303433 -9.140627)
			(xy 413.283853 -9.126447) (xy 413.269602 -9.10692) (xy 413.262067 -9.08395) (xy 413.261556 -9.071864)
			(xy 407.14168 -9.071864) (xy 407.141256 -9.083948) (xy 407.133795 -9.106934) (xy 407.119593 -9.126487)
			(xy 407.100041 -9.140692) (xy 407.077056 -9.148155) (xy 407.064972 -9.148572) (xy 406.028398 -9.148572)
			(xy 406.01631 -9.148094) (xy 405.993311 -9.140639) (xy 405.973732 -9.126454) (xy 405.959481 -9.106924)
			(xy 405.951947 -9.083951) (xy 405.951436 -9.071864) (xy 405.341836 -9.071864) (xy 405.34131 -9.083909)
			(xy 405.333892 -9.106827) (xy 405.319767 -9.12634) (xy 405.300312 -9.140546) (xy 405.277425 -9.14806)
			(xy 405.265382 -9.148572) (xy 404.2283 -9.148572) (xy 404.216214 -9.148187) (xy 404.193225 -9.140715)
			(xy 404.173671 -9.126503) (xy 404.159468 -9.106943) (xy 404.152007 -9.083951) (xy 404.151592 -9.071864)
			(xy 403.541992 -9.071864) (xy 403.541509 -9.083913) (xy 403.534086 -9.106839) (xy 403.519951 -9.126356)
			(xy 403.500484 -9.14056) (xy 403.477585 -9.148066) (xy 403.465538 -9.148572) (xy 402.428456 -9.148572)
			(xy 402.416376 -9.148173) (xy 402.393401 -9.140694) (xy 402.373861 -9.126482) (xy 402.35967 -9.106927)
			(xy 402.352215 -9.083945) (xy 402.351748 -9.071864) (xy 401.74164 -9.071864) (xy 401.741157 -9.083942)
			(xy 401.733703 -9.106918) (xy 401.719514 -9.126466) (xy 401.699979 -9.140672) (xy 401.677009 -9.148146)
			(xy 401.664932 -9.148572) (xy 400.628358 -9.148572) (xy 400.616267 -9.148129) (xy 400.593267 -9.140662)
			(xy 400.573689 -9.126469) (xy 400.55944 -9.106932) (xy 400.551907 -9.083953) (xy 400.551396 -9.071864)
			(xy 399.941796 -9.071864) (xy 399.941356 -9.083946) (xy 399.933897 -9.10693) (xy 399.919699 -9.126482)
			(xy 399.900151 -9.140686) (xy 399.87717 -9.148153) (xy 399.865088 -9.148572) (xy 398.828514 -9.148572)
			(xy 398.816426 -9.148081) (xy 398.793428 -9.140629) (xy 398.773849 -9.126449) (xy 398.759598 -9.106921)
			(xy 398.752063 -9.08395) (xy 398.751552 -9.071864) (xy 398.141952 -9.071864) (xy 398.14141 -9.083907)
			(xy 398.133994 -9.106823) (xy 398.119872 -9.126335) (xy 398.100422 -9.140541) (xy 398.077539 -9.148057)
			(xy 398.065498 -9.148572) (xy 397.028416 -9.148572) (xy 397.016331 -9.148173) (xy 396.993342 -9.140705)
			(xy 396.973789 -9.126497) (xy 396.959585 -9.10694) (xy 396.952124 -9.08395) (xy 396.951708 -9.071864)
			(xy 396.3416 -9.071864) (xy 396.341156 -9.083946) (xy 396.333698 -9.106929) (xy 396.3195 -9.12648)
			(xy 396.299954 -9.140685) (xy 396.276973 -9.148152) (xy 396.264892 -9.148572) (xy 395.228318 -9.148572)
			(xy 395.216231 -9.148077) (xy 395.193233 -9.140627) (xy 395.173653 -9.126447) (xy 395.159402 -9.10692)
			(xy 395.151867 -9.08395) (xy 395.151356 -9.071864) (xy 394.541756 -9.071864) (xy 394.541206 -9.083932)
			(xy 394.533759 -9.10689) (xy 394.519583 -9.126423) (xy 394.500065 -9.140621) (xy 394.477115 -9.148093)
			(xy 394.465048 -9.148572) (xy 393.428474 -9.148572) (xy 393.416384 -9.148115) (xy 393.393385 -9.140653)
			(xy 393.373806 -9.126463) (xy 393.359556 -9.106929) (xy 393.352023 -9.083952) (xy 393.351512 -9.071864)
			(xy 388.110984 -9.071864) (xy 388.110984 -9.780016) (xy 388.110499 -9.850398) (xy 388.102605 -9.99094)
			(xy 388.086844 -10.130819) (xy 388.063264 -10.269594) (xy 388.03194 -10.406828) (xy 387.992971 -10.54209)
			(xy 387.946478 -10.674954) (xy 387.892609 -10.805003) (xy 387.831533 -10.931826) (xy 387.763442 -11.055026)
			(xy 387.68855 -11.174213) (xy 387.607093 -11.289014) (xy 387.519328 -11.399067) (xy 387.425529 -11.504025)
			(xy 387.325993 -11.60356) (xy 387.221033 -11.697356) (xy 387.110979 -11.78512) (xy 386.996176 -11.866575)
			(xy 386.914842 -11.91768) (xy 393.35202 -11.91768) (xy 393.35202 -10.51814) (xy 393.352447 -10.506057)
			(xy 393.359907 -10.48307) (xy 393.374108 -10.463517) (xy 393.39366 -10.449313) (xy 393.416645 -10.441849)
			(xy 393.428728 -10.441432) (xy 394.465302 -10.441432) (xy 394.477391 -10.441906) (xy 394.50039 -10.449362)
			(xy 394.519969 -10.463547) (xy 394.53422 -10.483079) (xy 394.541753 -10.506053) (xy 394.542264 -10.51814)
			(xy 394.542264 -11.91768) (xy 395.151864 -11.91768) (xy 395.151864 -10.51814) (xy 395.152393 -10.506095)
			(xy 395.159811 -10.483177) (xy 395.173935 -10.463664) (xy 395.193389 -10.449458) (xy 395.216275 -10.441944)
			(xy 395.228318 -10.441432) (xy 396.2654 -10.441432) (xy 396.277487 -10.441813) (xy 396.300476 -10.449285)
			(xy 396.32003 -10.463498) (xy 396.334233 -10.48306) (xy 396.341693 -10.506053) (xy 396.342108 -10.51814)
			(xy 396.342108 -11.91768) (xy 396.951708 -11.91768) (xy 396.951708 -10.51814) (xy 396.952194 -10.506091)
			(xy 396.959617 -10.483165) (xy 396.97375 -10.463648) (xy 396.993216 -10.449444) (xy 397.016115 -10.441938)
			(xy 397.028162 -10.441432) (xy 398.065244 -10.441432) (xy 398.077325 -10.441827) (xy 398.1003 -10.449307)
			(xy 398.11984 -10.46352) (xy 398.134032 -10.483075) (xy 398.141486 -10.506059) (xy 398.141952 -10.51814)
			(xy 398.141952 -11.91768) (xy 398.75206 -11.91768) (xy 398.75206 -10.51814) (xy 398.752546 -10.506063)
			(xy 398.759999 -10.483087) (xy 398.774187 -10.463538) (xy 398.793722 -10.449332) (xy 398.816691 -10.441858)
			(xy 398.828768 -10.441432) (xy 399.865342 -10.441432) (xy 399.877433 -10.441871) (xy 399.900434 -10.449339)
			(xy 399.920012 -10.463533) (xy 399.934262 -10.483071) (xy 399.941794 -10.50605) (xy 399.942304 -10.51814)
			(xy 399.942304 -11.91768) (xy 400.551904 -11.91768) (xy 400.551904 -10.51814) (xy 400.552347 -10.506058)
			(xy 400.559805 -10.483075) (xy 400.574003 -10.463523) (xy 400.59355 -10.449318) (xy 400.61653 -10.441851)
			(xy 400.628612 -10.441432) (xy 401.665186 -10.441432) (xy 401.677274 -10.441919) (xy 401.700273 -10.449371)
			(xy 401.719852 -10.463553) (xy 401.734104 -10.483082) (xy 401.741637 -10.506054) (xy 401.742148 -10.51814)
			(xy 401.742148 -11.91768) (xy 402.351748 -11.91768) (xy 402.351748 -10.51814) (xy 402.352293 -10.506097)
			(xy 402.359708 -10.483181) (xy 402.373829 -10.463669) (xy 402.393279 -10.449463) (xy 402.416161 -10.441947)
			(xy 402.428202 -10.441432) (xy 403.465284 -10.441432) (xy 403.47737 -10.441827) (xy 403.500359 -10.449295)
			(xy 403.519913 -10.463504) (xy 403.534116 -10.483063) (xy 403.541577 -10.506054) (xy 403.541992 -10.51814)
			(xy 403.541992 -11.91768) (xy 404.1521 -11.91768) (xy 404.1521 -10.51814) (xy 404.152547 -10.506059)
			(xy 404.160004 -10.483076) (xy 404.174201 -10.463524) (xy 404.193747 -10.449319) (xy 404.216727 -10.441852)
			(xy 404.228808 -10.441432) (xy 405.265382 -10.441432) (xy 405.27747 -10.441923) (xy 405.300468 -10.449373)
			(xy 405.320048 -10.463554) (xy 405.334299 -10.483082) (xy 405.341833 -10.506054) (xy 405.342344 -10.51814)
			(xy 405.342344 -11.91768) (xy 405.951944 -11.91768) (xy 405.951944 -10.51814) (xy 405.952497 -10.506072)
			(xy 405.959943 -10.483114) (xy 405.974118 -10.463581) (xy 405.993636 -10.449383) (xy 406.016585 -10.441911)
			(xy 406.028652 -10.441432) (xy 407.065226 -10.441432) (xy 407.077316 -10.441885) (xy 407.100316 -10.449348)
			(xy 407.119895 -10.463538) (xy 407.134145 -10.483074) (xy 407.141678 -10.506051) (xy 407.142188 -10.51814)
			(xy 407.142188 -11.91768) (xy 413.262064 -11.91768) (xy 413.262064 -10.51814) (xy 413.262546 -10.506062)
			(xy 413.269999 -10.483085) (xy 413.284189 -10.463537) (xy 413.303725 -10.449331) (xy 413.326695 -10.441857)
			(xy 413.338772 -10.441432) (xy 414.375346 -10.441432) (xy 414.387437 -10.441868) (xy 414.410438 -10.449336)
			(xy 414.430016 -10.463531) (xy 414.444266 -10.48307) (xy 414.451798 -10.50605) (xy 414.452308 -10.51814)
			(xy 414.452308 -11.91768) (xy 415.061908 -11.91768) (xy 415.061908 -10.51814) (xy 415.062347 -10.506058)
			(xy 415.069805 -10.483074) (xy 415.084004 -10.463521) (xy 415.103552 -10.449316) (xy 415.126534 -10.441851)
			(xy 415.138616 -10.441432) (xy 416.17519 -10.441432) (xy 416.187278 -10.441916) (xy 416.210277 -10.449369)
			(xy 416.229857 -10.463551) (xy 416.244108 -10.483081) (xy 416.251641 -10.506053) (xy 416.252152 -10.51814)
			(xy 416.252152 -11.91768) (xy 416.861752 -11.91768) (xy 416.861752 -10.51814) (xy 416.862293 -10.506097)
			(xy 416.869709 -10.48318) (xy 416.88383 -10.463668) (xy 416.903281 -10.449462) (xy 416.926165 -10.441946)
			(xy 416.938206 -10.441432) (xy 417.975288 -10.441432) (xy 417.987374 -10.441824) (xy 418.010363 -10.449293)
			(xy 418.029917 -10.463503) (xy 418.04412 -10.483062) (xy 418.051581 -10.506054) (xy 418.051996 -10.51814)
			(xy 418.051996 -11.91768) (xy 418.662104 -11.91768) (xy 418.662104 -10.51814) (xy 418.662547 -10.506058)
			(xy 418.670005 -10.483075) (xy 418.684203 -10.463523) (xy 418.70375 -10.449318) (xy 418.72673 -10.441851)
			(xy 418.738812 -10.441432) (xy 419.775386 -10.441432) (xy 419.787474 -10.441919) (xy 419.810473 -10.449371)
			(xy 419.830052 -10.463553) (xy 419.844304 -10.483082) (xy 419.851837 -10.506054) (xy 419.852348 -10.51814)
			(xy 419.852348 -11.91768) (xy 424.4721 -11.91768) (xy 424.4721 -10.51814) (xy 424.472547 -10.506059)
			(xy 424.480004 -10.483076) (xy 424.494201 -10.463524) (xy 424.513747 -10.449319) (xy 424.536727 -10.441852)
			(xy 424.548808 -10.441432) (xy 425.585382 -10.441432) (xy 425.59747 -10.441923) (xy 425.620468 -10.449373)
			(xy 425.640048 -10.463554) (xy 425.654299 -10.483082) (xy 425.661833 -10.506054) (xy 425.662344 -10.51814)
			(xy 425.662344 -11.91768) (xy 426.271944 -11.91768) (xy 426.271944 -10.51814) (xy 426.272497 -10.506072)
			(xy 426.279943 -10.483114) (xy 426.294118 -10.463581) (xy 426.313636 -10.449383) (xy 426.336585 -10.441911)
			(xy 426.348652 -10.441432) (xy 427.385226 -10.441432) (xy 427.397316 -10.441885) (xy 427.420316 -10.449348)
			(xy 427.439895 -10.463538) (xy 427.454145 -10.483074) (xy 427.461678 -10.506051) (xy 427.462188 -10.51814)
			(xy 427.462188 -11.91768) (xy 428.071788 -11.91768) (xy 428.071788 -10.51814) (xy 428.072294 -10.506093)
			(xy 428.079714 -10.483171) (xy 428.093843 -10.463655) (xy 428.113304 -10.44945) (xy 428.136197 -10.441941)
			(xy 428.148242 -10.441432) (xy 429.185324 -10.441432) (xy 429.197412 -10.441793) (xy 429.220402 -10.449272)
			(xy 429.239956 -10.46349) (xy 429.254157 -10.483055) (xy 429.261617 -10.506052) (xy 429.262032 -10.51814)
			(xy 429.262032 -11.91768) (xy 429.87214 -11.91768) (xy 429.87214 -10.51814) (xy 429.872548 -10.506055)
			(xy 429.88001 -10.483065) (xy 429.894216 -10.46351) (xy 429.913772 -10.449306) (xy 429.936763 -10.441846)
			(xy 429.948848 -10.441432) (xy 430.985422 -10.441432) (xy 430.997512 -10.441888) (xy 431.020512 -10.44935)
			(xy 431.040091 -10.46354) (xy 431.054341 -10.483075) (xy 431.061874 -10.506052) (xy 431.062384 -10.51814)
			(xy 431.062384 -11.91768) (xy 431.671984 -11.91768) (xy 431.671984 -10.51814) (xy 431.672447 -10.50606)
			(xy 431.679902 -10.48308) (xy 431.694096 -10.46353) (xy 431.713637 -10.449324) (xy 431.736612 -10.441854)
			(xy 431.748692 -10.441432) (xy 432.785266 -10.441432) (xy 432.797353 -10.441936) (xy 432.820351 -10.449383)
			(xy 432.839931 -10.46356) (xy 432.854183 -10.483085) (xy 432.861717 -10.506055) (xy 432.862228 -10.51814)
			(xy 432.862228 -11.91768) (xy 432.861724 -11.929726) (xy 432.8543 -11.952647) (xy 432.840169 -11.97216)
			(xy 432.82071 -11.986365) (xy 432.797819 -11.993877) (xy 432.785774 -11.994388) (xy 431.748692 -11.994388)
			(xy 431.736607 -11.993994) (xy 431.71362 -11.986522) (xy 431.694069 -11.972312) (xy 431.679865 -11.952754)
			(xy 431.672402 -11.929765) (xy 431.671984 -11.91768) (xy 431.062384 -11.91768) (xy 431.061923 -11.929731)
			(xy 431.054494 -11.952658) (xy 431.040354 -11.972176) (xy 431.020882 -11.986379) (xy 430.997979 -11.993883)
			(xy 430.98593 -11.994388) (xy 429.948848 -11.994388) (xy 429.936766 -11.993946) (xy 429.913781 -11.986489)
			(xy 429.894228 -11.972292) (xy 429.880023 -11.952744) (xy 429.872558 -11.929762) (xy 429.87214 -11.91768)
			(xy 429.262032 -11.91768) (xy 429.261519 -11.929751) (xy 429.254065 -11.952714) (xy 429.23988 -11.972249)
			(xy 429.220353 -11.986445) (xy 429.197395 -11.993912) (xy 429.185324 -11.994388) (xy 428.14875 -11.994388)
			(xy 428.136666 -11.993851) (xy 428.113671 -11.986411) (xy 428.094093 -11.972242) (xy 428.07984 -11.952724)
			(xy 428.072302 -11.929762) (xy 428.071788 -11.91768) (xy 427.462188 -11.91768) (xy 427.461723 -11.92973)
			(xy 427.454294 -11.952657) (xy 427.440155 -11.972174) (xy 427.420685 -11.986378) (xy 427.397783 -11.993883)
			(xy 427.385734 -11.994388) (xy 426.348652 -11.994388) (xy 426.336573 -11.993976) (xy 426.313601 -11.986498)
			(xy 426.294063 -11.972289) (xy 426.279871 -11.952738) (xy 426.272413 -11.929759) (xy 426.271944 -11.91768)
			(xy 425.662344 -11.91768) (xy 425.661824 -11.929725) (xy 425.654402 -11.952642) (xy 425.640275 -11.972155)
			(xy 425.62082 -11.98636) (xy 425.597933 -11.993875) (xy 425.58589 -11.994388) (xy 424.548808 -11.994388)
			(xy 424.536724 -11.99398) (xy 424.513738 -11.986513) (xy 424.494186 -11.972306) (xy 424.479982 -11.952752)
			(xy 424.472518 -11.929764) (xy 424.4721 -11.91768) (xy 419.852348 -11.91768) (xy 419.851824 -11.929724)
			(xy 419.844403 -11.952641) (xy 419.830277 -11.972153) (xy 419.810823 -11.986359) (xy 419.787936 -11.993874)
			(xy 419.775894 -11.994388) (xy 418.738812 -11.994388) (xy 418.726728 -11.993977) (xy 418.703742 -11.98651)
			(xy 418.68419 -11.972304) (xy 418.669986 -11.952751) (xy 418.662522 -11.929764) (xy 418.662104 -11.91768)
			(xy 418.051996 -11.91768) (xy 418.05157 -11.929763) (xy 418.044106 -11.952747) (xy 418.029904 -11.972299)
			(xy 418.010354 -11.986503) (xy 417.987371 -11.993969) (xy 417.975288 -11.994388) (xy 416.938714 -11.994388)
			(xy 416.926628 -11.993881) (xy 416.903633 -11.986432) (xy 416.884055 -11.972254) (xy 416.869803 -11.952731)
			(xy 416.862266 -11.929764) (xy 416.861752 -11.91768) (xy 416.252152 -11.91768) (xy 416.251624 -11.929724)
			(xy 416.244203 -11.95264) (xy 416.230078 -11.972152) (xy 416.210625 -11.986358) (xy 416.18774 -11.993874)
			(xy 416.175698 -11.994388) (xy 415.138616 -11.994388) (xy 415.126532 -11.993973) (xy 415.103547 -11.986508)
			(xy 415.083994 -11.972303) (xy 415.06979 -11.95275) (xy 415.062326 -11.929764) (xy 415.061908 -11.91768)
			(xy 414.452308 -11.91768) (xy 414.451823 -11.929728) (xy 414.444397 -11.952652) (xy 414.430262 -11.972167)
			(xy 414.410798 -11.986372) (xy 414.387901 -11.99388) (xy 414.375854 -11.994388) (xy 413.338772 -11.994388)
			(xy 413.326694 -11.99396) (xy 413.303722 -11.986487) (xy 413.284184 -11.972282) (xy 413.269991 -11.952735)
			(xy 413.262533 -11.929758) (xy 413.262064 -11.91768) (xy 407.142188 -11.91768) (xy 407.141723 -11.92973)
			(xy 407.134294 -11.952657) (xy 407.120155 -11.972174) (xy 407.100685 -11.986378) (xy 407.077783 -11.993883)
			(xy 407.065734 -11.994388) (xy 406.028652 -11.994388) (xy 406.016573 -11.993976) (xy 405.993601 -11.986498)
			(xy 405.974063 -11.972289) (xy 405.959871 -11.952738) (xy 405.952413 -11.929759) (xy 405.951944 -11.91768)
			(xy 405.342344 -11.91768) (xy 405.341824 -11.929725) (xy 405.334402 -11.952642) (xy 405.320275 -11.972155)
			(xy 405.30082 -11.98636) (xy 405.277933 -11.993875) (xy 405.26589 -11.994388) (xy 404.228808 -11.994388)
			(xy 404.216724 -11.99398) (xy 404.193738 -11.986513) (xy 404.174186 -11.972306) (xy 404.159982 -11.952752)
			(xy 404.152518 -11.929764) (xy 404.1521 -11.91768) (xy 403.541992 -11.91768) (xy 403.54157 -11.929763)
			(xy 403.534106 -11.952748) (xy 403.519903 -11.9723) (xy 403.500352 -11.986504) (xy 403.477367 -11.993969)
			(xy 403.465284 -11.994388) (xy 402.42871 -11.994388) (xy 402.416624 -11.993885) (xy 402.393628 -11.986434)
			(xy 402.374051 -11.972256) (xy 402.359799 -11.952732) (xy 402.352262 -11.929764) (xy 402.351748 -11.91768)
			(xy 401.742148 -11.91768) (xy 401.741624 -11.929724) (xy 401.734203 -11.952641) (xy 401.720077 -11.972153)
			(xy 401.700623 -11.986359) (xy 401.677736 -11.993874) (xy 401.665694 -11.994388) (xy 400.628612 -11.994388)
			(xy 400.616528 -11.993977) (xy 400.593542 -11.98651) (xy 400.57399 -11.972304) (xy 400.559786 -11.952751)
			(xy 400.552322 -11.929764) (xy 400.551904 -11.91768) (xy 399.942304 -11.91768) (xy 399.941823 -11.929729)
			(xy 399.934396 -11.952653) (xy 399.920261 -11.972169) (xy 399.900795 -11.986373) (xy 399.877897 -11.99388)
			(xy 399.86585 -11.994388) (xy 398.828768 -11.994388) (xy 398.81669 -11.993963) (xy 398.793718 -11.986489)
			(xy 398.77418 -11.972283) (xy 398.759987 -11.952735) (xy 398.752529 -11.929759) (xy 398.75206 -11.91768)
			(xy 398.141952 -11.91768) (xy 398.141419 -11.929749) (xy 398.133968 -11.952708) (xy 398.119787 -11.972242)
			(xy 398.100266 -11.986439) (xy 398.077313 -11.993909) (xy 398.065244 -11.994388) (xy 397.02867 -11.994388)
			(xy 397.016582 -11.993919) (xy 396.993585 -11.986457) (xy 396.974008 -11.97227) (xy 396.959757 -11.952739)
			(xy 396.952221 -11.929767) (xy 396.951708 -11.91768) (xy 396.342108 -11.91768) (xy 396.34167 -11.929762)
			(xy 396.334208 -11.952744) (xy 396.320008 -11.972294) (xy 396.300462 -11.986499) (xy 396.277482 -11.993967)
			(xy 396.2654 -11.994388) (xy 395.228826 -11.994388) (xy 395.216741 -11.993871) (xy 395.193746 -11.986425)
			(xy 395.174168 -11.97225) (xy 395.159915 -11.952729) (xy 395.152378 -11.929763) (xy 395.151864 -11.91768)
			(xy 394.542264 -11.91768) (xy 394.541822 -11.929733) (xy 394.534391 -11.952664) (xy 394.520247 -11.972183)
			(xy 394.50077 -11.986386) (xy 394.477861 -11.993886) (xy 394.46581 -11.994388) (xy 393.428728 -11.994388)
			(xy 393.416645 -11.993963) (xy 393.39366 -11.986501) (xy 393.374107 -11.972299) (xy 393.359903 -11.952748)
			(xy 393.352438 -11.929763) (xy 393.35202 -11.91768) (xy 386.914842 -11.91768) (xy 386.876988 -11.941465)
			(xy 386.753787 -12.009554) (xy 386.626963 -12.070627) (xy 386.496913 -12.124494) (xy 386.364048 -12.170984)
			(xy 386.228785 -12.209951) (xy 386.091551 -12.241273) (xy 385.952775 -12.26485) (xy 385.812896 -12.280609)
			(xy 385.672354 -12.2885) (xy 385.601972 -12.289028) (xy 260.800088 -12.289028) (xy 260.744319 -12.28955)
			(xy 260.633094 -12.297886) (xy 260.522803 -12.314511) (xy 260.414062 -12.339331) (xy 260.30748 -12.372208)
			(xy 260.234662 -12.400788) (xy 436.813452 -12.400788) (xy 436.813941 -12.359678) (xy 436.821529 -12.27781)
			(xy 436.83664 -12.196991) (xy 436.859145 -12.117912) (xy 436.888851 -12.041247) (xy 436.925505 -11.96765)
			(xy 436.968795 -11.89775) (xy 437.01835 -11.832142) (xy 437.073748 -11.771388) (xy 437.134516 -11.716006)
			(xy 437.200136 -11.666467) (xy 437.270047 -11.623195) (xy 437.343653 -11.58656) (xy 437.420326 -11.556873)
			(xy 437.499411 -11.534389) (xy 437.580234 -11.519298) (xy 437.662104 -11.511731) (xy 437.703214 -11.51128)
			(xy 437.747029 -11.511772) (xy 437.83424 -11.520318) (xy 437.920187 -11.537406) (xy 438.004035 -11.562868)
			(xy 438.084971 -11.596458) (xy 438.123838 -11.61669) (xy 438.135191 -11.622017) (xy 438.160237 -11.622017)
			(xy 438.17159 -11.61669) (xy 438.210465 -11.596477) (xy 438.291405 -11.562905) (xy 438.375252 -11.537448)
			(xy 438.461195 -11.520353) (xy 438.548401 -11.511784) (xy 438.592214 -11.51128) (xy 438.636029 -11.511772)
			(xy 438.72324 -11.520318) (xy 438.809187 -11.537406) (xy 438.893035 -11.562868) (xy 438.973971 -11.596458)
			(xy 439.012838 -11.61669) (xy 439.024191 -11.622017) (xy 439.049237 -11.622017) (xy 439.06059 -11.61669)
			(xy 439.099465 -11.596477) (xy 439.180405 -11.562905) (xy 439.264252 -11.537448) (xy 439.350195 -11.520353)
			(xy 439.437401 -11.511784) (xy 439.481214 -11.51128) (xy 439.521951 -11.511719) (xy 439.603086 -11.519152)
			(xy 439.683202 -11.533973) (xy 439.761626 -11.556057) (xy 439.837703 -11.585219) (xy 439.910794 -11.621216)
			(xy 439.94578 -11.64209) (xy 439.954798 -11.647053) (xy 439.975154 -11.650004) (xy 439.995036 -11.644737)
			(xy 440.003438 -11.638788) (xy 440.091322 -11.570462) (xy 440.10072 -11.54049) (xy 440.095894 -11.52525)
			(xy 440.083229 -11.482506) (xy 440.065483 -11.395136) (xy 440.056563 -11.306429) (xy 440.056016 -11.261852)
			(xy 440.056016 -11.26109) (xy 440.056438 -11.22287) (xy 440.062998 -11.146712) (xy 440.076079 -11.071399)
			(xy 440.095582 -10.997489) (xy 440.108086 -10.96137) (xy 440.110695 -10.953059) (xy 440.110679 -10.935651)
			(xy 440.108086 -10.927334) (xy 440.095582 -10.891215) (xy 440.076095 -10.817302) (xy 440.063015 -10.74199)
			(xy 440.056437 -10.665834) (xy 440.056016 -10.627614) (xy 440.056016 -10.626852) (xy 440.05652 -10.584504)
			(xy 440.064571 -10.50019) (xy 440.0806 -10.417024) (xy 440.104461 -10.335757) (xy 440.13594 -10.257127)
			(xy 440.174751 -10.181846) (xy 440.220541 -10.110594) (xy 440.272897 -10.044018) (xy 440.331345 -9.98272)
			(xy 440.395355 -9.927255) (xy 440.464347 -9.878126) (xy 440.537697 -9.835777) (xy 440.61474 -9.800593)
			(xy 440.694779 -9.772891) (xy 440.777088 -9.752923) (xy 440.860923 -9.74087) (xy 440.945524 -9.73684)
			(xy 441.030125 -9.74087) (xy 441.11396 -9.752923) (xy 441.196269 -9.772891) (xy 441.276308 -9.800593)
			(xy 441.353351 -9.835777) (xy 441.426701 -9.878126) (xy 441.495693 -9.927255) (xy 441.559703 -9.98272)
			(xy 441.618151 -10.044018) (xy 441.670507 -10.110594) (xy 441.716297 -10.181846) (xy 441.755108 -10.257127)
			(xy 441.786587 -10.335757) (xy 441.810448 -10.417024) (xy 441.826477 -10.50019) (xy 441.834528 -10.584504)
			(xy 441.835032 -10.626852) (xy 441.835032 -10.627614) (xy 441.834614 -10.665834) (xy 441.828053 -10.741992)
			(xy 441.814972 -10.817305) (xy 441.795467 -10.891215) (xy 441.782962 -10.927334) (xy 441.780399 -10.935656)
			(xy 441.780383 -10.953054) (xy 441.782962 -10.96137) (xy 441.795465 -10.997489) (xy 441.814952 -11.071403)
			(xy 441.828033 -11.146715) (xy 441.834611 -11.22287) (xy 441.835032 -11.26109) (xy 441.835032 -11.261852)
			(xy 441.834502 -11.302954) (xy 441.826922 -11.384807) (xy 441.811821 -11.465611) (xy 441.789329 -11.544677)
			(xy 441.759637 -11.621331) (xy 441.722999 -11.694918) (xy 441.679728 -11.764811) (xy 441.630192 -11.830413)
			(xy 441.574815 -11.891164) (xy 441.54573 -11.91768) (xy 445.666876 -11.91768) (xy 445.666876 -10.51814)
			(xy 445.667347 -10.506061) (xy 445.674801 -10.483082) (xy 445.688993 -10.463533) (xy 445.708532 -10.449327)
			(xy 445.731505 -10.441855) (xy 445.743584 -10.441432) (xy 446.780158 -10.441432) (xy 446.792245 -10.441943)
			(xy 446.815243 -10.449387) (xy 446.834822 -10.463563) (xy 446.849075 -10.483087) (xy 446.856609 -10.506055)
			(xy 446.85712 -10.51814) (xy 446.85712 -11.91768) (xy 446.856623 -11.929727) (xy 446.849199 -11.952649)
			(xy 446.835067 -11.972163) (xy 446.815605 -11.986368) (xy 446.792711 -11.993878) (xy 446.780666 -11.994388)
			(xy 445.743584 -11.994388) (xy 445.731498 -11.994001) (xy 445.708512 -11.986526) (xy 445.68896 -11.972314)
			(xy 445.674757 -11.952756) (xy 445.667294 -11.929766) (xy 445.666876 -11.91768) (xy 441.54573 -11.91768)
			(xy 441.514068 -11.946546) (xy 441.44847 -11.996087) (xy 441.378581 -12.039364) (xy 441.304997 -12.076008)
			(xy 441.228346 -12.105706) (xy 441.149281 -12.128204) (xy 441.068478 -12.143312) (xy 440.986626 -12.150899)
			(xy 440.945524 -12.15136) (xy 440.945016 -12.15136) (xy 440.904322 -12.150875) (xy 440.823276 -12.143416)
			(xy 440.74325 -12.128584) (xy 440.664913 -12.106505) (xy 440.58892 -12.077363) (xy 440.515907 -12.041401)
			(xy 440.480958 -12.02055) (xy 440.471926 -12.015614) (xy 440.451579 -12.012649) (xy 440.431701 -12.017907)
			(xy 440.4233 -12.023852) (xy 440.335416 -12.092178) (xy 440.326018 -12.12215) (xy 440.330844 -12.13739)
			(xy 440.343568 -12.180123) (xy 440.361398 -12.267491) (xy 440.370394 -12.356204) (xy 440.370976 -12.400788)
			(xy 440.370415 -12.444238) (xy 440.361895 -12.530719) (xy 440.344992 -12.615959) (xy 440.319868 -12.699148)
			(xy 440.286761 -12.779495) (xy 440.266836 -12.81811) (xy 440.262961 -12.82623) (xy 440.260628 -12.84406)
			(xy 440.262264 -12.852908) (xy 440.272023 -12.900055) (xy 440.282457 -12.995773) (xy 440.283092 -13.043916)
			(xy 440.282667 -13.085188) (xy 440.275027 -13.167377) (xy 440.259804 -13.248505) (xy 440.23713 -13.327874)
			(xy 440.2072 -13.4048) (xy 440.170271 -13.478622) (xy 440.126661 -13.548705) (xy 440.076745 -13.614446)
			(xy 440.020952 -13.675279) (xy 439.959763 -13.730681) (xy 439.893704 -13.780175) (xy 439.823344 -13.823336)
			(xy 439.786522 -13.841984) (xy 439.778885 -13.846179) (xy 439.766763 -13.858679) (xy 439.759479 -13.874495)
			(xy 439.758328 -13.883132) (xy 439.755251 -13.911241) (xy 439.741951 -13.966197) (xy 439.720685 -14.018587)
			(xy 439.69192 -14.067266) (xy 439.656285 -14.111165) (xy 439.643167 -14.123162) (xy 440.58586 -14.123162)
			(xy 440.586283 -14.084873) (xy 440.592885 -14.008579) (xy 440.60603 -13.933136) (xy 440.625619 -13.859105)
			(xy 440.638184 -13.822934) (xy 440.640853 -13.814502) (xy 440.64084 -13.796827) (xy 440.638184 -13.78839)
			(xy 440.625655 -13.752208) (xy 440.606078 -13.678176) (xy 440.592927 -13.602738) (xy 440.586298 -13.52645)
			(xy 440.58586 -13.488162) (xy 440.586364 -13.445801) (xy 440.594417 -13.361464) (xy 440.610451 -13.278274)
			(xy 440.634319 -13.196984) (xy 440.665807 -13.118332) (xy 440.704629 -13.043029) (xy 440.750432 -12.971757)
			(xy 440.802803 -12.905161) (xy 440.861268 -12.843846) (xy 440.925296 -12.788365) (xy 440.994308 -12.739222)
			(xy 441.067678 -12.696862) (xy 441.144743 -12.661667) (xy 441.224805 -12.633958) (xy 441.307138 -12.613984)
			(xy 441.390997 -12.601927) (xy 441.475622 -12.597896) (xy 441.560247 -12.601927) (xy 441.644106 -12.613984)
			(xy 441.726439 -12.633958) (xy 441.806501 -12.661667) (xy 441.883566 -12.696862) (xy 441.956936 -12.739222)
			(xy 442.025948 -12.788365) (xy 442.089976 -12.843846) (xy 442.135955 -12.892066) (xy 445.44847 -12.892066)
			(xy 445.44847 -12.837534) (xy 445.456231 -12.783558) (xy 445.471594 -12.731236) (xy 445.494246 -12.681632)
			(xy 445.523728 -12.635757) (xy 445.559438 -12.594545) (xy 445.600649 -12.558834) (xy 445.646523 -12.529351)
			(xy 445.696126 -12.506697) (xy 445.748448 -12.491333) (xy 445.802424 -12.483571) (xy 445.82969 -12.483084)
			(xy 446.69329 -12.483084) (xy 446.720565 -12.483455) (xy 446.774559 -12.491217) (xy 446.826899 -12.506584)
			(xy 446.87652 -12.529244) (xy 446.92241 -12.558735) (xy 446.963636 -12.594456) (xy 446.999359 -12.635682)
			(xy 447.028851 -12.681571) (xy 447.051512 -12.731191) (xy 447.066881 -12.783531) (xy 447.074644 -12.837525)
			(xy 447.074644 -12.892075) (xy 447.066881 -12.946069) (xy 447.051512 -12.998409) (xy 447.028851 -13.048029)
			(xy 446.999359 -13.093918) (xy 446.963636 -13.135144) (xy 446.92241 -13.170865) (xy 446.87652 -13.200356)
			(xy 446.826899 -13.223016) (xy 446.774559 -13.238383) (xy 446.720565 -13.246145) (xy 446.69329 -13.246608)
			(xy 445.82969 -13.246608) (xy 445.802424 -13.246029) (xy 445.748448 -13.238267) (xy 445.696126 -13.222903)
			(xy 445.646523 -13.200249) (xy 445.600649 -13.170766) (xy 445.559438 -13.135055) (xy 445.523728 -13.093843)
			(xy 445.494246 -13.047968) (xy 445.471594 -12.998364) (xy 445.456231 -12.946042) (xy 445.44847 -12.892066)
			(xy 442.135955 -12.892066) (xy 442.148441 -12.905161) (xy 442.200812 -12.971757) (xy 442.246615 -13.043029)
			(xy 442.285437 -13.118332) (xy 442.316925 -13.196984) (xy 442.340793 -13.278274) (xy 442.356827 -13.361464)
			(xy 442.36488 -13.445801) (xy 442.365384 -13.488162) (xy 442.364966 -13.526452) (xy 442.358362 -13.602745)
			(xy 442.345216 -13.678188) (xy 442.325626 -13.752219) (xy 442.31306 -13.78839) (xy 442.310428 -13.796831)
			(xy 442.310415 -13.814498) (xy 442.31306 -13.822934) (xy 442.325598 -13.859113) (xy 442.345172 -13.933146)
			(xy 442.358321 -14.008585) (xy 442.364947 -14.084874) (xy 442.365384 -14.123162) (xy 442.36488 -14.165523)
			(xy 442.356827 -14.24986) (xy 442.340793 -14.33305) (xy 442.316925 -14.41434) (xy 442.285437 -14.492992)
			(xy 442.268155 -14.526514) (xy 449.780152 -14.526514) (xy 449.780656 -14.484153) (xy 449.788709 -14.399816)
			(xy 449.804743 -14.316626) (xy 449.828611 -14.235336) (xy 449.860099 -14.156684) (xy 449.898921 -14.081381)
			(xy 449.944724 -14.010109) (xy 449.997095 -13.943513) (xy 450.05556 -13.882198) (xy 450.119588 -13.826717)
			(xy 450.1886 -13.777574) (xy 450.26197 -13.735214) (xy 450.339035 -13.700019) (xy 450.419097 -13.67231)
			(xy 450.50143 -13.652336) (xy 450.585289 -13.640279) (xy 450.669914 -13.636248) (xy 450.754539 -13.640279)
			(xy 450.838398 -13.652336) (xy 450.920731 -13.67231) (xy 451.000793 -13.700019) (xy 451.077858 -13.735214)
			(xy 451.151228 -13.777574) (xy 451.22024 -13.826717) (xy 451.284268 -13.882198) (xy 451.342733 -13.943513)
			(xy 451.395104 -14.010109) (xy 451.440907 -14.081381) (xy 451.479729 -14.156684) (xy 451.511217 -14.235336)
			(xy 451.535085 -14.316626) (xy 451.551119 -14.399816) (xy 451.559172 -14.484153) (xy 451.559676 -14.526514)
			(xy 451.559114 -14.571839) (xy 451.549887 -14.662018) (xy 451.531531 -14.750791) (xy 451.504235 -14.837234)
			(xy 451.486778 -14.879066) (xy 451.483143 -14.888844) (xy 451.483128 -14.909681) (xy 451.486778 -14.919452)
			(xy 451.504363 -14.961485) (xy 451.531877 -15.048351) (xy 451.550364 -15.137575) (xy 451.559632 -15.228222)
			(xy 451.560184 -15.273782) (xy 451.559623 -15.318552) (xy 451.550621 -15.407639) (xy 451.532717 -15.495371)
			(xy 451.506092 -15.580861) (xy 451.489064 -15.62227) (xy 451.485509 -15.631864) (xy 451.485503 -15.652304)
			(xy 451.489064 -15.661894) (xy 451.50607 -15.703278) (xy 451.532693 -15.788702) (xy 451.550602 -15.876368)
			(xy 451.559616 -15.96539) (xy 451.560184 -16.010128) (xy 451.560184 -16.010382) (xy 451.55968 -16.05273)
			(xy 451.551629 -16.137044) (xy 451.5356 -16.22021) (xy 451.511739 -16.301477) (xy 451.48026 -16.380107)
			(xy 451.441449 -16.455388) (xy 451.395659 -16.52664) (xy 451.343303 -16.593216) (xy 451.284855 -16.654514)
			(xy 451.220845 -16.709979) (xy 451.151853 -16.759108) (xy 451.078503 -16.801457) (xy 451.00146 -16.836641)
			(xy 450.921421 -16.864343) (xy 450.839112 -16.884311) (xy 450.755277 -16.896364) (xy 450.670676 -16.900395)
			(xy 450.586075 -16.896364) (xy 450.50224 -16.884311) (xy 450.419931 -16.864343) (xy 450.339892 -16.836641)
			(xy 450.262849 -16.801457) (xy 450.189499 -16.759108) (xy 450.120507 -16.709979) (xy 450.056497 -16.654514)
			(xy 449.998049 -16.593216) (xy 449.945693 -16.52664) (xy 449.899903 -16.455388) (xy 449.861092 -16.380107)
			(xy 449.829613 -16.301477) (xy 449.805752 -16.22021) (xy 449.789723 -16.137044) (xy 449.781672 -16.05273)
			(xy 449.781168 -16.010382) (xy 449.781168 -16.010128) (xy 449.781731 -15.96539) (xy 449.790749 -15.876368)
			(xy 449.808655 -15.788701) (xy 449.83527 -15.703273) (xy 449.852288 -15.661894) (xy 449.855865 -15.652307)
			(xy 449.855859 -15.63186) (xy 449.852288 -15.62227) (xy 449.835263 -15.580859) (xy 449.808628 -15.495372)
			(xy 449.790721 -15.40764) (xy 449.781723 -15.318552) (xy 449.781168 -15.273782) (xy 449.781749 -15.228458)
			(xy 449.79099 -15.138283) (xy 449.809345 -15.049513) (xy 449.836623 -14.963067) (xy 449.854066 -14.92123)
			(xy 449.857691 -14.911438) (xy 449.857571 -14.890584) (xy 449.853812 -14.880844) (xy 449.836183 -14.838823)
			(xy 449.808624 -14.751958) (xy 449.790079 -14.662732) (xy 449.780742 -14.57208) (xy 449.780152 -14.526514)
			(xy 442.268155 -14.526514) (xy 442.246615 -14.568295) (xy 442.200812 -14.639567) (xy 442.148441 -14.706163)
			(xy 442.089976 -14.767478) (xy 442.025948 -14.822959) (xy 441.956936 -14.872102) (xy 441.883566 -14.914462)
			(xy 441.806501 -14.949657) (xy 441.726439 -14.977366) (xy 441.644106 -14.99734) (xy 441.560247 -15.009397)
			(xy 441.475622 -15.013429) (xy 441.390997 -15.009397) (xy 441.307138 -14.99734) (xy 441.224805 -14.977366)
			(xy 441.144743 -14.949657) (xy 441.067678 -14.914462) (xy 440.994308 -14.872102) (xy 440.925296 -14.822959)
			(xy 440.861268 -14.767478) (xy 440.802803 -14.706163) (xy 440.750432 -14.639567) (xy 440.704629 -14.568295)
			(xy 440.665807 -14.492992) (xy 440.634319 -14.41434) (xy 440.610451 -14.33305) (xy 440.594417 -14.24986)
			(xy 440.586364 -14.165523) (xy 440.58586 -14.123162) (xy 439.643167 -14.123162) (xy 439.614561 -14.149324)
			(xy 439.567661 -14.180907) (xy 439.516614 -14.205222) (xy 439.462537 -14.221736) (xy 439.406615 -14.230088)
			(xy 439.378344 -14.230604) (xy 439.350975 -14.230111) (xy 439.296797 -14.2223) (xy 439.244294 -14.206817)
			(xy 439.194547 -14.183981) (xy 439.148579 -14.154262) (xy 439.127646 -14.136624) (xy 439.127392 -14.13637)
			(xy 439.120314 -14.130771) (xy 439.103391 -14.124533) (xy 439.094372 -14.124178) (xy 439.027316 -14.124178)
			(xy 439.018301 -14.124547) (xy 439.001384 -14.130787) (xy 438.994296 -14.13637) (xy 438.994296 -14.136624)
			(xy 438.994042 -14.136624) (xy 438.973108 -14.154261) (xy 438.927135 -14.183972) (xy 438.877388 -14.206808)
			(xy 438.824888 -14.2223) (xy 438.770713 -14.230129) (xy 438.743344 -14.230604) (xy 438.713998 -14.230028)
			(xy 438.656001 -14.221024) (xy 438.600065 -14.203253) (xy 438.547506 -14.177132) (xy 438.499563 -14.143277)
			(xy 438.457364 -14.102486) (xy 438.421903 -14.055718) (xy 438.394015 -14.004075) (xy 438.38368 -13.976604)
			(xy 438.380221 -13.968026) (xy 438.368225 -13.953963) (xy 438.360312 -13.949172) (xy 438.333388 -13.93444)
			(xy 438.324705 -13.93016) (xy 438.305508 -13.927807) (xy 438.29605 -13.929868) (xy 438.259095 -13.939128)
			(xy 438.184005 -13.952036) (xy 438.108086 -13.958466) (xy 438.06999 -13.958824) (xy 438.028658 -13.958363)
			(xy 437.94635 -13.95071) (xy 437.865107 -13.935453) (xy 437.78563 -13.912724) (xy 437.708605 -13.882718)
			(xy 437.634696 -13.845694) (xy 437.564542 -13.801972) (xy 437.498747 -13.751929) (xy 437.43788 -13.695998)
			(xy 437.382465 -13.634659) (xy 437.332981 -13.568444) (xy 437.289854 -13.497922) (xy 437.253456 -13.423703)
			(xy 437.224103 -13.346427) (xy 437.202046 -13.266761) (xy 437.187477 -13.185391) (xy 437.18353 -13.144246)
			(xy 437.182106 -13.133691) (xy 437.171856 -13.11505) (xy 437.163718 -13.108178) (xy 437.131484 -13.082996)
			(xy 437.071245 -13.027653) (xy 437.016344 -12.967011) (xy 436.967245 -12.901582) (xy 436.924364 -12.831919)
			(xy 436.888063 -12.758612) (xy 436.858649 -12.682281) (xy 436.83637 -12.603571) (xy 436.821416 -12.523147)
			(xy 436.813913 -12.441689) (xy 436.813452 -12.400788) (xy 260.234662 -12.400788) (xy 260.203654 -12.412958)
			(xy 260.103162 -12.461353) (xy 260.006569 -12.517122) (xy 259.914413 -12.579954) (xy 259.82721 -12.649497)
			(xy 259.745448 -12.725362) (xy 259.669584 -12.807125) (xy 259.601843 -12.89207) (xy 431.453248 -12.89207)
			(xy 431.453248 -12.83753) (xy 431.46101 -12.783546) (xy 431.476376 -12.731216) (xy 431.499035 -12.681606)
			(xy 431.528523 -12.635726) (xy 431.564241 -12.594509) (xy 431.605461 -12.558796) (xy 431.651345 -12.529313)
			(xy 431.700957 -12.506661) (xy 431.753289 -12.4913) (xy 431.807274 -12.483544) (xy 431.834544 -12.483084)
			(xy 432.698144 -12.483084) (xy 432.725415 -12.483482) (xy 432.7794 -12.491249) (xy 432.83173 -12.50662)
			(xy 432.881341 -12.529282) (xy 432.927222 -12.558772) (xy 432.968439 -12.594492) (xy 433.004154 -12.635713)
			(xy 433.033639 -12.681598) (xy 433.056295 -12.731211) (xy 433.07166 -12.783543) (xy 433.079422 -12.837529)
			(xy 433.079422 -12.892071) (xy 433.07166 -12.946057) (xy 433.056295 -12.998389) (xy 433.033639 -13.048002)
			(xy 433.004154 -13.093887) (xy 432.968439 -13.135108) (xy 432.927222 -13.170828) (xy 432.881341 -13.200318)
			(xy 432.83173 -13.22298) (xy 432.7794 -13.238351) (xy 432.725415 -13.246118) (xy 432.698144 -13.246608)
			(xy 431.834544 -13.246608) (xy 431.807274 -13.246056) (xy 431.753289 -13.2383) (xy 431.700957 -13.222939)
			(xy 431.651345 -13.200287) (xy 431.605461 -13.170804) (xy 431.564241 -13.135091) (xy 431.528523 -13.093874)
			(xy 431.499035 -13.047994) (xy 431.476376 -12.998384) (xy 431.46101 -12.946054) (xy 431.453248 -12.89207)
			(xy 259.601843 -12.89207) (xy 259.600042 -12.894329) (xy 259.537211 -12.986486) (xy 259.481443 -13.08308)
			(xy 259.43305 -13.183572) (xy 259.392301 -13.287399) (xy 259.359426 -13.393981) (xy 259.334607 -13.502722)
			(xy 259.317984 -13.613014) (xy 259.309649 -13.724239) (xy 259.309108 -13.780008) (xy 259.309108 -17.126458)
			(xy 310.265572 -17.126458) (xy 310.265992 -17.082972) (xy 310.273576 -16.996331) (xy 310.288682 -16.910681)
			(xy 310.311195 -16.826674) (xy 310.340944 -16.744948) (xy 310.377702 -16.666126) (xy 310.421191 -16.590808)
			(xy 310.471078 -16.519566) (xy 310.526985 -16.452943) (xy 310.588485 -16.391447) (xy 310.65511 -16.335544)
			(xy 310.726355 -16.285661) (xy 310.801676 -16.242177) (xy 310.8805 -16.205422) (xy 310.962227 -16.175678)
			(xy 311.046236 -16.15317) (xy 311.131887 -16.138068) (xy 311.218528 -16.13049) (xy 311.262014 -16.130016)
			(xy 311.287414 -16.130016) (xy 311.33271 -16.130609) (xy 311.422936 -16.13873) (xy 311.512071 -16.154907)
			(xy 311.599397 -16.179009) (xy 311.684211 -16.210841) (xy 311.76583 -16.250148) (xy 311.843598 -16.296613)
			(xy 311.916887 -16.349861) (xy 311.985108 -16.409465) (xy 312.01736 -16.443198) (xy 389.814816 -16.443198)
			(xy 389.814816 -15.757398) (xy 389.81531 -15.745286) (xy 389.822795 -15.722246) (xy 389.837032 -15.702646)
			(xy 389.856628 -15.688404) (xy 389.879666 -15.680913) (xy 389.891778 -15.680436) (xy 390.086342 -15.680436)
			(xy 390.097468 -15.68085) (xy 390.118764 -15.68731) (xy 390.128252 -15.693136) (xy 390.421876 -15.885668)
			(xy 390.431259 -15.891373) (xy 390.452272 -15.897712) (xy 390.47422 -15.897786) (xy 390.495275 -15.891589)
			(xy 390.50468 -15.885922) (xy 390.800844 -15.693136) (xy 390.810337 -15.687325) (xy 390.831632 -15.680877)
			(xy 390.842754 -15.680436) (xy 391.037318 -15.680436) (xy 391.049433 -15.680896) (xy 391.072477 -15.688388)
			(xy 391.092078 -15.702633) (xy 391.106319 -15.722237) (xy 391.113806 -15.745283) (xy 391.11428 -15.757398)
			(xy 391.11428 -16.443198) (xy 395.402816 -16.443198) (xy 395.402816 -15.757398) (xy 395.40331 -15.745286)
			(xy 395.410795 -15.722246) (xy 395.425032 -15.702646) (xy 395.444628 -15.688404) (xy 395.467666 -15.680913)
			(xy 395.479778 -15.680436) (xy 395.674342 -15.680436) (xy 395.685468 -15.68085) (xy 395.706764 -15.68731)
			(xy 395.716252 -15.693136) (xy 396.009876 -15.885668) (xy 396.019259 -15.891373) (xy 396.040272 -15.897712)
			(xy 396.06222 -15.897786) (xy 396.083275 -15.891589) (xy 396.09268 -15.885922) (xy 396.388844 -15.693136)
			(xy 396.398337 -15.687325) (xy 396.419632 -15.680877) (xy 396.430754 -15.680436) (xy 396.625318 -15.680436)
			(xy 396.637433 -15.680896) (xy 396.660477 -15.688388) (xy 396.680078 -15.702633) (xy 396.694319 -15.722237)
			(xy 396.701806 -15.745283) (xy 396.70228 -15.757398) (xy 396.70228 -16.443198) (xy 400.990816 -16.443198)
			(xy 400.990816 -15.757398) (xy 400.99131 -15.745286) (xy 400.998795 -15.722246) (xy 401.013032 -15.702646)
			(xy 401.032628 -15.688404) (xy 401.055666 -15.680913) (xy 401.067778 -15.680436) (xy 401.262342 -15.680436)
			(xy 401.273468 -15.68085) (xy 401.294764 -15.68731) (xy 401.304252 -15.693136) (xy 401.597876 -15.885668)
			(xy 401.607259 -15.891373) (xy 401.628272 -15.897712) (xy 401.65022 -15.897786) (xy 401.671275 -15.891589)
			(xy 401.68068 -15.885922) (xy 401.976844 -15.693136) (xy 401.986337 -15.687325) (xy 402.007632 -15.680877)
			(xy 402.018754 -15.680436) (xy 402.213318 -15.680436) (xy 402.225433 -15.680896) (xy 402.248477 -15.688388)
			(xy 402.268078 -15.702633) (xy 402.282319 -15.722237) (xy 402.289806 -15.745283) (xy 402.29028 -15.757398)
			(xy 402.29028 -16.443198) (xy 406.578816 -16.443198) (xy 406.578816 -15.757398) (xy 406.57931 -15.745286)
			(xy 406.586795 -15.722246) (xy 406.601032 -15.702646) (xy 406.620628 -15.688404) (xy 406.643666 -15.680913)
			(xy 406.655778 -15.680436) (xy 406.850342 -15.680436) (xy 406.861468 -15.68085) (xy 406.882764 -15.68731)
			(xy 406.892252 -15.693136) (xy 407.185876 -15.885668) (xy 407.195259 -15.891373) (xy 407.216272 -15.897712)
			(xy 407.23822 -15.897786) (xy 407.259275 -15.891589) (xy 407.26868 -15.885922) (xy 407.564844 -15.693136)
			(xy 407.574337 -15.687325) (xy 407.595632 -15.680877) (xy 407.606754 -15.680436) (xy 407.801318 -15.680436)
			(xy 407.813433 -15.680896) (xy 407.836477 -15.688388) (xy 407.856078 -15.702633) (xy 407.870319 -15.722237)
			(xy 407.877806 -15.745283) (xy 407.87828 -15.757398) (xy 407.87828 -16.443198) (xy 412.166816 -16.443198)
			(xy 412.166816 -15.757398) (xy 412.16731 -15.745286) (xy 412.174795 -15.722246) (xy 412.189032 -15.702646)
			(xy 412.208628 -15.688404) (xy 412.231666 -15.680913) (xy 412.243778 -15.680436) (xy 412.438342 -15.680436)
			(xy 412.449468 -15.68085) (xy 412.470764 -15.68731) (xy 412.480252 -15.693136) (xy 412.773876 -15.885668)
			(xy 412.783259 -15.891373) (xy 412.804272 -15.897712) (xy 412.82622 -15.897786) (xy 412.847275 -15.891589)
			(xy 412.85668 -15.885922) (xy 413.152844 -15.693136) (xy 413.162337 -15.687325) (xy 413.183632 -15.680877)
			(xy 413.194754 -15.680436) (xy 413.389318 -15.680436) (xy 413.401433 -15.680896) (xy 413.424477 -15.688388)
			(xy 413.444078 -15.702633) (xy 413.458319 -15.722237) (xy 413.465806 -15.745283) (xy 413.46628 -15.757398)
			(xy 413.46628 -16.443198) (xy 418.060632 -16.443198) (xy 418.060632 -15.757398) (xy 418.06111 -15.745284)
			(xy 418.068597 -15.722242) (xy 418.082838 -15.702641) (xy 418.102438 -15.688399) (xy 418.12548 -15.680911)
			(xy 418.137594 -15.680436) (xy 418.332158 -15.680436) (xy 418.343284 -15.680844) (xy 418.364581 -15.687308)
			(xy 418.374068 -15.693136) (xy 418.667692 -15.885668) (xy 418.677068 -15.891386) (xy 418.698084 -15.897723)
			(xy 418.720035 -15.897793) (xy 418.741091 -15.891591) (xy 418.750496 -15.885922) (xy 419.04666 -15.693136)
			(xy 419.05615 -15.687319) (xy 419.077447 -15.680875) (xy 419.08857 -15.680436) (xy 419.283134 -15.680436)
			(xy 419.29525 -15.680883) (xy 419.318294 -15.688379) (xy 419.337895 -15.702628) (xy 419.352136 -15.722235)
			(xy 419.359622 -15.745282) (xy 419.360096 -15.757398) (xy 419.360096 -16.443198) (xy 423.648632 -16.443198)
			(xy 423.648632 -15.757398) (xy 423.64911 -15.745284) (xy 423.656597 -15.722242) (xy 423.670838 -15.702641)
			(xy 423.690438 -15.688399) (xy 423.71348 -15.680911) (xy 423.725594 -15.680436) (xy 423.920158 -15.680436)
			(xy 423.931284 -15.680844) (xy 423.952581 -15.687308) (xy 423.962068 -15.693136) (xy 424.255692 -15.885668)
			(xy 424.265068 -15.891386) (xy 424.286084 -15.897723) (xy 424.308035 -15.897793) (xy 424.329091 -15.891591)
			(xy 424.338496 -15.885922) (xy 424.63466 -15.693136) (xy 424.64415 -15.687319) (xy 424.665447 -15.680875)
			(xy 424.67657 -15.680436) (xy 424.871134 -15.680436) (xy 424.88325 -15.680883) (xy 424.906294 -15.688379)
			(xy 424.925895 -15.702628) (xy 424.940136 -15.722235) (xy 424.947622 -15.745282) (xy 424.948096 -15.757398)
			(xy 424.948096 -16.443198) (xy 429.270668 -16.443198) (xy 429.270668 -15.757398) (xy 429.271059 -15.745272)
			(xy 429.278555 -15.722208) (xy 429.292813 -15.702591) (xy 429.312437 -15.688341) (xy 429.335504 -15.680854)
			(xy 429.34763 -15.680436) (xy 429.542194 -15.680436) (xy 429.553318 -15.68087) (xy 429.574615 -15.687316)
			(xy 429.584104 -15.693136) (xy 429.877728 -15.885668) (xy 429.887087 -15.891417) (xy 429.908111 -15.897746)
			(xy 429.930067 -15.897808) (xy 429.951127 -15.891596) (xy 429.960532 -15.885922) (xy 430.256696 -15.693136)
			(xy 430.266199 -15.687343) (xy 430.287486 -15.680884) (xy 430.298606 -15.680436) (xy 430.49317 -15.680436)
			(xy 430.505291 -15.680885) (xy 430.528349 -15.688369) (xy 430.547964 -15.702613) (xy 430.562216 -15.722223)
			(xy 430.56971 -15.745277) (xy 430.570132 -15.757398) (xy 430.570132 -16.443198) (xy 430.569738 -16.455324)
			(xy 430.562242 -16.478387) (xy 430.547985 -16.498005) (xy 430.528362 -16.512255) (xy 430.505296 -16.519742)
			(xy 430.49317 -16.52016) (xy 430.298606 -16.52016) (xy 430.287482 -16.519727) (xy 430.266185 -16.513281)
			(xy 430.256696 -16.50746) (xy 429.961802 -16.314928) (xy 429.952415 -16.309225) (xy 429.931377 -16.302952)
			(xy 429.909423 -16.302952) (xy 429.888385 -16.309225) (xy 429.878998 -16.314928) (xy 429.585374 -16.50746)
			(xy 429.575877 -16.513264) (xy 429.554585 -16.519717) (xy 429.543464 -16.52016) (xy 429.34763 -16.52016)
			(xy 429.335509 -16.519715) (xy 429.31245 -16.51223) (xy 429.292835 -16.497985) (xy 429.278583 -16.478375)
			(xy 429.27109 -16.455319) (xy 429.270668 -16.443198) (xy 424.948096 -16.443198) (xy 424.947587 -16.455309)
			(xy 424.940104 -16.478346) (xy 424.925871 -16.497945) (xy 424.906279 -16.512188) (xy 424.883245 -16.519681)
			(xy 424.871134 -16.52016) (xy 424.67657 -16.52016) (xy 424.665445 -16.519741) (xy 424.644148 -16.513285)
			(xy 424.63466 -16.50746) (xy 424.339766 -16.314928) (xy 424.330379 -16.309225) (xy 424.309341 -16.302952)
			(xy 424.287387 -16.302952) (xy 424.266349 -16.309225) (xy 424.256962 -16.314928) (xy 423.963338 -16.50746)
			(xy 423.953848 -16.513277) (xy 423.932551 -16.519721) (xy 423.921428 -16.52016) (xy 423.725594 -16.52016)
			(xy 423.713479 -16.519693) (xy 423.690435 -16.512204) (xy 423.670834 -16.497961) (xy 423.656592 -16.478358)
			(xy 423.649106 -16.455313) (xy 423.648632 -16.443198) (xy 419.360096 -16.443198) (xy 419.359587 -16.455309)
			(xy 419.352104 -16.478346) (xy 419.337871 -16.497945) (xy 419.318279 -16.512188) (xy 419.295245 -16.519681)
			(xy 419.283134 -16.52016) (xy 419.08857 -16.52016) (xy 419.077445 -16.519741) (xy 419.056148 -16.513285)
			(xy 419.04666 -16.50746) (xy 418.751766 -16.314928) (xy 418.742379 -16.309225) (xy 418.721341 -16.302952)
			(xy 418.699387 -16.302952) (xy 418.678349 -16.309225) (xy 418.668962 -16.314928) (xy 418.375338 -16.50746)
			(xy 418.365848 -16.513277) (xy 418.344551 -16.519721) (xy 418.333428 -16.52016) (xy 418.137594 -16.52016)
			(xy 418.125479 -16.519693) (xy 418.102435 -16.512204) (xy 418.082834 -16.497961) (xy 418.068592 -16.478358)
			(xy 418.061106 -16.455313) (xy 418.060632 -16.443198) (xy 413.46628 -16.443198) (xy 413.465787 -16.455311)
			(xy 413.458302 -16.478351) (xy 413.444065 -16.497951) (xy 413.424469 -16.512193) (xy 413.401431 -16.519684)
			(xy 413.389318 -16.52016) (xy 413.194754 -16.52016) (xy 413.183628 -16.519748) (xy 413.162331 -16.513287)
			(xy 413.152844 -16.50746) (xy 412.85795 -16.314928) (xy 412.848563 -16.309225) (xy 412.827525 -16.302952)
			(xy 412.805571 -16.302952) (xy 412.784533 -16.309225) (xy 412.775146 -16.314928) (xy 412.481522 -16.50746)
			(xy 412.472016 -16.513247) (xy 412.450731 -16.51971) (xy 412.439612 -16.52016) (xy 412.243778 -16.52016)
			(xy 412.231662 -16.519707) (xy 412.208618 -16.512214) (xy 412.189016 -16.497967) (xy 412.174775 -16.478361)
			(xy 412.167289 -16.455314) (xy 412.166816 -16.443198) (xy 407.87828 -16.443198) (xy 407.877787 -16.455311)
			(xy 407.870302 -16.478351) (xy 407.856065 -16.497951) (xy 407.836469 -16.512193) (xy 407.813431 -16.519684)
			(xy 407.801318 -16.52016) (xy 407.606754 -16.52016) (xy 407.595628 -16.519748) (xy 407.574331 -16.513287)
			(xy 407.564844 -16.50746) (xy 407.26995 -16.314928) (xy 407.260563 -16.309225) (xy 407.239525 -16.302952)
			(xy 407.217571 -16.302952) (xy 407.196533 -16.309225) (xy 407.187146 -16.314928) (xy 406.893522 -16.50746)
			(xy 406.884016 -16.513247) (xy 406.862731 -16.51971) (xy 406.851612 -16.52016) (xy 406.655778 -16.52016)
			(xy 406.643662 -16.519707) (xy 406.620618 -16.512214) (xy 406.601016 -16.497967) (xy 406.586775 -16.478361)
			(xy 406.579289 -16.455314) (xy 406.578816 -16.443198) (xy 402.29028 -16.443198) (xy 402.289787 -16.455311)
			(xy 402.282302 -16.478351) (xy 402.268065 -16.497951) (xy 402.248469 -16.512193) (xy 402.225431 -16.519684)
			(xy 402.213318 -16.52016) (xy 402.018754 -16.52016) (xy 402.007628 -16.519748) (xy 401.986331 -16.513287)
			(xy 401.976844 -16.50746) (xy 401.68195 -16.314928) (xy 401.672563 -16.309225) (xy 401.651525 -16.302952)
			(xy 401.629571 -16.302952) (xy 401.608533 -16.309225) (xy 401.599146 -16.314928) (xy 401.305522 -16.50746)
			(xy 401.296016 -16.513247) (xy 401.274731 -16.51971) (xy 401.263612 -16.52016) (xy 401.067778 -16.52016)
			(xy 401.055662 -16.519707) (xy 401.032618 -16.512214) (xy 401.013016 -16.497967) (xy 400.998775 -16.478361)
			(xy 400.991289 -16.455314) (xy 400.990816 -16.443198) (xy 396.70228 -16.443198) (xy 396.701787 -16.455311)
			(xy 396.694302 -16.478351) (xy 396.680065 -16.497951) (xy 396.660469 -16.512193) (xy 396.637431 -16.519684)
			(xy 396.625318 -16.52016) (xy 396.430754 -16.52016) (xy 396.419628 -16.519748) (xy 396.398331 -16.513287)
			(xy 396.388844 -16.50746) (xy 396.09395 -16.314928) (xy 396.084563 -16.309225) (xy 396.063525 -16.302952)
			(xy 396.041571 -16.302952) (xy 396.020533 -16.309225) (xy 396.011146 -16.314928) (xy 395.717522 -16.50746)
			(xy 395.708016 -16.513247) (xy 395.686731 -16.51971) (xy 395.675612 -16.52016) (xy 395.479778 -16.52016)
			(xy 395.467662 -16.519707) (xy 395.444618 -16.512214) (xy 395.425016 -16.497967) (xy 395.410775 -16.478361)
			(xy 395.403289 -16.455314) (xy 395.402816 -16.443198) (xy 391.11428 -16.443198) (xy 391.113787 -16.455311)
			(xy 391.106302 -16.478351) (xy 391.092065 -16.497951) (xy 391.072469 -16.512193) (xy 391.049431 -16.519684)
			(xy 391.037318 -16.52016) (xy 390.842754 -16.52016) (xy 390.831628 -16.519748) (xy 390.810331 -16.513287)
			(xy 390.800844 -16.50746) (xy 390.50595 -16.314928) (xy 390.496563 -16.309225) (xy 390.475525 -16.302952)
			(xy 390.453571 -16.302952) (xy 390.432533 -16.309225) (xy 390.423146 -16.314928) (xy 390.129522 -16.50746)
			(xy 390.120016 -16.513247) (xy 390.098731 -16.51971) (xy 390.087612 -16.52016) (xy 389.891778 -16.52016)
			(xy 389.879662 -16.519707) (xy 389.856618 -16.512214) (xy 389.837016 -16.497967) (xy 389.822775 -16.478361)
			(xy 389.815289 -16.455314) (xy 389.814816 -16.443198) (xy 312.01736 -16.443198) (xy 312.047712 -16.474944)
			(xy 312.104194 -16.545772) (xy 312.1541 -16.621377) (xy 312.197028 -16.701151) (xy 312.232632 -16.784452)
			(xy 312.260626 -16.870609) (xy 312.280784 -16.958929) (xy 312.292944 -17.0487) (xy 312.297009 -17.1392)
			(xy 312.292944 -17.2297) (xy 312.280784 -17.319471) (xy 312.260626 -17.407791) (xy 312.232632 -17.493948)
			(xy 312.197028 -17.577249) (xy 312.163448 -17.639652) (xy 389.652738 -17.639652) (xy 389.652738 -17.585148)
			(xy 389.660494 -17.531197) (xy 389.675849 -17.4789) (xy 389.69849 -17.42932) (xy 389.727956 -17.383466)
			(xy 389.763647 -17.342273) (xy 389.804838 -17.306578) (xy 389.850688 -17.277107) (xy 389.900266 -17.254462)
			(xy 389.952562 -17.239102) (xy 390.006512 -17.23134) (xy 390.033764 -17.230852) (xy 390.897364 -17.230852)
			(xy 390.924616 -17.231393) (xy 390.978565 -17.239145) (xy 391.030862 -17.254496) (xy 391.080441 -17.277134)
			(xy 391.126294 -17.306598) (xy 391.167486 -17.342288) (xy 391.20318 -17.383477) (xy 391.232649 -17.429327)
			(xy 391.255291 -17.478905) (xy 391.270648 -17.5312) (xy 391.278405 -17.585148) (xy 391.278405 -17.639652)
			(xy 391.270648 -17.6936) (xy 391.255291 -17.745895) (xy 391.232649 -17.795473) (xy 391.20318 -17.841323)
			(xy 391.167486 -17.882512) (xy 391.126294 -17.918202) (xy 391.080441 -17.947666) (xy 391.037664 -17.967198)
			(xy 392.608816 -17.967198) (xy 392.608816 -17.281398) (xy 392.60931 -17.269286) (xy 392.616795 -17.246246)
			(xy 392.631032 -17.226646) (xy 392.650628 -17.212404) (xy 392.673666 -17.204913) (xy 392.685778 -17.204436)
			(xy 392.880342 -17.204436) (xy 392.891468 -17.20485) (xy 392.912764 -17.21131) (xy 392.922252 -17.217136)
			(xy 393.215876 -17.409668) (xy 393.225259 -17.415373) (xy 393.246272 -17.421712) (xy 393.26822 -17.421786)
			(xy 393.289275 -17.415589) (xy 393.29868 -17.409922) (xy 393.594844 -17.217136) (xy 393.604337 -17.211325)
			(xy 393.625632 -17.204877) (xy 393.636754 -17.204436) (xy 393.831318 -17.204436) (xy 393.843433 -17.204896)
			(xy 393.866477 -17.212388) (xy 393.886078 -17.226633) (xy 393.900319 -17.246237) (xy 393.907806 -17.269283)
			(xy 393.90828 -17.281398) (xy 393.90828 -17.639652) (xy 395.240738 -17.639652) (xy 395.240738 -17.585148)
			(xy 395.248494 -17.531197) (xy 395.263849 -17.4789) (xy 395.28649 -17.42932) (xy 395.315956 -17.383466)
			(xy 395.351647 -17.342273) (xy 395.392838 -17.306578) (xy 395.438688 -17.277107) (xy 395.488266 -17.254462)
			(xy 395.540562 -17.239102) (xy 395.594512 -17.23134) (xy 395.621764 -17.230852) (xy 396.485364 -17.230852)
			(xy 396.512616 -17.231393) (xy 396.566565 -17.239145) (xy 396.618862 -17.254496) (xy 396.668441 -17.277134)
			(xy 396.714294 -17.306598) (xy 396.755486 -17.342288) (xy 396.79118 -17.383477) (xy 396.820649 -17.429327)
			(xy 396.843291 -17.478905) (xy 396.858648 -17.5312) (xy 396.866405 -17.585148) (xy 396.866405 -17.639652)
			(xy 396.858648 -17.6936) (xy 396.843291 -17.745895) (xy 396.820649 -17.795473) (xy 396.79118 -17.841323)
			(xy 396.755486 -17.882512) (xy 396.714294 -17.918202) (xy 396.668441 -17.947666) (xy 396.625664 -17.967198)
			(xy 398.196816 -17.967198) (xy 398.196816 -17.281398) (xy 398.19731 -17.269286) (xy 398.204795 -17.246246)
			(xy 398.219032 -17.226646) (xy 398.238628 -17.212404) (xy 398.261666 -17.204913) (xy 398.273778 -17.204436)
			(xy 398.468342 -17.204436) (xy 398.479468 -17.20485) (xy 398.500764 -17.21131) (xy 398.510252 -17.217136)
			(xy 398.803876 -17.409668) (xy 398.813259 -17.415373) (xy 398.834272 -17.421712) (xy 398.85622 -17.421786)
			(xy 398.877275 -17.415589) (xy 398.88668 -17.409922) (xy 399.182844 -17.217136) (xy 399.192337 -17.211325)
			(xy 399.213632 -17.204877) (xy 399.224754 -17.204436) (xy 399.419318 -17.204436) (xy 399.431433 -17.204896)
			(xy 399.454477 -17.212388) (xy 399.474078 -17.226633) (xy 399.488319 -17.246237) (xy 399.495806 -17.269283)
			(xy 399.49628 -17.281398) (xy 399.49628 -17.639652) (xy 400.828738 -17.639652) (xy 400.828738 -17.585148)
			(xy 400.836494 -17.531197) (xy 400.851849 -17.4789) (xy 400.87449 -17.42932) (xy 400.903956 -17.383466)
			(xy 400.939647 -17.342273) (xy 400.980838 -17.306578) (xy 401.026688 -17.277107) (xy 401.076266 -17.254462)
			(xy 401.128562 -17.239102) (xy 401.182512 -17.23134) (xy 401.209764 -17.230852) (xy 402.073364 -17.230852)
			(xy 402.100616 -17.231393) (xy 402.154565 -17.239145) (xy 402.206862 -17.254496) (xy 402.256441 -17.277134)
			(xy 402.302294 -17.306598) (xy 402.343486 -17.342288) (xy 402.37918 -17.383477) (xy 402.408649 -17.429327)
			(xy 402.431291 -17.478905) (xy 402.446648 -17.5312) (xy 402.454405 -17.585148) (xy 402.454405 -17.639652)
			(xy 402.446648 -17.6936) (xy 402.431291 -17.745895) (xy 402.408649 -17.795473) (xy 402.37918 -17.841323)
			(xy 402.343486 -17.882512) (xy 402.302294 -17.918202) (xy 402.256441 -17.947666) (xy 402.213664 -17.967198)
			(xy 403.784816 -17.967198) (xy 403.784816 -17.281398) (xy 403.78531 -17.269286) (xy 403.792795 -17.246246)
			(xy 403.807032 -17.226646) (xy 403.826628 -17.212404) (xy 403.849666 -17.204913) (xy 403.861778 -17.204436)
			(xy 404.056342 -17.204436) (xy 404.067468 -17.20485) (xy 404.088764 -17.21131) (xy 404.098252 -17.217136)
			(xy 404.391876 -17.409668) (xy 404.401259 -17.415373) (xy 404.422272 -17.421712) (xy 404.44422 -17.421786)
			(xy 404.465275 -17.415589) (xy 404.47468 -17.409922) (xy 404.770844 -17.217136) (xy 404.780337 -17.211325)
			(xy 404.801632 -17.204877) (xy 404.812754 -17.204436) (xy 405.007318 -17.204436) (xy 405.019433 -17.204896)
			(xy 405.042477 -17.212388) (xy 405.062078 -17.226633) (xy 405.076319 -17.246237) (xy 405.083806 -17.269283)
			(xy 405.08428 -17.281398) (xy 405.08428 -17.640372) (xy 406.415424 -17.640372) (xy 406.415424 -17.585828)
			(xy 406.423187 -17.53184) (xy 406.438554 -17.479507) (xy 406.461214 -17.429893) (xy 406.490704 -17.38401)
			(xy 406.526425 -17.342791) (xy 406.567649 -17.307076) (xy 406.613536 -17.277591) (xy 406.663152 -17.254938)
			(xy 406.715487 -17.239576) (xy 406.769476 -17.23182) (xy 406.796748 -17.23136) (xy 407.660348 -17.23136)
			(xy 407.687617 -17.231806) (xy 407.741598 -17.239573) (xy 407.793925 -17.254944) (xy 407.843532 -17.277604)
			(xy 407.88941 -17.307093) (xy 407.930624 -17.34281) (xy 407.966336 -17.384029) (xy 407.995819 -17.42991)
			(xy 408.018473 -17.47952) (xy 408.033837 -17.531849) (xy 408.041598 -17.585831) (xy 408.041598 -17.640369)
			(xy 408.033837 -17.694351) (xy 408.018473 -17.74668) (xy 407.995819 -17.79629) (xy 407.966336 -17.842171)
			(xy 407.930624 -17.88339) (xy 407.88941 -17.919107) (xy 407.843532 -17.948596) (xy 407.802809 -17.967198)
			(xy 409.372816 -17.967198) (xy 409.372816 -17.281398) (xy 409.37331 -17.269286) (xy 409.380795 -17.246246)
			(xy 409.395032 -17.226646) (xy 409.414628 -17.212404) (xy 409.437666 -17.204913) (xy 409.449778 -17.204436)
			(xy 409.644342 -17.204436) (xy 409.655468 -17.20485) (xy 409.676764 -17.21131) (xy 409.686252 -17.217136)
			(xy 409.979876 -17.409668) (xy 409.989259 -17.415373) (xy 410.010272 -17.421712) (xy 410.03222 -17.421786)
			(xy 410.053275 -17.415589) (xy 410.06268 -17.409922) (xy 410.358844 -17.217136) (xy 410.368337 -17.211325)
			(xy 410.389632 -17.204877) (xy 410.400754 -17.204436) (xy 410.595318 -17.204436) (xy 410.607433 -17.204896)
			(xy 410.630477 -17.212388) (xy 410.650078 -17.226633) (xy 410.664319 -17.246237) (xy 410.671806 -17.269283)
			(xy 410.67228 -17.281398) (xy 410.67228 -17.640372) (xy 412.003424 -17.640372) (xy 412.003424 -17.585828)
			(xy 412.011187 -17.53184) (xy 412.026554 -17.479507) (xy 412.049214 -17.429893) (xy 412.078704 -17.38401)
			(xy 412.114425 -17.342791) (xy 412.155649 -17.307076) (xy 412.201536 -17.277591) (xy 412.251152 -17.254938)
			(xy 412.303487 -17.239576) (xy 412.357476 -17.23182) (xy 412.384748 -17.23136) (xy 413.248348 -17.23136)
			(xy 413.275617 -17.231806) (xy 413.329598 -17.239573) (xy 413.381925 -17.254944) (xy 413.431532 -17.277604)
			(xy 413.47741 -17.307093) (xy 413.518624 -17.34281) (xy 413.554336 -17.384029) (xy 413.583819 -17.42991)
			(xy 413.606473 -17.47952) (xy 413.621837 -17.531849) (xy 413.629598 -17.585831) (xy 413.629598 -17.640369)
			(xy 413.621837 -17.694351) (xy 413.606473 -17.74668) (xy 413.583819 -17.79629) (xy 413.554336 -17.842171)
			(xy 413.518624 -17.88339) (xy 413.47741 -17.919107) (xy 413.431532 -17.948596) (xy 413.390809 -17.967198)
			(xy 415.266632 -17.967198) (xy 415.266632 -17.281398) (xy 415.26711 -17.269284) (xy 415.274597 -17.246242)
			(xy 415.288838 -17.226641) (xy 415.308438 -17.212399) (xy 415.33148 -17.204911) (xy 415.343594 -17.204436)
			(xy 415.538158 -17.204436) (xy 415.549284 -17.204844) (xy 415.570581 -17.211308) (xy 415.580068 -17.217136)
			(xy 415.873692 -17.409668) (xy 415.883068 -17.415386) (xy 415.904084 -17.421723) (xy 415.926035 -17.421793)
			(xy 415.947091 -17.415591) (xy 415.956496 -17.409922) (xy 416.25266 -17.217136) (xy 416.26215 -17.211319)
			(xy 416.283447 -17.204875) (xy 416.29457 -17.204436) (xy 416.489134 -17.204436) (xy 416.50125 -17.204883)
			(xy 416.524294 -17.212379) (xy 416.543895 -17.226628) (xy 416.558136 -17.246235) (xy 416.565622 -17.269282)
			(xy 416.566096 -17.281398) (xy 416.566096 -17.639653) (xy 417.898538 -17.639653) (xy 417.898538 -17.585147)
			(xy 417.906295 -17.531195) (xy 417.92165 -17.478897) (xy 417.944292 -17.429315) (xy 417.97376 -17.383461)
			(xy 418.009453 -17.342267) (xy 418.050645 -17.306572) (xy 418.096498 -17.277102) (xy 418.146078 -17.254457)
			(xy 418.198376 -17.239099) (xy 418.252327 -17.231339) (xy 418.27958 -17.230852) (xy 419.14318 -17.230852)
			(xy 419.170431 -17.231394) (xy 419.224378 -17.239148) (xy 419.276673 -17.2545) (xy 419.326251 -17.277139)
			(xy 419.372101 -17.306604) (xy 419.413292 -17.342294) (xy 419.448984 -17.383483) (xy 419.478451 -17.429332)
			(xy 419.501093 -17.478908) (xy 419.516448 -17.531202) (xy 419.524205 -17.585149) (xy 419.524205 -17.639651)
			(xy 419.516448 -17.693598) (xy 419.501093 -17.745892) (xy 419.478451 -17.795468) (xy 419.448984 -17.841317)
			(xy 419.413292 -17.882506) (xy 419.372101 -17.918196) (xy 419.326251 -17.947661) (xy 419.283466 -17.967198)
			(xy 420.854632 -17.967198) (xy 420.854632 -17.281398) (xy 420.85511 -17.269284) (xy 420.862597 -17.246242)
			(xy 420.876838 -17.226641) (xy 420.896438 -17.212399) (xy 420.91948 -17.204911) (xy 420.931594 -17.204436)
			(xy 421.126158 -17.204436) (xy 421.137284 -17.204844) (xy 421.158581 -17.211308) (xy 421.168068 -17.217136)
			(xy 421.461692 -17.409668) (xy 421.471068 -17.415386) (xy 421.492084 -17.421723) (xy 421.514035 -17.421793)
			(xy 421.535091 -17.415591) (xy 421.544496 -17.409922) (xy 421.84066 -17.217136) (xy 421.85015 -17.211319)
			(xy 421.871447 -17.204875) (xy 421.88257 -17.204436) (xy 422.077134 -17.204436) (xy 422.08925 -17.204883)
			(xy 422.112294 -17.212379) (xy 422.131895 -17.226628) (xy 422.146136 -17.246235) (xy 422.153622 -17.269282)
			(xy 422.154096 -17.281398) (xy 422.154096 -17.639653) (xy 423.486538 -17.639653) (xy 423.486538 -17.585147)
			(xy 423.494295 -17.531195) (xy 423.50965 -17.478897) (xy 423.532292 -17.429315) (xy 423.56176 -17.383461)
			(xy 423.597453 -17.342267) (xy 423.638645 -17.306572) (xy 423.684498 -17.277102) (xy 423.734078 -17.254457)
			(xy 423.786376 -17.239099) (xy 423.840327 -17.231339) (xy 423.86758 -17.230852) (xy 424.73118 -17.230852)
			(xy 424.758431 -17.231394) (xy 424.812378 -17.239148) (xy 424.864673 -17.2545) (xy 424.914251 -17.277139)
			(xy 424.960101 -17.306604) (xy 425.001292 -17.342294) (xy 425.036984 -17.383483) (xy 425.066451 -17.429332)
			(xy 425.089093 -17.478908) (xy 425.104448 -17.531202) (xy 425.112205 -17.585149) (xy 425.112205 -17.639651)
			(xy 425.104448 -17.693598) (xy 425.089093 -17.745892) (xy 425.066451 -17.795468) (xy 425.036984 -17.841317)
			(xy 425.001292 -17.882506) (xy 424.960101 -17.918196) (xy 424.914251 -17.947661) (xy 424.871466 -17.967198)
			(xy 426.476668 -17.967198) (xy 426.476668 -17.281398) (xy 426.477059 -17.269272) (xy 426.484555 -17.246208)
			(xy 426.498813 -17.226591) (xy 426.518437 -17.212341) (xy 426.541504 -17.204854) (xy 426.55363 -17.204436)
			(xy 426.748194 -17.204436) (xy 426.759318 -17.20487) (xy 426.780615 -17.211316) (xy 426.790104 -17.217136)
			(xy 427.083728 -17.409668) (xy 427.093087 -17.415417) (xy 427.114111 -17.421746) (xy 427.136067 -17.421808)
			(xy 427.157127 -17.415596) (xy 427.166532 -17.409922) (xy 427.462696 -17.217136) (xy 427.472199 -17.211343)
			(xy 427.493486 -17.204884) (xy 427.504606 -17.204436) (xy 427.69917 -17.204436) (xy 427.711291 -17.204885)
			(xy 427.734349 -17.212369) (xy 427.753964 -17.226613) (xy 427.768216 -17.246223) (xy 427.77571 -17.269277)
			(xy 427.776132 -17.281398) (xy 427.776132 -17.640368) (xy 429.107346 -17.640368) (xy 429.107346 -17.585832)
			(xy 429.115108 -17.531852) (xy 429.130472 -17.479525) (xy 429.153127 -17.429918) (xy 429.182611 -17.38404)
			(xy 429.218324 -17.342824) (xy 429.25954 -17.307111) (xy 429.305418 -17.277627) (xy 429.355025 -17.254972)
			(xy 429.407352 -17.239608) (xy 429.461332 -17.231846) (xy 429.4886 -17.23136) (xy 430.3522 -17.23136)
			(xy 430.379471 -17.231802) (xy 430.433458 -17.239565) (xy 430.48579 -17.254931) (xy 430.535403 -17.277588)
			(xy 430.581287 -17.307076) (xy 430.622507 -17.342793) (xy 430.658224 -17.384013) (xy 430.687712 -17.429897)
			(xy 430.710369 -17.47951) (xy 430.725735 -17.531842) (xy 430.733498 -17.585829) (xy 430.733498 -17.640371)
			(xy 430.725735 -17.694358) (xy 430.710369 -17.74669) (xy 430.687712 -17.796303) (xy 430.658224 -17.842187)
			(xy 430.622507 -17.883407) (xy 430.581287 -17.919124) (xy 430.535403 -17.948612) (xy 430.494704 -17.967198)
			(xy 432.064668 -17.967198) (xy 432.064668 -17.281398) (xy 432.065059 -17.269272) (xy 432.072555 -17.246208)
			(xy 432.086813 -17.226591) (xy 432.106437 -17.212341) (xy 432.129504 -17.204854) (xy 432.14163 -17.204436)
			(xy 432.336194 -17.204436) (xy 432.347318 -17.20487) (xy 432.368615 -17.211316) (xy 432.378104 -17.217136)
			(xy 432.671728 -17.409668) (xy 432.681087 -17.415417) (xy 432.702111 -17.421746) (xy 432.724067 -17.421808)
			(xy 432.745127 -17.415596) (xy 432.754532 -17.409922) (xy 433.050696 -17.217136) (xy 433.060199 -17.211343)
			(xy 433.081486 -17.204884) (xy 433.092606 -17.204436) (xy 433.28717 -17.204436) (xy 433.299291 -17.204885)
			(xy 433.322349 -17.212369) (xy 433.341964 -17.226613) (xy 433.356216 -17.246223) (xy 433.36371 -17.269277)
			(xy 433.364132 -17.281398) (xy 433.364132 -17.967198) (xy 433.363738 -17.979324) (xy 433.356242 -18.002387)
			(xy 433.341985 -18.022005) (xy 433.322362 -18.036255) (xy 433.299296 -18.043742) (xy 433.28717 -18.04416)
			(xy 433.092606 -18.04416) (xy 433.081482 -18.043727) (xy 433.060185 -18.037281) (xy 433.050696 -18.03146)
			(xy 432.755802 -17.838928) (xy 432.746415 -17.833225) (xy 432.725377 -17.826952) (xy 432.703423 -17.826952)
			(xy 432.682385 -17.833225) (xy 432.672998 -17.838928) (xy 432.379374 -18.03146) (xy 432.369877 -18.037264)
			(xy 432.348585 -18.043717) (xy 432.337464 -18.04416) (xy 432.14163 -18.04416) (xy 432.129509 -18.043715)
			(xy 432.10645 -18.03623) (xy 432.086835 -18.021985) (xy 432.072583 -18.002375) (xy 432.06509 -17.979319)
			(xy 432.064668 -17.967198) (xy 430.494704 -17.967198) (xy 430.48579 -17.971269) (xy 430.433458 -17.986635)
			(xy 430.379471 -17.994398) (xy 430.3522 -17.994884) (xy 429.4886 -17.994884) (xy 429.461332 -17.994354)
			(xy 429.407352 -17.986592) (xy 429.355025 -17.971228) (xy 429.305418 -17.948573) (xy 429.25954 -17.919089)
			(xy 429.218324 -17.883376) (xy 429.182611 -17.84216) (xy 429.153127 -17.796282) (xy 429.130472 -17.746675)
			(xy 429.115108 -17.694348) (xy 429.107346 -17.640368) (xy 427.776132 -17.640368) (xy 427.776132 -17.967198)
			(xy 427.775738 -17.979324) (xy 427.768242 -18.002387) (xy 427.753985 -18.022005) (xy 427.734362 -18.036255)
			(xy 427.711296 -18.043742) (xy 427.69917 -18.04416) (xy 427.504606 -18.04416) (xy 427.493482 -18.043727)
			(xy 427.472185 -18.037281) (xy 427.462696 -18.03146) (xy 427.167802 -17.838928) (xy 427.158415 -17.833225)
			(xy 427.137377 -17.826952) (xy 427.115423 -17.826952) (xy 427.094385 -17.833225) (xy 427.084998 -17.838928)
			(xy 426.791374 -18.03146) (xy 426.781877 -18.037264) (xy 426.760585 -18.043717) (xy 426.749464 -18.04416)
			(xy 426.55363 -18.04416) (xy 426.541509 -18.043715) (xy 426.51845 -18.03623) (xy 426.498835 -18.021985)
			(xy 426.484583 -18.002375) (xy 426.47709 -17.979319) (xy 426.476668 -17.967198) (xy 424.871466 -17.967198)
			(xy 424.864673 -17.9703) (xy 424.812378 -17.985652) (xy 424.758431 -17.993406) (xy 424.73118 -17.993868)
			(xy 423.86758 -17.993868) (xy 423.840327 -17.993461) (xy 423.786376 -17.985701) (xy 423.734078 -17.970343)
			(xy 423.684498 -17.947698) (xy 423.638645 -17.918228) (xy 423.597453 -17.882533) (xy 423.56176 -17.841339)
			(xy 423.532292 -17.795485) (xy 423.50965 -17.745903) (xy 423.494295 -17.693605) (xy 423.486538 -17.639653)
			(xy 422.154096 -17.639653) (xy 422.154096 -17.967198) (xy 422.153587 -17.979309) (xy 422.146104 -18.002346)
			(xy 422.131871 -18.021945) (xy 422.112279 -18.036188) (xy 422.089245 -18.043681) (xy 422.077134 -18.04416)
			(xy 421.88257 -18.04416) (xy 421.871445 -18.043741) (xy 421.850148 -18.037285) (xy 421.84066 -18.03146)
			(xy 421.545766 -17.838928) (xy 421.536379 -17.833225) (xy 421.515341 -17.826952) (xy 421.493387 -17.826952)
			(xy 421.472349 -17.833225) (xy 421.462962 -17.838928) (xy 421.169338 -18.03146) (xy 421.159848 -18.037277)
			(xy 421.138551 -18.043721) (xy 421.127428 -18.04416) (xy 420.931594 -18.04416) (xy 420.919479 -18.043693)
			(xy 420.896435 -18.036204) (xy 420.876834 -18.021961) (xy 420.862592 -18.002358) (xy 420.855106 -17.979313)
			(xy 420.854632 -17.967198) (xy 419.283466 -17.967198) (xy 419.276673 -17.9703) (xy 419.224378 -17.985652)
			(xy 419.170431 -17.993406) (xy 419.14318 -17.993868) (xy 418.27958 -17.993868) (xy 418.252327 -17.993461)
			(xy 418.198376 -17.985701) (xy 418.146078 -17.970343) (xy 418.096498 -17.947698) (xy 418.050645 -17.918228)
			(xy 418.009453 -17.882533) (xy 417.97376 -17.841339) (xy 417.944292 -17.795485) (xy 417.92165 -17.745903)
			(xy 417.906295 -17.693605) (xy 417.898538 -17.639653) (xy 416.566096 -17.639653) (xy 416.566096 -17.967198)
			(xy 416.565587 -17.979309) (xy 416.558104 -18.002346) (xy 416.543871 -18.021945) (xy 416.524279 -18.036188)
			(xy 416.501245 -18.043681) (xy 416.489134 -18.04416) (xy 416.29457 -18.04416) (xy 416.283445 -18.043741)
			(xy 416.262148 -18.037285) (xy 416.25266 -18.03146) (xy 415.957766 -17.838928) (xy 415.948379 -17.833225)
			(xy 415.927341 -17.826952) (xy 415.905387 -17.826952) (xy 415.884349 -17.833225) (xy 415.874962 -17.838928)
			(xy 415.581338 -18.03146) (xy 415.571848 -18.037277) (xy 415.550551 -18.043721) (xy 415.539428 -18.04416)
			(xy 415.343594 -18.04416) (xy 415.331479 -18.043693) (xy 415.308435 -18.036204) (xy 415.288834 -18.021961)
			(xy 415.274592 -18.002358) (xy 415.267106 -17.979313) (xy 415.266632 -17.967198) (xy 413.390809 -17.967198)
			(xy 413.381925 -17.971256) (xy 413.329598 -17.986627) (xy 413.275617 -17.994394) (xy 413.248348 -17.994884)
			(xy 412.384748 -17.994884) (xy 412.357476 -17.99438) (xy 412.303487 -17.986624) (xy 412.251152 -17.971262)
			(xy 412.201536 -17.948609) (xy 412.155649 -17.919124) (xy 412.114425 -17.883409) (xy 412.078704 -17.84219)
			(xy 412.049214 -17.796307) (xy 412.026554 -17.746693) (xy 412.011187 -17.69436) (xy 412.003424 -17.640372)
			(xy 410.67228 -17.640372) (xy 410.67228 -17.967198) (xy 410.671787 -17.979311) (xy 410.664302 -18.002351)
			(xy 410.650065 -18.021951) (xy 410.630469 -18.036193) (xy 410.607431 -18.043684) (xy 410.595318 -18.04416)
			(xy 410.400754 -18.04416) (xy 410.389628 -18.043748) (xy 410.368331 -18.037287) (xy 410.358844 -18.03146)
			(xy 410.06395 -17.838928) (xy 410.054563 -17.833225) (xy 410.033525 -17.826952) (xy 410.011571 -17.826952)
			(xy 409.990533 -17.833225) (xy 409.981146 -17.838928) (xy 409.687522 -18.03146) (xy 409.678016 -18.037247)
			(xy 409.656731 -18.04371) (xy 409.645612 -18.04416) (xy 409.449778 -18.04416) (xy 409.437662 -18.043707)
			(xy 409.414618 -18.036214) (xy 409.395016 -18.021967) (xy 409.380775 -18.002361) (xy 409.373289 -17.979314)
			(xy 409.372816 -17.967198) (xy 407.802809 -17.967198) (xy 407.793925 -17.971256) (xy 407.741598 -17.986627)
			(xy 407.687617 -17.994394) (xy 407.660348 -17.994884) (xy 406.796748 -17.994884) (xy 406.769476 -17.99438)
			(xy 406.715487 -17.986624) (xy 406.663152 -17.971262) (xy 406.613536 -17.948609) (xy 406.567649 -17.919124)
			(xy 406.526425 -17.883409) (xy 406.490704 -17.84219) (xy 406.461214 -17.796307) (xy 406.438554 -17.746693)
			(xy 406.423187 -17.69436) (xy 406.415424 -17.640372) (xy 405.08428 -17.640372) (xy 405.08428 -17.967198)
			(xy 405.083787 -17.979311) (xy 405.076302 -18.002351) (xy 405.062065 -18.021951) (xy 405.042469 -18.036193)
			(xy 405.019431 -18.043684) (xy 405.007318 -18.04416) (xy 404.812754 -18.04416) (xy 404.801628 -18.043748)
			(xy 404.780331 -18.037287) (xy 404.770844 -18.03146) (xy 404.47595 -17.838928) (xy 404.466563 -17.833225)
			(xy 404.445525 -17.826952) (xy 404.423571 -17.826952) (xy 404.402533 -17.833225) (xy 404.393146 -17.838928)
			(xy 404.099522 -18.03146) (xy 404.090016 -18.037247) (xy 404.068731 -18.04371) (xy 404.057612 -18.04416)
			(xy 403.861778 -18.04416) (xy 403.849662 -18.043707) (xy 403.826618 -18.036214) (xy 403.807016 -18.021967)
			(xy 403.792775 -18.002361) (xy 403.785289 -17.979314) (xy 403.784816 -17.967198) (xy 402.213664 -17.967198)
			(xy 402.206862 -17.970304) (xy 402.154565 -17.985655) (xy 402.100616 -17.993407) (xy 402.073364 -17.993868)
			(xy 401.209764 -17.993868) (xy 401.182512 -17.99346) (xy 401.128562 -17.985698) (xy 401.076266 -17.970338)
			(xy 401.026688 -17.947693) (xy 400.980838 -17.918222) (xy 400.939647 -17.882527) (xy 400.903956 -17.841334)
			(xy 400.87449 -17.79548) (xy 400.851849 -17.7459) (xy 400.836494 -17.693603) (xy 400.828738 -17.639652)
			(xy 399.49628 -17.639652) (xy 399.49628 -17.967198) (xy 399.495787 -17.979311) (xy 399.488302 -18.002351)
			(xy 399.474065 -18.021951) (xy 399.454469 -18.036193) (xy 399.431431 -18.043684) (xy 399.419318 -18.04416)
			(xy 399.224754 -18.04416) (xy 399.213628 -18.043748) (xy 399.192331 -18.037287) (xy 399.182844 -18.03146)
			(xy 398.88795 -17.838928) (xy 398.878563 -17.833225) (xy 398.857525 -17.826952) (xy 398.835571 -17.826952)
			(xy 398.814533 -17.833225) (xy 398.805146 -17.838928) (xy 398.511522 -18.03146) (xy 398.502016 -18.037247)
			(xy 398.480731 -18.04371) (xy 398.469612 -18.04416) (xy 398.273778 -18.04416) (xy 398.261662 -18.043707)
			(xy 398.238618 -18.036214) (xy 398.219016 -18.021967) (xy 398.204775 -18.002361) (xy 398.197289 -17.979314)
			(xy 398.196816 -17.967198) (xy 396.625664 -17.967198) (xy 396.618862 -17.970304) (xy 396.566565 -17.985655)
			(xy 396.512616 -17.993407) (xy 396.485364 -17.993868) (xy 395.621764 -17.993868) (xy 395.594512 -17.99346)
			(xy 395.540562 -17.985698) (xy 395.488266 -17.970338) (xy 395.438688 -17.947693) (xy 395.392838 -17.918222)
			(xy 395.351647 -17.882527) (xy 395.315956 -17.841334) (xy 395.28649 -17.79548) (xy 395.263849 -17.7459)
			(xy 395.248494 -17.693603) (xy 395.240738 -17.639652) (xy 393.90828 -17.639652) (xy 393.90828 -17.967198)
			(xy 393.907787 -17.979311) (xy 393.900302 -18.002351) (xy 393.886065 -18.021951) (xy 393.866469 -18.036193)
			(xy 393.843431 -18.043684) (xy 393.831318 -18.04416) (xy 393.636754 -18.04416) (xy 393.625628 -18.043748)
			(xy 393.604331 -18.037287) (xy 393.594844 -18.03146) (xy 393.29995 -17.838928) (xy 393.290563 -17.833225)
			(xy 393.269525 -17.826952) (xy 393.247571 -17.826952) (xy 393.226533 -17.833225) (xy 393.217146 -17.838928)
			(xy 392.923522 -18.03146) (xy 392.914016 -18.037247) (xy 392.892731 -18.04371) (xy 392.881612 -18.04416)
			(xy 392.685778 -18.04416) (xy 392.673662 -18.043707) (xy 392.650618 -18.036214) (xy 392.631016 -18.021967)
			(xy 392.616775 -18.002361) (xy 392.609289 -17.979314) (xy 392.608816 -17.967198) (xy 391.037664 -17.967198)
			(xy 391.030862 -17.970304) (xy 390.978565 -17.985655) (xy 390.924616 -17.993407) (xy 390.897364 -17.993868)
			(xy 390.033764 -17.993868) (xy 390.006512 -17.99346) (xy 389.952562 -17.985698) (xy 389.900266 -17.970338)
			(xy 389.850688 -17.947693) (xy 389.804838 -17.918222) (xy 389.763647 -17.882527) (xy 389.727956 -17.841334)
			(xy 389.69849 -17.79548) (xy 389.675849 -17.7459) (xy 389.660494 -17.693603) (xy 389.652738 -17.639652)
			(xy 312.163448 -17.639652) (xy 312.1541 -17.657023) (xy 312.104194 -17.732628) (xy 312.047712 -17.803456)
			(xy 311.985108 -17.868935) (xy 311.916887 -17.928539) (xy 311.843598 -17.981787) (xy 311.76583 -18.028252)
			(xy 311.684211 -18.067559) (xy 311.599397 -18.099391) (xy 311.512071 -18.123493) (xy 311.422936 -18.13967)
			(xy 311.33271 -18.147791) (xy 311.287414 -18.1483) (xy 311.28716 -18.1483) (xy 311.242573 -18.147831)
			(xy 311.153739 -18.140039) (xy 311.065923 -18.124536) (xy 310.979792 -18.101438) (xy 310.896001 -18.070922)
			(xy 310.815188 -18.033221) (xy 310.737969 -17.988621) (xy 310.664929 -17.937461) (xy 310.596626 -17.88013)
			(xy 310.533579 -17.817066) (xy 310.476268 -17.748747) (xy 310.425128 -17.675693) (xy 310.380549 -17.598461)
			(xy 310.34287 -17.517638) (xy 310.312377 -17.433839) (xy 310.289303 -17.347701) (xy 310.273824 -17.259881)
			(xy 310.266056 -17.171045) (xy 310.265572 -17.126458) (xy 259.309108 -17.126458) (xy 259.309108 -19.164372)
			(xy 392.445424 -19.164372) (xy 392.445424 -19.109828) (xy 392.453187 -19.05584) (xy 392.468554 -19.003507)
			(xy 392.491214 -18.953893) (xy 392.520704 -18.90801) (xy 392.556425 -18.866791) (xy 392.597649 -18.831076)
			(xy 392.643536 -18.801591) (xy 392.693152 -18.778938) (xy 392.745487 -18.763576) (xy 392.799476 -18.75582)
			(xy 392.826748 -18.75536) (xy 393.690348 -18.75536) (xy 393.717617 -18.755806) (xy 393.771598 -18.763573)
			(xy 393.823925 -18.778944) (xy 393.873532 -18.801604) (xy 393.91941 -18.831093) (xy 393.960624 -18.86681)
			(xy 393.996336 -18.908029) (xy 394.025819 -18.95391) (xy 394.048473 -19.00352) (xy 394.063837 -19.055849)
			(xy 394.071598 -19.109831) (xy 394.071598 -19.163652) (xy 398.034738 -19.163652) (xy 398.034738 -19.109148)
			(xy 398.042494 -19.055197) (xy 398.057849 -19.0029) (xy 398.08049 -18.95332) (xy 398.109956 -18.907466)
			(xy 398.145647 -18.866273) (xy 398.186838 -18.830578) (xy 398.232688 -18.801107) (xy 398.282266 -18.778462)
			(xy 398.334562 -18.763102) (xy 398.388512 -18.75534) (xy 398.415764 -18.754852) (xy 399.279364 -18.754852)
			(xy 399.306616 -18.755393) (xy 399.360565 -18.763145) (xy 399.412862 -18.778496) (xy 399.462441 -18.801134)
			(xy 399.508294 -18.830598) (xy 399.549486 -18.866288) (xy 399.58518 -18.907477) (xy 399.614649 -18.953327)
			(xy 399.637291 -19.002905) (xy 399.652648 -19.0552) (xy 399.660405 -19.109148) (xy 399.660405 -19.163652)
			(xy 403.622738 -19.163652) (xy 403.622738 -19.109148) (xy 403.630494 -19.055197) (xy 403.645849 -19.0029)
			(xy 403.66849 -18.95332) (xy 403.697956 -18.907466) (xy 403.733647 -18.866273) (xy 403.774838 -18.830578)
			(xy 403.820688 -18.801107) (xy 403.870266 -18.778462) (xy 403.922562 -18.763102) (xy 403.976512 -18.75534)
			(xy 404.003764 -18.754852) (xy 404.867364 -18.754852) (xy 404.894616 -18.755393) (xy 404.948565 -18.763145)
			(xy 405.000862 -18.778496) (xy 405.050441 -18.801134) (xy 405.096294 -18.830598) (xy 405.137486 -18.866288)
			(xy 405.17318 -18.907477) (xy 405.202649 -18.953327) (xy 405.225291 -19.002905) (xy 405.240648 -19.0552)
			(xy 405.248405 -19.109148) (xy 405.248405 -19.163652) (xy 409.210738 -19.163652) (xy 409.210738 -19.109148)
			(xy 409.218494 -19.055197) (xy 409.233849 -19.0029) (xy 409.25649 -18.95332) (xy 409.285956 -18.907466)
			(xy 409.321647 -18.866273) (xy 409.362838 -18.830578) (xy 409.408688 -18.801107) (xy 409.458266 -18.778462)
			(xy 409.510562 -18.763102) (xy 409.564512 -18.75534) (xy 409.591764 -18.754852) (xy 410.455364 -18.754852)
			(xy 410.482616 -18.755393) (xy 410.536565 -18.763145) (xy 410.588862 -18.778496) (xy 410.638441 -18.801134)
			(xy 410.684294 -18.830598) (xy 410.725486 -18.866288) (xy 410.76118 -18.907477) (xy 410.790649 -18.953327)
			(xy 410.813291 -19.002905) (xy 410.828648 -19.0552) (xy 410.836405 -19.109148) (xy 410.836405 -19.163652)
			(xy 410.836405 -19.163653) (xy 415.104538 -19.163653) (xy 415.104538 -19.109147) (xy 415.112295 -19.055195)
			(xy 415.12765 -19.002897) (xy 415.150292 -18.953315) (xy 415.17976 -18.907461) (xy 415.215453 -18.866267)
			(xy 415.256645 -18.830572) (xy 415.302498 -18.801102) (xy 415.352078 -18.778457) (xy 415.404376 -18.763099)
			(xy 415.458327 -18.755339) (xy 415.48558 -18.754852) (xy 416.34918 -18.754852) (xy 416.376431 -18.755394)
			(xy 416.430378 -18.763148) (xy 416.482673 -18.7785) (xy 416.532251 -18.801139) (xy 416.578101 -18.830604)
			(xy 416.619292 -18.866294) (xy 416.654984 -18.907483) (xy 416.684451 -18.953332) (xy 416.707093 -19.002908)
			(xy 416.722448 -19.055202) (xy 416.730205 -19.109149) (xy 416.730205 -19.163651) (xy 416.730102 -19.164366)
			(xy 420.691346 -19.164366) (xy 420.691346 -19.109834) (xy 420.699107 -19.055857) (xy 420.714469 -19.003533)
			(xy 420.737121 -18.953928) (xy 420.766602 -18.908051) (xy 420.802312 -18.866837) (xy 420.843523 -18.831124)
			(xy 420.889396 -18.801639) (xy 420.938999 -18.778982) (xy 420.991321 -18.763614) (xy 421.045298 -18.755849)
			(xy 421.072564 -18.75536) (xy 421.936164 -18.75536) (xy 421.963438 -18.755777) (xy 422.017432 -18.763536)
			(xy 422.069772 -18.7789) (xy 422.119393 -18.801556) (xy 422.165284 -18.831045) (xy 422.20651 -18.866764)
			(xy 422.242234 -18.907988) (xy 422.271726 -18.953876) (xy 422.294388 -19.003494) (xy 422.309757 -19.055833)
			(xy 422.31752 -19.109826) (xy 422.31752 -19.163656) (xy 426.314515 -19.163656) (xy 426.314515 -19.109144)
			(xy 426.322273 -19.055185) (xy 426.337632 -19.002881) (xy 426.360278 -18.953294) (xy 426.38975 -18.907436)
			(xy 426.42545 -18.866238) (xy 426.466648 -18.830541) (xy 426.512508 -18.80107) (xy 426.562096 -18.778426)
			(xy 426.614401 -18.76307) (xy 426.66836 -18.755314) (xy 426.695616 -18.754852) (xy 427.559216 -18.754852)
			(xy 427.586464 -18.755419) (xy 427.640404 -18.763177) (xy 427.692691 -18.778532) (xy 427.742261 -18.801171)
			(xy 427.788105 -18.830635) (xy 427.829289 -18.866323) (xy 427.864975 -18.907508) (xy 427.894436 -18.953353)
			(xy 427.917074 -19.002924) (xy 427.932427 -19.055212) (xy 427.940182 -19.109152) (xy 427.940182 -19.163648)
			(xy 427.940181 -19.163656) (xy 431.902515 -19.163656) (xy 431.902515 -19.109144) (xy 431.910273 -19.055185)
			(xy 431.925632 -19.002881) (xy 431.948278 -18.953294) (xy 431.97775 -18.907436) (xy 432.01345 -18.866238)
			(xy 432.054648 -18.830541) (xy 432.100508 -18.80107) (xy 432.150096 -18.778426) (xy 432.202401 -18.76307)
			(xy 432.25636 -18.755314) (xy 432.283616 -18.754852) (xy 433.147216 -18.754852) (xy 433.174464 -18.755419)
			(xy 433.228404 -18.763177) (xy 433.280691 -18.778532) (xy 433.330261 -18.801171) (xy 433.376105 -18.830635)
			(xy 433.417289 -18.866323) (xy 433.452975 -18.907508) (xy 433.482436 -18.953353) (xy 433.505074 -19.002924)
			(xy 433.520427 -19.055212) (xy 433.528182 -19.109152) (xy 433.528182 -19.163648) (xy 433.520427 -19.217588)
			(xy 433.505074 -19.269876) (xy 433.482436 -19.319447) (xy 433.452975 -19.365292) (xy 433.417289 -19.406477)
			(xy 433.376105 -19.442165) (xy 433.330261 -19.471629) (xy 433.280691 -19.494268) (xy 433.228404 -19.509623)
			(xy 433.174464 -19.517381) (xy 433.147216 -19.517868) (xy 432.283616 -19.517868) (xy 432.25636 -19.517486)
			(xy 432.202401 -19.50973) (xy 432.150096 -19.494374) (xy 432.100508 -19.47173) (xy 432.054648 -19.442259)
			(xy 432.01345 -19.406562) (xy 431.97775 -19.365364) (xy 431.948278 -19.319506) (xy 431.925632 -19.269919)
			(xy 431.910273 -19.217615) (xy 431.902515 -19.163656) (xy 427.940181 -19.163656) (xy 427.932427 -19.217588)
			(xy 427.917074 -19.269876) (xy 427.894436 -19.319447) (xy 427.864975 -19.365292) (xy 427.829289 -19.406477)
			(xy 427.788105 -19.442165) (xy 427.742261 -19.471629) (xy 427.692691 -19.494268) (xy 427.640404 -19.509623)
			(xy 427.586464 -19.517381) (xy 427.559216 -19.517868) (xy 426.695616 -19.517868) (xy 426.66836 -19.517486)
			(xy 426.614401 -19.50973) (xy 426.562096 -19.494374) (xy 426.512508 -19.47173) (xy 426.466648 -19.442259)
			(xy 426.42545 -19.406562) (xy 426.38975 -19.365364) (xy 426.360278 -19.319506) (xy 426.337632 -19.269919)
			(xy 426.322273 -19.217615) (xy 426.314515 -19.163656) (xy 422.31752 -19.163656) (xy 422.31752 -19.164374)
			(xy 422.309757 -19.218367) (xy 422.294388 -19.270706) (xy 422.271726 -19.320324) (xy 422.242234 -19.366212)
			(xy 422.20651 -19.407436) (xy 422.165284 -19.443155) (xy 422.119393 -19.472644) (xy 422.069772 -19.4953)
			(xy 422.017432 -19.510664) (xy 421.963438 -19.518423) (xy 421.936164 -19.518884) (xy 421.072564 -19.518884)
			(xy 421.045298 -19.518351) (xy 420.991321 -19.510586) (xy 420.938999 -19.495218) (xy 420.889396 -19.472561)
			(xy 420.843523 -19.443076) (xy 420.802312 -19.407363) (xy 420.766602 -19.366149) (xy 420.737121 -19.320272)
			(xy 420.714469 -19.270667) (xy 420.699107 -19.218343) (xy 420.691346 -19.164366) (xy 416.730102 -19.164366)
			(xy 416.722448 -19.217598) (xy 416.707093 -19.269892) (xy 416.684451 -19.319468) (xy 416.654984 -19.365317)
			(xy 416.619292 -19.406506) (xy 416.578101 -19.442196) (xy 416.532251 -19.471661) (xy 416.482673 -19.4943)
			(xy 416.430378 -19.509652) (xy 416.376431 -19.517406) (xy 416.34918 -19.517868) (xy 415.48558 -19.517868)
			(xy 415.458327 -19.517461) (xy 415.404376 -19.509701) (xy 415.352078 -19.494343) (xy 415.302498 -19.471698)
			(xy 415.256645 -19.442228) (xy 415.215453 -19.406533) (xy 415.17976 -19.365339) (xy 415.150292 -19.319485)
			(xy 415.12765 -19.269903) (xy 415.112295 -19.217605) (xy 415.104538 -19.163653) (xy 410.836405 -19.163653)
			(xy 410.828648 -19.2176) (xy 410.813291 -19.269895) (xy 410.790649 -19.319473) (xy 410.76118 -19.365323)
			(xy 410.725486 -19.406512) (xy 410.684294 -19.442202) (xy 410.638441 -19.471666) (xy 410.588862 -19.494304)
			(xy 410.536565 -19.509655) (xy 410.482616 -19.517407) (xy 410.455364 -19.517868) (xy 409.591764 -19.517868)
			(xy 409.564512 -19.51746) (xy 409.510562 -19.509698) (xy 409.458266 -19.494338) (xy 409.408688 -19.471693)
			(xy 409.362838 -19.442222) (xy 409.321647 -19.406527) (xy 409.285956 -19.365334) (xy 409.25649 -19.31948)
			(xy 409.233849 -19.2699) (xy 409.218494 -19.217603) (xy 409.210738 -19.163652) (xy 405.248405 -19.163652)
			(xy 405.240648 -19.2176) (xy 405.225291 -19.269895) (xy 405.202649 -19.319473) (xy 405.17318 -19.365323)
			(xy 405.137486 -19.406512) (xy 405.096294 -19.442202) (xy 405.050441 -19.471666) (xy 405.000862 -19.494304)
			(xy 404.948565 -19.509655) (xy 404.894616 -19.517407) (xy 404.867364 -19.517868) (xy 404.003764 -19.517868)
			(xy 403.976512 -19.51746) (xy 403.922562 -19.509698) (xy 403.870266 -19.494338) (xy 403.820688 -19.471693)
			(xy 403.774838 -19.442222) (xy 403.733647 -19.406527) (xy 403.697956 -19.365334) (xy 403.66849 -19.31948)
			(xy 403.645849 -19.2699) (xy 403.630494 -19.217603) (xy 403.622738 -19.163652) (xy 399.660405 -19.163652)
			(xy 399.652648 -19.2176) (xy 399.637291 -19.269895) (xy 399.614649 -19.319473) (xy 399.58518 -19.365323)
			(xy 399.549486 -19.406512) (xy 399.508294 -19.442202) (xy 399.462441 -19.471666) (xy 399.412862 -19.494304)
			(xy 399.360565 -19.509655) (xy 399.306616 -19.517407) (xy 399.279364 -19.517868) (xy 398.415764 -19.517868)
			(xy 398.388512 -19.51746) (xy 398.334562 -19.509698) (xy 398.282266 -19.494338) (xy 398.232688 -19.471693)
			(xy 398.186838 -19.442222) (xy 398.145647 -19.406527) (xy 398.109956 -19.365334) (xy 398.08049 -19.31948)
			(xy 398.057849 -19.2699) (xy 398.042494 -19.217603) (xy 398.034738 -19.163652) (xy 394.071598 -19.163652)
			(xy 394.071598 -19.164369) (xy 394.063837 -19.218351) (xy 394.048473 -19.27068) (xy 394.025819 -19.32029)
			(xy 393.996336 -19.366171) (xy 393.960624 -19.40739) (xy 393.91941 -19.443107) (xy 393.873532 -19.472596)
			(xy 393.823925 -19.495256) (xy 393.771598 -19.510627) (xy 393.717617 -19.518394) (xy 393.690348 -19.518884)
			(xy 392.826748 -19.518884) (xy 392.799476 -19.51838) (xy 392.745487 -19.510624) (xy 392.693152 -19.495262)
			(xy 392.643536 -19.472609) (xy 392.597649 -19.443124) (xy 392.556425 -19.407409) (xy 392.520704 -19.36619)
			(xy 392.491214 -19.320307) (xy 392.468554 -19.270693) (xy 392.453187 -19.21836) (xy 392.445424 -19.164372)
			(xy 259.309108 -19.164372) (xy 259.309108 -20.4061) (xy 368.50594 -20.4061) (xy 368.510005 -20.315592)
			(xy 368.522167 -20.225813) (xy 368.542328 -20.137486) (xy 368.570325 -20.051322) (xy 368.605934 -19.968014)
			(xy 368.648867 -19.888233) (xy 368.698779 -19.812623) (xy 368.755267 -19.741791) (xy 368.817878 -19.676308)
			(xy 368.886107 -19.616701) (xy 368.959405 -19.56345) (xy 369.037181 -19.516984) (xy 369.118809 -19.477677)
			(xy 369.203632 -19.445846) (xy 369.290966 -19.421746) (xy 369.38011 -19.405573) (xy 369.470345 -19.397455)
			(xy 369.515644 -19.396964) (xy 369.560233 -19.397442) (xy 369.649072 -19.405219) (xy 369.736895 -19.420711)
			(xy 369.823033 -19.443798) (xy 369.906831 -19.474305) (xy 369.987651 -19.512001) (xy 370.064878 -19.556597)
			(xy 370.137923 -19.607756) (xy 370.206232 -19.665086) (xy 370.269283 -19.728153) (xy 370.326597 -19.796475)
			(xy 370.377737 -19.869533) (xy 370.422315 -19.946771) (xy 370.459991 -20.0276) (xy 370.490478 -20.111405)
			(xy 370.513544 -20.197549) (xy 370.529013 -20.285376) (xy 370.536768 -20.374217) (xy 370.537232 -20.418806)
			(xy 370.536774 -20.462284) (xy 370.529196 -20.54891) (xy 370.514098 -20.634545) (xy 370.491595 -20.71854)
			(xy 370.485037 -20.73656) (xy 440.464956 -20.73656) (xy 440.465378 -20.698271) (xy 440.471981 -20.621977)
			(xy 440.485126 -20.546534) (xy 440.504715 -20.472503) (xy 440.51728 -20.436332) (xy 440.51995 -20.4279)
			(xy 440.519937 -20.410225) (xy 440.51728 -20.401788) (xy 440.50475 -20.365606) (xy 440.485173 -20.291575)
			(xy 440.472022 -20.216136) (xy 440.465394 -20.139848) (xy 440.464956 -20.10156) (xy 440.46549 -20.057765)
			(xy 440.474106 -19.9706) (xy 440.49125 -19.884704) (xy 440.516756 -19.80091) (xy 440.550377 -19.72003)
			(xy 440.57062 -19.68119) (xy 440.576064 -19.669733) (xy 440.576046 -19.644397) (xy 440.57062 -19.63293)
			(xy 440.550398 -19.594081) (xy 440.51679 -19.513198) (xy 440.491286 -19.429406) (xy 440.474133 -19.343514)
			(xy 440.465497 -19.256354) (xy 440.464956 -19.21256) (xy 440.465378 -19.174271) (xy 440.471981 -19.097977)
			(xy 440.485126 -19.022534) (xy 440.504715 -18.948503) (xy 440.51728 -18.912332) (xy 440.51995 -18.9039)
			(xy 440.519937 -18.886225) (xy 440.51728 -18.877788) (xy 440.50475 -18.841606) (xy 440.485173 -18.767575)
			(xy 440.472022 -18.692136) (xy 440.465394 -18.615848) (xy 440.464956 -18.57756) (xy 440.465414 -18.53645)
			(xy 440.473005 -18.45458) (xy 440.488119 -18.373761) (xy 440.510626 -18.294681) (xy 440.540334 -18.218015)
			(xy 440.576991 -18.144418) (xy 440.620282 -18.074518) (xy 440.66984 -18.008911) (xy 440.72524 -17.948157)
			(xy 440.78601 -17.892775) (xy 440.851631 -17.843237) (xy 440.921544 -17.799965) (xy 440.995152 -17.76333)
			(xy 441.071826 -17.733644) (xy 441.150912 -17.71116) (xy 441.231736 -17.69607) (xy 441.313608 -17.688502)
			(xy 441.354718 -17.688052) (xy 441.395668 -17.688478) (xy 441.477223 -17.695989) (xy 441.557742 -17.710965)
			(xy 441.636544 -17.733279) (xy 441.712961 -17.762742) (xy 441.786347 -17.799105) (xy 441.856079 -17.842059)
			(xy 441.921567 -17.891241) (xy 441.982258 -17.946234) (xy 442.010292 -17.976088) (xy 442.017449 -17.983101)
			(xy 442.035585 -17.991562) (xy 442.055576 -17.99248) (xy 442.065156 -17.98955) (xy 442.102033 -17.976445)
			(xy 442.177582 -17.955997) (xy 442.254637 -17.94227) (xy 442.3326 -17.935373) (xy 442.371734 -17.93494)
			(xy 442.412849 -17.93538) (xy 442.494727 -17.942971) (xy 442.575557 -17.958083) (xy 442.654646 -17.980589)
			(xy 442.731323 -18.010296) (xy 442.804931 -18.046951) (xy 442.874843 -18.090241) (xy 442.940462 -18.139797)
			(xy 443.001229 -18.195196) (xy 443.056626 -18.255966) (xy 443.106179 -18.321587) (xy 443.149467 -18.391501)
			(xy 443.186119 -18.46511) (xy 443.213248 -18.535142) (xy 451.165468 -18.535142) (xy 451.165468 -18.534888)
			(xy 451.166052 -18.49015) (xy 451.175063 -18.401129) (xy 451.192964 -18.313462) (xy 451.219572 -18.228034)
			(xy 451.236588 -18.186654) (xy 451.240131 -18.177057) (xy 451.240147 -18.15662) (xy 451.236588 -18.14703)
			(xy 451.219555 -18.105656) (xy 451.192939 -18.020228) (xy 451.175038 -17.932559) (xy 451.166032 -17.843535)
			(xy 451.165468 -17.798796) (xy 451.165468 -17.798542) (xy 451.165972 -17.756194) (xy 451.174023 -17.67188)
			(xy 451.190052 -17.588714) (xy 451.213913 -17.507447) (xy 451.245392 -17.428817) (xy 451.284203 -17.353536)
			(xy 451.329993 -17.282284) (xy 451.382349 -17.215708) (xy 451.440797 -17.15441) (xy 451.504807 -17.098945)
			(xy 451.573799 -17.049816) (xy 451.647149 -17.007467) (xy 451.724192 -16.972283) (xy 451.804231 -16.944581)
			(xy 451.88654 -16.924613) (xy 451.970375 -16.91256) (xy 452.054976 -16.90853) (xy 452.139577 -16.91256)
			(xy 452.223412 -16.924613) (xy 452.305721 -16.944581) (xy 452.38576 -16.972283) (xy 452.462803 -17.007467)
			(xy 452.536153 -17.049816) (xy 452.605145 -17.098945) (xy 452.669155 -17.15441) (xy 452.727603 -17.215708)
			(xy 452.779959 -17.282284) (xy 452.825749 -17.353536) (xy 452.86456 -17.428817) (xy 452.896039 -17.507447)
			(xy 452.9199 -17.588714) (xy 452.935929 -17.67188) (xy 452.94398 -17.756194) (xy 452.944484 -17.798542)
			(xy 452.944484 -17.798796) (xy 452.943898 -17.843534) (xy 452.934888 -17.932555) (xy 452.916988 -18.020222)
			(xy 452.890379 -18.10565) (xy 452.873364 -18.14703) (xy 452.869775 -18.156614) (xy 452.869791 -18.177063)
			(xy 452.873364 -18.186654) (xy 452.890389 -18.228031) (xy 452.917007 -18.313458) (xy 452.934911 -18.401126)
			(xy 452.943919 -18.490149) (xy 452.944484 -18.534888) (xy 452.944484 -18.535142) (xy 452.94398 -18.57749)
			(xy 452.935929 -18.661804) (xy 452.9199 -18.74497) (xy 452.896039 -18.826237) (xy 452.86456 -18.904867)
			(xy 452.825749 -18.980148) (xy 452.779959 -19.0514) (xy 452.727603 -19.117976) (xy 452.669155 -19.179274)
			(xy 452.605145 -19.234739) (xy 452.536153 -19.283868) (xy 452.462803 -19.326217) (xy 452.38576 -19.361401)
			(xy 452.305721 -19.389103) (xy 452.223412 -19.409071) (xy 452.139577 -19.421124) (xy 452.054976 -19.425155)
			(xy 451.970375 -19.421124) (xy 451.88654 -19.409071) (xy 451.804231 -19.389103) (xy 451.724192 -19.361401)
			(xy 451.647149 -19.326217) (xy 451.573799 -19.283868) (xy 451.504807 -19.234739) (xy 451.440797 -19.179274)
			(xy 451.382349 -19.117976) (xy 451.329993 -19.0514) (xy 451.284203 -18.980148) (xy 451.245392 -18.904867)
			(xy 451.213913 -18.826237) (xy 451.190052 -18.74497) (xy 451.174023 -18.661804) (xy 451.165972 -18.57749)
			(xy 451.165468 -18.535142) (xy 443.213248 -18.535142) (xy 443.215823 -18.541788) (xy 443.238325 -18.620878)
			(xy 443.253434 -18.701708) (xy 443.261021 -18.783587) (xy 443.261496 -18.824702) (xy 443.261095 -18.862992)
			(xy 443.254486 -18.939286) (xy 443.241336 -19.014729) (xy 443.221741 -19.088759) (xy 443.209172 -19.12493)
			(xy 443.206519 -19.133366) (xy 443.20652 -19.151037) (xy 443.209172 -19.159474) (xy 443.221718 -19.195651)
			(xy 443.24129 -19.269684) (xy 443.254437 -19.345124) (xy 443.261061 -19.421414) (xy 443.261496 -19.459702)
			(xy 443.260982 -19.503497) (xy 443.252361 -19.590663) (xy 443.235212 -19.676559) (xy 443.209701 -19.760353)
			(xy 443.176076 -19.841233) (xy 443.155832 -19.880072) (xy 443.15041 -19.891537) (xy 443.150411 -19.916866)
			(xy 443.155832 -19.928332) (xy 443.176073 -19.967172) (xy 443.209679 -20.048057) (xy 443.235179 -20.131851)
			(xy 443.252328 -20.217745) (xy 443.260958 -20.304908) (xy 443.261496 -20.348702) (xy 443.261095 -20.386992)
			(xy 443.254486 -20.463286) (xy 443.241336 -20.538729) (xy 443.221741 -20.612759) (xy 443.209172 -20.64893)
			(xy 443.206519 -20.657366) (xy 443.20652 -20.675037) (xy 443.209172 -20.683474) (xy 443.221718 -20.719651)
			(xy 443.24129 -20.793684) (xy 443.254437 -20.869124) (xy 443.261061 -20.945414) (xy 443.261496 -20.983702)
			(xy 443.260989 -21.024815) (xy 443.253402 -21.106691) (xy 443.238293 -21.187518) (xy 443.215791 -21.266605)
			(xy 443.186088 -21.343279) (xy 443.149437 -21.416886) (xy 443.106152 -21.486797) (xy 443.0566 -21.552416)
			(xy 443.001205 -21.613183) (xy 442.94044 -21.66858) (xy 442.874823 -21.718133) (xy 442.804914 -21.761422)
			(xy 442.731309 -21.798075) (xy 442.654636 -21.827781) (xy 442.575549 -21.850286) (xy 442.494723 -21.865398)
			(xy 442.412847 -21.872988) (xy 442.371734 -21.873464) (xy 442.330778 -21.872996) (xy 442.249213 -21.865468)
			(xy 442.168686 -21.850472) (xy 442.089879 -21.828136) (xy 442.013459 -21.798648) (xy 441.940074 -21.762259)
			(xy 441.870346 -21.719277) (xy 441.804865 -21.670066) (xy 441.744186 -21.615042) (xy 441.71616 -21.585174)
			(xy 441.709037 -21.578124) (xy 441.690882 -21.569676) (xy 441.670879 -21.568774) (xy 441.661296 -21.571712)
			(xy 441.624502 -21.584749) (xy 441.549137 -21.605106) (xy 441.472276 -21.618771) (xy 441.394513 -21.625637)
			(xy 441.35548 -21.626068) (xy 441.354718 -21.626068) (xy 441.313612 -21.62557) (xy 441.23175 -21.617988)
			(xy 441.150936 -21.602885) (xy 441.07186 -21.580392) (xy 440.995197 -21.5507) (xy 440.9216 -21.514062)
			(xy 440.851696 -21.470791) (xy 440.786082 -21.421255) (xy 440.725318 -21.365878) (xy 440.669922 -21.305132)
			(xy 440.620366 -21.239533) (xy 440.577073 -21.169643) (xy 440.540412 -21.096058) (xy 440.510696 -21.019403)
			(xy 440.488178 -20.940335) (xy 440.473051 -20.859526) (xy 440.465443 -20.777666) (xy 440.464956 -20.73656)
			(xy 370.485037 -20.73656) (xy 370.461858 -20.800254) (xy 370.425114 -20.879065) (xy 370.381641 -20.954375)
			(xy 370.331772 -21.02561) (xy 370.275884 -21.092228) (xy 370.214404 -21.153723) (xy 370.147799 -21.209627)
			(xy 370.076576 -21.259513) (xy 370.001276 -21.303004) (xy 369.922473 -21.339767) (xy 369.840767 -21.369523)
			(xy 369.756778 -21.392046) (xy 369.671146 -21.407165) (xy 369.584522 -21.414763) (xy 369.541044 -21.415248)
			(xy 369.515644 -21.415248) (xy 369.470345 -21.414745) (xy 369.38011 -21.406627) (xy 369.290966 -21.390454)
			(xy 369.203632 -21.366354) (xy 369.118809 -21.334523) (xy 369.037181 -21.295216) (xy 368.959405 -21.24875)
			(xy 368.886107 -21.195499) (xy 368.817878 -21.135892) (xy 368.755267 -21.070409) (xy 368.698779 -20.999577)
			(xy 368.648867 -20.923967) (xy 368.605934 -20.844186) (xy 368.570325 -20.760878) (xy 368.542328 -20.674714)
			(xy 368.522167 -20.586387) (xy 368.510005 -20.496608) (xy 368.50594 -20.4061) (xy 259.309108 -20.4061)
			(xy 259.309108 -23.427944) (xy 389.165084 -23.427944) (xy 389.165084 -22.153372) (xy 389.16554 -22.141297)
			(xy 389.173009 -22.11833) (xy 389.187208 -22.098794) (xy 389.206748 -22.0846) (xy 389.229717 -22.077137)
			(xy 389.241792 -22.076664) (xy 389.750046 -22.076664) (xy 389.76214 -22.077069) (xy 389.785147 -22.084541)
			(xy 389.804728 -22.098743) (xy 389.818976 -22.11829) (xy 389.826502 -22.141279) (xy 389.827008 -22.153372)
			(xy 389.827008 -23.42769) (xy 389.826997 -23.427944) (xy 390.181084 -23.427944) (xy 390.181084 -22.153372)
			(xy 390.18154 -22.141297) (xy 390.189009 -22.11833) (xy 390.203208 -22.098794) (xy 390.222748 -22.0846)
			(xy 390.245717 -22.077137) (xy 390.257792 -22.076664) (xy 390.766046 -22.076664) (xy 390.77814 -22.077069)
			(xy 390.801147 -22.084541) (xy 390.820728 -22.098743) (xy 390.834976 -22.11829) (xy 390.842502 -22.141279)
			(xy 390.843008 -22.153372) (xy 390.843008 -23.42769) (xy 390.84248 -23.439799) (xy 390.835001 -23.462835)
			(xy 390.820772 -23.482432) (xy 390.801185 -23.496676) (xy 390.778155 -23.504172) (xy 390.766046 -23.504652)
			(xy 390.257792 -23.504652) (xy 390.245721 -23.504143) (xy 390.222761 -23.496684) (xy 390.203228 -23.482497)
			(xy 390.189033 -23.462971) (xy 390.181562 -23.440014) (xy 390.181084 -23.427944) (xy 389.826997 -23.427944)
			(xy 389.82648 -23.439799) (xy 389.819001 -23.462835) (xy 389.804772 -23.482432) (xy 389.785185 -23.496676)
			(xy 389.762155 -23.504172) (xy 389.750046 -23.504652) (xy 389.241792 -23.504652) (xy 389.229721 -23.504143)
			(xy 389.206761 -23.496684) (xy 389.187228 -23.482497) (xy 389.173033 -23.462971) (xy 389.165562 -23.440014)
			(xy 389.165084 -23.427944) (xy 259.309108 -23.427944) (xy 259.309108 -25.982422) (xy 440.239912 -25.982422)
			(xy 440.240419 -25.939461) (xy 440.248702 -25.85394) (xy 440.265193 -25.769616) (xy 440.289738 -25.687275)
			(xy 440.322109 -25.607684) (xy 440.362003 -25.531586) (xy 440.40905 -25.459689) (xy 440.46281 -25.392664)
			(xy 440.522782 -25.331135) (xy 440.588408 -25.275676) (xy 440.659076 -25.226803) (xy 440.69635 -25.205436)
			(xy 440.704332 -25.200469) (xy 440.716316 -25.186006) (xy 440.719718 -25.177242) (xy 440.733823 -25.137039)
			(xy 440.768699 -25.059297) (xy 440.810847 -24.985247) (xy 440.859883 -24.915565) (xy 440.915357 -24.850891)
			(xy 440.97676 -24.791817) (xy 441.043529 -24.738885) (xy 441.115054 -24.692579) (xy 441.190679 -24.653323)
			(xy 441.26971 -24.621478) (xy 441.351424 -24.597336) (xy 441.435072 -24.581116) (xy 441.519887 -24.572969)
			(xy 441.56249 -24.572468) (xy 441.562998 -24.572468) (xy 441.606762 -24.572982) (xy 441.693869 -24.581557)
			(xy 441.77971 -24.598653) (xy 441.863455 -24.624106) (xy 441.944293 -24.657667) (xy 441.983114 -24.677878)
			(xy 441.994467 -24.683205) (xy 442.019513 -24.683205) (xy 442.030866 -24.677878) (xy 442.069745 -24.657673)
			(xy 442.150684 -24.6241) (xy 442.23453 -24.598641) (xy 442.320472 -24.581544) (xy 442.407677 -24.572973)
			(xy 442.45149 -24.572468) (xy 442.495305 -24.572971) (xy 442.582516 -24.581515) (xy 442.668462 -24.5986)
			(xy 442.752311 -24.62406) (xy 442.833246 -24.657648) (xy 442.872114 -24.677878) (xy 442.883467 -24.683205)
			(xy 442.908513 -24.683205) (xy 442.919866 -24.677878) (xy 442.959061 -24.657499) (xy 443.040701 -24.623735)
			(xy 443.125286 -24.598229) (xy 443.211982 -24.581233) (xy 443.255908 -24.576532) (xy 443.266358 -24.575008)
			(xy 443.284755 -24.564681) (xy 443.297434 -24.547819) (xy 443.300358 -24.53767) (xy 443.310609 -24.496358)
			(xy 443.337964 -24.415751) (xy 443.372893 -24.338124) (xy 443.415077 -24.264189) (xy 443.464129 -24.19462)
			(xy 443.519603 -24.130055) (xy 443.580989 -24.071084) (xy 443.647727 -24.018245) (xy 443.719207 -23.972023)
			(xy 443.794775 -23.932839) (xy 443.87374 -23.901052) (xy 443.955381 -23.876952) (xy 444.038949 -23.86076)
			(xy 444.123683 -23.852625) (xy 444.166244 -23.852124) (xy 444.207348 -23.852525) (xy 444.289205 -23.860114)
			(xy 444.370013 -23.875224) (xy 444.449082 -23.897725) (xy 444.525738 -23.927425) (xy 444.599326 -23.964072)
			(xy 444.669219 -24.007352) (xy 444.734821 -24.056897) (xy 444.795571 -24.112283) (xy 444.850952 -24.173038)
			(xy 444.900491 -24.238644) (xy 444.943765 -24.30854) (xy 444.980405 -24.382132) (xy 445.0101 -24.45879)
			(xy 445.032594 -24.537861) (xy 445.047697 -24.61867) (xy 445.055279 -24.700528) (xy 445.055752 -24.741632)
			(xy 445.055238 -24.782654) (xy 445.04768 -24.864348) (xy 445.032631 -24.944999) (xy 445.01022 -25.023921)
			(xy 444.980635 -25.100445) (xy 444.94413 -25.173919) (xy 444.901014 -25.243719) (xy 444.851653 -25.309252)
			(xy 444.796467 -25.369961) (xy 444.735925 -25.425331) (xy 444.670542 -25.47489) (xy 444.600873 -25.518217)
			(xy 444.52751 -25.554945) (xy 444.451076 -25.584761) (xy 444.372222 -25.607412) (xy 444.291617 -25.622705)
			(xy 444.250826 -25.627076) (xy 444.240379 -25.628618) (xy 444.221981 -25.638935) (xy 444.2093 -25.655791)
			(xy 444.206376 -25.665938) (xy 444.196473 -25.705794) (xy 444.170375 -25.783666) (xy 444.137208 -25.8588)
			(xy 444.097254 -25.930555) (xy 444.050854 -25.998321) (xy 443.998403 -26.061519) (xy 443.940348 -26.119612)
			(xy 443.877184 -26.172104) (xy 443.809448 -26.218548) (xy 443.773814 -26.238962) (xy 443.765845 -26.243946)
			(xy 443.753852 -26.258396) (xy 443.750446 -26.267156) (xy 443.736369 -26.307378) (xy 443.701515 -26.385148)
			(xy 443.659384 -26.459228) (xy 443.61036 -26.528939) (xy 443.554893 -26.593641) (xy 443.493492 -26.652741)
			(xy 443.42672 -26.705698) (xy 443.355189 -26.752025) (xy 443.279554 -26.791298) (xy 443.200511 -26.823158)
			(xy 443.118782 -26.847311) (xy 443.035118 -26.863536) (xy 442.950285 -26.871685) (xy 442.907674 -26.872184)
			(xy 442.863879 -26.871639) (xy 442.776715 -26.863025) (xy 442.690819 -26.845883) (xy 442.607025 -26.82038)
			(xy 442.526144 -26.786761) (xy 442.487304 -26.76652) (xy 442.475838 -26.761102) (xy 442.45051 -26.761102)
			(xy 442.439044 -26.76652) (xy 442.400209 -26.786769) (xy 442.319322 -26.820374) (xy 442.235526 -26.845873)
			(xy 442.149632 -26.863019) (xy 442.062468 -26.871647) (xy 442.018674 -26.872184) (xy 441.974879 -26.871639)
			(xy 441.887715 -26.863025) (xy 441.801819 -26.845883) (xy 441.718025 -26.82038) (xy 441.637144 -26.786761)
			(xy 441.598304 -26.76652) (xy 441.586838 -26.761102) (xy 441.56151 -26.761102) (xy 441.550044 -26.76652)
			(xy 441.511209 -26.786769) (xy 441.430322 -26.820374) (xy 441.346526 -26.845873) (xy 441.260632 -26.863019)
			(xy 441.173468 -26.871647) (xy 441.129674 -26.872184) (xy 441.08856 -26.871712) (xy 441.006683 -26.864123)
			(xy 440.925855 -26.849012) (xy 440.846767 -26.826507) (xy 440.770092 -26.796802) (xy 440.696485 -26.760149)
			(xy 440.626574 -26.71686) (xy 440.560955 -26.667306) (xy 440.500188 -26.61191) (xy 440.444791 -26.551142)
			(xy 440.395237 -26.485523) (xy 440.351949 -26.415612) (xy 440.315297 -26.342004) (xy 440.285592 -26.265329)
			(xy 440.263088 -26.186241) (xy 440.247977 -26.105413) (xy 440.240388 -26.023536) (xy 440.239912 -25.982422)
			(xy 259.309108 -25.982422) (xy 259.309108 -32.117846) (xy 455.218281 -32.117846) (xy 455.218281 -31.988706)
			(xy 455.226231 -31.859811) (xy 455.242101 -31.731651) (xy 455.26583 -31.60471) (xy 455.297329 -31.479471)
			(xy 455.336478 -31.356408) (xy 455.383129 -31.235989) (xy 455.437104 -31.11867) (xy 455.498199 -31.004896)
			(xy 455.566182 -30.895099) (xy 455.640796 -30.789696) (xy 455.721757 -30.689086) (xy 455.808757 -30.593651)
			(xy 455.901468 -30.503752) (xy 455.999538 -30.419731) (xy 456.102593 -30.341907) (xy 456.210244 -30.270575)
			(xy 456.322083 -30.206005) (xy 456.437684 -30.148443) (xy 456.556609 -30.098106) (xy 456.678408 -30.055186)
			(xy 456.802618 -30.019845) (xy 456.928767 -29.992218) (xy 457.056379 -29.972409) (xy 457.184968 -29.960493)
			(xy 457.314046 -29.956517) (xy 457.443124 -29.960493) (xy 457.571713 -29.972409) (xy 457.699325 -29.992218)
			(xy 457.825474 -30.019845) (xy 457.949684 -30.055186) (xy 458.071483 -30.098106) (xy 458.190408 -30.148443)
			(xy 458.306009 -30.206005) (xy 458.417848 -30.270575) (xy 458.525499 -30.341907) (xy 458.628554 -30.419731)
			(xy 458.726624 -30.503752) (xy 458.819335 -30.593651) (xy 458.906335 -30.689086) (xy 458.987296 -30.789696)
			(xy 459.06191 -30.895099) (xy 459.129893 -31.004896) (xy 459.190988 -31.11867) (xy 459.244963 -31.235989)
			(xy 459.291614 -31.356408) (xy 459.330763 -31.479471) (xy 459.362262 -31.60471) (xy 459.385991 -31.731651)
			(xy 459.401861 -31.859811) (xy 459.409811 -31.988706) (xy 459.410308 -32.053276) (xy 459.409811 -32.117846)
			(xy 459.401861 -32.246741) (xy 459.385991 -32.374901) (xy 459.362262 -32.501842) (xy 459.330763 -32.627081)
			(xy 459.291614 -32.750144) (xy 459.244963 -32.870563) (xy 459.190988 -32.987882) (xy 459.129893 -33.101656)
			(xy 459.06191 -33.211453) (xy 458.987296 -33.316856) (xy 458.906335 -33.417466) (xy 458.819335 -33.512901)
			(xy 458.726624 -33.6028) (xy 458.628554 -33.686821) (xy 458.525499 -33.764645) (xy 458.417848 -33.835977)
			(xy 458.307206 -33.899856) (xy 461.798924 -33.899856) (xy 461.798924 -32.299656) (xy 461.799422 -32.222373)
			(xy 461.807378 -32.068013) (xy 461.823271 -31.914267) (xy 461.847057 -31.761543) (xy 461.878674 -31.610247)
			(xy 461.918037 -31.460778) (xy 461.965042 -31.313534) (xy 462.019566 -31.168904) (xy 462.081462 -31.027274)
			(xy 462.150567 -30.889017) (xy 462.226698 -30.754502) (xy 462.309652 -30.624083) (xy 462.399211 -30.498108)
			(xy 462.495135 -30.376911) (xy 462.597172 -30.260812) (xy 462.705049 -30.15012) (xy 462.818482 -30.045128)
			(xy 462.93717 -29.946115) (xy 463.060797 -29.853342) (xy 463.189036 -29.767057) (xy 463.321547 -29.687488)
			(xy 463.457979 -29.614846) (xy 463.597969 -29.549324) (xy 463.741146 -29.491095) (xy 463.887131 -29.440314)
			(xy 464.035537 -29.397115) (xy 464.185969 -29.361613) (xy 464.33803 -29.333903) (xy 464.491316 -29.314057)
			(xy 464.64542 -29.302128) (xy 464.799934 -29.298149) (xy 464.954448 -29.302128) (xy 465.108552 -29.314057)
			(xy 465.261838 -29.333903) (xy 465.413899 -29.361613) (xy 465.564331 -29.397115) (xy 465.712737 -29.440314)
			(xy 465.858722 -29.491095) (xy 466.001899 -29.549324) (xy 466.141889 -29.614846) (xy 466.278321 -29.687488)
			(xy 466.410832 -29.767057) (xy 466.539071 -29.853342) (xy 466.662698 -29.946115) (xy 466.781386 -30.045128)
			(xy 466.894819 -30.15012) (xy 467.002696 -30.260812) (xy 467.104733 -30.376911) (xy 467.200657 -30.498108)
			(xy 467.290216 -30.624083) (xy 467.37317 -30.754502) (xy 467.449301 -30.889017) (xy 467.518406 -31.027274)
			(xy 467.580302 -31.168904) (xy 467.634826 -31.313534) (xy 467.681831 -31.460778) (xy 467.721194 -31.610247)
			(xy 467.752811 -31.761543) (xy 467.776597 -31.914267) (xy 467.79249 -32.068013) (xy 467.800446 -32.222373)
			(xy 467.800944 -32.299656) (xy 467.800944 -33.899856) (xy 467.800446 -33.977139) (xy 467.79249 -34.131499)
			(xy 467.776597 -34.285245) (xy 467.752811 -34.437969) (xy 467.721194 -34.589265) (xy 467.681831 -34.738734)
			(xy 467.634826 -34.885978) (xy 467.580302 -35.030608) (xy 467.518406 -35.172238) (xy 467.449301 -35.310495)
			(xy 467.37317 -35.44501) (xy 467.290216 -35.575429) (xy 467.200657 -35.701404) (xy 467.104733 -35.822601)
			(xy 467.002696 -35.9387) (xy 466.894819 -36.049392) (xy 466.781386 -36.154384) (xy 466.662698 -36.253397)
			(xy 466.539071 -36.34617) (xy 466.410832 -36.432455) (xy 466.278321 -36.512024) (xy 466.141889 -36.584666)
			(xy 466.001899 -36.650188) (xy 465.858722 -36.708417) (xy 465.712737 -36.759198) (xy 465.564331 -36.802397)
			(xy 465.413899 -36.837899) (xy 465.261838 -36.865609) (xy 465.108552 -36.885455) (xy 464.954448 -36.897384)
			(xy 464.799934 -36.901364) (xy 464.64542 -36.897384) (xy 464.491316 -36.885455) (xy 464.33803 -36.865609)
			(xy 464.185969 -36.837899) (xy 464.035537 -36.802397) (xy 463.887131 -36.759198) (xy 463.741146 -36.708417)
			(xy 463.597969 -36.650188) (xy 463.457979 -36.584666) (xy 463.321547 -36.512024) (xy 463.189036 -36.432455)
			(xy 463.060797 -36.34617) (xy 462.93717 -36.253397) (xy 462.818482 -36.154384) (xy 462.705049 -36.049392)
			(xy 462.597172 -35.9387) (xy 462.495135 -35.822601) (xy 462.399211 -35.701404) (xy 462.309652 -35.575429)
			(xy 462.226698 -35.44501) (xy 462.150567 -35.310495) (xy 462.081462 -35.172238) (xy 462.019566 -35.030608)
			(xy 461.965042 -34.885978) (xy 461.918037 -34.738734) (xy 461.878674 -34.589265) (xy 461.847057 -34.437969)
			(xy 461.823271 -34.285245) (xy 461.807378 -34.131499) (xy 461.799422 -33.977139) (xy 461.798924 -33.899856)
			(xy 458.307206 -33.899856) (xy 458.306009 -33.900547) (xy 458.190408 -33.958109) (xy 458.071483 -34.008446)
			(xy 457.949684 -34.051366) (xy 457.825474 -34.086707) (xy 457.699325 -34.114334) (xy 457.571713 -34.134143)
			(xy 457.443124 -34.146059) (xy 457.314046 -34.150036) (xy 457.184968 -34.146059) (xy 457.056379 -34.134143)
			(xy 456.928767 -34.114334) (xy 456.802618 -34.086707) (xy 456.678408 -34.051366) (xy 456.556609 -34.008446)
			(xy 456.437684 -33.958109) (xy 456.322083 -33.900547) (xy 456.210244 -33.835977) (xy 456.102593 -33.764645)
			(xy 455.999538 -33.686821) (xy 455.901468 -33.6028) (xy 455.808757 -33.512901) (xy 455.721757 -33.417466)
			(xy 455.640796 -33.316856) (xy 455.566182 -33.211453) (xy 455.498199 -33.101656) (xy 455.437104 -32.987882)
			(xy 455.383129 -32.870563) (xy 455.336478 -32.750144) (xy 455.297329 -32.627081) (xy 455.26583 -32.501842)
			(xy 455.242101 -32.374901) (xy 455.226231 -32.246741) (xy 455.218281 -32.117846) (xy 259.309108 -32.117846)
			(xy 259.309108 -34.120074) (xy 259.308624 -34.190457) (xy 259.300733 -34.331001) (xy 259.284973 -34.470882)
			(xy 259.261395 -34.609659) (xy 259.230073 -34.746896) (xy 259.191105 -34.882161) (xy 259.144614 -35.015028)
			(xy 259.090747 -35.145079) (xy 259.029671 -35.271905) (xy 258.961581 -35.395107) (xy 258.88669 -35.514297)
			(xy 258.805233 -35.629101) (xy 258.717468 -35.739156) (xy 258.62367 -35.844118) (xy 258.524134 -35.943655)
			(xy 258.419173 -36.037454) (xy 258.309118 -36.12522) (xy 258.194315 -36.206678) (xy 258.075126 -36.28157)
			(xy 257.951924 -36.349661) (xy 257.825099 -36.410738) (xy 257.695048 -36.464606) (xy 257.562182 -36.511099)
			(xy 257.426917 -36.550068) (xy 257.289681 -36.581391) (xy 257.150904 -36.60497) (xy 257.011023 -36.620731)
			(xy 256.870479 -36.628623) (xy 256.800096 -36.629086) (xy 225.300032 -36.629086) (xy 225.229649 -36.628602)
			(xy 225.089105 -36.620711) (xy 224.949224 -36.604952) (xy 224.810447 -36.581374) (xy 224.673211 -36.550052)
			(xy 224.537946 -36.511084) (xy 224.40508 -36.464594) (xy 224.275029 -36.410726) (xy 224.148203 -36.349651)
			(xy 224.025001 -36.28156) (xy 223.905811 -36.206669) (xy 223.791008 -36.125213) (xy 223.680953 -36.037447)
			(xy 223.575992 -35.943648) (xy 223.476456 -35.844112) (xy 223.382657 -35.739152) (xy 223.294891 -35.629097)
			(xy 223.213434 -35.514294) (xy 223.138543 -35.395104) (xy 223.070452 -35.271902) (xy 223.009377 -35.145077)
			(xy 222.955509 -35.015026) (xy 222.909017 -34.882159) (xy 222.870049 -34.746895) (xy 222.838727 -34.609659)
			(xy 222.815149 -34.470882) (xy 222.799389 -34.331001) (xy 222.791498 -34.190457) (xy 222.79102 -34.120074)
			(xy 222.79102 -13.780008) (xy 222.790499 -13.724238) (xy 222.782164 -13.613011) (xy 222.765541 -13.502717)
			(xy 222.740722 -13.393974) (xy 222.707846 -13.287389) (xy 222.667097 -13.183559) (xy 222.618703 -13.083065)
			(xy 222.562935 -12.986469) (xy 222.500103 -12.894309) (xy 222.430561 -12.807103) (xy 222.354696 -12.725338)
			(xy 222.272933 -12.64947) (xy 222.185729 -12.579925) (xy 222.093572 -12.517091) (xy 221.996977 -12.461319)
			(xy 221.896485 -12.412922) (xy 221.792656 -12.37217) (xy 221.686073 -12.339291) (xy 221.57733 -12.314468)
			(xy 221.467037 -12.297841) (xy 221.35581 -12.289503) (xy 221.30004 -12.289028) (xy 196.701918 -12.289028)
			(xy 196.631535 -12.288544) (xy 196.49099 -12.280652) (xy 196.35111 -12.264892) (xy 196.212332 -12.241314)
			(xy 196.075095 -12.209992) (xy 195.939831 -12.171024) (xy 195.806964 -12.124532) (xy 195.676913 -12.070665)
			(xy 195.550086 -12.009589) (xy 195.426884 -11.941499) (xy 195.307694 -11.866608) (xy 195.19289 -11.785152)
			(xy 195.082834 -11.697386) (xy 194.977873 -11.603588) (xy 194.878335 -11.504052) (xy 194.784536 -11.399092)
			(xy 194.696769 -11.289037) (xy 194.615311 -11.174234) (xy 194.540418 -11.055045) (xy 194.472326 -10.931844)
			(xy 194.411249 -10.805018) (xy 194.35738 -10.674968) (xy 194.310887 -10.542102) (xy 194.271917 -10.406837)
			(xy 194.240593 -10.269601) (xy 194.217013 -10.130824) (xy 194.201251 -9.990943) (xy 194.193357 -9.850399)
			(xy 194.192906 -9.780016) (xy 194.192906 -5.839714) (xy 194.192489 -5.82969) (xy 194.184822 -5.811168)
			(xy 194.170649 -5.79699) (xy 194.152129 -5.789315) (xy 194.142106 -5.788914) (xy 126.661926 -5.788914)
			(xy 126.651902 -5.789329) (xy 126.633379 -5.796995) (xy 126.619202 -5.811169) (xy 126.611531 -5.82969)
			(xy 126.611126 -5.839714) (xy 126.611126 -9.780016) (xy 126.610632 -9.850398) (xy 126.602738 -9.990941)
			(xy 126.586977 -10.13082) (xy 126.563397 -10.269595) (xy 126.532074 -10.40683) (xy 126.51969 -10.449814)
			(xy 127.349765 -10.449814) (xy 127.353772 -10.361859) (xy 127.365761 -10.274634) (xy 127.385632 -10.18886)
			(xy 127.41322 -10.105248) (xy 127.448298 -10.024491) (xy 127.490574 -9.947259) (xy 127.539697 -9.874191)
			(xy 127.595262 -9.805893) (xy 127.656807 -9.742931) (xy 127.723823 -9.685826) (xy 127.795753 -9.635052)
			(xy 127.872003 -9.591029) (xy 127.951941 -9.554122) (xy 128.034903 -9.524637) (xy 128.120202 -9.502819)
			(xy 128.207132 -9.488848) (xy 128.294973 -9.482839) (xy 128.382996 -9.484843) (xy 128.470472 -9.494844)
			(xy 128.556676 -9.512757) (xy 128.640894 -9.538435) (xy 128.722428 -9.571665) (xy 128.800603 -9.612172)
			(xy 128.87477 -9.65962) (xy 128.944315 -9.713615) (xy 129.008662 -9.773711) (xy 129.067278 -9.83941)
			(xy 129.119676 -9.910166) (xy 129.165423 -9.985394) (xy 129.20414 -10.06447) (xy 129.235506 -10.14674)
			(xy 129.25926 -10.231521) (xy 129.266448 -10.270552) (xy 131.639267 -10.270552) (xy 131.639267 -10.216048)
			(xy 131.647024 -10.162097) (xy 131.66238 -10.1098) (xy 131.685023 -10.060221) (xy 131.714491 -10.014369)
			(xy 131.750185 -9.973177) (xy 131.791377 -9.937485) (xy 131.83723 -9.908018) (xy 131.88681 -9.885377)
			(xy 131.939107 -9.870022) (xy 131.993058 -9.862267) (xy 132.02031 -9.861804) (xy 132.88391 -9.861804)
			(xy 132.911162 -9.862266) (xy 132.96511 -9.870024) (xy 133.017405 -9.885381) (xy 133.066983 -9.908023)
			(xy 133.112833 -9.937491) (xy 133.154024 -9.973183) (xy 133.189715 -10.014375) (xy 133.219181 -10.060226)
			(xy 133.241823 -10.109804) (xy 133.257178 -10.1621) (xy 133.264934 -10.216048) (xy 133.264934 -10.270552)
			(xy 133.257178 -10.3245) (xy 133.241823 -10.376796) (xy 133.219181 -10.426374) (xy 133.189715 -10.472225)
			(xy 133.154024 -10.513417) (xy 133.112833 -10.549109) (xy 133.066983 -10.578577) (xy 133.017405 -10.601219)
			(xy 132.96511 -10.616576) (xy 132.911162 -10.624334) (xy 132.88391 -10.62482) (xy 132.02031 -10.62482)
			(xy 131.993058 -10.624333) (xy 131.939107 -10.616578) (xy 131.88681 -10.601223) (xy 131.83723 -10.578582)
			(xy 131.791377 -10.549115) (xy 131.750185 -10.513423) (xy 131.714491 -10.472231) (xy 131.685023 -10.426379)
			(xy 131.66238 -10.3768) (xy 131.647024 -10.324503) (xy 131.639267 -10.270552) (xy 129.266448 -10.270552)
			(xy 129.275207 -10.31811) (xy 129.283213 -10.405791) (xy 129.283714 -10.449814) (xy 129.283213 -10.493837)
			(xy 129.275207 -10.581518) (xy 129.25926 -10.668107) (xy 129.235506 -10.752888) (xy 129.212528 -10.813156)
			(xy 169.954611 -10.813156) (xy 169.954611 -10.758644) (xy 169.962369 -10.704687) (xy 169.977727 -10.652382)
			(xy 170.000372 -10.602796) (xy 170.029844 -10.556938) (xy 170.065542 -10.51574) (xy 170.106739 -10.480043)
			(xy 170.152598 -10.450571) (xy 170.202184 -10.427926) (xy 170.254488 -10.412568) (xy 170.308446 -10.404811)
			(xy 170.335702 -10.404348) (xy 171.199302 -10.404348) (xy 171.22655 -10.404922) (xy 171.280491 -10.412678)
			(xy 171.33278 -10.428032) (xy 171.382351 -10.45067) (xy 171.428196 -10.480133) (xy 171.469381 -10.515821)
			(xy 171.505068 -10.557006) (xy 171.534531 -10.602851) (xy 171.557169 -10.652422) (xy 171.572522 -10.704711)
			(xy 171.580278 -10.758652) (xy 171.580278 -10.813148) (xy 171.572522 -10.867089) (xy 171.557169 -10.919378)
			(xy 171.534531 -10.968949) (xy 171.505068 -11.014794) (xy 171.469381 -11.055979) (xy 171.428196 -11.091667)
			(xy 171.382351 -11.12113) (xy 171.33278 -11.143768) (xy 171.280491 -11.159122) (xy 171.22655 -11.166878)
			(xy 171.199302 -11.167364) (xy 170.335702 -11.167364) (xy 170.308446 -11.166989) (xy 170.254488 -11.159232)
			(xy 170.202184 -11.143874) (xy 170.152598 -11.121229) (xy 170.106739 -11.091757) (xy 170.065542 -11.05606)
			(xy 170.029844 -11.014862) (xy 170.000372 -10.969004) (xy 169.977727 -10.919418) (xy 169.962369 -10.867113)
			(xy 169.954611 -10.813156) (xy 129.212528 -10.813156) (xy 129.20414 -10.835158) (xy 129.165423 -10.914234)
			(xy 129.119676 -10.989462) (xy 129.067278 -11.060218) (xy 129.008662 -11.125917) (xy 128.944315 -11.186013)
			(xy 128.87477 -11.240008) (xy 128.800603 -11.287456) (xy 128.722428 -11.327963) (xy 128.640894 -11.361193)
			(xy 128.556676 -11.386871) (xy 128.470472 -11.404784) (xy 128.382996 -11.414785) (xy 128.294973 -11.416789)
			(xy 128.207132 -11.41078) (xy 128.120202 -11.396809) (xy 128.034903 -11.374991) (xy 127.951941 -11.345506)
			(xy 127.872003 -11.308599) (xy 127.795753 -11.264576) (xy 127.723823 -11.213802) (xy 127.656807 -11.156697)
			(xy 127.595262 -11.093735) (xy 127.539697 -11.025437) (xy 127.490574 -10.952369) (xy 127.448298 -10.875137)
			(xy 127.41322 -10.79438) (xy 127.385632 -10.710768) (xy 127.365761 -10.624994) (xy 127.353772 -10.537769)
			(xy 127.349765 -10.449814) (xy 126.51969 -10.449814) (xy 126.493105 -10.542092) (xy 126.446613 -10.674957)
			(xy 126.392744 -10.805006) (xy 126.331668 -10.93183) (xy 126.263578 -11.05503) (xy 126.188687 -11.174218)
			(xy 126.10723 -11.28902) (xy 126.019465 -11.399074) (xy 125.925667 -11.504033) (xy 125.826132 -11.603569)
			(xy 125.721172 -11.697366) (xy 125.611118 -11.785131) (xy 125.496317 -11.866588) (xy 125.495706 -11.866972)
			(xy 129.833804 -11.866972) (xy 129.833804 -11.812428) (xy 129.841567 -11.758438) (xy 129.856934 -11.706103)
			(xy 129.879594 -11.656488) (xy 129.909085 -11.610603) (xy 129.944805 -11.569383) (xy 129.986029 -11.533665)
			(xy 130.031916 -11.504179) (xy 130.081533 -11.481523) (xy 130.13387 -11.46616) (xy 130.18786 -11.458401)
			(xy 130.215132 -11.45794) (xy 131.078732 -11.45794) (xy 131.106 -11.458425) (xy 131.15998 -11.46619)
			(xy 131.212306 -11.481558) (xy 131.261913 -11.504216) (xy 131.30779 -11.533703) (xy 131.349004 -11.569419)
			(xy 131.384716 -11.610636) (xy 131.414199 -11.656515) (xy 131.436853 -11.706124) (xy 131.452217 -11.758451)
			(xy 131.459978 -11.812432) (xy 131.459978 -11.866968) (xy 131.452217 -11.920949) (xy 131.436853 -11.973276)
			(xy 131.432747 -11.982267) (xy 135.233942 -11.982267) (xy 135.233942 -11.927733) (xy 135.241703 -11.873755)
			(xy 135.257066 -11.82143) (xy 135.279719 -11.771824) (xy 135.309201 -11.725946) (xy 135.344912 -11.684731)
			(xy 135.386124 -11.649018) (xy 135.431999 -11.619533) (xy 135.481603 -11.596876) (xy 135.533927 -11.581509)
			(xy 135.587905 -11.573744) (xy 135.615172 -11.573256) (xy 136.478772 -11.573256) (xy 136.506046 -11.573682)
			(xy 136.560038 -11.581441) (xy 136.612377 -11.596805) (xy 136.661996 -11.619462) (xy 136.707885 -11.648951)
			(xy 136.74911 -11.68467) (xy 136.784832 -11.725893) (xy 136.814324 -11.77178) (xy 136.836985 -11.821397)
			(xy 136.852353 -11.873735) (xy 136.860116 -11.927726) (xy 136.860116 -11.982274) (xy 136.852353 -12.036265)
			(xy 136.836985 -12.088603) (xy 136.814324 -12.13822) (xy 136.784832 -12.184107) (xy 136.74911 -12.22533)
			(xy 136.707885 -12.261049) (xy 136.661996 -12.290538) (xy 136.612377 -12.313195) (xy 136.560038 -12.328559)
			(xy 136.506046 -12.336318) (xy 136.478772 -12.33678) (xy 135.615172 -12.33678) (xy 135.587905 -12.336256)
			(xy 135.533927 -12.328491) (xy 135.481603 -12.313124) (xy 135.431999 -12.290467) (xy 135.386124 -12.260982)
			(xy 135.344912 -12.225269) (xy 135.309201 -12.184054) (xy 135.279719 -12.138176) (xy 135.257066 -12.08857)
			(xy 135.241703 -12.036245) (xy 135.233942 -11.982267) (xy 131.432747 -11.982267) (xy 131.414199 -12.022885)
			(xy 131.384716 -12.068764) (xy 131.349004 -12.109981) (xy 131.30779 -12.145697) (xy 131.261913 -12.175184)
			(xy 131.212306 -12.197842) (xy 131.15998 -12.21321) (xy 131.106 -12.220975) (xy 131.078732 -12.221464)
			(xy 130.215132 -12.221464) (xy 130.18786 -12.220999) (xy 130.13387 -12.21324) (xy 130.081533 -12.197877)
			(xy 130.031916 -12.175221) (xy 129.986029 -12.145735) (xy 129.944805 -12.110017) (xy 129.909085 -12.068797)
			(xy 129.879594 -12.022912) (xy 129.856934 -11.973297) (xy 129.841567 -11.920962) (xy 129.833804 -11.866972)
			(xy 125.495706 -11.866972) (xy 125.377128 -11.941479) (xy 125.253928 -12.009569) (xy 125.127104 -12.070645)
			(xy 124.997055 -12.124513) (xy 124.86419 -12.171005) (xy 124.728928 -12.209974) (xy 124.591693 -12.241298)
			(xy 124.452918 -12.264877) (xy 124.313039 -12.280639) (xy 124.172496 -12.288532) (xy 124.102114 -12.289028)
			(xy 83.70189 -12.289028) (xy 83.631508 -12.288534) (xy 83.490965 -12.280641) (xy 83.351086 -12.26488)
			(xy 83.21231 -12.2413) (xy 83.075075 -12.209977) (xy 82.939812 -12.171008) (xy 82.806947 -12.124516)
			(xy 82.676898 -12.070648) (xy 82.550073 -12.009572) (xy 82.426873 -11.941482) (xy 82.307684 -11.866591)
			(xy 82.192882 -11.785134) (xy 82.082828 -11.697369) (xy 81.977868 -11.603571) (xy 81.878333 -11.504036)
			(xy 81.784535 -11.399076) (xy 81.696769 -11.289022) (xy 81.615313 -11.174221) (xy 81.540421 -11.055032)
			(xy 81.47233 -10.931832) (xy 81.411254 -10.805008) (xy 81.357386 -10.674959) (xy 81.310894 -10.542094)
			(xy 81.271924 -10.406831) (xy 81.240601 -10.269596) (xy 81.217021 -10.13082) (xy 81.20126 -9.990941)
			(xy 81.193366 -9.850398) (xy 81.192878 -9.780016) (xy 81.192878 -0.559816) (xy 81.192461 -0.549794)
			(xy 81.184793 -0.531276) (xy 81.170619 -0.517104) (xy 81.1521 -0.509438) (xy 81.142078 -0.509016)
			(xy 13.661898 -0.509016) (xy 13.651878 -0.509436) (xy 13.633365 -0.517107) (xy 13.619197 -0.53128)
			(xy 13.611532 -0.549796) (xy 13.611098 -0.559816) (xy 13.611098 -5.169916) (xy 14.349737 -5.169916)
			(xy 14.353744 -5.081961) (xy 14.365733 -4.994736) (xy 14.385604 -4.908962) (xy 14.413192 -4.82535)
			(xy 14.44827 -4.744593) (xy 14.490546 -4.667361) (xy 14.539669 -4.594293) (xy 14.595234 -4.525995)
			(xy 14.656779 -4.463033) (xy 14.723795 -4.405928) (xy 14.795725 -4.355154) (xy 14.871975 -4.311131)
			(xy 14.951913 -4.274224) (xy 15.034875 -4.244739) (xy 15.120174 -4.222921) (xy 15.207104 -4.20895)
			(xy 15.294945 -4.202941) (xy 15.382968 -4.204945) (xy 15.470444 -4.214946) (xy 15.556648 -4.232859)
			(xy 15.640866 -4.258537) (xy 15.7224 -4.291767) (xy 15.800575 -4.332274) (xy 15.874742 -4.379722)
			(xy 15.944287 -4.433717) (xy 16.008634 -4.493813) (xy 16.06725 -4.559512) (xy 16.119648 -4.630268)
			(xy 16.165395 -4.705496) (xy 16.204112 -4.784572) (xy 16.235478 -4.866842) (xy 16.259232 -4.951623)
			(xy 16.266423 -4.990667) (xy 20.439138 -4.990667) (xy 20.439138 -4.936133) (xy 20.446899 -4.882153)
			(xy 20.462263 -4.829827) (xy 20.484917 -4.78022) (xy 20.5144 -4.734341) (xy 20.550112 -4.693126)
			(xy 20.591325 -4.657412) (xy 20.637202 -4.627926) (xy 20.686808 -4.60527) (xy 20.739133 -4.589903)
			(xy 20.793113 -4.58214) (xy 20.82038 -4.581652) (xy 21.68398 -4.581652) (xy 21.711253 -4.582086)
			(xy 21.765244 -4.589846) (xy 21.817581 -4.605211) (xy 21.867198 -4.627869) (xy 21.913086 -4.657357)
			(xy 21.95431 -4.693076) (xy 21.990031 -4.734298) (xy 22.019522 -4.780184) (xy 22.042182 -4.8298)
			(xy 22.057549 -4.882136) (xy 22.065312 -4.936127) (xy 22.065312 -4.990671) (xy 24.039016 -4.990671)
			(xy 24.039016 -4.936129) (xy 24.046778 -4.882142) (xy 24.062145 -4.82981) (xy 24.084803 -4.780197)
			(xy 24.114292 -4.734314) (xy 24.15001 -4.693095) (xy 24.191231 -4.657379) (xy 24.237116 -4.627893)
			(xy 24.28673 -4.605237) (xy 24.339064 -4.589873) (xy 24.393051 -4.582114) (xy 24.420322 -4.581652)
			(xy 25.283922 -4.581652) (xy 25.311191 -4.582112) (xy 25.365175 -4.589876) (xy 25.417503 -4.605244)
			(xy 25.467113 -4.627903) (xy 25.512992 -4.65739) (xy 25.554209 -4.693107) (xy 25.589923 -4.734325)
			(xy 25.619408 -4.780207) (xy 25.642063 -4.829817) (xy 25.657428 -4.882147) (xy 25.66519 -4.936131)
			(xy 25.66519 -4.990667) (xy 27.639038 -4.990667) (xy 27.639038 -4.936133) (xy 27.646799 -4.882155)
			(xy 27.662162 -4.82983) (xy 27.684814 -4.780224) (xy 27.714296 -4.734347) (xy 27.750006 -4.693131)
			(xy 27.791218 -4.657417) (xy 27.837092 -4.627932) (xy 27.886696 -4.605274) (xy 27.93902 -4.589906)
			(xy 27.992997 -4.582141) (xy 28.020264 -4.581652) (xy 28.883864 -4.581652) (xy 28.911138 -4.582085)
			(xy 28.96513 -4.589843) (xy 29.017469 -4.605207) (xy 29.067089 -4.627863) (xy 29.112979 -4.657351)
			(xy 29.154205 -4.69307) (xy 29.189927 -4.734292) (xy 29.219419 -4.78018) (xy 29.24208 -4.829797)
			(xy 29.257449 -4.882134) (xy 29.265212 -4.936126) (xy 29.265212 -4.990667) (xy 31.239238 -4.990667)
			(xy 31.239238 -4.936133) (xy 31.246999 -4.882155) (xy 31.262361 -4.829831) (xy 31.285014 -4.780225)
			(xy 31.314495 -4.734348) (xy 31.350205 -4.693133) (xy 31.391416 -4.657419) (xy 31.43729 -4.627933)
			(xy 31.486893 -4.605275) (xy 31.539216 -4.589907) (xy 31.593193 -4.582141) (xy 31.62046 -4.581652)
			(xy 32.48406 -4.581652) (xy 32.511334 -4.582085) (xy 32.565327 -4.589843) (xy 32.617666 -4.605206)
			(xy 32.667286 -4.627862) (xy 32.713177 -4.65735) (xy 32.754403 -4.693068) (xy 32.790126 -4.734291)
			(xy 32.819619 -4.780178) (xy 32.84228 -4.829796) (xy 32.857649 -4.882134) (xy 32.865412 -4.936126)
			(xy 32.865412 -4.990671) (xy 40.349116 -4.990671) (xy 40.349116 -4.936129) (xy 40.356878 -4.882142)
			(xy 40.372245 -4.829809) (xy 40.394903 -4.780196) (xy 40.424392 -4.734313) (xy 40.460111 -4.693094)
			(xy 40.501332 -4.657378) (xy 40.547217 -4.627892) (xy 40.596832 -4.605237) (xy 40.649165 -4.589873)
			(xy 40.703153 -4.582114) (xy 40.730424 -4.581652) (xy 41.594024 -4.581652) (xy 41.621293 -4.582112)
			(xy 41.675276 -4.589877) (xy 41.727605 -4.605245) (xy 41.777214 -4.627903) (xy 41.823093 -4.657391)
			(xy 41.86431 -4.693107) (xy 41.900024 -4.734326) (xy 41.929508 -4.780207) (xy 41.952164 -4.829818)
			(xy 41.967528 -4.882147) (xy 41.97529 -4.936131) (xy 41.97529 -4.990667) (xy 43.949138 -4.990667)
			(xy 43.949138 -4.936133) (xy 43.956899 -4.882155) (xy 43.972262 -4.82983) (xy 43.994915 -4.780224)
			(xy 44.024396 -4.734346) (xy 44.060107 -4.693131) (xy 44.101319 -4.657417) (xy 44.147194 -4.627931)
			(xy 44.196798 -4.605274) (xy 44.249121 -4.589906) (xy 44.303099 -4.582141) (xy 44.330366 -4.581652)
			(xy 45.193966 -4.581652) (xy 45.22124 -4.582085) (xy 45.275232 -4.589844) (xy 45.327571 -4.605208)
			(xy 45.37719 -4.627864) (xy 45.42308 -4.657352) (xy 45.464305 -4.693071) (xy 45.500028 -4.734293)
			(xy 45.52952 -4.78018) (xy 45.552181 -4.829797) (xy 45.567549 -4.882135) (xy 45.575312 -4.936126)
			(xy 45.575312 -4.990667) (xy 51.559238 -4.990667) (xy 51.559238 -4.936133) (xy 51.566999 -4.882155)
			(xy 51.582361 -4.829831) (xy 51.605014 -4.780225) (xy 51.634495 -4.734348) (xy 51.670205 -4.693133)
			(xy 51.711416 -4.657419) (xy 51.75729 -4.627933) (xy 51.806893 -4.605275) (xy 51.859216 -4.589907)
			(xy 51.913193 -4.582141) (xy 51.94046 -4.581652) (xy 52.80406 -4.581652) (xy 52.831334 -4.582085)
			(xy 52.885327 -4.589843) (xy 52.937666 -4.605206) (xy 52.987286 -4.627862) (xy 53.033177 -4.65735)
			(xy 53.074403 -4.693068) (xy 53.110126 -4.734291) (xy 53.139619 -4.780178) (xy 53.16228 -4.829796)
			(xy 53.177649 -4.882134) (xy 53.185412 -4.936126) (xy 53.185412 -4.99067) (xy 55.159115 -4.99067)
			(xy 55.159115 -4.93613) (xy 55.166877 -4.882145) (xy 55.182243 -4.829814) (xy 55.2049 -4.780202)
			(xy 55.234387 -4.73432) (xy 55.270103 -4.693102) (xy 55.311322 -4.657386) (xy 55.357204 -4.627899)
			(xy 55.406816 -4.605242) (xy 55.459147 -4.589877) (xy 55.513132 -4.582115) (xy 55.540402 -4.581652)
			(xy 56.404002 -4.581652) (xy 56.431272 -4.582111) (xy 56.485258 -4.589873) (xy 56.537589 -4.605239)
			(xy 56.587201 -4.627896) (xy 56.633083 -4.657383) (xy 56.674302 -4.6931) (xy 56.710018 -4.734319)
			(xy 56.739505 -4.780201) (xy 56.762162 -4.829813) (xy 56.777528 -4.882144) (xy 56.78529 -4.93613)
			(xy 56.78529 -4.99067) (xy 56.777528 -5.044656) (xy 56.762162 -5.096987) (xy 56.739505 -5.146599)
			(xy 56.710018 -5.192481) (xy 56.674302 -5.2337) (xy 56.633083 -5.269417) (xy 56.587201 -5.298904)
			(xy 56.537589 -5.321561) (xy 56.485258 -5.336927) (xy 56.431272 -5.344689) (xy 56.404002 -5.345176)
			(xy 55.540402 -5.345176) (xy 55.513132 -5.344685) (xy 55.459147 -5.336923) (xy 55.406816 -5.321558)
			(xy 55.357204 -5.298901) (xy 55.311322 -5.269414) (xy 55.270103 -5.233698) (xy 55.234387 -5.19248)
			(xy 55.2049 -5.146598) (xy 55.182243 -5.096986) (xy 55.166877 -5.044655) (xy 55.159115 -4.99067)
			(xy 53.185412 -4.99067) (xy 53.185412 -4.990674) (xy 53.177649 -5.044666) (xy 53.16228 -5.097004)
			(xy 53.139619 -5.146622) (xy 53.110126 -5.192509) (xy 53.074403 -5.233732) (xy 53.033177 -5.26945)
			(xy 52.987286 -5.298938) (xy 52.937666 -5.321594) (xy 52.885327 -5.336957) (xy 52.831334 -5.344715)
			(xy 52.80406 -5.345176) (xy 51.94046 -5.345176) (xy 51.913194 -5.344659) (xy 51.859216 -5.336893)
			(xy 51.806893 -5.321525) (xy 51.75729 -5.298867) (xy 51.711416 -5.269381) (xy 51.670205 -5.233667)
			(xy 51.634495 -5.192452) (xy 51.605014 -5.146575) (xy 51.582361 -5.096969) (xy 51.566999 -5.044645)
			(xy 51.559238 -4.990667) (xy 45.575312 -4.990667) (xy 45.575312 -4.990674) (xy 45.567549 -5.044665)
			(xy 45.552181 -5.097003) (xy 45.52952 -5.14662) (xy 45.500028 -5.192507) (xy 45.464305 -5.233729)
			(xy 45.42308 -5.269448) (xy 45.37719 -5.298936) (xy 45.327571 -5.321592) (xy 45.275232 -5.336956)
			(xy 45.22124 -5.344715) (xy 45.193966 -5.345176) (xy 44.330366 -5.345176) (xy 44.303099 -5.344659)
			(xy 44.249121 -5.336894) (xy 44.196798 -5.321526) (xy 44.147194 -5.298869) (xy 44.101319 -5.269383)
			(xy 44.060107 -5.233669) (xy 44.024396 -5.192454) (xy 43.994915 -5.146576) (xy 43.972262 -5.09697)
			(xy 43.956899 -5.044645) (xy 43.949138 -4.990667) (xy 41.97529 -4.990667) (xy 41.97529 -4.990669)
			(xy 41.967528 -5.044653) (xy 41.952164 -5.096982) (xy 41.929508 -5.146593) (xy 41.900024 -5.192474)
			(xy 41.86431 -5.233693) (xy 41.823093 -5.269409) (xy 41.777214 -5.298897) (xy 41.727605 -5.321555)
			(xy 41.675276 -5.336923) (xy 41.621293 -5.344688) (xy 41.594024 -5.345176) (xy 40.730424 -5.345176)
			(xy 40.703153 -5.344686) (xy 40.649165 -5.336927) (xy 40.596832 -5.321563) (xy 40.547217 -5.298908)
			(xy 40.501332 -5.269422) (xy 40.460111 -5.233706) (xy 40.424392 -5.192487) (xy 40.394903 -5.146604)
			(xy 40.372245 -5.096991) (xy 40.356878 -5.044658) (xy 40.349116 -4.990671) (xy 32.865412 -4.990671)
			(xy 32.865412 -4.990674) (xy 32.857649 -5.044666) (xy 32.84228 -5.097004) (xy 32.819619 -5.146622)
			(xy 32.790126 -5.192509) (xy 32.754403 -5.233732) (xy 32.713177 -5.26945) (xy 32.667286 -5.298938)
			(xy 32.617666 -5.321594) (xy 32.565327 -5.336957) (xy 32.511334 -5.344715) (xy 32.48406 -5.345176)
			(xy 31.62046 -5.345176) (xy 31.593194 -5.344659) (xy 31.539216 -5.336893) (xy 31.486893 -5.321525)
			(xy 31.43729 -5.298867) (xy 31.391416 -5.269381) (xy 31.350205 -5.233667) (xy 31.314495 -5.192452)
			(xy 31.285014 -5.146575) (xy 31.262361 -5.096969) (xy 31.246999 -5.044645) (xy 31.239238 -4.990667)
			(xy 29.265212 -4.990667) (xy 29.265212 -4.990674) (xy 29.257449 -5.044666) (xy 29.24208 -5.097003)
			(xy 29.219419 -5.14662) (xy 29.189927 -5.192508) (xy 29.154205 -5.23373) (xy 29.112979 -5.269449)
			(xy 29.067089 -5.298937) (xy 29.017469 -5.321593) (xy 28.96513 -5.336957) (xy 28.911138 -5.344715)
			(xy 28.883864 -5.345176) (xy 28.020264 -5.345176) (xy 27.992997 -5.344659) (xy 27.93902 -5.336894)
			(xy 27.886696 -5.321526) (xy 27.837092 -5.298868) (xy 27.791218 -5.269383) (xy 27.750006 -5.233669)
			(xy 27.714296 -5.192453) (xy 27.684814 -5.146576) (xy 27.662162 -5.09697) (xy 27.646799 -5.044645)
			(xy 27.639038 -4.990667) (xy 25.66519 -4.990667) (xy 25.66519 -4.990669) (xy 25.657428 -5.044653)
			(xy 25.642063 -5.096983) (xy 25.619408 -5.146593) (xy 25.589923 -5.192475) (xy 25.554209 -5.233693)
			(xy 25.512992 -5.26941) (xy 25.467113 -5.298897) (xy 25.417503 -5.321556) (xy 25.365175 -5.336924)
			(xy 25.311191 -5.344688) (xy 25.283922 -5.345176) (xy 24.420322 -5.345176) (xy 24.393051 -5.344686)
			(xy 24.339064 -5.336927) (xy 24.28673 -5.321563) (xy 24.237116 -5.298907) (xy 24.191231 -5.269421)
			(xy 24.15001 -5.233705) (xy 24.114292 -5.192486) (xy 24.084803 -5.146603) (xy 24.062145 -5.09699)
			(xy 24.046778 -5.044658) (xy 24.039016 -4.990671) (xy 22.065312 -4.990671) (xy 22.065312 -4.990673)
			(xy 22.057549 -5.044664) (xy 22.042182 -5.097) (xy 22.019522 -5.146616) (xy 21.990031 -5.192502)
			(xy 21.95431 -5.233724) (xy 21.913086 -5.269443) (xy 21.867198 -5.298931) (xy 21.817581 -5.321589)
			(xy 21.765244 -5.336954) (xy 21.711253 -5.344714) (xy 21.68398 -5.345176) (xy 20.82038 -5.345176)
			(xy 20.793113 -5.34466) (xy 20.739133 -5.336897) (xy 20.686808 -5.32153) (xy 20.637202 -5.298874)
			(xy 20.591325 -5.269388) (xy 20.550112 -5.233674) (xy 20.5144 -5.192459) (xy 20.484917 -5.14658)
			(xy 20.462263 -5.096973) (xy 20.446899 -5.044647) (xy 20.439138 -4.990667) (xy 16.266423 -4.990667)
			(xy 16.275179 -5.038212) (xy 16.283185 -5.125893) (xy 16.283686 -5.169916) (xy 16.283185 -5.213939)
			(xy 16.275179 -5.30162) (xy 16.259232 -5.388209) (xy 16.235478 -5.47299) (xy 16.204112 -5.55526)
			(xy 16.165395 -5.634336) (xy 16.119648 -5.709564) (xy 16.06725 -5.78032) (xy 16.008634 -5.846019)
			(xy 15.944287 -5.906115) (xy 15.874742 -5.96011) (xy 15.800575 -6.007558) (xy 15.7224 -6.048065)
			(xy 15.640866 -6.081295) (xy 15.556648 -6.106973) (xy 15.470444 -6.124886) (xy 15.382968 -6.134887)
			(xy 15.294945 -6.136891) (xy 15.207104 -6.130882) (xy 15.120174 -6.116911) (xy 15.034875 -6.095093)
			(xy 14.951913 -6.065608) (xy 14.871975 -6.028701) (xy 14.795725 -5.984678) (xy 14.723795 -5.933904)
			(xy 14.656779 -5.876799) (xy 14.595234 -5.813837) (xy 14.539669 -5.745539) (xy 14.490546 -5.672471)
			(xy 14.44827 -5.595239) (xy 14.413192 -5.514482) (xy 14.385604 -5.43087) (xy 14.365733 -5.345096)
			(xy 14.353744 -5.257871) (xy 14.349737 -5.169916) (xy 13.611098 -5.169916) (xy 13.611098 -6.169914)
			(xy 78.515217 -6.169914) (xy 78.519222 -6.082006) (xy 78.531205 -5.994826) (xy 78.551065 -5.909097)
			(xy 78.57864 -5.825529) (xy 78.613699 -5.744815) (xy 78.655952 -5.667623) (xy 78.70505 -5.594594)
			(xy 78.760586 -5.526332) (xy 78.822098 -5.463402) (xy 78.889079 -5.406328) (xy 78.960972 -5.35558)
			(xy 79.037181 -5.31158) (xy 79.117076 -5.274693) (xy 79.199995 -5.245224) (xy 79.28525 -5.223417)
			(xy 79.372134 -5.209453) (xy 79.459928 -5.203447) (xy 79.547905 -5.205451) (xy 79.635335 -5.215446)
			(xy 79.721494 -5.23335) (xy 79.805668 -5.259014) (xy 79.887159 -5.292227) (xy 79.965293 -5.332713)
			(xy 80.039421 -5.380135) (xy 80.108929 -5.434102) (xy 80.173243 -5.494167) (xy 80.231827 -5.559831)
			(xy 80.284198 -5.63055) (xy 80.329921 -5.705738) (xy 80.368618 -5.784773) (xy 80.399967 -5.866999)
			(xy 80.423709 -5.951735) (xy 80.439647 -6.038279) (xy 80.447649 -6.125914) (xy 80.44815 -6.169914)
			(xy 80.447649 -6.213914) (xy 80.439647 -6.301549) (xy 80.423709 -6.388093) (xy 80.399967 -6.472829)
			(xy 80.368618 -6.555055) (xy 80.329921 -6.63409) (xy 80.284198 -6.709278) (xy 80.231827 -6.779997)
			(xy 80.173243 -6.845661) (xy 80.108929 -6.905726) (xy 80.039421 -6.959693) (xy 79.965293 -7.007115)
			(xy 79.887159 -7.047601) (xy 79.805668 -7.080814) (xy 79.721494 -7.106478) (xy 79.635335 -7.124382)
			(xy 79.547905 -7.134377) (xy 79.459928 -7.136381) (xy 79.372134 -7.130375) (xy 79.28525 -7.116411)
			(xy 79.199995 -7.094604) (xy 79.117076 -7.065135) (xy 79.037181 -7.028248) (xy 78.960972 -6.984248)
			(xy 78.889079 -6.9335) (xy 78.822098 -6.876426) (xy 78.760586 -6.813496) (xy 78.70505 -6.745234)
			(xy 78.655952 -6.672205) (xy 78.613699 -6.595013) (xy 78.57864 -6.514299) (xy 78.551065 -6.430731)
			(xy 78.531205 -6.345002) (xy 78.519222 -6.257822) (xy 78.515217 -6.169914) (xy 13.611098 -6.169914)
			(xy 13.611098 -6.75243) (xy 18.634432 -6.75243) (xy 18.634432 -6.69789) (xy 18.642194 -6.643907)
			(xy 18.65756 -6.591577) (xy 18.680216 -6.541966) (xy 18.709702 -6.496085) (xy 18.745417 -6.454867)
			(xy 18.786635 -6.419152) (xy 18.832516 -6.389666) (xy 18.882127 -6.36701) (xy 18.934457 -6.351644)
			(xy 18.98844 -6.343882) (xy 19.01571 -6.343396) (xy 19.87931 -6.343396) (xy 19.906579 -6.343886)
			(xy 19.960563 -6.351648) (xy 20.012892 -6.367013) (xy 20.062502 -6.389669) (xy 20.108382 -6.419155)
			(xy 20.1496 -6.45487) (xy 20.185315 -6.496088) (xy 20.214801 -6.541968) (xy 20.237457 -6.591578)
			(xy 20.252822 -6.643907) (xy 20.260584 -6.697891) (xy 20.260584 -6.752429) (xy 20.260584 -6.752431)
			(xy 22.234349 -6.752431) (xy 22.234349 -6.697889) (xy 22.242112 -6.643901) (xy 22.257478 -6.591568)
			(xy 22.280136 -6.541955) (xy 22.309624 -6.496071) (xy 22.345342 -6.45485) (xy 22.386562 -6.419133)
			(xy 22.432447 -6.389645) (xy 22.48206 -6.366987) (xy 22.534393 -6.351621) (xy 22.588381 -6.343859)
			(xy 22.615652 -6.343396) (xy 23.479252 -6.343396) (xy 23.506521 -6.343887) (xy 23.560504 -6.351648)
			(xy 23.612833 -6.367014) (xy 23.662443 -6.38967) (xy 23.708323 -6.419156) (xy 23.749541 -6.454871)
			(xy 23.785255 -6.496088) (xy 23.814741 -6.541969) (xy 23.837397 -6.591579) (xy 23.852762 -6.643908)
			(xy 23.860524 -6.697891) (xy 23.860524 -6.752429) (xy 23.860518 -6.752472) (xy 25.834283 -6.752472)
			(xy 25.834283 -6.697928) (xy 25.842045 -6.643939) (xy 25.857412 -6.591604) (xy 25.88007 -6.541989)
			(xy 25.909558 -6.496103) (xy 25.945277 -6.454881) (xy 25.986498 -6.419162) (xy 26.032384 -6.389673)
			(xy 26.081998 -6.367014) (xy 26.134333 -6.351646) (xy 26.188322 -6.343883) (xy 26.215594 -6.343396)
			(xy 27.079194 -6.343396) (xy 27.106462 -6.343943) (xy 27.160444 -6.351704) (xy 27.212772 -6.367068)
			(xy 27.26238 -6.389722) (xy 27.308259 -6.419207) (xy 27.349476 -6.45492) (xy 27.38519 -6.496136)
			(xy 27.414675 -6.542015) (xy 27.43733 -6.591623) (xy 27.452695 -6.64395) (xy 27.460457 -6.697932)
			(xy 27.460457 -6.752468) (xy 27.460456 -6.752472) (xy 29.434483 -6.752472) (xy 29.434483 -6.697928)
			(xy 29.442245 -6.643939) (xy 29.457611 -6.591605) (xy 29.480269 -6.54199) (xy 29.509757 -6.496105)
			(xy 29.545476 -6.454883) (xy 29.586697 -6.419163) (xy 29.632581 -6.389674) (xy 29.682196 -6.367015)
			(xy 29.73453 -6.351647) (xy 29.788518 -6.343883) (xy 29.81579 -6.343396) (xy 30.67939 -6.343396)
			(xy 30.706658 -6.343943) (xy 30.76064 -6.351703) (xy 30.812969 -6.367067) (xy 30.862578 -6.389721)
			(xy 30.908457 -6.419205) (xy 30.949674 -6.454919) (xy 30.985389 -6.496135) (xy 31.014874 -6.542014)
			(xy 31.03753 -6.591622) (xy 31.052895 -6.64395) (xy 31.060657 -6.697932) (xy 31.060657 -6.752468)
			(xy 31.060657 -6.75247) (xy 38.544482 -6.75247) (xy 38.544482 -6.69793) (xy 38.552244 -6.643944)
			(xy 38.567608 -6.591613) (xy 38.590264 -6.542) (xy 38.619749 -6.496116) (xy 38.655463 -6.454895)
			(xy 38.696679 -6.419176) (xy 38.74256 -6.389686) (xy 38.792169 -6.367025) (xy 38.844499 -6.351654)
			(xy 38.898484 -6.343886) (xy 38.925754 -6.343396) (xy 39.789354 -6.343396) (xy 39.816624 -6.34394)
			(xy 39.87061 -6.351696) (xy 39.922943 -6.367057) (xy 39.972556 -6.389709) (xy 40.01844 -6.419192)
			(xy 40.059662 -6.454906) (xy 40.09538 -6.496123) (xy 40.124869 -6.542004) (xy 40.147527 -6.591614)
			(xy 40.162894 -6.643945) (xy 40.170656 -6.69793) (xy 40.170656 -6.75247) (xy 40.170656 -6.752472)
			(xy 42.144383 -6.752472) (xy 42.144383 -6.697928) (xy 42.152145 -6.643939) (xy 42.167512 -6.591604)
			(xy 42.19017 -6.541988) (xy 42.219659 -6.496103) (xy 42.255378 -6.454881) (xy 42.296599 -6.419161)
			(xy 42.342485 -6.389672) (xy 42.3921 -6.367013) (xy 42.444435 -6.351646) (xy 42.498424 -6.343883)
			(xy 42.525696 -6.343396) (xy 43.389296 -6.343396) (xy 43.416564 -6.343943) (xy 43.470546 -6.351704)
			(xy 43.522873 -6.367068) (xy 43.572481 -6.389723) (xy 43.61836 -6.419207) (xy 43.659576 -6.454921)
			(xy 43.69529 -6.496136) (xy 43.724775 -6.542015) (xy 43.74743 -6.591623) (xy 43.762795 -6.643951)
			(xy 43.770557 -6.697932) (xy 43.770557 -6.752468) (xy 43.770556 -6.752472) (xy 49.754483 -6.752472)
			(xy 49.754483 -6.697928) (xy 49.762245 -6.643939) (xy 49.777611 -6.591605) (xy 49.800269 -6.54199)
			(xy 49.829757 -6.496105) (xy 49.865476 -6.454883) (xy 49.906697 -6.419163) (xy 49.952581 -6.389674)
			(xy 50.002196 -6.367015) (xy 50.05453 -6.351647) (xy 50.108518 -6.343883) (xy 50.13579 -6.343396)
			(xy 50.99939 -6.343396) (xy 51.026658 -6.343943) (xy 51.08064 -6.351703) (xy 51.132969 -6.367067)
			(xy 51.182578 -6.389721) (xy 51.228457 -6.419205) (xy 51.269674 -6.454919) (xy 51.305389 -6.496135)
			(xy 51.334874 -6.542014) (xy 51.35753 -6.591622) (xy 51.372895 -6.64395) (xy 51.380657 -6.697932)
			(xy 51.380657 -6.752468) (xy 51.380656 -6.752475) (xy 53.35436 -6.752475) (xy 53.35436 -6.697925)
			(xy 53.362124 -6.643929) (xy 53.377493 -6.591588) (xy 53.400155 -6.541967) (xy 53.429649 -6.496077)
			(xy 53.465374 -6.454851) (xy 53.506603 -6.41913) (xy 53.552495 -6.38964) (xy 53.602118 -6.366982)
			(xy 53.65446 -6.351617) (xy 53.708457 -6.343857) (xy 53.735732 -6.343396) (xy 54.599332 -6.343396)
			(xy 54.626597 -6.343969) (xy 54.680571 -6.351733) (xy 54.732891 -6.367099) (xy 54.782492 -6.389755)
			(xy 54.828364 -6.419238) (xy 54.869573 -6.45495) (xy 54.905281 -6.496162) (xy 54.93476 -6.542036)
			(xy 54.957412 -6.591639) (xy 54.972774 -6.64396) (xy 54.980534 -6.697935) (xy 54.980534 -6.752465)
			(xy 54.980533 -6.752471) (xy 56.954382 -6.752471) (xy 56.954382 -6.697929) (xy 56.962144 -6.643942)
			(xy 56.97751 -6.591608) (xy 57.000167 -6.541994) (xy 57.029654 -6.49611) (xy 57.06537 -6.454888)
			(xy 57.106589 -6.419169) (xy 57.152472 -6.389679) (xy 57.202084 -6.367019) (xy 57.254416 -6.35165)
			(xy 57.308403 -6.343884) (xy 57.335674 -6.343396) (xy 58.199274 -6.343396) (xy 58.226543 -6.343942)
			(xy 58.280527 -6.3517) (xy 58.332857 -6.367062) (xy 58.382468 -6.389716) (xy 58.42835 -6.4192) (xy 58.469569 -6.454913)
			(xy 58.505285 -6.496129) (xy 58.534772 -6.542009) (xy 58.557429 -6.591619) (xy 58.564228 -6.614772)
			(xy 70.948992 -6.614772) (xy 70.948992 -6.560228) (xy 70.956754 -6.506238) (xy 70.972121 -6.453903)
			(xy 70.994781 -6.404288) (xy 71.02427 -6.358403) (xy 71.05999 -6.317181) (xy 71.101212 -6.281463)
			(xy 71.147099 -6.251975) (xy 71.196715 -6.229317) (xy 71.24905 -6.213952) (xy 71.30304 -6.206191)
			(xy 71.330312 -6.205728) (xy 72.193912 -6.205728) (xy 72.22118 -6.206235) (xy 72.275161 -6.213998)
			(xy 72.327488 -6.229364) (xy 72.377095 -6.25202) (xy 72.422973 -6.281506) (xy 72.464188 -6.31722)
			(xy 72.499901 -6.358436) (xy 72.529385 -6.404315) (xy 72.55204 -6.453924) (xy 72.567404 -6.506251)
			(xy 72.575166 -6.560232) (xy 72.575166 -6.614768) (xy 72.567404 -6.668749) (xy 72.55204 -6.721076)
			(xy 72.529385 -6.770685) (xy 72.499901 -6.816564) (xy 72.464188 -6.85778) (xy 72.422973 -6.893494)
			(xy 72.377095 -6.92298) (xy 72.327488 -6.945636) (xy 72.275161 -6.961002) (xy 72.22118 -6.968765)
			(xy 72.193912 -6.969252) (xy 71.330312 -6.969252) (xy 71.30304 -6.968809) (xy 71.24905 -6.961048)
			(xy 71.196715 -6.945683) (xy 71.147099 -6.923025) (xy 71.101212 -6.893537) (xy 71.05999 -6.857819)
			(xy 71.02427 -6.816597) (xy 70.994781 -6.770712) (xy 70.972121 -6.721097) (xy 70.956754 -6.668762)
			(xy 70.948992 -6.614772) (xy 58.564228 -6.614772) (xy 58.572795 -6.643948) (xy 58.580557 -6.697931)
			(xy 58.580557 -6.752469) (xy 58.572795 -6.806452) (xy 58.557429 -6.858781) (xy 58.534772 -6.908391)
			(xy 58.505285 -6.954271) (xy 58.469569 -6.995487) (xy 58.42835 -7.0312) (xy 58.382468 -7.060684)
			(xy 58.332857 -7.083338) (xy 58.280527 -7.0987) (xy 58.226543 -7.106458) (xy 58.199274 -7.10692)
			(xy 57.335674 -7.10692) (xy 57.308403 -7.106516) (xy 57.254416 -7.09875) (xy 57.202084 -7.083381)
			(xy 57.152472 -7.060721) (xy 57.106589 -7.031231) (xy 57.06537 -6.995512) (xy 57.029654 -6.95429)
			(xy 57.000167 -6.908406) (xy 56.97751 -6.858792) (xy 56.962144 -6.806458) (xy 56.954382 -6.752471)
			(xy 54.980533 -6.752471) (xy 54.972774 -6.80644) (xy 54.957412 -6.858761) (xy 54.93476 -6.908364)
			(xy 54.905281 -6.954238) (xy 54.869573 -6.99545) (xy 54.828364 -7.031162) (xy 54.782492 -7.060645)
			(xy 54.732891 -7.083301) (xy 54.680571 -7.098667) (xy 54.626597 -7.106431) (xy 54.599332 -7.10692)
			(xy 53.735732 -7.10692) (xy 53.708457 -7.106543) (xy 53.65446 -7.098783) (xy 53.602118 -7.083418)
			(xy 53.552495 -7.06076) (xy 53.506603 -7.03127) (xy 53.465374 -6.995549) (xy 53.429649 -6.954323)
			(xy 53.400155 -6.908433) (xy 53.377493 -6.858812) (xy 53.362124 -6.806471) (xy 53.35436 -6.752475)
			(xy 51.380656 -6.752475) (xy 51.372895 -6.80645) (xy 51.35753 -6.858778) (xy 51.334874 -6.908386)
			(xy 51.305389 -6.954265) (xy 51.269674 -6.995481) (xy 51.228457 -7.031195) (xy 51.182578 -7.060679)
			(xy 51.132969 -7.083333) (xy 51.08064 -7.098697) (xy 51.026658 -7.106457) (xy 50.99939 -7.10692)
			(xy 50.13579 -7.10692) (xy 50.108518 -7.106517) (xy 50.05453 -7.098753) (xy 50.002196 -7.083385)
			(xy 49.952581 -7.060726) (xy 49.906697 -7.031237) (xy 49.865476 -6.995517) (xy 49.829757 -6.954295)
			(xy 49.800269 -6.90841) (xy 49.777611 -6.858795) (xy 49.762245 -6.806461) (xy 49.754483 -6.752472)
			(xy 43.770556 -6.752472) (xy 43.762795 -6.806449) (xy 43.74743 -6.858777) (xy 43.724775 -6.908385)
			(xy 43.69529 -6.954264) (xy 43.659576 -6.995479) (xy 43.61836 -7.031193) (xy 43.572481 -7.060677)
			(xy 43.522873 -7.083332) (xy 43.470546 -7.098696) (xy 43.416564 -7.106457) (xy 43.389296 -7.10692)
			(xy 42.525696 -7.10692) (xy 42.498424 -7.106517) (xy 42.444435 -7.098754) (xy 42.3921 -7.083387)
			(xy 42.342485 -7.060728) (xy 42.296599 -7.031239) (xy 42.255378 -6.995519) (xy 42.219659 -6.954297)
			(xy 42.19017 -6.908412) (xy 42.167512 -6.858796) (xy 42.152145 -6.806461) (xy 42.144383 -6.752472)
			(xy 40.170656 -6.752472) (xy 40.162894 -6.806455) (xy 40.147527 -6.858786) (xy 40.124869 -6.908396)
			(xy 40.09538 -6.954277) (xy 40.059661 -6.995494) (xy 40.01844 -7.031208) (xy 39.972556 -7.060691)
			(xy 39.922943 -7.083343) (xy 39.87061 -7.098704) (xy 39.816624 -7.10646) (xy 39.789354 -7.10692)
			(xy 38.925754 -7.10692) (xy 38.898484 -7.106514) (xy 38.844499 -7.098746) (xy 38.792169 -7.083375)
			(xy 38.74256 -7.060714) (xy 38.696679 -7.031224) (xy 38.655463 -6.995505) (xy 38.619749 -6.954284)
			(xy 38.590264 -6.9084) (xy 38.567608 -6.858787) (xy 38.552244 -6.806456) (xy 38.544482 -6.75247)
			(xy 31.060657 -6.75247) (xy 31.052895 -6.80645) (xy 31.03753 -6.858778) (xy 31.014874 -6.908386)
			(xy 30.985389 -6.954265) (xy 30.949674 -6.995481) (xy 30.908457 -7.031195) (xy 30.862578 -7.060679)
			(xy 30.812969 -7.083333) (xy 30.76064 -7.098697) (xy 30.706658 -7.106457) (xy 30.67939 -7.10692)
			(xy 29.81579 -7.10692) (xy 29.788518 -7.106517) (xy 29.73453 -7.098753) (xy 29.682196 -7.083385)
			(xy 29.632581 -7.060726) (xy 29.586697 -7.031237) (xy 29.545476 -6.995517) (xy 29.509757 -6.954295)
			(xy 29.480269 -6.90841) (xy 29.457611 -6.858795) (xy 29.442245 -6.806461) (xy 29.434483 -6.752472)
			(xy 27.460456 -6.752472) (xy 27.452695 -6.80645) (xy 27.43733 -6.858777) (xy 27.414675 -6.908385)
			(xy 27.38519 -6.954264) (xy 27.349476 -6.99548) (xy 27.308259 -7.031193) (xy 27.26238 -7.060678)
			(xy 27.212772 -7.083332) (xy 27.160444 -7.098696) (xy 27.106462 -7.106457) (xy 27.079194 -7.10692)
			(xy 26.215594 -7.10692) (xy 26.188322 -7.106517) (xy 26.134333 -7.098754) (xy 26.081998 -7.083386)
			(xy 26.032384 -7.060727) (xy 25.986498 -7.031238) (xy 25.945277 -6.995519) (xy 25.909558 -6.954297)
			(xy 25.88007 -6.908411) (xy 25.857412 -6.858796) (xy 25.842045 -6.806461) (xy 25.834283 -6.752472)
			(xy 23.860518 -6.752472) (xy 23.852762 -6.806412) (xy 23.837397 -6.858741) (xy 23.814741 -6.908351)
			(xy 23.785255 -6.954232) (xy 23.749541 -6.995449) (xy 23.708323 -7.031164) (xy 23.662443 -7.06065)
			(xy 23.612833 -7.083306) (xy 23.560504 -7.098672) (xy 23.506521 -7.106433) (xy 23.479252 -7.10692)
			(xy 22.615652 -7.10692) (xy 22.588381 -7.106461) (xy 22.534393 -7.098699) (xy 22.48206 -7.083333)
			(xy 22.432447 -7.060675) (xy 22.386562 -7.031187) (xy 22.345342 -6.99547) (xy 22.309624 -6.954249)
			(xy 22.280136 -6.908365) (xy 22.257478 -6.858752) (xy 22.242112 -6.806419) (xy 22.234349 -6.752431)
			(xy 20.260584 -6.752431) (xy 20.252822 -6.806413) (xy 20.237457 -6.858742) (xy 20.214801 -6.908352)
			(xy 20.185315 -6.954232) (xy 20.1496 -6.99545) (xy 20.108382 -7.031165) (xy 20.062502 -7.060651)
			(xy 20.012892 -7.083307) (xy 19.960563 -7.098672) (xy 19.906579 -7.106434) (xy 19.87931 -7.10692)
			(xy 19.01571 -7.10692) (xy 18.98844 -7.106438) (xy 18.934457 -7.098676) (xy 18.882127 -7.08331) (xy 18.832516 -7.060654)
			(xy 18.786635 -7.031168) (xy 18.745417 -6.995453) (xy 18.709702 -6.954235) (xy 18.680216 -6.908354)
			(xy 18.65756 -6.858743) (xy 18.642194 -6.806413) (xy 18.634432 -6.75243) (xy 13.611098 -6.75243)
			(xy 13.611098 -8.980424) (xy 17.166336 -8.980424) (xy 17.166336 -7.67461) (xy 17.166816 -7.662521)
			(xy 17.174269 -7.639522) (xy 17.188453 -7.619942) (xy 17.207983 -7.605691) (xy 17.230957 -7.598158)
			(xy 17.243044 -7.597648) (xy 18.058384 -7.597648) (xy 18.070453 -7.598177) (xy 18.093413 -7.60563)
			(xy 18.112946 -7.619811) (xy 18.127143 -7.639334) (xy 18.134613 -7.662287) (xy 18.135092 -7.674356)
			(xy 18.135092 -8.98017) (xy 18.134568 -8.992255) (xy 18.127123 -9.015249) (xy 18.11295 -9.034827)
			(xy 18.09343 -9.049079) (xy 18.070467 -9.056618) (xy 18.058384 -9.057132) (xy 17.243044 -9.057132)
			(xy 17.230966 -9.05665) (xy 17.207989 -9.049198) (xy 17.18844 -9.035009) (xy 17.174233 -9.015472)
			(xy 17.16676 -8.992502) (xy 17.166336 -8.980424) (xy 13.611098 -8.980424) (xy 13.611098 -9.071864)
			(xy 18.85188 -9.071864) (xy 18.85188 -7.672324) (xy 18.852333 -7.660244) (xy 18.859793 -7.637264)
			(xy 18.873989 -7.617714) (xy 18.893532 -7.603509) (xy 18.916508 -7.596039) (xy 18.928588 -7.595616)
			(xy 19.965162 -7.595616) (xy 19.977247 -7.596139) (xy 20.000243 -7.603583) (xy 20.019821 -7.617756)
			(xy 20.034074 -7.637276) (xy 20.041611 -7.660241) (xy 20.042124 -7.672324) (xy 20.042124 -9.071864)
			(xy 20.651724 -9.071864) (xy 20.651724 -7.672324) (xy 20.652134 -7.660239) (xy 20.659599 -7.637252)
			(xy 20.673804 -7.617699) (xy 20.693359 -7.603495) (xy 20.716347 -7.596032) (xy 20.728432 -7.595616)
			(xy 21.765006 -7.595616) (xy 21.777093 -7.596102) (xy 21.80009 -7.603557) (xy 21.819668 -7.61774)
			(xy 21.833919 -7.637268) (xy 21.841455 -7.660238) (xy 21.841968 -7.672324) (xy 21.841968 -9.071864)
			(xy 22.451568 -9.071864) (xy 22.451568 -7.672324) (xy 22.45208 -7.660278) (xy 22.459502 -7.637359)
			(xy 22.473631 -7.617845) (xy 22.493088 -7.60364) (xy 22.515978 -7.596128) (xy 22.528022 -7.595616)
			(xy 23.565104 -7.595616) (xy 23.577189 -7.596009) (xy 23.600176 -7.603481) (xy 23.619729 -7.617691)
			(xy 23.633932 -7.637249) (xy 23.641395 -7.660238) (xy 23.641812 -7.672324) (xy 23.641812 -9.071864)
			(xy 24.25192 -9.071864) (xy 24.25192 -7.672324) (xy 24.252334 -7.66024) (xy 24.259798 -7.637253)
			(xy 24.274003 -7.6177) (xy 24.293557 -7.603496) (xy 24.316544 -7.596033) (xy 24.328628 -7.595616)
			(xy 25.365202 -7.595616) (xy 25.377289 -7.596105) (xy 25.400286 -7.60356) (xy 25.419864 -7.617741)
			(xy 25.434115 -7.637269) (xy 25.441651 -7.660238) (xy 25.442164 -7.672324) (xy 25.442164 -9.071864)
			(xy 26.051764 -9.071864) (xy 26.051764 -7.672324) (xy 26.052284 -7.660253) (xy 26.059737 -7.637292)
			(xy 26.07392 -7.617757) (xy 26.093445 -7.60356) (xy 26.116402 -7.596092) (xy 26.128472 -7.595616)
			(xy 27.165046 -7.595616) (xy 27.177136 -7.596068) (xy 27.200134 -7.603534) (xy 27.219711 -7.617726)
			(xy 27.233961 -7.63726) (xy 27.241496 -7.660236) (xy 27.242008 -7.672324) (xy 27.242008 -9.071864)
			(xy 27.851608 -9.071864) (xy 27.851608 -7.672324) (xy 27.85208 -7.660274) (xy 27.859508 -7.637348)
			(xy 27.873645 -7.617831) (xy 27.893113 -7.603627) (xy 27.916014 -7.596122) (xy 27.928062 -7.595616)
			(xy 28.965144 -7.595616) (xy 28.977223 -7.596027) (xy 29.000196 -7.603504) (xy 29.019734 -7.617714)
			(xy 29.033927 -7.637265) (xy 29.041384 -7.660244) (xy 29.041852 -7.672324) (xy 29.041852 -9.071864)
			(xy 29.651452 -9.071864) (xy 29.651452 -7.672324) (xy 29.651979 -7.66028) (xy 29.6594 -7.637363)
			(xy 29.673525 -7.617851) (xy 29.692978 -7.603645) (xy 29.715864 -7.59613) (xy 29.727906 -7.595616)
			(xy 30.764988 -7.595616) (xy 30.777072 -7.596023) (xy 30.800059 -7.603491) (xy 30.819611 -7.617697)
			(xy 30.833815 -7.637252) (xy 30.841278 -7.660239) (xy 30.841696 -7.672324) (xy 30.841696 -9.071864)
			(xy 31.451804 -9.071864) (xy 31.451804 -7.672324) (xy 31.452233 -7.660241) (xy 31.459696 -7.637257)
			(xy 31.473897 -7.617706) (xy 31.493447 -7.603501) (xy 31.516429 -7.596035) (xy 31.528512 -7.595616)
			(xy 32.565086 -7.595616) (xy 32.577172 -7.596119) (xy 32.600169 -7.603569) (xy 32.619747 -7.617747)
			(xy 32.633998 -7.637272) (xy 32.641535 -7.660239) (xy 32.642048 -7.672324) (xy 32.642048 -9.071864)
			(xy 38.761924 -9.071864) (xy 38.761924 -7.672324) (xy 38.762334 -7.660239) (xy 38.769799 -7.637252)
			(xy 38.784004 -7.617699) (xy 38.803559 -7.603495) (xy 38.826547 -7.596032) (xy 38.838632 -7.595616)
			(xy 39.875206 -7.595616) (xy 39.887293 -7.596102) (xy 39.91029 -7.603557) (xy 39.929868 -7.61774)
			(xy 39.944119 -7.637268) (xy 39.951655 -7.660238) (xy 39.952168 -7.672324) (xy 39.952168 -9.071864)
			(xy 40.561768 -9.071864) (xy 40.561768 -7.672324) (xy 40.56228 -7.660278) (xy 40.569702 -7.637359)
			(xy 40.583831 -7.617845) (xy 40.603288 -7.60364) (xy 40.626178 -7.596128) (xy 40.638222 -7.595616)
			(xy 41.675304 -7.595616) (xy 41.687389 -7.596009) (xy 41.710376 -7.603481) (xy 41.729929 -7.617691)
			(xy 41.744132 -7.637249) (xy 41.751595 -7.660238) (xy 41.752012 -7.672324) (xy 41.752012 -9.071864)
			(xy 42.36212 -9.071864) (xy 42.36212 -7.672324) (xy 42.362534 -7.66024) (xy 42.369998 -7.637253)
			(xy 42.384203 -7.6177) (xy 42.403757 -7.603496) (xy 42.426744 -7.596033) (xy 42.438828 -7.595616)
			(xy 43.475402 -7.595616) (xy 43.487489 -7.596105) (xy 43.510486 -7.60356) (xy 43.530064 -7.617741)
			(xy 43.544315 -7.637269) (xy 43.551851 -7.660238) (xy 43.552364 -7.672324) (xy 43.552364 -9.071864)
			(xy 44.161964 -9.071864) (xy 44.161964 -7.672324) (xy 44.162484 -7.660253) (xy 44.169937 -7.637292)
			(xy 44.18412 -7.617757) (xy 44.203645 -7.60356) (xy 44.226602 -7.596092) (xy 44.238672 -7.595616)
			(xy 45.275246 -7.595616) (xy 45.287336 -7.596068) (xy 45.310334 -7.603534) (xy 45.329911 -7.617726)
			(xy 45.344161 -7.63726) (xy 45.351696 -7.660236) (xy 45.352208 -7.672324) (xy 45.352208 -9.071864)
			(xy 49.97196 -9.071864) (xy 49.97196 -7.672324) (xy 49.972484 -7.660254) (xy 49.979936 -7.637293)
			(xy 49.994118 -7.617758) (xy 50.013643 -7.603562) (xy 50.036598 -7.596093) (xy 50.048668 -7.595616)
			(xy 51.085242 -7.595616) (xy 51.097331 -7.596071) (xy 51.120329 -7.603536) (xy 51.139907 -7.617727)
			(xy 51.154157 -7.637261) (xy 51.161692 -7.660236) (xy 51.162204 -7.672324) (xy 51.162204 -9.071864)
			(xy 51.771804 -9.071864) (xy 51.771804 -7.672324) (xy 51.77228 -7.660275) (xy 51.779707 -7.637349)
			(xy 51.793843 -7.617833) (xy 51.813311 -7.603629) (xy 51.83621 -7.596123) (xy 51.848258 -7.595616)
			(xy 52.88534 -7.595616) (xy 52.897419 -7.59603) (xy 52.920392 -7.603507) (xy 52.93993 -7.617715)
			(xy 52.954122 -7.637266) (xy 52.96158 -7.660245) (xy 52.962048 -7.672324) (xy 52.962048 -9.071864)
			(xy 53.572156 -9.071864) (xy 53.572156 -7.672324) (xy 53.572684 -7.660254) (xy 53.580136 -7.637294)
			(xy 53.594317 -7.61776) (xy 53.61384 -7.603563) (xy 53.636795 -7.596093) (xy 53.648864 -7.595616)
			(xy 54.685438 -7.595616) (xy 54.697527 -7.596074) (xy 54.720525 -7.603539) (xy 54.740102 -7.617728)
			(xy 54.754352 -7.637262) (xy 54.761888 -7.660236) (xy 54.7624 -7.672324) (xy 54.7624 -9.071864) (xy 55.372 -9.071864)
			(xy 55.372 -7.672324) (xy 55.372433 -7.660242) (xy 55.379895 -7.637258) (xy 55.394096 -7.617707)
			(xy 55.413644 -7.603503) (xy 55.436626 -7.596036) (xy 55.448708 -7.595616) (xy 56.485282 -7.595616)
			(xy 56.497368 -7.596122) (xy 56.520364 -7.603571) (xy 56.539942 -7.617748) (xy 56.554194 -7.637272)
			(xy 56.561731 -7.66024) (xy 56.562244 -7.672324) (xy 56.562244 -9.071864) (xy 57.171844 -9.071864)
			(xy 57.171844 -7.672324) (xy 57.172384 -7.660255) (xy 57.179834 -7.637297) (xy 57.194013 -7.617764)
			(xy 57.213533 -7.603567) (xy 57.236484 -7.596095) (xy 57.248552 -7.595616) (xy 58.285126 -7.595616)
			(xy 58.297215 -7.596085) (xy 58.320212 -7.603546) (xy 58.339789 -7.617733) (xy 58.35404 -7.637264)
			(xy 58.361576 -7.660237) (xy 58.362088 -7.672324) (xy 58.362088 -9.071864) (xy 71.166736 -9.071864)
			(xy 71.166736 -7.672324) (xy 71.167181 -7.660272) (xy 71.174611 -7.637341) (xy 71.188755 -7.617821)
			(xy 71.208231 -7.603618) (xy 71.231139 -7.596118) (xy 71.24319 -7.595616) (xy 72.280272 -7.595616)
			(xy 72.292356 -7.596037) (xy 72.315341 -7.6035) (xy 72.334894 -7.617703) (xy 72.349098 -7.637255)
			(xy 72.356562 -7.66024) (xy 72.35698 -7.672324) (xy 72.35698 -9.071864) (xy 72.356556 -9.083948)
			(xy 72.349095 -9.106934) (xy 72.334893 -9.126487) (xy 72.315341 -9.140692) (xy 72.292356 -9.148155)
			(xy 72.280272 -9.148572) (xy 71.243698 -9.148572) (xy 71.23161 -9.148094) (xy 71.208611 -9.140639)
			(xy 71.189032 -9.126454) (xy 71.174781 -9.106924) (xy 71.167247 -9.083951) (xy 71.166736 -9.071864)
			(xy 58.362088 -9.071864) (xy 58.361609 -9.083914) (xy 58.354185 -9.10684) (xy 58.34005 -9.126357)
			(xy 58.320582 -9.140562) (xy 58.297682 -9.148066) (xy 58.285634 -9.148572) (xy 57.248552 -9.148572)
			(xy 57.236471 -9.148176) (xy 57.213496 -9.140696) (xy 57.193957 -9.126483) (xy 57.179765 -9.106928)
			(xy 57.172311 -9.083945) (xy 57.171844 -9.071864) (xy 56.562244 -9.071864) (xy 56.56171 -9.083908)
			(xy 56.554293 -9.106825) (xy 56.54017 -9.126338) (xy 56.520717 -9.140544) (xy 56.497832 -9.148059)
			(xy 56.48579 -9.148572) (xy 55.448708 -9.148572) (xy 55.436622 -9.14818) (xy 55.413633 -9.140711)
			(xy 55.39408 -9.1265) (xy 55.379877 -9.106941) (xy 55.372415 -9.08395) (xy 55.372 -9.071864) (xy 54.7624 -9.071864)
			(xy 54.761909 -9.083912) (xy 54.754487 -9.106837) (xy 54.740354 -9.126353) (xy 54.72089 -9.140558)
			(xy 54.697993 -9.148065) (xy 54.685946 -9.148572) (xy 53.648864 -9.148572) (xy 53.636784 -9.148166)
			(xy 53.613809 -9.140689) (xy 53.59427 -9.126479) (xy 53.580078 -9.106926) (xy 53.572623 -9.083944)
			(xy 53.572156 -9.071864) (xy 52.962048 -9.071864) (xy 52.961506 -9.083933) (xy 52.954058 -9.106892)
			(xy 52.93988 -9.126426) (xy 52.92036 -9.140623) (xy 52.897408 -9.148094) (xy 52.88534 -9.148572)
			(xy 51.848766 -9.148572) (xy 51.836676 -9.148122) (xy 51.813676 -9.140657) (xy 51.794098 -9.126466)
			(xy 51.779848 -9.10693) (xy 51.772315 -9.083953) (xy 51.771804 -9.071864) (xy 51.162204 -9.071864)
			(xy 51.16171 -9.083912) (xy 51.154287 -9.106836) (xy 51.140155 -9.126352) (xy 51.120692 -9.140556)
			(xy 51.097796 -9.148064) (xy 51.08575 -9.148572) (xy 50.048668 -9.148572) (xy 50.03658 -9.148214)
			(xy 50.01359 -9.140733) (xy 49.994037 -9.126514) (xy 49.979836 -9.106949) (xy 49.972375 -9.083952)
			(xy 49.97196 -9.071864) (xy 45.352208 -9.071864) (xy 45.35171 -9.083912) (xy 45.344288 -9.106835)
			(xy 45.330157 -9.12635) (xy 45.310695 -9.140555) (xy 45.2878 -9.148064) (xy 45.275754 -9.148572)
			(xy 44.238672 -9.148572) (xy 44.226584 -9.148211) (xy 44.203594 -9.140731) (xy 44.184042 -9.126513)
			(xy 44.16984 -9.106948) (xy 44.162379 -9.083952) (xy 44.161964 -9.071864) (xy 43.552364 -9.071864)
			(xy 43.551909 -9.083916) (xy 43.544482 -9.106846) (xy 43.530341 -9.126366) (xy 43.510867 -9.140569)
			(xy 43.48796 -9.14807) (xy 43.47591 -9.148572) (xy 42.438828 -9.148572) (xy 42.426743 -9.148163)
			(xy 42.403755 -9.140699) (xy 42.384201 -9.126493) (xy 42.369998 -9.106938) (xy 42.362536 -9.083949)
			(xy 42.36212 -9.071864) (xy 41.752012 -9.071864) (xy 41.751557 -9.083944) (xy 41.7441 -9.106925)
			(xy 41.729904 -9.126476) (xy 41.710361 -9.140681) (xy 41.687384 -9.14815) (xy 41.675304 -9.148572)
			(xy 40.63873 -9.148572) (xy 40.626643 -9.148067) (xy 40.603646 -9.14062) (xy 40.584066 -9.126443)
			(xy 40.569814 -9.106918) (xy 40.562279 -9.083949) (xy 40.561768 -9.071864) (xy 39.952168 -9.071864)
			(xy 39.951709 -9.083915) (xy 39.944282 -9.106845) (xy 39.930142 -9.126364) (xy 39.910669 -9.140568)
			(xy 39.887764 -9.148069) (xy 39.875714 -9.148572) (xy 38.838632 -9.148572) (xy 38.826547 -9.148159)
			(xy 38.80356 -9.140696) (xy 38.784006 -9.126491) (xy 38.769802 -9.106937) (xy 38.76234 -9.083949)
			(xy 38.761924 -9.071864) (xy 32.642048 -9.071864) (xy 32.64151 -9.083908) (xy 32.634093 -9.106824)
			(xy 32.619971 -9.126336) (xy 32.60052 -9.140542) (xy 32.577635 -9.148058) (xy 32.565594 -9.148572)
			(xy 31.528512 -9.148572) (xy 31.516426 -9.148176) (xy 31.493438 -9.140708) (xy 31.473884 -9.126498)
			(xy 31.459681 -9.10694) (xy 31.45222 -9.08395) (xy 31.451804 -9.071864) (xy 30.841696 -9.071864)
			(xy 30.841256 -9.083946) (xy 30.833797 -9.10693) (xy 30.819599 -9.126482) (xy 30.800051 -9.140686)
			(xy 30.77707 -9.148153) (xy 30.764988 -9.148572) (xy 29.728414 -9.148572) (xy 29.716326 -9.148081)
			(xy 29.693328 -9.140629) (xy 29.673749 -9.126449) (xy 29.659498 -9.106921) (xy 29.651963 -9.08395)
			(xy 29.651452 -9.071864) (xy 29.041852 -9.071864) (xy 29.041306 -9.083932) (xy 29.033859 -9.106891)
			(xy 29.019682 -9.126425) (xy 29.000163 -9.140622) (xy 28.977212 -9.148093) (xy 28.965144 -9.148572)
			(xy 27.92857 -9.148572) (xy 27.91648 -9.148119) (xy 27.89348 -9.140655) (xy 27.873902 -9.126464)
			(xy 27.859652 -9.106929) (xy 27.852119 -9.083952) (xy 27.851608 -9.071864) (xy 27.242008 -9.071864)
			(xy 27.24151 -9.083912) (xy 27.234088 -9.106835) (xy 27.219957 -9.12635) (xy 27.200495 -9.140555)
			(xy 27.1776 -9.148064) (xy 27.165554 -9.148572) (xy 26.128472 -9.148572) (xy 26.116384 -9.148211)
			(xy 26.093394 -9.140731) (xy 26.073842 -9.126513) (xy 26.05964 -9.106948) (xy 26.052179 -9.083952)
			(xy 26.051764 -9.071864) (xy 25.442164 -9.071864) (xy 25.441709 -9.083916) (xy 25.434282 -9.106846)
			(xy 25.420141 -9.126366) (xy 25.400667 -9.140569) (xy 25.37776 -9.14807) (xy 25.36571 -9.148572)
			(xy 24.328628 -9.148572) (xy 24.316543 -9.148163) (xy 24.293555 -9.140699) (xy 24.274001 -9.126493)
			(xy 24.259798 -9.106938) (xy 24.252336 -9.083949) (xy 24.25192 -9.071864) (xy 23.641812 -9.071864)
			(xy 23.641357 -9.083944) (xy 23.6339 -9.106925) (xy 23.619704 -9.126476) (xy 23.600161 -9.140681)
			(xy 23.577184 -9.14815) (xy 23.565104 -9.148572) (xy 22.52853 -9.148572) (xy 22.516443 -9.148067)
			(xy 22.493446 -9.14062) (xy 22.473866 -9.126443) (xy 22.459614 -9.106918) (xy 22.452079 -9.083949)
			(xy 22.451568 -9.071864) (xy 21.841968 -9.071864) (xy 21.841509 -9.083915) (xy 21.834082 -9.106845)
			(xy 21.819942 -9.126364) (xy 21.800469 -9.140568) (xy 21.777564 -9.148069) (xy 21.765514 -9.148572)
			(xy 20.728432 -9.148572) (xy 20.716347 -9.148159) (xy 20.69336 -9.140696) (xy 20.673806 -9.126491)
			(xy 20.659602 -9.106937) (xy 20.65214 -9.083949) (xy 20.651724 -9.071864) (xy 20.042124 -9.071864)
			(xy 20.04161 -9.08391) (xy 20.03419 -9.10683) (xy 20.020062 -9.126345) (xy 20.000605 -9.14055) (xy 19.977714 -9.148061)
			(xy 19.96567 -9.148572) (xy 18.928588 -9.148572) (xy 18.916501 -9.148197) (xy 18.893512 -9.140722)
			(xy 18.873959 -9.126507) (xy 18.859756 -9.106945) (xy 18.852295 -9.083951) (xy 18.85188 -9.071864)
			(xy 13.611098 -9.071864) (xy 13.611098 -9.780016) (xy 13.610604 -9.850398) (xy 13.602711 -9.990941)
			(xy 13.58695 -10.13082) (xy 13.563371 -10.269596) (xy 13.532048 -10.406831) (xy 13.493079 -10.542094)
			(xy 13.446587 -10.674959) (xy 13.392719 -10.805008) (xy 13.331643 -10.931832) (xy 13.263553 -11.055033)
			(xy 13.188662 -11.174221) (xy 13.107205 -11.289023) (xy 13.01944 -11.399077) (xy 12.925642 -11.504037)
			(xy 12.826107 -11.603572) (xy 12.721147 -11.69737) (xy 12.611093 -11.785135) (xy 12.496291 -11.866592)
			(xy 12.414985 -11.91768) (xy 18.85188 -11.91768) (xy 18.85188 -10.51814) (xy 18.852394 -10.506094)
			(xy 18.859813 -10.483173) (xy 18.87394 -10.463658) (xy 18.893399 -10.449453) (xy 18.91629 -10.441942)
			(xy 18.928334 -10.441432) (xy 19.965416 -10.441432) (xy 19.977504 -10.4418) (xy 20.000494 -10.449276)
			(xy 20.020047 -10.463493) (xy 20.034249 -10.483057) (xy 20.041709 -10.506052) (xy 20.042124 -10.51814)
			(xy 20.042124 -11.91768) (xy 20.652232 -11.91768) (xy 20.652232 -10.51814) (xy 20.652647 -10.506055)
			(xy 20.660109 -10.483067) (xy 20.674313 -10.463513) (xy 20.693867 -10.449309) (xy 20.716855 -10.441847)
			(xy 20.72894 -10.441432) (xy 21.765514 -10.441432) (xy 21.777604 -10.441895) (xy 21.800603 -10.449355)
			(xy 21.820182 -10.463543) (xy 21.834433 -10.483076) (xy 21.841966 -10.506052) (xy 21.842476 -10.51814)
			(xy 21.842476 -11.91768) (xy 22.452076 -11.91768) (xy 22.452076 -10.51814) (xy 22.452547 -10.506061)
			(xy 22.460001 -10.483082) (xy 22.474193 -10.463533) (xy 22.493732 -10.449327) (xy 22.516705 -10.441855)
			(xy 22.528784 -10.441432) (xy 23.565358 -10.441432) (xy 23.577445 -10.441943) (xy 23.600443 -10.449387)
			(xy 23.620022 -10.463563) (xy 23.634275 -10.483087) (xy 23.641809 -10.506055) (xy 23.64232 -10.51814)
			(xy 23.64232 -11.91768) (xy 24.25192 -11.91768) (xy 24.25192 -10.51814) (xy 24.252394 -10.50609)
			(xy 24.259818 -10.483162) (xy 24.273955 -10.463644) (xy 24.293424 -10.44944) (xy 24.316326 -10.441936)
			(xy 24.328374 -10.441432) (xy 25.365456 -10.441432) (xy 25.37754 -10.441851) (xy 25.400528 -10.449311)
			(xy 25.420083 -10.463514) (xy 25.434287 -10.483068) (xy 25.441749 -10.506056) (xy 25.442164 -10.51814)
			(xy 25.442164 -11.91768) (xy 26.051764 -11.91768) (xy 26.051764 -10.51814) (xy 26.052293 -10.506095)
			(xy 26.059711 -10.483177) (xy 26.073835 -10.463664) (xy 26.093289 -10.449458) (xy 26.116175 -10.441944)
			(xy 26.128218 -10.441432) (xy 27.1653 -10.441432) (xy 27.177387 -10.441813) (xy 27.200376 -10.449285)
			(xy 27.21993 -10.463498) (xy 27.234133 -10.48306) (xy 27.241593 -10.506053) (xy 27.242008 -10.51814)
			(xy 27.242008 -11.91768) (xy 27.852116 -11.91768) (xy 27.852116 -10.51814) (xy 27.852547 -10.506057)
			(xy 27.860007 -10.483071) (xy 27.874207 -10.463518) (xy 27.893757 -10.449314) (xy 27.916741 -10.44185)
			(xy 27.928824 -10.441432) (xy 28.965398 -10.441432) (xy 28.977487 -10.441909) (xy 29.000486 -10.449364)
			(xy 29.020065 -10.463549) (xy 29.034316 -10.483079) (xy 29.041849 -10.506053) (xy 29.04236 -10.51814)
			(xy 29.04236 -11.91768) (xy 29.65196 -11.91768) (xy 29.65196 -10.51814) (xy 29.652493 -10.506096)
			(xy 29.65991 -10.483178) (xy 29.674033 -10.463665) (xy 29.693486 -10.449459) (xy 29.716372 -10.441945)
			(xy 29.728414 -10.441432) (xy 30.765496 -10.441432) (xy 30.777583 -10.441816) (xy 30.800572 -10.449288)
			(xy 30.820126 -10.4635) (xy 30.834329 -10.48306) (xy 30.841789 -10.506053) (xy 30.842204 -10.51814)
			(xy 30.842204 -11.91768) (xy 31.451804 -11.91768) (xy 31.451804 -10.51814) (xy 31.452294 -10.506091)
			(xy 31.459716 -10.483166) (xy 31.473849 -10.46365) (xy 31.493314 -10.449445) (xy 31.516211 -10.441939)
			(xy 31.528258 -10.441432) (xy 32.56534 -10.441432) (xy 32.577421 -10.441831) (xy 32.600396 -10.449309)
			(xy 32.619936 -10.463521) (xy 32.634128 -10.483076) (xy 32.641582 -10.506059) (xy 32.642048 -10.51814)
			(xy 32.642048 -11.91768) (xy 38.761924 -11.91768) (xy 38.761924 -10.51814) (xy 38.762394 -10.506089)
			(xy 38.769819 -10.483161) (xy 38.783956 -10.463643) (xy 38.803426 -10.449439) (xy 38.826329 -10.441936)
			(xy 38.838378 -10.441432) (xy 39.87546 -10.441432) (xy 39.887545 -10.441847) (xy 39.910533 -10.449309)
			(xy 39.930087 -10.463513) (xy 39.944291 -10.483067) (xy 39.951753 -10.506055) (xy 39.952168 -10.51814)
			(xy 39.952168 -11.91768) (xy 40.561768 -11.91768) (xy 40.561768 -10.51814) (xy 40.562293 -10.506095)
			(xy 40.569711 -10.483176) (xy 40.583836 -10.463662) (xy 40.603291 -10.449457) (xy 40.626179 -10.441944)
			(xy 40.638222 -10.441432) (xy 41.675304 -10.441432) (xy 41.687391 -10.44181) (xy 41.710381 -10.449283)
			(xy 41.729934 -10.463497) (xy 41.744137 -10.483059) (xy 41.751597 -10.506053) (xy 41.752012 -10.51814)
			(xy 41.752012 -11.91768) (xy 42.36212 -11.91768) (xy 42.36212 -10.51814) (xy 42.362547 -10.506057)
			(xy 42.370007 -10.48307) (xy 42.384208 -10.463517) (xy 42.40376 -10.449313) (xy 42.426745 -10.441849)
			(xy 42.438828 -10.441432) (xy 43.475402 -10.441432) (xy 43.487491 -10.441906) (xy 43.51049 -10.449362)
			(xy 43.530069 -10.463547) (xy 43.54432 -10.483079) (xy 43.551853 -10.506053) (xy 43.552364 -10.51814)
			(xy 43.552364 -11.91768) (xy 44.161964 -11.91768) (xy 44.161964 -10.51814) (xy 44.162493 -10.506095)
			(xy 44.169911 -10.483177) (xy 44.184035 -10.463664) (xy 44.203489 -10.449458) (xy 44.226375 -10.441944)
			(xy 44.238418 -10.441432) (xy 45.2755 -10.441432) (xy 45.287587 -10.441813) (xy 45.310576 -10.449285)
			(xy 45.33013 -10.463498) (xy 45.344333 -10.48306) (xy 45.351793 -10.506053) (xy 45.352208 -10.51814)
			(xy 45.352208 -11.91768) (xy 49.97196 -11.91768) (xy 49.97196 -10.51814) (xy 49.972493 -10.506096)
			(xy 49.97991 -10.483178) (xy 49.994033 -10.463665) (xy 50.013486 -10.449459) (xy 50.036372 -10.441945)
			(xy 50.048414 -10.441432) (xy 51.085496 -10.441432) (xy 51.097583 -10.441816) (xy 51.120572 -10.449288)
			(xy 51.140126 -10.4635) (xy 51.154329 -10.48306) (xy 51.161789 -10.506053) (xy 51.162204 -10.51814)
			(xy 51.162204 -11.91768) (xy 51.771804 -11.91768) (xy 51.771804 -10.51814) (xy 51.772294 -10.506091)
			(xy 51.779716 -10.483166) (xy 51.793849 -10.46365) (xy 51.813314 -10.449445) (xy 51.836211 -10.441939)
			(xy 51.848258 -10.441432) (xy 52.88534 -10.441432) (xy 52.897421 -10.441831) (xy 52.920396 -10.449309)
			(xy 52.939936 -10.463521) (xy 52.954128 -10.483076) (xy 52.961582 -10.506059) (xy 52.962048 -10.51814)
			(xy 52.962048 -11.91768) (xy 53.572156 -11.91768) (xy 53.572156 -10.51814) (xy 53.572646 -10.506063)
			(xy 53.580098 -10.483088) (xy 53.594286 -10.46354) (xy 53.613819 -10.449333) (xy 53.636787 -10.441858)
			(xy 53.648864 -10.441432) (xy 54.685438 -10.441432) (xy 54.697529 -10.441875) (xy 54.720529 -10.449341)
			(xy 54.740108 -10.463534) (xy 54.754357 -10.483072) (xy 54.76189 -10.506051) (xy 54.7624 -10.51814)
			(xy 54.7624 -11.91768) (xy 55.372 -11.91768) (xy 55.372 -10.51814) (xy 55.372494 -10.506092) (xy 55.379916 -10.483168)
			(xy 55.394048 -10.463651) (xy 55.413511 -10.449446) (xy 55.436408 -10.441939) (xy 55.448454 -10.441432)
			(xy 56.485536 -10.441432) (xy 56.497625 -10.441783) (xy 56.520615 -10.449265) (xy 56.540168 -10.463486)
			(xy 56.55437 -10.483053) (xy 56.561829 -10.506051) (xy 56.562244 -10.51814) (xy 56.562244 -11.91768)
			(xy 57.171844 -11.91768) (xy 57.171844 -10.51814) (xy 57.172393 -10.506097) (xy 57.179808 -10.483183)
			(xy 57.193928 -10.463671) (xy 57.213376 -10.449464) (xy 57.236258 -10.441947) (xy 57.248298 -10.441432)
			(xy 58.28538 -10.441432) (xy 58.297466 -10.44183) (xy 58.320454 -10.449297) (xy 58.340008 -10.463506)
			(xy 58.354212 -10.483063) (xy 58.361673 -10.506054) (xy 58.362088 -10.51814) (xy 58.362088 -11.91768)
			(xy 58.36167 -11.929764) (xy 58.354205 -11.952749) (xy 58.340001 -11.972301) (xy 58.320449 -11.986505)
			(xy 58.297464 -11.99397) (xy 58.28538 -11.994388) (xy 57.248806 -11.994388) (xy 57.23672 -11.993888)
			(xy 57.213724 -11.986436) (xy 57.194146 -11.972257) (xy 57.179895 -11.952732) (xy 57.172358 -11.929765)
			(xy 57.171844 -11.91768) (xy 56.562244 -11.91768) (xy 56.561719 -11.92975) (xy 56.554267 -11.95271)
			(xy 56.540085 -11.972245) (xy 56.520561 -11.986441) (xy 56.497606 -11.993911) (xy 56.485536 -11.994388)
			(xy 55.448962 -11.994388) (xy 55.436873 -11.993926) (xy 55.413876 -11.986462) (xy 55.394299 -11.972273)
			(xy 55.380049 -11.952741) (xy 55.372513 -11.929767) (xy 55.372 -11.91768) (xy 54.7624 -11.91768)
			(xy 54.761923 -11.929729) (xy 54.754496 -11.952654) (xy 54.740359 -11.97217) (xy 54.720892 -11.986374)
			(xy 54.697993 -11.993881) (xy 54.685946 -11.994388) (xy 53.648864 -11.994388) (xy 53.636786 -11.993966)
			(xy 53.613814 -11.986491) (xy 53.594276 -11.972285) (xy 53.580083 -11.952736) (xy 53.572625 -11.929759)
			(xy 53.572156 -11.91768) (xy 52.962048 -11.91768) (xy 52.961519 -11.92975) (xy 52.954067 -11.952709)
			(xy 52.939886 -11.972243) (xy 52.920363 -11.98644) (xy 52.897409 -11.99391) (xy 52.88534 -11.994388)
			(xy 51.848766 -11.994388) (xy 51.836677 -11.993922) (xy 51.81368 -11.98646) (xy 51.794103 -11.972272)
			(xy 51.779853 -11.95274) (xy 51.772317 -11.929767) (xy 51.771804 -11.91768) (xy 51.162204 -11.91768)
			(xy 51.16177 -11.929762) (xy 51.154308 -11.952745) (xy 51.140107 -11.972296) (xy 51.120559 -11.9865)
			(xy 51.097578 -11.993968) (xy 51.085496 -11.994388) (xy 50.048922 -11.994388) (xy 50.036836 -11.993874)
			(xy 50.013841 -11.986427) (xy 49.994263 -11.972252) (xy 49.980011 -11.952729) (xy 49.972474 -11.929764)
			(xy 49.97196 -11.91768) (xy 45.352208 -11.91768) (xy 45.35177 -11.929762) (xy 45.344308 -11.952744)
			(xy 45.330108 -11.972294) (xy 45.310562 -11.986499) (xy 45.287582 -11.993967) (xy 45.2755 -11.994388)
			(xy 44.238926 -11.994388) (xy 44.226841 -11.993871) (xy 44.203846 -11.986425) (xy 44.184268 -11.97225)
			(xy 44.170015 -11.952729) (xy 44.162478 -11.929763) (xy 44.161964 -11.91768) (xy 43.552364 -11.91768)
			(xy 43.551922 -11.929733) (xy 43.544491 -11.952664) (xy 43.530347 -11.972183) (xy 43.51087 -11.986386)
			(xy 43.487961 -11.993886) (xy 43.47591 -11.994388) (xy 42.438828 -11.994388) (xy 42.426745 -11.993963)
			(xy 42.40376 -11.986501) (xy 42.384207 -11.972299) (xy 42.370003 -11.952748) (xy 42.362538 -11.929763)
			(xy 42.36212 -11.91768) (xy 41.752012 -11.91768) (xy 41.75157 -11.929761) (xy 41.744109 -11.952743)
			(xy 41.72991 -11.972293) (xy 41.710364 -11.986498) (xy 41.687385 -11.993966) (xy 41.675304 -11.994388)
			(xy 40.63873 -11.994388) (xy 40.626645 -11.993868) (xy 40.60365 -11.986423) (xy 40.584072 -11.972249)
			(xy 40.569819 -11.952728) (xy 40.562282 -11.929763) (xy 40.561768 -11.91768) (xy 39.952168 -11.91768)
			(xy 39.95177 -11.929766) (xy 39.944303 -11.952754) (xy 39.930094 -11.972308) (xy 39.910537 -11.986512)
			(xy 39.887546 -11.993973) (xy 39.87546 -11.994388) (xy 38.838886 -11.994388) (xy 38.826798 -11.993905)
			(xy 38.803802 -11.986448) (xy 38.784225 -11.972265) (xy 38.769974 -11.952736) (xy 38.762437 -11.929766)
			(xy 38.761924 -11.91768) (xy 32.642048 -11.91768) (xy 32.641519 -11.92975) (xy 32.634067 -11.952709)
			(xy 32.619886 -11.972243) (xy 32.600363 -11.98644) (xy 32.577409 -11.99391) (xy 32.56534 -11.994388)
			(xy 31.528766 -11.994388) (xy 31.516677 -11.993922) (xy 31.49368 -11.98646) (xy 31.474103 -11.972272)
			(xy 31.459853 -11.95274) (xy 31.452317 -11.929767) (xy 31.451804 -11.91768) (xy 30.842204 -11.91768)
			(xy 30.84177 -11.929762) (xy 30.834308 -11.952745) (xy 30.820107 -11.972296) (xy 30.800559 -11.9865)
			(xy 30.777578 -11.993968) (xy 30.765496 -11.994388) (xy 29.728922 -11.994388) (xy 29.716836 -11.993874)
			(xy 29.693841 -11.986427) (xy 29.674263 -11.972252) (xy 29.660011 -11.952729) (xy 29.652474 -11.929764)
			(xy 29.65196 -11.91768) (xy 29.04236 -11.91768) (xy 29.041922 -11.929733) (xy 29.03449 -11.952665)
			(xy 29.020345 -11.972184) (xy 29.000867 -11.986387) (xy 28.977958 -11.993887) (xy 28.965906 -11.994388)
			(xy 27.928824 -11.994388) (xy 27.916741 -11.993966) (xy 27.893755 -11.986503) (xy 27.874203 -11.9723)
			(xy 27.859999 -11.952748) (xy 27.852534 -11.929763) (xy 27.852116 -11.91768) (xy 27.242008 -11.91768)
			(xy 27.24157 -11.929762) (xy 27.234108 -11.952744) (xy 27.219908 -11.972294) (xy 27.200362 -11.986499)
			(xy 27.177382 -11.993967) (xy 27.1653 -11.994388) (xy 26.128726 -11.994388) (xy 26.116641 -11.993871)
			(xy 26.093646 -11.986425) (xy 26.074068 -11.97225) (xy 26.059815 -11.952729) (xy 26.052278 -11.929763)
			(xy 26.051764 -11.91768) (xy 25.442164 -11.91768) (xy 25.441769 -11.929766) (xy 25.434302 -11.952756)
			(xy 25.420093 -11.97231) (xy 25.400534 -11.986513) (xy 25.377542 -11.993973) (xy 25.365456 -11.994388)
			(xy 24.328882 -11.994388) (xy 24.316794 -11.993909) (xy 24.293798 -11.98645) (xy 24.27422 -11.972266)
			(xy 24.259969 -11.952737) (xy 24.252433 -11.929766) (xy 24.25192 -11.91768) (xy 23.64232 -11.91768)
			(xy 23.641823 -11.929727) (xy 23.634399 -11.952649) (xy 23.620267 -11.972163) (xy 23.600805 -11.986368)
			(xy 23.577911 -11.993878) (xy 23.565866 -11.994388) (xy 22.528784 -11.994388) (xy 22.516698 -11.994001)
			(xy 22.493712 -11.986526) (xy 22.47416 -11.972314) (xy 22.459957 -11.952756) (xy 22.452494 -11.929766)
			(xy 22.452076 -11.91768) (xy 21.842476 -11.91768) (xy 21.842023 -11.929732) (xy 21.834592 -11.95266)
			(xy 21.820451 -11.972179) (xy 21.800977 -11.986382) (xy 21.778072 -11.993884) (xy 21.766022 -11.994388)
			(xy 20.72894 -11.994388) (xy 20.716857 -11.993953) (xy 20.693873 -11.986494) (xy 20.67432 -11.972294)
			(xy 20.660115 -11.952745) (xy 20.65265 -11.929763) (xy 20.652232 -11.91768) (xy 20.042124 -11.91768)
			(xy 20.04167 -11.92976) (xy 20.03421 -11.952739) (xy 20.020014 -11.972289) (xy 20.000472 -11.986494)
			(xy 19.977496 -11.993965) (xy 19.965416 -11.994388) (xy 18.928842 -11.994388) (xy 18.916757 -11.993857)
			(xy 18.893763 -11.986416) (xy 18.874185 -11.972244) (xy 18.859932 -11.952726) (xy 18.852394 -11.929763)
			(xy 18.85188 -11.91768) (xy 12.414985 -11.91768) (xy 12.377103 -11.941483) (xy 12.253902 -12.009573)
			(xy 12.127078 -12.070649) (xy 11.997029 -12.124517) (xy 11.864164 -12.171009) (xy 11.728901 -12.209978)
			(xy 11.591666 -12.241301) (xy 11.45289 -12.26488) (xy 11.313011 -12.280641) (xy 11.172468 -12.288534)
			(xy 11.102086 -12.289028) (xy 1.999996 -12.289028) (xy 1.944227 -12.289537) (xy 1.833 -12.297872)
			(xy 1.722707 -12.314497) (xy 1.613965 -12.339317) (xy 1.507382 -12.372193) (xy 1.403554 -12.412943)
			(xy 1.353372 -12.43711) (xy 62.309756 -12.43711) (xy 62.310222 -12.396003) (xy 62.317806 -12.314139)
			(xy 62.332909 -12.233324) (xy 62.355404 -12.154247) (xy 62.385098 -12.077583) (xy 62.421737 -12.003984)
			(xy 62.46501 -11.93408) (xy 62.514548 -11.868466) (xy 62.569927 -11.807701) (xy 62.630676 -11.752305)
			(xy 62.696277 -11.70275) (xy 62.766169 -11.659457) (xy 62.839757 -11.622797) (xy 62.916414 -11.593082)
			(xy 62.995485 -11.570566) (xy 63.076295 -11.55544) (xy 63.158157 -11.547833) (xy 63.199264 -11.547348)
			(xy 63.243059 -11.547873) (xy 63.330225 -11.556491) (xy 63.416121 -11.573637) (xy 63.499915 -11.599145)
			(xy 63.580795 -11.632768) (xy 63.619634 -11.653012) (xy 63.6311 -11.65843) (xy 63.656428 -11.65843)
			(xy 63.667894 -11.653012) (xy 63.706738 -11.632781) (xy 63.787623 -11.599174) (xy 63.871416 -11.573672)
			(xy 63.957309 -11.556521) (xy 64.04447 -11.547888) (xy 64.088264 -11.547348) (xy 64.132059 -11.547873)
			(xy 64.219225 -11.556491) (xy 64.305121 -11.573637) (xy 64.388915 -11.599145) (xy 64.469795 -11.632768)
			(xy 64.508634 -11.653012) (xy 64.5201 -11.65843) (xy 64.545428 -11.65843) (xy 64.556894 -11.653012)
			(xy 64.595738 -11.632781) (xy 64.676623 -11.599174) (xy 64.760416 -11.573672) (xy 64.846309 -11.556521)
			(xy 64.93347 -11.547888) (xy 64.977264 -11.547348) (xy 65.021059 -11.547873) (xy 65.108225 -11.556491)
			(xy 65.194121 -11.573637) (xy 65.277915 -11.599145) (xy 65.358795 -11.632768) (xy 65.397634 -11.653012)
			(xy 65.4091 -11.65843) (xy 65.434428 -11.65843) (xy 65.445894 -11.653012) (xy 65.484738 -11.632781)
			(xy 65.565623 -11.599174) (xy 65.649416 -11.573672) (xy 65.735309 -11.556521) (xy 65.82247 -11.547888)
			(xy 65.866264 -11.547348) (xy 65.904554 -11.547763) (xy 65.980848 -11.554368) (xy 66.05629 -11.567515)
			(xy 66.130321 -11.587105) (xy 66.166492 -11.599672) (xy 66.174929 -11.602323) (xy 66.192599 -11.602323)
			(xy 66.201036 -11.599672) (xy 66.237216 -11.587135) (xy 66.311248 -11.56756) (xy 66.386687 -11.554411)
			(xy 66.462976 -11.547785) (xy 66.501264 -11.547348) (xy 66.54268 -11.547848) (xy 66.625149 -11.555593)
			(xy 66.706543 -11.570964) (xy 66.786158 -11.593827) (xy 66.863305 -11.623986) (xy 66.937318 -11.661178)
			(xy 66.972688 -11.68273) (xy 66.980074 -11.686987) (xy 66.996689 -11.690769) (xy 67.013625 -11.688896)
			(xy 67.021456 -11.685524) (xy 67.057233 -11.668994) (xy 67.131154 -11.641645) (xy 67.207206 -11.620946)
			(xy 67.284791 -11.607058) (xy 67.363301 -11.600092) (xy 67.40271 -11.599672) (xy 67.443826 -11.600089)
			(xy 67.525707 -11.607677) (xy 67.606539 -11.622789) (xy 67.685632 -11.645294) (xy 67.76231 -11.675001)
			(xy 67.835921 -11.711656) (xy 67.905835 -11.754947) (xy 67.971457 -11.804505) (xy 68.032226 -11.859906)
			(xy 68.084891 -11.91768) (xy 71.166736 -11.91768) (xy 71.166736 -10.51814) (xy 71.167195 -10.506088)
			(xy 71.174621 -10.483158) (xy 71.18876 -10.463638) (xy 71.208234 -10.449435) (xy 71.23114 -10.441934)
			(xy 71.24319 -10.441432) (xy 72.280272 -10.441432) (xy 72.292357 -10.441837) (xy 72.315346 -10.449302)
			(xy 72.3349 -10.463509) (xy 72.349104 -10.483065) (xy 72.356565 -10.506055) (xy 72.35698 -10.51814)
			(xy 72.35698 -11.91768) (xy 72.35657 -11.929764) (xy 72.349104 -11.952751) (xy 72.334899 -11.972304)
			(xy 72.315344 -11.986508) (xy 72.292356 -11.993971) (xy 72.280272 -11.994388) (xy 71.243698 -11.994388)
			(xy 71.231611 -11.993895) (xy 71.208615 -11.986441) (xy 71.189038 -11.97226) (xy 71.174786 -11.952734)
			(xy 71.167249 -11.929765) (xy 71.166736 -11.91768) (xy 68.084891 -11.91768) (xy 68.087623 -11.920677)
			(xy 68.137178 -11.986301) (xy 68.180465 -12.056218) (xy 68.217117 -12.12983) (xy 68.24682 -12.20651)
			(xy 68.269321 -12.285604) (xy 68.284429 -12.366436) (xy 68.292013 -12.448318) (xy 68.292472 -12.489434)
			(xy 68.291907 -12.533047) (xy 68.283357 -12.619854) (xy 68.266352 -12.705408) (xy 68.241056 -12.788886)
			(xy 68.207711 -12.869488) (xy 68.195659 -12.892068) (xy 70.948547 -12.892068) (xy 70.948547 -12.837532)
			(xy 70.956309 -12.783551) (xy 70.971673 -12.731225) (xy 70.994328 -12.681617) (xy 71.023813 -12.635739)
			(xy 71.059526 -12.594524) (xy 71.100742 -12.558811) (xy 71.146621 -12.529327) (xy 71.196228 -12.506672)
			(xy 71.248555 -12.491308) (xy 71.302536 -12.483547) (xy 71.329804 -12.483084) (xy 72.193404 -12.483084)
			(xy 72.220676 -12.483479) (xy 72.274666 -12.491242) (xy 72.327001 -12.506609) (xy 72.376617 -12.529269)
			(xy 72.422503 -12.558758) (xy 72.463725 -12.594478) (xy 72.499444 -12.6357) (xy 72.528933 -12.681586)
			(xy 72.551592 -12.731202) (xy 72.566959 -12.783538) (xy 72.574721 -12.837528) (xy 72.574721 -12.892072)
			(xy 72.566959 -12.946062) (xy 72.551592 -12.998398) (xy 72.528933 -13.048014) (xy 72.499444 -13.0939)
			(xy 72.463725 -13.135122) (xy 72.422503 -13.170842) (xy 72.376617 -13.200331) (xy 72.327001 -13.222991)
			(xy 72.274666 -13.238358) (xy 72.220676 -13.246121) (xy 72.193404 -13.246608) (xy 71.329804 -13.246608)
			(xy 71.302536 -13.246053) (xy 71.248555 -13.238292) (xy 71.196228 -13.222928) (xy 71.146621 -13.200273)
			(xy 71.100742 -13.170789) (xy 71.059526 -13.135076) (xy 71.023813 -13.093861) (xy 70.994328 -13.047983)
			(xy 70.971673 -12.998375) (xy 70.956309 -12.946049) (xy 70.948547 -12.892068) (xy 68.195659 -12.892068)
			(xy 68.166638 -12.946439) (xy 68.118231 -13.019001) (xy 68.062955 -13.086478) (xy 68.00134 -13.14822)
			(xy 67.933978 -13.203636) (xy 67.861516 -13.252193) (xy 67.823334 -13.273278) (xy 67.814055 -13.278811)
			(xy 67.800889 -13.295908) (xy 67.797934 -13.306298) (xy 67.787525 -13.3474) (xy 67.759881 -13.427561)
			(xy 67.724737 -13.504728) (xy 67.682409 -13.578201) (xy 67.633283 -13.647314) (xy 67.577804 -13.711439)
			(xy 67.516475 -13.769995) (xy 67.449854 -13.82245) (xy 67.378544 -13.868328) (xy 67.303192 -13.907213)
			(xy 67.224482 -13.938753) (xy 67.143129 -13.96266) (xy 67.05987 -13.978719) (xy 66.975461 -13.986784)
			(xy 66.933064 -13.987272) (xy 66.894775 -13.986847) (xy 66.818481 -13.980245) (xy 66.743038 -13.967101)
			(xy 66.669007 -13.947513) (xy 66.632836 -13.934948) (xy 66.624399 -13.932297) (xy 66.606729 -13.932297)
			(xy 66.598292 -13.934948) (xy 66.56211 -13.947478) (xy 66.488079 -13.967055) (xy 66.41264 -13.980205)
			(xy 66.336352 -13.986834) (xy 66.298064 -13.987272) (xy 66.254269 -13.986733) (xy 66.167104 -13.978118)
			(xy 66.081208 -13.960975) (xy 65.997414 -13.93547) (xy 65.916534 -13.90185) (xy 65.877694 -13.881608)
			(xy 65.866228 -13.87619) (xy 65.8409 -13.87619) (xy 65.829434 -13.881608) (xy 65.790581 -13.901822)
			(xy 65.709699 -13.935433) (xy 65.625908 -13.96094) (xy 65.540018 -13.978094) (xy 65.452857 -13.986731)
			(xy 65.409064 -13.987272) (xy 65.365269 -13.986733) (xy 65.278104 -13.978118) (xy 65.192208 -13.960975)
			(xy 65.108414 -13.93547) (xy 65.027534 -13.90185) (xy 64.988694 -13.881608) (xy 64.977228 -13.87619)
			(xy 64.9519 -13.87619) (xy 64.940434 -13.881608) (xy 64.901581 -13.901822) (xy 64.820699 -13.935433)
			(xy 64.736908 -13.96094) (xy 64.651018 -13.978094) (xy 64.563857 -13.986731) (xy 64.520064 -13.987272)
			(xy 64.476269 -13.986733) (xy 64.389104 -13.978118) (xy 64.303208 -13.960975) (xy 64.219414 -13.93547)
			(xy 64.138534 -13.90185) (xy 64.099694 -13.881608) (xy 64.088228 -13.87619) (xy 64.0629 -13.87619)
			(xy 64.051434 -13.881608) (xy 64.012581 -13.901822) (xy 63.931699 -13.935433) (xy 63.847908 -13.96094)
			(xy 63.762018 -13.978094) (xy 63.674857 -13.986731) (xy 63.631064 -13.987272) (xy 63.588804 -13.98679)
			(xy 63.504665 -13.978779) (xy 63.421665 -13.962822) (xy 63.340553 -13.939064) (xy 63.26206 -13.907718)
			(xy 63.186895 -13.869068) (xy 63.115735 -13.823463) (xy 63.049222 -13.771312) (xy 62.987956 -13.713088)
			(xy 62.93249 -13.649314) (xy 62.883323 -13.580566) (xy 62.840899 -13.507464) (xy 62.805601 -13.430668)
			(xy 62.777747 -13.35087) (xy 62.757589 -13.268789) (xy 62.750954 -13.22705) (xy 62.748768 -13.216225)
			(xy 62.736658 -13.197787) (xy 62.727586 -13.19149) (xy 62.693115 -13.169417) (xy 62.628004 -13.119803)
			(xy 62.567725 -13.064419) (xy 62.512788 -13.003732) (xy 62.463657 -12.938255) (xy 62.420747 -12.868543)
			(xy 62.384422 -12.795185) (xy 62.354987 -12.7188) (xy 62.332693 -12.640034) (xy 62.317728 -12.559554)
			(xy 62.310218 -12.47804) (xy 62.309756 -12.43711) (xy 1.353372 -12.43711) (xy 1.303061 -12.461339)
			(xy 1.206466 -12.517108) (xy 1.114309 -12.579941) (xy 1.027105 -12.649484) (xy 0.945341 -12.72535)
			(xy 0.869476 -12.807114) (xy 0.801731 -12.892064) (xy 56.95347 -12.892064) (xy 56.95347 -12.837536)
			(xy 56.96123 -12.783562) (xy 56.976591 -12.731243) (xy 56.999242 -12.681641) (xy 57.02872 -12.635768)
			(xy 57.064426 -12.594556) (xy 57.105634 -12.558845) (xy 57.151504 -12.529362) (xy 57.201103 -12.506706)
			(xy 57.253421 -12.491339) (xy 57.307394 -12.483573) (xy 57.334658 -12.483084) (xy 58.198258 -12.483084)
			(xy 58.225534 -12.483453) (xy 58.279532 -12.491211) (xy 58.331876 -12.506575) (xy 58.381501 -12.529233)
			(xy 58.427395 -12.558723) (xy 58.468625 -12.594445) (xy 58.504351 -12.635671) (xy 58.533847 -12.681562)
			(xy 58.55651 -12.731184) (xy 58.57188 -12.783527) (xy 58.579644 -12.837524) (xy 58.579644 -12.892076)
			(xy 58.57188 -12.946073) (xy 58.55651 -12.998416) (xy 58.533847 -13.048037) (xy 58.504351 -13.093929)
			(xy 58.468625 -13.135155) (xy 58.427395 -13.170877) (xy 58.381501 -13.200367) (xy 58.331876 -13.223025)
			(xy 58.279532 -13.238389) (xy 58.225534 -13.246147) (xy 58.198258 -13.246608) (xy 57.334658 -13.246608)
			(xy 57.307394 -13.246027) (xy 57.253421 -13.238261) (xy 57.201103 -13.222894) (xy 57.151504 -13.200238)
			(xy 57.105634 -13.170755) (xy 57.064426 -13.135044) (xy 57.02872 -13.093832) (xy 56.999242 -13.047959)
			(xy 56.976591 -12.998357) (xy 56.96123 -12.946038) (xy 56.95347 -12.892064) (xy 0.801731 -12.892064)
			(xy 0.799933 -12.894318) (xy 0.737102 -12.986476) (xy 0.681333 -13.083072) (xy 0.632939 -13.183565)
			(xy 0.59219 -13.287393) (xy 0.559313 -13.393977) (xy 0.534494 -13.502719) (xy 0.517871 -13.613012)
			(xy 0.509536 -13.724239) (xy 0.509016 -13.780008) (xy 0.509016 -14.351762) (xy 130.051556 -14.351762)
			(xy 130.051556 -12.952222) (xy 130.051979 -12.940099) (xy 130.059467 -12.917037) (xy 130.073718 -12.89742)
			(xy 130.093334 -12.883169) (xy 130.116395 -12.87568) (xy 130.128518 -12.87526) (xy 131.165092 -12.87526)
			(xy 131.177163 -12.875771) (xy 131.200124 -12.883227) (xy 131.219659 -12.897413) (xy 131.233855 -12.91694)
			(xy 131.241323 -12.939897) (xy 131.2418 -12.951968) (xy 131.2418 -14.351762) (xy 131.241789 -14.352016)
			(xy 131.851908 -14.352016) (xy 131.851908 -12.952222) (xy 131.852426 -12.940137) (xy 131.859872 -12.917142)
			(xy 131.874047 -12.897565) (xy 131.893568 -12.883312) (xy 131.916533 -12.875774) (xy 131.928616 -12.87526)
			(xy 132.96519 -12.87526) (xy 132.977314 -12.875669) (xy 133.000377 -12.883161) (xy 133.019994 -12.897415)
			(xy 133.034244 -12.917034) (xy 133.041733 -12.940098) (xy 133.042152 -12.952222) (xy 133.042152 -14.248384)
			(xy 135.55472 -14.248384) (xy 135.55472 -12.952984) (xy 135.555099 -12.940898) (xy 135.562575 -12.91791)
			(xy 135.576788 -12.898357) (xy 135.596349 -12.884155) (xy 135.619341 -12.876692) (xy 135.631428 -12.876276)
			(xy 136.459976 -12.876276) (xy 136.472056 -12.876733) (xy 136.495035 -12.884192) (xy 136.514584 -12.898387)
			(xy 136.52879 -12.917929) (xy 136.536261 -12.940904) (xy 136.536684 -12.952984) (xy 136.536684 -14.248384)
			(xy 136.536273 -14.260468) (xy 136.528807 -14.283454) (xy 136.514601 -14.303007) (xy 136.495047 -14.317211)
			(xy 136.47206 -14.324674) (xy 136.459976 -14.325092) (xy 135.631428 -14.325092) (xy 135.619345 -14.324663)
			(xy 135.596361 -14.317201) (xy 135.576809 -14.303) (xy 135.562604 -14.28345) (xy 135.555139 -14.260467)
			(xy 135.55472 -14.248384) (xy 133.042152 -14.248384) (xy 133.042152 -14.351762) (xy 166.571676 -14.351762)
			(xy 166.571676 -12.952222) (xy 166.572079 -12.940097) (xy 166.57957 -12.917032) (xy 166.593825 -12.897413)
			(xy 166.613446 -12.883163) (xy 166.636513 -12.875677) (xy 166.648638 -12.87526) (xy 167.685212 -12.87526)
			(xy 167.697318 -12.875705) (xy 167.720338 -12.883203) (xy 167.739908 -12.897459) (xy 167.754104 -12.917072)
			(xy 167.761531 -12.940115) (xy 167.76192 -12.952222) (xy 167.76192 -14.351762) (xy 168.37152 -14.351762)
			(xy 168.37152 -12.952222) (xy 168.371978 -12.940102) (xy 168.379462 -12.917047) (xy 168.393705 -12.897433)
			(xy 168.413311 -12.883181) (xy 168.436362 -12.875685) (xy 168.448482 -12.87526) (xy 169.485056 -12.87526)
			(xy 169.497159 -12.875753) (xy 169.520178 -12.883236) (xy 169.539748 -12.897479) (xy 169.553946 -12.917082)
			(xy 169.561374 -12.940119) (xy 169.561764 -12.952222) (xy 169.561764 -14.351762) (xy 170.171872 -14.351762)
			(xy 170.171872 -12.952222) (xy 170.172327 -12.94013) (xy 170.179781 -12.917125) (xy 170.19397 -12.897542)
			(xy 170.213508 -12.883292) (xy 170.23649 -12.875765) (xy 170.24858 -12.87526) (xy 171.285154 -12.87526)
			(xy 171.297277 -12.875699) (xy 171.320338 -12.883182) (xy 171.339955 -12.897427) (xy 171.354207 -12.917041)
			(xy 171.361697 -12.9401) (xy 171.362116 -12.952222) (xy 171.362116 -13.106908) (xy 191.037972 -13.106908)
			(xy 191.03849 -13.065179) (xy 191.046314 -12.98209) (xy 191.061883 -12.900098) (xy 191.085062 -12.819924)
			(xy 191.115646 -12.742273) (xy 191.153367 -12.667827) (xy 191.197893 -12.59724) (xy 191.248833 -12.531132)
			(xy 191.305739 -12.470085) (xy 191.368112 -12.414635) (xy 191.435403 -12.365269) (xy 191.507021 -12.32242)
			(xy 191.582336 -12.286466) (xy 191.660687 -12.257723) (xy 191.700912 -12.24661) (xy 191.713612 -12.243308)
			(xy 191.732408 -12.225274) (xy 191.765936 -12.117578) (xy 191.760348 -12.091924) (xy 191.751712 -12.082018)
			(xy 191.723476 -12.048682) (xy 191.672486 -11.977736) (xy 191.628113 -11.902474) (xy 191.590718 -11.823512)
			(xy 191.560607 -11.741496) (xy 191.538028 -11.657095) (xy 191.523163 -11.571) (xy 191.516135 -11.483915)
			(xy 191.517001 -11.39655) (xy 191.525753 -11.309621) (xy 191.542322 -11.223837) (xy 191.56657 -11.139901)
			(xy 191.5983 -11.058497) (xy 191.637253 -10.980292) (xy 191.683109 -10.905925) (xy 191.735495 -10.836003)
			(xy 191.793982 -10.771099) (xy 191.858092 -10.711742) (xy 191.927301 -10.658417) (xy 192.001043 -10.611562)
			(xy 192.078715 -10.571558) (xy 192.159684 -10.538733) (xy 192.243285 -10.513355) (xy 192.328838 -10.495631)
			(xy 192.415641 -10.485707) (xy 192.502986 -10.483662) (xy 192.590159 -10.489515) (xy 192.676446 -10.503218)
			(xy 192.761144 -10.524657) (xy 192.843559 -10.553659) (xy 192.923018 -10.589985) (xy 192.998871 -10.63334)
			(xy 193.070499 -10.683368) (xy 193.137315 -10.739661) (xy 193.198774 -10.801758) (xy 193.254374 -10.869153)
			(xy 193.303659 -10.941294) (xy 193.346227 -11.017591) (xy 193.381731 -11.097421) (xy 193.409879 -11.180131)
			(xy 193.430442 -11.265046) (xy 193.443252 -11.35147) (xy 193.448204 -11.438699) (xy 193.445257 -11.526018)
			(xy 193.434436 -11.612714) (xy 193.415829 -11.698079) (xy 193.389589 -11.781414) (xy 193.355929 -11.862038)
			(xy 193.315124 -11.939293) (xy 193.267509 -12.012547) (xy 193.213473 -12.081201) (xy 193.153457 -12.144694)
			(xy 193.121026 -12.173966) (xy 193.112347 -12.182457) (xy 193.103466 -12.205016) (xy 193.104008 -12.217146)
			(xy 193.112136 -12.298934) (xy 193.113935 -12.310868) (xy 193.126948 -12.331156) (xy 193.137028 -12.337796)
			(xy 193.137282 -12.33805) (xy 193.173525 -12.359702) (xy 193.242152 -12.408882) (xy 193.305811 -12.464344)
			(xy 193.363928 -12.525589) (xy 193.415979 -12.592065) (xy 193.461498 -12.663174) (xy 193.500073 -12.738277)
			(xy 193.531358 -12.816697) (xy 193.555071 -12.897729) (xy 193.570999 -12.980643) (xy 193.578999 -13.064693)
			(xy 193.579496 -13.106908) (xy 193.579055 -13.148019) (xy 193.571467 -13.22989) (xy 193.556355 -13.310712)
			(xy 193.533849 -13.389794) (xy 193.504141 -13.466462) (xy 193.467484 -13.540061) (xy 193.424192 -13.609963)
			(xy 193.374634 -13.675571) (xy 193.319232 -13.736326) (xy 193.25846 -13.791709) (xy 193.192836 -13.841247)
			(xy 193.122921 -13.884518) (xy 193.049311 -13.921151) (xy 192.972634 -13.950836) (xy 192.893545 -13.973317)
			(xy 192.812719 -13.988404) (xy 192.730845 -13.995968) (xy 192.689734 -13.996416) (xy 192.643339 -13.99582)
			(xy 192.551051 -13.986179) (xy 192.460267 -13.966987) (xy 192.371973 -13.938452) (xy 192.329308 -13.920216)
			(xy 192.319366 -13.91641) (xy 192.298102 -13.91641) (xy 192.28816 -13.920216) (xy 192.245553 -13.938427)
			(xy 192.157387 -13.966948) (xy 192.066733 -13.986143) (xy 191.974574 -13.995806) (xy 191.928242 -13.996416)
			(xy 191.927734 -13.996416) (xy 191.886626 -13.995955) (xy 191.804762 -13.988373) (xy 191.723946 -13.973271)
			(xy 191.644867 -13.950778) (xy 191.568202 -13.921085) (xy 191.494602 -13.884445) (xy 191.424697 -13.841172)
			(xy 191.359082 -13.791634) (xy 191.298317 -13.736254) (xy 191.24292 -13.675504) (xy 191.193365 -13.609903)
			(xy 191.150073 -13.540009) (xy 191.113413 -13.46642) (xy 191.083699 -13.389762) (xy 191.061184 -13.31069)
			(xy 191.04606 -13.229878) (xy 191.038456 -13.148015) (xy 191.037972 -13.106908) (xy 171.362116 -13.106908)
			(xy 171.362116 -14.351762) (xy 171.361707 -14.363887) (xy 171.35422 -14.386953) (xy 171.339967 -14.406573)
			(xy 171.320346 -14.420823) (xy 171.297279 -14.428308) (xy 171.285154 -14.428724) (xy 170.24858 -14.428724)
			(xy 170.236472 -14.428301) (xy 170.213449 -14.420799) (xy 170.193878 -14.406538) (xy 170.179683 -14.38692)
			(xy 170.172259 -14.363871) (xy 170.171872 -14.351762) (xy 169.561764 -14.351762) (xy 169.56126 -14.363849)
			(xy 169.553815 -14.386848) (xy 169.539637 -14.406428) (xy 169.520111 -14.42068) (xy 169.497141 -14.428214)
			(xy 169.485056 -14.428724) (xy 168.448482 -14.428724) (xy 168.436355 -14.428355) (xy 168.413289 -14.420853)
			(xy 168.393671 -14.406589) (xy 168.379422 -14.386961) (xy 168.371937 -14.36389) (xy 168.37152 -14.351762)
			(xy 167.76192 -14.351762) (xy 167.76146 -14.363854) (xy 167.754008 -14.38686) (xy 167.739822 -14.406444)
			(xy 167.720284 -14.420694) (xy 167.697302 -14.42822) (xy 167.685212 -14.428724) (xy 166.648638 -14.428724)
			(xy 166.636513 -14.428307) (xy 166.613449 -14.420821) (xy 166.59383 -14.40657) (xy 166.579579 -14.386951)
			(xy 166.572093 -14.363887) (xy 166.571676 -14.351762) (xy 133.042152 -14.351762) (xy 133.041708 -14.363884)
			(xy 133.034225 -14.386943) (xy 133.01998 -14.40656) (xy 133.000368 -14.420812) (xy 132.977312 -14.428303)
			(xy 132.96519 -14.428724) (xy 131.928616 -14.428724) (xy 131.916544 -14.428222) (xy 131.89358 -14.420766)
			(xy 131.874044 -14.406579) (xy 131.859848 -14.387049) (xy 131.852383 -14.364088) (xy 131.851908 -14.352016)
			(xy 131.241789 -14.352016) (xy 131.241261 -14.363846) (xy 131.23382 -14.386838) (xy 131.21965 -14.406415)
			(xy 131.200134 -14.420669) (xy 131.177174 -14.428209) (xy 131.165092 -14.428724) (xy 130.128518 -14.428724)
			(xy 130.116392 -14.428324) (xy 130.093328 -14.420832) (xy 130.073709 -14.406577) (xy 130.059459 -14.386954)
			(xy 130.051973 -14.363888) (xy 130.051556 -14.351762) (xy 0.509016 -14.351762) (xy 0.509016 -15.959836)
			(xy 12.444984 -15.959836) (xy 12.444984 -14.685518) (xy 12.445424 -14.673425) (xy 12.452881 -14.650418)
			(xy 12.467073 -14.630834) (xy 12.486615 -14.616584) (xy 12.5096 -14.609059) (xy 12.521692 -14.608556)
			(xy 13.029946 -14.608556) (xy 13.042065 -14.608973) (xy 13.065113 -14.616475) (xy 13.084715 -14.63073)
			(xy 13.098954 -14.650345) (xy 13.106437 -14.673399) (xy 13.106908 -14.685518) (xy 13.106908 -15.959836)
			(xy 13.540232 -15.959836) (xy 13.540232 -14.685518) (xy 13.540723 -14.67343) (xy 13.548173 -14.650432)
			(xy 13.562354 -14.630852) (xy 13.581882 -14.616601) (xy 13.604854 -14.609067) (xy 13.61694 -14.608556)
			(xy 14.125194 -14.608556) (xy 14.137318 -14.608965) (xy 14.16038 -14.616458) (xy 14.179997 -14.630712)
			(xy 14.194247 -14.650331) (xy 14.201736 -14.673394) (xy 14.202156 -14.685518) (xy 14.202156 -15.959836)
			(xy 14.201672 -15.971883) (xy 14.194236 -15.9948) (xy 14.1801 -16.01431) (xy 14.160638 -16.028514)
			(xy 14.137747 -16.03603) (xy 14.125702 -16.036544) (xy 13.61694 -16.036544) (xy 13.604863 -16.036054)
			(xy 13.581888 -16.028602) (xy 13.56234 -16.014414) (xy 13.548133 -15.994881) (xy 13.540658 -15.971913)
			(xy 13.540232 -15.959836) (xy 13.106908 -15.959836) (xy 13.106471 -15.971887) (xy 13.099029 -15.994813)
			(xy 13.084882 -16.014327) (xy 13.065408 -16.02853) (xy 13.042504 -16.036036) (xy 13.030454 -16.036544)
			(xy 12.521692 -16.036544) (xy 12.509621 -16.036043) (xy 12.486659 -16.028583) (xy 12.467126 -16.014394)
			(xy 12.45293 -15.994866) (xy 12.445461 -15.971907) (xy 12.444984 -15.959836) (xy 0.509016 -15.959836)
			(xy 0.509016 -16.443452) (xy 15.315184 -16.443452) (xy 15.315184 -15.757398) (xy 15.315607 -15.745304)
			(xy 15.323069 -15.722296) (xy 15.337266 -15.702712) (xy 15.356811 -15.688463) (xy 15.379799 -15.680939)
			(xy 15.391892 -15.680436) (xy 15.586456 -15.680436) (xy 15.597582 -15.680845) (xy 15.618879 -15.687308)
			(xy 15.628366 -15.693136) (xy 15.92199 -15.885668) (xy 15.931367 -15.891385) (xy 15.952383 -15.897721)
			(xy 15.974333 -15.897792) (xy 15.995389 -15.891591) (xy 16.004794 -15.885922) (xy 16.300958 -15.693136)
			(xy 16.310448 -15.68732) (xy 16.331745 -15.680875) (xy 16.342868 -15.680436) (xy 16.537432 -15.680436)
			(xy 16.549521 -15.680786) (xy 16.572512 -15.688268) (xy 16.592066 -15.702489) (xy 16.606267 -15.722056)
			(xy 16.613726 -15.745055) (xy 16.61414 -15.757144) (xy 16.61414 -16.443198) (xy 16.614131 -16.443452)
			(xy 20.903184 -16.443452) (xy 20.903184 -15.757398) (xy 20.903607 -15.745304) (xy 20.911069 -15.722296)
			(xy 20.925266 -15.702712) (xy 20.944811 -15.688463) (xy 20.967799 -15.680939) (xy 20.979892 -15.680436)
			(xy 21.174456 -15.680436) (xy 21.185582 -15.680845) (xy 21.206879 -15.687308) (xy 21.216366 -15.693136)
			(xy 21.50999 -15.885668) (xy 21.519367 -15.891385) (xy 21.540383 -15.897721) (xy 21.562333 -15.897792)
			(xy 21.583389 -15.891591) (xy 21.592794 -15.885922) (xy 21.888958 -15.693136) (xy 21.898448 -15.68732)
			(xy 21.919745 -15.680875) (xy 21.930868 -15.680436) (xy 22.125432 -15.680436) (xy 22.137521 -15.680786)
			(xy 22.160512 -15.688268) (xy 22.180066 -15.702489) (xy 22.194267 -15.722056) (xy 22.201726 -15.745055)
			(xy 22.20214 -15.757144) (xy 22.20214 -16.443198) (xy 22.202131 -16.443452) (xy 26.491184 -16.443452)
			(xy 26.491184 -15.757398) (xy 26.491607 -15.745304) (xy 26.499069 -15.722296) (xy 26.513266 -15.702712)
			(xy 26.532811 -15.688463) (xy 26.555799 -15.680939) (xy 26.567892 -15.680436) (xy 26.762456 -15.680436)
			(xy 26.773582 -15.680845) (xy 26.794879 -15.687308) (xy 26.804366 -15.693136) (xy 27.09799 -15.885668)
			(xy 27.107367 -15.891385) (xy 27.128383 -15.897721) (xy 27.150333 -15.897792) (xy 27.171389 -15.891591)
			(xy 27.180794 -15.885922) (xy 27.476958 -15.693136) (xy 27.486448 -15.68732) (xy 27.507745 -15.680875)
			(xy 27.518868 -15.680436) (xy 27.713432 -15.680436) (xy 27.725521 -15.680786) (xy 27.748512 -15.688268)
			(xy 27.768066 -15.702489) (xy 27.782267 -15.722056) (xy 27.789726 -15.745055) (xy 27.79014 -15.757144)
			(xy 27.79014 -16.443198) (xy 27.790131 -16.443452) (xy 32.079184 -16.443452) (xy 32.079184 -15.757398)
			(xy 32.079607 -15.745304) (xy 32.087069 -15.722296) (xy 32.101266 -15.702712) (xy 32.120811 -15.688463)
			(xy 32.143799 -15.680939) (xy 32.155892 -15.680436) (xy 32.350456 -15.680436) (xy 32.361582 -15.680845)
			(xy 32.382879 -15.687308) (xy 32.392366 -15.693136) (xy 32.68599 -15.885668) (xy 32.695367 -15.891385)
			(xy 32.716383 -15.897721) (xy 32.738333 -15.897792) (xy 32.759389 -15.891591) (xy 32.768794 -15.885922)
			(xy 33.064958 -15.693136) (xy 33.074448 -15.68732) (xy 33.095745 -15.680875) (xy 33.106868 -15.680436)
			(xy 33.301432 -15.680436) (xy 33.313521 -15.680786) (xy 33.336512 -15.688268) (xy 33.356066 -15.702489)
			(xy 33.370267 -15.722056) (xy 33.377726 -15.745055) (xy 33.37814 -15.757144) (xy 33.37814 -16.443198)
			(xy 33.378131 -16.443452) (xy 37.667184 -16.443452) (xy 37.667184 -15.757398) (xy 37.667607 -15.745304)
			(xy 37.675069 -15.722296) (xy 37.689266 -15.702712) (xy 37.708811 -15.688463) (xy 37.731799 -15.680939)
			(xy 37.743892 -15.680436) (xy 37.938456 -15.680436) (xy 37.949582 -15.680845) (xy 37.970879 -15.687308)
			(xy 37.980366 -15.693136) (xy 38.27399 -15.885668) (xy 38.283367 -15.891385) (xy 38.304383 -15.897721)
			(xy 38.326333 -15.897792) (xy 38.347389 -15.891591) (xy 38.356794 -15.885922) (xy 38.652958 -15.693136)
			(xy 38.662448 -15.68732) (xy 38.683745 -15.680875) (xy 38.694868 -15.680436) (xy 38.889432 -15.680436)
			(xy 38.901521 -15.680786) (xy 38.924512 -15.688268) (xy 38.944066 -15.702489) (xy 38.958267 -15.722056)
			(xy 38.965726 -15.745055) (xy 38.96614 -15.757144) (xy 38.96614 -16.443198) (xy 38.966131 -16.443452)
			(xy 43.561 -16.443452) (xy 43.561 -15.757398) (xy 43.561505 -15.745312) (xy 43.568958 -15.722318)
			(xy 43.583136 -15.702742) (xy 43.602659 -15.68849) (xy 43.625624 -15.680951) (xy 43.637708 -15.680436)
			(xy 43.832272 -15.680436) (xy 43.843395 -15.680879) (xy 43.864692 -15.687318) (xy 43.874182 -15.693136)
			(xy 44.167806 -15.885668) (xy 44.177175 -15.891398) (xy 44.198195 -15.897732) (xy 44.220147 -15.897799)
			(xy 44.241205 -15.891593) (xy 44.25061 -15.885922) (xy 44.546774 -15.693136) (xy 44.556281 -15.687351)
			(xy 44.577565 -15.680887) (xy 44.588684 -15.680436) (xy 44.783248 -15.680436) (xy 44.795329 -15.680824)
			(xy 44.818306 -15.688305) (xy 44.837846 -15.70252) (xy 44.852037 -15.722077) (xy 44.859491 -15.745062)
			(xy 44.859956 -15.757144) (xy 44.859956 -16.443198) (xy 44.859946 -16.443452) (xy 49.149 -16.443452)
			(xy 49.149 -15.757398) (xy 49.149505 -15.745312) (xy 49.156958 -15.722318) (xy 49.171136 -15.702742)
			(xy 49.190659 -15.68849) (xy 49.213624 -15.680951) (xy 49.225708 -15.680436) (xy 49.420272 -15.680436)
			(xy 49.431395 -15.680879) (xy 49.452692 -15.687318) (xy 49.462182 -15.693136) (xy 49.755806 -15.885668)
			(xy 49.765175 -15.891398) (xy 49.786195 -15.897732) (xy 49.808147 -15.897799) (xy 49.829205 -15.891593)
			(xy 49.83861 -15.885922) (xy 50.134774 -15.693136) (xy 50.144281 -15.687351) (xy 50.165565 -15.680887)
			(xy 50.176684 -15.680436) (xy 50.371248 -15.680436) (xy 50.383329 -15.680824) (xy 50.406306 -15.688305)
			(xy 50.425846 -15.70252) (xy 50.440037 -15.722077) (xy 50.447491 -15.745062) (xy 50.447956 -15.757144)
			(xy 50.447956 -16.443198) (xy 50.447946 -16.443452) (xy 54.771036 -16.443452) (xy 54.771036 -15.757398)
			(xy 54.771506 -15.745309) (xy 54.778963 -15.722309) (xy 54.793149 -15.702729) (xy 54.812681 -15.688479)
			(xy 54.835656 -15.680946) (xy 54.847744 -15.680436) (xy 55.042308 -15.680436) (xy 55.053432 -15.680864)
			(xy 55.074729 -15.687314) (xy 55.084218 -15.693136) (xy 55.377842 -15.885668) (xy 55.387194 -15.891429)
			(xy 55.408222 -15.897756) (xy 55.43018 -15.897814) (xy 55.451241 -15.891599) (xy 55.460646 -15.885922)
			(xy 55.75681 -15.693136) (xy 55.76631 -15.687337) (xy 55.7876 -15.680882) (xy 55.79872 -15.680436)
			(xy 55.993284 -15.680436) (xy 56.00537 -15.680827) (xy 56.02836 -15.688296) (xy 56.047914 -15.702506)
			(xy 56.062117 -15.722065) (xy 56.069577 -15.745058) (xy 56.069992 -15.757144) (xy 56.069992 -16.443198)
			(xy 56.069491 -16.455284) (xy 56.062039 -16.478279) (xy 56.04786 -16.497857) (xy 56.028336 -16.512108)
			(xy 56.005368 -16.519646) (xy 55.993284 -16.52016) (xy 55.79872 -16.52016) (xy 55.787596 -16.519721)
			(xy 55.766299 -16.513279) (xy 55.75681 -16.50746) (xy 55.461916 -16.314928) (xy 55.452529 -16.309225)
			(xy 55.431491 -16.302952) (xy 55.409537 -16.302952) (xy 55.388499 -16.309225) (xy 55.379112 -16.314928)
			(xy 55.085488 -16.50746) (xy 55.075988 -16.513259) (xy 55.054699 -16.519715) (xy 55.043578 -16.52016)
			(xy 54.847744 -16.52016) (xy 54.835659 -16.519749) (xy 54.812669 -16.512288) (xy 54.793114 -16.498083)
			(xy 54.77891 -16.478527) (xy 54.77145 -16.455537) (xy 54.771036 -16.443452) (xy 50.447946 -16.443452)
			(xy 50.447491 -16.455288) (xy 50.440034 -16.478289) (xy 50.425847 -16.497869) (xy 50.406313 -16.51212)
			(xy 50.383336 -16.519651) (xy 50.371248 -16.52016) (xy 50.176684 -16.52016) (xy 50.165559 -16.519736)
			(xy 50.144262 -16.513283) (xy 50.134774 -16.50746) (xy 49.83988 -16.314928) (xy 49.830493 -16.309225)
			(xy 49.809455 -16.302952) (xy 49.787501 -16.302952) (xy 49.766463 -16.309225) (xy 49.757076 -16.314928)
			(xy 49.463452 -16.50746) (xy 49.45396 -16.513272) (xy 49.432664 -16.51972) (xy 49.421542 -16.52016)
			(xy 49.225708 -16.52016) (xy 49.213621 -16.51978) (xy 49.19063 -16.512309) (xy 49.171076 -16.498096)
			(xy 49.156873 -16.478534) (xy 49.149414 -16.455539) (xy 49.149 -16.443452) (xy 44.859946 -16.443452)
			(xy 44.859491 -16.455288) (xy 44.852034 -16.478289) (xy 44.837847 -16.497869) (xy 44.818313 -16.51212)
			(xy 44.795336 -16.519651) (xy 44.783248 -16.52016) (xy 44.588684 -16.52016) (xy 44.577559 -16.519736)
			(xy 44.556262 -16.513283) (xy 44.546774 -16.50746) (xy 44.25188 -16.314928) (xy 44.242493 -16.309225)
			(xy 44.221455 -16.302952) (xy 44.199501 -16.302952) (xy 44.178463 -16.309225) (xy 44.169076 -16.314928)
			(xy 43.875452 -16.50746) (xy 43.86596 -16.513272) (xy 43.844664 -16.51972) (xy 43.833542 -16.52016)
			(xy 43.637708 -16.52016) (xy 43.625621 -16.51978) (xy 43.60263 -16.512309) (xy 43.583076 -16.498096)
			(xy 43.568873 -16.478534) (xy 43.561414 -16.455539) (xy 43.561 -16.443452) (xy 38.966131 -16.443452)
			(xy 38.96569 -16.455289) (xy 38.958232 -16.478293) (xy 38.944041 -16.497875) (xy 38.924503 -16.512125)
			(xy 38.901522 -16.519653) (xy 38.889432 -16.52016) (xy 38.694868 -16.52016) (xy 38.683743 -16.519742)
			(xy 38.662446 -16.513285) (xy 38.652958 -16.50746) (xy 38.358064 -16.314928) (xy 38.348677 -16.309225)
			(xy 38.327639 -16.302952) (xy 38.305685 -16.302952) (xy 38.284647 -16.309225) (xy 38.27526 -16.314928)
			(xy 37.981636 -16.50746) (xy 37.972147 -16.513278) (xy 37.950849 -16.519722) (xy 37.939726 -16.52016)
			(xy 37.743892 -16.52016) (xy 37.731804 -16.519794) (xy 37.708813 -16.512318) (xy 37.689259 -16.498102)
			(xy 37.675056 -16.478537) (xy 37.667598 -16.45554) (xy 37.667184 -16.443452) (xy 33.378131 -16.443452)
			(xy 33.37769 -16.455289) (xy 33.370232 -16.478293) (xy 33.356041 -16.497875) (xy 33.336503 -16.512125)
			(xy 33.313522 -16.519653) (xy 33.301432 -16.52016) (xy 33.106868 -16.52016) (xy 33.095743 -16.519742)
			(xy 33.074446 -16.513285) (xy 33.064958 -16.50746) (xy 32.770064 -16.314928) (xy 32.760677 -16.309225)
			(xy 32.739639 -16.302952) (xy 32.717685 -16.302952) (xy 32.696647 -16.309225) (xy 32.68726 -16.314928)
			(xy 32.393636 -16.50746) (xy 32.384147 -16.513278) (xy 32.362849 -16.519722) (xy 32.351726 -16.52016)
			(xy 32.155892 -16.52016) (xy 32.143804 -16.519794) (xy 32.120813 -16.512318) (xy 32.101259 -16.498102)
			(xy 32.087056 -16.478537) (xy 32.079598 -16.45554) (xy 32.079184 -16.443452) (xy 27.790131 -16.443452)
			(xy 27.78969 -16.455289) (xy 27.782232 -16.478293) (xy 27.768041 -16.497875) (xy 27.748503 -16.512125)
			(xy 27.725522 -16.519653) (xy 27.713432 -16.52016) (xy 27.518868 -16.52016) (xy 27.507743 -16.519742)
			(xy 27.486446 -16.513285) (xy 27.476958 -16.50746) (xy 27.182064 -16.314928) (xy 27.172677 -16.309225)
			(xy 27.151639 -16.302952) (xy 27.129685 -16.302952) (xy 27.108647 -16.309225) (xy 27.09926 -16.314928)
			(xy 26.805636 -16.50746) (xy 26.796147 -16.513278) (xy 26.774849 -16.519722) (xy 26.763726 -16.52016)
			(xy 26.567892 -16.52016) (xy 26.555804 -16.519794) (xy 26.532813 -16.512318) (xy 26.513259 -16.498102)
			(xy 26.499056 -16.478537) (xy 26.491598 -16.45554) (xy 26.491184 -16.443452) (xy 22.202131 -16.443452)
			(xy 22.20169 -16.455289) (xy 22.194232 -16.478293) (xy 22.180041 -16.497875) (xy 22.160503 -16.512125)
			(xy 22.137522 -16.519653) (xy 22.125432 -16.52016) (xy 21.930868 -16.52016) (xy 21.919743 -16.519742)
			(xy 21.898446 -16.513285) (xy 21.888958 -16.50746) (xy 21.594064 -16.314928) (xy 21.584677 -16.309225)
			(xy 21.563639 -16.302952) (xy 21.541685 -16.302952) (xy 21.520647 -16.309225) (xy 21.51126 -16.314928)
			(xy 21.217636 -16.50746) (xy 21.208147 -16.513278) (xy 21.186849 -16.519722) (xy 21.175726 -16.52016)
			(xy 20.979892 -16.52016) (xy 20.967804 -16.519794) (xy 20.944813 -16.512318) (xy 20.925259 -16.498102)
			(xy 20.911056 -16.478537) (xy 20.903598 -16.45554) (xy 20.903184 -16.443452) (xy 16.614131 -16.443452)
			(xy 16.61369 -16.455289) (xy 16.606232 -16.478293) (xy 16.592041 -16.497875) (xy 16.572503 -16.512125)
			(xy 16.549522 -16.519653) (xy 16.537432 -16.52016) (xy 16.342868 -16.52016) (xy 16.331743 -16.519742)
			(xy 16.310446 -16.513285) (xy 16.300958 -16.50746) (xy 16.006064 -16.314928) (xy 15.996677 -16.309225)
			(xy 15.975639 -16.302952) (xy 15.953685 -16.302952) (xy 15.932647 -16.309225) (xy 15.92326 -16.314928)
			(xy 15.629636 -16.50746) (xy 15.620147 -16.513278) (xy 15.598849 -16.519722) (xy 15.587726 -16.52016)
			(xy 15.391892 -16.52016) (xy 15.379804 -16.519794) (xy 15.356813 -16.512318) (xy 15.337259 -16.498102)
			(xy 15.323056 -16.478537) (xy 15.315598 -16.45554) (xy 15.315184 -16.443452) (xy 0.509016 -16.443452)
			(xy 0.509016 -16.5207) (xy 76.28834 -16.5207) (xy 76.29237 -16.436094) (xy 76.304425 -16.352254)
			(xy 76.324394 -16.26994) (xy 76.352098 -16.189896) (xy 76.387284 -16.112849) (xy 76.429635 -16.039495)
			(xy 76.478768 -15.970499) (xy 76.534236 -15.906485) (xy 76.595538 -15.848035) (xy 76.662118 -15.795676)
			(xy 76.733375 -15.749883) (xy 76.808661 -15.711071) (xy 76.887296 -15.679591) (xy 76.968567 -15.655728)
			(xy 77.051738 -15.639698) (xy 77.136057 -15.631648) (xy 77.178408 -15.63116) (xy 77.178916 -15.63116)
			(xy 77.224101 -15.631724) (xy 77.314005 -15.640873) (xy 77.402518 -15.659097) (xy 77.488725 -15.686205)
			(xy 77.530452 -15.70355) (xy 77.539034 -15.706862) (xy 77.557395 -15.707764) (xy 77.566266 -15.705328)
			(xy 77.610936 -15.69133) (xy 77.702468 -15.671687) (xy 77.795557 -15.661772) (xy 77.842364 -15.661132)
			(xy 77.84338 -15.661132) (xy 77.885732 -15.661539) (xy 77.970052 -15.669589) (xy 78.053225 -15.685618)
			(xy 78.134498 -15.70948) (xy 78.213134 -15.74096) (xy 78.288422 -15.779772) (xy 78.35968 -15.825565)
			(xy 78.426262 -15.877924) (xy 78.487566 -15.936376) (xy 78.543035 -16.00039) (xy 78.592169 -16.069387)
			(xy 78.634521 -16.142742) (xy 78.669709 -16.219791) (xy 78.697413 -16.299835) (xy 78.717383 -16.382151)
			(xy 78.729438 -16.465992) (xy 78.733468 -16.5506) (xy 78.729438 -16.635208) (xy 78.717383 -16.719049)
			(xy 78.697413 -16.801365) (xy 78.669709 -16.881409) (xy 78.634521 -16.958458) (xy 78.592169 -17.031813)
			(xy 78.543035 -17.10081) (xy 78.487566 -17.164824) (xy 78.426262 -17.223276) (xy 78.35968 -17.275635)
			(xy 78.288422 -17.321428) (xy 78.213134 -17.36024) (xy 78.134498 -17.39172) (xy 78.053225 -17.415582)
			(xy 77.970052 -17.431611) (xy 77.885732 -17.439661) (xy 77.84338 -17.440148) (xy 77.842872 -17.440148)
			(xy 77.797687 -17.439588) (xy 77.707782 -17.430437) (xy 77.61927 -17.412213) (xy 77.533063 -17.385103)
			(xy 77.491336 -17.367758) (xy 77.482756 -17.36444) (xy 77.464393 -17.363542) (xy 77.455522 -17.36598)
			(xy 77.410853 -17.379982) (xy 77.319321 -17.399623) (xy 77.226231 -17.409537) (xy 77.179424 -17.410176)
			(xy 77.178408 -17.410176) (xy 77.136057 -17.409752) (xy 77.051738 -17.401702) (xy 76.968567 -17.385672)
			(xy 76.887296 -17.361809) (xy 76.808661 -17.330329) (xy 76.733375 -17.291517) (xy 76.662118 -17.245724)
			(xy 76.595538 -17.193365) (xy 76.534236 -17.134915) (xy 76.478768 -17.070901) (xy 76.429635 -17.001905)
			(xy 76.387284 -16.928551) (xy 76.352098 -16.851504) (xy 76.324394 -16.77146) (xy 76.304425 -16.689146)
			(xy 76.29237 -16.605306) (xy 76.28834 -16.5207) (xy 0.509016 -16.5207) (xy 0.509016 -17.639611) (xy 15.152858 -17.639611)
			(xy 15.152858 -17.585109) (xy 15.160614 -17.531161) (xy 15.175969 -17.478867) (xy 15.19861 -17.42929)
			(xy 15.228076 -17.383439) (xy 15.263768 -17.342249) (xy 15.304958 -17.306558) (xy 15.350808 -17.277091)
			(xy 15.400385 -17.25445) (xy 15.452679 -17.239095) (xy 15.506627 -17.231338) (xy 15.533878 -17.230852)
			(xy 16.397478 -17.230852) (xy 16.424731 -17.231315) (xy 16.478682 -17.239072) (xy 16.53098 -17.254428)
			(xy 16.580561 -17.27707) (xy 16.626414 -17.306538) (xy 16.667607 -17.342232) (xy 16.703301 -17.383424)
			(xy 16.732769 -17.429278) (xy 16.755412 -17.478858) (xy 16.770768 -17.531156) (xy 16.778525 -17.585107)
			(xy 16.778525 -17.639613) (xy 16.770768 -17.693564) (xy 16.755412 -17.745862) (xy 16.732769 -17.795442)
			(xy 16.703301 -17.841296) (xy 16.667607 -17.882488) (xy 16.626414 -17.918182) (xy 16.580561 -17.94765)
			(xy 16.537199 -17.967452) (xy 18.109184 -17.967452) (xy 18.109184 -17.281398) (xy 18.109607 -17.269304)
			(xy 18.117069 -17.246296) (xy 18.131266 -17.226712) (xy 18.150811 -17.212463) (xy 18.173799 -17.204939)
			(xy 18.185892 -17.204436) (xy 18.380456 -17.204436) (xy 18.391582 -17.204845) (xy 18.412879 -17.211308)
			(xy 18.422366 -17.217136) (xy 18.71599 -17.409668) (xy 18.725367 -17.415385) (xy 18.746383 -17.421721)
			(xy 18.768333 -17.421792) (xy 18.789389 -17.415591) (xy 18.798794 -17.409922) (xy 19.094958 -17.217136)
			(xy 19.104448 -17.21132) (xy 19.125745 -17.204875) (xy 19.136868 -17.204436) (xy 19.331432 -17.204436)
			(xy 19.343521 -17.204786) (xy 19.366512 -17.212268) (xy 19.386066 -17.226489) (xy 19.400267 -17.246056)
			(xy 19.407726 -17.269055) (xy 19.40814 -17.281144) (xy 19.40814 -17.639611) (xy 20.740858 -17.639611)
			(xy 20.740858 -17.585109) (xy 20.748614 -17.531161) (xy 20.763969 -17.478867) (xy 20.78661 -17.42929)
			(xy 20.816076 -17.383439) (xy 20.851768 -17.342249) (xy 20.892958 -17.306558) (xy 20.938808 -17.277091)
			(xy 20.988385 -17.25445) (xy 21.040679 -17.239095) (xy 21.094627 -17.231338) (xy 21.121878 -17.230852)
			(xy 21.985478 -17.230852) (xy 22.012729 -17.231394) (xy 22.066677 -17.239147) (xy 22.118972 -17.2545)
			(xy 22.168549 -17.277139) (xy 22.2144 -17.306603) (xy 22.255591 -17.342293) (xy 22.291284 -17.383482)
			(xy 22.320751 -17.429331) (xy 22.343392 -17.478908) (xy 22.358748 -17.531202) (xy 22.366505 -17.585149)
			(xy 22.366505 -17.639651) (xy 22.358748 -17.693598) (xy 22.343392 -17.745892) (xy 22.320751 -17.795469)
			(xy 22.291284 -17.841318) (xy 22.255591 -17.882507) (xy 22.2144 -17.918197) (xy 22.168549 -17.947661)
			(xy 22.125209 -17.967452) (xy 23.697184 -17.967452) (xy 23.697184 -17.281398) (xy 23.697607 -17.269304)
			(xy 23.705069 -17.246296) (xy 23.719266 -17.226712) (xy 23.738811 -17.212463) (xy 23.761799 -17.204939)
			(xy 23.773892 -17.204436) (xy 23.968456 -17.204436) (xy 23.979582 -17.204845) (xy 24.000879 -17.211308)
			(xy 24.010366 -17.217136) (xy 24.30399 -17.409668) (xy 24.313367 -17.415385) (xy 24.334383 -17.421721)
			(xy 24.356333 -17.421792) (xy 24.377389 -17.415591) (xy 24.386794 -17.409922) (xy 24.682958 -17.217136)
			(xy 24.692448 -17.21132) (xy 24.713745 -17.204875) (xy 24.724868 -17.204436) (xy 24.919432 -17.204436)
			(xy 24.931521 -17.204786) (xy 24.954512 -17.212268) (xy 24.974066 -17.226489) (xy 24.988267 -17.246056)
			(xy 24.995726 -17.269055) (xy 24.99614 -17.281144) (xy 24.99614 -17.639653) (xy 26.328838 -17.639653)
			(xy 26.328838 -17.585147) (xy 26.336595 -17.531195) (xy 26.35195 -17.478897) (xy 26.374592 -17.429316)
			(xy 26.404059 -17.383462) (xy 26.439752 -17.342268) (xy 26.480944 -17.306573) (xy 26.526797 -17.277103)
			(xy 26.576376 -17.254458) (xy 26.628674 -17.239099) (xy 26.682625 -17.231339) (xy 26.709878 -17.230852)
			(xy 27.573478 -17.230852) (xy 27.600729 -17.231394) (xy 27.654677 -17.239147) (xy 27.706972 -17.2545)
			(xy 27.756549 -17.277139) (xy 27.8024 -17.306603) (xy 27.843591 -17.342293) (xy 27.879284 -17.383482)
			(xy 27.908751 -17.429331) (xy 27.931392 -17.478908) (xy 27.946748 -17.531202) (xy 27.954505 -17.585149)
			(xy 27.954505 -17.639651) (xy 27.946748 -17.693598) (xy 27.931392 -17.745892) (xy 27.908751 -17.795469)
			(xy 27.879284 -17.841318) (xy 27.843591 -17.882507) (xy 27.8024 -17.918197) (xy 27.756549 -17.947661)
			(xy 27.713209 -17.967452) (xy 29.285184 -17.967452) (xy 29.285184 -17.281398) (xy 29.285607 -17.269304)
			(xy 29.293069 -17.246296) (xy 29.307266 -17.226712) (xy 29.326811 -17.212463) (xy 29.349799 -17.204939)
			(xy 29.361892 -17.204436) (xy 29.556456 -17.204436) (xy 29.567582 -17.204845) (xy 29.588879 -17.211308)
			(xy 29.598366 -17.217136) (xy 29.89199 -17.409668) (xy 29.901367 -17.415385) (xy 29.922383 -17.421721)
			(xy 29.944333 -17.421792) (xy 29.965389 -17.415591) (xy 29.974794 -17.409922) (xy 30.270958 -17.217136)
			(xy 30.280448 -17.21132) (xy 30.301745 -17.204875) (xy 30.312868 -17.204436) (xy 30.507432 -17.204436)
			(xy 30.519521 -17.204786) (xy 30.542512 -17.212268) (xy 30.562066 -17.226489) (xy 30.576267 -17.246056)
			(xy 30.583726 -17.269055) (xy 30.58414 -17.281144) (xy 30.58414 -17.640366) (xy 31.915646 -17.640366)
			(xy 31.915646 -17.585834) (xy 31.923406 -17.531857) (xy 31.938769 -17.479533) (xy 31.961421 -17.429928)
			(xy 31.990902 -17.384052) (xy 32.026611 -17.342838) (xy 32.067822 -17.307125) (xy 32.113695 -17.277639)
			(xy 32.163298 -17.254982) (xy 32.21562 -17.239615) (xy 32.269596 -17.231849) (xy 32.296862 -17.23136)
			(xy 33.160462 -17.23136) (xy 33.187736 -17.231777) (xy 33.24173 -17.239535) (xy 33.294071 -17.254899)
			(xy 33.343691 -17.277556) (xy 33.389583 -17.307044) (xy 33.43081 -17.342764) (xy 33.466533 -17.383987)
			(xy 33.496026 -17.429875) (xy 33.518688 -17.479494) (xy 33.534057 -17.531832) (xy 33.54182 -17.585826)
			(xy 33.54182 -17.640374) (xy 33.534057 -17.694368) (xy 33.518688 -17.746706) (xy 33.496026 -17.796325)
			(xy 33.466533 -17.842213) (xy 33.43081 -17.883436) (xy 33.389583 -17.919156) (xy 33.343691 -17.948644)
			(xy 33.302501 -17.967452) (xy 34.873184 -17.967452) (xy 34.873184 -17.281398) (xy 34.873607 -17.269304)
			(xy 34.881069 -17.246296) (xy 34.895266 -17.226712) (xy 34.914811 -17.212463) (xy 34.937799 -17.204939)
			(xy 34.949892 -17.204436) (xy 35.144456 -17.204436) (xy 35.155582 -17.204845) (xy 35.176879 -17.211308)
			(xy 35.186366 -17.217136) (xy 35.47999 -17.409668) (xy 35.489367 -17.415385) (xy 35.510383 -17.421721)
			(xy 35.532333 -17.421792) (xy 35.553389 -17.415591) (xy 35.562794 -17.409922) (xy 35.858958 -17.217136)
			(xy 35.868448 -17.21132) (xy 35.889745 -17.204875) (xy 35.900868 -17.204436) (xy 36.095432 -17.204436)
			(xy 36.107521 -17.204786) (xy 36.130512 -17.212268) (xy 36.150066 -17.226489) (xy 36.164267 -17.246056)
			(xy 36.171726 -17.269055) (xy 36.17214 -17.281144) (xy 36.17214 -17.640366) (xy 37.503646 -17.640366)
			(xy 37.503646 -17.585834) (xy 37.511406 -17.531857) (xy 37.526769 -17.479533) (xy 37.549421 -17.429928)
			(xy 37.578902 -17.384052) (xy 37.614611 -17.342838) (xy 37.655822 -17.307125) (xy 37.701695 -17.277639)
			(xy 37.751298 -17.254982) (xy 37.80362 -17.239615) (xy 37.857596 -17.231849) (xy 37.884862 -17.23136)
			(xy 38.748462 -17.23136) (xy 38.775736 -17.231777) (xy 38.82973 -17.239535) (xy 38.882071 -17.254899)
			(xy 38.931691 -17.277556) (xy 38.977583 -17.307044) (xy 39.01881 -17.342764) (xy 39.054533 -17.383987)
			(xy 39.084026 -17.429875) (xy 39.106688 -17.479494) (xy 39.122057 -17.531832) (xy 39.12982 -17.585826)
			(xy 39.12982 -17.640374) (xy 39.122057 -17.694368) (xy 39.106688 -17.746706) (xy 39.084026 -17.796325)
			(xy 39.054533 -17.842213) (xy 39.01881 -17.883436) (xy 38.977583 -17.919156) (xy 38.931691 -17.948644)
			(xy 38.890501 -17.967452) (xy 40.767 -17.967452) (xy 40.767 -17.281398) (xy 40.767505 -17.269312)
			(xy 40.774958 -17.246318) (xy 40.789136 -17.226742) (xy 40.808659 -17.21249) (xy 40.831624 -17.204951)
			(xy 40.843708 -17.204436) (xy 41.038272 -17.204436) (xy 41.049395 -17.204879) (xy 41.070692 -17.211318)
			(xy 41.080182 -17.217136) (xy 41.373806 -17.409668) (xy 41.383175 -17.415398) (xy 41.404195 -17.421732)
			(xy 41.426147 -17.421799) (xy 41.447205 -17.415593) (xy 41.45661 -17.409922) (xy 41.752774 -17.217136)
			(xy 41.762281 -17.211351) (xy 41.783565 -17.204887) (xy 41.794684 -17.204436) (xy 41.989248 -17.204436)
			(xy 42.001329 -17.204824) (xy 42.024306 -17.212305) (xy 42.043846 -17.22652) (xy 42.058037 -17.246077)
			(xy 42.065491 -17.269062) (xy 42.065956 -17.281144) (xy 42.065956 -17.639654) (xy 43.398638 -17.639654)
			(xy 43.398638 -17.585146) (xy 43.406395 -17.531193) (xy 43.421751 -17.478894) (xy 43.444395 -17.429312)
			(xy 43.473863 -17.383457) (xy 43.509558 -17.342262) (xy 43.550752 -17.306567) (xy 43.596606 -17.277097)
			(xy 43.646188 -17.254454) (xy 43.698487 -17.239096) (xy 43.75244 -17.231338) (xy 43.779694 -17.230852)
			(xy 44.643294 -17.230852) (xy 44.670544 -17.231395) (xy 44.72449 -17.23915) (xy 44.776783 -17.254504)
			(xy 44.826359 -17.277144) (xy 44.872208 -17.306609) (xy 44.913397 -17.342299) (xy 44.949088 -17.383487)
			(xy 44.978553 -17.429336) (xy 45.001194 -17.478911) (xy 45.016548 -17.531204) (xy 45.024305 -17.58515)
			(xy 45.024305 -17.63965) (xy 45.016548 -17.693596) (xy 45.001194 -17.745889) (xy 44.978553 -17.795464)
			(xy 44.949088 -17.841313) (xy 44.913397 -17.882501) (xy 44.872208 -17.918191) (xy 44.826359 -17.947656)
			(xy 44.783011 -17.967452) (xy 46.355 -17.967452) (xy 46.355 -17.281398) (xy 46.355505 -17.269312)
			(xy 46.362958 -17.246318) (xy 46.377136 -17.226742) (xy 46.396659 -17.21249) (xy 46.419624 -17.204951)
			(xy 46.431708 -17.204436) (xy 46.626272 -17.204436) (xy 46.637395 -17.204879) (xy 46.658692 -17.211318)
			(xy 46.668182 -17.217136) (xy 46.961806 -17.409668) (xy 46.971175 -17.415398) (xy 46.992195 -17.421732)
			(xy 47.014147 -17.421799) (xy 47.035205 -17.415593) (xy 47.04461 -17.409922) (xy 47.340774 -17.217136)
			(xy 47.350281 -17.211351) (xy 47.371565 -17.204887) (xy 47.382684 -17.204436) (xy 47.577248 -17.204436)
			(xy 47.589329 -17.204824) (xy 47.612306 -17.212305) (xy 47.631846 -17.22652) (xy 47.646037 -17.246077)
			(xy 47.653491 -17.269062) (xy 47.653956 -17.281144) (xy 47.653956 -17.639654) (xy 48.986638 -17.639654)
			(xy 48.986638 -17.585146) (xy 48.994395 -17.531193) (xy 49.009751 -17.478894) (xy 49.032395 -17.429312)
			(xy 49.061863 -17.383457) (xy 49.097558 -17.342262) (xy 49.138752 -17.306567) (xy 49.184606 -17.277097)
			(xy 49.234188 -17.254454) (xy 49.286487 -17.239096) (xy 49.34044 -17.231338) (xy 49.367694 -17.230852)
			(xy 50.231294 -17.230852) (xy 50.258544 -17.231395) (xy 50.31249 -17.23915) (xy 50.364783 -17.254504)
			(xy 50.414359 -17.277144) (xy 50.460208 -17.306609) (xy 50.501397 -17.342299) (xy 50.537088 -17.383487)
			(xy 50.566553 -17.429336) (xy 50.589194 -17.478911) (xy 50.604548 -17.531204) (xy 50.612305 -17.58515)
			(xy 50.612305 -17.63965) (xy 50.604548 -17.693596) (xy 50.589194 -17.745889) (xy 50.566553 -17.795464)
			(xy 50.537088 -17.841313) (xy 50.501397 -17.882501) (xy 50.460208 -17.918191) (xy 50.414359 -17.947656)
			(xy 50.371011 -17.967452) (xy 51.977036 -17.967452) (xy 51.977036 -17.281398) (xy 51.977506 -17.269309)
			(xy 51.984963 -17.246309) (xy 51.999149 -17.226729) (xy 52.018681 -17.212479) (xy 52.041656 -17.204946)
			(xy 52.053744 -17.204436) (xy 52.248308 -17.204436) (xy 52.259432 -17.204864) (xy 52.280729 -17.211314)
			(xy 52.290218 -17.217136) (xy 52.583842 -17.409668) (xy 52.593194 -17.415429) (xy 52.614222 -17.421756)
			(xy 52.63618 -17.421814) (xy 52.657241 -17.415599) (xy 52.666646 -17.409922) (xy 52.96281 -17.217136)
			(xy 52.97231 -17.211337) (xy 52.9936 -17.204882) (xy 53.00472 -17.204436) (xy 53.199284 -17.204436)
			(xy 53.21137 -17.204827) (xy 53.23436 -17.212296) (xy 53.253914 -17.226506) (xy 53.268117 -17.246065)
			(xy 53.275577 -17.269058) (xy 53.275992 -17.281144) (xy 53.275992 -17.64037) (xy 54.607423 -17.64037)
			(xy 54.607423 -17.58583) (xy 54.615186 -17.531845) (xy 54.630552 -17.479514) (xy 54.653209 -17.429903)
			(xy 54.682696 -17.384021) (xy 54.718413 -17.342803) (xy 54.759632 -17.307088) (xy 54.805515 -17.277602)
			(xy 54.855127 -17.254947) (xy 54.907459 -17.239583) (xy 54.961444 -17.231822) (xy 54.988714 -17.23136)
			(xy 55.852314 -17.23136) (xy 55.879584 -17.231803) (xy 55.933569 -17.239567) (xy 55.9859 -17.254935)
			(xy 56.035512 -17.277593) (xy 56.081393 -17.307081) (xy 56.122612 -17.342798) (xy 56.158328 -17.384018)
			(xy 56.187814 -17.429901) (xy 56.21047 -17.479513) (xy 56.225836 -17.531844) (xy 56.233598 -17.58583)
			(xy 56.233598 -17.64037) (xy 56.225836 -17.694356) (xy 56.21047 -17.746687) (xy 56.187814 -17.796299)
			(xy 56.158328 -17.842182) (xy 56.122612 -17.883402) (xy 56.081393 -17.919119) (xy 56.035512 -17.948607)
			(xy 55.994249 -17.967452) (xy 57.565036 -17.967452) (xy 57.565036 -17.281398) (xy 57.565506 -17.269309)
			(xy 57.572963 -17.246309) (xy 57.587149 -17.226729) (xy 57.606681 -17.212479) (xy 57.629656 -17.204946)
			(xy 57.641744 -17.204436) (xy 57.836308 -17.204436) (xy 57.847432 -17.204864) (xy 57.868729 -17.211314)
			(xy 57.878218 -17.217136) (xy 58.171842 -17.409668) (xy 58.181194 -17.415429) (xy 58.202222 -17.421756)
			(xy 58.22418 -17.421814) (xy 58.245241 -17.415599) (xy 58.254646 -17.409922) (xy 58.55081 -17.217136)
			(xy 58.56031 -17.211337) (xy 58.5816 -17.204882) (xy 58.59272 -17.204436) (xy 58.787284 -17.204436)
			(xy 58.79937 -17.204827) (xy 58.82236 -17.212296) (xy 58.841914 -17.226506) (xy 58.856117 -17.246065)
			(xy 58.863577 -17.269058) (xy 58.863992 -17.281144) (xy 58.863992 -17.967198) (xy 58.863491 -17.979284)
			(xy 58.856039 -18.002279) (xy 58.84186 -18.021857) (xy 58.822336 -18.036108) (xy 58.799368 -18.043646)
			(xy 58.787284 -18.04416) (xy 58.59272 -18.04416) (xy 58.581596 -18.043721) (xy 58.560299 -18.037279)
			(xy 58.55081 -18.03146) (xy 58.255916 -17.838928) (xy 58.246529 -17.833225) (xy 58.225491 -17.826952)
			(xy 58.203537 -17.826952) (xy 58.182499 -17.833225) (xy 58.173112 -17.838928) (xy 57.879488 -18.03146)
			(xy 57.869988 -18.037259) (xy 57.848699 -18.043715) (xy 57.837578 -18.04416) (xy 57.641744 -18.04416)
			(xy 57.629659 -18.043749) (xy 57.606669 -18.036288) (xy 57.587114 -18.022083) (xy 57.57291 -18.002527)
			(xy 57.56545 -17.979537) (xy 57.565036 -17.967452) (xy 55.994249 -17.967452) (xy 55.9859 -17.971265)
			(xy 55.933569 -17.986633) (xy 55.879584 -17.994397) (xy 55.852314 -17.994884) (xy 54.988714 -17.994884)
			(xy 54.961444 -17.994378) (xy 54.907459 -17.986617) (xy 54.855127 -17.971253) (xy 54.805515 -17.948598)
			(xy 54.759632 -17.919112) (xy 54.718413 -17.883397) (xy 54.682696 -17.842179) (xy 54.653209 -17.796297)
			(xy 54.630552 -17.746686) (xy 54.615186 -17.694355) (xy 54.607423 -17.64037) (xy 53.275992 -17.64037)
			(xy 53.275992 -17.967198) (xy 53.275491 -17.979284) (xy 53.268039 -18.002279) (xy 53.25386 -18.021857)
			(xy 53.234336 -18.036108) (xy 53.211368 -18.043646) (xy 53.199284 -18.04416) (xy 53.00472 -18.04416)
			(xy 52.993596 -18.043721) (xy 52.972299 -18.037279) (xy 52.96281 -18.03146) (xy 52.667916 -17.838928)
			(xy 52.658529 -17.833225) (xy 52.637491 -17.826952) (xy 52.615537 -17.826952) (xy 52.594499 -17.833225)
			(xy 52.585112 -17.838928) (xy 52.291488 -18.03146) (xy 52.281988 -18.037259) (xy 52.260699 -18.043715)
			(xy 52.249578 -18.04416) (xy 52.053744 -18.04416) (xy 52.041659 -18.043749) (xy 52.018669 -18.036288)
			(xy 51.999114 -18.022083) (xy 51.98491 -18.002527) (xy 51.97745 -17.979537) (xy 51.977036 -17.967452)
			(xy 50.371011 -17.967452) (xy 50.364783 -17.970296) (xy 50.31249 -17.98565) (xy 50.258544 -17.993405)
			(xy 50.231294 -17.993868) (xy 49.367694 -17.993868) (xy 49.34044 -17.993462) (xy 49.286487 -17.985704)
			(xy 49.234188 -17.970346) (xy 49.184606 -17.947703) (xy 49.138752 -17.918233) (xy 49.097558 -17.882538)
			(xy 49.061863 -17.841343) (xy 49.032395 -17.795488) (xy 49.009751 -17.745906) (xy 48.994395 -17.693607)
			(xy 48.986638 -17.639654) (xy 47.653956 -17.639654) (xy 47.653956 -17.967198) (xy 47.653491 -17.979288)
			(xy 47.646034 -18.002289) (xy 47.631847 -18.021869) (xy 47.612313 -18.03612) (xy 47.589336 -18.043651)
			(xy 47.577248 -18.04416) (xy 47.382684 -18.04416) (xy 47.371559 -18.043736) (xy 47.350262 -18.037283)
			(xy 47.340774 -18.03146) (xy 47.04588 -17.838928) (xy 47.036493 -17.833225) (xy 47.015455 -17.826952)
			(xy 46.993501 -17.826952) (xy 46.972463 -17.833225) (xy 46.963076 -17.838928) (xy 46.669452 -18.03146)
			(xy 46.65996 -18.037272) (xy 46.638664 -18.04372) (xy 46.627542 -18.04416) (xy 46.431708 -18.04416)
			(xy 46.419621 -18.04378) (xy 46.39663 -18.036309) (xy 46.377076 -18.022096) (xy 46.362873 -18.002534)
			(xy 46.355414 -17.979539) (xy 46.355 -17.967452) (xy 44.783011 -17.967452) (xy 44.776783 -17.970296)
			(xy 44.72449 -17.98565) (xy 44.670544 -17.993405) (xy 44.643294 -17.993868) (xy 43.779694 -17.993868)
			(xy 43.75244 -17.993462) (xy 43.698487 -17.985704) (xy 43.646188 -17.970346) (xy 43.596606 -17.947703)
			(xy 43.550752 -17.918233) (xy 43.509558 -17.882538) (xy 43.473863 -17.841343) (xy 43.444395 -17.795488)
			(xy 43.421751 -17.745906) (xy 43.406395 -17.693607) (xy 43.398638 -17.639654) (xy 42.065956 -17.639654)
			(xy 42.065956 -17.967198) (xy 42.065491 -17.979288) (xy 42.058034 -18.002289) (xy 42.043847 -18.021869)
			(xy 42.024313 -18.03612) (xy 42.001336 -18.043651) (xy 41.989248 -18.04416) (xy 41.794684 -18.04416)
			(xy 41.783559 -18.043736) (xy 41.762262 -18.037283) (xy 41.752774 -18.03146) (xy 41.45788 -17.838928)
			(xy 41.448493 -17.833225) (xy 41.427455 -17.826952) (xy 41.405501 -17.826952) (xy 41.384463 -17.833225)
			(xy 41.375076 -17.838928) (xy 41.081452 -18.03146) (xy 41.07196 -18.037272) (xy 41.050664 -18.04372)
			(xy 41.039542 -18.04416) (xy 40.843708 -18.04416) (xy 40.831621 -18.04378) (xy 40.80863 -18.036309)
			(xy 40.789076 -18.022096) (xy 40.774873 -18.002534) (xy 40.767414 -17.979539) (xy 40.767 -17.967452)
			(xy 38.890501 -17.967452) (xy 38.882071 -17.971301) (xy 38.82973 -17.986665) (xy 38.775736 -17.994423)
			(xy 38.748462 -17.994884) (xy 37.884862 -17.994884) (xy 37.857596 -17.994351) (xy 37.80362 -17.986585)
			(xy 37.751298 -17.971218) (xy 37.701695 -17.948561) (xy 37.655822 -17.919075) (xy 37.614611 -17.883362)
			(xy 37.578902 -17.842148) (xy 37.549421 -17.796272) (xy 37.526769 -17.746667) (xy 37.511406 -17.694343)
			(xy 37.503646 -17.640366) (xy 36.17214 -17.640366) (xy 36.17214 -17.967198) (xy 36.17169 -17.979289)
			(xy 36.164232 -18.002293) (xy 36.150041 -18.021875) (xy 36.130503 -18.036125) (xy 36.107522 -18.043653)
			(xy 36.095432 -18.04416) (xy 35.900868 -18.04416) (xy 35.889743 -18.043742) (xy 35.868446 -18.037285)
			(xy 35.858958 -18.03146) (xy 35.564064 -17.838928) (xy 35.554677 -17.833225) (xy 35.533639 -17.826952)
			(xy 35.511685 -17.826952) (xy 35.490647 -17.833225) (xy 35.48126 -17.838928) (xy 35.187636 -18.03146)
			(xy 35.178147 -18.037278) (xy 35.156849 -18.043722) (xy 35.145726 -18.04416) (xy 34.949892 -18.04416)
			(xy 34.937804 -18.043794) (xy 34.914813 -18.036318) (xy 34.895259 -18.022102) (xy 34.881056 -18.002537)
			(xy 34.873598 -17.97954) (xy 34.873184 -17.967452) (xy 33.302501 -17.967452) (xy 33.294071 -17.971301)
			(xy 33.24173 -17.986665) (xy 33.187736 -17.994423) (xy 33.160462 -17.994884) (xy 32.296862 -17.994884)
			(xy 32.269596 -17.994351) (xy 32.21562 -17.986585) (xy 32.163298 -17.971218) (xy 32.113695 -17.948561)
			(xy 32.067822 -17.919075) (xy 32.026611 -17.883362) (xy 31.990902 -17.842148) (xy 31.961421 -17.796272)
			(xy 31.938769 -17.746667) (xy 31.923406 -17.694343) (xy 31.915646 -17.640366) (xy 30.58414 -17.640366)
			(xy 30.58414 -17.967198) (xy 30.58369 -17.979289) (xy 30.576232 -18.002293) (xy 30.562041 -18.021875)
			(xy 30.542503 -18.036125) (xy 30.519522 -18.043653) (xy 30.507432 -18.04416) (xy 30.312868 -18.04416)
			(xy 30.301743 -18.043742) (xy 30.280446 -18.037285) (xy 30.270958 -18.03146) (xy 29.976064 -17.838928)
			(xy 29.966677 -17.833225) (xy 29.945639 -17.826952) (xy 29.923685 -17.826952) (xy 29.902647 -17.833225)
			(xy 29.89326 -17.838928) (xy 29.599636 -18.03146) (xy 29.590147 -18.037278) (xy 29.568849 -18.043722)
			(xy 29.557726 -18.04416) (xy 29.361892 -18.04416) (xy 29.349804 -18.043794) (xy 29.326813 -18.036318)
			(xy 29.307259 -18.022102) (xy 29.293056 -18.002537) (xy 29.285598 -17.97954) (xy 29.285184 -17.967452)
			(xy 27.713209 -17.967452) (xy 27.706972 -17.9703) (xy 27.654677 -17.985653) (xy 27.600729 -17.993406)
			(xy 27.573478 -17.993868) (xy 26.709878 -17.993868) (xy 26.682625 -17.993461) (xy 26.628674 -17.985701)
			(xy 26.576376 -17.970342) (xy 26.526797 -17.947697) (xy 26.480944 -17.918227) (xy 26.439752 -17.882532)
			(xy 26.404059 -17.841338) (xy 26.374592 -17.795484) (xy 26.35195 -17.745903) (xy 26.336595 -17.693605)
			(xy 26.328838 -17.639653) (xy 24.99614 -17.639653) (xy 24.99614 -17.967198) (xy 24.99569 -17.979289)
			(xy 24.988232 -18.002293) (xy 24.974041 -18.021875) (xy 24.954503 -18.036125) (xy 24.931522 -18.043653)
			(xy 24.919432 -18.04416) (xy 24.724868 -18.04416) (xy 24.713743 -18.043742) (xy 24.692446 -18.037285)
			(xy 24.682958 -18.03146) (xy 24.388064 -17.838928) (xy 24.378677 -17.833225) (xy 24.357639 -17.826952)
			(xy 24.335685 -17.826952) (xy 24.314647 -17.833225) (xy 24.30526 -17.838928) (xy 24.011636 -18.03146)
			(xy 24.002147 -18.037278) (xy 23.980849 -18.043722) (xy 23.969726 -18.04416) (xy 23.773892 -18.04416)
			(xy 23.761804 -18.043794) (xy 23.738813 -18.036318) (xy 23.719259 -18.022102) (xy 23.705056 -18.002537)
			(xy 23.697598 -17.97954) (xy 23.697184 -17.967452) (xy 22.125209 -17.967452) (xy 22.118972 -17.9703)
			(xy 22.066677 -17.985653) (xy 22.012729 -17.993406) (xy 21.985478 -17.993868) (xy 21.121878 -17.993868)
			(xy 21.094627 -17.993382) (xy 21.040679 -17.985625) (xy 20.988385 -17.97027) (xy 20.938808 -17.947629)
			(xy 20.892958 -17.918162) (xy 20.851768 -17.882471) (xy 20.816076 -17.841281) (xy 20.78661 -17.79543)
			(xy 20.763969 -17.745853) (xy 20.748614 -17.693559) (xy 20.740858 -17.639611) (xy 19.40814 -17.639611)
			(xy 19.40814 -17.967198) (xy 19.40769 -17.979289) (xy 19.400232 -18.002293) (xy 19.386041 -18.021875)
			(xy 19.366503 -18.036125) (xy 19.343522 -18.043653) (xy 19.331432 -18.04416) (xy 19.136868 -18.04416)
			(xy 19.125743 -18.043742) (xy 19.104446 -18.037285) (xy 19.094958 -18.03146) (xy 18.800064 -17.838928)
			(xy 18.790677 -17.833225) (xy 18.769639 -17.826952) (xy 18.747685 -17.826952) (xy 18.726647 -17.833225)
			(xy 18.71726 -17.838928) (xy 18.423636 -18.03146) (xy 18.414147 -18.037278) (xy 18.392849 -18.043722)
			(xy 18.381726 -18.04416) (xy 18.185892 -18.04416) (xy 18.173804 -18.043794) (xy 18.150813 -18.036318)
			(xy 18.131259 -18.022102) (xy 18.117056 -18.002537) (xy 18.109598 -17.97954) (xy 18.109184 -17.967452)
			(xy 16.537199 -17.967452) (xy 16.53098 -17.970292) (xy 16.478682 -17.985648) (xy 16.424731 -17.993405)
			(xy 16.397478 -17.993868) (xy 15.533878 -17.993868) (xy 15.506627 -17.993382) (xy 15.452679 -17.985625)
			(xy 15.400385 -17.97027) (xy 15.350808 -17.947629) (xy 15.304958 -17.918162) (xy 15.263768 -17.882471)
			(xy 15.228076 -17.841281) (xy 15.19861 -17.79543) (xy 15.175969 -17.745853) (xy 15.160614 -17.693559)
			(xy 15.152858 -17.639611) (xy 0.509016 -17.639611) (xy 0.509016 -19.164391) (xy 17.945563 -19.164391)
			(xy 17.945563 -19.109849) (xy 17.953326 -19.055862) (xy 17.968692 -19.00353) (xy 17.99135 -18.953917)
			(xy 18.020837 -18.908033) (xy 18.056555 -18.866813) (xy 18.097775 -18.831096) (xy 18.143658 -18.801609)
			(xy 18.193272 -18.778951) (xy 18.245604 -18.763585) (xy 18.299591 -18.755823) (xy 18.326862 -18.75536)
			(xy 19.190462 -18.75536) (xy 19.217731 -18.755843) (xy 19.271715 -18.763605) (xy 19.324045 -18.77897)
			(xy 19.373655 -18.801627) (xy 19.419536 -18.831113) (xy 19.460753 -18.866828) (xy 19.496469 -18.908046)
			(xy 19.525954 -18.953927) (xy 19.548611 -19.003537) (xy 19.563976 -19.055867) (xy 19.571738 -19.109851)
			(xy 19.571738 -19.163653) (xy 23.534838 -19.163653) (xy 23.534838 -19.109147) (xy 23.542595 -19.055195)
			(xy 23.55795 -19.002897) (xy 23.580592 -18.953316) (xy 23.610059 -18.907462) (xy 23.645752 -18.866268)
			(xy 23.686944 -18.830573) (xy 23.732797 -18.801103) (xy 23.782376 -18.778458) (xy 23.834674 -18.763099)
			(xy 23.888625 -18.755339) (xy 23.915878 -18.754852) (xy 24.779478 -18.754852) (xy 24.806729 -18.755394)
			(xy 24.860677 -18.763147) (xy 24.912972 -18.7785) (xy 24.962549 -18.801139) (xy 25.0084 -18.830603)
			(xy 25.049591 -18.866293) (xy 25.085284 -18.907482) (xy 25.114751 -18.953331) (xy 25.137392 -19.002908)
			(xy 25.152748 -19.055202) (xy 25.160505 -19.109149) (xy 25.160505 -19.163651) (xy 25.160505 -19.163653)
			(xy 29.122838 -19.163653) (xy 29.122838 -19.109147) (xy 29.130595 -19.055195) (xy 29.14595 -19.002897)
			(xy 29.168592 -18.953316) (xy 29.198059 -18.907462) (xy 29.233752 -18.866268) (xy 29.274944 -18.830573)
			(xy 29.320797 -18.801103) (xy 29.370376 -18.778458) (xy 29.422674 -18.763099) (xy 29.476625 -18.755339)
			(xy 29.503878 -18.754852) (xy 30.367478 -18.754852) (xy 30.394729 -18.755394) (xy 30.448677 -18.763147)
			(xy 30.500972 -18.7785) (xy 30.550549 -18.801139) (xy 30.5964 -18.830603) (xy 30.637591 -18.866293)
			(xy 30.673284 -18.907482) (xy 30.702751 -18.953331) (xy 30.725392 -19.002908) (xy 30.740748 -19.055202)
			(xy 30.748505 -19.109149) (xy 30.748505 -19.163651) (xy 30.748505 -19.163653) (xy 34.710838 -19.163653)
			(xy 34.710838 -19.109147) (xy 34.718595 -19.055195) (xy 34.73395 -19.002897) (xy 34.756592 -18.953316)
			(xy 34.786059 -18.907462) (xy 34.821752 -18.866268) (xy 34.862944 -18.830573) (xy 34.908797 -18.801103)
			(xy 34.958376 -18.778458) (xy 35.010674 -18.763099) (xy 35.064625 -18.755339) (xy 35.091878 -18.754852)
			(xy 35.955478 -18.754852) (xy 35.982729 -18.755394) (xy 36.036677 -18.763147) (xy 36.088972 -18.7785)
			(xy 36.138549 -18.801139) (xy 36.1844 -18.830603) (xy 36.225591 -18.866293) (xy 36.261284 -18.907482)
			(xy 36.290751 -18.953331) (xy 36.313392 -19.002908) (xy 36.328748 -19.055202) (xy 36.336505 -19.109149)
			(xy 36.336505 -19.163651) (xy 36.336505 -19.163654) (xy 40.604638 -19.163654) (xy 40.604638 -19.109146)
			(xy 40.612395 -19.055193) (xy 40.627751 -19.002894) (xy 40.650395 -18.953312) (xy 40.679863 -18.907457)
			(xy 40.715558 -18.866262) (xy 40.756752 -18.830567) (xy 40.802606 -18.801097) (xy 40.852188 -18.778454)
			(xy 40.904487 -18.763096) (xy 40.95844 -18.755338) (xy 40.985694 -18.754852) (xy 41.849294 -18.754852)
			(xy 41.876544 -18.755395) (xy 41.93049 -18.76315) (xy 41.982783 -18.778504) (xy 42.032359 -18.801144)
			(xy 42.078208 -18.830609) (xy 42.119397 -18.866299) (xy 42.155088 -18.907487) (xy 42.184553 -18.953336)
			(xy 42.207194 -19.002911) (xy 42.222548 -19.055204) (xy 42.230305 -19.10915) (xy 42.230305 -19.16365)
			(xy 42.230202 -19.164367) (xy 46.191446 -19.164367) (xy 46.191446 -19.109833) (xy 46.199207 -19.055855)
			(xy 46.21457 -19.00353) (xy 46.237224 -18.953924) (xy 46.266706 -18.908047) (xy 46.302417 -18.866832)
			(xy 46.343629 -18.831119) (xy 46.389505 -18.801634) (xy 46.439109 -18.778978) (xy 46.491433 -18.763612)
			(xy 46.545411 -18.755848) (xy 46.572678 -18.75536) (xy 47.436278 -18.75536) (xy 47.463552 -18.755778)
			(xy 47.517544 -18.763538) (xy 47.569882 -18.778903) (xy 47.619501 -18.801561) (xy 47.66539 -18.83105)
			(xy 47.706615 -18.866769) (xy 47.742337 -18.907992) (xy 47.771828 -18.95388) (xy 47.794489 -19.003497)
			(xy 47.809857 -19.055835) (xy 47.81762 -19.109826) (xy 47.81762 -19.163657) (xy 51.814615 -19.163657)
			(xy 51.814615 -19.109143) (xy 51.822374 -19.055184) (xy 51.837733 -19.002878) (xy 51.86038 -18.95329)
			(xy 51.889854 -18.907431) (xy 51.925554 -18.866233) (xy 51.966755 -18.830536) (xy 52.012617 -18.801065)
			(xy 52.062206 -18.778422) (xy 52.114513 -18.763067) (xy 52.168473 -18.755313) (xy 52.19573 -18.754852)
			(xy 53.05933 -18.754852) (xy 53.086577 -18.75542) (xy 53.140516 -18.763179) (xy 53.192801 -18.778535)
			(xy 53.24237 -18.801176) (xy 53.288211 -18.83064) (xy 53.329394 -18.866328) (xy 53.365078 -18.907513)
			(xy 53.394538 -18.953357) (xy 53.417175 -19.002927) (xy 53.432527 -19.055214) (xy 53.440282 -19.109153)
			(xy 53.440282 -19.163647) (xy 53.440281 -19.163657) (xy 57.402615 -19.163657) (xy 57.402615 -19.109143)
			(xy 57.410374 -19.055184) (xy 57.425733 -19.002878) (xy 57.44838 -18.95329) (xy 57.477854 -18.907431)
			(xy 57.513554 -18.866233) (xy 57.554755 -18.830536) (xy 57.600617 -18.801065) (xy 57.650206 -18.778422)
			(xy 57.702513 -18.763067) (xy 57.756473 -18.755313) (xy 57.78373 -18.754852) (xy 58.64733 -18.754852)
			(xy 58.674577 -18.75542) (xy 58.728516 -18.763179) (xy 58.780801 -18.778535) (xy 58.83037 -18.801176)
			(xy 58.876211 -18.83064) (xy 58.917394 -18.866328) (xy 58.953078 -18.907513) (xy 58.982538 -18.953357)
			(xy 59.005175 -19.002927) (xy 59.020527 -19.055214) (xy 59.028282 -19.109153) (xy 59.028282 -19.163647)
			(xy 59.020527 -19.217586) (xy 59.005175 -19.269873) (xy 58.982538 -19.319443) (xy 58.953078 -19.365287)
			(xy 58.917394 -19.406472) (xy 58.876211 -19.44216) (xy 58.83037 -19.471624) (xy 58.780801 -19.494265)
			(xy 58.728516 -19.509621) (xy 58.674577 -19.51738) (xy 58.64733 -19.517868) (xy 57.78373 -19.517868)
			(xy 57.756473 -19.517487) (xy 57.702513 -19.509733) (xy 57.650206 -19.494378) (xy 57.600617 -19.471735)
			(xy 57.554755 -19.442264) (xy 57.513554 -19.406567) (xy 57.477854 -19.365369) (xy 57.44838 -19.31951)
			(xy 57.425733 -19.269922) (xy 57.410374 -19.217616) (xy 57.402615 -19.163657) (xy 53.440281 -19.163657)
			(xy 53.432527 -19.217586) (xy 53.417175 -19.269873) (xy 53.394538 -19.319443) (xy 53.365078 -19.365287)
			(xy 53.329394 -19.406472) (xy 53.288211 -19.44216) (xy 53.24237 -19.471624) (xy 53.192801 -19.494265)
			(xy 53.140516 -19.509621) (xy 53.086577 -19.51738) (xy 53.05933 -19.517868) (xy 52.19573 -19.517868)
			(xy 52.168473 -19.517487) (xy 52.114513 -19.509733) (xy 52.062206 -19.494378) (xy 52.012617 -19.471735)
			(xy 51.966755 -19.442264) (xy 51.925554 -19.406567) (xy 51.889854 -19.365369) (xy 51.86038 -19.31951)
			(xy 51.837733 -19.269922) (xy 51.822374 -19.217616) (xy 51.814615 -19.163657) (xy 47.81762 -19.163657)
			(xy 47.81762 -19.164374) (xy 47.809857 -19.218365) (xy 47.794489 -19.270703) (xy 47.771828 -19.32032)
			(xy 47.742337 -19.366208) (xy 47.706615 -19.407431) (xy 47.66539 -19.44315) (xy 47.619501 -19.472639)
			(xy 47.569882 -19.495297) (xy 47.517544 -19.510662) (xy 47.463552 -19.518422) (xy 47.436278 -19.518884)
			(xy 46.572678 -19.518884) (xy 46.545411 -19.518352) (xy 46.491433 -19.510588) (xy 46.439109 -19.495222)
			(xy 46.389505 -19.472566) (xy 46.343629 -19.443081) (xy 46.302417 -19.407368) (xy 46.266706 -19.366153)
			(xy 46.237224 -19.320276) (xy 46.21457 -19.27067) (xy 46.199207 -19.218345) (xy 46.191446 -19.164367)
			(xy 42.230202 -19.164367) (xy 42.222548 -19.217596) (xy 42.207194 -19.269889) (xy 42.184553 -19.319464)
			(xy 42.155088 -19.365313) (xy 42.119397 -19.406501) (xy 42.078208 -19.442191) (xy 42.032359 -19.471656)
			(xy 41.982783 -19.494296) (xy 41.93049 -19.50965) (xy 41.876544 -19.517405) (xy 41.849294 -19.517868)
			(xy 40.985694 -19.517868) (xy 40.95844 -19.517462) (xy 40.904487 -19.509704) (xy 40.852188 -19.494346)
			(xy 40.802606 -19.471703) (xy 40.756752 -19.442233) (xy 40.715558 -19.406538) (xy 40.679863 -19.365343)
			(xy 40.650395 -19.319488) (xy 40.627751 -19.269906) (xy 40.612395 -19.217607) (xy 40.604638 -19.163654)
			(xy 36.336505 -19.163654) (xy 36.328748 -19.217598) (xy 36.313392 -19.269892) (xy 36.290751 -19.319469)
			(xy 36.261284 -19.365318) (xy 36.225591 -19.406507) (xy 36.1844 -19.442197) (xy 36.138549 -19.471661)
			(xy 36.088972 -19.4943) (xy 36.036677 -19.509653) (xy 35.982729 -19.517406) (xy 35.955478 -19.517868)
			(xy 35.091878 -19.517868) (xy 35.064625 -19.517461) (xy 35.010674 -19.509701) (xy 34.958376 -19.494342)
			(xy 34.908797 -19.471697) (xy 34.862944 -19.442227) (xy 34.821752 -19.406532) (xy 34.786059 -19.365338)
			(xy 34.756592 -19.319484) (xy 34.73395 -19.269903) (xy 34.718595 -19.217605) (xy 34.710838 -19.163653)
			(xy 30.748505 -19.163653) (xy 30.740748 -19.217598) (xy 30.725392 -19.269892) (xy 30.702751 -19.319469)
			(xy 30.673284 -19.365318) (xy 30.637591 -19.406507) (xy 30.5964 -19.442197) (xy 30.550549 -19.471661)
			(xy 30.500972 -19.4943) (xy 30.448677 -19.509653) (xy 30.394729 -19.517406) (xy 30.367478 -19.517868)
			(xy 29.503878 -19.517868) (xy 29.476625 -19.517461) (xy 29.422674 -19.509701) (xy 29.370376 -19.494342)
			(xy 29.320797 -19.471697) (xy 29.274944 -19.442227) (xy 29.233752 -19.406532) (xy 29.198059 -19.365338)
			(xy 29.168592 -19.319484) (xy 29.14595 -19.269903) (xy 29.130595 -19.217605) (xy 29.122838 -19.163653)
			(xy 25.160505 -19.163653) (xy 25.152748 -19.217598) (xy 25.137392 -19.269892) (xy 25.114751 -19.319469)
			(xy 25.085284 -19.365318) (xy 25.049591 -19.406507) (xy 25.0084 -19.442197) (xy 24.962549 -19.471661)
			(xy 24.912972 -19.4943) (xy 24.860677 -19.509653) (xy 24.806729 -19.517406) (xy 24.779478 -19.517868)
			(xy 23.915878 -19.517868) (xy 23.888625 -19.517461) (xy 23.834674 -19.509701) (xy 23.782376 -19.494342)
			(xy 23.732797 -19.471697) (xy 23.686944 -19.442227) (xy 23.645752 -19.406532) (xy 23.610059 -19.365338)
			(xy 23.580592 -19.319484) (xy 23.55795 -19.269903) (xy 23.542595 -19.217605) (xy 23.534838 -19.163653)
			(xy 19.571738 -19.163653) (xy 19.571738 -19.164389) (xy 19.563976 -19.218373) (xy 19.548611 -19.270703)
			(xy 19.525954 -19.320313) (xy 19.496469 -19.366194) (xy 19.460753 -19.407412) (xy 19.419536 -19.443127)
			(xy 19.373655 -19.472613) (xy 19.324045 -19.49527) (xy 19.271715 -19.510635) (xy 19.217731 -19.518397)
			(xy 19.190462 -19.518884) (xy 18.326862 -19.518884) (xy 18.299591 -19.518417) (xy 18.245604 -19.510655)
			(xy 18.193272 -19.495289) (xy 18.143658 -19.472631) (xy 18.097775 -19.443144) (xy 18.056555 -19.407427)
			(xy 18.020837 -19.366207) (xy 17.99135 -19.320323) (xy 17.968692 -19.27071) (xy 17.953326 -19.218378)
			(xy 17.945563 -19.164391) (xy 0.509016 -19.164391) (xy 0.509016 -20.327366) (xy 65.88506 -20.327366)
			(xy 65.885484 -20.289077) (xy 65.892086 -20.212783) (xy 65.90523 -20.13734) (xy 65.924819 -20.063309)
			(xy 65.937384 -20.027138) (xy 65.940051 -20.018705) (xy 65.94004 -20.001031) (xy 65.937384 -19.992594)
			(xy 65.924856 -19.956411) (xy 65.905279 -19.88238) (xy 65.892127 -19.806942) (xy 65.885498 -19.730654)
			(xy 65.88506 -19.692366) (xy 65.885582 -19.650174) (xy 65.893576 -19.56617) (xy 65.909488 -19.483301)
			(xy 65.933176 -19.402311) (xy 65.964427 -19.323927) (xy 66.00296 -19.248856) (xy 66.048429 -19.17777)
			(xy 66.074036 -19.144234) (xy 66.079883 -19.13601) (xy 66.085128 -19.116537) (xy 66.082515 -19.096539)
			(xy 66.077846 -19.087592) (xy 66.058798 -19.053767) (xy 66.026006 -18.983399) (xy 65.999468 -18.910441)
			(xy 65.979384 -18.83545) (xy 65.965909 -18.758994) (xy 65.959144 -18.681655) (xy 65.95872 -18.642838)
			(xy 65.95872 -18.642584) (xy 65.959137 -18.60148) (xy 65.966724 -18.519622) (xy 65.981831 -18.438814)
			(xy 66.00433 -18.359744) (xy 66.034029 -18.283087) (xy 66.070674 -18.209498) (xy 66.113953 -18.139604)
			(xy 66.163496 -18.074001) (xy 66.218881 -18.01325) (xy 66.279635 -17.957868) (xy 66.34524 -17.908328)
			(xy 66.415137 -17.865053) (xy 66.488728 -17.828411) (xy 66.565386 -17.798716) (xy 66.644456 -17.776221)
			(xy 66.725266 -17.761118) (xy 66.807124 -17.753535) (xy 66.848228 -17.753076) (xy 66.889911 -17.753577)
			(xy 66.972911 -17.761363) (xy 67.054819 -17.776882) (xy 67.134915 -17.799999) (xy 67.212496 -17.830511)
			(xy 67.286881 -17.868149) (xy 67.357417 -17.912584) (xy 67.423485 -17.963425) (xy 67.484504 -18.020226)
			(xy 67.53994 -18.082488) (xy 67.565016 -18.115788) (xy 67.56527 -18.116042) (xy 67.570757 -18.122776)
			(xy 67.585223 -18.132372) (xy 67.602063 -18.136587) (xy 67.610736 -18.136108) (xy 67.697858 -18.127726)
			(xy 67.706567 -18.126584) (xy 67.722478 -18.119178) (xy 67.734922 -18.1068) (xy 67.739006 -18.099024)
			(xy 67.739006 -18.098516) (xy 67.757258 -18.060702) (xy 67.799884 -17.988356) (xy 67.849141 -17.920351)
			(xy 67.90459 -17.857291) (xy 67.965736 -17.79974) (xy 68.032035 -17.748209) (xy 68.102897 -17.703158)
			(xy 68.17769 -17.664987) (xy 68.255748 -17.634037) (xy 68.336377 -17.610583) (xy 68.418857 -17.594835)
			(xy 68.502455 -17.586933) (xy 68.54444 -17.586452) (xy 68.5868 -17.58693) (xy 68.671136 -17.594986)
			(xy 68.754325 -17.611023) (xy 68.835612 -17.634895) (xy 68.914262 -17.666384) (xy 68.989563 -17.705208)
			(xy 69.060833 -17.751013) (xy 69.127426 -17.803385) (xy 69.18874 -17.86185) (xy 69.244218 -17.925878)
			(xy 69.293359 -17.99489) (xy 69.335718 -18.068261) (xy 69.370911 -18.145325) (xy 69.39862 -18.225386)
			(xy 69.401856 -18.238724) (xy 79.0321 -18.238724) (xy 79.032651 -18.193954) (xy 79.041664 -18.104869)
			(xy 79.059573 -18.017137) (xy 79.086195 -17.931647) (xy 79.10322 -17.890236) (xy 79.106772 -17.880641)
			(xy 79.106781 -17.860202) (xy 79.10322 -17.850612) (xy 79.086184 -17.809205) (xy 79.059551 -17.723717)
			(xy 79.041646 -17.635983) (xy 79.032653 -17.546895) (xy 79.0321 -17.502124) (xy 79.032604 -17.459763)
			(xy 79.040657 -17.375426) (xy 79.056691 -17.292236) (xy 79.080559 -17.210946) (xy 79.112047 -17.132294)
			(xy 79.150869 -17.056991) (xy 79.196672 -16.985719) (xy 79.249043 -16.919123) (xy 79.307508 -16.857808)
			(xy 79.371536 -16.802327) (xy 79.440548 -16.753184) (xy 79.513918 -16.710824) (xy 79.590983 -16.675629)
			(xy 79.671045 -16.64792) (xy 79.753378 -16.627946) (xy 79.837237 -16.615889) (xy 79.921862 -16.611858)
			(xy 80.006487 -16.615889) (xy 80.090346 -16.627946) (xy 80.172679 -16.64792) (xy 80.252741 -16.675629)
			(xy 80.329806 -16.710824) (xy 80.403176 -16.753184) (xy 80.472188 -16.802327) (xy 80.536216 -16.857808)
			(xy 80.594681 -16.919123) (xy 80.647052 -16.985719) (xy 80.692855 -17.056991) (xy 80.731677 -17.132294)
			(xy 80.757813 -17.197578) (xy 131.851908 -17.197578) (xy 131.851908 -15.798038) (xy 131.852392 -15.78592)
			(xy 131.85987 -15.762868) (xy 131.874106 -15.743255) (xy 131.893707 -15.729001) (xy 131.916753 -15.721502)
			(xy 131.92887 -15.721076) (xy 132.965444 -15.721076) (xy 132.977519 -15.721526) (xy 133.000485 -15.728999)
			(xy 133.02002 -15.7432) (xy 133.034214 -15.76274) (xy 133.041678 -15.785709) (xy 133.042152 -15.797784)
			(xy 133.042152 -17.197578) (xy 133.042122 -17.19834) (xy 135.55472 -17.19834) (xy 135.55472 -15.90294)
			(xy 135.555147 -15.890857) (xy 135.562607 -15.86787) (xy 135.576808 -15.848317) (xy 135.59636 -15.834113)
			(xy 135.619345 -15.826649) (xy 135.631428 -15.826232) (xy 136.459976 -15.826232) (xy 136.472061 -15.826634)
			(xy 136.49505 -15.8341) (xy 136.514604 -15.848307) (xy 136.528808 -15.867864) (xy 136.536269 -15.890854)
			(xy 136.536684 -15.90294) (xy 136.536684 -17.19834) (xy 137.354564 -17.19834) (xy 137.354564 -15.90294)
			(xy 137.355093 -15.890895) (xy 137.362511 -15.867977) (xy 137.376635 -15.848464) (xy 137.396089 -15.834258)
			(xy 137.418975 -15.826744) (xy 137.431018 -15.826232) (xy 138.260074 -15.826232) (xy 138.272161 -15.826729)
			(xy 138.29516 -15.834178) (xy 138.314739 -15.848357) (xy 138.328991 -15.867884) (xy 138.336525 -15.890854)
			(xy 138.337036 -15.90294) (xy 138.337036 -17.19834) (xy 139.154408 -17.19834) (xy 139.154408 -15.90294)
			(xy 139.154894 -15.890891) (xy 139.162317 -15.867965) (xy 139.17645 -15.848448) (xy 139.195916 -15.834244)
			(xy 139.218815 -15.826738) (xy 139.230862 -15.826232) (xy 140.059918 -15.826232) (xy 140.072008 -15.826692)
			(xy 140.095008 -15.834152) (xy 140.114587 -15.848341) (xy 140.128837 -15.867875) (xy 140.13637 -15.890852)
			(xy 140.13688 -15.90294) (xy 140.13688 -17.19834) (xy 140.95476 -17.19834) (xy 140.95476 -15.90294)
			(xy 140.955246 -15.890863) (xy 140.962699 -15.867887) (xy 140.976887 -15.848338) (xy 140.996422 -15.834132)
			(xy 141.019391 -15.826658) (xy 141.031468 -15.826232) (xy 141.860016 -15.826232) (xy 141.872104 -15.8266)
			(xy 141.895094 -15.834076) (xy 141.914647 -15.848293) (xy 141.928849 -15.867857) (xy 141.936309 -15.890852)
			(xy 141.936724 -15.90294) (xy 141.936724 -16.416528) (xy 191.571372 -16.416528) (xy 191.571784 -16.378238)
			(xy 191.57839 -16.301944) (xy 191.591537 -16.226502) (xy 191.611129 -16.152471) (xy 191.623696 -16.1163)
			(xy 191.626331 -16.10786) (xy 191.62634 -16.090193) (xy 191.623696 -16.081756) (xy 191.611158 -16.045577)
			(xy 191.591583 -15.971544) (xy 191.578434 -15.896105) (xy 191.571809 -15.819816) (xy 191.571372 -15.781528)
			(xy 191.571879 -15.740418) (xy 191.579464 -15.65855) (xy 191.594572 -15.577731) (xy 191.617074 -15.498651)
			(xy 191.646778 -15.421985) (xy 191.68343 -15.348387) (xy 191.726718 -15.278486) (xy 191.776272 -15.212878)
			(xy 191.831669 -15.152124) (xy 191.892437 -15.096741) (xy 191.958056 -15.047202) (xy 192.027967 -15.00393)
			(xy 192.101573 -14.967295) (xy 192.178246 -14.937609) (xy 192.257331 -14.915125) (xy 192.338154 -14.900036)
			(xy 192.420024 -14.89247) (xy 192.461134 -14.89202) (xy 192.499451 -14.892376) (xy 192.575804 -14.898912)
			(xy 192.651311 -14.912) (xy 192.72541 -14.931543) (xy 192.761616 -14.94409) (xy 192.769932 -14.946676)
			(xy 192.787336 -14.946676) (xy 192.795652 -14.94409) (xy 192.831863 -14.931562) (xy 192.905965 -14.912041)
			(xy 192.981469 -14.898959) (xy 193.057819 -14.892413) (xy 193.096134 -14.89202) (xy 193.134451 -14.892376)
			(xy 193.210804 -14.898912) (xy 193.286311 -14.912) (xy 193.36041 -14.931543) (xy 193.396616 -14.94409)
			(xy 193.404932 -14.946676) (xy 193.422336 -14.946676) (xy 193.430652 -14.94409) (xy 193.466772 -14.93159)
			(xy 193.540685 -14.912102) (xy 193.615997 -14.899021) (xy 193.692153 -14.892442) (xy 193.730372 -14.89202)
			(xy 193.731134 -14.89202) (xy 193.772241 -14.89248) (xy 193.854104 -14.900067) (xy 193.934917 -14.915174)
			(xy 194.013993 -14.937671) (xy 194.090656 -14.967367) (xy 194.164253 -15.004008) (xy 194.234156 -15.047282)
			(xy 194.299769 -15.09682) (xy 194.360532 -15.152199) (xy 194.415928 -15.212948) (xy 194.465484 -15.278547)
			(xy 194.508776 -15.348439) (xy 194.545437 -15.422026) (xy 194.575153 -15.498681) (xy 194.597672 -15.577751)
			(xy 194.6128 -15.658561) (xy 194.620409 -15.740421) (xy 194.620896 -15.781528) (xy 194.620451 -15.819809)
			(xy 194.613795 -15.896082) (xy 194.600605 -15.971499) (xy 194.591178 -16.008604) (xy 194.588893 -16.019174)
			(xy 194.592456 -16.040487) (xy 194.598036 -16.049752) (xy 194.621836 -16.08633) (xy 194.662956 -16.163308)
			(xy 194.696348 -16.24394) (xy 194.721691 -16.327453) (xy 194.738741 -16.413043) (xy 194.747336 -16.499892)
			(xy 194.747896 -16.543528) (xy 194.747474 -16.584639) (xy 194.739884 -16.666511) (xy 194.72477 -16.747333)
			(xy 194.702263 -16.826416) (xy 194.672553 -16.903083) (xy 194.635895 -16.976682) (xy 194.592602 -17.046584)
			(xy 194.543042 -17.112192) (xy 194.487639 -17.172947) (xy 194.426866 -17.22833) (xy 194.361241 -17.277868)
			(xy 194.291325 -17.321138) (xy 194.217714 -17.357772) (xy 194.141037 -17.387456) (xy 194.061947 -17.409938)
			(xy 193.98112 -17.425024) (xy 193.899246 -17.432588) (xy 193.858134 -17.433036) (xy 193.814503 -17.432505)
			(xy 193.727659 -17.42397) (xy 193.642069 -17.40697) (xy 193.558556 -17.381667) (xy 193.477923 -17.348306)
			(xy 193.400945 -17.307207) (xy 193.364358 -17.28343) (xy 193.355108 -17.277824) (xy 193.333785 -17.274289)
			(xy 193.32321 -17.276572) (xy 193.286097 -17.285942) (xy 193.210677 -17.299046) (xy 193.134409 -17.305624)
			(xy 193.096134 -17.306036) (xy 193.057818 -17.305656) (xy 192.981465 -17.299127) (xy 192.905958 -17.286046)
			(xy 192.831859 -17.26651) (xy 192.795652 -17.253966) (xy 192.787336 -17.25138) (xy 192.769932 -17.25138)
			(xy 192.761616 -17.253966) (xy 192.725489 -17.266445) (xy 192.651578 -17.285939) (xy 192.576269 -17.299026)
			(xy 192.500115 -17.305611) (xy 192.461896 -17.306036) (xy 192.461134 -17.306036) (xy 192.420027 -17.305555)
			(xy 192.338163 -17.297973) (xy 192.257348 -17.282872) (xy 192.178271 -17.260379) (xy 192.101606 -17.230687)
			(xy 192.028008 -17.194048) (xy 191.958103 -17.150776) (xy 191.892489 -17.10124) (xy 191.831724 -17.045861)
			(xy 191.776328 -16.985113) (xy 191.726772 -16.919513) (xy 191.683479 -16.849621) (xy 191.646819 -16.776033)
			(xy 191.617104 -16.699377) (xy 191.594588 -16.620307) (xy 191.579463 -16.539496) (xy 191.571857 -16.457635)
			(xy 191.571372 -16.416528) (xy 141.936724 -16.416528) (xy 141.936724 -17.19834) (xy 141.93627 -17.210415)
			(xy 141.928799 -17.233381) (xy 141.914599 -17.252916) (xy 141.895059 -17.26711) (xy 141.872091 -17.274574)
			(xy 141.860016 -17.275048) (xy 141.031468 -17.275048) (xy 141.019396 -17.274564) (xy 140.996434 -17.267097)
			(xy 140.976901 -17.252905) (xy 140.962706 -17.233373) (xy 140.955237 -17.210412) (xy 140.95476 -17.19834)
			(xy 140.13688 -17.19834) (xy 140.136474 -17.210394) (xy 140.129028 -17.233325) (xy 140.114874 -17.252841)
			(xy 140.095391 -17.267043) (xy 140.072479 -17.274544) (xy 140.060426 -17.275048) (xy 139.23137 -17.275048)
			(xy 139.219278 -17.274618) (xy 139.196274 -17.267152) (xy 139.176694 -17.252956) (xy 139.162444 -17.233414)
			(xy 139.154915 -17.210431) (xy 139.154408 -17.19834) (xy 138.337036 -17.19834) (xy 138.336575 -17.210389)
			(xy 138.329136 -17.23331) (xy 138.314994 -17.252822) (xy 138.295526 -17.267025) (xy 138.272629 -17.274537)
			(xy 138.260582 -17.275048) (xy 137.431526 -17.275048) (xy 137.419437 -17.27457) (xy 137.396435 -17.267119)
			(xy 137.376853 -17.252936) (xy 137.362602 -17.233404) (xy 137.355072 -17.210428) (xy 137.354564 -17.19834)
			(xy 136.536684 -17.19834) (xy 136.53627 -17.210419) (xy 136.528793 -17.233392) (xy 136.514585 -17.25293)
			(xy 136.495034 -17.267122) (xy 136.472055 -17.27458) (xy 136.459976 -17.275048) (xy 135.631428 -17.275048)
			(xy 135.619359 -17.274513) (xy 135.596399 -17.267063) (xy 135.576865 -17.252883) (xy 135.562668 -17.233362)
			(xy 135.555198 -17.210409) (xy 135.55472 -17.19834) (xy 133.042122 -17.19834) (xy 133.041674 -17.209667)
			(xy 133.034222 -17.232668) (xy 133.020039 -17.252249) (xy 133.000507 -17.2665) (xy 132.977532 -17.274031)
			(xy 132.965444 -17.27454) (xy 131.92887 -17.27454) (xy 131.916752 -17.274114) (xy 131.893704 -17.266615)
			(xy 131.874101 -17.252362) (xy 131.859861 -17.23275) (xy 131.852378 -17.209697) (xy 131.851908 -17.197578)
			(xy 80.757813 -17.197578) (xy 80.763165 -17.210946) (xy 80.787033 -17.292236) (xy 80.803067 -17.375426)
			(xy 80.81112 -17.459763) (xy 80.811624 -17.502124) (xy 80.811054 -17.546893) (xy 80.802046 -17.635978)
			(xy 80.784143 -17.723709) (xy 80.757526 -17.809201) (xy 80.740504 -17.850612) (xy 80.736924 -17.860198)
			(xy 80.736933 -17.880645) (xy 80.740504 -17.890236) (xy 80.757551 -17.931638) (xy 80.784182 -18.017129)
			(xy 80.802084 -18.104863) (xy 80.808854 -18.171951) (xy 131.633699 -18.171951) (xy 131.633699 -18.117449)
			(xy 131.641456 -18.063503) (xy 131.656811 -18.011209) (xy 131.679453 -17.961633) (xy 131.708919 -17.915784)
			(xy 131.744611 -17.874596) (xy 131.785802 -17.838906) (xy 131.831653 -17.809442) (xy 131.88123 -17.786804)
			(xy 131.933524 -17.771451) (xy 131.987471 -17.763698) (xy 132.014722 -17.763236) (xy 132.878322 -17.763236)
			(xy 132.905575 -17.763635) (xy 132.959527 -17.771395) (xy 133.011825 -17.786754) (xy 133.061405 -17.809399)
			(xy 133.107258 -17.838869) (xy 133.148451 -17.874565) (xy 133.184144 -17.915759) (xy 133.213611 -17.961614)
			(xy 133.236254 -18.011196) (xy 133.251609 -18.063495) (xy 133.259366 -18.117447) (xy 133.259366 -18.171946)
			(xy 137.033822 -18.171946) (xy 137.033822 -18.117454) (xy 137.041577 -18.063516) (xy 137.056928 -18.01123)
			(xy 137.079564 -17.961661) (xy 137.109023 -17.915818) (xy 137.144706 -17.874633) (xy 137.185887 -17.838946)
			(xy 137.231728 -17.809482) (xy 137.281294 -17.786841) (xy 137.333578 -17.771485) (xy 137.387516 -17.763725)
			(xy 137.414762 -17.763236) (xy 138.278362 -17.763236) (xy 138.30562 -17.763608) (xy 138.359581 -17.771362)
			(xy 138.41189 -17.786716) (xy 138.46148 -17.809359) (xy 138.507344 -17.83883) (xy 138.548546 -17.874528)
			(xy 138.584247 -17.915726) (xy 138.613722 -17.961586) (xy 138.63637 -18.011175) (xy 138.65173 -18.063482)
			(xy 138.659489 -18.117442) (xy 138.659489 -18.17195) (xy 140.633699 -18.17195) (xy 140.633699 -18.11745)
			(xy 140.641455 -18.063505) (xy 140.65681 -18.011213) (xy 140.67945 -17.961638) (xy 140.708915 -17.91579)
			(xy 140.744605 -17.874602) (xy 140.785793 -17.838913) (xy 140.831642 -17.809448) (xy 140.881217 -17.786808)
			(xy 140.933509 -17.771455) (xy 140.987454 -17.763699) (xy 141.014704 -17.763236) (xy 141.878304 -17.763236)
			(xy 141.905558 -17.763634) (xy 141.959512 -17.771392) (xy 142.011812 -17.786749) (xy 142.061394 -17.809393)
			(xy 142.10725 -17.838863) (xy 142.148444 -17.874559) (xy 142.184139 -17.915754) (xy 142.213609 -17.961609)
			(xy 142.236252 -18.011192) (xy 142.251609 -18.063492) (xy 142.259366 -18.117446) (xy 142.259366 -18.171954)
			(xy 142.251609 -18.225908) (xy 142.236252 -18.278208) (xy 142.213609 -18.327791) (xy 142.184139 -18.373646)
			(xy 142.148444 -18.414841) (xy 142.10725 -18.450537) (xy 142.061394 -18.480007) (xy 142.011812 -18.502651)
			(xy 141.959512 -18.518008) (xy 141.905558 -18.525766) (xy 141.878304 -18.526252) (xy 141.014704 -18.526252)
			(xy 140.987454 -18.525701) (xy 140.933509 -18.517945) (xy 140.881217 -18.502592) (xy 140.831642 -18.479952)
			(xy 140.785793 -18.450487) (xy 140.744605 -18.414798) (xy 140.708915 -18.37361) (xy 140.67945 -18.327762)
			(xy 140.65681 -18.278187) (xy 140.641455 -18.225895) (xy 140.633699 -18.17195) (xy 138.659489 -18.17195)
			(xy 138.659489 -18.171958) (xy 138.65173 -18.225918) (xy 138.63637 -18.278225) (xy 138.613722 -18.327814)
			(xy 138.584247 -18.373674) (xy 138.548546 -18.414872) (xy 138.507344 -18.45057) (xy 138.46148 -18.480041)
			(xy 138.41189 -18.502684) (xy 138.359581 -18.518038) (xy 138.30562 -18.525792) (xy 138.278362 -18.526252)
			(xy 137.414762 -18.526252) (xy 137.387516 -18.525675) (xy 137.333578 -18.517915) (xy 137.281294 -18.502559)
			(xy 137.231728 -18.479918) (xy 137.185887 -18.450454) (xy 137.144706 -18.414767) (xy 137.109023 -18.373582)
			(xy 137.079564 -18.327739) (xy 137.056928 -18.27817) (xy 137.041577 -18.225884) (xy 137.033822 -18.171946)
			(xy 133.259366 -18.171946) (xy 133.259366 -18.171953) (xy 133.251609 -18.225905) (xy 133.236254 -18.278204)
			(xy 133.213611 -18.327786) (xy 133.184144 -18.373641) (xy 133.148451 -18.414835) (xy 133.107258 -18.450531)
			(xy 133.061405 -18.480001) (xy 133.011825 -18.502646) (xy 132.959527 -18.518005) (xy 132.905575 -18.525765)
			(xy 132.878322 -18.526252) (xy 132.014722 -18.526252) (xy 131.987471 -18.525702) (xy 131.933524 -18.517949)
			(xy 131.88123 -18.502596) (xy 131.831653 -18.479958) (xy 131.785802 -18.450494) (xy 131.744611 -18.414804)
			(xy 131.708919 -18.373616) (xy 131.679453 -18.327767) (xy 131.656811 -18.278191) (xy 131.641456 -18.225897)
			(xy 131.633699 -18.171951) (xy 80.808854 -18.171951) (xy 80.811074 -18.193953) (xy 80.811624 -18.238724)
			(xy 80.81112 -18.281085) (xy 80.803067 -18.365422) (xy 80.787033 -18.448612) (xy 80.763165 -18.529902)
			(xy 80.731677 -18.608554) (xy 80.692855 -18.683857) (xy 80.647052 -18.755129) (xy 80.594681 -18.821725)
			(xy 80.536216 -18.88304) (xy 80.472188 -18.938521) (xy 80.403176 -18.987664) (xy 80.329806 -19.030024)
			(xy 80.252741 -19.065219) (xy 80.172679 -19.092928) (xy 80.090346 -19.112902) (xy 80.006487 -19.124959)
			(xy 79.921862 -19.128991) (xy 79.837237 -19.124959) (xy 79.753378 -19.112902) (xy 79.671045 -19.092928)
			(xy 79.590983 -19.065219) (xy 79.513918 -19.030024) (xy 79.440548 -18.987664) (xy 79.371536 -18.938521)
			(xy 79.307508 -18.88304) (xy 79.249043 -18.821725) (xy 79.196672 -18.755129) (xy 79.150869 -18.683857)
			(xy 79.112047 -18.608554) (xy 79.080559 -18.529902) (xy 79.056691 -18.448612) (xy 79.040657 -18.365422)
			(xy 79.032604 -18.281085) (xy 79.0321 -18.238724) (xy 69.401856 -18.238724) (xy 69.418593 -18.307718)
			(xy 69.430649 -18.391576) (xy 69.434681 -18.4762) (xy 69.430649 -18.560824) (xy 69.418593 -18.644682)
			(xy 69.39862 -18.727014) (xy 69.370911 -18.807075) (xy 69.335718 -18.884139) (xy 69.293359 -18.95751)
			(xy 69.244218 -19.026522) (xy 69.18874 -19.09055) (xy 69.127426 -19.149015) (xy 69.060833 -19.201387)
			(xy 68.989563 -19.247192) (xy 68.914262 -19.286016) (xy 68.835612 -19.317505) (xy 68.754325 -19.341377)
			(xy 68.671136 -19.357414) (xy 68.5868 -19.36547) (xy 68.54444 -19.365976) (xy 68.502753 -19.365468)
			(xy 68.419745 -19.357644) (xy 68.337834 -19.342089) (xy 68.257737 -19.31894) (xy 68.180157 -19.288398)
			(xy 68.105774 -19.250734) (xy 68.035242 -19.206275) (xy 67.969177 -19.155414) (xy 67.90816 -19.098595)
			(xy 67.852727 -19.036317) (xy 67.827652 -19.00301) (xy 67.827398 -19.002756) (xy 67.821873 -18.996058)
			(xy 67.807425 -18.986454) (xy 67.790601 -18.982223) (xy 67.781932 -18.98269) (xy 67.69481 -18.991072)
			(xy 67.686098 -18.992195) (xy 67.670187 -18.999611) (xy 67.657745 -19.011995) (xy 67.653662 -19.019774)
			(xy 67.653662 -19.020282) (xy 67.63179 -19.065383) (xy 67.579339 -19.150805) (xy 67.549014 -19.190716)
			(xy 67.543272 -19.198996) (xy 67.538026 -19.218428) (xy 67.540615 -19.238388) (xy 67.545204 -19.247358)
			(xy 67.564269 -19.281203) (xy 67.597117 -19.351604) (xy 67.623706 -19.424598) (xy 67.643834 -19.499632)
			(xy 67.657349 -19.576134) (xy 67.664146 -19.653523) (xy 67.664584 -19.692366) (xy 67.664167 -19.730656)
			(xy 67.657563 -19.806949) (xy 67.644416 -19.882392) (xy 67.624826 -19.956423) (xy 67.61226 -19.992594)
			(xy 67.609626 -20.001035) (xy 67.609615 -20.018702) (xy 67.61226 -20.027138) (xy 67.624799 -20.063317)
			(xy 67.644373 -20.13735) (xy 67.653158 -20.187755) (xy 138.765443 -20.187755) (xy 138.765443 -20.133245)
			(xy 138.773201 -20.079289) (xy 138.788559 -20.026987) (xy 138.811205 -19.977403) (xy 138.840677 -19.931547)
			(xy 138.876376 -19.890352) (xy 138.917574 -19.854657) (xy 138.963433 -19.825189) (xy 139.013019 -19.802547)
			(xy 139.065322 -19.787194) (xy 139.119279 -19.779441) (xy 139.146534 -19.77898) (xy 140.137134 -19.77898)
			(xy 140.164383 -19.779493) (xy 140.218325 -19.787253) (xy 140.270614 -19.80261) (xy 140.320185 -19.825253)
			(xy 140.36603 -19.854719) (xy 140.407215 -19.890409) (xy 140.442901 -19.931597) (xy 140.472364 -19.977445)
			(xy 140.495002 -20.027018) (xy 140.510354 -20.079308) (xy 140.51811 -20.133251) (xy 140.51811 -20.187749)
			(xy 140.510354 -20.241692) (xy 140.495002 -20.293982) (xy 140.472364 -20.343555) (xy 140.442901 -20.389403)
			(xy 140.423588 -20.411694) (xy 159.806132 -20.411694) (xy 159.806132 -19.725894) (xy 159.806607 -19.71378)
			(xy 159.814095 -19.690737) (xy 159.828336 -19.671136) (xy 159.847937 -19.656895) (xy 159.87098 -19.649407)
			(xy 159.883094 -19.648932) (xy 160.077658 -19.648932) (xy 160.088784 -19.649341) (xy 160.110081 -19.655804)
			(xy 160.119568 -19.661632) (xy 160.414462 -19.854164) (xy 160.423849 -19.859867) (xy 160.444887 -19.86614)
			(xy 160.466841 -19.86614) (xy 160.487879 -19.859867) (xy 160.497266 -19.854164) (xy 160.79089 -19.661632)
			(xy 160.800394 -19.65584) (xy 160.82168 -19.64938) (xy 160.8328 -19.648932) (xy 161.028634 -19.648932)
			(xy 161.04075 -19.649383) (xy 161.063793 -19.656878) (xy 161.083394 -19.671126) (xy 161.097634 -19.690732)
			(xy 161.105122 -19.713778) (xy 161.105596 -19.725894) (xy 161.105596 -19.942048) (xy 175.988472 -19.942048)
			(xy 175.988976 -19.899687) (xy 175.997029 -19.81535) (xy 176.013063 -19.73216) (xy 176.036931 -19.65087)
			(xy 176.068419 -19.572218) (xy 176.107241 -19.496915) (xy 176.153044 -19.425643) (xy 176.205415 -19.359047)
			(xy 176.26388 -19.297732) (xy 176.327908 -19.242251) (xy 176.39692 -19.193108) (xy 176.47029 -19.150748)
			(xy 176.547355 -19.115553) (xy 176.627417 -19.087844) (xy 176.70975 -19.06787) (xy 176.793609 -19.055813)
			(xy 176.878234 -19.051782) (xy 176.962859 -19.055813) (xy 177.046718 -19.06787) (xy 177.129051 -19.087844)
			(xy 177.209113 -19.115553) (xy 177.286178 -19.150748) (xy 177.359548 -19.193108) (xy 177.42856 -19.242251)
			(xy 177.492588 -19.297732) (xy 177.551053 -19.359047) (xy 177.603424 -19.425643) (xy 177.649227 -19.496915)
			(xy 177.688049 -19.572218) (xy 177.719537 -19.65087) (xy 177.743405 -19.73216) (xy 177.759439 -19.81535)
			(xy 177.767492 -19.899687) (xy 177.767996 -19.942048) (xy 177.767398 -19.98792) (xy 177.757891 -20.079169)
			(xy 177.739034 -20.168954) (xy 177.725578 -20.212812) (xy 177.722752 -20.223379) (xy 177.72523 -20.245087)
			(xy 177.730404 -20.254722) (xy 177.750836 -20.289402) (xy 177.786035 -20.361795) (xy 177.814552 -20.437071)
			(xy 177.836153 -20.514616) (xy 177.850661 -20.593794) (xy 177.857958 -20.67396) (xy 177.85842 -20.714208)
			(xy 177.85842 -20.715224) (xy 177.857839 -20.760561) (xy 177.84856 -20.850758) (xy 177.830152 -20.939544)
			(xy 177.817018 -20.98294) (xy 177.81462 -20.991841) (xy 177.815621 -21.010233) (xy 177.823067 -21.02708)
			(xy 177.835994 -21.040201) (xy 177.844196 -21.044408) (xy 177.8824 -21.062505) (xy 177.955518 -21.104946)
			(xy 178.024281 -21.15413) (xy 178.088069 -21.209614) (xy 178.146306 -21.270898) (xy 178.198469 -21.337429)
			(xy 178.244087 -21.408608) (xy 178.282748 -21.483792) (xy 178.314103 -21.562305) (xy 178.337871 -21.643437)
			(xy 178.353837 -21.726458) (xy 178.361856 -21.810619) (xy 178.362356 -21.85289) (xy 178.361892 -21.894005)
			(xy 178.354306 -21.975884) (xy 178.339197 -22.056714) (xy 178.316694 -22.135805) (xy 178.28699 -22.212482)
			(xy 178.250337 -22.286091) (xy 178.207049 -22.356005) (xy 178.157495 -22.421626) (xy 178.102097 -22.482394)
			(xy 178.041329 -22.537792) (xy 177.975708 -22.587347) (xy 177.905795 -22.630635) (xy 177.832186 -22.667288)
			(xy 177.755509 -22.696993) (xy 177.676418 -22.719496) (xy 177.595588 -22.734605) (xy 177.513709 -22.742192)
			(xy 177.472594 -22.742652) (xy 177.429071 -22.742084) (xy 177.34244 -22.73358) (xy 177.257055 -22.716655)
			(xy 177.173731 -22.69147) (xy 177.093266 -22.658267) (xy 177.016429 -22.617362) (xy 176.943956 -22.569146)
			(xy 176.876538 -22.514083) (xy 176.814822 -22.452697) (xy 176.759398 -22.385575) (xy 176.710795 -22.313361)
			(xy 176.669479 -22.236745) (xy 176.652174 -22.196806) (xy 176.647921 -22.187866) (xy 176.633936 -22.17388)
			(xy 176.624996 -22.169628) (xy 176.585068 -22.152314) (xy 176.508472 -22.110985) (xy 176.436278 -22.062372)
			(xy 176.369178 -22.006941) (xy 176.307813 -21.945221) (xy 176.252769 -21.877802) (xy 176.204574 -21.80533)
			(xy 176.163687 -21.728496) (xy 176.1305 -21.648037) (xy 176.105331 -21.564721) (xy 176.088419 -21.479345)
			(xy 176.079928 -21.392725) (xy 176.079404 -21.349208) (xy 176.079404 -21.348446) (xy 176.079814 -21.310226)
			(xy 176.086378 -21.234067) (xy 176.099462 -21.158755) (xy 176.118968 -21.084845) (xy 176.131474 -21.048726)
			(xy 176.134055 -21.040409) (xy 176.134058 -21.023006) (xy 176.131474 -21.01469) (xy 176.118957 -20.978475)
			(xy 176.099434 -20.904375) (xy 176.086349 -20.828871) (xy 176.079799 -20.752523) (xy 176.079404 -20.714208)
			(xy 176.07999 -20.668344) (xy 176.089425 -20.577104) (xy 176.108186 -20.487316) (xy 176.121568 -20.443444)
			(xy 176.124428 -20.432883) (xy 176.121929 -20.411168) (xy 176.116742 -20.401534) (xy 176.096312 -20.366847)
			(xy 176.06107 -20.294464) (xy 176.032509 -20.219194) (xy 176.010862 -20.141652) (xy 175.996306 -20.062472)
			(xy 175.988959 -19.982301) (xy 175.988472 -19.942048) (xy 161.105596 -19.942048) (xy 161.105596 -20.411694)
			(xy 161.105084 -20.423805) (xy 161.097602 -20.446842) (xy 161.083369 -20.466441) (xy 161.063778 -20.480684)
			(xy 161.040745 -20.488177) (xy 161.028634 -20.488656) (xy 160.83407 -20.488656) (xy 160.822945 -20.488238)
			(xy 160.801648 -20.481781) (xy 160.79216 -20.475956) (xy 160.498536 -20.283424) (xy 160.489147 -20.27773)
			(xy 160.468137 -20.271389) (xy 160.446191 -20.271312) (xy 160.425137 -20.277506) (xy 160.415732 -20.28317)
			(xy 160.119568 -20.475956) (xy 160.110072 -20.481762) (xy 160.088779 -20.488213) (xy 160.077658 -20.488656)
			(xy 159.883094 -20.488656) (xy 159.870979 -20.488193) (xy 159.847934 -20.480703) (xy 159.828332 -20.466459)
			(xy 159.814091 -20.446855) (xy 159.806605 -20.423809) (xy 159.806132 -20.411694) (xy 140.423588 -20.411694)
			(xy 140.407215 -20.430591) (xy 140.36603 -20.466281) (xy 140.320185 -20.495747) (xy 140.270614 -20.51839)
			(xy 140.218325 -20.533747) (xy 140.164383 -20.541507) (xy 140.137134 -20.541996) (xy 139.146534 -20.541996)
			(xy 139.119279 -20.541559) (xy 139.065322 -20.533806) (xy 139.013019 -20.518453) (xy 138.963433 -20.495811)
			(xy 138.917574 -20.466343) (xy 138.876376 -20.430648) (xy 138.840677 -20.389453) (xy 138.811205 -20.343597)
			(xy 138.788559 -20.294013) (xy 138.773201 -20.241711) (xy 138.765443 -20.187755) (xy 67.653158 -20.187755)
			(xy 67.657521 -20.212789) (xy 67.664147 -20.289078) (xy 67.664584 -20.327366) (xy 67.66408 -20.369727)
			(xy 67.656027 -20.454064) (xy 67.639993 -20.537254) (xy 67.616125 -20.618544) (xy 67.584637 -20.697196)
			(xy 67.545815 -20.772499) (xy 67.500012 -20.843771) (xy 67.447641 -20.910367) (xy 67.389176 -20.971682)
			(xy 67.325148 -21.027163) (xy 67.256136 -21.076306) (xy 67.182766 -21.118666) (xy 67.105701 -21.153861)
			(xy 67.025639 -21.18157) (xy 66.943306 -21.201544) (xy 66.859447 -21.213601) (xy 66.774822 -21.217633)
			(xy 66.690197 -21.213601) (xy 66.606338 -21.201544) (xy 66.524005 -21.18157) (xy 66.443943 -21.153861)
			(xy 66.366878 -21.118666) (xy 66.293508 -21.076306) (xy 66.224496 -21.027163) (xy 66.160468 -20.971682)
			(xy 66.102003 -20.910367) (xy 66.049632 -20.843771) (xy 66.003829 -20.772499) (xy 65.965007 -20.697196)
			(xy 65.933519 -20.618544) (xy 65.909651 -20.537254) (xy 65.893617 -20.454064) (xy 65.885564 -20.369727)
			(xy 65.88506 -20.327366) (xy 0.509016 -20.327366) (xy 0.509016 -22.309271) (xy 65.993006 -22.309271)
			(xy 65.993006 -22.224549) (xy 66.001059 -22.140212) (xy 66.017093 -22.057022) (xy 66.040961 -21.975732)
			(xy 66.072449 -21.89708) (xy 66.111271 -21.821777) (xy 66.157074 -21.750505) (xy 66.209445 -21.683909)
			(xy 66.26791 -21.622594) (xy 66.331938 -21.567113) (xy 66.40095 -21.51797) (xy 66.47432 -21.47561)
			(xy 66.551385 -21.440415) (xy 66.631447 -21.412706) (xy 66.71378 -21.392732) (xy 66.797639 -21.380675)
			(xy 66.882264 -21.376644) (xy 66.966889 -21.380675) (xy 67.050748 -21.392732) (xy 67.133081 -21.412706)
			(xy 67.213143 -21.440415) (xy 67.290208 -21.47561) (xy 67.363578 -21.51797) (xy 67.43259 -21.567113)
			(xy 67.496618 -21.622594) (xy 67.555083 -21.683909) (xy 67.607454 -21.750505) (xy 67.653257 -21.821777)
			(xy 67.692079 -21.89708) (xy 67.723567 -21.975732) (xy 67.747435 -22.057022) (xy 67.763469 -22.140212)
			(xy 67.771522 -22.224549) (xy 67.772026 -22.26691) (xy 67.771522 -22.309271) (xy 67.763469 -22.393608)
			(xy 67.747435 -22.476798) (xy 67.723567 -22.558088) (xy 67.722853 -22.559872) (xy 114.452596 -22.559872)
			(xy 114.452596 -22.505328) (xy 114.460358 -22.45134) (xy 114.475725 -22.399006) (xy 114.498383 -22.349391)
			(xy 114.527872 -22.303506) (xy 114.563591 -22.262285) (xy 114.604813 -22.226567) (xy 114.650698 -22.19708)
			(xy 114.700313 -22.174422) (xy 114.752648 -22.159056) (xy 114.806636 -22.151295) (xy 114.833908 -22.150832)
			(xy 115.697508 -22.150832) (xy 115.724777 -22.151331) (xy 115.778758 -22.159093) (xy 115.831086 -22.174459)
			(xy 115.880695 -22.197116) (xy 115.926574 -22.226601) (xy 115.96779 -22.262316) (xy 116.003504 -22.303533)
			(xy 116.032988 -22.349412) (xy 116.055644 -22.399021) (xy 116.071008 -22.451349) (xy 116.07877 -22.505331)
			(xy 116.07877 -22.559869) (xy 116.071008 -22.613851) (xy 116.055644 -22.666179) (xy 116.032988 -22.715788)
			(xy 116.003504 -22.761667) (xy 115.96779 -22.802884) (xy 115.926574 -22.838599) (xy 115.880695 -22.868084)
			(xy 115.831086 -22.890741) (xy 115.778758 -22.906107) (xy 115.724777 -22.913869) (xy 115.697508 -22.914356)
			(xy 114.833908 -22.914356) (xy 114.806636 -22.913905) (xy 114.752648 -22.906144) (xy 114.700313 -22.890778)
			(xy 114.650698 -22.86812) (xy 114.604813 -22.838633) (xy 114.563591 -22.802915) (xy 114.527872 -22.761694)
			(xy 114.498383 -22.715809) (xy 114.475725 -22.666194) (xy 114.460358 -22.61386) (xy 114.452596 -22.559872)
			(xy 67.722853 -22.559872) (xy 67.692079 -22.63674) (xy 67.653257 -22.712043) (xy 67.607454 -22.783315)
			(xy 67.555083 -22.849911) (xy 67.496618 -22.911226) (xy 67.43259 -22.966707) (xy 67.363578 -23.01585)
			(xy 67.361784 -23.016886) (xy 136.323137 -23.016886) (xy 136.327046 -22.962479) (xy 136.338661 -22.909183)
			(xy 136.357746 -22.858084) (xy 136.383911 -22.810221) (xy 136.416623 -22.766572) (xy 136.435592 -22.74697)
			(xy 137.046208 -22.1361) (xy 137.06783 -22.115331) (xy 137.116345 -22.080114) (xy 137.169764 -22.052902)
			(xy 137.226775 -22.034363) (xy 137.285982 -22.024951) (xy 137.315956 -22.02434) (xy 137.31621 -22.02434)
			(xy 137.34348 -22.024815) (xy 137.397464 -22.032578) (xy 137.449794 -22.047945) (xy 137.499404 -22.070602)
			(xy 137.545285 -22.10009) (xy 137.586503 -22.135806) (xy 137.622218 -22.177025) (xy 137.651703 -22.222907)
			(xy 137.674359 -22.272518) (xy 137.689724 -22.324848) (xy 137.697486 -22.378832) (xy 137.697972 -22.406102)
			(xy 137.697972 -22.406356) (xy 137.6974 -22.436336) (xy 137.688023 -22.495559) (xy 137.669494 -22.552585)
			(xy 137.64227 -22.606009) (xy 137.60702 -22.654514) (xy 137.586212 -22.676104) (xy 136.975342 -23.28672)
			(xy 136.955728 -23.305677) (xy 136.912079 -23.338389) (xy 136.864216 -23.364554) (xy 136.813117 -23.383639)
			(xy 136.759821 -23.395254) (xy 136.705414 -23.399163) (xy 136.651005 -23.395286) (xy 136.597702 -23.383703)
			(xy 136.546591 -23.364649) (xy 136.498713 -23.338513) (xy 136.455044 -23.305826) (xy 136.416474 -23.267256)
			(xy 136.383787 -23.223587) (xy 136.357651 -23.175709) (xy 136.338597 -23.124598) (xy 136.327014 -23.071295)
			(xy 136.323137 -23.016886) (xy 67.361784 -23.016886) (xy 67.290208 -23.05821) (xy 67.213143 -23.093405)
			(xy 67.133081 -23.121114) (xy 67.050748 -23.141088) (xy 66.966889 -23.153145) (xy 66.882264 -23.157177)
			(xy 66.797639 -23.153145) (xy 66.71378 -23.141088) (xy 66.631447 -23.121114) (xy 66.551385 -23.093405)
			(xy 66.47432 -23.05821) (xy 66.40095 -23.01585) (xy 66.331938 -22.966707) (xy 66.26791 -22.911226)
			(xy 66.209445 -22.849911) (xy 66.157074 -22.783315) (xy 66.111271 -22.712043) (xy 66.072449 -22.63674)
			(xy 66.040961 -22.558088) (xy 66.017093 -22.476798) (xy 66.001059 -22.393608) (xy 65.993006 -22.309271)
			(xy 0.509016 -22.309271) (xy 0.509016 -23.593552) (xy 189.619128 -23.593552) (xy 189.619128 -23.593298)
			(xy 189.619711 -23.54856) (xy 189.628722 -23.459539) (xy 189.646623 -23.371871) (xy 189.673232 -23.286444)
			(xy 189.690248 -23.245064) (xy 189.69384 -23.235481) (xy 189.693822 -23.215031) (xy 189.690248 -23.20544)
			(xy 189.673222 -23.164064) (xy 189.646604 -23.078637) (xy 189.6287 -22.990968) (xy 189.619692 -22.901945)
			(xy 189.619128 -22.857206) (xy 189.619128 -22.856952) (xy 189.619632 -22.814604) (xy 189.627683 -22.73029)
			(xy 189.643712 -22.647124) (xy 189.667573 -22.565857) (xy 189.699052 -22.487227) (xy 189.737863 -22.411946)
			(xy 189.783653 -22.340694) (xy 189.836009 -22.274118) (xy 189.894457 -22.21282) (xy 189.958467 -22.157355)
			(xy 190.027459 -22.108226) (xy 190.100809 -22.065877) (xy 190.177852 -22.030693) (xy 190.257891 -22.002991)
			(xy 190.3402 -21.983023) (xy 190.424035 -21.97097) (xy 190.508636 -21.96694) (xy 190.593237 -21.97097)
			(xy 190.677072 -21.983023) (xy 190.759381 -22.002991) (xy 190.83942 -22.030693) (xy 190.916463 -22.065877)
			(xy 190.989813 -22.108226) (xy 191.058805 -22.157355) (xy 191.122815 -22.21282) (xy 191.181263 -22.274118)
			(xy 191.233619 -22.340694) (xy 191.279409 -22.411946) (xy 191.31822 -22.487227) (xy 191.349699 -22.565857)
			(xy 191.37356 -22.647124) (xy 191.389589 -22.73029) (xy 191.39764 -22.814604) (xy 191.398144 -22.856952)
			(xy 191.398144 -22.857206) (xy 191.397557 -22.901944) (xy 191.388547 -22.990965) (xy 191.370647 -23.078632)
			(xy 191.344039 -23.16406) (xy 191.327024 -23.20544) (xy 191.323489 -23.215039) (xy 191.323471 -23.235473)
			(xy 191.327024 -23.245064) (xy 191.344055 -23.286438) (xy 191.370671 -23.371866) (xy 191.388573 -23.459535)
			(xy 191.39758 -23.548559) (xy 191.398144 -23.593298) (xy 191.398144 -23.593552) (xy 191.39764 -23.6359)
			(xy 191.389589 -23.720214) (xy 191.37356 -23.80338) (xy 191.349699 -23.884647) (xy 191.31822 -23.963277)
			(xy 191.279409 -24.038558) (xy 191.233619 -24.10981) (xy 191.181263 -24.176386) (xy 191.122815 -24.237684)
			(xy 191.058805 -24.293149) (xy 190.989813 -24.342278) (xy 190.916463 -24.384627) (xy 190.83942 -24.419811)
			(xy 190.759381 -24.447513) (xy 190.677072 -24.467481) (xy 190.593237 -24.479534) (xy 190.508636 -24.483565)
			(xy 190.424035 -24.479534) (xy 190.3402 -24.467481) (xy 190.257891 -24.447513) (xy 190.177852 -24.419811)
			(xy 190.100809 -24.384627) (xy 190.027459 -24.342278) (xy 189.958467 -24.293149) (xy 189.894457 -24.237684)
			(xy 189.836009 -24.176386) (xy 189.783653 -24.10981) (xy 189.737863 -24.038558) (xy 189.699052 -23.963277)
			(xy 189.667573 -23.884647) (xy 189.643712 -23.80338) (xy 189.627683 -23.720214) (xy 189.619632 -23.6359)
			(xy 189.619128 -23.593552) (xy 0.509016 -23.593552) (xy 0.509016 -25.56891) (xy 65.510156 -25.56891)
			(xy 65.510621 -25.527206) (xy 65.518403 -25.444163) (xy 65.533928 -25.362214) (xy 65.557059 -25.282079)
			(xy 65.587593 -25.204462) (xy 65.625262 -25.130046) (xy 65.669734 -25.059485) (xy 65.720619 -24.993398)
			(xy 65.777469 -24.932368) (xy 65.839786 -24.876929) (xy 65.873122 -24.851868) (xy 65.88167 -24.844931)
			(xy 65.892346 -24.825708) (xy 65.893696 -24.814784) (xy 65.897332 -24.773398) (xy 65.911399 -24.69151)
			(xy 65.933041 -24.611291) (xy 65.962067 -24.53344) (xy 65.998226 -24.458634) (xy 66.041203 -24.387525)
			(xy 66.090622 -24.320733) (xy 66.146054 -24.25884) (xy 66.207015 -24.202385) (xy 66.272974 -24.15186)
			(xy 66.343357 -24.107705) (xy 66.41755 -24.070304) (xy 66.494907 -24.039985) (xy 66.574755 -24.01701)
			(xy 66.656396 -24.00158) (xy 66.739121 -23.99383) (xy 66.780664 -23.993348) (xy 66.824459 -23.993873)
			(xy 66.911625 -24.002491) (xy 66.997521 -24.019637) (xy 67.081315 -24.045145) (xy 67.162195 -24.078768)
			(xy 67.201034 -24.099012) (xy 67.2125 -24.10443) (xy 67.237828 -24.10443) (xy 67.249294 -24.099012)
			(xy 67.288138 -24.078781) (xy 67.369023 -24.045174) (xy 67.452816 -24.019672) (xy 67.538709 -24.002521)
			(xy 67.62587 -23.993888) (xy 67.669664 -23.993348) (xy 67.713459 -23.993873) (xy 67.800625 -24.002491)
			(xy 67.886521 -24.019637) (xy 67.970315 -24.045145) (xy 68.051195 -24.078768) (xy 68.090034 -24.099012)
			(xy 68.1015 -24.10443) (xy 68.126828 -24.10443) (xy 68.138294 -24.099012) (xy 68.177138 -24.078781)
			(xy 68.258023 -24.045174) (xy 68.341816 -24.019672) (xy 68.427709 -24.002521) (xy 68.51487 -23.993888)
			(xy 68.558664 -23.993348) (xy 68.607651 -23.994055) (xy 68.705028 -24.00487) (xy 68.752974 -24.014938)
			(xy 68.762324 -24.016604) (xy 68.781086 -24.013776) (xy 68.797533 -24.004314) (xy 68.803774 -23.997158)
			(xy 68.831851 -23.962886) (xy 68.893786 -23.899527) (xy 68.961714 -23.842641) (xy 69.034963 -23.792791)
			(xy 69.112805 -23.750472) (xy 69.19447 -23.716104) (xy 69.279148 -23.690027) (xy 69.365999 -23.672499)
			(xy 69.454163 -23.663695) (xy 69.498464 -23.663148) (xy 69.540827 -23.663615) (xy 69.625169 -23.671665)
			(xy 69.708365 -23.687697) (xy 69.789659 -23.711564) (xy 69.868317 -23.743051) (xy 69.943625 -23.781873)
			(xy 70.014902 -23.827677) (xy 70.081502 -23.880049) (xy 70.142823 -23.938516) (xy 70.198307 -24.002546)
			(xy 70.247454 -24.071561) (xy 70.250564 -24.076947) (xy 112.652614 -24.076947) (xy 112.652614 -24.022453)
			(xy 112.660369 -23.968515) (xy 112.67572 -23.916228) (xy 112.698356 -23.866659) (xy 112.727815 -23.820815)
			(xy 112.763499 -23.77963) (xy 112.80468 -23.743942) (xy 112.85052 -23.714477) (xy 112.900087 -23.691836)
			(xy 112.952372 -23.676478) (xy 113.006309 -23.668717) (xy 113.033556 -23.668228) (xy 113.897156 -23.668228)
			(xy 113.924413 -23.668616) (xy 113.978374 -23.676369) (xy 114.030682 -23.691722) (xy 114.080273 -23.714364)
			(xy 114.126136 -23.743834) (xy 114.167338 -23.779531) (xy 114.20304 -23.820729) (xy 114.232514 -23.866588)
			(xy 114.255162 -23.916176) (xy 114.270522 -23.968483) (xy 114.278281 -24.022443) (xy 114.278281 -24.076957)
			(xy 114.270522 -24.130917) (xy 114.255235 -24.182975) (xy 116.218856 -24.182975) (xy 116.218856 -24.128425)
			(xy 116.226619 -24.074429) (xy 116.241989 -24.022088) (xy 116.264651 -23.972468) (xy 116.294144 -23.926577)
			(xy 116.329868 -23.885352) (xy 116.371096 -23.84963) (xy 116.416989 -23.820139) (xy 116.466611 -23.79748)
			(xy 116.518953 -23.782114) (xy 116.572949 -23.774354) (xy 116.600224 -23.773892) (xy 117.463824 -23.773892)
			(xy 117.491089 -23.774472) (xy 117.545063 -23.782235) (xy 117.597384 -23.797601) (xy 117.646985 -23.820256)
			(xy 117.692857 -23.849739) (xy 117.734067 -23.88545) (xy 117.769776 -23.926662) (xy 117.799256 -23.972536)
			(xy 117.821907 -24.022139) (xy 117.83727 -24.07446) (xy 117.84503 -24.128435) (xy 117.84503 -24.182965)
			(xy 117.83727 -24.23694) (xy 117.821907 -24.289261) (xy 117.799256 -24.338864) (xy 117.769776 -24.384738)
			(xy 117.734067 -24.42595) (xy 117.692857 -24.461661) (xy 117.646985 -24.491144) (xy 117.597384 -24.513799)
			(xy 117.545063 -24.529165) (xy 117.491089 -24.536928) (xy 117.463824 -24.537416) (xy 116.600224 -24.537416)
			(xy 116.572949 -24.537046) (xy 116.518953 -24.529286) (xy 116.466611 -24.51392) (xy 116.416989 -24.491261)
			(xy 116.371096 -24.46177) (xy 116.329868 -24.426049) (xy 116.294144 -24.384823) (xy 116.264651 -24.338932)
			(xy 116.241989 -24.289312) (xy 116.226619 -24.236971) (xy 116.218856 -24.182975) (xy 114.255235 -24.182975)
			(xy 114.255162 -24.183224) (xy 114.232514 -24.232812) (xy 114.20304 -24.278671) (xy 114.167338 -24.319869)
			(xy 114.126136 -24.355566) (xy 114.080273 -24.385036) (xy 114.030682 -24.407678) (xy 113.978374 -24.423031)
			(xy 113.924414 -24.430784) (xy 113.897156 -24.431244) (xy 113.033556 -24.431244) (xy 113.006309 -24.430683)
			(xy 112.952372 -24.422922) (xy 112.900087 -24.407564) (xy 112.85052 -24.384923) (xy 112.80468 -24.355458)
			(xy 112.763499 -24.31977) (xy 112.727815 -24.278585) (xy 112.698356 -24.232741) (xy 112.67572 -24.183172)
			(xy 112.660369 -24.130885) (xy 112.652614 -24.076947) (xy 70.250564 -24.076947) (xy 70.289818 -24.144935)
			(xy 70.325015 -24.222004) (xy 70.352727 -24.302069) (xy 70.372702 -24.384407) (xy 70.38476 -24.46827)
			(xy 70.388792 -24.5529) (xy 70.38476 -24.63753) (xy 70.37544 -24.702351) (xy 130.235962 -24.702351)
			(xy 130.235962 -24.647849) (xy 130.243717 -24.593903) (xy 130.259071 -24.541609) (xy 130.28171 -24.492033)
			(xy 130.311174 -24.446182) (xy 130.346863 -24.404991) (xy 130.38805 -24.369298) (xy 130.433897 -24.33983)
			(xy 130.483472 -24.317185) (xy 130.535764 -24.301826) (xy 130.589709 -24.294065) (xy 130.61696 -24.293576)
			(xy 131.48056 -24.293576) (xy 131.507814 -24.294069) (xy 131.561767 -24.301821) (xy 131.614067 -24.317173)
			(xy 131.66365 -24.339812) (xy 131.709506 -24.369277) (xy 131.750702 -24.40497) (xy 131.786399 -24.446162)
			(xy 131.815869 -24.492015) (xy 131.838513 -24.541595) (xy 131.853871 -24.593894) (xy 131.861629 -24.647846)
			(xy 131.861629 -24.702354) (xy 131.853871 -24.756306) (xy 131.838513 -24.808605) (xy 131.815869 -24.858185)
			(xy 131.786399 -24.904038) (xy 131.750702 -24.94523) (xy 131.709506 -24.980923) (xy 131.66365 -25.010388)
			(xy 131.614067 -25.033027) (xy 131.561767 -25.048379) (xy 131.507814 -25.056131) (xy 131.48056 -25.056592)
			(xy 130.61696 -25.056592) (xy 130.589709 -25.056135) (xy 130.535764 -25.048374) (xy 130.483472 -25.033015)
			(xy 130.433897 -25.01037) (xy 130.38805 -24.980902) (xy 130.346863 -24.945209) (xy 130.311174 -24.904018)
			(xy 130.28171 -24.858167) (xy 130.259071 -24.808591) (xy 130.243717 -24.756297) (xy 130.235962 -24.702351)
			(xy 70.37544 -24.702351) (xy 70.372702 -24.721393) (xy 70.352727 -24.803731) (xy 70.325015 -24.883796)
			(xy 70.289818 -24.960865) (xy 70.247454 -25.034239) (xy 70.198307 -25.103254) (xy 70.142823 -25.167284)
			(xy 70.081502 -25.225751) (xy 70.014902 -25.278123) (xy 69.943625 -25.323927) (xy 69.868317 -25.362749)
			(xy 69.789659 -25.394236) (xy 69.708365 -25.418103) (xy 69.625169 -25.434135) (xy 69.540827 -25.442185)
			(xy 69.498464 -25.442672) (xy 69.449476 -25.441976) (xy 69.3521 -25.431154) (xy 69.304154 -25.421082)
			(xy 69.294812 -25.41935) (xy 69.276039 -25.422204) (xy 69.259591 -25.431693) (xy 69.253354 -25.438862)
			(xy 69.228687 -25.46901) (xy 69.174875 -25.52534) (xy 69.116354 -25.57676) (xy 69.085206 -25.600152)
			(xy 69.076637 -25.607067) (xy 69.065975 -25.626306) (xy 69.065849 -25.62733) (xy 133.339332 -25.62733)
			(xy 133.339332 -24.76373) (xy 133.339818 -24.736479) (xy 133.347574 -24.682531) (xy 133.362929 -24.630236)
			(xy 133.385571 -24.580659) (xy 133.415037 -24.534809) (xy 133.450728 -24.493618) (xy 133.491919 -24.457927)
			(xy 133.537769 -24.428461) (xy 133.587346 -24.405819) (xy 133.639641 -24.390464) (xy 133.693589 -24.382708)
			(xy 133.748091 -24.382708) (xy 133.802039 -24.390464) (xy 133.854334 -24.405819) (xy 133.903911 -24.428461)
			(xy 133.949761 -24.457927) (xy 133.990952 -24.493618) (xy 134.026643 -24.534809) (xy 134.056109 -24.580659)
			(xy 134.078751 -24.630236) (xy 134.094106 -24.682531) (xy 134.101862 -24.736479) (xy 134.102348 -24.76373)
			(xy 134.102348 -25.62733) (xy 134.101862 -25.654581) (xy 134.094106 -25.708529) (xy 134.078751 -25.760824)
			(xy 134.056109 -25.810401) (xy 134.026643 -25.856251) (xy 133.990952 -25.897442) (xy 133.949761 -25.933133)
			(xy 133.903911 -25.962599) (xy 133.854334 -25.985241) (xy 133.802039 -26.000596) (xy 133.748091 -26.008352)
			(xy 133.693589 -26.008352) (xy 133.639641 -26.000596) (xy 133.587346 -25.985241) (xy 133.537769 -25.962599)
			(xy 133.491919 -25.933133) (xy 133.450728 -25.897442) (xy 133.415037 -25.856251) (xy 133.385571 -25.810401)
			(xy 133.362929 -25.760824) (xy 133.347574 -25.708529) (xy 133.339818 -25.654581) (xy 133.339332 -25.62733)
			(xy 69.065849 -25.62733) (xy 69.064632 -25.637236) (xy 69.060986 -25.678621) (xy 69.046917 -25.760507)
			(xy 69.025275 -25.840725) (xy 68.996248 -25.918575) (xy 68.960089 -25.99338) (xy 68.917113 -26.064488)
			(xy 68.867694 -26.131279) (xy 68.812263 -26.193171) (xy 68.751303 -26.249626) (xy 68.685345 -26.300151)
			(xy 68.614964 -26.344307) (xy 68.540772 -26.381708) (xy 68.463416 -26.412028) (xy 68.38357 -26.435004)
			(xy 68.30193 -26.450436) (xy 68.219207 -26.458189) (xy 68.177664 -26.458672) (xy 68.133869 -26.458133)
			(xy 68.046704 -26.449518) (xy 67.960808 -26.432375) (xy 67.877014 -26.40687) (xy 67.796134 -26.37325)
			(xy 67.757294 -26.353008) (xy 67.745828 -26.34759) (xy 67.7205 -26.34759) (xy 67.709034 -26.353008)
			(xy 67.670181 -26.373222) (xy 67.589299 -26.406833) (xy 67.505508 -26.43234) (xy 67.419618 -26.449494)
			(xy 67.332457 -26.458131) (xy 67.288664 -26.458672) (xy 67.244869 -26.458133) (xy 67.157704 -26.449518)
			(xy 67.071808 -26.432375) (xy 66.988014 -26.40687) (xy 66.907134 -26.37325) (xy 66.868294 -26.353008)
			(xy 66.856828 -26.34759) (xy 66.8315 -26.34759) (xy 66.820034 -26.353008) (xy 66.781181 -26.373222)
			(xy 66.700299 -26.406833) (xy 66.616508 -26.43234) (xy 66.530618 -26.449494) (xy 66.443457 -26.458131)
			(xy 66.399664 -26.458672) (xy 66.358552 -26.458282) (xy 66.276678 -26.45069) (xy 66.195855 -26.435576)
			(xy 66.116771 -26.413067) (xy 66.040102 -26.383356) (xy 65.966502 -26.346696) (xy 65.8966 -26.3034)
			(xy 65.830991 -26.253838) (xy 65.770236 -26.198433) (xy 65.714853 -26.137658) (xy 65.665316 -26.072031)
			(xy 65.622046 -26.002113) (xy 65.585413 -25.928499) (xy 65.55573 -25.85182) (xy 65.53325 -25.772728)
			(xy 65.518165 -25.691899) (xy 65.510603 -25.610022) (xy 65.510156 -25.56891) (xy 0.509016 -25.56891)
			(xy 0.509016 -29.026161) (xy 11.140205 -29.026161) (xy 11.147539 -28.866724) (xy 11.162812 -28.70785)
			(xy 11.185984 -28.549934) (xy 11.216999 -28.39337) (xy 11.255779 -28.238547) (xy 11.302228 -28.085849)
			(xy 11.35623 -27.935656) (xy 11.417652 -27.788341) (xy 11.48634 -27.644271) (xy 11.562123 -27.503804)
			(xy 11.644814 -27.367289) (xy 11.734207 -27.235065) (xy 11.830079 -27.107461) (xy 11.932193 -26.984794)
			(xy 12.040293 -26.86737) (xy 12.154112 -26.75548) (xy 12.273367 -26.649402) (xy 12.397761 -26.5494)
			(xy 12.526985 -26.455723) (xy 12.660717 -26.368604) (xy 12.798626 -26.288258) (xy 12.940368 -26.214886)
			(xy 13.085591 -26.148671) (xy 13.233934 -26.089776) (xy 13.385028 -26.038349) (xy 13.538498 -25.994517)
			(xy 13.693962 -25.958388) (xy 13.851033 -25.930054) (xy 14.009321 -25.909584) (xy 14.168433 -25.897029)
			(xy 14.327973 -25.892421) (xy 14.487544 -25.895771) (xy 14.64675 -25.90707) (xy 14.805195 -25.92629)
			(xy 14.962485 -25.953385) (xy 15.118229 -25.988285) (xy 15.272039 -26.030905) (xy 15.423535 -26.081139)
			(xy 15.572338 -26.138862) (xy 15.718078 -26.203929) (xy 15.860395 -26.27618) (xy 15.998933 -26.355436)
			(xy 16.133349 -26.441497) (xy 16.263308 -26.534152) (xy 16.388487 -26.633169) (xy 16.508575 -26.738303)
			(xy 16.623273 -26.849292) (xy 16.678148 -26.907236) (xy 17.093762 -27.351736) (xy 112.919256 -27.351736)
			(xy 112.919256 -26.843736) (xy 112.919814 -26.833635) (xy 112.927531 -26.814966) (xy 112.941806 -26.800672)
			(xy 112.960464 -26.792928) (xy 112.970564 -26.792428) (xy 113.6269 -26.792428) (xy 113.637026 -26.792817)
			(xy 113.655735 -26.80057) (xy 113.67005 -26.814895) (xy 113.67779 -26.83361) (xy 113.678208 -26.843736)
			(xy 113.678208 -27.351736) (xy 113.919 -27.351736) (xy 113.919 -26.843736) (xy 113.919446 -26.833616)
			(xy 113.927182 -26.814913) (xy 113.94149 -26.800598) (xy 113.960188 -26.792851) (xy 113.970308 -26.792428)
			(xy 114.626898 -26.792428) (xy 114.637023 -26.792928) (xy 114.655742 -26.800653) (xy 114.670098 -26.814935)
			(xy 114.677919 -26.833614) (xy 114.67846 -26.843736) (xy 114.67846 -27.351736) (xy 115.419124 -27.351736)
			(xy 115.419124 -26.843736) (xy 115.419546 -26.833613) (xy 115.427287 -26.814906) (xy 115.441602 -26.800589)
			(xy 115.460309 -26.792847) (xy 115.470432 -26.792428) (xy 116.127022 -26.792428) (xy 116.137149 -26.792908)
			(xy 116.155868 -26.800641) (xy 116.170223 -26.814929) (xy 116.178044 -26.833612) (xy 116.178584 -26.843736)
			(xy 116.178584 -27.351736) (xy 116.178144 -27.361849) (xy 116.170392 -27.380531) (xy 116.156081 -27.394825)
			(xy 116.13739 -27.402556) (xy 116.127276 -27.403044) (xy 115.470686 -27.403044) (xy 115.460556 -27.402584)
			(xy 115.441832 -27.394849) (xy 115.427476 -27.380554) (xy 115.41966 -27.361863) (xy 115.419124 -27.351736)
			(xy 114.67846 -27.351736) (xy 114.678113 -27.361866) (xy 114.670345 -27.380578) (xy 114.656007 -27.394892)
			(xy 114.637282 -27.402629) (xy 114.627152 -27.403044) (xy 113.970562 -27.403044) (xy 113.960431 -27.402604)
			(xy 113.941706 -27.394861) (xy 113.92735 -27.38056) (xy 113.919535 -27.361865) (xy 113.919 -27.351736)
			(xy 113.678208 -27.351736) (xy 113.677745 -27.361846) (xy 113.669997 -27.380524) (xy 113.655693 -27.394817)
			(xy 113.63701 -27.402552) (xy 113.6269 -27.403044) (xy 112.970564 -27.403044) (xy 112.960458 -27.402545)
			(xy 112.941788 -27.394804) (xy 112.927496 -27.380512) (xy 112.919755 -27.361842) (xy 112.919256 -27.351736)
			(xy 17.093762 -27.351736) (xy 17.601048 -27.89428) (xy 130.306572 -27.89428) (xy 130.306572 -26.62428)
			(xy 130.307068 -26.614173) (xy 130.314807 -26.5955) (xy 130.3291 -26.581207) (xy 130.347773 -26.573468)
			(xy 130.35788 -26.572972) (xy 130.637534 -26.572972) (xy 130.651504 -26.575004) (xy 130.659033 -26.576913)
			(xy 130.674555 -26.576512) (xy 130.681984 -26.574242) (xy 130.73761 -26.555446) (xy 130.741118 -26.55416)
			(xy 130.747748 -26.550718) (xy 130.750818 -26.548588) (xy 130.757422 -26.543762) (xy 130.761994 -26.537412)
			(xy 130.780119 -26.513843) (xy 130.82244 -26.472085) (xy 130.870719 -26.437388) (xy 130.92379 -26.410589)
			(xy 130.980373 -26.392335) (xy 131.0391 -26.383067) (xy 131.068826 -26.382472) (xy 131.069334 -26.382472)
			(xy 131.099067 -26.383027) (xy 131.157812 -26.392252) (xy 131.214412 -26.410489) (xy 131.267493 -26.437295)
			(xy 131.315767 -26.472019) (xy 131.358062 -26.513819) (xy 131.376166 -26.537412) (xy 131.380738 -26.543762)
			(xy 131.387342 -26.548334) (xy 131.390407 -26.550522) (xy 131.397035 -26.554095) (xy 131.40055 -26.555446)
			(xy 131.46405 -26.576782) (xy 131.479036 -26.57729) (xy 131.486402 -26.575004) (xy 131.486656 -26.575004)
			(xy 131.500626 -26.572972) (xy 131.78028 -26.572972) (xy 131.790384 -26.573501) (xy 131.809056 -26.581227)
			(xy 131.823351 -26.59551) (xy 131.831091 -26.614176) (xy 131.831588 -26.62428) (xy 131.831588 -26.76779)
			(xy 141.621764 -26.76779) (xy 141.621764 -25.90419) (xy 141.62225 -25.876921) (xy 141.630012 -25.822937)
			(xy 141.645377 -25.770607) (xy 141.668034 -25.720997) (xy 141.69752 -25.675116) (xy 141.733235 -25.633899)
			(xy 141.774452 -25.598184) (xy 141.820333 -25.568698) (xy 141.869943 -25.546041) (xy 141.922273 -25.530676)
			(xy 141.976257 -25.522914) (xy 142.030795 -25.522914) (xy 142.084779 -25.530676) (xy 142.137109 -25.546041)
			(xy 142.186719 -25.568698) (xy 142.2326 -25.598184) (xy 142.273817 -25.633899) (xy 142.309532 -25.675116)
			(xy 142.339018 -25.720997) (xy 142.361675 -25.770607) (xy 142.37704 -25.822937) (xy 142.384802 -25.876921)
			(xy 142.385288 -25.90419) (xy 142.385288 -26.634948) (xy 175.442372 -26.634948) (xy 175.442817 -26.593237)
			(xy 175.450618 -26.510181) (xy 175.466165 -26.428221) (xy 175.489321 -26.348077) (xy 175.519883 -26.270455)
			(xy 175.557582 -26.196038) (xy 175.602086 -26.125479) (xy 175.653004 -26.059399) (xy 175.709888 -25.99838)
			(xy 175.772239 -25.942957) (xy 175.805592 -25.917906) (xy 175.814178 -25.911009) (xy 175.82483 -25.891756)
			(xy 175.826166 -25.880822) (xy 175.829855 -25.839448) (xy 175.843941 -25.757582) (xy 175.865598 -25.677385)
			(xy 175.894637 -25.599556) (xy 175.930804 -25.524774) (xy 175.973785 -25.453688) (xy 176.023205 -25.386918)
			(xy 176.078634 -25.325046) (xy 176.13959 -25.268611) (xy 176.205541 -25.218103) (xy 176.275913 -25.173964)
			(xy 176.350094 -25.136576) (xy 176.427436 -25.106267) (xy 176.507267 -25.083299) (xy 176.588892 -25.067873)
			(xy 176.671599 -25.060123) (xy 176.713134 -25.05964) (xy 176.713642 -25.05964) (xy 176.757406 -25.060139)
			(xy 176.844513 -25.068717) (xy 176.930355 -25.085818) (xy 177.0141 -25.111273) (xy 177.094937 -25.144838)
			(xy 177.133758 -25.16505) (xy 177.145111 -25.170377) (xy 177.170157 -25.170377) (xy 177.18151 -25.16505)
			(xy 177.22038 -25.144826) (xy 177.301322 -25.111257) (xy 177.38517 -25.085803) (xy 177.471113 -25.068709)
			(xy 177.55832 -25.060143) (xy 177.602134 -25.05964) (xy 177.645949 -25.060116) (xy 177.733161 -25.068665)
			(xy 177.819109 -25.085756) (xy 177.902957 -25.111222) (xy 177.983891 -25.144816) (xy 178.022758 -25.16505)
			(xy 178.034111 -25.170377) (xy 178.059157 -25.170377) (xy 178.07051 -25.16505) (xy 178.10938 -25.144826)
			(xy 178.190322 -25.111257) (xy 178.27417 -25.085803) (xy 178.360113 -25.068709) (xy 178.44732 -25.060143)
			(xy 178.491134 -25.05964) (xy 178.541288 -25.060291) (xy 178.640969 -25.071493) (xy 178.690016 -25.081992)
			(xy 178.700529 -25.083816) (xy 178.72144 -25.079687) (xy 178.7389 -25.067462) (xy 178.74488 -25.058624)
			(xy 178.766746 -25.023211) (xy 178.816155 -24.956227) (xy 178.871604 -24.894151) (xy 178.932608 -24.837525)
			(xy 178.998633 -24.786843) (xy 179.069104 -24.742549) (xy 179.143403 -24.705031) (xy 179.220882 -24.674615)
			(xy 179.300862 -24.651569) (xy 179.382645 -24.636093) (xy 179.465517 -24.628322) (xy 179.507134 -24.62784)
			(xy 179.549484 -24.628249) (xy 179.633799 -24.636303) (xy 179.716968 -24.652336) (xy 179.798236 -24.676201)
			(xy 179.876867 -24.707683) (xy 179.95215 -24.746496) (xy 180.023403 -24.79229) (xy 180.08998 -24.844649)
			(xy 180.151278 -24.9031) (xy 180.206744 -24.967112) (xy 180.255873 -25.036107) (xy 180.298222 -25.10946)
			(xy 180.333407 -25.186506) (xy 180.361109 -25.266547) (xy 180.381077 -25.348859) (xy 180.39313 -25.432696)
			(xy 180.397161 -25.5173) (xy 180.39313 -25.601904) (xy 180.381077 -25.685741) (xy 180.361109 -25.768053)
			(xy 180.333407 -25.848094) (xy 180.298222 -25.92514) (xy 180.255873 -25.998493) (xy 180.206744 -26.067488)
			(xy 180.151278 -26.1315) (xy 180.08998 -26.189951) (xy 180.023403 -26.24231) (xy 179.95215 -26.288104)
			(xy 179.876867 -26.326917) (xy 179.798236 -26.358399) (xy 179.716968 -26.382264) (xy 179.633799 -26.398297)
			(xy 179.549484 -26.406351) (xy 179.507134 -26.406856) (xy 179.505864 -26.406856) (xy 179.456029 -26.406131)
			(xy 179.35699 -26.394927) (xy 179.308252 -26.384504) (xy 179.297742 -26.382653) (xy 179.276827 -26.386794)
			(xy 179.259367 -26.39903) (xy 179.253388 -26.407872) (xy 179.230217 -26.445289) (xy 179.177598 -26.515842)
			(xy 179.118275 -26.58086) (xy 179.052827 -26.639708) (xy 179.017676 -26.66619) (xy 179.009104 -26.673102)
			(xy 178.998441 -26.692343) (xy 178.997102 -26.703274) (xy 178.993441 -26.744651) (xy 178.979354 -26.826519)
			(xy 178.957697 -26.906717) (xy 178.928657 -26.984547) (xy 178.892489 -27.059331) (xy 178.849506 -27.130418)
			(xy 178.835198 -27.149749) (xy 180.032656 -27.149749) (xy 180.032656 -27.065027) (xy 180.040709 -26.98069)
			(xy 180.056743 -26.8975) (xy 180.080611 -26.81621) (xy 180.112099 -26.737558) (xy 180.150921 -26.662255)
			(xy 180.196724 -26.590983) (xy 180.249095 -26.524387) (xy 180.30756 -26.463072) (xy 180.371588 -26.407591)
			(xy 180.4406 -26.358448) (xy 180.51397 -26.316088) (xy 180.591035 -26.280893) (xy 180.671097 -26.253184)
			(xy 180.75343 -26.23321) (xy 180.837289 -26.221153) (xy 180.921914 -26.217122) (xy 181.006539 -26.221153)
			(xy 181.090398 -26.23321) (xy 181.172731 -26.253184) (xy 181.252793 -26.280893) (xy 181.329858 -26.316088)
			(xy 181.403228 -26.358448) (xy 181.47224 -26.407591) (xy 181.536268 -26.463072) (xy 181.594733 -26.524387)
			(xy 181.647104 -26.590983) (xy 181.692907 -26.662255) (xy 181.731729 -26.737558) (xy 181.763217 -26.81621)
			(xy 181.787085 -26.8975) (xy 181.803119 -26.98069) (xy 181.811172 -27.065027) (xy 181.811676 -27.107388)
			(xy 181.811172 -27.149749) (xy 181.803119 -27.234086) (xy 181.787085 -27.317276) (xy 181.763217 -27.398566)
			(xy 181.731729 -27.477218) (xy 181.692907 -27.552521) (xy 181.647104 -27.623793) (xy 181.594733 -27.690389)
			(xy 181.536268 -27.751704) (xy 181.47224 -27.807185) (xy 181.403228 -27.856328) (xy 181.329858 -27.898688)
			(xy 181.252793 -27.933883) (xy 181.172731 -27.961592) (xy 181.090398 -27.981566) (xy 181.006539 -27.993623)
			(xy 180.921914 -27.997655) (xy 180.837289 -27.993623) (xy 180.75343 -27.981566) (xy 180.671097 -27.961592)
			(xy 180.591035 -27.933883) (xy 180.51397 -27.898688) (xy 180.4406 -27.856328) (xy 180.371588 -27.807185)
			(xy 180.30756 -27.751704) (xy 180.249095 -27.690389) (xy 180.196724 -27.623793) (xy 180.150921 -27.552521)
			(xy 180.112099 -27.477218) (xy 180.080611 -27.398566) (xy 180.056743 -27.317276) (xy 180.040709 -27.234086)
			(xy 180.032656 -27.149749) (xy 178.835198 -27.149749) (xy 178.800084 -27.197189) (xy 178.744653 -27.259061)
			(xy 178.683695 -27.315497) (xy 178.617742 -27.366004) (xy 178.547367 -27.410143) (xy 178.473184 -27.447529)
			(xy 178.395839 -27.477837) (xy 178.316006 -27.500803) (xy 178.234379 -27.516227) (xy 178.15167 -27.523974)
			(xy 178.110134 -27.524456) (xy 178.109626 -27.524456) (xy 178.065862 -27.523929) (xy 177.978756 -27.515357)
			(xy 177.892915 -27.498263) (xy 177.809169 -27.472814) (xy 177.728331 -27.439255) (xy 177.68951 -27.419046)
			(xy 177.678157 -27.413719) (xy 177.653111 -27.413719) (xy 177.641758 -27.419046) (xy 177.602894 -27.439282)
			(xy 177.521951 -27.472849) (xy 177.438101 -27.498301) (xy 177.352156 -27.515391) (xy 177.264948 -27.523955)
			(xy 177.221134 -27.524456) (xy 177.177318 -27.523994) (xy 177.090106 -27.515442) (xy 177.004158 -27.498348)
			(xy 176.920311 -27.472879) (xy 176.839376 -27.439281) (xy 176.80051 -27.419046) (xy 176.789157 -27.413719)
			(xy 176.764111 -27.413719) (xy 176.752758 -27.419046) (xy 176.713921 -27.439222) (xy 176.633081 -27.472767)
			(xy 176.549339 -27.498216) (xy 176.463504 -27.515325) (xy 176.376404 -27.523927) (xy 176.332642 -27.524456)
			(xy 176.332134 -27.524456) (xy 176.291028 -27.523955) (xy 176.209165 -27.516374) (xy 176.128351 -27.501273)
			(xy 176.049275 -27.47878) (xy 175.972611 -27.449089) (xy 175.899013 -27.412452) (xy 175.829109 -27.369181)
			(xy 175.763495 -27.319646) (xy 175.702731 -27.264268) (xy 175.647335 -27.203522) (xy 175.597779 -27.137923)
			(xy 175.554486 -27.068033) (xy 175.517825 -26.994447) (xy 175.488109 -26.917792) (xy 175.465592 -26.838723)
			(xy 175.450465 -26.757914) (xy 175.442858 -26.676054) (xy 175.442372 -26.634948) (xy 142.385288 -26.634948)
			(xy 142.385288 -26.76779) (xy 142.384802 -26.795059) (xy 142.37704 -26.849043) (xy 142.361675 -26.901373)
			(xy 142.339018 -26.950983) (xy 142.309532 -26.996864) (xy 142.273817 -27.038081) (xy 142.2326 -27.073796)
			(xy 142.186719 -27.103282) (xy 142.137109 -27.125939) (xy 142.084779 -27.141304) (xy 142.030795 -27.149066)
			(xy 141.976257 -27.149066) (xy 141.922273 -27.141304) (xy 141.869943 -27.125939) (xy 141.820333 -27.103282)
			(xy 141.774452 -27.073796) (xy 141.733235 -27.038081) (xy 141.69752 -26.996864) (xy 141.668034 -26.950983)
			(xy 141.645377 -26.901373) (xy 141.630012 -26.849043) (xy 141.62225 -26.795059) (xy 141.621764 -26.76779)
			(xy 131.831588 -26.76779) (xy 131.831588 -27.89428) (xy 131.831167 -27.904403) (xy 131.823424 -27.923108)
			(xy 131.809108 -27.937424) (xy 131.790403 -27.945167) (xy 131.78028 -27.945588) (xy 131.500626 -27.945588)
			(xy 131.486656 -27.943556) (xy 131.479122 -27.941671) (xy 131.463605 -27.942055) (xy 131.456176 -27.944318)
			(xy 131.40055 -27.963114) (xy 131.397037 -27.964387) (xy 131.390409 -27.967838) (xy 131.387342 -27.969972)
			(xy 131.380738 -27.974798) (xy 131.376166 -27.981148) (xy 131.358081 -28.004749) (xy 131.31575 -28.046502)
			(xy 131.267462 -28.081194) (xy 131.214383 -28.107987) (xy 131.157795 -28.126234) (xy 131.099062 -28.135496)
			(xy 131.069334 -28.136088) (xy 131.068826 -28.136088) (xy 131.039094 -28.135505) (xy 130.980349 -28.126288)
			(xy 130.923749 -28.108058) (xy 130.870667 -28.081257) (xy 130.822393 -28.046537) (xy 130.780098 -28.004739)
			(xy 130.761994 -27.981148) (xy 130.757422 -27.974798) (xy 130.750818 -27.970226) (xy 130.74776 -27.968028)
			(xy 130.741127 -27.964461) (xy 130.73761 -27.963114) (xy 130.67411 -27.941778) (xy 130.659124 -27.94127)
			(xy 130.651758 -27.943556) (xy 130.651504 -27.943556) (xy 130.637534 -27.945588) (xy 130.35788 -27.945588)
			(xy 130.347768 -27.945131) (xy 130.329087 -27.937385) (xy 130.314793 -27.923079) (xy 130.307061 -27.904392)
			(xy 130.306572 -27.89428) (xy 17.601048 -27.89428) (xy 17.770856 -28.07589) (xy 17.824996 -28.134528)
			(xy 17.928078 -28.256394) (xy 18.024957 -28.383247) (xy 18.115392 -28.514772) (xy 18.199158 -28.650641)
			(xy 18.276047 -28.790516) (xy 18.345869 -28.934051) (xy 18.408448 -29.080887) (xy 18.463631 -29.230661)
			(xy 18.511279 -29.382999) (xy 18.546379 -29.51861) (xy 101.326696 -29.51861) (xy 101.326696 -28.65501)
			(xy 101.327182 -28.627759) (xy 101.334938 -28.573811) (xy 101.350293 -28.521516) (xy 101.372935 -28.471939)
			(xy 101.402401 -28.426089) (xy 101.438092 -28.384898) (xy 101.479283 -28.349207) (xy 101.525133 -28.319741)
			(xy 101.57471 -28.297099) (xy 101.627005 -28.281744) (xy 101.680953 -28.273988) (xy 101.735455 -28.273988)
			(xy 101.789403 -28.281744) (xy 101.841698 -28.297099) (xy 101.891275 -28.319741) (xy 101.937125 -28.349207)
			(xy 101.978316 -28.384898) (xy 102.014007 -28.426089) (xy 102.043473 -28.471939) (xy 102.066115 -28.521516)
			(xy 102.08147 -28.573811) (xy 102.089226 -28.627759) (xy 102.089712 -28.65501) (xy 102.089712 -28.765754)
			(xy 102.99446 -28.765754) (xy 102.99446 -28.613354) (xy 102.994873 -28.601235) (xy 103.002375 -28.578186)
			(xy 103.016632 -28.558584) (xy 103.036247 -28.544344) (xy 103.059302 -28.536862) (xy 103.071422 -28.536392)
			(xy 103.300022 -28.536392) (xy 103.312133 -28.536892) (xy 103.335169 -28.54438) (xy 103.354767 -28.558616)
			(xy 103.369009 -28.578209) (xy 103.376504 -28.601243) (xy 103.376984 -28.613354) (xy 103.376984 -28.765754)
			(xy 103.376501 -28.777872) (xy 103.369024 -28.800926) (xy 103.354788 -28.82054) (xy 103.335187 -28.834793)
			(xy 103.31214 -28.842291) (xy 103.300022 -28.842716) (xy 103.071422 -28.842716) (xy 103.059296 -28.842321)
			(xy 103.03623 -28.834829) (xy 103.01661 -28.820572) (xy 103.00236 -28.800949) (xy 102.994876 -28.77788)
			(xy 102.99446 -28.765754) (xy 102.089712 -28.765754) (xy 102.089712 -29.38272) (xy 135.170672 -29.38272)
			(xy 135.170672 -28.11272) (xy 135.171201 -28.102616) (xy 135.178927 -28.083944) (xy 135.19321 -28.069649)
			(xy 135.211876 -28.061909) (xy 135.22198 -28.061412) (xy 135.501634 -28.061412) (xy 135.515604 -28.063444)
			(xy 135.523133 -28.065356) (xy 135.538655 -28.064955) (xy 135.546084 -28.062682) (xy 135.60171 -28.043886)
			(xy 135.605221 -28.042608) (xy 135.611851 -28.039163) (xy 135.614918 -28.037028) (xy 135.621522 -28.032202)
			(xy 135.626094 -28.025852) (xy 135.644202 -28.00227) (xy 135.686529 -27.960516) (xy 135.734812 -27.925822)
			(xy 135.787886 -27.899026) (xy 135.84447 -27.880774) (xy 135.903199 -27.871507) (xy 135.932926 -27.870912)
			(xy 135.933434 -27.870912) (xy 135.963168 -27.871451) (xy 136.021915 -27.880677) (xy 136.078516 -27.898916)
			(xy 136.131597 -27.925725) (xy 136.17987 -27.960453) (xy 136.222163 -28.002258) (xy 136.240266 -28.025852)
			(xy 136.244838 -28.032202) (xy 136.251442 -28.036774) (xy 136.254505 -28.038965) (xy 136.261134 -28.042536)
			(xy 136.26465 -28.043886) (xy 136.32815 -28.065222) (xy 136.343136 -28.06573) (xy 136.350502 -28.063444)
			(xy 136.350756 -28.063444) (xy 136.364726 -28.061412) (xy 136.64438 -28.061412) (xy 136.654503 -28.061833)
			(xy 136.673208 -28.069576) (xy 136.687524 -28.083892) (xy 136.695267 -28.102597) (xy 136.695688 -28.11272)
			(xy 136.695688 -28.526871) (xy 139.853386 -28.526871) (xy 139.853386 -28.472329) (xy 139.861148 -28.418343)
			(xy 139.876513 -28.366011) (xy 139.89917 -28.316397) (xy 139.928656 -28.270513) (xy 139.964371 -28.229293)
			(xy 140.005589 -28.193574) (xy 140.051471 -28.164084) (xy 140.101082 -28.141424) (xy 140.153414 -28.126054)
			(xy 140.207399 -28.118289) (xy 140.23467 -28.1178) (xy 141.09827 -28.1178) (xy 141.12554 -28.118337)
			(xy 141.179524 -28.126095) (xy 141.231856 -28.141457) (xy 141.281468 -28.164111) (xy 141.32735 -28.193595)
			(xy 141.36857 -28.229309) (xy 141.404287 -28.270526) (xy 141.433775 -28.316406) (xy 141.456432 -28.366016)
			(xy 141.471798 -28.418346) (xy 141.479561 -28.47233) (xy 141.479561 -28.52687) (xy 141.471798 -28.580854)
			(xy 141.456432 -28.633184) (xy 141.433775 -28.682794) (xy 141.404287 -28.728674) (xy 141.36857 -28.769891)
			(xy 141.32735 -28.805605) (xy 141.281468 -28.835089) (xy 141.231856 -28.857743) (xy 141.179524 -28.873105)
			(xy 141.12554 -28.880863) (xy 141.09827 -28.881324) (xy 140.23467 -28.881324) (xy 140.207399 -28.880911)
			(xy 140.153414 -28.873146) (xy 140.101082 -28.857776) (xy 140.051471 -28.835116) (xy 140.005589 -28.805626)
			(xy 139.964371 -28.769907) (xy 139.928656 -28.728687) (xy 139.89917 -28.682803) (xy 139.876513 -28.633189)
			(xy 139.861148 -28.580857) (xy 139.853386 -28.526871) (xy 136.695688 -28.526871) (xy 136.695688 -29.38272)
			(xy 136.695231 -29.392832) (xy 136.687485 -29.411513) (xy 136.673179 -29.425807) (xy 136.654492 -29.433539)
			(xy 136.64438 -29.434028) (xy 136.364726 -29.434028) (xy 136.350756 -29.431996) (xy 136.343222 -29.430114)
			(xy 136.327705 -29.430497) (xy 136.320276 -29.432758) (xy 136.26465 -29.451554) (xy 136.26114 -29.452833)
			(xy 136.25451 -29.45628) (xy 136.251442 -29.458412) (xy 136.244838 -29.463238) (xy 136.240266 -29.469588)
			(xy 136.222165 -29.493176) (xy 136.179839 -29.534933) (xy 136.131555 -29.569628) (xy 136.078479 -29.596424)
			(xy 136.021892 -29.614673) (xy 135.963162 -29.623936) (xy 135.933434 -29.624528) (xy 135.932926 -29.624528)
			(xy 135.903195 -29.623929) (xy 135.844451 -29.614713) (xy 135.787852 -29.596485) (xy 135.734771 -29.569687)
			(xy 135.686496 -29.534971) (xy 135.6442 -29.493177) (xy 135.626094 -29.469588) (xy 135.621522 -29.463238)
			(xy 135.614918 -29.458666) (xy 135.611858 -29.456471) (xy 135.605226 -29.452902) (xy 135.60171 -29.451554)
			(xy 135.53821 -29.430218) (xy 135.523224 -29.42971) (xy 135.515858 -29.431996) (xy 135.515604 -29.431996)
			(xy 135.501634 -29.434028) (xy 135.22198 -29.434028) (xy 135.211873 -29.433532) (xy 135.1932 -29.425793)
			(xy 135.178907 -29.4115) (xy 135.171168 -29.392827) (xy 135.170672 -29.38272) (xy 102.089712 -29.38272)
			(xy 102.089712 -29.51861) (xy 102.089226 -29.545861) (xy 102.08147 -29.599809) (xy 102.072795 -29.629354)
			(xy 102.99446 -29.629354) (xy 102.99446 -29.476954) (xy 102.994873 -29.464835) (xy 103.002375 -29.441786)
			(xy 103.016632 -29.422184) (xy 103.036247 -29.407944) (xy 103.059302 -29.400462) (xy 103.071422 -29.399992)
			(xy 103.300022 -29.399992) (xy 103.312133 -29.400492) (xy 103.335169 -29.40798) (xy 103.354767 -29.422216)
			(xy 103.369009 -29.441809) (xy 103.376504 -29.464843) (xy 103.376984 -29.476954) (xy 103.376984 -29.629354)
			(xy 103.376501 -29.641472) (xy 103.369024 -29.664526) (xy 103.354788 -29.68414) (xy 103.335187 -29.698393)
			(xy 103.31214 -29.705891) (xy 103.300022 -29.706316) (xy 103.071422 -29.706316) (xy 103.059296 -29.705921)
			(xy 103.03623 -29.698429) (xy 103.01661 -29.684172) (xy 103.00236 -29.664549) (xy 102.994876 -29.64148)
			(xy 102.99446 -29.629354) (xy 102.072795 -29.629354) (xy 102.066115 -29.652104) (xy 102.043473 -29.701681)
			(xy 102.014007 -29.747531) (xy 101.978316 -29.788722) (xy 101.937125 -29.824413) (xy 101.891275 -29.853879)
			(xy 101.841698 -29.876521) (xy 101.789403 -29.891876) (xy 101.735455 -29.899632) (xy 101.680953 -29.899632)
			(xy 101.627005 -29.891876) (xy 101.57471 -29.876521) (xy 101.525133 -29.853879) (xy 101.479283 -29.824413)
			(xy 101.438092 -29.788722) (xy 101.402401 -29.747531) (xy 101.372935 -29.701681) (xy 101.350293 -29.652104)
			(xy 101.334938 -29.599809) (xy 101.327182 -29.545861) (xy 101.326696 -29.51861) (xy 18.546379 -29.51861)
			(xy 18.551274 -29.537523) (xy 18.583516 -29.693848) (xy 18.607926 -29.851586) (xy 18.624443 -30.010345)
			(xy 18.633025 -30.16973) (xy 18.633652 -30.329344) (xy 18.626321 -30.488792) (xy 18.611051 -30.647675)
			(xy 18.587881 -30.8056) (xy 18.58385 -30.825948) (xy 108.093256 -30.825948) (xy 108.093256 -30.169612)
			(xy 108.093794 -30.159509) (xy 108.101519 -30.14084) (xy 108.1158 -30.126546) (xy 108.134462 -30.118803)
			(xy 108.144564 -30.118304) (xy 108.652818 -30.118304) (xy 108.662941 -30.118811) (xy 108.681656 -30.126538)
			(xy 108.688957 -30.1338) (xy 197.595716 -30.1338) (xy 197.599747 -30.049172) (xy 197.611805 -29.965311)
			(xy 197.631779 -29.882976) (xy 197.65949 -29.802912) (xy 197.694686 -29.725844) (xy 197.737048 -29.652472)
			(xy 197.786193 -29.583458) (xy 197.841676 -29.519429) (xy 197.902994 -29.460963) (xy 197.969592 -29.408591)
			(xy 198.040866 -29.362787) (xy 198.116172 -29.323965) (xy 198.194827 -29.292477) (xy 198.276119 -29.268609)
			(xy 198.359312 -29.252576) (xy 198.443652 -29.244524) (xy 198.486014 -29.244036) (xy 198.524304 -29.244437)
			(xy 198.600598 -29.251046) (xy 198.676041 -29.264197) (xy 198.750071 -29.283791) (xy 198.786242 -29.29636)
			(xy 198.794679 -29.299011) (xy 198.812349 -29.299011) (xy 198.820786 -29.29636) (xy 198.856961 -29.283808)
			(xy 198.930995 -29.264238) (xy 199.006435 -29.251093) (xy 199.082726 -29.244471) (xy 199.121014 -29.244036)
			(xy 199.159304 -29.244437) (xy 199.235598 -29.251046) (xy 199.311041 -29.264197) (xy 199.385071 -29.283791)
			(xy 199.421242 -29.29636) (xy 199.429679 -29.299011) (xy 199.447349 -29.299011) (xy 199.455786 -29.29636)
			(xy 199.491961 -29.283808) (xy 199.565995 -29.264238) (xy 199.641435 -29.251093) (xy 199.717726 -29.244471)
			(xy 199.756014 -29.244036) (xy 199.794304 -29.244437) (xy 199.870598 -29.251046) (xy 199.946041 -29.264197)
			(xy 200.020071 -29.283791) (xy 200.056242 -29.29636) (xy 200.064679 -29.299011) (xy 200.082349 -29.299011)
			(xy 200.090786 -29.29636) (xy 200.126961 -29.283808) (xy 200.200995 -29.264238) (xy 200.276435 -29.251093)
			(xy 200.352726 -29.244471) (xy 200.391014 -29.244036) (xy 200.431702 -29.244422) (xy 200.512738 -29.251848)
			(xy 200.592757 -29.266645) (xy 200.67109 -29.288689) (xy 200.747082 -29.317797) (xy 200.820096 -29.353725)
			(xy 200.889524 -29.396173) (xy 200.954784 -29.444785) (xy 201.015331 -29.499155) (xy 201.070657 -29.558829)
			(xy 201.120302 -29.623307) (xy 201.163849 -29.69205) (xy 201.200934 -29.764484) (xy 201.216514 -29.802074)
			(xy 201.22098 -29.811942) (xy 201.236608 -29.826918) (xy 201.256995 -29.83419) (xy 201.267822 -29.833824)
			(xy 201.286077 -29.832403) (xy 201.322664 -29.83088) (xy 201.340974 -29.830776) (xy 201.383338 -29.831187)
			(xy 201.467682 -29.839239) (xy 201.550879 -29.855272) (xy 201.632176 -29.87914) (xy 201.710835 -29.910629)
			(xy 201.786145 -29.949452) (xy 201.857423 -29.995258) (xy 201.924025 -30.047632) (xy 201.985346 -30.1061)
			(xy 202.040832 -30.170132) (xy 202.08998 -30.239149) (xy 202.132344 -30.312525) (xy 202.167542 -30.389596)
			(xy 202.195254 -30.469663) (xy 202.21523 -30.552003) (xy 202.227288 -30.635868) (xy 202.23132 -30.7205)
			(xy 202.227288 -30.805132) (xy 202.21523 -30.888997) (xy 202.195254 -30.971337) (xy 202.167542 -31.051404)
			(xy 202.132344 -31.128475) (xy 202.08998 -31.201851) (xy 202.040832 -31.270868) (xy 201.985346 -31.3349)
			(xy 201.924025 -31.393368) (xy 201.857423 -31.445742) (xy 201.786145 -31.491548) (xy 201.710835 -31.530371)
			(xy 201.632176 -31.56186) (xy 201.550879 -31.585728) (xy 201.467682 -31.601761) (xy 201.383338 -31.609813)
			(xy 201.340974 -31.6103) (xy 201.302684 -31.609905) (xy 201.226389 -31.603295) (xy 201.150947 -31.590142)
			(xy 201.076917 -31.570546) (xy 201.040746 -31.557976) (xy 201.032309 -31.555325) (xy 201.014639 -31.555325)
			(xy 201.006202 -31.557976) (xy 200.970027 -31.570528) (xy 200.895993 -31.590099) (xy 200.820553 -31.603244)
			(xy 200.744262 -31.609866) (xy 200.705974 -31.6103) (xy 200.667684 -31.609905) (xy 200.591389 -31.603295)
			(xy 200.515947 -31.590142) (xy 200.441917 -31.570546) (xy 200.405746 -31.557976) (xy 200.397309 -31.555325)
			(xy 200.379639 -31.555325) (xy 200.371202 -31.557976) (xy 200.335027 -31.570528) (xy 200.260993 -31.590099)
			(xy 200.185553 -31.603244) (xy 200.109262 -31.609866) (xy 200.070974 -31.6103) (xy 200.032684 -31.609905)
			(xy 199.956389 -31.603295) (xy 199.880947 -31.590142) (xy 199.806917 -31.570546) (xy 199.770746 -31.557976)
			(xy 199.762309 -31.555325) (xy 199.744639 -31.555325) (xy 199.736202 -31.557976) (xy 199.700027 -31.570528)
			(xy 199.625993 -31.590099) (xy 199.550553 -31.603244) (xy 199.474262 -31.609866) (xy 199.435974 -31.6103)
			(xy 199.395288 -31.609814) (xy 199.314256 -31.602396) (xy 199.23424 -31.587608) (xy 199.15591 -31.565572)
			(xy 199.07992 -31.536472) (xy 199.006906 -31.500553) (xy 198.937478 -31.458114) (xy 198.872217 -31.40951)
			(xy 198.81167 -31.355148) (xy 198.756341 -31.295482) (xy 198.706694 -31.231012) (xy 198.663144 -31.162275)
			(xy 198.626056 -31.089848) (xy 198.610474 -31.052262) (xy 198.605924 -31.042441) (xy 198.590335 -31.027459)
			(xy 198.569982 -31.020164) (xy 198.559166 -31.020512) (xy 198.540911 -31.021927) (xy 198.504324 -31.023454)
			(xy 198.486014 -31.02356) (xy 198.443652 -31.023076) (xy 198.359312 -31.015024) (xy 198.276119 -30.998991)
			(xy 198.194827 -30.975123) (xy 198.116172 -30.943635) (xy 198.040866 -30.904813) (xy 197.969592 -30.859009)
			(xy 197.902994 -30.806637) (xy 197.841676 -30.748171) (xy 197.786193 -30.684142) (xy 197.737048 -30.615128)
			(xy 197.694686 -30.541756) (xy 197.65949 -30.464688) (xy 197.631779 -30.384624) (xy 197.611805 -30.302289)
			(xy 197.599747 -30.218428) (xy 197.595716 -30.1338) (xy 108.688957 -30.1338) (xy 108.696011 -30.140817)
			(xy 108.703836 -30.159491) (xy 108.70438 -30.169612) (xy 108.70438 -30.825948) (xy 108.703954 -30.836062)
			(xy 108.696196 -30.854745) (xy 108.681881 -30.869039) (xy 108.663187 -30.876769) (xy 108.653072 -30.877256)
			(xy 108.144818 -30.877256) (xy 108.134692 -30.876759) (xy 108.11597 -30.869036) (xy 108.101613 -30.854753)
			(xy 108.093794 -30.836071) (xy 108.093256 -30.825948) (xy 18.58385 -30.825948) (xy 18.556867 -30.962174)
			(xy 18.518086 -31.117007) (xy 18.471636 -31.269714) (xy 18.417631 -31.419917) (xy 18.356206 -31.56724)
			(xy 18.287514 -31.711318) (xy 18.211725 -31.851793) (xy 18.129028 -31.988316) (xy 18.039629 -32.120546)
			(xy 17.943749 -32.248156) (xy 17.841627 -32.370828) (xy 17.733517 -32.488256) (xy 17.619688 -32.60015)
			(xy 17.500423 -32.70623) (xy 17.376019 -32.806234) (xy 17.246784 -32.899911) (xy 17.173557 -32.94761)
			(xy 102.642416 -32.94761) (xy 102.642416 -31.95701) (xy 102.642902 -31.929759) (xy 102.650658 -31.875811)
			(xy 102.666013 -31.823516) (xy 102.688655 -31.773939) (xy 102.718121 -31.728089) (xy 102.753812 -31.686898)
			(xy 102.795003 -31.651207) (xy 102.840853 -31.621741) (xy 102.89043 -31.599099) (xy 102.942725 -31.583744)
			(xy 102.996673 -31.575988) (xy 103.051175 -31.575988) (xy 103.105123 -31.583744) (xy 103.157418 -31.599099)
			(xy 103.206995 -31.621741) (xy 103.252845 -31.651207) (xy 103.294036 -31.686898) (xy 103.329727 -31.728089)
			(xy 103.359193 -31.773939) (xy 103.381835 -31.823516) (xy 103.39719 -31.875811) (xy 103.404946 -31.929759)
			(xy 103.405432 -31.95701) (xy 103.405432 -32.131254) (xy 103.80726 -32.131254) (xy 103.80726 -31.978854)
			(xy 103.807673 -31.966735) (xy 103.815175 -31.943686) (xy 103.829432 -31.924084) (xy 103.849047 -31.909844)
			(xy 103.872102 -31.902362) (xy 103.884222 -31.901892) (xy 104.112822 -31.901892) (xy 104.124933 -31.902392)
			(xy 104.147969 -31.90988) (xy 104.167567 -31.924116) (xy 104.181809 -31.943709) (xy 104.189304 -31.966743)
			(xy 104.189784 -31.978854) (xy 104.189784 -32.131254) (xy 104.189301 -32.143372) (xy 104.181824 -32.166426)
			(xy 104.167588 -32.18604) (xy 104.147987 -32.200293) (xy 104.12494 -32.207791) (xy 104.112822 -32.208216)
			(xy 103.884222 -32.208216) (xy 103.872096 -32.207821) (xy 103.84903 -32.200329) (xy 103.82941 -32.186072)
			(xy 103.81516 -32.166449) (xy 103.807676 -32.14338) (xy 103.80726 -32.131254) (xy 103.405432 -32.131254)
			(xy 103.405432 -32.405066) (xy 105.659936 -32.405066) (xy 105.659936 -31.541466) (xy 105.660422 -31.514215)
			(xy 105.668178 -31.460267) (xy 105.683533 -31.407972) (xy 105.706175 -31.358395) (xy 105.735641 -31.312545)
			(xy 105.771332 -31.271354) (xy 105.812523 -31.235663) (xy 105.858373 -31.206197) (xy 105.90795 -31.183555)
			(xy 105.960245 -31.1682) (xy 106.014193 -31.160444) (xy 106.068695 -31.160444) (xy 106.122643 -31.1682)
			(xy 106.174938 -31.183555) (xy 106.224515 -31.206197) (xy 106.270365 -31.235663) (xy 106.311556 -31.271354)
			(xy 106.347247 -31.312545) (xy 106.376713 -31.358395) (xy 106.399355 -31.407972) (xy 106.41471 -31.460267)
			(xy 106.422466 -31.514215) (xy 106.422952 -31.541466) (xy 106.422952 -32.326072) (xy 108.093256 -32.326072)
			(xy 108.093256 -31.669736) (xy 108.093814 -31.659635) (xy 108.101531 -31.640966) (xy 108.115806 -31.626672)
			(xy 108.134464 -31.618928) (xy 108.144564 -31.618428) (xy 108.652818 -31.618428) (xy 108.662944 -31.618911)
			(xy 108.681664 -31.626643) (xy 108.696019 -31.64093) (xy 108.70384 -31.659612) (xy 108.70438 -31.669736)
			(xy 108.70438 -32.17926) (xy 139.770612 -32.17926) (xy 139.770612 -30.27426) (xy 139.77103 -30.262181)
			(xy 139.778506 -30.239209) (xy 139.792714 -30.219671) (xy 139.812263 -30.205479) (xy 139.835241 -30.198021)
			(xy 139.84732 -30.197552) (xy 140.20292 -30.197552) (xy 140.214992 -30.198047) (xy 140.237953 -30.20551)
			(xy 140.257486 -30.2197) (xy 140.271681 -30.239229) (xy 140.27915 -30.262189) (xy 140.279628 -30.27426)
			(xy 140.279628 -30.400244) (xy 140.280009 -30.409548) (xy 140.286594 -30.426947) (xy 140.29898 -30.440828)
			(xy 140.30706 -30.445456) (xy 140.400024 -30.493462) (xy 140.428218 -30.49143) (xy 140.439902 -30.483302)
			(xy 140.464191 -30.466805) (xy 140.516771 -30.440678) (xy 140.572737 -30.422926) (xy 140.630763 -30.413969)
			(xy 140.66012 -30.413452) (xy 140.689474 -30.414007) (xy 140.747492 -30.422979) (xy 140.803454 -30.440723)
			(xy 140.856041 -30.466822) (xy 140.880338 -30.483302) (xy 140.892022 -30.49143) (xy 140.920216 -30.493462)
			(xy 141.01318 -30.445456) (xy 141.021246 -30.440821) (xy 141.033591 -30.426918) (xy 141.040201 -30.40954)
			(xy 141.040612 -30.400244) (xy 141.040612 -30.27426) (xy 141.04103 -30.262181) (xy 141.048506 -30.239209)
			(xy 141.062714 -30.219671) (xy 141.082263 -30.205479) (xy 141.105241 -30.198021) (xy 141.11732 -30.197552)
			(xy 141.47292 -30.197552) (xy 141.484992 -30.198047) (xy 141.507953 -30.20551) (xy 141.527486 -30.2197)
			(xy 141.541681 -30.239229) (xy 141.54915 -30.262189) (xy 141.549628 -30.27426) (xy 141.549628 -32.13989)
			(xy 144.108932 -32.13989) (xy 144.108932 -30.23489) (xy 144.109399 -30.222801) (xy 144.116857 -30.199801)
			(xy 144.131044 -30.180222) (xy 144.150577 -30.165972) (xy 144.173552 -30.158439) (xy 144.18564 -30.157928)
			(xy 144.54124 -30.157928) (xy 144.553354 -30.158283) (xy 144.576387 -30.165797) (xy 144.595962 -30.180073)
			(xy 144.610154 -30.199709) (xy 144.617569 -30.222775) (xy 144.617948 -30.23489) (xy 144.617948 -30.418024)
			(xy 144.618333 -30.427328) (xy 144.624914 -30.444728) (xy 144.6373 -30.458608) (xy 144.64538 -30.463236)
			(xy 144.738344 -30.511242) (xy 144.766538 -30.50921) (xy 144.778222 -30.501082) (xy 144.802504 -30.484574)
			(xy 144.855087 -30.458451) (xy 144.911055 -30.440702) (xy 144.969082 -30.431748) (xy 144.99844 -30.431232)
			(xy 145.027794 -30.431781) (xy 145.085812 -30.440755) (xy 145.141774 -30.458501) (xy 145.194361 -30.484601)
			(xy 145.218658 -30.501082) (xy 145.230342 -30.50921) (xy 145.258536 -30.511242) (xy 145.3515 -30.463236)
			(xy 145.359536 -30.458555) (xy 145.371883 -30.444671) (xy 145.378509 -30.427313) (xy 145.378932 -30.418024)
			(xy 145.378932 -30.23489) (xy 145.379399 -30.222801) (xy 145.386857 -30.199801) (xy 145.401044 -30.180222)
			(xy 145.420577 -30.165972) (xy 145.443552 -30.158439) (xy 145.45564 -30.157928) (xy 145.81124 -30.157928)
			(xy 145.823354 -30.158283) (xy 145.846387 -30.165797) (xy 145.865962 -30.180073) (xy 145.880154 -30.199709)
			(xy 145.887569 -30.222775) (xy 145.887948 -30.23489) (xy 145.887948 -32.13989) (xy 145.887484 -32.15198)
			(xy 145.880028 -32.174982) (xy 145.865841 -32.194564) (xy 145.846307 -32.208814) (xy 145.823329 -32.216344)
			(xy 145.81124 -32.216852) (xy 145.45564 -32.216852) (xy 145.443538 -32.21635) (xy 145.420521 -32.208868)
			(xy 145.400952 -32.194627) (xy 145.386754 -32.175026) (xy 145.379323 -32.151992) (xy 145.378932 -32.13989)
			(xy 145.378932 -32.071056) (xy 145.378571 -32.06175) (xy 145.371981 -32.044347) (xy 145.359584 -32.030469)
			(xy 145.3515 -32.025844) (xy 145.258536 -31.977838) (xy 145.230342 -31.97987) (xy 145.218658 -31.987998)
			(xy 145.19438 -32.004512) (xy 145.141796 -32.030635) (xy 145.085827 -32.048382) (xy 145.027798 -32.057334)
			(xy 144.99844 -32.057848) (xy 144.969085 -32.057313) (xy 144.911067 -32.048335) (xy 144.855105 -32.030585)
			(xy 144.802518 -32.004481) (xy 144.778222 -31.987998) (xy 144.766538 -31.97987) (xy 144.738344 -31.977838)
			(xy 144.64538 -32.025844) (xy 144.637305 -32.030466) (xy 144.624965 -32.044377) (xy 144.618358 -32.061759)
			(xy 144.617948 -32.071056) (xy 144.617948 -32.13989) (xy 144.617484 -32.15198) (xy 144.610028 -32.174982)
			(xy 144.595841 -32.194564) (xy 144.576307 -32.208814) (xy 144.553329 -32.216344) (xy 144.54124 -32.216852)
			(xy 144.18564 -32.216852) (xy 144.173538 -32.21635) (xy 144.150521 -32.208868) (xy 144.130952 -32.194627)
			(xy 144.116754 -32.175026) (xy 144.109323 -32.151992) (xy 144.108932 -32.13989) (xy 141.549628 -32.13989)
			(xy 141.549628 -32.17926) (xy 141.549154 -32.191339) (xy 141.541699 -32.214317) (xy 141.527509 -32.233866)
			(xy 141.50797 -32.248072) (xy 141.484998 -32.255544) (xy 141.47292 -32.255968) (xy 141.11732 -32.255968)
			(xy 141.105234 -32.25557) (xy 141.082246 -32.248103) (xy 141.062692 -32.233894) (xy 141.048488 -32.214337)
			(xy 141.041027 -32.191346) (xy 141.040612 -32.17926) (xy 141.040612 -32.053276) (xy 141.040196 -32.043976)
			(xy 141.033624 -32.02658) (xy 141.021252 -32.012697) (xy 141.01318 -32.008064) (xy 140.920216 -31.960058)
			(xy 140.892022 -31.96209) (xy 140.880338 -31.970218) (xy 140.856039 -31.9867) (xy 140.803462 -32.012829)
			(xy 140.7475 -32.030585) (xy 140.689476 -32.039548) (xy 140.66012 -32.040068) (xy 140.630765 -32.039539)
			(xy 140.572746 -32.030559) (xy 140.516785 -32.012807) (xy 140.464198 -31.986701) (xy 140.439902 -31.970218)
			(xy 140.428218 -31.96209) (xy 140.400024 -31.960058) (xy 140.30706 -32.008064) (xy 140.299016 -32.012732)
			(xy 140.286674 -32.026623) (xy 140.280051 -32.043986) (xy 140.279628 -32.053276) (xy 140.279628 -32.17926)
			(xy 140.279154 -32.191339) (xy 140.271699 -32.214317) (xy 140.257509 -32.233866) (xy 140.23797 -32.248072)
			(xy 140.214998 -32.255544) (xy 140.20292 -32.255968) (xy 139.84732 -32.255968) (xy 139.835234 -32.25557)
			(xy 139.812246 -32.248103) (xy 139.792692 -32.233894) (xy 139.778488 -32.214337) (xy 139.771027 -32.191346)
			(xy 139.770612 -32.17926) (xy 108.70438 -32.17926) (xy 108.70438 -32.326072) (xy 108.703961 -32.336195)
			(xy 108.696218 -32.354902) (xy 108.681902 -32.369218) (xy 108.663195 -32.376961) (xy 108.653072 -32.37738)
			(xy 108.144818 -32.37738) (xy 108.134695 -32.376859) (xy 108.115978 -32.369141) (xy 108.101622 -32.354866)
			(xy 108.093798 -32.336192) (xy 108.093256 -32.326072) (xy 106.422952 -32.326072) (xy 106.422952 -32.405066)
			(xy 106.422466 -32.432317) (xy 106.41471 -32.486265) (xy 106.399355 -32.53856) (xy 106.376713 -32.588137)
			(xy 106.347247 -32.633987) (xy 106.311556 -32.675178) (xy 106.270365 -32.710869) (xy 106.224515 -32.740335)
			(xy 106.174938 -32.762977) (xy 106.122643 -32.778332) (xy 106.068695 -32.786088) (xy 106.014193 -32.786088)
			(xy 105.960245 -32.778332) (xy 105.90795 -32.762977) (xy 105.858373 -32.740335) (xy 105.812523 -32.710869)
			(xy 105.771332 -32.675178) (xy 105.735641 -32.633987) (xy 105.706175 -32.588137) (xy 105.683533 -32.53856)
			(xy 105.668178 -32.486265) (xy 105.660422 -32.432317) (xy 105.659936 -32.405066) (xy 103.405432 -32.405066)
			(xy 103.405432 -32.94761) (xy 103.404946 -32.974861) (xy 103.402072 -32.994854) (xy 103.80726 -32.994854)
			(xy 103.80726 -32.842454) (xy 103.807673 -32.830335) (xy 103.815175 -32.807286) (xy 103.829432 -32.787684)
			(xy 103.849047 -32.773444) (xy 103.872102 -32.765962) (xy 103.884222 -32.765492) (xy 104.112822 -32.765492)
			(xy 104.124933 -32.765992) (xy 104.147969 -32.77348) (xy 104.167567 -32.787716) (xy 104.181809 -32.807309)
			(xy 104.189304 -32.830343) (xy 104.189784 -32.842454) (xy 104.189784 -32.994854) (xy 104.189301 -33.006972)
			(xy 104.181824 -33.030026) (xy 104.167588 -33.04964) (xy 104.147987 -33.063893) (xy 104.12494 -33.071391)
			(xy 104.112822 -33.071816) (xy 103.884222 -33.071816) (xy 103.872096 -33.071421) (xy 103.84903 -33.063929)
			(xy 103.82941 -33.049672) (xy 103.81516 -33.030049) (xy 103.807676 -33.00698) (xy 103.80726 -32.994854)
			(xy 103.402072 -32.994854) (xy 103.39719 -33.028809) (xy 103.381835 -33.081104) (xy 103.359193 -33.130681)
			(xy 103.329727 -33.176531) (xy 103.294036 -33.217722) (xy 103.252845 -33.253413) (xy 103.206995 -33.282879)
			(xy 103.157418 -33.305521) (xy 103.105123 -33.320876) (xy 103.068995 -33.32607) (xy 108.093256 -33.32607)
			(xy 108.093256 -32.669734) (xy 108.093692 -32.659562) (xy 108.101469 -32.640765) (xy 108.115852 -32.626378)
			(xy 108.134647 -32.618595) (xy 108.144818 -32.618172) (xy 108.652818 -32.618172) (xy 108.662995 -32.61855)
			(xy 108.681797 -32.626347) (xy 108.696182 -32.640747) (xy 108.70396 -32.659557) (xy 108.70438 -32.669734)
			(xy 108.70438 -33.052356) (xy 119.734235 -33.052356) (xy 119.734235 -32.997844) (xy 119.741993 -32.943888)
			(xy 119.757352 -32.891585) (xy 119.779997 -32.842) (xy 119.80947 -32.796143) (xy 119.845169 -32.754947)
			(xy 119.886367 -32.719252) (xy 119.932226 -32.689783) (xy 119.981813 -32.667141) (xy 120.034117 -32.651787)
			(xy 120.088074 -32.644033) (xy 120.11533 -32.643572) (xy 120.97893 -32.643572) (xy 121.006178 -32.6441)
			(xy 121.06012 -32.65186) (xy 121.112408 -32.667217) (xy 121.161979 -32.689858) (xy 121.207823 -32.719324)
			(xy 121.249008 -32.755014) (xy 121.284694 -32.796201) (xy 121.314156 -32.842047) (xy 121.336794 -32.89162)
			(xy 121.352147 -32.943909) (xy 121.359902 -32.997852) (xy 121.359902 -33.052348) (xy 121.352147 -33.106291)
			(xy 121.336794 -33.15858) (xy 121.314156 -33.208153) (xy 121.284694 -33.253999) (xy 121.249008 -33.295186)
			(xy 121.207823 -33.330876) (xy 121.161979 -33.360342) (xy 121.112408 -33.382983) (xy 121.06012 -33.39834)
			(xy 121.006178 -33.4061) (xy 120.97893 -33.406588) (xy 120.11533 -33.406588) (xy 120.088074 -33.406167)
			(xy 120.034117 -33.398413) (xy 119.981813 -33.383059) (xy 119.932226 -33.360417) (xy 119.886367 -33.330948)
			(xy 119.845169 -33.295253) (xy 119.80947 -33.254057) (xy 119.779997 -33.2082) (xy 119.757352 -33.158615)
			(xy 119.741993 -33.106312) (xy 119.734235 -33.052356) (xy 108.70438 -33.052356) (xy 108.70438 -33.32607)
			(xy 108.703912 -33.336237) (xy 108.69614 -33.355028) (xy 108.681768 -33.369413) (xy 108.662985 -33.377202)
			(xy 108.652818 -33.377632) (xy 108.144818 -33.377632) (xy 108.134644 -33.377221) (xy 108.115844 -33.369436)
			(xy 108.101457 -33.355046) (xy 108.093677 -33.336244) (xy 108.093256 -33.32607) (xy 103.068995 -33.32607)
			(xy 103.051175 -33.328632) (xy 102.996673 -33.328632) (xy 102.942725 -33.320876) (xy 102.89043 -33.305521)
			(xy 102.840853 -33.282879) (xy 102.795003 -33.253413) (xy 102.753812 -33.217722) (xy 102.718121 -33.176531)
			(xy 102.688655 -33.130681) (xy 102.666013 -33.081104) (xy 102.650658 -33.028809) (xy 102.642902 -32.974861)
			(xy 102.642416 -32.94761) (xy 17.173557 -32.94761) (xy 17.11304 -32.98703) (xy 16.975119 -33.067374)
			(xy 16.833366 -33.140743) (xy 16.688131 -33.206955) (xy 16.539776 -33.265845) (xy 16.38867 -33.317266)
			(xy 16.235188 -33.361091) (xy 16.079713 -33.397211) (xy 15.922631 -33.425536) (xy 15.764332 -33.445995)
			(xy 15.605209 -33.458538) (xy 15.44566 -33.463134) (xy 15.286079 -33.459771) (xy 15.126865 -33.448457)
			(xy 14.968413 -33.42922) (xy 14.811116 -33.402109) (xy 14.655367 -33.367191) (xy 14.501552 -33.324553)
			(xy 14.350053 -33.2743) (xy 14.201248 -33.216557) (xy 14.055506 -33.151469) (xy 13.91319 -33.079197)
			(xy 13.774653 -32.999921) (xy 13.64024 -32.913837) (xy 13.510286 -32.82116) (xy 13.385112 -32.72212)
			(xy 13.265032 -32.616964) (xy 13.150342 -32.505953) (xy 13.095478 -32.447992) (xy 12.00277 -31.279592)
			(xy 11.948692 -31.220903) (xy 11.845626 -31.099035) (xy 11.748763 -30.972182) (xy 11.658343 -30.840658)
			(xy 11.574591 -30.704792) (xy 11.497716 -30.564919) (xy 11.427907 -30.421388) (xy 11.36534 -30.274557)
			(xy 11.310169 -30.124789) (xy 11.262532 -29.972457) (xy 11.222547 -29.81794) (xy 11.190314 -29.661623)
			(xy 11.165912 -29.503893) (xy 11.149402 -29.345143) (xy 11.140826 -29.185767) (xy 11.140205 -29.026161)
			(xy 0.509016 -29.026161) (xy 0.509016 -33.838388) (xy 122.111008 -33.838388) (xy 122.111008 -32.974788)
			(xy 122.111494 -32.947519) (xy 122.119256 -32.893535) (xy 122.134621 -32.841205) (xy 122.157278 -32.791595)
			(xy 122.186764 -32.745714) (xy 122.222479 -32.704497) (xy 122.263696 -32.668782) (xy 122.309577 -32.639296)
			(xy 122.359187 -32.616639) (xy 122.411517 -32.601274) (xy 122.465501 -32.593512) (xy 122.520039 -32.593512)
			(xy 122.574023 -32.601274) (xy 122.626353 -32.616639) (xy 122.675963 -32.639296) (xy 122.721844 -32.668782)
			(xy 122.763061 -32.704497) (xy 122.798776 -32.745714) (xy 122.828262 -32.791595) (xy 122.850919 -32.841205)
			(xy 122.866284 -32.893535) (xy 122.874046 -32.947519) (xy 122.874532 -32.974788) (xy 122.874532 -33.838388)
			(xy 122.874046 -33.865657) (xy 122.866284 -33.919641) (xy 122.850919 -33.971971) (xy 122.828262 -34.021581)
			(xy 122.798776 -34.067462) (xy 122.763061 -34.108679) (xy 122.721844 -34.144394) (xy 122.675963 -34.17388)
			(xy 122.626353 -34.196537) (xy 122.617733 -34.199068) (xy 123.959112 -34.199068) (xy 123.959112 -33.843468)
			(xy 123.959537 -33.83139) (xy 123.967011 -33.808418) (xy 123.981217 -33.78888) (xy 124.000765 -33.774687)
			(xy 124.023741 -33.767229) (xy 124.03582 -33.76676) (xy 124.161804 -33.76676) (xy 124.171112 -33.766428)
			(xy 124.188515 -33.759822) (xy 124.202392 -33.747416) (xy 124.207016 -33.739328) (xy 124.255022 -33.646364)
			(xy 124.25299 -33.61817) (xy 124.244862 -33.606486) (xy 124.228355 -33.582203) (xy 124.202232 -33.52962)
			(xy 124.184483 -33.473653) (xy 124.175528 -33.415626) (xy 124.175012 -33.386268) (xy 124.175569 -33.356914)
			(xy 124.184541 -33.298897) (xy 124.202285 -33.242935) (xy 124.228383 -33.190347) (xy 124.244862 -33.16605)
			(xy 124.25299 -33.154366) (xy 124.255022 -33.126172) (xy 124.207016 -33.033208) (xy 124.202346 -33.025165)
			(xy 124.188457 -33.012818) (xy 124.171095 -33.006196) (xy 124.161804 -33.005776) (xy 124.03582 -33.005776)
			(xy 124.023735 -33.00537) (xy 124.000748 -32.997904) (xy 123.981194 -32.983697) (xy 123.966991 -32.964142)
			(xy 123.959528 -32.941153) (xy 123.959112 -32.929068) (xy 123.959112 -32.573468) (xy 123.959537 -32.56139)
			(xy 123.967011 -32.538418) (xy 123.981217 -32.51888) (xy 124.000765 -32.504687) (xy 124.023741 -32.497229)
			(xy 124.03582 -32.49676) (xy 125.94082 -32.49676) (xy 125.952892 -32.497247) (xy 125.975855 -32.504711)
			(xy 125.995389 -32.518903) (xy 126.009584 -32.538435) (xy 126.017051 -32.561396) (xy 126.017528 -32.573468)
			(xy 126.017528 -32.929068) (xy 126.01706 -32.941147) (xy 126.009604 -32.964125) (xy 125.995411 -32.983674)
			(xy 125.975872 -32.99788) (xy 125.952899 -33.005352) (xy 125.94082 -33.005776) (xy 125.814836 -33.005776)
			(xy 125.805528 -33.006118) (xy 125.788124 -33.012716) (xy 125.774247 -33.02512) (xy 125.769624 -33.033208)
			(xy 125.721618 -33.126172) (xy 125.72365 -33.154366) (xy 125.731778 -33.16605) (xy 125.748293 -33.190327)
			(xy 125.774416 -33.242911) (xy 125.792163 -33.298881) (xy 125.801114 -33.35691) (xy 125.801628 -33.386268)
			(xy 125.8011 -33.415623) (xy 125.792121 -33.473642) (xy 125.774369 -33.529604) (xy 125.748262 -33.58219)
			(xy 125.731778 -33.606486) (xy 125.72365 -33.61817) (xy 125.721618 -33.646364) (xy 125.769624 -33.739328)
			(xy 125.774256 -33.747396) (xy 125.788163 -33.759736) (xy 125.80554 -33.766347) (xy 125.814836 -33.76676)
			(xy 125.94082 -33.76676) (xy 125.952892 -33.767247) (xy 125.975855 -33.774711) (xy 125.995389 -33.788903)
			(xy 126.009584 -33.808435) (xy 126.017051 -33.831396) (xy 126.017528 -33.843468) (xy 126.017528 -34.086038)
			(xy 128.183132 -34.086038) (xy 128.183132 -33.660588) (xy 128.18355 -33.648534) (xy 128.19099 -33.625603)
			(xy 128.205141 -33.606084) (xy 128.224622 -33.591883) (xy 128.247533 -33.584383) (xy 128.259586 -33.58388)
			(xy 129.428494 -33.58388) (xy 129.440587 -33.584313) (xy 129.463594 -33.591773) (xy 129.483178 -33.605967)
			(xy 129.484482 -33.607756) (xy 131.404868 -33.607756) (xy 131.404868 -32.439356) (xy 131.405326 -32.427282)
			(xy 131.412798 -32.404317) (xy 131.426997 -32.384783) (xy 131.446535 -32.370589) (xy 131.469501 -32.363123)
			(xy 131.481576 -32.362648) (xy 131.907026 -32.362648) (xy 131.919118 -32.363085) (xy 131.942121 -32.37055)
			(xy 131.961701 -32.384744) (xy 131.97595 -32.404284) (xy 131.98348 -32.427266) (xy 131.983988 -32.439356)
			(xy 131.983988 -33.607756) (xy 132.20446 -33.607756) (xy 132.20446 -32.439356) (xy 132.204922 -32.427307)
			(xy 132.212362 -32.404387) (xy 132.226503 -32.384876) (xy 132.24597 -32.370672) (xy 132.268867 -32.36316)
			(xy 132.280914 -32.362648) (xy 132.706872 -32.362648) (xy 132.718941 -32.363187) (xy 132.7419 -32.370637)
			(xy 132.761433 -32.384815) (xy 132.77563 -32.404336) (xy 132.783101 -32.427288) (xy 132.78358 -32.439356)
			(xy 132.78358 -33.607756) (xy 132.783149 -33.619839) (xy 132.775691 -33.642825) (xy 132.76149 -33.662379)
			(xy 132.74194 -33.676583) (xy 132.718955 -33.684047) (xy 132.706872 -33.684464) (xy 132.281422 -33.684464)
			(xy 132.269334 -33.683974) (xy 132.246335 -33.676524) (xy 132.226755 -33.662343) (xy 132.212503 -33.642814)
			(xy 132.20497 -33.619842) (xy 132.20446 -33.607756) (xy 131.983988 -33.607756) (xy 131.983502 -33.619805)
			(xy 131.97608 -33.642731) (xy 131.961947 -33.662249) (xy 131.94248 -33.676453) (xy 131.919581 -33.683958)
			(xy 131.907534 -33.684464) (xy 131.481576 -33.684464) (xy 131.469488 -33.684107) (xy 131.446497 -33.676628)
			(xy 131.426943 -33.662409) (xy 131.412741 -33.642842) (xy 131.405282 -33.619845) (xy 131.404868 -33.607756)
			(xy 129.484482 -33.607756) (xy 129.497427 -33.62551) (xy 129.504952 -33.648496) (xy 129.505456 -33.660588)
			(xy 129.505456 -34.086038) (xy 129.505021 -34.098155) (xy 129.497522 -34.121201) (xy 129.483271 -34.140802)
			(xy 129.463661 -34.155042) (xy 129.440611 -34.162528) (xy 129.428494 -34.163) (xy 128.260094 -34.163)
			(xy 128.247983 -34.162494) (xy 128.224946 -34.15501) (xy 128.205348 -34.140775) (xy 128.191105 -34.121183)
			(xy 128.183611 -34.098149) (xy 128.183132 -34.086038) (xy 126.017528 -34.086038) (xy 126.017528 -34.199068)
			(xy 126.01706 -34.211147) (xy 126.009604 -34.234125) (xy 125.995411 -34.253674) (xy 125.975872 -34.26788)
			(xy 125.952899 -34.275352) (xy 125.94082 -34.275776) (xy 124.03582 -34.275776) (xy 124.023735 -34.27537)
			(xy 124.000748 -34.267904) (xy 123.981194 -34.253697) (xy 123.966991 -34.234142) (xy 123.959528 -34.211153)
			(xy 123.959112 -34.199068) (xy 122.617733 -34.199068) (xy 122.574023 -34.211902) (xy 122.520039 -34.219664)
			(xy 122.465501 -34.219664) (xy 122.411517 -34.211902) (xy 122.359187 -34.196537) (xy 122.309577 -34.17388)
			(xy 122.263696 -34.144394) (xy 122.222479 -34.108679) (xy 122.186764 -34.067462) (xy 122.157278 -34.021581)
			(xy 122.134621 -33.971971) (xy 122.119256 -33.919641) (xy 122.111494 -33.865657) (xy 122.111008 -33.838388)
			(xy 0.509016 -33.838388) (xy 0.509016 -36.853368) (xy 121.927112 -36.853368) (xy 121.927112 -36.497768)
			(xy 121.927537 -36.48569) (xy 121.935011 -36.462718) (xy 121.949217 -36.44318) (xy 121.968765 -36.428987)
			(xy 121.991741 -36.421529) (xy 122.00382 -36.42106) (xy 122.121168 -36.42106) (xy 122.130307 -36.420676)
			(xy 122.147424 -36.414266) (xy 122.161197 -36.402252) (xy 122.165872 -36.39439) (xy 122.20829 -36.315396)
			(xy 122.212321 -36.30717) (xy 122.21479 -36.289029) (xy 122.210724 -36.271179) (xy 122.206004 -36.263326)
			(xy 122.191091 -36.239839) (xy 122.16755 -36.18943) (xy 122.151575 -36.136137) (xy 122.143504 -36.081091)
			(xy 122.143508 -36.025456) (xy 122.151587 -35.97041) (xy 122.167569 -35.91712) (xy 122.191117 -35.866714)
			(xy 122.206004 -35.84321) (xy 122.210748 -35.835372) (xy 122.214795 -35.817516) (xy 122.212306 -35.799376)
			(xy 122.20829 -35.79114) (xy 122.165872 -35.712146) (xy 122.161223 -35.704267) (xy 122.147436 -35.692258)
			(xy 122.13031 -35.685852) (xy 122.121168 -35.685476) (xy 122.00382 -35.685476) (xy 121.991735 -35.68507)
			(xy 121.968748 -35.677604) (xy 121.949194 -35.663397) (xy 121.934991 -35.643842) (xy 121.927528 -35.620853)
			(xy 121.927112 -35.608768) (xy 121.927112 -35.253168) (xy 121.927537 -35.24109) (xy 121.935011 -35.218118)
			(xy 121.949217 -35.19858) (xy 121.968765 -35.184387) (xy 121.991741 -35.176929) (xy 122.00382 -35.17646)
			(xy 123.90882 -35.17646) (xy 123.920892 -35.176947) (xy 123.943855 -35.184411) (xy 123.963389 -35.198603)
			(xy 123.977584 -35.218135) (xy 123.985051 -35.241096) (xy 123.985528 -35.253168) (xy 123.985528 -35.286188)
			(xy 128.183132 -35.286188) (xy 128.183132 -34.860738) (xy 128.183592 -34.848618) (xy 128.191073 -34.825561)
			(xy 128.205315 -34.805946) (xy 128.224922 -34.791693) (xy 128.247974 -34.784199) (xy 128.260094 -34.783776)
			(xy 129.428494 -34.783776) (xy 129.44062 -34.784166) (xy 129.463685 -34.791661) (xy 129.483304 -34.805919)
			(xy 129.497554 -34.825543) (xy 129.505039 -34.848612) (xy 129.505456 -34.860738) (xy 129.505456 -35.286188)
			(xy 129.504931 -35.298232) (xy 129.497508 -35.321148) (xy 129.483382 -35.340659) (xy 129.463929 -35.354865)
			(xy 129.441044 -35.362381) (xy 129.429002 -35.362896) (xy 128.260094 -35.362896) (xy 128.248008 -35.362398)
			(xy 128.225013 -35.354944) (xy 128.205436 -35.340764) (xy 128.191185 -35.32124) (xy 128.183647 -35.298272)
			(xy 128.183132 -35.286188) (xy 123.985528 -35.286188) (xy 123.985528 -35.608768) (xy 123.98506 -35.620847)
			(xy 123.977604 -35.643825) (xy 123.963411 -35.663374) (xy 123.943872 -35.67758) (xy 123.920899 -35.685052)
			(xy 123.90882 -35.685476) (xy 123.791472 -35.685476) (xy 123.782333 -35.685849) (xy 123.781296 -35.686238)
			(xy 135.882888 -35.686238) (xy 135.882888 -35.260788) (xy 135.88335 -35.248738) (xy 135.890784 -35.225815)
			(xy 135.904925 -35.2063) (xy 135.924394 -35.192097) (xy 135.947294 -35.184589) (xy 135.959342 -35.18408)
			(xy 137.12825 -35.18408) (xy 137.140341 -35.184551) (xy 137.163347 -35.191998) (xy 137.182931 -35.206183)
			(xy 137.197182 -35.225718) (xy 137.204708 -35.248699) (xy 137.205212 -35.260788) (xy 137.205212 -35.686238)
			(xy 137.204722 -35.69835) (xy 137.19723 -35.721386) (xy 137.182991 -35.740982) (xy 137.163396 -35.755224)
			(xy 137.140361 -35.76272) (xy 137.12825 -35.7632) (xy 135.95985 -35.7632) (xy 135.947737 -35.762731)
			(xy 135.924698 -35.755235) (xy 135.905101 -35.740991) (xy 135.890859 -35.721391) (xy 135.883367 -35.698351)
			(xy 135.882888 -35.686238) (xy 123.781296 -35.686238) (xy 123.765219 -35.69227) (xy 123.751445 -35.704285)
			(xy 123.746768 -35.712146) (xy 123.70435 -35.79114) (xy 123.700377 -35.79939) (xy 123.697893 -35.817514)
			(xy 123.701932 -35.835356) (xy 123.706636 -35.84321) (xy 123.721495 -35.86673) (xy 123.745044 -35.917131)
			(xy 123.761027 -35.970417) (xy 123.769106 -36.025458) (xy 123.76911 -36.081089) (xy 123.761039 -36.136131)
			(xy 123.745063 -36.189419) (xy 123.721521 -36.239823) (xy 123.706636 -36.263326) (xy 123.701941 -36.271189)
			(xy 123.697874 -36.28903) (xy 123.700344 -36.307162) (xy 123.70435 -36.315396) (xy 123.746768 -36.39439)
			(xy 123.751476 -36.402229) (xy 123.765235 -36.414249) (xy 123.782338 -36.420673) (xy 123.791472 -36.42106)
			(xy 123.90882 -36.42106) (xy 123.920892 -36.421547) (xy 123.943855 -36.429011) (xy 123.963389 -36.443203)
			(xy 123.977584 -36.462735) (xy 123.985051 -36.485696) (xy 123.985528 -36.497768) (xy 123.985528 -36.853368)
			(xy 123.98506 -36.865447) (xy 123.978347 -36.886134) (xy 135.882888 -36.886134) (xy 135.882888 -36.460684)
			(xy 135.883346 -36.448634) (xy 135.890782 -36.42571) (xy 135.904924 -36.406196) (xy 135.924393 -36.391993)
			(xy 135.947294 -36.384485) (xy 135.959342 -36.383976) (xy 137.12825 -36.383976) (xy 137.140341 -36.384451)
			(xy 137.163346 -36.391898) (xy 137.18293 -36.406081) (xy 137.197181 -36.425616) (xy 137.204707 -36.448595)
			(xy 137.205212 -36.460684) (xy 137.205212 -36.886134) (xy 137.204718 -36.898245) (xy 137.197228 -36.921281)
			(xy 137.18299 -36.940878) (xy 137.163396 -36.95512) (xy 137.140361 -36.962616) (xy 137.12825 -36.963096)
			(xy 135.95985 -36.963096) (xy 135.947736 -36.962631) (xy 135.924697 -36.955135) (xy 135.905099 -36.940889)
			(xy 135.890858 -36.921289) (xy 135.883366 -36.898248) (xy 135.882888 -36.886134) (xy 123.978347 -36.886134)
			(xy 123.977604 -36.888425) (xy 123.963411 -36.907974) (xy 123.943872 -36.92218) (xy 123.920899 -36.929652)
			(xy 123.90882 -36.930076) (xy 122.00382 -36.930076) (xy 121.991735 -36.92967) (xy 121.968748 -36.922204)
			(xy 121.949194 -36.907997) (xy 121.934991 -36.888442) (xy 121.927528 -36.865453) (xy 121.927112 -36.853368)
			(xy 0.509016 -36.853368) (xy 0.509016 -39.23137) (xy 9.080235 -39.23137) (xy 9.080235 -39.10223)
			(xy 9.088185 -38.973335) (xy 9.104055 -38.845175) (xy 9.127784 -38.718234) (xy 9.159283 -38.592995)
			(xy 9.198432 -38.469932) (xy 9.245083 -38.349513) (xy 9.299058 -38.232194) (xy 9.360153 -38.11842)
			(xy 9.428136 -38.008623) (xy 9.50275 -37.90322) (xy 9.583711 -37.80261) (xy 9.670711 -37.707175)
			(xy 9.763422 -37.617276) (xy 9.861492 -37.533255) (xy 9.964547 -37.455431) (xy 10.072198 -37.384099)
			(xy 10.184037 -37.319529) (xy 10.299638 -37.261967) (xy 10.418563 -37.21163) (xy 10.540362 -37.16871)
			(xy 10.664572 -37.133369) (xy 10.790721 -37.105742) (xy 10.918333 -37.085933) (xy 11.046922 -37.074017)
			(xy 11.176 -37.070041) (xy 11.305078 -37.074017) (xy 11.433667 -37.085933) (xy 11.521898 -37.099629)
			(xy 170.60087 -37.099629) (xy 170.60087 -37.000299) (xy 170.608862 -36.901292) (xy 170.624796 -36.803249)
			(xy 170.648567 -36.706806) (xy 170.680022 -36.612588) (xy 170.718955 -36.521208) (xy 170.765116 -36.433256)
			(xy 170.818204 -36.349304) (xy 170.877875 -36.269895) (xy 170.943743 -36.195546) (xy 171.01538 -36.126738)
			(xy 171.092321 -36.063918) (xy 171.174067 -36.007493) (xy 171.260089 -35.957828) (xy 171.349828 -35.915246)
			(xy 171.442702 -35.880024) (xy 171.53811 -35.852388) (xy 171.635432 -35.83252) (xy 171.734037 -35.820547)
			(xy 171.833286 -35.816548) (xy 171.932535 -35.820547) (xy 172.03114 -35.83252) (xy 172.128462 -35.852388)
			(xy 172.22387 -35.880024) (xy 172.316744 -35.915246) (xy 172.406483 -35.957828) (xy 172.492505 -36.007493)
			(xy 172.574251 -36.063918) (xy 172.651192 -36.126738) (xy 172.722829 -36.195546) (xy 172.788697 -36.269895)
			(xy 172.848368 -36.349304) (xy 172.901456 -36.433256) (xy 172.947617 -36.521208) (xy 172.98655 -36.612588)
			(xy 173.018005 -36.706806) (xy 173.041776 -36.803249) (xy 173.05771 -36.901292) (xy 173.065702 -37.000299)
			(xy 173.066202 -37.049964) (xy 173.065702 -37.099629) (xy 173.05771 -37.198636) (xy 173.041776 -37.296679)
			(xy 173.034033 -37.328094) (xy 197.270624 -37.328094) (xy 197.271107 -37.28698) (xy 197.278695 -37.205103)
			(xy 197.293804 -37.124275) (xy 197.316307 -37.045187) (xy 197.346011 -36.968512) (xy 197.382664 -36.894904)
			(xy 197.425951 -36.824993) (xy 197.475504 -36.759373) (xy 197.5309 -36.698606) (xy 197.591667 -36.643209)
			(xy 197.657286 -36.593655) (xy 197.727197 -36.550367) (xy 197.800804 -36.513715) (xy 197.877479 -36.48401)
			(xy 197.956568 -36.461506) (xy 198.037395 -36.446396) (xy 198.119272 -36.438808) (xy 198.160386 -36.438332)
			(xy 198.203952 -36.438853) (xy 198.290667 -36.447372) (xy 198.376134 -36.464329) (xy 198.459533 -36.489562)
			(xy 198.540065 -36.522829) (xy 198.616958 -36.563811) (xy 198.689475 -36.612116) (xy 198.756921 -36.66728)
			(xy 198.81865 -36.728775) (xy 198.87407 -36.796011) (xy 198.922649 -36.868345) (xy 198.963923 -36.945081)
			(xy 198.997496 -37.025486) (xy 199.010778 -37.066982) (xy 199.013703 -37.075249) (xy 199.024271 -37.089233)
			(xy 199.038923 -37.098854) (xy 199.047354 -37.101272) (xy 199.088321 -37.111837) (xy 199.168226 -37.13965)
			(xy 199.24513 -37.174922) (xy 199.318339 -37.217334) (xy 199.387193 -37.266504) (xy 199.451068 -37.321986)
			(xy 199.509389 -37.383281) (xy 199.529427 -37.408809) (xy 207.619596 -37.408809) (xy 207.619596 -37.324087)
			(xy 207.627649 -37.23975) (xy 207.643683 -37.15656) (xy 207.667551 -37.07527) (xy 207.699039 -36.996618)
			(xy 207.737861 -36.921315) (xy 207.783664 -36.850043) (xy 207.836035 -36.783447) (xy 207.8945 -36.722132)
			(xy 207.958528 -36.666651) (xy 208.02754 -36.617508) (xy 208.10091 -36.575148) (xy 208.177975 -36.539953)
			(xy 208.258037 -36.512244) (xy 208.34037 -36.49227) (xy 208.424229 -36.480213) (xy 208.508854 -36.476182)
			(xy 208.593479 -36.480213) (xy 208.677338 -36.49227) (xy 208.759671 -36.512244) (xy 208.839733 -36.539953)
			(xy 208.916798 -36.575148) (xy 208.990168 -36.617508) (xy 209.05918 -36.666651) (xy 209.123208 -36.722132)
			(xy 209.181673 -36.783447) (xy 209.234044 -36.850043) (xy 209.279847 -36.921315) (xy 209.318669 -36.996618)
			(xy 209.350157 -37.07527) (xy 209.374025 -37.15656) (xy 209.390059 -37.23975) (xy 209.398112 -37.324087)
			(xy 209.398616 -37.366448) (xy 209.398112 -37.408809) (xy 209.390059 -37.493146) (xy 209.374025 -37.576336)
			(xy 209.350157 -37.657626) (xy 209.318669 -37.736278) (xy 209.279847 -37.811581) (xy 209.234044 -37.882853)
			(xy 209.181673 -37.949449) (xy 209.123208 -38.010764) (xy 209.05918 -38.066245) (xy 208.990168 -38.115388)
			(xy 208.916798 -38.157748) (xy 208.839733 -38.192943) (xy 208.759671 -38.220652) (xy 208.677338 -38.240626)
			(xy 208.593479 -38.252683) (xy 208.508854 -38.256715) (xy 208.424229 -38.252683) (xy 208.34037 -38.240626)
			(xy 208.258037 -38.220652) (xy 208.177975 -38.192943) (xy 208.10091 -38.157748) (xy 208.02754 -38.115388)
			(xy 207.958528 -38.066245) (xy 207.8945 -38.010764) (xy 207.836035 -37.949449) (xy 207.783664 -37.882853)
			(xy 207.737861 -37.811581) (xy 207.699039 -37.736278) (xy 207.667551 -37.657626) (xy 207.643683 -37.576336)
			(xy 207.627649 -37.493146) (xy 207.619596 -37.408809) (xy 199.529427 -37.408809) (xy 199.561629 -37.449835)
			(xy 199.607316 -37.521047) (xy 199.646037 -37.596273) (xy 199.677444 -37.674835) (xy 199.701252 -37.756024)
			(xy 199.717247 -37.839106) (xy 199.725284 -37.92333) (xy 199.725788 -37.965634) (xy 199.72532 -38.006748)
			(xy 199.71773 -38.088625) (xy 199.702618 -38.169453) (xy 199.680113 -38.248541) (xy 199.650407 -38.325216)
			(xy 199.613754 -38.398823) (xy 199.570465 -38.468734) (xy 199.520911 -38.534353) (xy 199.465514 -38.595119)
			(xy 199.404746 -38.650516) (xy 199.339127 -38.70007) (xy 199.269216 -38.743357) (xy 199.195608 -38.78001)
			(xy 199.118933 -38.809716) (xy 199.039845 -38.83222) (xy 198.959017 -38.847331) (xy 198.87714 -38.85492)
			(xy 198.836026 -38.855396) (xy 198.792461 -38.854844) (xy 198.705747 -38.846327) (xy 198.620282 -38.829372)
			(xy 198.536884 -38.804141) (xy 198.456353 -38.770876) (xy 198.379461 -38.729896) (xy 198.306944 -38.681594)
			(xy 198.239498 -38.626432) (xy 198.177769 -38.56494) (xy 198.122348 -38.497707) (xy 198.073767 -38.425377)
			(xy 198.032492 -38.348643) (xy 197.998917 -38.26824) (xy 197.985634 -38.226746) (xy 197.982688 -38.218487)
			(xy 197.97213 -38.204501) (xy 197.957486 -38.194877) (xy 197.949058 -38.192456) (xy 197.908101 -38.181857)
			(xy 197.828197 -38.154046) (xy 197.751293 -38.118776) (xy 197.678085 -38.076367) (xy 197.609232 -38.0272)
			(xy 197.545356 -37.97172) (xy 197.487035 -37.910428) (xy 197.434795 -37.843877) (xy 197.389107 -37.772668)
			(xy 197.350384 -37.697444) (xy 197.318976 -37.618885) (xy 197.295165 -37.537699) (xy 197.279169 -37.454619)
			(xy 197.271129 -37.370397) (xy 197.270624 -37.328094) (xy 173.034033 -37.328094) (xy 173.018005 -37.393122)
			(xy 172.98655 -37.48734) (xy 172.947617 -37.57872) (xy 172.901456 -37.666672) (xy 172.848368 -37.750624)
			(xy 172.788697 -37.830033) (xy 172.722829 -37.904382) (xy 172.651192 -37.97319) (xy 172.574251 -38.03601)
			(xy 172.492505 -38.092435) (xy 172.406483 -38.1421) (xy 172.316744 -38.184682) (xy 172.22387 -38.219904)
			(xy 172.128462 -38.24754) (xy 172.03114 -38.267408) (xy 171.932535 -38.279381) (xy 171.833286 -38.283381)
			(xy 171.734037 -38.279381) (xy 171.635432 -38.267408) (xy 171.53811 -38.24754) (xy 171.442702 -38.219904)
			(xy 171.349828 -38.184682) (xy 171.260089 -38.1421) (xy 171.174067 -38.092435) (xy 171.092321 -38.03601)
			(xy 171.01538 -37.97319) (xy 170.943743 -37.904382) (xy 170.877875 -37.830033) (xy 170.818204 -37.750624)
			(xy 170.765116 -37.666672) (xy 170.718955 -37.57872) (xy 170.680022 -37.48734) (xy 170.648567 -37.393122)
			(xy 170.624796 -37.296679) (xy 170.608862 -37.198636) (xy 170.60087 -37.099629) (xy 11.521898 -37.099629)
			(xy 11.561279 -37.105742) (xy 11.687428 -37.133369) (xy 11.811638 -37.16871) (xy 11.933437 -37.21163)
			(xy 12.052362 -37.261967) (xy 12.167963 -37.319529) (xy 12.279802 -37.384099) (xy 12.387453 -37.455431)
			(xy 12.490508 -37.533255) (xy 12.588578 -37.617276) (xy 12.681289 -37.707175) (xy 12.768289 -37.80261)
			(xy 12.84925 -37.90322) (xy 12.923864 -38.008623) (xy 12.991847 -38.11842) (xy 13.052942 -38.232194)
			(xy 13.106917 -38.349513) (xy 13.153568 -38.469932) (xy 13.192717 -38.592995) (xy 13.224216 -38.718234)
			(xy 13.247945 -38.845175) (xy 13.263815 -38.973335) (xy 13.271765 -39.10223) (xy 13.272262 -39.1668)
			(xy 13.271765 -39.23137) (xy 13.263815 -39.360265) (xy 13.256012 -39.423283) (xy 254.45872 -39.423283)
			(xy 254.45872 -39.338561) (xy 254.466773 -39.254224) (xy 254.482807 -39.171034) (xy 254.506675 -39.089744)
			(xy 254.538163 -39.011092) (xy 254.576985 -38.935789) (xy 254.622788 -38.864517) (xy 254.675159 -38.797921)
			(xy 254.733624 -38.736606) (xy 254.797652 -38.681125) (xy 254.866664 -38.631982) (xy 254.940034 -38.589622)
			(xy 255.017099 -38.554427) (xy 255.097161 -38.526718) (xy 255.179494 -38.506744) (xy 255.263353 -38.494687)
			(xy 255.347978 -38.490656) (xy 255.432603 -38.494687) (xy 255.516462 -38.506744) (xy 255.598795 -38.526718)
			(xy 255.678857 -38.554427) (xy 255.755922 -38.589622) (xy 255.829292 -38.631982) (xy 255.898304 -38.681125)
			(xy 255.962332 -38.736606) (xy 256.020797 -38.797921) (xy 256.073168 -38.864517) (xy 256.118971 -38.935789)
			(xy 256.157793 -39.011092) (xy 256.189281 -39.089744) (xy 256.213149 -39.171034) (xy 256.229183 -39.254224)
			(xy 256.237236 -39.338561) (xy 256.23774 -39.380922) (xy 256.237236 -39.423283) (xy 256.229183 -39.50762)
			(xy 256.213149 -39.59081) (xy 256.189281 -39.6721) (xy 256.157793 -39.750752) (xy 256.118971 -39.826055)
			(xy 256.073168 -39.897327) (xy 256.020797 -39.963923) (xy 255.962332 -40.025238) (xy 255.898304 -40.080719)
			(xy 255.829292 -40.129862) (xy 255.755922 -40.172222) (xy 255.678857 -40.207417) (xy 255.598795 -40.235126)
			(xy 255.516462 -40.2551) (xy 255.432603 -40.267157) (xy 255.347978 -40.271189) (xy 255.263353 -40.267157)
			(xy 255.179494 -40.2551) (xy 255.097161 -40.235126) (xy 255.017099 -40.207417) (xy 254.940034 -40.172222)
			(xy 254.866664 -40.129862) (xy 254.797652 -40.080719) (xy 254.733624 -40.025238) (xy 254.675159 -39.963923)
			(xy 254.622788 -39.897327) (xy 254.576985 -39.826055) (xy 254.538163 -39.750752) (xy 254.506675 -39.6721)
			(xy 254.482807 -39.59081) (xy 254.466773 -39.50762) (xy 254.45872 -39.423283) (xy 13.256012 -39.423283)
			(xy 13.247945 -39.488425) (xy 13.224216 -39.615366) (xy 13.192717 -39.740605) (xy 13.153568 -39.863668)
			(xy 13.106917 -39.984087) (xy 13.052942 -40.101406) (xy 12.991847 -40.21518) (xy 12.923864 -40.324977)
			(xy 12.84925 -40.43038) (xy 12.768289 -40.53099) (xy 12.681289 -40.626425) (xy 12.588578 -40.716324)
			(xy 12.490508 -40.800345) (xy 12.413317 -40.858637) (xy 24.936192 -40.858637) (xy 24.936192 -40.773915)
			(xy 24.944245 -40.689578) (xy 24.960279 -40.606388) (xy 24.984147 -40.525098) (xy 25.015635 -40.446446)
			(xy 25.054457 -40.371143) (xy 25.10026 -40.299871) (xy 25.152631 -40.233275) (xy 25.211096 -40.17196)
			(xy 25.275124 -40.116479) (xy 25.344136 -40.067336) (xy 25.417506 -40.024976) (xy 25.494571 -39.989781)
			(xy 25.574633 -39.962072) (xy 25.656966 -39.942098) (xy 25.740825 -39.930041) (xy 25.82545 -39.92601)
			(xy 25.910075 -39.930041) (xy 25.993934 -39.942098) (xy 26.076267 -39.962072) (xy 26.156329 -39.989781)
			(xy 26.233394 -40.024976) (xy 26.306764 -40.067336) (xy 26.375776 -40.116479) (xy 26.439804 -40.17196)
			(xy 26.498269 -40.233275) (xy 26.55064 -40.299871) (xy 26.596443 -40.371143) (xy 26.635265 -40.446446)
			(xy 26.666753 -40.525098) (xy 26.690621 -40.606388) (xy 26.706655 -40.689578) (xy 26.711938 -40.744902)
			(xy 235.083357 -40.744902) (xy 235.087362 -40.656994) (xy 235.099345 -40.569814) (xy 235.119205 -40.484085)
			(xy 235.14678 -40.400517) (xy 235.181839 -40.319803) (xy 235.224092 -40.242611) (xy 235.27319 -40.169582)
			(xy 235.328726 -40.10132) (xy 235.390238 -40.03839) (xy 235.457219 -39.981316) (xy 235.529112 -39.930568)
			(xy 235.605321 -39.886568) (xy 235.685216 -39.849681) (xy 235.768135 -39.820212) (xy 235.85339 -39.798405)
			(xy 235.940274 -39.784441) (xy 236.028068 -39.778435) (xy 236.116045 -39.780439) (xy 236.203475 -39.790434)
			(xy 236.289634 -39.808338) (xy 236.373808 -39.834002) (xy 236.455299 -39.867215) (xy 236.533433 -39.907701)
			(xy 236.607561 -39.955123) (xy 236.677069 -40.00909) (xy 236.741383 -40.069155) (xy 236.799967 -40.134819)
			(xy 236.852338 -40.205538) (xy 236.898061 -40.280726) (xy 236.936758 -40.359761) (xy 236.968107 -40.441987)
			(xy 236.991849 -40.526723) (xy 237.007787 -40.613267) (xy 237.015789 -40.700902) (xy 237.01629 -40.744902)
			(xy 237.015789 -40.788902) (xy 237.007787 -40.876537) (xy 236.994276 -40.9499) (xy 246.935452 -40.9499)
			(xy 246.939482 -40.865295) (xy 246.951537 -40.781456) (xy 246.971506 -40.699142) (xy 246.999209 -40.619099)
			(xy 247.034396 -40.542053) (xy 247.076747 -40.468699) (xy 247.125879 -40.399704) (xy 247.181347 -40.335692)
			(xy 247.242648 -40.277242) (xy 247.309228 -40.224883) (xy 247.380484 -40.179091) (xy 247.45577 -40.14028)
			(xy 247.534404 -40.1088) (xy 247.615675 -40.084938) (xy 247.698846 -40.06891) (xy 247.783163 -40.060859)
			(xy 247.825514 -40.060372) (xy 247.868043 -40.060872) (xy 247.952713 -40.068982) (xy 248.036223 -40.085137)
			(xy 248.11781 -40.109189) (xy 248.196728 -40.140918) (xy 248.272258 -40.180035) (xy 248.343709 -40.226182)
			(xy 248.41043 -40.278938) (xy 248.441464 -40.308022) (xy 248.441718 -40.308276) (xy 248.44904 -40.314652)
			(xy 248.467069 -40.321822) (xy 248.47677 -40.322246) (xy 248.557288 -40.321992) (xy 248.575576 -40.314626)
			(xy 248.582688 -40.307514) (xy 248.613778 -40.278057) (xy 248.680689 -40.224588) (xy 248.752429 -40.177798)
			(xy 248.828335 -40.13812) (xy 248.907704 -40.105923) (xy 248.9898 -40.081504) (xy 249.073863 -40.065089)
			(xy 249.159115 -40.056831) (xy 249.20194 -40.056308) (xy 249.202448 -40.056308) (xy 249.244796 -40.056782)
			(xy 249.329107 -40.064837) (xy 249.412272 -40.08087) (xy 249.493536 -40.104735) (xy 249.572163 -40.136216)
			(xy 249.647442 -40.175029) (xy 249.718691 -40.220821) (xy 249.785265 -40.273178) (xy 249.84656 -40.331627)
			(xy 249.902022 -40.395637) (xy 249.951149 -40.464629) (xy 249.993496 -40.537978) (xy 250.028678 -40.615021)
			(xy 250.056379 -40.695058) (xy 250.076346 -40.777367) (xy 250.088399 -40.8612) (xy 250.092429 -40.9458)
			(xy 250.088399 -41.0304) (xy 250.076346 -41.114233) (xy 250.056379 -41.196542) (xy 250.028678 -41.276579)
			(xy 249.993496 -41.353622) (xy 249.951149 -41.426971) (xy 249.902022 -41.495963) (xy 249.84656 -41.559973)
			(xy 249.785265 -41.618422) (xy 249.718691 -41.670779) (xy 249.647442 -41.716571) (xy 249.572163 -41.755384)
			(xy 249.493536 -41.786865) (xy 249.412272 -41.81073) (xy 249.329107 -41.826763) (xy 249.244796 -41.834818)
			(xy 249.202448 -41.835324) (xy 249.159919 -41.834822) (xy 249.07525 -41.826709) (xy 248.991741 -41.810552)
			(xy 248.910155 -41.7865) (xy 248.831237 -41.754771) (xy 248.755707 -41.715655) (xy 248.684255 -41.66951)
			(xy 248.617533 -41.616756) (xy 248.586498 -41.587674) (xy 248.586244 -41.58742) (xy 248.578903 -41.58107)
			(xy 248.560888 -41.573885) (xy 248.551192 -41.57345) (xy 248.470674 -41.573704) (xy 248.452386 -41.58107)
			(xy 248.445274 -41.588182) (xy 248.414201 -41.617657) (xy 248.347287 -41.671125) (xy 248.275544 -41.717913)
			(xy 248.199635 -41.757589) (xy 248.120264 -41.789784) (xy 248.038166 -41.8142) (xy 247.954101 -41.830612)
			(xy 247.868848 -41.838866) (xy 247.826022 -41.839388) (xy 247.825514 -41.839388) (xy 247.783163 -41.838941)
			(xy 247.698846 -41.83089) (xy 247.615675 -41.814862) (xy 247.534404 -41.791) (xy 247.45577 -41.75952)
			(xy 247.380484 -41.720709) (xy 247.309228 -41.674917) (xy 247.242648 -41.622558) (xy 247.181347 -41.564108)
			(xy 247.125879 -41.500096) (xy 247.076747 -41.431101) (xy 247.034396 -41.357747) (xy 246.999209 -41.280701)
			(xy 246.971506 -41.200658) (xy 246.951537 -41.118344) (xy 246.939482 -41.034505) (xy 246.935452 -40.9499)
			(xy 236.994276 -40.9499) (xy 236.991849 -40.963081) (xy 236.968107 -41.047817) (xy 236.936758 -41.130043)
			(xy 236.898061 -41.209078) (xy 236.852338 -41.284266) (xy 236.799967 -41.354985) (xy 236.741383 -41.420649)
			(xy 236.677069 -41.480714) (xy 236.607561 -41.534681) (xy 236.533433 -41.582103) (xy 236.455299 -41.622589)
			(xy 236.373808 -41.655802) (xy 236.289634 -41.681466) (xy 236.203475 -41.69937) (xy 236.116045 -41.709365)
			(xy 236.028068 -41.711369) (xy 235.940274 -41.705363) (xy 235.85339 -41.691399) (xy 235.768135 -41.669592)
			(xy 235.685216 -41.640123) (xy 235.605321 -41.603236) (xy 235.529112 -41.559236) (xy 235.457219 -41.508488)
			(xy 235.390238 -41.451414) (xy 235.328726 -41.388484) (xy 235.27319 -41.320222) (xy 235.224092 -41.247193)
			(xy 235.181839 -41.170001) (xy 235.14678 -41.089287) (xy 235.119205 -41.005719) (xy 235.099345 -40.91999)
			(xy 235.087362 -40.83281) (xy 235.083357 -40.744902) (xy 26.711938 -40.744902) (xy 26.714708 -40.773915)
			(xy 26.715212 -40.816276) (xy 26.714708 -40.858637) (xy 26.706655 -40.942974) (xy 26.690621 -41.026164)
			(xy 26.666753 -41.107454) (xy 26.635265 -41.186106) (xy 26.596443 -41.261409) (xy 26.55064 -41.332681)
			(xy 26.498269 -41.399277) (xy 26.439804 -41.460592) (xy 26.375776 -41.516073) (xy 26.306764 -41.565216)
			(xy 26.233394 -41.607576) (xy 26.156329 -41.642771) (xy 26.076267 -41.67048) (xy 25.993934 -41.690454)
			(xy 25.910075 -41.702511) (xy 25.82545 -41.706543) (xy 25.740825 -41.702511) (xy 25.656966 -41.690454)
			(xy 25.574633 -41.67048) (xy 25.494571 -41.642771) (xy 25.417506 -41.607576) (xy 25.344136 -41.565216)
			(xy 25.275124 -41.516073) (xy 25.211096 -41.460592) (xy 25.152631 -41.399277) (xy 25.10026 -41.332681)
			(xy 25.054457 -41.261409) (xy 25.015635 -41.186106) (xy 24.984147 -41.107454) (xy 24.960279 -41.026164)
			(xy 24.944245 -40.942974) (xy 24.936192 -40.858637) (xy 12.413317 -40.858637) (xy 12.387453 -40.878169)
			(xy 12.279802 -40.949501) (xy 12.167963 -41.014071) (xy 12.052362 -41.071633) (xy 11.933437 -41.12197)
			(xy 11.811638 -41.16489) (xy 11.687428 -41.200231) (xy 11.561279 -41.227858) (xy 11.433667 -41.247667)
			(xy 11.305078 -41.259583) (xy 11.176 -41.26356) (xy 11.046922 -41.259583) (xy 10.918333 -41.247667)
			(xy 10.790721 -41.227858) (xy 10.664572 -41.200231) (xy 10.540362 -41.16489) (xy 10.418563 -41.12197)
			(xy 10.299638 -41.071633) (xy 10.184037 -41.014071) (xy 10.072198 -40.949501) (xy 9.964547 -40.878169)
			(xy 9.861492 -40.800345) (xy 9.763422 -40.716324) (xy 9.670711 -40.626425) (xy 9.583711 -40.53099)
			(xy 9.50275 -40.43038) (xy 9.428136 -40.324977) (xy 9.360153 -40.21518) (xy 9.299058 -40.101406)
			(xy 9.245083 -39.984087) (xy 9.198432 -39.863668) (xy 9.159283 -39.740605) (xy 9.127784 -39.615366)
			(xy 9.104055 -39.488425) (xy 9.088185 -39.360265) (xy 9.080235 -39.23137) (xy 0.509016 -39.23137)
			(xy 0.509016 -43.481752) (xy 178.630072 -43.481752) (xy 178.630072 -42.618152) (xy 178.630558 -42.590883)
			(xy 178.63832 -42.536899) (xy 178.653685 -42.484569) (xy 178.676342 -42.434959) (xy 178.705828 -42.389078)
			(xy 178.741543 -42.347861) (xy 178.78276 -42.312146) (xy 178.828641 -42.28266) (xy 178.878251 -42.260003)
			(xy 178.930581 -42.244638) (xy 178.984565 -42.236876) (xy 179.039103 -42.236876) (xy 179.093087 -42.244638)
			(xy 179.145417 -42.260003) (xy 179.195027 -42.28266) (xy 179.240908 -42.312146) (xy 179.282125 -42.347861)
			(xy 179.31784 -42.389078) (xy 179.347326 -42.434959) (xy 179.369983 -42.484569) (xy 179.385348 -42.536899)
			(xy 179.39311 -42.590883) (xy 179.393596 -42.618152) (xy 179.393596 -43.481752) (xy 179.39311 -43.509021)
			(xy 179.385348 -43.563005) (xy 179.369983 -43.615335) (xy 179.347326 -43.664945) (xy 179.31784 -43.710826)
			(xy 179.282125 -43.752043) (xy 179.240908 -43.787758) (xy 179.195027 -43.817244) (xy 179.145417 -43.839901)
			(xy 179.093087 -43.855266) (xy 179.039103 -43.863028) (xy 178.984565 -43.863028) (xy 178.930581 -43.855266)
			(xy 178.878251 -43.839901) (xy 178.828641 -43.817244) (xy 178.78276 -43.787758) (xy 178.741543 -43.752043)
			(xy 178.705828 -43.710826) (xy 178.676342 -43.664945) (xy 178.653685 -43.615335) (xy 178.63832 -43.563005)
			(xy 178.630558 -43.509021) (xy 178.630072 -43.481752) (xy 0.509016 -43.481752) (xy 0.509016 -47.04994)
			(xy 59.582066 -47.04994) (xy 59.586045 -46.890389) (xy 59.597972 -46.731234) (xy 59.617818 -46.572872)
			(xy 59.645532 -46.415696) (xy 59.681047 -46.260096) (xy 59.724273 -46.10646) (xy 59.775104 -45.95517)
			(xy 59.833413 -45.806602) (xy 59.899054 -45.661125) (xy 59.971866 -45.519101) (xy 60.051666 -45.380882)
			(xy 60.138257 -45.246813) (xy 60.231423 -45.117227) (xy 60.330933 -44.992446) (xy 60.436538 -44.87278)
			(xy 60.547978 -44.758527) (xy 60.664973 -44.649971) (xy 60.787235 -44.547381) (xy 60.914458 -44.451014)
			(xy 61.046326 -44.361107) (xy 61.182512 -44.277886) (xy 61.322677 -44.201556) (xy 61.466472 -44.132307)
			(xy 61.613541 -44.070313) (xy 61.763517 -44.015726) (xy 61.916027 -43.968683) (xy 62.070693 -43.9293)
			(xy 62.227129 -43.897676) (xy 62.384947 -43.873888) (xy 62.543755 -43.857997) (xy 62.703158 -43.850041)
			(xy 62.782958 -43.849544) (xy 64.382904 -43.849544) (xy 64.462705 -43.850033) (xy 64.622107 -43.857989)
			(xy 64.780916 -43.87388) (xy 64.938734 -43.897668) (xy 65.095171 -43.929293) (xy 65.249837 -43.968675)
			(xy 65.402347 -44.015719) (xy 65.552323 -44.070306) (xy 65.699392 -44.132301) (xy 65.843188 -44.201549)
			(xy 65.983353 -44.277879) (xy 66.119539 -44.361101) (xy 66.251408 -44.451008) (xy 66.378631 -44.547376)
			(xy 66.500893 -44.649966) (xy 66.617889 -44.758522) (xy 66.729328 -44.872775) (xy 66.834934 -44.992442)
			(xy 66.934444 -45.117223) (xy 67.02761 -45.246809) (xy 67.114201 -45.380878) (xy 67.194001 -45.519097)
			(xy 67.266813 -45.661122) (xy 67.332455 -45.806599) (xy 67.390764 -45.955168) (xy 67.441595 -46.106458)
			(xy 67.484821 -46.260094) (xy 67.520336 -46.415694) (xy 67.54805 -46.572871) (xy 67.567896 -46.731233)
			(xy 67.579823 -46.890388) (xy 67.583802 -47.04994) (xy 89.78165 -47.04994) (xy 89.78563 -46.895439)
			(xy 89.797557 -46.741349) (xy 89.817402 -46.588076) (xy 89.84511 -46.436028) (xy 89.880608 -46.285609)
			(xy 89.923803 -46.137216) (xy 89.97458 -45.991243) (xy 90.032804 -45.848078) (xy 90.098321 -45.708101)
			(xy 90.170957 -45.571681) (xy 90.250519 -45.439181) (xy 90.336796 -45.310953) (xy 90.42956 -45.187337)
			(xy 90.528565 -45.068659) (xy 90.633548 -44.955236) (xy 90.74423 -44.847368) (xy 90.860319 -44.74534)
			(xy 90.981506 -44.649424) (xy 91.10747 -44.559873) (xy 91.237877 -44.476926) (xy 91.372381 -44.400801)
			(xy 91.510626 -44.331702) (xy 91.652244 -44.269811) (xy 91.796861 -44.215293) (xy 91.944092 -44.168291)
			(xy 92.093548 -44.128931) (xy 92.244832 -44.097317) (xy 92.397543 -44.073533) (xy 92.551275 -44.057642)
			(xy 92.705622 -44.049686) (xy 92.782898 -44.049188) (xy 94.383098 -44.049188) (xy 94.460374 -44.049669)
			(xy 94.614722 -44.057625) (xy 94.768456 -44.073516) (xy 94.921168 -44.0973) (xy 95.072452 -44.128914)
			(xy 95.221909 -44.168274) (xy 95.369142 -44.215276) (xy 95.513759 -44.269795) (xy 95.655379 -44.331686)
			(xy 95.793624 -44.400785) (xy 95.928129 -44.47691) (xy 96.058537 -44.559858) (xy 96.184502 -44.649409)
			(xy 96.30569 -44.745326) (xy 96.421779 -44.847354) (xy 96.532463 -44.955223) (xy 96.541616 -44.965112)
			(xy 176.307496 -44.965112) (xy 176.307496 -44.13504) (xy 176.307994 -44.122992) (xy 176.315415 -44.100069)
			(xy 176.329546 -44.080553) (xy 176.349009 -44.066348) (xy 176.371904 -44.05884) (xy 176.38395 -44.058332)
			(xy 177.832258 -44.058332) (xy 177.844345 -44.058843) (xy 177.867343 -44.066287) (xy 177.886922 -44.080463)
			(xy 177.901175 -44.099987) (xy 177.908709 -44.122955) (xy 177.90922 -44.13504) (xy 177.90922 -44.965112)
			(xy 177.908751 -44.977161) (xy 177.901317 -45.000083) (xy 177.887178 -45.019597) (xy 177.867711 -45.033801)
			(xy 177.844813 -45.04131) (xy 177.832766 -45.04182) (xy 176.384458 -45.04182) (xy 176.372362 -45.041428)
			(xy 176.349354 -45.033955) (xy 176.329771 -45.01975) (xy 176.315523 -45.000199) (xy 176.307999 -44.977207)
			(xy 176.307496 -44.965112) (xy 96.541616 -44.965112) (xy 96.637446 -45.068647) (xy 96.681178 -45.121068)
			(xy 180.10886 -45.121068) (xy 180.10886 -44.926504) (xy 180.109236 -44.915397) (xy 180.115551 -44.894101)
			(xy 180.121306 -44.884594) (xy 180.313838 -44.5897) (xy 180.319543 -44.580314) (xy 180.325817 -44.559276)
			(xy 180.325817 -44.537321) (xy 180.319542 -44.516282) (xy 180.313838 -44.506896) (xy 180.121306 -44.213272)
			(xy 180.115572 -44.203754) (xy 180.109237 -44.182467) (xy 180.10886 -44.171362) (xy 180.10886 -43.975528)
			(xy 180.109387 -43.963458) (xy 180.116838 -43.940497) (xy 180.13102 -43.920962) (xy 180.150543 -43.906766)
			(xy 180.173498 -43.899297) (xy 180.185568 -43.89882) (xy 180.871368 -43.89882) (xy 180.883452 -43.89924)
			(xy 180.906438 -43.906703) (xy 180.925991 -43.920906) (xy 180.940196 -43.940458) (xy 180.947659 -43.963444)
			(xy 180.948076 -43.975528) (xy 180.948076 -44.170092) (xy 180.947712 -44.181198) (xy 180.941377 -44.20249)
			(xy 180.93563 -44.212002) (xy 180.743098 -44.505626) (xy 180.737353 -44.514986) (xy 180.731026 -44.53601)
			(xy 180.730964 -44.557965) (xy 180.737172 -44.579024) (xy 180.742844 -44.58843) (xy 180.93563 -44.884594)
			(xy 180.941392 -44.894097) (xy 180.947708 -44.915396) (xy 180.948076 -44.926504) (xy 180.948076 -44.980098)
			(xy 181.659784 -44.980098) (xy 181.659784 -44.116498) (xy 181.66027 -44.089229) (xy 181.668032 -44.035245)
			(xy 181.683397 -43.982915) (xy 181.706054 -43.933305) (xy 181.73554 -43.887424) (xy 181.771255 -43.846207)
			(xy 181.812472 -43.810492) (xy 181.858353 -43.781006) (xy 181.907963 -43.758349) (xy 181.960293 -43.742984)
			(xy 182.014277 -43.735222) (xy 182.068815 -43.735222) (xy 182.122799 -43.742984) (xy 182.175129 -43.758349)
			(xy 182.224739 -43.781006) (xy 182.27062 -43.810492) (xy 182.311837 -43.846207) (xy 182.347552 -43.887424)
			(xy 182.377038 -43.933305) (xy 182.399695 -43.982915) (xy 182.412218 -44.025566) (xy 236.740192 -44.025566)
			(xy 236.74068 -43.984453) (xy 236.74827 -43.902577) (xy 236.763381 -43.82175) (xy 236.785886 -43.742663)
			(xy 236.815591 -43.665989) (xy 236.852243 -43.592383) (xy 236.895531 -43.522473) (xy 236.945083 -43.456854)
			(xy 237.000479 -43.396088) (xy 237.061245 -43.340691) (xy 237.126863 -43.291137) (xy 237.196773 -43.247849)
			(xy 237.270378 -43.211196) (xy 237.347052 -43.181489) (xy 237.426139 -43.158984) (xy 237.506965 -43.143872)
			(xy 237.588841 -43.136281) (xy 237.629954 -43.135804) (xy 237.672596 -43.136331) (xy 237.757484 -43.144543)
			(xy 237.841197 -43.160838) (xy 237.922968 -43.185068) (xy 237.962694 -43.200574) (xy 237.971356 -43.203655)
			(xy 237.989722 -43.204046) (xy 237.998508 -43.201336) (xy 238.034032 -43.189272) (xy 238.106663 -43.170452)
			(xy 238.18062 -43.157817) (xy 238.25538 -43.151455) (xy 238.292894 -43.151044) (xy 238.332166 -43.151496)
			(xy 238.410399 -43.158477) (xy 238.487712 -43.172332) (xy 238.563501 -43.192954) (xy 238.600488 -43.206162)
			(xy 238.609037 -43.208926) (xy 238.626991 -43.208926) (xy 238.63554 -43.206162) (xy 238.672533 -43.192975)
			(xy 238.748323 -43.172363) (xy 238.825633 -43.158506) (xy 238.903863 -43.151512) (xy 238.943134 -43.151044)
			(xy 238.981423 -43.151469) (xy 239.057717 -43.158071) (xy 239.133159 -43.171215) (xy 239.207191 -43.190803)
			(xy 239.243362 -43.203368) (xy 239.251799 -43.206019) (xy 239.269469 -43.206019) (xy 239.277906 -43.203368)
			(xy 239.314089 -43.190839) (xy 239.38812 -43.171262) (xy 239.463558 -43.158111) (xy 239.539846 -43.151482)
			(xy 239.578134 -43.151044) (xy 239.616423 -43.151469) (xy 239.692717 -43.158071) (xy 239.768159 -43.171215)
			(xy 239.842191 -43.190803) (xy 239.878362 -43.203368) (xy 239.886799 -43.206019) (xy 239.904469 -43.206019)
			(xy 239.912906 -43.203368) (xy 239.949089 -43.190839) (xy 240.02312 -43.171262) (xy 240.098558 -43.158111)
			(xy 240.174846 -43.151482) (xy 240.213134 -43.151044) (xy 240.25606 -43.151581) (xy 240.341511 -43.159862)
			(xy 240.425768 -43.176335) (xy 240.508046 -43.200846) (xy 240.587581 -43.233168) (xy 240.613613 -43.246802)
			(xy 243.62918 -43.246802) (xy 243.629584 -43.208512) (xy 243.636192 -43.132218) (xy 243.649342 -43.056775)
			(xy 243.668936 -42.982745) (xy 243.681504 -42.946574) (xy 243.684156 -42.938137) (xy 243.684156 -42.920466)
			(xy 243.681504 -42.91203) (xy 243.668959 -42.875853) (xy 243.649386 -42.80182) (xy 243.636239 -42.72638)
			(xy 243.629616 -42.65009) (xy 243.62918 -42.611802) (xy 243.629684 -42.569441) (xy 243.637737 -42.485104)
			(xy 243.653771 -42.401914) (xy 243.677639 -42.320624) (xy 243.709127 -42.241972) (xy 243.747949 -42.166669)
			(xy 243.793752 -42.095397) (xy 243.846123 -42.028801) (xy 243.904588 -41.967486) (xy 243.968616 -41.912005)
			(xy 244.037628 -41.862862) (xy 244.110998 -41.820502) (xy 244.188063 -41.785307) (xy 244.268125 -41.757598)
			(xy 244.350458 -41.737624) (xy 244.434317 -41.725567) (xy 244.518942 -41.721536) (xy 244.603567 -41.725567)
			(xy 244.687426 -41.737624) (xy 244.769759 -41.757598) (xy 244.849821 -41.785307) (xy 244.926886 -41.820502)
			(xy 245.000256 -41.862862) (xy 245.069268 -41.912005) (xy 245.133296 -41.967486) (xy 245.191761 -42.028801)
			(xy 245.244132 -42.095397) (xy 245.289935 -42.166669) (xy 245.328757 -42.241972) (xy 245.360245 -42.320624)
			(xy 245.384113 -42.401914) (xy 245.400147 -42.485104) (xy 245.4082 -42.569441) (xy 245.408704 -42.611802)
			(xy 245.408302 -42.650092) (xy 245.401694 -42.726386) (xy 245.388543 -42.801829) (xy 245.368949 -42.875859)
			(xy 245.35638 -42.91203) (xy 245.353727 -42.920466) (xy 245.353728 -42.938137) (xy 245.35638 -42.946574)
			(xy 245.368926 -42.982751) (xy 245.388499 -43.056784) (xy 245.401645 -43.132224) (xy 245.408269 -43.208514)
			(xy 245.408704 -43.246802) (xy 245.4082 -43.289163) (xy 245.400147 -43.3735) (xy 245.384113 -43.45669)
			(xy 245.360245 -43.53798) (xy 245.328757 -43.616632) (xy 245.289935 -43.691935) (xy 245.244132 -43.763207)
			(xy 245.191761 -43.829803) (xy 245.133296 -43.891118) (xy 245.069268 -43.946599) (xy 245.000256 -43.995742)
			(xy 244.926886 -44.038102) (xy 244.849821 -44.073297) (xy 244.769759 -44.101006) (xy 244.687426 -44.12098)
			(xy 244.603567 -44.133037) (xy 244.518942 -44.137069) (xy 244.434317 -44.133037) (xy 244.350458 -44.12098)
			(xy 244.268125 -44.101006) (xy 244.188063 -44.073297) (xy 244.110998 -44.038102) (xy 244.037628 -43.995742)
			(xy 243.968616 -43.946599) (xy 243.904588 -43.891118) (xy 243.846123 -43.829803) (xy 243.793752 -43.763207)
			(xy 243.747949 -43.691935) (xy 243.709127 -43.616632) (xy 243.677639 -43.53798) (xy 243.653771 -43.45669)
			(xy 243.637737 -43.3735) (xy 243.629684 -43.289163) (xy 243.62918 -43.246802) (xy 240.613613 -43.246802)
			(xy 240.663633 -43.272999) (xy 240.735496 -43.31997) (xy 240.802501 -43.373643) (xy 240.864025 -43.433521)
			(xy 240.919496 -43.499046) (xy 240.968398 -43.569608) (xy 241.010277 -43.644552) (xy 241.044744 -43.723182)
			(xy 241.071477 -43.804765) (xy 241.090229 -43.888544) (xy 241.096038 -43.931078) (xy 241.097792 -43.94092)
			(xy 241.107661 -43.958279) (xy 241.123386 -43.970587) (xy 241.132868 -43.97375) (xy 241.172506 -43.985287)
			(xy 241.249638 -44.014728) (xy 241.32371 -44.051189) (xy 241.394086 -44.094356) (xy 241.460159 -44.143858)
			(xy 241.521362 -44.199269) (xy 241.577167 -44.260112) (xy 241.627095 -44.325864) (xy 241.670716 -44.395959)
			(xy 241.707655 -44.469795) (xy 241.737594 -44.546735) (xy 241.760276 -44.626118) (xy 241.775505 -44.707261)
			(xy 241.78315 -44.789466) (xy 241.783616 -44.830746) (xy 241.783231 -44.871862) (xy 241.775639 -44.953744)
			(xy 241.760525 -45.034576) (xy 241.738017 -45.113668) (xy 241.708307 -45.190346) (xy 241.671649 -45.263956)
			(xy 241.628355 -45.333869) (xy 241.578796 -45.39949) (xy 241.523393 -45.460258) (xy 241.462619 -45.515654)
			(xy 241.396993 -45.565207) (xy 241.327075 -45.608494) (xy 241.253462 -45.645144) (xy 241.176781 -45.674846)
			(xy 241.097686 -45.697346) (xy 241.016853 -45.712452) (xy 240.93497 -45.720035) (xy 240.893854 -45.720508)
			(xy 240.848047 -45.719908) (xy 240.756919 -45.710469) (xy 240.667241 -45.691726) (xy 240.579961 -45.663878)
			(xy 240.537746 -45.646086) (xy 240.528923 -45.642621) (xy 240.509997 -45.641842) (xy 240.500916 -45.644562)
			(xy 240.454475 -45.659757) (xy 240.359116 -45.681105) (xy 240.261993 -45.691873) (xy 240.213134 -45.692568)
			(xy 240.174844 -45.692152) (xy 240.09855 -45.685547) (xy 240.023108 -45.672401) (xy 239.949077 -45.652811)
			(xy 239.912906 -45.640244) (xy 239.904469 -45.637593) (xy 239.886799 -45.637593) (xy 239.878362 -45.640244)
			(xy 239.842183 -45.652782) (xy 239.76815 -45.672357) (xy 239.692711 -45.685505) (xy 239.616422 -45.692131)
			(xy 239.578134 -45.692568) (xy 239.539844 -45.692152) (xy 239.46355 -45.685547) (xy 239.388108 -45.672401)
			(xy 239.314077 -45.652811) (xy 239.277906 -45.640244) (xy 239.269469 -45.637593) (xy 239.251799 -45.637593)
			(xy 239.243362 -45.640244) (xy 239.207183 -45.652782) (xy 239.13315 -45.672357) (xy 239.057711 -45.685505)
			(xy 238.981422 -45.692131) (xy 238.943134 -45.692568) (xy 238.903862 -45.692107) (xy 238.825629 -45.685129)
			(xy 238.748316 -45.671276) (xy 238.672527 -45.650657) (xy 238.63554 -45.63745) (xy 238.626991 -45.634686)
			(xy 238.609037 -45.634686) (xy 238.600488 -45.63745) (xy 238.563502 -45.650659) (xy 238.48771 -45.671265)
			(xy 238.410397 -45.685115) (xy 238.332165 -45.692103) (xy 238.292894 -45.692568) (xy 238.24936 -45.692039)
			(xy 238.16271 -45.683524) (xy 238.077306 -45.666586) (xy 237.993965 -45.641387) (xy 237.913484 -45.608168)
			(xy 237.87481 -45.588174) (xy 237.86657 -45.584248) (xy 237.848476 -45.581916) (xy 237.839504 -45.583602)
			(xy 237.790336 -45.594179) (xy 237.690402 -45.605511) (xy 237.640114 -45.606208) (xy 237.599001 -45.605674)
			(xy 237.517127 -45.598088) (xy 237.436301 -45.582981) (xy 237.357214 -45.560481) (xy 237.280541 -45.53078)
			(xy 237.206935 -45.494131) (xy 237.137024 -45.450847) (xy 237.071406 -45.401297) (xy 237.010639 -45.345904)
			(xy 236.955242 -45.285141) (xy 236.905687 -45.219525) (xy 236.862399 -45.149618) (xy 236.825745 -45.076014)
			(xy 236.796038 -44.999343) (xy 236.773533 -44.920257) (xy 236.75842 -44.839433) (xy 236.750829 -44.757559)
			(xy 236.750352 -44.716446) (xy 236.750814 -44.676228) (xy 236.758123 -44.596123) (xy 236.772622 -44.517004)
			(xy 236.794193 -44.439513) (xy 236.80801 -44.40174) (xy 236.811025 -44.392621) (xy 236.810769 -44.373433)
			(xy 236.807502 -44.364402) (xy 236.791394 -44.324025) (xy 236.766206 -44.240819) (xy 236.749266 -44.15555)
			(xy 236.740738 -44.069034) (xy 236.740192 -44.025566) (xy 182.412218 -44.025566) (xy 182.41506 -44.035245)
			(xy 182.422822 -44.089229) (xy 182.423308 -44.116498) (xy 182.423308 -44.980098) (xy 182.422822 -45.007367)
			(xy 182.41506 -45.061351) (xy 182.399695 -45.113681) (xy 182.377038 -45.163291) (xy 182.347552 -45.209172)
			(xy 182.311837 -45.250389) (xy 182.27062 -45.286104) (xy 182.224739 -45.31559) (xy 182.175129 -45.338247)
			(xy 182.122799 -45.353612) (xy 182.068815 -45.361374) (xy 182.014277 -45.361374) (xy 181.960293 -45.353612)
			(xy 181.907963 -45.338247) (xy 181.858353 -45.31559) (xy 181.812472 -45.286104) (xy 181.771255 -45.250389)
			(xy 181.73554 -45.209172) (xy 181.706054 -45.163291) (xy 181.683397 -45.113681) (xy 181.668032 -45.061351)
			(xy 181.66027 -45.007367) (xy 181.659784 -44.980098) (xy 180.948076 -44.980098) (xy 180.948076 -45.121068)
			(xy 180.94766 -45.133152) (xy 180.940197 -45.156139) (xy 180.925993 -45.175693) (xy 180.906439 -45.189897)
			(xy 180.883452 -45.19736) (xy 180.871368 -45.197776) (xy 180.185568 -45.197776) (xy 180.173489 -45.197363)
			(xy 180.150515 -45.189888) (xy 180.130975 -45.175679) (xy 180.116783 -45.156128) (xy 180.109327 -45.133148)
			(xy 180.10886 -45.121068) (xy 96.681178 -45.121068) (xy 96.736452 -45.187325) (xy 96.829216 -45.310943)
			(xy 96.915495 -45.439171) (xy 96.995057 -45.571672) (xy 97.067693 -45.708092) (xy 97.133211 -45.848071)
			(xy 97.191435 -45.991237) (xy 97.242212 -46.13721) (xy 97.285407 -46.285604) (xy 97.320906 -46.436025)
			(xy 97.326183 -46.464982) (xy 176.307496 -46.464982) (xy 176.307496 -45.63491) (xy 176.30802 -45.6228)
			(xy 176.315499 -45.599764) (xy 176.329729 -45.580166) (xy 176.349318 -45.565923) (xy 176.372348 -45.558428)
			(xy 176.384458 -45.557948) (xy 177.832258 -45.557948) (xy 177.84438 -45.558396) (xy 177.867439 -45.565878)
			(xy 177.887055 -45.580122) (xy 177.901308 -45.599733) (xy 177.908799 -45.622789) (xy 177.90922 -45.63491)
			(xy 177.90922 -46.464982) (xy 177.908824 -46.477108) (xy 177.907317 -46.481746) (xy 178.630072 -46.481746)
			(xy 178.630072 -45.618146) (xy 178.630558 -45.590877) (xy 178.63832 -45.536893) (xy 178.653685 -45.484563)
			(xy 178.676342 -45.434953) (xy 178.705828 -45.389072) (xy 178.741543 -45.347855) (xy 178.78276 -45.31214)
			(xy 178.828641 -45.282654) (xy 178.878251 -45.259997) (xy 178.930581 -45.244632) (xy 178.984565 -45.23687)
			(xy 179.039103 -45.23687) (xy 179.093087 -45.244632) (xy 179.145417 -45.259997) (xy 179.195027 -45.282654)
			(xy 179.240908 -45.31214) (xy 179.282125 -45.347855) (xy 179.31784 -45.389072) (xy 179.347326 -45.434953)
			(xy 179.369983 -45.484563) (xy 179.385348 -45.536893) (xy 179.39311 -45.590877) (xy 179.393596 -45.618146)
			(xy 179.393596 -46.481746) (xy 179.39311 -46.509015) (xy 179.385348 -46.562999) (xy 179.369983 -46.615329)
			(xy 179.347326 -46.664939) (xy 179.31784 -46.71082) (xy 179.282125 -46.752037) (xy 179.240908 -46.787752)
			(xy 179.195027 -46.817238) (xy 179.145417 -46.839895) (xy 179.093087 -46.85526) (xy 179.039103 -46.863022)
			(xy 178.984565 -46.863022) (xy 178.930581 -46.85526) (xy 178.878251 -46.839895) (xy 178.828641 -46.817238)
			(xy 178.78276 -46.787752) (xy 178.741543 -46.752037) (xy 178.705828 -46.71082) (xy 178.676342 -46.664939)
			(xy 178.653685 -46.615329) (xy 178.63832 -46.562999) (xy 178.630558 -46.509015) (xy 178.630072 -46.481746)
			(xy 177.907317 -46.481746) (xy 177.901332 -46.500173) (xy 177.887075 -46.519792) (xy 177.867452 -46.534043)
			(xy 177.844384 -46.541528) (xy 177.832258 -46.541944) (xy 176.384458 -46.541944) (xy 176.372339 -46.541524)
			(xy 176.349292 -46.534023) (xy 176.329689 -46.519768) (xy 176.31545 -46.500154) (xy 176.307967 -46.477101)
			(xy 176.307496 -46.464982) (xy 97.326183 -46.464982) (xy 97.348615 -46.588073) (xy 97.368459 -46.741347)
			(xy 97.380387 -46.895438) (xy 97.384366 -47.04994) (xy 97.380387 -47.204442) (xy 97.368459 -47.358533)
			(xy 97.348615 -47.511807) (xy 97.320906 -47.663855) (xy 97.285407 -47.814276) (xy 97.242212 -47.96267)
			(xy 97.241365 -47.965106) (xy 176.307496 -47.965106) (xy 176.307496 -47.135034) (xy 176.30804 -47.122925)
			(xy 176.315513 -47.09989) (xy 176.329738 -47.080292) (xy 176.349322 -47.066047) (xy 176.37235 -47.058552)
			(xy 176.384458 -47.058072) (xy 177.832258 -47.058072) (xy 177.844382 -47.058496) (xy 177.867445 -47.065981)
			(xy 177.887064 -47.08023) (xy 177.901315 -47.099848) (xy 177.908803 -47.12291) (xy 177.90922 -47.135034)
			(xy 177.90922 -47.965106) (xy 177.908844 -47.977233) (xy 177.901345 -48.000299) (xy 177.887084 -48.019918)
			(xy 177.867456 -48.034167) (xy 177.844385 -48.041652) (xy 177.832258 -48.042068) (xy 176.384458 -48.042068)
			(xy 176.372342 -48.041624) (xy 176.349298 -48.034126) (xy 176.329698 -48.019877) (xy 176.315457 -48.000269)
			(xy 176.30797 -47.977222) (xy 176.307496 -47.965106) (xy 97.241365 -47.965106) (xy 97.191435 -48.108643)
			(xy 97.166861 -48.169068) (xy 180.10886 -48.169068) (xy 180.10886 -47.974504) (xy 180.109236 -47.963397)
			(xy 180.115551 -47.942101) (xy 180.121306 -47.932594) (xy 180.313838 -47.6377) (xy 180.319543 -47.628314)
			(xy 180.325817 -47.607276) (xy 180.325817 -47.585321) (xy 180.319542 -47.564282) (xy 180.313838 -47.554896)
			(xy 180.121306 -47.261272) (xy 180.115572 -47.251754) (xy 180.109237 -47.230467) (xy 180.10886 -47.219362)
			(xy 180.10886 -47.023528) (xy 180.109387 -47.011458) (xy 180.116838 -46.988497) (xy 180.13102 -46.968962)
			(xy 180.150543 -46.954766) (xy 180.173498 -46.947297) (xy 180.185568 -46.94682) (xy 180.871368 -46.94682)
			(xy 180.883452 -46.94724) (xy 180.906438 -46.954703) (xy 180.925991 -46.968906) (xy 180.940196 -46.988458)
			(xy 180.947659 -47.011444) (xy 180.948076 -47.023528) (xy 180.948076 -47.218092) (xy 180.947712 -47.229198)
			(xy 180.941377 -47.25049) (xy 180.93563 -47.260002) (xy 180.743098 -47.553626) (xy 180.737353 -47.562986)
			(xy 180.731026 -47.58401) (xy 180.730964 -47.605965) (xy 180.737172 -47.627024) (xy 180.742844 -47.63643)
			(xy 180.93563 -47.932594) (xy 180.941392 -47.942097) (xy 180.947708 -47.963396) (xy 180.948076 -47.974504)
			(xy 180.948076 -48.028098) (xy 181.659784 -48.028098) (xy 181.659784 -47.164498) (xy 181.66027 -47.137229)
			(xy 181.668032 -47.083245) (xy 181.683397 -47.030915) (xy 181.706054 -46.981305) (xy 181.73554 -46.935424)
			(xy 181.771255 -46.894207) (xy 181.812472 -46.858492) (xy 181.858353 -46.829006) (xy 181.907963 -46.806349)
			(xy 181.960293 -46.790984) (xy 182.014277 -46.783222) (xy 182.068815 -46.783222) (xy 182.122799 -46.790984)
			(xy 182.175129 -46.806349) (xy 182.224739 -46.829006) (xy 182.27062 -46.858492) (xy 182.311837 -46.894207)
			(xy 182.347552 -46.935424) (xy 182.377038 -46.981305) (xy 182.399695 -47.030915) (xy 182.41506 -47.083245)
			(xy 182.422822 -47.137229) (xy 182.423308 -47.164498) (xy 182.423308 -48.028098) (xy 182.422822 -48.055367)
			(xy 182.41506 -48.109351) (xy 182.399695 -48.161681) (xy 182.377038 -48.211291) (xy 182.347552 -48.257172)
			(xy 182.311837 -48.298389) (xy 182.27062 -48.334104) (xy 182.224739 -48.36359) (xy 182.175129 -48.386247)
			(xy 182.122799 -48.401612) (xy 182.068815 -48.409374) (xy 182.014277 -48.409374) (xy 181.960293 -48.401612)
			(xy 181.907963 -48.386247) (xy 181.858353 -48.36359) (xy 181.812472 -48.334104) (xy 181.771255 -48.298389)
			(xy 181.73554 -48.257172) (xy 181.706054 -48.211291) (xy 181.683397 -48.161681) (xy 181.668032 -48.109351)
			(xy 181.66027 -48.055367) (xy 181.659784 -48.028098) (xy 180.948076 -48.028098) (xy 180.948076 -48.169068)
			(xy 180.94766 -48.181152) (xy 180.940197 -48.204139) (xy 180.925993 -48.223693) (xy 180.906439 -48.237897)
			(xy 180.883452 -48.24536) (xy 180.871368 -48.245776) (xy 180.185568 -48.245776) (xy 180.173489 -48.245363)
			(xy 180.150515 -48.237888) (xy 180.130975 -48.223679) (xy 180.116783 -48.204128) (xy 180.109327 -48.181148)
			(xy 180.10886 -48.169068) (xy 97.166861 -48.169068) (xy 97.133211 -48.251809) (xy 97.067693 -48.391788)
			(xy 96.995057 -48.528208) (xy 96.915495 -48.660709) (xy 96.829216 -48.788937) (xy 96.736452 -48.912555)
			(xy 96.637446 -49.031233) (xy 96.532463 -49.144657) (xy 96.421779 -49.252526) (xy 96.30569 -49.354554)
			(xy 96.184502 -49.450471) (xy 96.164099 -49.464976) (xy 176.307496 -49.464976) (xy 176.307496 -48.634904)
			(xy 176.307963 -48.622854) (xy 176.315394 -48.59993) (xy 176.329534 -48.580414) (xy 176.349002 -48.566211)
			(xy 176.371902 -48.558704) (xy 176.38395 -48.558196) (xy 177.832258 -48.558196) (xy 177.844341 -48.558742)
			(xy 177.867333 -48.566182) (xy 177.88691 -48.58035) (xy 177.901163 -48.599864) (xy 177.908704 -48.622823)
			(xy 177.90922 -48.634904) (xy 177.90922 -49.464976) (xy 177.90872 -49.477023) (xy 177.907192 -49.48174)
			(xy 178.630072 -49.48174) (xy 178.630072 -48.61814) (xy 178.630558 -48.590871) (xy 178.63832 -48.536887)
			(xy 178.653685 -48.484557) (xy 178.676342 -48.434947) (xy 178.705828 -48.389066) (xy 178.741543 -48.347849)
			(xy 178.78276 -48.312134) (xy 178.828641 -48.282648) (xy 178.878251 -48.259991) (xy 178.930581 -48.244626)
			(xy 178.984565 -48.236864) (xy 179.039103 -48.236864) (xy 179.093087 -48.244626) (xy 179.145417 -48.259991)
			(xy 179.195027 -48.282648) (xy 179.240908 -48.312134) (xy 179.282125 -48.347849) (xy 179.31784 -48.389066)
			(xy 179.347326 -48.434947) (xy 179.369983 -48.484557) (xy 179.385348 -48.536887) (xy 179.39311 -48.590871)
			(xy 179.393596 -48.61814) (xy 179.393596 -49.48174) (xy 179.39311 -49.509009) (xy 179.385348 -49.562993)
			(xy 179.369983 -49.615323) (xy 179.347326 -49.664933) (xy 179.31784 -49.710814) (xy 179.282125 -49.752031)
			(xy 179.240908 -49.787746) (xy 179.195027 -49.817232) (xy 179.145417 -49.839889) (xy 179.093087 -49.855254)
			(xy 179.039103 -49.863016) (xy 178.984565 -49.863016) (xy 178.930581 -49.855254) (xy 178.878251 -49.839889)
			(xy 178.828641 -49.817232) (xy 178.78276 -49.787746) (xy 178.741543 -49.752031) (xy 178.705828 -49.710814)
			(xy 178.676342 -49.664933) (xy 178.653685 -49.615323) (xy 178.63832 -49.562993) (xy 178.630558 -49.509009)
			(xy 178.630072 -49.48174) (xy 177.907192 -49.48174) (xy 177.901296 -49.499944) (xy 177.887165 -49.519459)
			(xy 177.867704 -49.533664) (xy 177.844811 -49.541174) (xy 177.832766 -49.541684) (xy 176.384458 -49.541684)
			(xy 176.372369 -49.541229) (xy 176.349371 -49.533764) (xy 176.329793 -49.519573) (xy 176.315543 -49.500039)
			(xy 176.308008 -49.477064) (xy 176.307496 -49.464976) (xy 96.164099 -49.464976) (xy 96.058537 -49.540022)
			(xy 95.928129 -49.62297) (xy 95.793624 -49.699095) (xy 95.655379 -49.768194) (xy 95.513759 -49.830085)
			(xy 95.369142 -49.884604) (xy 95.221909 -49.931606) (xy 95.072452 -49.970966) (xy 94.921168 -50.00258)
			(xy 94.768456 -50.026364) (xy 94.614722 -50.042255) (xy 94.460374 -50.050211) (xy 94.383098 -50.0507)
			(xy 92.782898 -50.0507) (xy 92.705622 -50.050194) (xy 92.551275 -50.042238) (xy 92.397543 -50.026347)
			(xy 92.244832 -50.002563) (xy 92.093548 -49.970949) (xy 91.944092 -49.931589) (xy 91.796861 -49.884587)
			(xy 91.652244 -49.830069) (xy 91.510626 -49.768178) (xy 91.372381 -49.699079) (xy 91.237877 -49.622954)
			(xy 91.10747 -49.540007) (xy 90.981506 -49.450456) (xy 90.860319 -49.35454) (xy 90.74423 -49.252512)
			(xy 90.633548 -49.144644) (xy 90.528565 -49.031221) (xy 90.42956 -48.912543) (xy 90.336796 -48.788927)
			(xy 90.250519 -48.660699) (xy 90.170957 -48.528199) (xy 90.098321 -48.391779) (xy 90.032804 -48.251802)
			(xy 89.97458 -48.108637) (xy 89.923803 -47.962664) (xy 89.880608 -47.814271) (xy 89.84511 -47.663852)
			(xy 89.817402 -47.511804) (xy 89.797557 -47.358531) (xy 89.78563 -47.204441) (xy 89.78165 -47.04994)
			(xy 67.583802 -47.04994) (xy 67.579823 -47.209492) (xy 67.567896 -47.368647) (xy 67.54805 -47.527009)
			(xy 67.520336 -47.684186) (xy 67.484821 -47.839786) (xy 67.441595 -47.993422) (xy 67.390764 -48.144712)
			(xy 67.332455 -48.293281) (xy 67.266813 -48.438758) (xy 67.194001 -48.580783) (xy 67.114201 -48.719002)
			(xy 67.02761 -48.853071) (xy 66.934444 -48.982657) (xy 66.834934 -49.107438) (xy 66.729328 -49.227105)
			(xy 66.617889 -49.341358) (xy 66.500893 -49.449914) (xy 66.378631 -49.552504) (xy 66.251408 -49.648872)
			(xy 66.119539 -49.738779) (xy 65.983353 -49.822001) (xy 65.843188 -49.898331) (xy 65.699392 -49.967579)
			(xy 65.552323 -50.029574) (xy 65.402347 -50.084161) (xy 65.249837 -50.131205) (xy 65.095171 -50.170587)
			(xy 64.938734 -50.202212) (xy 64.780916 -50.226) (xy 64.622107 -50.241891) (xy 64.462705 -50.249847)
			(xy 64.382904 -50.250344) (xy 62.782958 -50.250344) (xy 62.703158 -50.249839) (xy 62.543755 -50.241883)
			(xy 62.384947 -50.225992) (xy 62.227129 -50.202204) (xy 62.070693 -50.17058) (xy 61.916027 -50.131197)
			(xy 61.763517 -50.084154) (xy 61.613541 -50.029567) (xy 61.466472 -49.967573) (xy 61.322677 -49.898324)
			(xy 61.182512 -49.821994) (xy 61.046326 -49.738773) (xy 60.914458 -49.648866) (xy 60.787235 -49.552499)
			(xy 60.664973 -49.449909) (xy 60.547978 -49.341353) (xy 60.436538 -49.2271) (xy 60.330933 -49.107434)
			(xy 60.231423 -48.982653) (xy 60.138257 -48.853067) (xy 60.051666 -48.718998) (xy 59.971866 -48.580779)
			(xy 59.899054 -48.438755) (xy 59.833413 -48.293278) (xy 59.775104 -48.14471) (xy 59.724273 -47.99342)
			(xy 59.681047 -47.839784) (xy 59.645532 -47.684184) (xy 59.617818 -47.527008) (xy 59.597972 -47.368646)
			(xy 59.586045 -47.209491) (xy 59.582066 -47.04994) (xy 0.509016 -47.04994) (xy 0.509016 -50.9651)
			(xy 176.307496 -50.9651) (xy 176.307496 -50.135028) (xy 176.307984 -50.12298) (xy 176.315408 -50.100056)
			(xy 176.329542 -50.08054) (xy 176.349006 -50.066335) (xy 176.371903 -50.058828) (xy 176.38395 -50.05832)
			(xy 177.832258 -50.05832) (xy 177.844343 -50.058843) (xy 177.867339 -50.066285) (xy 177.886918 -50.080458)
			(xy 177.901171 -50.099979) (xy 177.908707 -50.122945) (xy 177.90922 -50.135028) (xy 177.90922 -50.9651)
			(xy 177.90874 -50.977148) (xy 177.90131 -51.00007) (xy 177.887174 -51.019584) (xy 177.867709 -51.033788)
			(xy 177.844812 -51.041298) (xy 177.832766 -51.041808) (xy 176.384458 -51.041808) (xy 176.372371 -51.041329)
			(xy 176.349377 -51.033867) (xy 176.329802 -51.019682) (xy 176.315551 -51.000154) (xy 176.308012 -50.977185)
			(xy 176.307496 -50.9651) (xy 0.509016 -50.9651) (xy 0.509016 -51.090068) (xy 180.10886 -51.090068)
			(xy 180.10886 -50.895504) (xy 180.109236 -50.884397) (xy 180.115551 -50.863101) (xy 180.121306 -50.853594)
			(xy 180.313838 -50.5587) (xy 180.319543 -50.549314) (xy 180.325817 -50.528276) (xy 180.325817 -50.506321)
			(xy 180.319542 -50.485282) (xy 180.313838 -50.475896) (xy 180.121306 -50.182272) (xy 180.115572 -50.172754)
			(xy 180.109237 -50.151467) (xy 180.10886 -50.140362) (xy 180.10886 -49.944528) (xy 180.109387 -49.932458)
			(xy 180.116838 -49.909497) (xy 180.13102 -49.889962) (xy 180.150543 -49.875766) (xy 180.173498 -49.868297)
			(xy 180.185568 -49.86782) (xy 180.871368 -49.86782) (xy 180.883452 -49.86824) (xy 180.906438 -49.875703)
			(xy 180.925991 -49.889906) (xy 180.940196 -49.909458) (xy 180.947659 -49.932444) (xy 180.948076 -49.944528)
			(xy 180.948076 -50.139092) (xy 180.947712 -50.150198) (xy 180.941377 -50.17149) (xy 180.93563 -50.181002)
			(xy 180.743098 -50.474626) (xy 180.737353 -50.483986) (xy 180.731026 -50.50501) (xy 180.730964 -50.526965)
			(xy 180.737172 -50.548024) (xy 180.742844 -50.55743) (xy 180.93563 -50.853594) (xy 180.941392 -50.863097)
			(xy 180.947708 -50.884396) (xy 180.948076 -50.895504) (xy 180.948076 -50.949098) (xy 181.659784 -50.949098)
			(xy 181.659784 -50.085498) (xy 181.66027 -50.058229) (xy 181.668032 -50.004245) (xy 181.683397 -49.951915)
			(xy 181.706054 -49.902305) (xy 181.73554 -49.856424) (xy 181.771255 -49.815207) (xy 181.812472 -49.779492)
			(xy 181.858353 -49.750006) (xy 181.907963 -49.727349) (xy 181.960293 -49.711984) (xy 182.014277 -49.704222)
			(xy 182.068815 -49.704222) (xy 182.122799 -49.711984) (xy 182.175129 -49.727349) (xy 182.224739 -49.750006)
			(xy 182.27062 -49.779492) (xy 182.311837 -49.815207) (xy 182.347552 -49.856424) (xy 182.377038 -49.902305)
			(xy 182.399695 -49.951915) (xy 182.41506 -50.004245) (xy 182.422822 -50.058229) (xy 182.423308 -50.085498)
			(xy 182.423308 -50.949098) (xy 182.422822 -50.976367) (xy 182.41506 -51.030351) (xy 182.399695 -51.082681)
			(xy 182.377038 -51.132291) (xy 182.347552 -51.178172) (xy 182.311837 -51.219389) (xy 182.27062 -51.255104)
			(xy 182.224739 -51.28459) (xy 182.175129 -51.307247) (xy 182.122799 -51.322612) (xy 182.068815 -51.330374)
			(xy 182.014277 -51.330374) (xy 181.960293 -51.322612) (xy 181.907963 -51.307247) (xy 181.858353 -51.28459)
			(xy 181.812472 -51.255104) (xy 181.771255 -51.219389) (xy 181.73554 -51.178172) (xy 181.706054 -51.132291)
			(xy 181.683397 -51.082681) (xy 181.668032 -51.030351) (xy 181.66027 -50.976367) (xy 181.659784 -50.949098)
			(xy 180.948076 -50.949098) (xy 180.948076 -51.090068) (xy 180.94766 -51.102152) (xy 180.940197 -51.125139)
			(xy 180.925993 -51.144693) (xy 180.906439 -51.158897) (xy 180.883452 -51.16636) (xy 180.871368 -51.166776)
			(xy 180.185568 -51.166776) (xy 180.173489 -51.166363) (xy 180.150515 -51.158888) (xy 180.130975 -51.144679)
			(xy 180.116783 -51.125128) (xy 180.109327 -51.102148) (xy 180.10886 -51.090068) (xy 0.509016 -51.090068)
			(xy 0.509016 -52.46497) (xy 176.307496 -52.46497) (xy 176.307496 -51.634898) (xy 176.30801 -51.622788)
			(xy 176.315492 -51.599751) (xy 176.329725 -51.580153) (xy 176.349316 -51.56591) (xy 176.372348 -51.558416)
			(xy 176.384458 -51.557936) (xy 177.832258 -51.557936) (xy 177.844378 -51.558396) (xy 177.867436 -51.565876)
			(xy 177.887051 -51.580118) (xy 177.901304 -51.599725) (xy 177.908797 -51.622778) (xy 177.90922 -51.634898)
			(xy 177.90922 -52.46497) (xy 177.908814 -52.477095) (xy 177.907308 -52.481734) (xy 178.630072 -52.481734)
			(xy 178.630072 -51.618134) (xy 178.630558 -51.590865) (xy 178.63832 -51.536881) (xy 178.653685 -51.484551)
			(xy 178.676342 -51.434941) (xy 178.705828 -51.38906) (xy 178.741543 -51.347843) (xy 178.78276 -51.312128)
			(xy 178.828641 -51.282642) (xy 178.878251 -51.259985) (xy 178.930581 -51.24462) (xy 178.984565 -51.236858)
			(xy 179.039103 -51.236858) (xy 179.093087 -51.24462) (xy 179.145417 -51.259985) (xy 179.195027 -51.282642)
			(xy 179.240908 -51.312128) (xy 179.282125 -51.347843) (xy 179.31784 -51.38906) (xy 179.347326 -51.434941)
			(xy 179.369983 -51.484551) (xy 179.385348 -51.536881) (xy 179.39311 -51.590865) (xy 179.393596 -51.618134)
			(xy 179.393596 -51.999896) (xy 201.367397 -51.999896) (xy 201.371407 -51.837793) (xy 201.38343 -51.676088)
			(xy 201.403434 -51.515174) (xy 201.431372 -51.355447) (xy 201.467175 -51.197297) (xy 201.510755 -51.041111)
			(xy 201.562006 -50.887271) (xy 201.620802 -50.736154) (xy 201.687 -50.58813) (xy 201.760436 -50.44356)
			(xy 201.840933 -50.302799) (xy 201.928292 -50.166191) (xy 202.0223 -50.034071) (xy 202.122727 -49.906761)
			(xy 202.229327 -49.784573) (xy 202.341839 -49.667807) (xy 202.459987 -49.556748) (xy 202.583484 -49.451667)
			(xy 202.712026 -49.352823) (xy 202.845299 -49.260456) (xy 202.982977 -49.174793) (xy 203.124723 -49.096044)
			(xy 203.27019 -49.024401) (xy 203.419022 -48.960039) (xy 203.570854 -48.903117) (xy 203.725316 -48.853773)
			(xy 203.882029 -48.812128) (xy 204.04061 -48.778283) (xy 204.200671 -48.752323) (xy 204.361819 -48.73431)
			(xy 204.523661 -48.724289) (xy 204.685801 -48.722283) (xy 204.847842 -48.728299) (xy 205.009386 -48.74232)
			(xy 205.17004 -48.764313) (xy 205.32941 -48.794225) (xy 205.487105 -48.831981) (xy 205.64274 -48.877489)
			(xy 205.795934 -48.930639) (xy 205.946312 -48.9913) (xy 206.093507 -49.059323) (xy 206.237157 -49.134542)
			(xy 206.376912 -49.216773) (xy 206.512428 -49.305815) (xy 206.643376 -49.40145) (xy 206.769434 -49.503444)
			(xy 206.890294 -49.611547) (xy 207.00566 -49.725494) (xy 207.115249 -49.845008) (xy 207.218794 -49.969795)
			(xy 207.316041 -50.09955) (xy 207.406753 -50.233955) (xy 207.490706 -50.372682) (xy 207.567696 -50.515391)
			(xy 207.637535 -50.661732) (xy 207.70005 -50.811349) (xy 207.755091 -50.963874) (xy 207.802521 -51.118934)
			(xy 207.818131 -51.180746) (xy 235.862368 -51.180746) (xy 235.862368 -50.148744) (xy 235.86285 -50.136666)
			(xy 235.870302 -50.113689) (xy 235.884491 -50.09414) (xy 235.904028 -50.079933) (xy 235.926998 -50.07246)
			(xy 235.939076 -50.072036) (xy 237.15853 -50.072036) (xy 237.170621 -50.072482) (xy 237.193622 -50.079946)
			(xy 237.213201 -50.094138) (xy 237.227451 -50.113676) (xy 237.234982 -50.136655) (xy 237.235492 -50.148744)
			(xy 237.235492 -51.180746) (xy 237.235028 -51.19286) (xy 237.227532 -51.2159) (xy 237.213287 -51.235498)
			(xy 237.193685 -51.249739) (xy 237.170644 -51.25723) (xy 237.15853 -51.257708) (xy 235.939076 -51.257708)
			(xy 235.926967 -51.257304) (xy 235.90394 -51.249799) (xy 235.884368 -51.235534) (xy 235.870174 -51.215911)
			(xy 235.862752 -51.192857) (xy 235.862368 -51.180746) (xy 207.818131 -51.180746) (xy 207.842224 -51.27615)
			(xy 207.874105 -51.435138) (xy 207.898083 -51.595507) (xy 207.914102 -51.756866) (xy 207.922121 -51.91882)
			(xy 207.922622 -51.999896) (xy 207.922121 -52.080972) (xy 207.914102 -52.242926) (xy 207.898083 -52.404285)
			(xy 207.874105 -52.564654) (xy 207.842224 -52.723642) (xy 207.802521 -52.880858) (xy 207.771937 -52.980844)
			(xy 231.364536 -52.980844) (xy 231.364536 -51.949096) (xy 231.36491 -51.937009) (xy 231.372384 -51.914018)
			(xy 231.386598 -51.894464) (xy 231.406161 -51.880262) (xy 231.429156 -51.872802) (xy 231.441244 -51.872388)
			(xy 232.558844 -51.872388) (xy 232.57092 -51.872827) (xy 232.593888 -51.880301) (xy 232.613424 -51.894504)
			(xy 232.627618 -51.914047) (xy 232.63508 -51.937019) (xy 232.635552 -51.949096) (xy 232.635552 -52.980844)
			(xy 235.964476 -52.980844) (xy 235.964476 -51.949096) (xy 235.964961 -51.937023) (xy 235.972422 -51.914058)
			(xy 235.986614 -51.894523) (xy 236.006148 -51.880328) (xy 236.029111 -51.872863) (xy 236.041184 -51.872388)
			(xy 237.158784 -51.872388) (xy 237.170865 -51.872826) (xy 237.193847 -51.880289) (xy 237.213397 -51.894489)
			(xy 237.227602 -51.914035) (xy 237.23507 -51.937015) (xy 237.235492 -51.949096) (xy 237.235492 -52.980844)
			(xy 237.235073 -52.992922) (xy 237.227597 -53.015894) (xy 237.213389 -53.035432) (xy 237.203212 -53.04282)
			(xy 238.733076 -53.04282) (xy 238.733076 -52.848256) (xy 238.73343 -52.837147) (xy 238.73976 -52.815851)
			(xy 238.745522 -52.806346) (xy 238.938054 -52.511452) (xy 238.943714 -52.502042) (xy 238.949996 -52.481014)
			(xy 238.950008 -52.459069) (xy 238.943749 -52.438034) (xy 238.938054 -52.428648) (xy 238.745522 -52.135024)
			(xy 238.739771 -52.125515) (xy 238.733447 -52.104221) (xy 238.733076 -52.093114) (xy 238.733076 -51.89728)
			(xy 238.733547 -51.885206) (xy 238.741013 -51.862241) (xy 238.755209 -51.842706) (xy 238.774745 -51.828511)
			(xy 238.79771 -51.821046) (xy 238.809784 -51.820572) (xy 239.495584 -51.820572) (xy 239.507656 -51.821078)
			(xy 239.530619 -51.828533) (xy 239.550155 -51.84272) (xy 239.56435 -51.862249) (xy 239.571817 -51.885208)
			(xy 239.572292 -51.89728) (xy 239.572292 -52.091844) (xy 239.571949 -52.10175) (xy 244.67947 -52.10175)
			(xy 244.679975 -52.075243) (xy 244.687334 -52.022743) (xy 244.701889 -51.971767) (xy 244.723361 -51.923297)
			(xy 244.751335 -51.878265) (xy 244.785274 -51.837539) (xy 244.824523 -51.801903) (xy 244.868327 -51.772043)
			(xy 244.915843 -51.748534) (xy 244.966156 -51.731829) (xy 244.992144 -51.726592) (xy 245.000543 -51.724726)
			(xy 245.015476 -51.716197) (xy 245.026755 -51.703216) (xy 245.030244 -51.69535) (xy 245.045663 -51.657494)
			(xy 245.082559 -51.584546) (xy 245.125992 -51.515291) (xy 245.175596 -51.450313) (xy 245.230952 -51.39016)
			(xy 245.291595 -51.335341) (xy 245.357011 -51.286316) (xy 245.426649 -51.2435) (xy 245.499922 -51.207254)
			(xy 245.576211 -51.177884) (xy 245.654873 -51.155637) (xy 245.735245 -51.140701) (xy 245.816648 -51.133203)
			(xy 245.857522 -51.13274) (xy 245.899843 -51.133258) (xy 245.984099 -51.14133) (xy 246.067208 -51.157371)
			(xy 246.148416 -51.181236) (xy 246.226989 -51.212708) (xy 246.302217 -51.251503) (xy 246.33809 -51.273964)
			(xy 246.346484 -51.278827) (xy 246.365522 -51.28248) (xy 246.38456 -51.278827) (xy 246.392954 -51.273964)
			(xy 246.42883 -51.25151) (xy 246.504063 -51.212731) (xy 246.582638 -51.181268) (xy 246.663845 -51.157405)
			(xy 246.74695 -51.141356) (xy 246.831202 -51.133268) (xy 246.873522 -51.13274) (xy 246.926862 -51.134518)
			(xy 246.938638 -51.134618) (xy 246.960306 -51.125466) (xy 246.975671 -51.107657) (xy 246.979186 -51.096418)
			(xy 246.990138 -51.056039) (xy 247.018713 -50.977397) (xy 247.054545 -50.901785) (xy 247.097317 -50.829872)
			(xy 247.146653 -50.762292) (xy 247.202115 -50.699642) (xy 247.263214 -50.642477) (xy 247.329411 -50.5913)
			(xy 247.40012 -50.546564) (xy 247.474717 -50.508665) (xy 247.552542 -50.477936) (xy 247.632909 -50.45465)
			(xy 247.715107 -50.439012) (xy 247.79841 -50.431161) (xy 247.840246 -50.430684) (xy 247.883752 -50.431235)
			(xy 247.970347 -50.439729) (xy 248.055699 -50.456641) (xy 248.138991 -50.481809) (xy 248.219426 -50.514992)
			(xy 248.296235 -50.555874) (xy 248.332752 -50.579528) (xy 248.341308 -50.584744) (xy 248.360946 -50.588653)
			(xy 248.380584 -50.584744) (xy 248.38914 -50.579528) (xy 248.425663 -50.555885) (xy 248.50248 -50.515022)
			(xy 248.582916 -50.481847) (xy 248.666204 -50.456676) (xy 248.751551 -50.439749) (xy 248.838142 -50.431227)
			(xy 248.881646 -50.430684) (xy 248.926403 -50.431259) (xy 249.015462 -50.440266) (xy 249.103167 -50.458165)
			(xy 249.188634 -50.484775) (xy 249.270999 -50.519828) (xy 249.349431 -50.562968) (xy 249.386598 -50.58791)
			(xy 249.394939 -50.593062) (xy 249.414052 -50.597328) (xy 249.433374 -50.594144) (xy 249.44197 -50.589434)
			(xy 249.4758 -50.569354) (xy 249.546346 -50.534523) (xy 249.619688 -50.506051) (xy 249.695257 -50.484158)
			(xy 249.772462 -50.469016) (xy 249.850701 -50.460742) (xy 249.890026 -50.45964) (xy 249.889772 -50.4444)
			(xy 249.889772 -50.443892) (xy 249.89024 -50.405527) (xy 249.896983 -50.329093) (xy 249.903234 -50.291238)
			(xy 249.904413 -50.282319) (xy 249.901131 -50.26464) (xy 249.891952 -50.249179) (xy 249.8852 -50.243232)
			(xy 249.851748 -50.215094) (xy 249.789907 -50.153305) (xy 249.734424 -50.08575) (xy 249.685833 -50.01308)
			(xy 249.644603 -49.935995) (xy 249.61113 -49.855239) (xy 249.585738 -49.771589) (xy 249.568671 -49.685852)
			(xy 249.560094 -49.598855) (xy 249.559572 -49.555146) (xy 249.560076 -49.512785) (xy 249.568129 -49.428448)
			(xy 249.584163 -49.345258) (xy 249.608031 -49.263968) (xy 249.639519 -49.185316) (xy 249.678341 -49.110013)
			(xy 249.724144 -49.038741) (xy 249.776515 -48.972145) (xy 249.83498 -48.91083) (xy 249.899008 -48.855349)
			(xy 249.96802 -48.806206) (xy 250.04139 -48.763846) (xy 250.118455 -48.728651) (xy 250.198517 -48.700942)
			(xy 250.28085 -48.680968) (xy 250.364709 -48.668911) (xy 250.449334 -48.66488) (xy 250.533959 -48.668911)
			(xy 250.617818 -48.680968) (xy 250.700151 -48.700942) (xy 250.780213 -48.728651) (xy 250.857278 -48.763846)
			(xy 250.930648 -48.806206) (xy 250.99966 -48.855349) (xy 251.063688 -48.91083) (xy 251.122153 -48.972145)
			(xy 251.174524 -49.038741) (xy 251.220327 -49.110013) (xy 251.259149 -49.185316) (xy 251.290637 -49.263968)
			(xy 251.314505 -49.345258) (xy 251.330539 -49.428448) (xy 251.338592 -49.512785) (xy 251.339096 -49.555146)
			(xy 251.338636 -49.593574) (xy 251.331894 -49.670136) (xy 251.325634 -49.708054) (xy 251.324473 -49.716974)
			(xy 251.32775 -49.73465) (xy 251.336921 -49.750111) (xy 251.343668 -49.75606) (xy 251.362142 -49.771471)
			(xy 251.397596 -49.803999) (xy 251.414534 -49.821084) (xy 251.422676 -49.828571) (xy 251.443355 -49.836348)
			(xy 251.454412 -49.83607) (xy 251.469822 -49.835031) (xy 251.50069 -49.833886) (xy 251.516134 -49.833784)
			(xy 251.557251 -49.834166) (xy 251.639133 -49.841757) (xy 251.719966 -49.85687) (xy 251.79906 -49.879378)
			(xy 251.875739 -49.909087) (xy 251.94935 -49.945745) (xy 252.019265 -49.989039) (xy 252.084886 -50.038598)
			(xy 252.145655 -50.094001) (xy 252.201053 -50.154775) (xy 252.250607 -50.220401) (xy 252.293894 -50.29032)
			(xy 252.330545 -50.363934) (xy 252.360248 -50.440616) (xy 252.382748 -50.519712) (xy 252.397854 -50.600546)
			(xy 252.405438 -50.682429) (xy 252.405896 -50.723546) (xy 252.405358 -50.767341) (xy 252.396743 -50.854506)
			(xy 252.379599 -50.940401) (xy 252.354094 -51.024196) (xy 252.320474 -51.105076) (xy 252.300232 -51.143916)
			(xy 252.29478 -51.15537) (xy 252.2948 -51.18071) (xy 252.300232 -51.192176) (xy 252.320452 -51.231026)
			(xy 252.354062 -51.311909) (xy 252.379567 -51.3957) (xy 252.39672 -51.481592) (xy 252.405355 -51.568752)
			(xy 252.405896 -51.612546) (xy 252.405358 -51.656341) (xy 252.396743 -51.743506) (xy 252.379599 -51.829401)
			(xy 252.354094 -51.913196) (xy 252.320474 -51.994076) (xy 252.317441 -51.999896) (xy 265.367523 -51.999896)
			(xy 265.371533 -51.837793) (xy 265.383556 -51.676088) (xy 265.40356 -51.515174) (xy 265.431498 -51.355447)
			(xy 265.467301 -51.197297) (xy 265.510881 -51.041111) (xy 265.562132 -50.887271) (xy 265.620928 -50.736154)
			(xy 265.687126 -50.58813) (xy 265.760562 -50.44356) (xy 265.841059 -50.302799) (xy 265.928418 -50.166191)
			(xy 266.022426 -50.034071) (xy 266.122853 -49.906761) (xy 266.229453 -49.784573) (xy 266.341965 -49.667807)
			(xy 266.460113 -49.556748) (xy 266.58361 -49.451667) (xy 266.712152 -49.352823) (xy 266.845425 -49.260456)
			(xy 266.983103 -49.174793) (xy 267.124849 -49.096044) (xy 267.270316 -49.024401) (xy 267.419148 -48.960039)
			(xy 267.57098 -48.903117) (xy 267.725442 -48.853773) (xy 267.882155 -48.812128) (xy 268.040736 -48.778283)
			(xy 268.200797 -48.752323) (xy 268.361945 -48.73431) (xy 268.523787 -48.724289) (xy 268.685927 -48.722283)
			(xy 268.847968 -48.728299) (xy 269.009512 -48.74232) (xy 269.170166 -48.764313) (xy 269.329536 -48.794225)
			(xy 269.487231 -48.831981) (xy 269.642866 -48.877489) (xy 269.79606 -48.930639) (xy 269.946438 -48.9913)
			(xy 270.093633 -49.059323) (xy 270.237283 -49.134542) (xy 270.377038 -49.216773) (xy 270.512554 -49.305815)
			(xy 270.643502 -49.40145) (xy 270.76956 -49.503444) (xy 270.89042 -49.611547) (xy 271.005786 -49.725494)
			(xy 271.115375 -49.845008) (xy 271.21892 -49.969795) (xy 271.316167 -50.09955) (xy 271.406879 -50.233955)
			(xy 271.490832 -50.372682) (xy 271.567822 -50.515391) (xy 271.637661 -50.661732) (xy 271.700176 -50.811349)
			(xy 271.755217 -50.963874) (xy 271.802647 -51.118934) (xy 271.84235 -51.27615) (xy 271.874231 -51.435138)
			(xy 271.898209 -51.595507) (xy 271.914228 -51.756866) (xy 271.922247 -51.91882) (xy 271.922748 -51.999896)
			(xy 271.922247 -52.080972) (xy 271.914228 -52.242926) (xy 271.898209 -52.404285) (xy 271.874231 -52.564654)
			(xy 271.84235 -52.723642) (xy 271.802647 -52.880858) (xy 271.755217 -53.035918) (xy 271.700176 -53.188443)
			(xy 271.637661 -53.33806) (xy 271.567822 -53.484401) (xy 271.490832 -53.62711) (xy 271.406879 -53.765837)
			(xy 271.316167 -53.900242) (xy 271.21892 -54.029997) (xy 271.115375 -54.154784) (xy 271.005786 -54.274298)
			(xy 270.89042 -54.388245) (xy 270.76956 -54.496348) (xy 270.643502 -54.598342) (xy 270.512554 -54.693977)
			(xy 270.377038 -54.783019) (xy 270.237283 -54.86525) (xy 270.093633 -54.940469) (xy 269.946438 -55.008492)
			(xy 269.79606 -55.069153) (xy 269.642866 -55.122303) (xy 269.487231 -55.167811) (xy 269.329536 -55.205567)
			(xy 269.170166 -55.235479) (xy 269.009512 -55.257472) (xy 268.847968 -55.271493) (xy 268.685927 -55.277509)
			(xy 268.523787 -55.275503) (xy 268.361945 -55.265482) (xy 268.200797 -55.247469) (xy 268.040736 -55.221509)
			(xy 267.882155 -55.187664) (xy 267.725442 -55.146019) (xy 267.57098 -55.096675) (xy 267.419148 -55.039753)
			(xy 267.270316 -54.975391) (xy 267.124849 -54.903748) (xy 266.983103 -54.824999) (xy 266.845425 -54.739336)
			(xy 266.712152 -54.646969) (xy 266.58361 -54.548125) (xy 266.460113 -54.443044) (xy 266.341965 -54.331985)
			(xy 266.229453 -54.215219) (xy 266.122853 -54.093031) (xy 266.022426 -53.965721) (xy 265.928418 -53.833601)
			(xy 265.841059 -53.696993) (xy 265.760562 -53.556232) (xy 265.687126 -53.411662) (xy 265.620928 -53.263638)
			(xy 265.562132 -53.112521) (xy 265.510881 -52.958681) (xy 265.467301 -52.802495) (xy 265.431498 -52.644345)
			(xy 265.40356 -52.484618) (xy 265.383556 -52.323704) (xy 265.371533 -52.161999) (xy 265.367523 -51.999896)
			(xy 252.317441 -51.999896) (xy 252.300232 -52.032916) (xy 252.29478 -52.04437) (xy 252.2948 -52.06971)
			(xy 252.300232 -52.081176) (xy 252.320452 -52.120026) (xy 252.354062 -52.200909) (xy 252.379567 -52.2847)
			(xy 252.39672 -52.370592) (xy 252.405355 -52.457752) (xy 252.405896 -52.501546) (xy 252.405431 -52.54266)
			(xy 252.39784 -52.624537) (xy 252.382728 -52.705364) (xy 252.360222 -52.784452) (xy 252.330515 -52.861127)
			(xy 252.293861 -52.934733) (xy 252.250573 -53.004644) (xy 252.201018 -53.070263) (xy 252.145621 -53.131029)
			(xy 252.084853 -53.186426) (xy 252.019234 -53.235979) (xy 251.949323 -53.279267) (xy 251.875716 -53.31592)
			(xy 251.799041 -53.345626) (xy 251.719952 -53.36813) (xy 251.639125 -53.383242) (xy 251.557248 -53.390832)
			(xy 251.516134 -53.391308) (xy 251.471924 -53.390745) (xy 251.383942 -53.381965) (xy 251.297264 -53.3645)
			(xy 251.212747 -53.33852) (xy 251.131225 -53.304282) (xy 251.053503 -53.262125) (xy 250.980346 -53.212465)
			(xy 250.912478 -53.15579) (xy 250.881134 -53.124608) (xy 250.873005 -53.117104) (xy 250.852316 -53.109337)
			(xy 250.841256 -53.109622) (xy 250.825846 -53.110663) (xy 250.794978 -53.111806) (xy 250.779534 -53.111908)
			(xy 250.737779 -53.111492) (xy 250.654637 -53.103677) (xy 250.572592 -53.088104) (xy 250.492369 -53.064909)
			(xy 250.414673 -53.034297) (xy 250.340188 -52.996537) (xy 250.269571 -52.951961) (xy 250.203442 -52.900963)
			(xy 250.142385 -52.843991) (xy 250.086937 -52.781547) (xy 250.037585 -52.714181) (xy 249.994765 -52.642486)
			(xy 249.958854 -52.567092) (xy 249.930167 -52.488665) (xy 249.908958 -52.407894) (xy 249.895413 -52.32549)
			(xy 249.892058 -52.283868) (xy 249.891061 -52.274773) (xy 249.88348 -52.258135) (xy 249.870549 -52.245209)
			(xy 249.853908 -52.237634) (xy 249.844814 -52.236624) (xy 249.805225 -52.23352) (xy 249.726783 -52.221122)
			(xy 249.649759 -52.201775) (xy 249.574769 -52.175634) (xy 249.50241 -52.142907) (xy 249.433259 -52.103855)
			(xy 249.400314 -52.081684) (xy 249.392012 -52.076461) (xy 249.372875 -52.072218) (xy 249.353539 -52.075433)
			(xy 249.344942 -52.08016) (xy 249.312459 -52.099495) (xy 249.244799 -52.133223) (xy 249.174522 -52.161088)
			(xy 249.13844 -52.172362) (xy 249.128616 -52.175851) (xy 249.112727 -52.189319) (xy 249.103444 -52.207965)
			(xy 249.102372 -52.218336) (xy 249.099675 -52.260463) (xy 249.087279 -52.34397) (xy 249.067027 -52.425926)
			(xy 249.039099 -52.505595) (xy 249.003748 -52.582258) (xy 248.961291 -52.655227) (xy 248.912112 -52.723845)
			(xy 248.856651 -52.787493) (xy 248.795409 -52.8456) (xy 248.728936 -52.897642) (xy 248.657831 -52.943151)
			(xy 248.582733 -52.981717) (xy 248.504319 -53.012994) (xy 248.423294 -53.036699) (xy 248.340387 -53.052621)
			(xy 248.256345 -53.060614) (xy 248.214134 -53.061108) (xy 248.171669 -53.060607) (xy 248.087125 -53.052507)
			(xy 248.003739 -53.036385) (xy 247.922268 -53.01239) (xy 247.843456 -52.98074) (xy 247.768018 -52.941722)
			(xy 247.696643 -52.895693) (xy 247.629979 -52.84307) (xy 247.568634 -52.784334) (xy 247.540526 -52.752498)
			(xy 247.534176 -52.745132) (xy 247.517412 -52.736496) (xy 247.429274 -52.726336) (xy 247.410986 -52.731416)
			(xy 247.403112 -52.737258) (xy 247.370277 -52.761024) (xy 247.301045 -52.803187) (xy 247.228263 -52.838875)
			(xy 247.152535 -52.867791) (xy 247.07449 -52.889697) (xy 246.994775 -52.904409) (xy 246.914052 -52.911805)
			(xy 246.873522 -52.912264) (xy 246.831202 -52.911724) (xy 246.746946 -52.903656) (xy 246.663838 -52.887619)
			(xy 246.58263 -52.863758) (xy 246.504056 -52.83229) (xy 246.428827 -52.793499) (xy 246.392954 -52.77104)
			(xy 246.38456 -52.766177) (xy 246.365522 -52.762524) (xy 246.346484 -52.766177) (xy 246.33809 -52.77104)
			(xy 246.302222 -52.793507) (xy 246.226987 -52.832285) (xy 246.148411 -52.863747) (xy 246.067203 -52.887609)
			(xy 245.984096 -52.903654) (xy 245.899842 -52.911738) (xy 245.857522 -52.912264) (xy 245.813221 -52.911666)
			(xy 245.725058 -52.90285) (xy 245.638208 -52.885314) (xy 245.553531 -52.85923) (xy 245.471867 -52.824858)
			(xy 245.394025 -52.782538) (xy 245.320775 -52.732689) (xy 245.252843 -52.675806) (xy 245.190903 -52.61245)
			(xy 245.135568 -52.543252) (xy 245.111016 -52.506372) (xy 245.106055 -52.499361) (xy 245.092457 -52.488884)
			(xy 245.076169 -52.483465) (xy 245.067582 -52.483258) (xy 245.060978 -52.483258) (xy 245.033722 -52.482865)
			(xy 244.979766 -52.475104) (xy 244.927464 -52.459743) (xy 244.87788 -52.437094) (xy 244.832025 -52.407619)
			(xy 244.790831 -52.371918) (xy 244.755138 -52.330717) (xy 244.725671 -52.284856) (xy 244.703032 -52.235269)
			(xy 244.68768 -52.182963) (xy 244.679929 -52.129006) (xy 244.67947 -52.10175) (xy 239.571949 -52.10175)
			(xy 239.571907 -52.102948) (xy 239.565586 -52.12424) (xy 239.559846 -52.133754) (xy 239.367314 -52.427378)
			(xy 239.361609 -52.436761) (xy 239.355271 -52.457774) (xy 239.355198 -52.479722) (xy 239.361394 -52.500777)
			(xy 239.36706 -52.510182) (xy 239.559846 -52.806346) (xy 239.565592 -52.815858) (xy 239.571918 -52.83715)
			(xy 239.572292 -52.848256) (xy 239.572292 -53.04282) (xy 239.571852 -53.054897) (xy 239.564382 -53.077868)
			(xy 239.55018 -53.097406) (xy 239.530635 -53.111599) (xy 239.507661 -53.119058) (xy 239.495584 -53.119528)
			(xy 238.809784 -53.119528) (xy 238.797711 -53.11905) (xy 238.774746 -53.111585) (xy 238.755211 -53.097391)
			(xy 238.741017 -53.077857) (xy 238.733551 -53.054893) (xy 238.733076 -53.04282) (xy 237.203212 -53.04282)
			(xy 237.19384 -53.049624) (xy 237.170863 -53.057083) (xy 237.158784 -53.057552) (xy 236.041184 -53.057552)
			(xy 236.029113 -53.05705) (xy 236.006153 -53.049588) (xy 235.98662 -53.0354) (xy 235.972424 -53.015872)
			(xy 235.964954 -52.992915) (xy 235.964476 -52.980844) (xy 232.635552 -52.980844) (xy 232.635074 -52.992916)
			(xy 232.627605 -53.015878) (xy 232.61341 -53.03541) (xy 232.593878 -53.049605) (xy 232.570916 -53.057074)
			(xy 232.558844 -53.057552) (xy 231.441244 -53.057552) (xy 231.429176 -53.056999) (xy 231.406218 -53.049554)
			(xy 231.386684 -53.035379) (xy 231.372486 -53.015861) (xy 231.365015 -52.992911) (xy 231.364536 -52.980844)
			(xy 207.771937 -52.980844) (xy 207.755091 -53.035918) (xy 207.70005 -53.188443) (xy 207.637535 -53.33806)
			(xy 207.567696 -53.484401) (xy 207.490706 -53.62711) (xy 207.406753 -53.765837) (xy 207.316041 -53.900242)
			(xy 207.218794 -54.029997) (xy 207.115249 -54.154784) (xy 207.00566 -54.274298) (xy 206.890294 -54.388245)
			(xy 206.769434 -54.496348) (xy 206.643376 -54.598342) (xy 206.512428 -54.693977) (xy 206.380073 -54.780942)
			(xy 231.364536 -54.780942) (xy 231.364536 -53.749194) (xy 231.365002 -53.737105) (xy 231.37246 -53.714104)
			(xy 231.386647 -53.694525) (xy 231.40618 -53.680275) (xy 231.429156 -53.672742) (xy 231.441244 -53.672232)
			(xy 232.558844 -53.672232) (xy 232.570958 -53.672579) (xy 232.593993 -53.680095) (xy 232.613568 -53.694373)
			(xy 232.62776 -53.714011) (xy 232.635173 -53.737078) (xy 232.635552 -53.749194) (xy 232.635552 -54.780942)
			(xy 235.964476 -54.780942) (xy 235.964476 -53.749194) (xy 235.964903 -53.737101) (xy 235.972366 -53.714094)
			(xy 235.986561 -53.694511) (xy 236.006106 -53.680262) (xy 236.029092 -53.672736) (xy 236.041184 -53.672232)
			(xy 237.158784 -53.672232) (xy 237.170895 -53.672631) (xy 237.193927 -53.680129) (xy 237.213503 -53.694394)
			(xy 237.227697 -53.714022) (xy 237.235113 -53.737081) (xy 237.235492 -53.749194) (xy 237.235492 -54.780942)
			(xy 237.235029 -54.793031) (xy 237.227565 -54.816027) (xy 237.213376 -54.835604) (xy 237.193844 -54.849854)
			(xy 237.187888 -54.851808) (xy 238.733076 -54.851808) (xy 238.733076 -54.657244) (xy 238.733425 -54.646135)
			(xy 238.739758 -54.624838) (xy 238.745522 -54.615334) (xy 238.938054 -54.32044) (xy 238.943724 -54.311035)
			(xy 238.950004 -54.290005) (xy 238.950013 -54.268058) (xy 238.943751 -54.247023) (xy 238.938054 -54.237636)
			(xy 238.745522 -53.944012) (xy 238.739767 -53.934505) (xy 238.733445 -53.913209) (xy 238.733076 -53.902102)
			(xy 238.733076 -53.706268) (xy 238.733536 -53.694193) (xy 238.741006 -53.671228) (xy 238.755204 -53.651693)
			(xy 238.774742 -53.637499) (xy 238.797709 -53.630034) (xy 238.809784 -53.62956) (xy 239.495584 -53.62956)
			(xy 239.507655 -53.630077) (xy 239.530616 -53.637532) (xy 239.55015 -53.651715) (xy 239.564347 -53.671241)
			(xy 239.571815 -53.694198) (xy 239.572292 -53.706268) (xy 239.572292 -53.900832) (xy 239.571902 -53.911936)
			(xy 239.565584 -53.933228) (xy 239.559846 -53.942742) (xy 239.367314 -54.236366) (xy 239.361619 -54.245754)
			(xy 239.355279 -54.266765) (xy 239.355203 -54.288711) (xy 239.361396 -54.309765) (xy 239.36706 -54.31917)
			(xy 239.559846 -54.615334) (xy 239.565587 -54.624848) (xy 239.571917 -54.646139) (xy 239.572292 -54.657244)
			(xy 239.572292 -54.851808) (xy 239.571894 -54.863893) (xy 239.564422 -54.886879) (xy 239.550213 -54.90643)
			(xy 239.530657 -54.920633) (xy 239.507669 -54.928098) (xy 239.495584 -54.928516) (xy 238.809784 -54.928516)
			(xy 238.797709 -54.928049) (xy 238.774743 -54.920583) (xy 238.755207 -54.906387) (xy 238.741013 -54.88685)
			(xy 238.733549 -54.863883) (xy 238.733076 -54.851808) (xy 237.187888 -54.851808) (xy 237.170871 -54.857391)
			(xy 237.158784 -54.857904) (xy 236.041184 -54.857904) (xy 236.029075 -54.857497) (xy 236.006048 -54.849994)
			(xy 235.986475 -54.83573) (xy 235.972281 -54.816107) (xy 235.96486 -54.793053) (xy 235.964476 -54.780942)
			(xy 232.635552 -54.780942) (xy 232.635128 -54.793035) (xy 232.627659 -54.816038) (xy 232.613462 -54.835618)
			(xy 232.593919 -54.849867) (xy 232.570935 -54.857396) (xy 232.558844 -54.857904) (xy 231.441244 -54.857904)
			(xy 231.429138 -54.857446) (xy 231.406113 -54.849959) (xy 231.386539 -54.835708) (xy 231.372343 -54.816095)
			(xy 231.36492 -54.793049) (xy 231.364536 -54.780942) (xy 206.380073 -54.780942) (xy 206.376912 -54.783019)
			(xy 206.237157 -54.86525) (xy 206.093507 -54.940469) (xy 205.946312 -55.008492) (xy 205.795934 -55.069153)
			(xy 205.64274 -55.122303) (xy 205.487105 -55.167811) (xy 205.32941 -55.205567) (xy 205.17004 -55.235479)
			(xy 205.009386 -55.257472) (xy 204.847842 -55.271493) (xy 204.685801 -55.277509) (xy 204.523661 -55.275503)
			(xy 204.361819 -55.265482) (xy 204.200671 -55.247469) (xy 204.04061 -55.221509) (xy 203.882029 -55.187664)
			(xy 203.725316 -55.146019) (xy 203.570854 -55.096675) (xy 203.419022 -55.039753) (xy 203.27019 -54.975391)
			(xy 203.124723 -54.903748) (xy 202.982977 -54.824999) (xy 202.845299 -54.739336) (xy 202.712026 -54.646969)
			(xy 202.583484 -54.548125) (xy 202.459987 -54.443044) (xy 202.341839 -54.331985) (xy 202.229327 -54.215219)
			(xy 202.122727 -54.093031) (xy 202.0223 -53.965721) (xy 201.928292 -53.833601) (xy 201.840933 -53.696993)
			(xy 201.760436 -53.556232) (xy 201.687 -53.411662) (xy 201.620802 -53.263638) (xy 201.562006 -53.112521)
			(xy 201.510755 -52.958681) (xy 201.467175 -52.802495) (xy 201.431372 -52.644345) (xy 201.403434 -52.484618)
			(xy 201.38343 -52.323704) (xy 201.371407 -52.161999) (xy 201.367397 -51.999896) (xy 179.393596 -51.999896)
			(xy 179.393596 -52.481734) (xy 179.39311 -52.509003) (xy 179.385348 -52.562987) (xy 179.369983 -52.615317)
			(xy 179.347326 -52.664927) (xy 179.31784 -52.710808) (xy 179.282125 -52.752025) (xy 179.240908 -52.78774)
			(xy 179.195027 -52.817226) (xy 179.145417 -52.839883) (xy 179.093087 -52.855248) (xy 179.039103 -52.86301)
			(xy 178.984565 -52.86301) (xy 178.930581 -52.855248) (xy 178.878251 -52.839883) (xy 178.828641 -52.817226)
			(xy 178.78276 -52.78774) (xy 178.741543 -52.752025) (xy 178.705828 -52.710808) (xy 178.676342 -52.664927)
			(xy 178.653685 -52.615317) (xy 178.63832 -52.562987) (xy 178.630558 -52.509003) (xy 178.630072 -52.481734)
			(xy 177.907308 -52.481734) (xy 177.901325 -52.50016) (xy 177.887071 -52.51978) (xy 177.86745 -52.53403)
			(xy 177.844383 -52.541516) (xy 177.832258 -52.541932) (xy 176.384458 -52.541932) (xy 176.372338 -52.541524)
			(xy 176.349289 -52.534021) (xy 176.329685 -52.519764) (xy 176.315446 -52.500147) (xy 176.307965 -52.47709)
			(xy 176.307496 -52.46497) (xy 0.509016 -52.46497) (xy 0.509016 -53.965094) (xy 176.307496 -53.965094)
			(xy 176.307496 -53.135022) (xy 176.30803 -53.122913) (xy 176.315506 -53.099877) (xy 176.329733 -53.080279)
			(xy 176.34932 -53.066035) (xy 176.372349 -53.05854) (xy 176.384458 -53.05806) (xy 177.832258 -53.05806)
			(xy 177.844381 -53.058496) (xy 177.867442 -53.065979) (xy 177.88706 -53.080226) (xy 177.901312 -53.09984)
			(xy 177.908801 -53.122899) (xy 177.90922 -53.135022) (xy 177.90922 -53.965094) (xy 177.908834 -53.977221)
			(xy 177.901338 -54.000286) (xy 177.887079 -54.019905) (xy 177.867454 -54.034155) (xy 177.844385 -54.04164)
			(xy 177.832258 -54.042056) (xy 176.384458 -54.042056) (xy 176.372341 -54.041624) (xy 176.349295 -54.034124)
			(xy 176.329693 -54.019872) (xy 176.315454 -54.000262) (xy 176.307968 -53.977212) (xy 176.307496 -53.965094)
			(xy 0.509016 -53.965094) (xy 0.509016 -54.095904) (xy 180.10886 -54.095904) (xy 180.10886 -53.90134)
			(xy 180.109209 -53.890231) (xy 180.115543 -53.868935) (xy 180.121306 -53.85943) (xy 180.313838 -53.564536)
			(xy 180.319512 -53.555134) (xy 180.325793 -53.534103) (xy 180.325801 -53.512154) (xy 180.319536 -53.491118)
			(xy 180.313838 -53.481732) (xy 180.121306 -53.188108) (xy 180.115548 -53.178603) (xy 180.109228 -53.157306)
			(xy 180.10886 -53.146198) (xy 180.10886 -52.950364) (xy 180.109333 -52.938291) (xy 180.116801 -52.915328)
			(xy 180.130997 -52.895794) (xy 180.150531 -52.8816) (xy 180.173495 -52.874132) (xy 180.185568 -52.873656)
			(xy 180.871368 -52.873656) (xy 180.883437 -52.874191) (xy 180.906397 -52.88164) (xy 180.925932 -52.89582)
			(xy 180.940129 -52.915342) (xy 180.947599 -52.938295) (xy 180.948076 -52.950364) (xy 180.948076 -53.144928)
			(xy 180.947687 -53.156032) (xy 180.941369 -53.177324) (xy 180.93563 -53.186838) (xy 180.743098 -53.480462)
			(xy 180.737407 -53.489853) (xy 180.731068 -53.510862) (xy 180.730991 -53.532807) (xy 180.737182 -53.55386)
			(xy 180.742844 -53.563266) (xy 180.93563 -53.85943) (xy 180.941368 -53.868946) (xy 180.9477 -53.890235)
			(xy 180.948076 -53.90134) (xy 180.948076 -53.954934) (xy 181.659784 -53.954934) (xy 181.659784 -53.091334)
			(xy 181.66027 -53.064065) (xy 181.668032 -53.010081) (xy 181.683397 -52.957751) (xy 181.706054 -52.908141)
			(xy 181.73554 -52.86226) (xy 181.771255 -52.821043) (xy 181.812472 -52.785328) (xy 181.858353 -52.755842)
			(xy 181.907963 -52.733185) (xy 181.960293 -52.71782) (xy 182.014277 -52.710058) (xy 182.068815 -52.710058)
			(xy 182.122799 -52.71782) (xy 182.175129 -52.733185) (xy 182.224739 -52.755842) (xy 182.27062 -52.785328)
			(xy 182.311837 -52.821043) (xy 182.347552 -52.86226) (xy 182.377038 -52.908141) (xy 182.399695 -52.957751)
			(xy 182.41506 -53.010081) (xy 182.422822 -53.064065) (xy 182.423308 -53.091334) (xy 182.423308 -53.954934)
			(xy 182.422822 -53.982203) (xy 182.41506 -54.036187) (xy 182.399695 -54.088517) (xy 182.377038 -54.138127)
			(xy 182.347552 -54.184008) (xy 182.311837 -54.225225) (xy 182.27062 -54.26094) (xy 182.224739 -54.290426)
			(xy 182.175129 -54.313083) (xy 182.122799 -54.328448) (xy 182.068815 -54.33621) (xy 182.014277 -54.33621)
			(xy 181.960293 -54.328448) (xy 181.907963 -54.313083) (xy 181.858353 -54.290426) (xy 181.812472 -54.26094)
			(xy 181.771255 -54.225225) (xy 181.73554 -54.184008) (xy 181.706054 -54.138127) (xy 181.683397 -54.088517)
			(xy 181.668032 -54.036187) (xy 181.66027 -53.982203) (xy 181.659784 -53.954934) (xy 180.948076 -53.954934)
			(xy 180.948076 -54.095904) (xy 180.94769 -54.10799) (xy 180.940218 -54.130978) (xy 180.926006 -54.150532)
			(xy 180.906446 -54.164734) (xy 180.883454 -54.172196) (xy 180.871368 -54.172612) (xy 180.185568 -54.172612)
			(xy 180.173492 -54.172163) (xy 180.150525 -54.164692) (xy 180.130988 -54.150492) (xy 180.116795 -54.13095)
			(xy 180.109332 -54.10798) (xy 180.10886 -54.095904) (xy 0.509016 -54.095904) (xy 0.509016 -55.464964)
			(xy 176.307496 -55.464964) (xy 176.307496 -54.634892) (xy 176.307953 -54.622842) (xy 176.315388 -54.599917)
			(xy 176.329529 -54.580401) (xy 176.349 -54.566198) (xy 176.371901 -54.558692) (xy 176.38395 -54.558184)
			(xy 177.832258 -54.558184) (xy 177.84435 -54.558644) (xy 177.867356 -54.566094) (xy 177.886941 -54.580281)
			(xy 177.901191 -54.599819) (xy 177.908716 -54.622802) (xy 177.90922 -54.634892) (xy 177.90922 -55.464964)
			(xy 177.90871 -55.47701) (xy 177.907182 -55.481728) (xy 178.630072 -55.481728) (xy 178.630072 -54.618128)
			(xy 178.630558 -54.590859) (xy 178.63832 -54.536875) (xy 178.653685 -54.484545) (xy 178.676342 -54.434935)
			(xy 178.705828 -54.389054) (xy 178.741543 -54.347837) (xy 178.78276 -54.312122) (xy 178.828641 -54.282636)
			(xy 178.878251 -54.259979) (xy 178.930581 -54.244614) (xy 178.984565 -54.236852) (xy 179.039103 -54.236852)
			(xy 179.093087 -54.244614) (xy 179.145417 -54.259979) (xy 179.195027 -54.282636) (xy 179.240908 -54.312122)
			(xy 179.282125 -54.347837) (xy 179.31784 -54.389054) (xy 179.347326 -54.434935) (xy 179.369983 -54.484545)
			(xy 179.385348 -54.536875) (xy 179.39311 -54.590859) (xy 179.393596 -54.618128) (xy 179.393596 -55.481728)
			(xy 179.39311 -55.508997) (xy 179.385348 -55.562981) (xy 179.369983 -55.615311) (xy 179.347326 -55.664921)
			(xy 179.31784 -55.710802) (xy 179.282125 -55.752019) (xy 179.240908 -55.787734) (xy 179.195027 -55.81722)
			(xy 179.145417 -55.839877) (xy 179.093087 -55.855242) (xy 179.039103 -55.863004) (xy 178.984565 -55.863004)
			(xy 178.930581 -55.855242) (xy 178.878251 -55.839877) (xy 178.828641 -55.81722) (xy 178.78276 -55.787734)
			(xy 178.741543 -55.752019) (xy 178.705828 -55.710802) (xy 178.676342 -55.664921) (xy 178.653685 -55.615311)
			(xy 178.63832 -55.562981) (xy 178.630558 -55.508997) (xy 178.630072 -55.481728) (xy 177.907182 -55.481728)
			(xy 177.901289 -55.499931) (xy 177.887161 -55.519446) (xy 177.867702 -55.533651) (xy 177.84481 -55.541162)
			(xy 177.832766 -55.541672) (xy 176.384458 -55.541672) (xy 176.372367 -55.541229) (xy 176.349367 -55.533762)
			(xy 176.329789 -55.519569) (xy 176.31554 -55.500032) (xy 176.308007 -55.477053) (xy 176.307496 -55.464964)
			(xy 0.509016 -55.464964) (xy 0.509016 -57.094435) (xy 170.842169 -57.094435) (xy 170.842169 -57.005413)
			(xy 170.850149 -56.916749) (xy 170.866045 -56.829158) (xy 170.889728 -56.743343) (xy 170.921008 -56.659998)
			(xy 170.959634 -56.579792) (xy 171.005293 -56.503371) (xy 171.057619 -56.43135) (xy 171.11619 -56.36431)
			(xy 171.180535 -56.30279) (xy 171.250135 -56.247286) (xy 171.324431 -56.198244) (xy 171.402823 -56.156059)
			(xy 171.484682 -56.121071) (xy 171.569347 -56.093562) (xy 171.656137 -56.073752) (xy 171.744353 -56.061802)
			(xy 171.833286 -56.057809) (xy 171.922219 -56.061802) (xy 172.010435 -56.073752) (xy 172.097225 -56.093562)
			(xy 172.18189 -56.121071) (xy 172.263749 -56.156059) (xy 172.342141 -56.198244) (xy 172.416437 -56.247286)
			(xy 172.486037 -56.30279) (xy 172.550382 -56.36431) (xy 172.608953 -56.43135) (xy 172.661279 -56.503371)
			(xy 172.706938 -56.579792) (xy 172.707417 -56.580786) (xy 231.364536 -56.580786) (xy 231.364536 -55.549038)
			(xy 231.36504 -55.536951) (xy 231.372485 -55.513952) (xy 231.386663 -55.494372) (xy 231.406189 -55.48012)
			(xy 231.429159 -55.472586) (xy 231.441244 -55.472076) (xy 232.558844 -55.472076) (xy 232.570953 -55.472479)
			(xy 232.593977 -55.479987) (xy 232.613548 -55.494253) (xy 232.627742 -55.513876) (xy 232.635166 -55.536928)
			(xy 232.635552 -55.549038) (xy 232.635552 -56.580786) (xy 235.964476 -56.580786) (xy 235.964476 -55.549038)
			(xy 235.96494 -55.536947) (xy 235.972391 -55.513941) (xy 235.986577 -55.494358) (xy 236.006114 -55.480107)
			(xy 236.029094 -55.472581) (xy 236.041184 -55.472076) (xy 237.158784 -55.472076) (xy 237.17089 -55.47253)
			(xy 237.193912 -55.480022) (xy 237.213483 -55.494275) (xy 237.227679 -55.513887) (xy 237.235105 -55.536931)
			(xy 237.235492 -55.549038) (xy 237.235492 -56.580786) (xy 237.234981 -56.592872) (xy 237.227532 -56.615866)
			(xy 237.213356 -56.635444) (xy 237.203331 -56.642762) (xy 240.434876 -56.642762) (xy 240.434876 -56.448198)
			(xy 240.435247 -56.437091) (xy 240.441565 -56.415794) (xy 240.447322 -56.406288) (xy 240.639854 -56.111394)
			(xy 240.645563 -56.102011) (xy 240.651835 -56.080971) (xy 240.651833 -56.059016) (xy 240.645557 -56.037977)
			(xy 240.639854 -56.02859) (xy 240.447322 -55.734966) (xy 240.441587 -55.725449) (xy 240.435252 -55.704161)
			(xy 240.434876 -55.693056) (xy 240.434876 -55.497222) (xy 240.435327 -55.48513) (xy 240.442782 -55.462124)
			(xy 240.456971 -55.442541) (xy 240.476511 -55.428291) (xy 240.499494 -55.420765) (xy 240.511584 -55.42026)
			(xy 241.197384 -55.42026) (xy 241.209488 -55.42073) (xy 241.232508 -55.42822) (xy 241.252078 -55.442469)
			(xy 241.266274 -55.462077) (xy 241.273703 -55.485117) (xy 241.274092 -55.497222) (xy 241.274092 -55.691786)
			(xy 241.273724 -55.702892) (xy 241.267391 -55.724184) (xy 241.261646 -55.733696) (xy 241.069114 -56.02732)
			(xy 241.063373 -56.036683) (xy 241.057043 -56.057705) (xy 241.05698 -56.07966) (xy 241.063188 -56.100719)
			(xy 241.06886 -56.110124) (xy 241.261646 -56.406288) (xy 241.267407 -56.415791) (xy 241.273724 -56.43709)
			(xy 241.274092 -56.448198) (xy 241.274092 -56.642762) (xy 241.273561 -56.654846) (xy 241.266118 -56.67784)
			(xy 241.251947 -56.697418) (xy 241.232429 -56.711671) (xy 241.209466 -56.71921) (xy 241.197384 -56.719724)
			(xy 240.511584 -56.719724) (xy 240.499477 -56.719298) (xy 240.476453 -56.711797) (xy 240.456882 -56.697537)
			(xy 240.442687 -56.677919) (xy 240.435263 -56.654871) (xy 240.434876 -56.642762) (xy 237.203331 -56.642762)
			(xy 237.193833 -56.649696) (xy 237.170868 -56.657234) (xy 237.158784 -56.657748) (xy 236.041184 -56.657748)
			(xy 236.029079 -56.657298) (xy 236.006059 -56.6498) (xy 235.986491 -56.635545) (xy 235.972295 -56.615934)
			(xy 235.964866 -56.592892) (xy 235.964476 -56.580786) (xy 232.635552 -56.580786) (xy 232.63508 -56.592876)
			(xy 232.627627 -56.615877) (xy 232.613441 -56.635458) (xy 232.593908 -56.649709) (xy 232.570932 -56.65724)
			(xy 232.558844 -56.657748) (xy 231.441244 -56.657748) (xy 231.429142 -56.657247) (xy 231.406125 -56.649765)
			(xy 231.386555 -56.635524) (xy 231.372357 -56.615923) (xy 231.364927 -56.592889) (xy 231.364536 -56.580786)
			(xy 172.707417 -56.580786) (xy 172.745564 -56.659998) (xy 172.776844 -56.743343) (xy 172.800527 -56.829158)
			(xy 172.816423 -56.916749) (xy 172.824403 -57.005413) (xy 172.824902 -57.049924) (xy 172.824403 -57.094435)
			(xy 172.816423 -57.183099) (xy 172.800527 -57.27069) (xy 172.776844 -57.356505) (xy 172.745564 -57.43985)
			(xy 172.706938 -57.520056) (xy 172.661279 -57.596477) (xy 172.608953 -57.668498) (xy 172.550382 -57.735538)
			(xy 172.486037 -57.797058) (xy 172.416437 -57.852562) (xy 172.342141 -57.901604) (xy 172.263749 -57.943789)
			(xy 172.18189 -57.978777) (xy 172.097225 -58.006286) (xy 172.010435 -58.026096) (xy 171.922219 -58.038046)
			(xy 171.833286 -58.04204) (xy 171.744353 -58.038046) (xy 171.656137 -58.026096) (xy 171.569347 -58.006286)
			(xy 171.484682 -57.978777) (xy 171.402823 -57.943789) (xy 171.324431 -57.901604) (xy 171.250135 -57.852562)
			(xy 171.180535 -57.797058) (xy 171.11619 -57.735538) (xy 171.057619 -57.668498) (xy 171.005293 -57.596477)
			(xy 170.959634 -57.520056) (xy 170.921008 -57.43985) (xy 170.889728 -57.356505) (xy 170.866045 -57.27069)
			(xy 170.850149 -57.183099) (xy 170.842169 -57.094435) (xy 0.509016 -57.094435) (xy 0.509016 -58.380884)
			(xy 231.364536 -58.380884) (xy 231.364536 -57.349136) (xy 231.364944 -57.337051) (xy 231.372407 -57.314062)
			(xy 231.386613 -57.294507) (xy 231.406169 -57.280303) (xy 231.429159 -57.272843) (xy 231.441244 -57.272428)
			(xy 232.558844 -57.272428) (xy 232.570924 -57.272827) (xy 232.593899 -57.280306) (xy 232.613439 -57.294518)
			(xy 232.62763 -57.314073) (xy 232.635085 -57.337055) (xy 232.635552 -57.349136) (xy 232.635552 -58.380884)
			(xy 235.964476 -58.380884) (xy 235.964476 -57.349136) (xy 235.964943 -57.337057) (xy 235.972399 -57.314078)
			(xy 235.986591 -57.294528) (xy 236.006131 -57.280323) (xy 236.029105 -57.272851) (xy 236.041184 -57.272428)
			(xy 237.158784 -57.272428) (xy 237.170869 -57.272827) (xy 237.193858 -57.280295) (xy 237.213411 -57.294503)
			(xy 237.227615 -57.31406) (xy 237.235076 -57.33705) (xy 237.235492 -57.349136) (xy 237.235492 -58.380884)
			(xy 237.235073 -58.392967) (xy 237.227608 -58.415952) (xy 237.213404 -58.435504) (xy 237.203278 -58.44286)
			(xy 238.733076 -58.44286) (xy 238.733076 -58.248296) (xy 238.733446 -58.237188) (xy 238.739765 -58.215892)
			(xy 238.745522 -58.206386) (xy 238.938054 -57.911492) (xy 238.943765 -57.90211) (xy 238.950036 -57.881069)
			(xy 238.950033 -57.859114) (xy 238.943758 -57.838075) (xy 238.938054 -57.828688) (xy 238.745522 -57.535064)
			(xy 238.739786 -57.525547) (xy 238.733452 -57.504259) (xy 238.733076 -57.493154) (xy 238.733076 -57.29732)
			(xy 238.73353 -57.28524) (xy 238.74099 -57.262261) (xy 238.755186 -57.242711) (xy 238.774728 -57.228506)
			(xy 238.797704 -57.221035) (xy 238.809784 -57.220612) (xy 239.495584 -57.220612) (xy 239.507668 -57.221027)
			(xy 239.530653 -57.228492) (xy 239.550206 -57.242697) (xy 239.56441 -57.26225) (xy 239.571874 -57.285236)
			(xy 239.572292 -57.29732) (xy 239.572292 -57.491884) (xy 239.571923 -57.50299) (xy 239.565591 -57.524281)
			(xy 239.559846 -57.533794) (xy 239.367314 -57.827418) (xy 239.361574 -57.836782) (xy 239.355244 -57.857804)
			(xy 239.355181 -57.879758) (xy 239.361388 -57.900817) (xy 239.36706 -57.910222) (xy 239.559846 -58.206386)
			(xy 239.565607 -58.21589) (xy 239.571924 -58.237188) (xy 239.572292 -58.248296) (xy 239.572292 -58.44286)
			(xy 239.571853 -58.454942) (xy 239.564395 -58.477926) (xy 239.550196 -58.497479) (xy 239.530648 -58.511684)
			(xy 239.507666 -58.519149) (xy 239.495584 -58.519568) (xy 238.809784 -58.519568) (xy 238.797696 -58.5192)
			(xy 238.774706 -58.511724) (xy 238.755153 -58.497507) (xy 238.740951 -58.477943) (xy 238.733491 -58.454948)
			(xy 238.733076 -58.44286) (xy 237.203278 -58.44286) (xy 237.193852 -58.449708) (xy 237.170867 -58.457173)
			(xy 237.158784 -58.457592) (xy 236.041184 -58.457592) (xy 236.029107 -58.457149) (xy 236.006137 -58.44968)
			(xy 235.986599 -58.435479) (xy 235.972405 -58.415935) (xy 235.964946 -58.392961) (xy 235.964476 -58.380884)
			(xy 232.635552 -58.380884) (xy 232.635023 -58.392953) (xy 232.62757 -58.415913) (xy 232.613389 -58.435446)
			(xy 232.593866 -58.449643) (xy 232.570913 -58.457113) (xy 232.558844 -58.457592) (xy 231.441244 -58.457592)
			(xy 231.429162 -58.45715) (xy 231.406178 -58.449692) (xy 231.386626 -58.435494) (xy 231.372421 -58.415947)
			(xy 231.364955 -58.392966) (xy 231.364536 -58.380884) (xy 0.509016 -58.380884) (xy 0.509016 -60.375038)
			(xy 233.333297 -60.375038) (xy 233.337302 -60.28713) (xy 233.349285 -60.19995) (xy 233.369145 -60.114221)
			(xy 233.39672 -60.030653) (xy 233.431779 -59.949939) (xy 233.474032 -59.872747) (xy 233.52313 -59.799718)
			(xy 233.578666 -59.731456) (xy 233.640178 -59.668526) (xy 233.707159 -59.611452) (xy 233.779052 -59.560704)
			(xy 233.855261 -59.516704) (xy 233.935156 -59.479817) (xy 234.018075 -59.450348) (xy 234.10333 -59.428541)
			(xy 234.190214 -59.414577) (xy 234.278008 -59.408571) (xy 234.365985 -59.410575) (xy 234.453415 -59.42057)
			(xy 234.539574 -59.438474) (xy 234.623748 -59.464138) (xy 234.705239 -59.497351) (xy 234.783373 -59.537837)
			(xy 234.857501 -59.585259) (xy 234.927009 -59.639226) (xy 234.991323 -59.699291) (xy 235.049907 -59.764955)
			(xy 235.102278 -59.835674) (xy 235.148001 -59.910862) (xy 235.186698 -59.989897) (xy 235.218047 -60.072123)
			(xy 235.241789 -60.156859) (xy 235.257727 -60.243403) (xy 235.265729 -60.331038) (xy 235.26623 -60.375038)
			(xy 235.265729 -60.419038) (xy 235.257727 -60.506673) (xy 235.241789 -60.593217) (xy 235.218047 -60.677953)
			(xy 235.186698 -60.760179) (xy 235.148001 -60.839214) (xy 235.102278 -60.914402) (xy 235.049907 -60.985121)
			(xy 234.991323 -61.050785) (xy 234.927009 -61.11085) (xy 234.857501 -61.164817) (xy 234.783373 -61.212239)
			(xy 234.705239 -61.252725) (xy 234.623748 -61.285938) (xy 234.539574 -61.311602) (xy 234.453415 -61.329506)
			(xy 234.365985 -61.339501) (xy 234.278008 -61.341505) (xy 234.190214 -61.335499) (xy 234.10333 -61.321535)
			(xy 234.018075 -61.299728) (xy 233.935156 -61.270259) (xy 233.855261 -61.233372) (xy 233.779052 -61.189372)
			(xy 233.707159 -61.138624) (xy 233.640178 -61.08155) (xy 233.578666 -61.01862) (xy 233.52313 -60.950358)
			(xy 233.474032 -60.877329) (xy 233.431779 -60.800137) (xy 233.39672 -60.719423) (xy 233.369145 -60.635855)
			(xy 233.349285 -60.550126) (xy 233.337302 -60.462946) (xy 233.333297 -60.375038) (xy 0.509016 -60.375038)
			(xy 0.509016 -74.760836) (xy 39.554404 -74.760836) (xy 39.554404 -66.060828) (xy 39.554909 -65.955304)
			(xy 39.562993 -65.74441) (xy 39.579149 -65.533981) (xy 39.603352 -65.324324) (xy 39.635569 -65.115749)
			(xy 39.675751 -64.908561) (xy 39.723839 -64.703064) (xy 39.779763 -64.49956) (xy 39.84344 -64.298347)
			(xy 39.914778 -64.09972) (xy 39.993672 -63.903972) (xy 40.080005 -63.71139) (xy 40.173652 -63.522255)
			(xy 40.274474 -63.336846) (xy 40.382324 -63.155435) (xy 40.497043 -62.978288) (xy 40.618463 -62.805666)
			(xy 40.746406 -62.63782) (xy 40.880684 -62.474998) (xy 41.0211 -62.317439) (xy 41.167448 -62.165374)
			(xy 41.319513 -62.019026) (xy 41.477072 -61.87861) (xy 41.639894 -61.744332) (xy 41.80774 -61.616389)
			(xy 41.980362 -61.494969) (xy 42.157509 -61.38025) (xy 42.33892 -61.2724) (xy 42.524329 -61.171578)
			(xy 42.713464 -61.077931) (xy 42.906046 -60.991598) (xy 43.101794 -60.912704) (xy 43.300421 -60.841366)
			(xy 43.501634 -60.777689) (xy 43.705138 -60.721765) (xy 43.910635 -60.673677) (xy 44.117823 -60.633495)
			(xy 44.326398 -60.601278) (xy 44.536055 -60.577075) (xy 44.746484 -60.560919) (xy 44.957378 -60.552835)
			(xy 45.168426 -60.552835) (xy 45.37932 -60.560919) (xy 45.589749 -60.577075) (xy 45.799406 -60.601278)
			(xy 46.007981 -60.633495) (xy 46.215169 -60.673677) (xy 46.420666 -60.721765) (xy 46.62417 -60.777689)
			(xy 46.825383 -60.841366) (xy 47.02401 -60.912704) (xy 47.219758 -60.991598) (xy 47.41234 -61.077931)
			(xy 47.601475 -61.171578) (xy 47.786884 -61.2724) (xy 47.968295 -61.38025) (xy 48.145442 -61.494969)
			(xy 48.318064 -61.616389) (xy 48.48591 -61.744332) (xy 48.648732 -61.87861) (xy 48.806291 -62.019026)
			(xy 48.958356 -62.165374) (xy 49.104704 -62.317439) (xy 49.24512 -62.474998) (xy 49.379398 -62.63782)
			(xy 49.507341 -62.805666) (xy 49.628761 -62.978288) (xy 49.74348 -63.155435) (xy 49.85133 -63.336846)
			(xy 49.952152 -63.522255) (xy 50.045799 -63.71139) (xy 50.132132 -63.903972) (xy 50.211026 -64.09972)
			(xy 50.282364 -64.298347) (xy 50.346041 -64.49956) (xy 50.401965 -64.703064) (xy 50.450053 -64.908561)
			(xy 50.490235 -65.115749) (xy 50.522452 -65.324324) (xy 50.546655 -65.533981) (xy 50.562811 -65.74441)
			(xy 50.570895 -65.955304) (xy 50.5714 -66.060828) (xy 50.5714 -74.760836) (xy 50.571366 -74.767948)
			(xy 173.354492 -74.767948) (xy 173.354492 -66.06794) (xy 173.354997 -65.962416) (xy 173.363081 -65.751522)
			(xy 173.379237 -65.541093) (xy 173.40344 -65.331436) (xy 173.435657 -65.122861) (xy 173.475839 -64.915673)
			(xy 173.523927 -64.710176) (xy 173.579851 -64.506672) (xy 173.643528 -64.305459) (xy 173.714866 -64.106832)
			(xy 173.79376 -63.911084) (xy 173.880093 -63.718502) (xy 173.97374 -63.529367) (xy 174.074562 -63.343958)
			(xy 174.182412 -63.162547) (xy 174.297131 -62.9854) (xy 174.418551 -62.812778) (xy 174.546494 -62.644932)
			(xy 174.680772 -62.48211) (xy 174.821188 -62.324551) (xy 174.967536 -62.172486) (xy 175.119601 -62.026138)
			(xy 175.27716 -61.885722) (xy 175.439982 -61.751444) (xy 175.607828 -61.623501) (xy 175.78045 -61.502081)
			(xy 175.957597 -61.387362) (xy 176.139008 -61.279512) (xy 176.324417 -61.17869) (xy 176.513552 -61.085043)
			(xy 176.706134 -60.99871) (xy 176.901882 -60.919816) (xy 177.100509 -60.848478) (xy 177.301722 -60.784801)
			(xy 177.505226 -60.728877) (xy 177.710723 -60.680789) (xy 177.917911 -60.640607) (xy 178.126486 -60.60839)
			(xy 178.336143 -60.584187) (xy 178.546572 -60.568031) (xy 178.757466 -60.559947) (xy 178.968514 -60.559947)
			(xy 179.179408 -60.568031) (xy 179.389837 -60.584187) (xy 179.599494 -60.60839) (xy 179.808069 -60.640607)
			(xy 180.015257 -60.680789) (xy 180.220754 -60.728877) (xy 180.424258 -60.784801) (xy 180.625471 -60.848478)
			(xy 180.824098 -60.919816) (xy 181.019846 -60.99871) (xy 181.212428 -61.085043) (xy 181.401563 -61.17869)
			(xy 181.586972 -61.279512) (xy 181.768383 -61.387362) (xy 181.94553 -61.502081) (xy 182.118152 -61.623501)
			(xy 182.285998 -61.751444) (xy 182.44882 -61.885722) (xy 182.606379 -62.026138) (xy 182.758444 -62.172486)
			(xy 182.904792 -62.324551) (xy 183.045208 -62.48211) (xy 183.179486 -62.644932) (xy 183.307429 -62.812778)
			(xy 183.428849 -62.9854) (xy 183.543568 -63.162547) (xy 183.651418 -63.343958) (xy 183.75224 -63.529367)
			(xy 183.845887 -63.718502) (xy 183.93222 -63.911084) (xy 184.011114 -64.106832) (xy 184.082452 -64.305459)
			(xy 184.146129 -64.506672) (xy 184.202053 -64.710176) (xy 184.250141 -64.915673) (xy 184.290323 -65.122861)
			(xy 184.32254 -65.331436) (xy 184.346743 -65.541093) (xy 184.362899 -65.751522) (xy 184.370983 -65.962416)
			(xy 184.371488 -66.06794) (xy 184.371488 -74.760836) (xy 287.494472 -74.760836) (xy 287.494472 -66.060828)
			(xy 287.494977 -65.955304) (xy 287.503061 -65.74441) (xy 287.519217 -65.533981) (xy 287.54342 -65.324324)
			(xy 287.575637 -65.115749) (xy 287.615819 -64.908561) (xy 287.663907 -64.703064) (xy 287.719831 -64.49956)
			(xy 287.783508 -64.298347) (xy 287.854846 -64.09972) (xy 287.93374 -63.903972) (xy 288.020073 -63.71139)
			(xy 288.11372 -63.522255) (xy 288.214542 -63.336846) (xy 288.322392 -63.155435) (xy 288.437111 -62.978288)
			(xy 288.558531 -62.805666) (xy 288.686474 -62.63782) (xy 288.820752 -62.474998) (xy 288.961168 -62.317439)
			(xy 289.107516 -62.165374) (xy 289.259581 -62.019026) (xy 289.41714 -61.87861) (xy 289.579962 -61.744332)
			(xy 289.747808 -61.616389) (xy 289.92043 -61.494969) (xy 290.097577 -61.38025) (xy 290.278988 -61.2724)
			(xy 290.464397 -61.171578) (xy 290.653532 -61.077931) (xy 290.846114 -60.991598) (xy 291.041862 -60.912704)
			(xy 291.240489 -60.841366) (xy 291.441702 -60.777689) (xy 291.645206 -60.721765) (xy 291.850703 -60.673677)
			(xy 292.057891 -60.633495) (xy 292.266466 -60.601278) (xy 292.476123 -60.577075) (xy 292.686552 -60.560919)
			(xy 292.897446 -60.552835) (xy 293.108494 -60.552835) (xy 293.319388 -60.560919) (xy 293.529817 -60.577075)
			(xy 293.739474 -60.601278) (xy 293.948049 -60.633495) (xy 294.155237 -60.673677) (xy 294.360734 -60.721765)
			(xy 294.564238 -60.777689) (xy 294.765451 -60.841366) (xy 294.964078 -60.912704) (xy 295.159826 -60.991598)
			(xy 295.352408 -61.077931) (xy 295.541543 -61.171578) (xy 295.726952 -61.2724) (xy 295.908363 -61.38025)
			(xy 296.08551 -61.494969) (xy 296.258132 -61.616389) (xy 296.425978 -61.744332) (xy 296.5888 -61.87861)
			(xy 296.746359 -62.019026) (xy 296.898424 -62.165374) (xy 297.044772 -62.317439) (xy 297.185188 -62.474998)
			(xy 297.319466 -62.63782) (xy 297.447409 -62.805666) (xy 297.568829 -62.978288) (xy 297.683548 -63.155435)
			(xy 297.791398 -63.336846) (xy 297.89222 -63.522255) (xy 297.985867 -63.71139) (xy 298.0722 -63.903972)
			(xy 298.151094 -64.09972) (xy 298.222432 -64.298347) (xy 298.286109 -64.49956) (xy 298.342033 -64.703064)
			(xy 298.390121 -64.908561) (xy 298.430303 -65.115749) (xy 298.46252 -65.324324) (xy 298.486723 -65.533981)
			(xy 298.502879 -65.74441) (xy 298.510963 -65.955304) (xy 298.511468 -66.060828) (xy 298.511468 -74.760836)
			(xy 298.511434 -74.767948) (xy 421.29456 -74.767948) (xy 421.29456 -66.06794) (xy 421.295065 -65.962416)
			(xy 421.303149 -65.751522) (xy 421.319305 -65.541093) (xy 421.343508 -65.331436) (xy 421.375725 -65.122861)
			(xy 421.415907 -64.915673) (xy 421.463995 -64.710176) (xy 421.519919 -64.506672) (xy 421.583596 -64.305459)
			(xy 421.654934 -64.106832) (xy 421.733828 -63.911084) (xy 421.820161 -63.718502) (xy 421.913808 -63.529367)
			(xy 422.01463 -63.343958) (xy 422.12248 -63.162547) (xy 422.237199 -62.9854) (xy 422.358619 -62.812778)
			(xy 422.486562 -62.644932) (xy 422.62084 -62.48211) (xy 422.761256 -62.324551) (xy 422.907604 -62.172486)
			(xy 423.059669 -62.026138) (xy 423.217228 -61.885722) (xy 423.38005 -61.751444) (xy 423.547896 -61.623501)
			(xy 423.720518 -61.502081) (xy 423.897665 -61.387362) (xy 424.079076 -61.279512) (xy 424.264485 -61.17869)
			(xy 424.45362 -61.085043) (xy 424.646202 -60.99871) (xy 424.84195 -60.919816) (xy 425.040577 -60.848478)
			(xy 425.24179 -60.784801) (xy 425.445294 -60.728877) (xy 425.650791 -60.680789) (xy 425.857979 -60.640607)
			(xy 426.066554 -60.60839) (xy 426.276211 -60.584187) (xy 426.48664 -60.568031) (xy 426.697534 -60.559947)
			(xy 426.908582 -60.559947) (xy 427.119476 -60.568031) (xy 427.329905 -60.584187) (xy 427.539562 -60.60839)
			(xy 427.748137 -60.640607) (xy 427.955325 -60.680789) (xy 428.160822 -60.728877) (xy 428.364326 -60.784801)
			(xy 428.565539 -60.848478) (xy 428.764166 -60.919816) (xy 428.959914 -60.99871) (xy 429.152496 -61.085043)
			(xy 429.341631 -61.17869) (xy 429.52704 -61.279512) (xy 429.708451 -61.387362) (xy 429.885598 -61.502081)
			(xy 430.05822 -61.623501) (xy 430.226066 -61.751444) (xy 430.388888 -61.885722) (xy 430.546447 -62.026138)
			(xy 430.698512 -62.172486) (xy 430.84486 -62.324551) (xy 430.985276 -62.48211) (xy 431.119554 -62.644932)
			(xy 431.247497 -62.812778) (xy 431.368917 -62.9854) (xy 431.483636 -63.162547) (xy 431.591486 -63.343958)
			(xy 431.692308 -63.529367) (xy 431.785955 -63.718502) (xy 431.872288 -63.911084) (xy 431.951182 -64.106832)
			(xy 432.02252 -64.305459) (xy 432.086197 -64.506672) (xy 432.142121 -64.710176) (xy 432.190209 -64.915673)
			(xy 432.230391 -65.122861) (xy 432.262608 -65.331436) (xy 432.286811 -65.541093) (xy 432.302967 -65.751522)
			(xy 432.311051 -65.962416) (xy 432.311556 -66.06794) (xy 432.311556 -74.767948) (xy 432.311051 -74.873472)
			(xy 432.302967 -75.084366) (xy 432.286811 -75.294795) (xy 432.262608 -75.504452) (xy 432.230391 -75.713027)
			(xy 432.190209 -75.920215) (xy 432.142121 -76.125712) (xy 432.086197 -76.329216) (xy 432.02252 -76.530429)
			(xy 431.951182 -76.729056) (xy 431.872288 -76.924804) (xy 431.785955 -77.117386) (xy 431.692308 -77.306521)
			(xy 431.591486 -77.49193) (xy 431.483636 -77.673341) (xy 431.368917 -77.850488) (xy 431.247497 -78.02311)
			(xy 431.119554 -78.190956) (xy 430.985276 -78.353778) (xy 430.84486 -78.511337) (xy 430.698512 -78.663402)
			(xy 430.546447 -78.80975) (xy 430.388888 -78.950166) (xy 430.226066 -79.084444) (xy 430.05822 -79.212387)
			(xy 429.885598 -79.333807) (xy 429.708451 -79.448526) (xy 429.52704 -79.556376) (xy 429.341631 -79.657198)
			(xy 429.152496 -79.750845) (xy 428.959914 -79.837178) (xy 428.764166 -79.916072) (xy 428.565539 -79.98741)
			(xy 428.364326 -80.051087) (xy 428.160822 -80.107011) (xy 427.955325 -80.155099) (xy 427.748137 -80.195281)
			(xy 427.539562 -80.227498) (xy 427.329905 -80.251701) (xy 427.119476 -80.267857) (xy 426.908582 -80.275941)
			(xy 426.697534 -80.275941) (xy 426.48664 -80.267857) (xy 426.276211 -80.251701) (xy 426.066554 -80.227498)
			(xy 425.857979 -80.195281) (xy 425.650791 -80.155099) (xy 425.445294 -80.107011) (xy 425.24179 -80.051087)
			(xy 425.040577 -79.98741) (xy 424.84195 -79.916072) (xy 424.646202 -79.837178) (xy 424.45362 -79.750845)
			(xy 424.264485 -79.657198) (xy 424.079076 -79.556376) (xy 423.897665 -79.448526) (xy 423.720518 -79.333807)
			(xy 423.547896 -79.212387) (xy 423.38005 -79.084444) (xy 423.217228 -78.950166) (xy 423.059669 -78.80975)
			(xy 422.907604 -78.663402) (xy 422.761256 -78.511337) (xy 422.62084 -78.353778) (xy 422.486562 -78.190956)
			(xy 422.358619 -78.02311) (xy 422.237199 -77.850488) (xy 422.12248 -77.673341) (xy 422.01463 -77.49193)
			(xy 421.913808 -77.306521) (xy 421.820161 -77.117386) (xy 421.733828 -76.924804) (xy 421.654934 -76.729056)
			(xy 421.583596 -76.530429) (xy 421.519919 -76.329216) (xy 421.463995 -76.125712) (xy 421.415907 -75.920215)
			(xy 421.375725 -75.713027) (xy 421.343508 -75.504452) (xy 421.319305 -75.294795) (xy 421.303149 -75.084366)
			(xy 421.295065 -74.873472) (xy 421.29456 -74.767948) (xy 298.511434 -74.767948) (xy 298.510963 -74.86636)
			(xy 298.502879 -75.077254) (xy 298.486723 -75.287683) (xy 298.46252 -75.49734) (xy 298.430303 -75.705915)
			(xy 298.390121 -75.913103) (xy 298.342033 -76.1186) (xy 298.286109 -76.322104) (xy 298.222432 -76.523317)
			(xy 298.151094 -76.721944) (xy 298.0722 -76.917692) (xy 297.985867 -77.110274) (xy 297.89222 -77.299409)
			(xy 297.791398 -77.484818) (xy 297.683548 -77.666229) (xy 297.568829 -77.843376) (xy 297.447409 -78.015998)
			(xy 297.319466 -78.183844) (xy 297.185188 -78.346666) (xy 297.044772 -78.504225) (xy 296.898424 -78.65629)
			(xy 296.746359 -78.802638) (xy 296.5888 -78.943054) (xy 296.425978 -79.077332) (xy 296.258132 -79.205275)
			(xy 296.08551 -79.326695) (xy 295.908363 -79.441414) (xy 295.726952 -79.549264) (xy 295.541543 -79.650086)
			(xy 295.352408 -79.743733) (xy 295.159826 -79.830066) (xy 294.964078 -79.90896) (xy 294.765451 -79.980298)
			(xy 294.564238 -80.043975) (xy 294.360734 -80.099899) (xy 294.155237 -80.147987) (xy 293.948049 -80.188169)
			(xy 293.739474 -80.220386) (xy 293.529817 -80.244589) (xy 293.319388 -80.260745) (xy 293.108494 -80.268829)
			(xy 292.897446 -80.268829) (xy 292.686552 -80.260745) (xy 292.476123 -80.244589) (xy 292.266466 -80.220386)
			(xy 292.057891 -80.188169) (xy 291.850703 -80.147987) (xy 291.645206 -80.099899) (xy 291.441702 -80.043975)
			(xy 291.240489 -79.980298) (xy 291.041862 -79.90896) (xy 290.846114 -79.830066) (xy 290.653532 -79.743733)
			(xy 290.464397 -79.650086) (xy 290.278988 -79.549264) (xy 290.097577 -79.441414) (xy 289.92043 -79.326695)
			(xy 289.747808 -79.205275) (xy 289.579962 -79.077332) (xy 289.41714 -78.943054) (xy 289.259581 -78.802638)
			(xy 289.107516 -78.65629) (xy 288.961168 -78.504225) (xy 288.820752 -78.346666) (xy 288.686474 -78.183844)
			(xy 288.558531 -78.015998) (xy 288.437111 -77.843376) (xy 288.322392 -77.666229) (xy 288.214542 -77.484818)
			(xy 288.11372 -77.299409) (xy 288.020073 -77.110274) (xy 287.93374 -76.917692) (xy 287.854846 -76.721944)
			(xy 287.783508 -76.523317) (xy 287.719831 -76.322104) (xy 287.663907 -76.1186) (xy 287.615819 -75.913103)
			(xy 287.575637 -75.705915) (xy 287.54342 -75.49734) (xy 287.519217 -75.287683) (xy 287.503061 -75.077254)
			(xy 287.494977 -74.86636) (xy 287.494472 -74.760836) (xy 184.371488 -74.760836) (xy 184.371488 -74.767948)
			(xy 184.370983 -74.873472) (xy 184.362899 -75.084366) (xy 184.346743 -75.294795) (xy 184.32254 -75.504452)
			(xy 184.290323 -75.713027) (xy 184.250141 -75.920215) (xy 184.202053 -76.125712) (xy 184.146129 -76.329216)
			(xy 184.082452 -76.530429) (xy 184.011114 -76.729056) (xy 183.93222 -76.924804) (xy 183.845887 -77.117386)
			(xy 183.75224 -77.306521) (xy 183.651418 -77.49193) (xy 183.543568 -77.673341) (xy 183.428849 -77.850488)
			(xy 183.307429 -78.02311) (xy 183.179486 -78.190956) (xy 183.045208 -78.353778) (xy 182.904792 -78.511337)
			(xy 182.758444 -78.663402) (xy 182.606379 -78.80975) (xy 182.44882 -78.950166) (xy 182.285998 -79.084444)
			(xy 182.118152 -79.212387) (xy 181.94553 -79.333807) (xy 181.768383 -79.448526) (xy 181.586972 -79.556376)
			(xy 181.401563 -79.657198) (xy 181.212428 -79.750845) (xy 181.019846 -79.837178) (xy 180.824098 -79.916072)
			(xy 180.625471 -79.98741) (xy 180.424258 -80.051087) (xy 180.220754 -80.107011) (xy 180.015257 -80.155099)
			(xy 179.808069 -80.195281) (xy 179.599494 -80.227498) (xy 179.389837 -80.251701) (xy 179.179408 -80.267857)
			(xy 178.968514 -80.275941) (xy 178.757466 -80.275941) (xy 178.546572 -80.267857) (xy 178.336143 -80.251701)
			(xy 178.126486 -80.227498) (xy 177.917911 -80.195281) (xy 177.710723 -80.155099) (xy 177.505226 -80.107011)
			(xy 177.301722 -80.051087) (xy 177.100509 -79.98741) (xy 176.901882 -79.916072) (xy 176.706134 -79.837178)
			(xy 176.513552 -79.750845) (xy 176.324417 -79.657198) (xy 176.139008 -79.556376) (xy 175.957597 -79.448526)
			(xy 175.78045 -79.333807) (xy 175.607828 -79.212387) (xy 175.439982 -79.084444) (xy 175.27716 -78.950166)
			(xy 175.119601 -78.80975) (xy 174.967536 -78.663402) (xy 174.821188 -78.511337) (xy 174.680772 -78.353778)
			(xy 174.546494 -78.190956) (xy 174.418551 -78.02311) (xy 174.297131 -77.850488) (xy 174.182412 -77.673341)
			(xy 174.074562 -77.49193) (xy 173.97374 -77.306521) (xy 173.880093 -77.117386) (xy 173.79376 -76.924804)
			(xy 173.714866 -76.729056) (xy 173.643528 -76.530429) (xy 173.579851 -76.329216) (xy 173.523927 -76.125712)
			(xy 173.475839 -75.920215) (xy 173.435657 -75.713027) (xy 173.40344 -75.504452) (xy 173.379237 -75.294795)
			(xy 173.363081 -75.084366) (xy 173.354997 -74.873472) (xy 173.354492 -74.767948) (xy 50.571366 -74.767948)
			(xy 50.570895 -74.86636) (xy 50.562811 -75.077254) (xy 50.546655 -75.287683) (xy 50.522452 -75.49734)
			(xy 50.490235 -75.705915) (xy 50.450053 -75.913103) (xy 50.401965 -76.1186) (xy 50.346041 -76.322104)
			(xy 50.282364 -76.523317) (xy 50.211026 -76.721944) (xy 50.132132 -76.917692) (xy 50.045799 -77.110274)
			(xy 49.952152 -77.299409) (xy 49.85133 -77.484818) (xy 49.74348 -77.666229) (xy 49.628761 -77.843376)
			(xy 49.507341 -78.015998) (xy 49.379398 -78.183844) (xy 49.24512 -78.346666) (xy 49.104704 -78.504225)
			(xy 48.958356 -78.65629) (xy 48.806291 -78.802638) (xy 48.648732 -78.943054) (xy 48.48591 -79.077332)
			(xy 48.318064 -79.205275) (xy 48.145442 -79.326695) (xy 47.968295 -79.441414) (xy 47.786884 -79.549264)
			(xy 47.601475 -79.650086) (xy 47.41234 -79.743733) (xy 47.219758 -79.830066) (xy 47.02401 -79.90896)
			(xy 46.825383 -79.980298) (xy 46.62417 -80.043975) (xy 46.420666 -80.099899) (xy 46.215169 -80.147987)
			(xy 46.007981 -80.188169) (xy 45.799406 -80.220386) (xy 45.589749 -80.244589) (xy 45.37932 -80.260745)
			(xy 45.168426 -80.268829) (xy 44.957378 -80.268829) (xy 44.746484 -80.260745) (xy 44.536055 -80.244589)
			(xy 44.326398 -80.220386) (xy 44.117823 -80.188169) (xy 43.910635 -80.147987) (xy 43.705138 -80.099899)
			(xy 43.501634 -80.043975) (xy 43.300421 -79.980298) (xy 43.101794 -79.90896) (xy 42.906046 -79.830066)
			(xy 42.713464 -79.743733) (xy 42.524329 -79.650086) (xy 42.33892 -79.549264) (xy 42.157509 -79.441414)
			(xy 41.980362 -79.326695) (xy 41.80774 -79.205275) (xy 41.639894 -79.077332) (xy 41.477072 -78.943054)
			(xy 41.319513 -78.802638) (xy 41.167448 -78.65629) (xy 41.0211 -78.504225) (xy 40.880684 -78.346666)
			(xy 40.746406 -78.183844) (xy 40.618463 -78.015998) (xy 40.497043 -77.843376) (xy 40.382324 -77.666229)
			(xy 40.274474 -77.484818) (xy 40.173652 -77.299409) (xy 40.080005 -77.110274) (xy 39.993672 -76.917692)
			(xy 39.914778 -76.721944) (xy 39.84344 -76.523317) (xy 39.779763 -76.322104) (xy 39.723839 -76.1186)
			(xy 39.675751 -75.913103) (xy 39.635569 -75.705915) (xy 39.603352 -75.49734) (xy 39.579149 -75.287683)
			(xy 39.562993 -75.077254) (xy 39.554909 -74.86636) (xy 39.554404 -74.760836) (xy 0.509016 -74.760836)
			(xy 0.509016 -77.67193) (xy 0.5095 -77.725143) (xy 0.517108 -77.831296) (xy 0.532269 -77.936637)
			(xy 0.554904 -78.040627) (xy 0.584899 -78.142739) (xy 0.622101 -78.242451) (xy 0.666319 -78.339256)
			(xy 0.71733 -78.43266) (xy 0.774873 -78.522188) (xy 0.838654 -78.607384) (xy 0.90835 -78.687813)
			(xy 0.945642 -78.725776) (xy 1.77419 -79.554324) (xy 1.823612 -79.604428) (xy 1.917404 -79.709374)
			(xy 2.005163 -79.819414) (xy 2.086614 -79.934202) (xy 2.161501 -80.053377) (xy 2.229587 -80.176563)
			(xy 2.290658 -80.303374) (xy 2.344523 -80.433409) (xy 2.391012 -80.56626) (xy 2.429978 -80.701509)
			(xy 2.461299 -80.83873) (xy 2.484876 -80.977491) (xy 2.500635 -81.117356) (xy 2.508527 -81.257885)
			(xy 2.509012 -81.32826) (xy 2.509012 -81.691972) (xy 232.140715 -81.691972) (xy 232.145114 -81.518126)
			(xy 232.157548 -81.34467) (xy 232.177991 -81.171975) (xy 232.206398 -81.00041) (xy 232.242709 -80.830342)
			(xy 232.286847 -80.662135) (xy 232.338717 -80.49615) (xy 232.398207 -80.332741) (xy 232.465191 -80.172258)
			(xy 232.539525 -80.015044) (xy 232.62105 -79.861437) (xy 232.709592 -79.711764) (xy 232.804961 -79.566346)
			(xy 232.906953 -79.425495) (xy 233.015351 -79.289511) (xy 233.129921 -79.158685) (xy 233.250418 -79.033298)
			(xy 233.376586 -78.913618) (xy 233.508153 -78.799901) (xy 233.644839 -78.69239) (xy 233.715306 -78.641448)
			(xy 238.084614 -78.641448) (xy 238.155081 -78.69239) (xy 238.291767 -78.799901) (xy 238.423334 -78.913618)
			(xy 238.549502 -79.033298) (xy 238.669999 -79.158685) (xy 238.784569 -79.289511) (xy 238.892967 -79.425495)
			(xy 238.994959 -79.566346) (xy 239.090328 -79.711764) (xy 239.17887 -79.861437) (xy 239.260395 -80.015044)
			(xy 239.334729 -80.172258) (xy 239.401713 -80.332741) (xy 239.461203 -80.49615) (xy 239.513073 -80.662135)
			(xy 239.557211 -80.830342) (xy 239.593522 -81.00041) (xy 239.608937 -81.093507) (xy 398.275806 -81.093507)
			(xy 398.275806 -81.008785) (xy 398.283859 -80.924448) (xy 398.299893 -80.841258) (xy 398.323761 -80.759968)
			(xy 398.355249 -80.681316) (xy 398.394071 -80.606013) (xy 398.439874 -80.534741) (xy 398.492245 -80.468145)
			(xy 398.55071 -80.40683) (xy 398.614738 -80.351349) (xy 398.68375 -80.302206) (xy 398.75712 -80.259846)
			(xy 398.834185 -80.224651) (xy 398.914247 -80.196942) (xy 398.99658 -80.176968) (xy 399.080439 -80.164911)
			(xy 399.165064 -80.16088) (xy 399.249689 -80.164911) (xy 399.333548 -80.176968) (xy 399.415881 -80.196942)
			(xy 399.495943 -80.224651) (xy 399.573008 -80.259846) (xy 399.646378 -80.302206) (xy 399.71539 -80.351349)
			(xy 399.779418 -80.40683) (xy 399.837883 -80.468145) (xy 399.890254 -80.534741) (xy 399.936057 -80.606013)
			(xy 399.974879 -80.681316) (xy 400.006367 -80.759968) (xy 400.030235 -80.841258) (xy 400.046269 -80.924448)
			(xy 400.054322 -81.008785) (xy 400.054826 -81.051146) (xy 400.054322 -81.093507) (xy 400.046269 -81.177844)
			(xy 400.030235 -81.261034) (xy 400.006367 -81.342324) (xy 399.974879 -81.420976) (xy 399.936057 -81.496279)
			(xy 399.890254 -81.567551) (xy 399.837883 -81.634147) (xy 399.779418 -81.695462) (xy 399.71539 -81.750943)
			(xy 399.646378 -81.800086) (xy 399.573008 -81.842446) (xy 399.495943 -81.877641) (xy 399.415881 -81.90535)
			(xy 399.333548 -81.925324) (xy 399.249689 -81.937381) (xy 399.165064 -81.941413) (xy 399.080439 -81.937381)
			(xy 398.99658 -81.925324) (xy 398.914247 -81.90535) (xy 398.834185 -81.877641) (xy 398.75712 -81.842446)
			(xy 398.68375 -81.800086) (xy 398.614738 -81.750943) (xy 398.55071 -81.695462) (xy 398.492245 -81.634147)
			(xy 398.439874 -81.567551) (xy 398.394071 -81.496279) (xy 398.355249 -81.420976) (xy 398.323761 -81.342324)
			(xy 398.299893 -81.261034) (xy 398.283859 -81.177844) (xy 398.275806 -81.093507) (xy 239.608937 -81.093507)
			(xy 239.621929 -81.171975) (xy 239.642372 -81.34467) (xy 239.654806 -81.518126) (xy 239.659205 -81.691972)
			(xy 239.655559 -81.865835) (xy 239.643877 -82.039343) (xy 239.624183 -82.212126) (xy 239.596519 -82.383812)
			(xy 239.560945 -82.554036) (xy 239.517536 -82.722432) (xy 239.466387 -82.888641) (xy 239.407605 -83.052306)
			(xy 239.341317 -83.213078) (xy 239.267665 -83.370612) (xy 239.186806 -83.524571) (xy 239.098913 -83.674626)
			(xy 239.004175 -83.820455) (xy 238.902794 -83.961748) (xy 238.794987 -84.0982) (xy 238.680985 -84.229521)
			(xy 238.561032 -84.355429) (xy 238.435384 -84.475655) (xy 238.30431 -84.589941) (xy 238.168092 -84.698043)
			(xy 238.027019 -84.79973) (xy 237.881395 -84.894784) (xy 237.731531 -84.983001) (xy 237.577747 -85.064194)
			(xy 237.420373 -85.138187) (xy 237.259746 -85.204823) (xy 237.096208 -85.263959) (xy 236.930111 -85.315469)
			(xy 236.761809 -85.359242) (xy 236.591663 -85.395185) (xy 236.420037 -85.423221) (xy 236.247297 -85.443289)
			(xy 236.073815 -85.455348) (xy 235.89996 -85.45937) (xy 235.726105 -85.455348) (xy 235.552623 -85.443289)
			(xy 235.379883 -85.423221) (xy 235.208257 -85.395185) (xy 235.038111 -85.359242) (xy 234.869809 -85.315469)
			(xy 234.703712 -85.263959) (xy 234.540174 -85.204823) (xy 234.379547 -85.138187) (xy 234.222173 -85.064194)
			(xy 234.068389 -84.983001) (xy 233.918525 -84.894784) (xy 233.772901 -84.79973) (xy 233.631828 -84.698043)
			(xy 233.49561 -84.589941) (xy 233.364536 -84.475655) (xy 233.238888 -84.355429) (xy 233.118935 -84.229521)
			(xy 233.004933 -84.0982) (xy 232.897126 -83.961748) (xy 232.795745 -83.820455) (xy 232.701007 -83.674626)
			(xy 232.613114 -83.524571) (xy 232.532255 -83.370612) (xy 232.458603 -83.213078) (xy 232.392315 -83.052306)
			(xy 232.333533 -82.888641) (xy 232.282384 -82.722432) (xy 232.238975 -82.554036) (xy 232.203401 -82.383812)
			(xy 232.175737 -82.212126) (xy 232.156043 -82.039343) (xy 232.144361 -81.865835) (xy 232.140715 -81.691972)
			(xy 2.509012 -81.691972) (xy 2.509012 -84.065147) (xy 218.29831 -84.065147) (xy 218.29831 -84.010653)
			(xy 218.306065 -83.956712) (xy 218.321417 -83.904424) (xy 218.344054 -83.854854) (xy 218.373515 -83.809009)
			(xy 218.4092 -83.767823) (xy 218.450383 -83.732134) (xy 218.496225 -83.70267) (xy 218.545794 -83.680029)
			(xy 218.598081 -83.664672) (xy 218.652021 -83.656912) (xy 218.679268 -83.656424) (xy 219.542868 -83.656424)
			(xy 219.570125 -83.656821) (xy 219.624084 -83.664575) (xy 219.67639 -83.679929) (xy 219.725978 -83.702572)
			(xy 219.771839 -83.732041) (xy 219.813039 -83.767738) (xy 219.848739 -83.808935) (xy 219.878213 -83.854794)
			(xy 219.90086 -83.90438) (xy 219.916219 -83.956685) (xy 219.923977 -84.010643) (xy 219.923977 -84.065157)
			(xy 219.916219 -84.119115) (xy 219.90086 -84.17142) (xy 219.878213 -84.221006) (xy 219.848739 -84.266865)
			(xy 219.813039 -84.308062) (xy 219.771839 -84.343759) (xy 219.725978 -84.373228) (xy 219.67639 -84.395871)
			(xy 219.624084 -84.411225) (xy 219.570125 -84.418979) (xy 219.542868 -84.41944) (xy 218.679268 -84.41944)
			(xy 218.652021 -84.418888) (xy 218.598081 -84.411128) (xy 218.545794 -84.395771) (xy 218.496225 -84.37313)
			(xy 218.450383 -84.343666) (xy 218.4092 -84.307977) (xy 218.373515 -84.266791) (xy 218.344054 -84.220946)
			(xy 218.321417 -84.171376) (xy 218.306065 -84.119088) (xy 218.29831 -84.065147) (xy 2.509012 -84.065147)
			(xy 2.509012 -86.948548) (xy 217.344518 -86.948548) (xy 217.344518 -86.894052) (xy 217.352274 -86.84011)
			(xy 217.367627 -86.787821) (xy 217.390266 -86.738249) (xy 217.419729 -86.692404) (xy 217.455416 -86.651218)
			(xy 217.496602 -86.61553) (xy 217.542447 -86.586067) (xy 217.592019 -86.563428) (xy 217.644308 -86.548074)
			(xy 217.69825 -86.540318) (xy 217.725498 -86.539832) (xy 218.589098 -86.539832) (xy 218.616354 -86.540215)
			(xy 218.670311 -86.547972) (xy 218.722614 -86.56333) (xy 218.7722 -86.585975) (xy 218.818058 -86.615446)
			(xy 218.859255 -86.651143) (xy 218.894953 -86.69234) (xy 218.924424 -86.738198) (xy 218.947069 -86.787784)
			(xy 218.962427 -86.840087) (xy 218.970185 -86.894044) (xy 218.970185 -86.948556) (xy 218.962427 -87.002513)
			(xy 218.947069 -87.054816) (xy 218.924424 -87.104402) (xy 218.894953 -87.15026) (xy 218.859255 -87.191457)
			(xy 218.818058 -87.227154) (xy 218.7722 -87.256625) (xy 218.722614 -87.27927) (xy 218.670311 -87.294628)
			(xy 218.616354 -87.302385) (xy 218.589098 -87.302848) (xy 217.725498 -87.302848) (xy 217.69825 -87.302282)
			(xy 217.644308 -87.294526) (xy 217.592019 -87.279172) (xy 217.542447 -87.256533) (xy 217.496602 -87.22707)
			(xy 217.455416 -87.191382) (xy 217.419729 -87.150196) (xy 217.390266 -87.104351) (xy 217.367627 -87.054779)
			(xy 217.352274 -87.00249) (xy 217.344518 -86.948548) (xy 2.509012 -86.948548) (xy 2.509012 -101.8413)
			(xy 13.937488 -101.8413) (xy 13.937488 -101.256846) (xy 13.937947 -101.244754) (xy 13.945397 -101.221747)
			(xy 13.959584 -101.202162) (xy 13.979123 -101.187912) (xy 14.002106 -101.180387) (xy 14.014196 -101.179884)
			(xy 14.615668 -101.179884) (xy 14.627748 -101.18034) (xy 14.650729 -101.187798) (xy 14.670279 -101.201993)
			(xy 14.684484 -101.221536) (xy 14.691954 -101.244512) (xy 14.692376 -101.256592) (xy 14.692376 -101.841046)
			(xy 14.692367 -101.8413) (xy 14.93774 -101.8413) (xy 14.93774 -101.256846) (xy 14.938247 -101.244759)
			(xy 14.945691 -101.22176) (xy 14.959867 -101.202179) (xy 14.979393 -101.187927) (xy 15.002363 -101.180394)
			(xy 15.014448 -101.179884) (xy 15.61592 -101.179884) (xy 15.627995 -101.180347) (xy 15.650961 -101.187814)
			(xy 15.670497 -101.202011) (xy 15.684691 -101.22155) (xy 15.692155 -101.244517) (xy 15.692628 -101.256592)
			(xy 15.692628 -101.841046) (xy 15.692231 -101.853141) (xy 15.684758 -101.876149) (xy 15.670554 -101.895731)
			(xy 15.651005 -101.909978) (xy 15.628014 -101.917504) (xy 15.61592 -101.918008) (xy 15.014448 -101.918008)
			(xy 15.002368 -101.917546) (xy 14.979387 -101.910092) (xy 14.959836 -101.895899) (xy 14.94563 -101.876356)
			(xy 14.938161 -101.85338) (xy 14.93774 -101.8413) (xy 14.692367 -101.8413) (xy 14.691932 -101.853136)
			(xy 14.684465 -101.876136) (xy 14.670272 -101.895714) (xy 14.650735 -101.909963) (xy 14.627757 -101.917497)
			(xy 14.615668 -101.918008) (xy 14.014196 -101.918008) (xy 14.002121 -101.917539) (xy 13.979154 -101.910076)
			(xy 13.959617 -101.89588) (xy 13.945423 -101.876342) (xy 13.93796 -101.853375) (xy 13.937488 -101.8413)
			(xy 2.509012 -101.8413) (xy 2.509012 -106.83494) (xy 11.166856 -106.83494) (xy 11.166856 -104.92994)
			(xy 11.167393 -104.917896) (xy 11.174809 -104.894979) (xy 11.188932 -104.875467) (xy 11.208384 -104.86126)
			(xy 11.231268 -104.853745) (xy 11.24331 -104.853232) (xy 11.599418 -104.853232) (xy 11.611508 -104.853692)
			(xy 11.634508 -104.861152) (xy 11.654087 -104.875341) (xy 11.668337 -104.894875) (xy 11.67587 -104.917852)
			(xy 11.67638 -104.92994) (xy 11.67638 -105.092246) (xy 11.676852 -105.101955) (xy 11.684055 -105.119987)
			(xy 11.697447 -105.134047) (xy 11.706098 -105.138474) (xy 11.789918 -105.176828) (xy 11.79891 -105.180472)
			(xy 11.818274 -105.181431) (xy 11.836627 -105.17518) (xy 11.844274 -105.169208) (xy 11.844528 -105.168954)
			(xy 11.865464 -105.151375) (xy 11.911399 -105.121736) (xy 11.961094 -105.098958) (xy 12.013532 -105.083507)
			(xy 12.067639 -105.075699) (xy 12.094972 -105.075228) (xy 12.09548 -105.075228) (xy 12.124672 -105.075772)
			(xy 12.182376 -105.084641) (xy 12.238053 -105.102207) (xy 12.290401 -105.128057) (xy 12.338194 -105.161588)
			(xy 12.35964 -105.1814) (xy 12.359894 -105.181654) (xy 12.367426 -105.188122) (xy 12.385889 -105.195352)
			(xy 12.405715 -105.195036) (xy 12.415012 -105.19156) (xy 12.500356 -105.154984) (xy 12.505944 -105.15219)
			(xy 12.513179 -105.14762) (xy 12.524383 -105.134706) (xy 12.530675 -105.118809) (xy 12.531344 -105.11028)
			(xy 12.531344 -105.108248) (xy 12.531344 -104.95153) (xy 12.531786 -104.939408) (xy 12.53927 -104.916349)
			(xy 12.553516 -104.896733) (xy 12.573128 -104.882481) (xy 12.596184 -104.874989) (xy 12.608306 -104.874568)
			(xy 12.963906 -104.874568) (xy 12.976032 -104.874955) (xy 12.999096 -104.882453) (xy 13.018714 -104.896712)
			(xy 13.032963 -104.916336) (xy 13.04045 -104.939404) (xy 13.040868 -104.95153) (xy 13.040868 -105.122472)
			(xy 14.014704 -105.122472) (xy 14.014704 -105.007664) (xy 14.015118 -104.994468) (xy 14.022099 -104.969014)
			(xy 14.035508 -104.946281) (xy 14.054408 -104.927858) (xy 14.077477 -104.915034) (xy 14.103101 -104.908707)
			(xy 14.116304 -104.908604) (xy 14.11732 -104.908604) (xy 14.4145 -104.908604) (xy 14.427703 -104.90864)
			(xy 14.453324 -104.91499) (xy 14.476388 -104.927831) (xy 14.495281 -104.946267) (xy 14.508684 -104.969008)
			(xy 14.51566 -104.994466) (xy 14.5161 -105.007664) (xy 14.5161 -105.122472) (xy 14.515432 -105.131378)
			(xy 14.504326 -105.145288) (xy 14.49578 -105.147872) (xy 14.46403 -105.154984) (xy 14.460866 -105.158205)
			(xy 14.456822 -105.166268) (xy 14.456156 -105.170732) (xy 14.456156 -105.38841) (xy 14.455724 -105.395302)
			(xy 14.448827 -105.407238) (xy 14.436887 -105.414128) (xy 14.429994 -105.414572) (xy 14.10081 -105.414572)
			(xy 14.093922 -105.414109) (xy 14.081989 -105.407226) (xy 14.075096 -105.395298) (xy 14.074648 -105.38841)
			(xy 14.074648 -105.170732) (xy 14.07403 -105.166253) (xy 14.069979 -105.158175) (xy 14.066774 -105.154984)
			(xy 14.035024 -105.147872) (xy 14.026475 -105.14529) (xy 14.015356 -105.13138) (xy 14.014704 -105.122472)
			(xy 13.040868 -105.122472) (xy 13.040868 -106.08818) (xy 15.033244 -106.08818) (xy 15.033244 -104.18318)
			(xy 15.033742 -104.171134) (xy 15.041173 -104.148218) (xy 15.055306 -104.128707) (xy 15.074765 -104.114502)
			(xy 15.097654 -104.106987) (xy 15.109698 -104.106472) (xy 15.465806 -104.106472) (xy 15.477899 -104.106903)
			(xy 15.500905 -104.114365) (xy 15.520488 -104.12856) (xy 15.534737 -104.148103) (xy 15.542263 -104.171088)
			(xy 15.542768 -104.18318) (xy 15.542768 -104.303068) (xy 15.543157 -104.312688) (xy 15.55026 -104.330568)
			(xy 15.563445 -104.344581) (xy 15.571978 -104.349042) (xy 15.668752 -104.394254) (xy 15.698216 -104.39019)
			(xy 15.709392 -104.380792) (xy 15.730108 -104.364069) (xy 15.7753 -104.335924) (xy 15.823964 -104.314331)
			(xy 15.875155 -104.299709) (xy 15.927882 -104.29234) (xy 15.954502 -104.291892) (xy 15.983718 -104.292443)
			(xy 16.041476 -104.301285) (xy 16.097208 -104.318838) (xy 16.149608 -104.344692) (xy 16.197449 -104.378239)
			(xy 16.218916 -104.398064) (xy 16.229838 -104.408732) (xy 16.25981 -104.41432) (xy 16.359886 -104.371648)
			(xy 16.368815 -104.367335) (xy 16.382672 -104.353169) (xy 16.390156 -104.33482) (xy 16.39062 -104.324912)
			(xy 16.39062 -104.21366) (xy 16.391026 -104.201606) (xy 16.398472 -104.178675) (xy 16.412626 -104.159159)
			(xy 16.432109 -104.144957) (xy 16.455021 -104.137456) (xy 16.467074 -104.136952) (xy 16.823182 -104.136952)
			(xy 16.835272 -104.137423) (xy 16.858274 -104.144876) (xy 16.877855 -104.159061) (xy 16.892106 -104.178595)
			(xy 16.899636 -104.201572) (xy 16.900144 -104.21366) (xy 16.900144 -104.343651) (xy 326.803 -104.343651)
			(xy 326.803 -104.258929) (xy 326.811053 -104.174592) (xy 326.827087 -104.091402) (xy 326.850955 -104.010112)
			(xy 326.882443 -103.93146) (xy 326.921265 -103.856157) (xy 326.967068 -103.784885) (xy 327.019439 -103.718289)
			(xy 327.077904 -103.656974) (xy 327.141932 -103.601493) (xy 327.210944 -103.55235) (xy 327.284314 -103.50999)
			(xy 327.361379 -103.474795) (xy 327.441441 -103.447086) (xy 327.523774 -103.427112) (xy 327.607633 -103.415055)
			(xy 327.692258 -103.411024) (xy 327.776883 -103.415055) (xy 327.860742 -103.427112) (xy 327.943075 -103.447086)
			(xy 328.023137 -103.474795) (xy 328.100202 -103.50999) (xy 328.173572 -103.55235) (xy 328.242584 -103.601493)
			(xy 328.306612 -103.656974) (xy 328.365077 -103.718289) (xy 328.417448 -103.784885) (xy 328.463251 -103.856157)
			(xy 328.502073 -103.93146) (xy 328.533561 -104.010112) (xy 328.557429 -104.091402) (xy 328.573463 -104.174592)
			(xy 328.581516 -104.258929) (xy 328.58202 -104.30129) (xy 328.581516 -104.343651) (xy 328.573463 -104.427988)
			(xy 328.557429 -104.511178) (xy 328.533561 -104.592468) (xy 328.502073 -104.67112) (xy 328.463251 -104.746423)
			(xy 328.417448 -104.817695) (xy 328.365077 -104.884291) (xy 328.306612 -104.945606) (xy 328.242584 -105.001087)
			(xy 328.173572 -105.05023) (xy 328.100202 -105.09259) (xy 328.023137 -105.127785) (xy 327.943075 -105.155494)
			(xy 327.860742 -105.175468) (xy 327.776883 -105.187525) (xy 327.692258 -105.191557) (xy 327.607633 -105.187525)
			(xy 327.523774 -105.175468) (xy 327.441441 -105.155494) (xy 327.361379 -105.127785) (xy 327.284314 -105.09259)
			(xy 327.210944 -105.05023) (xy 327.141932 -105.001087) (xy 327.077904 -104.945606) (xy 327.019439 -104.884291)
			(xy 326.967068 -104.817695) (xy 326.921265 -104.746423) (xy 326.882443 -104.67112) (xy 326.850955 -104.592468)
			(xy 326.827087 -104.511178) (xy 326.811053 -104.427988) (xy 326.803 -104.343651) (xy 16.900144 -104.343651)
			(xy 16.900144 -105.122472) (xy 17.408144 -105.122472) (xy 17.408144 -105.007664) (xy 17.408518 -104.994465)
			(xy 17.415502 -104.969005) (xy 17.428917 -104.946267) (xy 17.447826 -104.927843) (xy 17.470905 -104.915022)
			(xy 17.496538 -104.908702) (xy 17.509744 -104.908604) (xy 17.51076 -104.908604) (xy 17.80794 -104.908604)
			(xy 17.821141 -104.908694) (xy 17.84676 -104.91503) (xy 17.869823 -104.927859) (xy 17.888717 -104.946284)
			(xy 17.902122 -104.969018) (xy 17.9091 -104.99447) (xy 17.90954 -105.007664) (xy 17.90954 -105.122472)
			(xy 17.908915 -105.131388) (xy 17.89778 -105.1453) (xy 17.88922 -105.147872) (xy 17.85747 -105.154984)
			(xy 17.854313 -105.158211) (xy 17.850264 -105.166269) (xy 17.849596 -105.170732) (xy 17.849596 -105.38841)
			(xy 17.849125 -105.395296) (xy 17.842241 -105.407224) (xy 17.830319 -105.414119) (xy 17.823434 -105.414572)
			(xy 17.49425 -105.414572) (xy 17.487357 -105.414155) (xy 17.475424 -105.407247) (xy 17.468534 -105.395304)
			(xy 17.468088 -105.38841) (xy 17.468088 -105.170732) (xy 17.467459 -105.166255) (xy 17.463415 -105.158177)
			(xy 17.460214 -105.154984) (xy 17.428464 -105.147872) (xy 17.419904 -105.145319) (xy 17.408792 -105.131386)
			(xy 17.408144 -105.122472) (xy 16.900144 -105.122472) (xy 16.900144 -106.11866) (xy 16.899607 -106.130704)
			(xy 16.892191 -106.153621) (xy 16.878068 -106.173133) (xy 16.858616 -106.18734) (xy 16.835732 -106.194855)
			(xy 16.82369 -106.195368) (xy 16.467582 -106.195368) (xy 16.455492 -106.194908) (xy 16.432492 -106.187448)
			(xy 16.412913 -106.173259) (xy 16.398663 -106.153725) (xy 16.39113 -106.130748) (xy 16.39062 -106.11866)
			(xy 16.39062 -106.012488) (xy 16.390122 -106.002583) (xy 16.382666 -105.984234) (xy 16.3688 -105.970093)
			(xy 16.359886 -105.965752) (xy 16.25981 -105.92308) (xy 16.229838 -105.928668) (xy 16.218916 -105.939336)
			(xy 16.19745 -105.95916) (xy 16.149597 -105.992687) (xy 16.097196 -106.018534) (xy 16.041469 -106.036098)
			(xy 15.983717 -106.044968) (xy 15.954502 -106.045508) (xy 15.927881 -106.045057) (xy 15.87515 -106.037706)
			(xy 15.823955 -106.02309) (xy 15.775291 -106.001493) (xy 15.730104 -105.973337) (xy 15.709392 -105.956608)
			(xy 15.698216 -105.94721) (xy 15.668752 -105.943146) (xy 15.571978 -105.988358) (xy 15.563444 -105.992815)
			(xy 15.550261 -106.006826) (xy 15.543176 -106.024713) (xy 15.542768 -106.034332) (xy 15.542768 -106.08818)
			(xy 15.542322 -106.100232) (xy 15.534891 -106.123163) (xy 15.520748 -106.142682) (xy 15.501272 -106.156884)
			(xy 15.478365 -106.164385) (xy 15.466314 -106.164888) (xy 15.110206 -106.164888) (xy 15.09812 -106.164388)
			(xy 15.075124 -106.156936) (xy 15.055546 -106.142757) (xy 15.041295 -106.123232) (xy 15.033758 -106.100265)
			(xy 15.033244 -106.08818) (xy 13.040868 -106.08818) (xy 13.040868 -106.85653) (xy 13.040414 -106.868646)
			(xy 13.032919 -106.891689) (xy 13.018672 -106.91129) (xy 12.999067 -106.92553) (xy 12.976022 -106.933018)
			(xy 12.963906 -106.933492) (xy 12.608306 -106.933492) (xy 12.596195 -106.932983) (xy 12.573157 -106.925502)
			(xy 12.553558 -106.911268) (xy 12.539315 -106.891675) (xy 12.531822 -106.868641) (xy 12.531344 -106.85653)
			(xy 12.531344 -106.793792) (xy 12.530659 -106.785268) (xy 12.524342 -106.769386) (xy 12.513176 -106.756446)
			(xy 12.505944 -106.751882) (xy 12.500356 -106.749088) (xy 12.415012 -106.712512) (xy 12.405719 -106.709012)
			(xy 12.385882 -106.708697) (xy 12.367401 -106.715917) (xy 12.359894 -106.722418) (xy 12.35964 -106.722672)
			(xy 12.338189 -106.742475) (xy 12.290383 -106.775978) (xy 12.238035 -106.801817) (xy 12.182365 -106.819389)
			(xy 12.124669 -106.828285) (xy 12.09548 -106.828844) (xy 12.094972 -106.828844) (xy 12.067638 -106.828373)
			(xy 12.013531 -106.820567) (xy 11.961091 -106.805118) (xy 11.911393 -106.782343) (xy 11.865455 -106.752708)
			(xy 11.844528 -106.735118) (xy 11.844274 -106.734864) (xy 11.836648 -106.728846) (xy 11.818289 -106.722546)
			(xy 11.798905 -106.723554) (xy 11.789918 -106.727244) (xy 11.706098 -106.765598) (xy 11.697428 -106.770001)
			(xy 11.684021 -106.784067) (xy 11.676805 -106.80211) (xy 11.67638 -106.811826) (xy 11.67638 -106.83494)
			(xy 11.675974 -106.846994) (xy 11.668528 -106.869925) (xy 11.654374 -106.889441) (xy 11.634891 -106.903643)
			(xy 11.611979 -106.911144) (xy 11.599926 -106.911648) (xy 11.243818 -106.911648) (xy 11.231728 -106.911177)
			(xy 11.208726 -106.903724) (xy 11.189145 -106.889539) (xy 11.174894 -106.870005) (xy 11.167364 -106.847028)
			(xy 11.166856 -106.83494) (xy 2.509012 -106.83494) (xy 2.509012 -107.796076) (xy 15.009368 -107.796076)
			(xy 15.009368 -107.466892) (xy 15.009745 -107.459966) (xy 15.016723 -107.448005) (xy 15.022576 -107.444286)
			(xy 15.0241 -107.443524) (xy 15.026804 -107.442328) (xy 15.032574 -107.441039) (xy 15.03553 -107.440984)
			(xy 15.250668 -107.440984) (xy 15.255873 -107.440687) (xy 15.265344 -107.43636) (xy 15.268956 -107.432602)
			(xy 15.27556 -107.403138) (xy 15.275814 -107.401868) (xy 15.278376 -107.393164) (xy 15.292423 -107.381763)
			(xy 15.301468 -107.38104) (xy 15.41653 -107.38104) (xy 15.433153 -107.381655) (xy 15.464559 -107.39257)
			(xy 15.477998 -107.402376) (xy 15.478506 -107.402884) (xy 15.486634 -107.41025) (xy 15.495743 -107.42009)
			(xy 15.508861 -107.443462) (xy 15.515274 -107.469486) (xy 15.515336 -107.482894) (xy 15.515336 -107.484164)
			(xy 15.515336 -107.780074) (xy 15.515323 -107.782106) (xy 16.41602 -107.782106) (xy 16.41602 -107.480862)
			(xy 16.416363 -107.467782) (xy 16.423021 -107.442487) (xy 16.436026 -107.419794) (xy 16.444976 -107.41025)
			(xy 16.453104 -107.402884) (xy 16.453612 -107.402376) (xy 16.467031 -107.392541) (xy 16.498453 -107.381655)
			(xy 16.51508 -107.38104) (xy 16.630142 -107.38104) (xy 16.639191 -107.381757) (xy 16.653243 -107.393158)
			(xy 16.655796 -107.401868) (xy 16.65605 -107.403138) (xy 16.662654 -107.432602) (xy 16.666281 -107.436338)
			(xy 16.675744 -107.440661) (xy 16.680942 -107.440984) (xy 16.89608 -107.440984) (xy 16.902924 -107.441361)
			(xy 16.914782 -107.448198) (xy 16.921631 -107.460048) (xy 16.921988 -107.466892) (xy 16.921988 -107.796076)
			(xy 16.921634 -107.802924) (xy 16.914791 -107.814788) (xy 16.902928 -107.821633) (xy 16.89608 -107.821984)
			(xy 16.680942 -107.821984) (xy 16.675735 -107.822265) (xy 16.666262 -107.826602) (xy 16.662654 -107.830366)
			(xy 16.65605 -107.85983) (xy 16.655796 -107.8611) (xy 16.653211 -107.869795) (xy 16.639181 -107.881201)
			(xy 16.630142 -107.881928) (xy 16.51508 -107.881928) (xy 16.498459 -107.881295) (xy 16.467053 -107.870391)
			(xy 16.453612 -107.860592) (xy 16.453104 -107.860084) (xy 16.444976 -107.852718) (xy 16.436025 -107.843174)
			(xy 16.423016 -107.82048) (xy 16.416348 -107.795187) (xy 16.41602 -107.782106) (xy 15.515323 -107.782106)
			(xy 15.515253 -107.793481) (xy 15.508841 -107.819502) (xy 15.495744 -107.842883) (xy 15.486634 -107.852718)
			(xy 15.478506 -107.860084) (xy 15.477998 -107.860592) (xy 15.464574 -107.870419) (xy 15.433156 -107.881311)
			(xy 15.41653 -107.881928) (xy 15.301468 -107.881928) (xy 15.292415 -107.881227) (xy 15.278361 -107.869816)
			(xy 15.275814 -107.8611) (xy 15.27556 -107.85983) (xy 15.268956 -107.830366) (xy 15.26534 -107.826611)
			(xy 15.255873 -107.82227) (xy 15.250668 -107.821984) (xy 15.03553 -107.821984) (xy 15.029155 -107.821704)
			(xy 15.017833 -107.815861) (xy 15.01394 -107.810808) (xy 15.013178 -107.809284) (xy 15.01267 -107.808776)
			(xy 15.01114 -107.805826) (xy 15.009466 -107.799398) (xy 15.009368 -107.796076) (xy 2.509012 -107.796076)
			(xy 2.509012 -108.943971) (xy 11.292822 -108.943971) (xy 11.292822 -108.889469) (xy 11.300578 -108.835522)
			(xy 11.315933 -108.783228) (xy 11.338574 -108.733651) (xy 11.36804 -108.687801) (xy 11.403731 -108.646611)
			(xy 11.444921 -108.61092) (xy 11.490771 -108.581454) (xy 11.540348 -108.558813) (xy 11.592642 -108.543458)
			(xy 11.646589 -108.535702) (xy 11.67384 -108.535216) (xy 12.53744 -108.535216) (xy 12.564692 -108.535694)
			(xy 12.61864 -108.54345) (xy 12.670935 -108.558806) (xy 12.720513 -108.581447) (xy 12.766364 -108.610914)
			(xy 12.807554 -108.646606) (xy 12.843246 -108.687796) (xy 12.872713 -108.733647) (xy 12.895354 -108.783225)
			(xy 12.91071 -108.83552) (xy 12.918466 -108.889468) (xy 12.918466 -108.943972) (xy 12.91071 -108.99792)
			(xy 12.895354 -109.050215) (xy 12.872713 -109.099793) (xy 12.843246 -109.145644) (xy 12.807554 -109.186834)
			(xy 12.766364 -109.222526) (xy 12.720513 -109.251993) (xy 12.670935 -109.274634) (xy 12.61864 -109.28999)
			(xy 12.564692 -109.297746) (xy 12.53744 -109.298232) (xy 11.67384 -109.298232) (xy 11.646589 -109.297738)
			(xy 11.592642 -109.289982) (xy 11.540348 -109.274627) (xy 11.490771 -109.251986) (xy 11.444921 -109.22252)
			(xy 11.403731 -109.186829) (xy 11.36804 -109.145639) (xy 11.338574 -109.099789) (xy 11.315933 -109.050212)
			(xy 11.300578 -108.997918) (xy 11.292822 -108.943971) (xy 2.509012 -108.943971) (xy 2.509012 -109.451973)
			(xy 15.092889 -109.451973) (xy 15.092889 -109.397467) (xy 15.100646 -109.343517) (xy 15.116002 -109.291219)
			(xy 15.138645 -109.241639) (xy 15.168113 -109.195786) (xy 15.203807 -109.154594) (xy 15.244999 -109.118901)
			(xy 15.290853 -109.089433) (xy 15.340433 -109.066791) (xy 15.39273 -109.051435) (xy 15.446681 -109.043679)
			(xy 15.473934 -109.043216) (xy 16.464534 -109.043216) (xy 16.491785 -109.043694) (xy 16.545733 -109.051451)
			(xy 16.598028 -109.066807) (xy 16.647605 -109.089448) (xy 16.693456 -109.118915) (xy 16.734646 -109.154607)
			(xy 16.770337 -109.195798) (xy 16.799804 -109.241648) (xy 16.822445 -109.291226) (xy 16.8378 -109.343521)
			(xy 16.845556 -109.397469) (xy 16.845556 -109.451971) (xy 16.8378 -109.505919) (xy 16.822445 -109.558214)
			(xy 16.799804 -109.607792) (xy 16.770337 -109.653642) (xy 16.734646 -109.694833) (xy 16.693456 -109.730525)
			(xy 16.647605 -109.759992) (xy 16.598028 -109.782633) (xy 16.545733 -109.797989) (xy 16.491785 -109.805746)
			(xy 16.464534 -109.806232) (xy 15.473934 -109.806232) (xy 15.446681 -109.805761) (xy 15.39273 -109.798005)
			(xy 15.340433 -109.782649) (xy 15.290853 -109.760007) (xy 15.244999 -109.730539) (xy 15.203807 -109.694846)
			(xy 15.168113 -109.653654) (xy 15.138645 -109.607801) (xy 15.116002 -109.558221) (xy 15.100646 -109.505923)
			(xy 15.092889 -109.451973) (xy 2.509012 -109.451973) (xy 2.509012 -114.734161) (xy 11.255226 -114.734161)
			(xy 11.255226 -114.679659) (xy 11.262982 -114.625711) (xy 11.278337 -114.573416) (xy 11.300979 -114.523839)
			(xy 11.330445 -114.477988) (xy 11.366136 -114.436798) (xy 11.407326 -114.401106) (xy 11.453177 -114.371639)
			(xy 11.502754 -114.348998) (xy 11.555049 -114.333643) (xy 11.608997 -114.325886) (xy 11.636248 -114.3254)
			(xy 12.499848 -114.3254) (xy 12.527101 -114.325867) (xy 12.581052 -114.333624) (xy 12.633349 -114.34898)
			(xy 12.68293 -114.371622) (xy 12.728783 -114.40109) (xy 12.769975 -114.436783) (xy 12.805669 -114.477976)
			(xy 12.835137 -114.523829) (xy 12.85778 -114.573409) (xy 12.873136 -114.625706) (xy 12.880893 -114.679657)
			(xy 12.880893 -114.734163) (xy 12.873136 -114.788114) (xy 12.85778 -114.840411) (xy 12.835137 -114.889991)
			(xy 12.805669 -114.935844) (xy 12.769975 -114.977037) (xy 12.728783 -115.01273) (xy 12.68293 -115.042198)
			(xy 12.633349 -115.06484) (xy 12.581052 -115.080196) (xy 12.527101 -115.087953) (xy 12.499848 -115.088416)
			(xy 11.636248 -115.088416) (xy 11.608997 -115.087934) (xy 11.555049 -115.080177) (xy 11.502754 -115.064822)
			(xy 11.453177 -115.042181) (xy 11.407326 -115.012714) (xy 11.366136 -114.977022) (xy 11.330445 -114.935832)
			(xy 11.300979 -114.889981) (xy 11.278337 -114.840404) (xy 11.262982 -114.788109) (xy 11.255226 -114.734161)
			(xy 2.509012 -114.734161) (xy 2.509012 -133.480302) (xy 20.179284 -133.480302) (xy 20.179284 -132.489702)
			(xy 20.17977 -132.462451) (xy 20.187526 -132.408503) (xy 20.202881 -132.356208) (xy 20.225523 -132.306631)
			(xy 20.254989 -132.260781) (xy 20.29068 -132.21959) (xy 20.331871 -132.183899) (xy 20.377721 -132.154433)
			(xy 20.427298 -132.131791) (xy 20.479593 -132.116436) (xy 20.533541 -132.10868) (xy 20.588043 -132.10868)
			(xy 20.641991 -132.116436) (xy 20.694286 -132.131791) (xy 20.743863 -132.154433) (xy 20.789713 -132.183899)
			(xy 20.830904 -132.21959) (xy 20.866595 -132.260781) (xy 20.896061 -132.306631) (xy 20.918703 -132.356208)
			(xy 20.934058 -132.408503) (xy 20.941814 -132.462451) (xy 20.9423 -132.489702) (xy 20.9423 -133.480302)
			(xy 20.941814 -133.507553) (xy 20.934058 -133.561501) (xy 20.918703 -133.613796) (xy 20.896061 -133.663373)
			(xy 20.866595 -133.709223) (xy 20.830904 -133.750414) (xy 20.789713 -133.786105) (xy 20.743863 -133.815571)
			(xy 20.694286 -133.838213) (xy 20.641991 -133.853568) (xy 20.588043 -133.861324) (xy 20.533541 -133.861324)
			(xy 20.479593 -133.853568) (xy 20.427298 -133.838213) (xy 20.377721 -133.815571) (xy 20.331871 -133.786105)
			(xy 20.29068 -133.750414) (xy 20.254989 -133.709223) (xy 20.225523 -133.663373) (xy 20.202881 -133.613796)
			(xy 20.187526 -133.561501) (xy 20.17977 -133.507553) (xy 20.179284 -133.480302) (xy 2.509012 -133.480302)
			(xy 2.509012 -138.001502) (xy 20.019264 -138.001502) (xy 20.019264 -137.010902) (xy 20.01975 -136.983651)
			(xy 20.027506 -136.929703) (xy 20.042861 -136.877408) (xy 20.065503 -136.827831) (xy 20.094969 -136.781981)
			(xy 20.13066 -136.74079) (xy 20.171851 -136.705099) (xy 20.217701 -136.675633) (xy 20.267278 -136.652991)
			(xy 20.319573 -136.637636) (xy 20.373521 -136.62988) (xy 20.428023 -136.62988) (xy 20.481971 -136.637636)
			(xy 20.534266 -136.652991) (xy 20.583843 -136.675633) (xy 20.629693 -136.705099) (xy 20.670884 -136.74079)
			(xy 20.706575 -136.781981) (xy 20.736041 -136.827831) (xy 20.758683 -136.877408) (xy 20.774038 -136.929703)
			(xy 20.781794 -136.983651) (xy 20.78228 -137.010902) (xy 20.78228 -138.001502) (xy 20.781794 -138.028753)
			(xy 20.774038 -138.082701) (xy 20.758683 -138.134996) (xy 20.736041 -138.184573) (xy 20.706575 -138.230423)
			(xy 20.670884 -138.271614) (xy 20.629693 -138.307305) (xy 20.583843 -138.336771) (xy 20.534266 -138.359413)
			(xy 20.481971 -138.374768) (xy 20.428023 -138.382524) (xy 20.373521 -138.382524) (xy 20.319573 -138.374768)
			(xy 20.267278 -138.359413) (xy 20.217701 -138.336771) (xy 20.171851 -138.307305) (xy 20.13066 -138.271614)
			(xy 20.094969 -138.230423) (xy 20.065503 -138.184573) (xy 20.042861 -138.134996) (xy 20.027506 -138.082701)
			(xy 20.01975 -138.028753) (xy 20.019264 -138.001502) (xy 2.509012 -138.001502) (xy 2.509012 -145.104166)
			(xy 163.29995 -145.104166) (xy 163.29995 -145.049634) (xy 163.30771 -144.995658) (xy 163.323072 -144.943336)
			(xy 163.345724 -144.893732) (xy 163.375204 -144.847856) (xy 163.410912 -144.806643) (xy 163.452121 -144.77093)
			(xy 163.497993 -144.741445) (xy 163.547595 -144.718788) (xy 163.599915 -144.70342) (xy 163.653891 -144.695653)
			(xy 163.681156 -144.695164) (xy 164.671756 -144.695164) (xy 164.699031 -144.695573) (xy 164.753026 -144.70333)
			(xy 164.805368 -144.718694) (xy 164.85499 -144.74135) (xy 164.900882 -144.770839) (xy 164.94211 -144.806559)
			(xy 164.977835 -144.847783) (xy 165.007329 -144.893672) (xy 165.029991 -144.943291) (xy 165.045361 -144.995631)
			(xy 165.053124 -145.049625) (xy 165.053124 -145.104175) (xy 165.045361 -145.158169) (xy 165.029991 -145.210509)
			(xy 165.007329 -145.260128) (xy 164.977835 -145.306017) (xy 164.94211 -145.347241) (xy 164.900882 -145.382961)
			(xy 164.85499 -145.41245) (xy 164.805368 -145.435106) (xy 164.753026 -145.45047) (xy 164.699031 -145.458227)
			(xy 164.671756 -145.458688) (xy 163.681156 -145.458688) (xy 163.653891 -145.458147) (xy 163.599915 -145.45038)
			(xy 163.547595 -145.435012) (xy 163.497993 -145.412355) (xy 163.452121 -145.38287) (xy 163.410912 -145.347157)
			(xy 163.375204 -145.305944) (xy 163.345724 -145.260068) (xy 163.323072 -145.210464) (xy 163.30771 -145.158142)
			(xy 163.29995 -145.104166) (xy 2.509012 -145.104166) (xy 2.509012 -153.765504) (xy 24.441921 -153.765504)
			(xy 24.445917 -153.555618) (xy 24.457902 -153.346036) (xy 24.477856 -153.137062) (xy 24.505752 -152.929)
			(xy 24.541549 -152.72215) (xy 24.585194 -152.516813) (xy 24.636626 -152.313287) (xy 24.695768 -152.111866)
			(xy 24.762536 -151.912843) (xy 24.836832 -151.716506) (xy 24.91855 -151.52314) (xy 25.007569 -151.333025)
			(xy 25.103762 -151.146437) (xy 25.206989 -150.963646) (xy 25.3171 -150.784918) (xy 25.433935 -150.610511)
			(xy 25.557325 -150.440679) (xy 25.687092 -150.275667) (xy 25.823046 -150.115716) (xy 25.964992 -149.961056)
			(xy 26.112722 -149.811912) (xy 26.266024 -149.668501) (xy 26.424674 -149.53103) (xy 26.588443 -149.399698)
			(xy 26.757093 -149.274697) (xy 26.930379 -149.156206) (xy 27.108051 -149.044399) (xy 27.289851 -148.939437)
			(xy 27.475515 -148.841472) (xy 27.664773 -148.750647) (xy 27.857353 -148.667093) (xy 28.052974 -148.59093)
			(xy 28.251352 -148.522271) (xy 28.452201 -148.461214) (xy 28.655228 -148.407847) (xy 28.860141 -148.362249)
			(xy 29.06664 -148.324484) (xy 29.274427 -148.294609) (xy 29.483202 -148.272666) (xy 29.69266 -148.258687)
			(xy 29.902499 -148.252692) (xy 30.112413 -148.254691) (xy 30.3221 -148.264679) (xy 30.531254 -148.282644)
			(xy 30.739572 -148.308558) (xy 30.946753 -148.342383) (xy 31.152497 -148.384072) (xy 31.356503 -148.433564)
			(xy 31.558478 -148.490786) (xy 31.758128 -148.555656) (xy 31.955163 -148.62808) (xy 32.149299 -148.707953)
			(xy 32.340252 -148.795159) (xy 32.527748 -148.889571) (xy 32.711513 -148.991053) (xy 32.891281 -149.099457)
			(xy 33.066792 -149.214627) (xy 33.237791 -149.336395) (xy 33.404031 -149.464584) (xy 33.56527 -149.59901)
			(xy 33.721274 -149.739477) (xy 33.871817 -149.885781) (xy 34.016681 -150.03771) (xy 34.155656 -150.195044)
			(xy 34.288541 -150.357555) (xy 34.415142 -150.525008) (xy 34.535277 -150.697158) (xy 34.648771 -150.873758)
			(xy 34.688915 -150.941786) (xy 108.742233 -150.941786) (xy 108.746238 -150.836037) (xy 108.758228 -150.730894)
			(xy 108.778137 -150.626959) (xy 108.805848 -150.524827) (xy 108.841205 -150.425083) (xy 108.884003 -150.328299)
			(xy 108.933999 -150.235029) (xy 108.990906 -150.145808) (xy 109.054397 -150.061145) (xy 109.124109 -149.981527)
			(xy 109.199643 -149.907409) (xy 109.280566 -149.839216) (xy 109.366415 -149.777338) (xy 109.456698 -149.722131)
			(xy 109.550897 -149.673909) (xy 109.648474 -149.632949) (xy 109.748869 -149.599487) (xy 109.851507 -149.573713)
			(xy 109.9558 -149.555775) (xy 110.061151 -149.545776) (xy 110.166957 -149.543773) (xy 110.272611 -149.549778)
			(xy 110.377508 -149.563757) (xy 110.481048 -149.585628) (xy 110.582637 -149.615268) (xy 110.681694 -149.652506)
			(xy 110.777651 -149.697128) (xy 110.869958 -149.74888) (xy 110.958087 -149.807465) (xy 111.041533 -149.872547)
			(xy 111.119817 -149.943753) (xy 111.187365 -150.015249) (xy 160.856694 -150.015249) (xy 160.856694 -149.960751)
			(xy 160.86445 -149.906808) (xy 160.879803 -149.854517) (xy 160.902441 -149.804944) (xy 160.931904 -149.759096)
			(xy 160.967592 -149.717909) (xy 161.008777 -149.682219) (xy 161.054623 -149.652753) (xy 161.104195 -149.630111)
			(xy 161.156484 -149.614755) (xy 161.210427 -149.606996) (xy 161.237676 -149.606508) (xy 162.228276 -149.606508)
			(xy 162.255531 -149.606937) (xy 162.309487 -149.614692) (xy 162.36179 -149.630046) (xy 162.411375 -149.652688)
			(xy 162.457233 -149.682157) (xy 162.498431 -149.717852) (xy 162.534128 -149.759047) (xy 162.5636 -149.804904)
			(xy 162.586245 -149.854488) (xy 162.601603 -149.90679) (xy 162.609361 -149.960745) (xy 162.609361 -149.967557)
			(xy 163.793819 -149.967557) (xy 163.793819 -149.913043) (xy 163.801578 -149.859084) (xy 163.816937 -149.806779)
			(xy 163.839584 -149.757192) (xy 163.869057 -149.711333) (xy 163.904758 -149.670135) (xy 163.945958 -149.634438)
			(xy 163.99182 -149.604968) (xy 164.041409 -149.582325) (xy 164.093716 -149.566971) (xy 164.147675 -149.559217)
			(xy 164.174932 -149.558756) (xy 165.165532 -149.558756) (xy 165.192779 -149.559316) (xy 165.246718 -149.567076)
			(xy 165.299004 -149.582432) (xy 165.348573 -149.605073) (xy 165.394415 -149.634537) (xy 165.435597 -149.670226)
			(xy 165.471282 -149.711411) (xy 165.500742 -149.757255) (xy 165.523379 -149.806826) (xy 165.538731 -149.859113)
			(xy 165.546486 -149.913053) (xy 165.546486 -149.967547) (xy 165.538731 -150.021487) (xy 165.523379 -150.073774)
			(xy 165.500742 -150.123345) (xy 165.471282 -150.169189) (xy 165.435597 -150.210374) (xy 165.394415 -150.246063)
			(xy 165.348573 -150.275527) (xy 165.299004 -150.298168) (xy 165.246718 -150.313524) (xy 165.192779 -150.321284)
			(xy 165.165532 -150.321772) (xy 164.174932 -150.321772) (xy 164.147675 -150.321383) (xy 164.093716 -150.313629)
			(xy 164.041409 -150.298275) (xy 163.99182 -150.275632) (xy 163.945958 -150.246162) (xy 163.904758 -150.210465)
			(xy 163.869057 -150.169267) (xy 163.839584 -150.123408) (xy 163.816937 -150.073821) (xy 163.801578 -150.021516)
			(xy 163.793819 -149.967557) (xy 162.609361 -149.967557) (xy 162.609361 -150.015255) (xy 162.601603 -150.06921)
			(xy 162.586245 -150.121512) (xy 162.5636 -150.171096) (xy 162.534128 -150.216953) (xy 162.498431 -150.258148)
			(xy 162.457233 -150.293843) (xy 162.411375 -150.323312) (xy 162.36179 -150.345954) (xy 162.309487 -150.361308)
			(xy 162.255531 -150.369063) (xy 162.228276 -150.369524) (xy 161.237676 -150.369524) (xy 161.210427 -150.369004)
			(xy 161.156484 -150.361245) (xy 161.104195 -150.345889) (xy 161.054623 -150.323247) (xy 161.008777 -150.293781)
			(xy 160.967592 -150.258091) (xy 160.931904 -150.216904) (xy 160.902441 -150.171056) (xy 160.879803 -150.121483)
			(xy 160.86445 -150.069192) (xy 160.856694 -150.015249) (xy 111.187365 -150.015249) (xy 111.192492 -150.020676)
			(xy 111.259142 -150.102876) (xy 111.319384 -150.18988) (xy 111.372873 -150.281191) (xy 111.419304 -150.376286)
			(xy 111.458409 -150.47462) (xy 111.489966 -150.575631) (xy 111.513793 -150.678738) (xy 111.529754 -150.783352)
			(xy 111.537758 -150.888874) (xy 111.538258 -150.941786) (xy 111.537758 -150.994698) (xy 111.529754 -151.10022)
			(xy 111.513793 -151.204834) (xy 111.489966 -151.307941) (xy 111.458409 -151.408952) (xy 111.419304 -151.507286)
			(xy 111.372873 -151.602381) (xy 111.319384 -151.693692) (xy 111.259142 -151.780696) (xy 111.192492 -151.862896)
			(xy 111.119817 -151.939819) (xy 111.041533 -152.011025) (xy 110.958087 -152.076107) (xy 110.869958 -152.134692)
			(xy 110.777651 -152.186444) (xy 110.681694 -152.231066) (xy 110.582637 -152.268304) (xy 110.481048 -152.297944)
			(xy 110.377508 -152.319815) (xy 110.272611 -152.333794) (xy 110.166957 -152.339799) (xy 110.061151 -152.337796)
			(xy 109.9558 -152.327797) (xy 109.851507 -152.309859) (xy 109.748869 -152.284085) (xy 109.648474 -152.250623)
			(xy 109.550897 -152.209663) (xy 109.456698 -152.161441) (xy 109.366415 -152.106234) (xy 109.280566 -152.044356)
			(xy 109.199643 -151.976163) (xy 109.124109 -151.902045) (xy 109.054397 -151.822427) (xy 108.990906 -151.737764)
			(xy 108.933999 -151.648543) (xy 108.884003 -151.555273) (xy 108.841205 -151.458489) (xy 108.805848 -151.358745)
			(xy 108.778137 -151.256613) (xy 108.758228 -151.152678) (xy 108.746238 -151.047535) (xy 108.742233 -150.941786)
			(xy 34.688915 -150.941786) (xy 34.755459 -151.05455) (xy 34.855186 -151.239273) (xy 34.947809 -151.427659)
			(xy 35.033193 -151.619434) (xy 35.111214 -151.814321) (xy 35.181759 -152.012037) (xy 35.244726 -152.212295)
			(xy 35.300023 -152.414805) (xy 35.34757 -152.619274) (xy 35.354948 -152.657556) (xy 115.368832 -152.657556)
			(xy 115.369254 -152.619267) (xy 115.375857 -152.542973) (xy 115.389002 -152.46753) (xy 115.40859 -152.393499)
			(xy 115.421156 -152.357328) (xy 115.423829 -152.348897) (xy 115.423815 -152.331221) (xy 115.421156 -152.322784)
			(xy 115.408624 -152.286603) (xy 115.389048 -152.212571) (xy 115.375898 -152.137132) (xy 115.36927 -152.060844)
			(xy 115.368832 -152.022556) (xy 115.369211 -151.981443) (xy 115.376803 -151.89957) (xy 115.391918 -151.818746)
			(xy 115.414428 -151.739662) (xy 115.44414 -151.662993) (xy 115.480801 -151.589393) (xy 115.524097 -151.51949)
			(xy 115.573659 -151.453881) (xy 115.629065 -151.393126) (xy 115.689841 -151.337743) (xy 115.755469 -151.288206)
			(xy 115.825388 -151.244936) (xy 115.899002 -151.208303) (xy 115.975683 -151.178621) (xy 116.054775 -151.156141)
			(xy 116.135605 -151.141056) (xy 116.217481 -151.133495) (xy 116.258594 -151.133048) (xy 116.29691 -151.133415)
			(xy 116.373264 -151.139947) (xy 116.448771 -151.153032) (xy 116.52287 -151.172572) (xy 116.559076 -151.185118)
			(xy 116.567392 -151.187704) (xy 116.584796 -151.187704) (xy 116.593112 -151.185118) (xy 116.629327 -151.172602)
			(xy 116.703427 -151.153078) (xy 116.778931 -151.139993) (xy 116.855279 -151.133443) (xy 116.893594 -151.133048)
			(xy 116.933808 -151.133478) (xy 117.01391 -151.140701) (xy 117.093031 -151.155132) (xy 117.170525 -151.176654)
			(xy 117.2083 -151.190452) (xy 117.217087 -151.193359) (xy 117.235581 -151.193359) (xy 117.244368 -151.190452)
			(xy 117.282145 -151.176662) (xy 117.359642 -151.155155) (xy 117.438762 -151.140723) (xy 117.518861 -151.133486)
			(xy 117.559074 -151.133048) (xy 117.59739 -151.133421) (xy 117.673744 -151.139951) (xy 117.74925 -151.153034)
			(xy 117.82335 -151.172573) (xy 117.859556 -151.185118) (xy 117.867872 -151.187704) (xy 117.885276 -151.187704)
			(xy 117.893592 -151.185118) (xy 117.929809 -151.172608) (xy 118.003908 -151.153082) (xy 118.079411 -151.139995)
			(xy 118.155759 -151.133444) (xy 118.194074 -151.133048) (xy 118.23239 -151.133421) (xy 118.308744 -151.139951)
			(xy 118.38425 -151.153034) (xy 118.45835 -151.172573) (xy 118.494556 -151.185118) (xy 118.502872 -151.187704)
			(xy 118.520276 -151.187704) (xy 118.528592 -151.185118) (xy 118.564809 -151.172608) (xy 118.638908 -151.153082)
			(xy 118.714411 -151.139995) (xy 118.790759 -151.133444) (xy 118.829074 -151.133048) (xy 118.86739 -151.133421)
			(xy 118.943744 -151.139951) (xy 119.01925 -151.153034) (xy 119.09335 -151.172573) (xy 119.129556 -151.185118)
			(xy 119.137872 -151.187704) (xy 119.155276 -151.187704) (xy 119.163592 -151.185118) (xy 119.199718 -151.172636)
			(xy 119.273629 -151.153143) (xy 119.348939 -151.140056) (xy 119.425093 -151.133472) (xy 119.463312 -151.133048)
			(xy 119.464074 -151.133048) (xy 119.505181 -151.133537) (xy 119.587043 -151.141119) (xy 119.667858 -151.156221)
			(xy 119.746934 -151.178714) (xy 119.823598 -151.208407) (xy 119.897196 -151.245045) (xy 119.9671 -151.288316)
			(xy 120.032714 -151.337852) (xy 120.093479 -151.39323) (xy 120.148875 -151.453978) (xy 120.198431 -151.519577)
			(xy 120.241724 -151.589468) (xy 120.278384 -151.663055) (xy 120.3081 -151.73971) (xy 120.330617 -151.818779)
			(xy 120.345743 -151.899589) (xy 120.35335 -151.98145) (xy 120.353836 -152.022556) (xy 120.353419 -152.060846)
			(xy 120.346814 -152.137139) (xy 120.333668 -152.212582) (xy 120.314078 -152.286613) (xy 120.301512 -152.322784)
			(xy 120.298884 -152.331226) (xy 120.29887 -152.348891) (xy 120.301512 -152.357328) (xy 120.314046 -152.393509)
			(xy 120.333622 -152.467541) (xy 120.346772 -152.542979) (xy 120.353399 -152.619268) (xy 120.353836 -152.657556)
			(xy 120.353306 -152.698665) (xy 120.345722 -152.780533) (xy 120.330616 -152.861351) (xy 120.308115 -152.940431)
			(xy 120.278413 -153.017096) (xy 120.241762 -153.090693) (xy 120.198476 -153.160594) (xy 120.148923 -153.226202)
			(xy 120.093528 -153.286957) (xy 120.032762 -153.34234) (xy 119.967144 -153.391879) (xy 119.897234 -153.435151)
			(xy 119.823629 -153.471786) (xy 119.746958 -153.501473) (xy 119.667874 -153.523957) (xy 119.587052 -153.539047)
			(xy 119.505183 -153.546614) (xy 119.464074 -153.547064) (xy 119.425757 -153.546706) (xy 119.349404 -153.540171)
			(xy 119.273897 -153.527084) (xy 119.199798 -153.507541) (xy 119.163592 -153.494994) (xy 119.155276 -153.492408)
			(xy 119.137872 -153.492408) (xy 119.129556 -153.494994) (xy 119.093344 -153.507519) (xy 119.019243 -153.527041)
			(xy 118.943738 -153.540123) (xy 118.867389 -153.546671) (xy 118.829074 -153.547064) (xy 118.790757 -153.546706)
			(xy 118.714404 -153.540171) (xy 118.638897 -153.527084) (xy 118.564798 -153.507541) (xy 118.528592 -153.494994)
			(xy 118.520276 -153.492408) (xy 118.502872 -153.492408) (xy 118.494556 -153.494994) (xy 118.458344 -153.507519)
			(xy 118.384243 -153.527041) (xy 118.308738 -153.540123) (xy 118.232389 -153.546671) (xy 118.194074 -153.547064)
			(xy 118.155757 -153.546706) (xy 118.079404 -153.540171) (xy 118.003897 -153.527084) (xy 117.929798 -153.507541)
			(xy 117.893592 -153.494994) (xy 117.885276 -153.492408) (xy 117.867872 -153.492408) (xy 117.859556 -153.494994)
			(xy 117.823344 -153.507519) (xy 117.749243 -153.527041) (xy 117.673738 -153.540123) (xy 117.597389 -153.546671)
			(xy 117.559074 -153.547064) (xy 117.51886 -153.546643) (xy 117.438758 -153.539418) (xy 117.359636 -153.524984)
			(xy 117.282143 -153.50346) (xy 117.244368 -153.48966) (xy 117.235581 -153.486753) (xy 117.217087 -153.486753)
			(xy 117.2083 -153.48966) (xy 117.170526 -153.50346) (xy 117.093029 -153.524965) (xy 117.013907 -153.539393)
			(xy 116.933807 -153.546627) (xy 116.893594 -153.547064) (xy 116.855277 -153.5467) (xy 116.778924 -153.540167)
			(xy 116.703417 -153.527082) (xy 116.629318 -153.50754) (xy 116.593112 -153.494994) (xy 116.584796 -153.492408)
			(xy 116.567392 -153.492408) (xy 116.559076 -153.494994) (xy 116.522953 -153.507485) (xy 116.449041 -153.526976)
			(xy 116.37373 -153.54006) (xy 116.297575 -153.546641) (xy 116.259356 -153.547064) (xy 116.258594 -153.547064)
			(xy 116.217487 -153.546593) (xy 116.135624 -153.539008) (xy 116.05481 -153.523904) (xy 115.975734 -153.501409)
			(xy 115.89907 -153.471714) (xy 115.825473 -153.435075) (xy 115.755569 -153.391802) (xy 115.689955 -153.342264)
			(xy 115.629192 -153.286885) (xy 115.573796 -153.226137) (xy 115.52424 -153.160537) (xy 115.480947 -153.090646)
			(xy 115.444287 -153.017059) (xy 115.414571 -152.940403) (xy 115.392053 -152.861333) (xy 115.376926 -152.780524)
			(xy 115.369318 -152.698663) (xy 115.368832 -152.657556) (xy 35.354948 -152.657556) (xy 35.387298 -152.825405)
			(xy 35.41915 -153.032898) (xy 35.44308 -153.241454) (xy 35.459052 -153.45077) (xy 35.467044 -153.660542)
			(xy 35.467544 -153.765504) (xy 35.467044 -153.870466) (xy 35.459052 -154.080238) (xy 35.44308 -154.289554)
			(xy 35.422918 -154.465274) (xy 127.823468 -154.465274) (xy 127.824038 -154.420505) (xy 127.833047 -154.33142)
			(xy 127.850949 -154.243689) (xy 127.877566 -154.158197) (xy 127.894588 -154.116786) (xy 127.89817 -154.1072)
			(xy 127.89816 -154.086753) (xy 127.894588 -154.077162) (xy 127.87754 -154.03576) (xy 127.850909 -153.95027)
			(xy 127.833008 -153.862535) (xy 127.824018 -153.773445) (xy 127.823468 -153.728674) (xy 127.824038 -153.683905)
			(xy 127.833047 -153.59482) (xy 127.850949 -153.507089) (xy 127.877566 -153.421597) (xy 127.894588 -153.380186)
			(xy 127.89817 -153.3706) (xy 127.89816 -153.350153) (xy 127.894588 -153.340562) (xy 127.87754 -153.29916)
			(xy 127.850909 -153.21367) (xy 127.833008 -153.125935) (xy 127.824018 -153.036845) (xy 127.823468 -152.992074)
			(xy 127.823874 -152.950958) (xy 127.831464 -152.869076) (xy 127.846576 -152.788245) (xy 127.869082 -152.709152)
			(xy 127.898791 -152.632473) (xy 127.935447 -152.558863) (xy 127.978739 -152.488949) (xy 128.028297 -152.423328)
			(xy 128.083699 -152.362559) (xy 128.144471 -152.307161) (xy 128.210095 -152.257607) (xy 128.280012 -152.21432)
			(xy 128.353625 -152.177668) (xy 128.430305 -152.147965) (xy 128.509399 -152.125463) (xy 128.590232 -152.110356)
			(xy 128.672114 -152.102771) (xy 128.71323 -152.102312) (xy 128.754841 -152.102773) (xy 128.837698 -152.110553)
			(xy 128.919467 -152.126031) (xy 128.999435 -152.149074) (xy 129.076903 -152.179479) (xy 129.151195 -152.216982)
			(xy 129.186686 -152.23871) (xy 129.195829 -152.243863) (xy 129.216542 -152.24708) (xy 129.236814 -152.241752)
			(xy 129.24536 -152.235662) (xy 129.278989 -152.209671) (xy 129.350383 -152.163546) (xy 129.425854 -152.124445)
			(xy 129.504712 -152.092724) (xy 129.586237 -152.068675) (xy 129.669685 -152.052515) (xy 129.754295 -152.044393)
			(xy 129.796794 -152.043892) (xy 129.837907 -152.044419) (xy 129.919782 -152.052005) (xy 130.000607 -152.067113)
			(xy 130.079694 -152.089613) (xy 130.156368 -152.119315) (xy 130.229974 -152.155965) (xy 130.299884 -152.19925)
			(xy 130.365503 -152.2488) (xy 130.42627 -152.304193) (xy 130.481667 -152.364957) (xy 130.531221 -152.430573)
			(xy 130.57451 -152.500481) (xy 130.611164 -152.574085) (xy 130.64087 -152.650756) (xy 130.663376 -152.729842)
			(xy 130.678488 -152.810667) (xy 130.686079 -152.892541) (xy 130.686556 -152.933654) (xy 130.685993 -152.978424)
			(xy 130.676983 -153.067509) (xy 130.659077 -153.15524) (xy 130.632459 -153.240731) (xy 130.615436 -153.282142)
			(xy 130.611899 -153.291741) (xy 130.611882 -153.312176) (xy 130.615436 -153.321766) (xy 130.63244 -153.363117)
			(xy 130.659051 -153.448479) (xy 130.676958 -153.536082) (xy 130.68598 -153.625039) (xy 130.686556 -153.669746)
			(xy 130.686556 -153.670762) (xy 130.686302 -153.682192) (xy 130.712781 -153.688138) (xy 130.765016 -153.702881)
			(xy 130.790696 -153.711656) (xy 130.798893 -153.71417) (xy 130.816027 -153.71417) (xy 130.824224 -153.711656)
			(xy 130.85944 -153.699695) (xy 130.931444 -153.681041) (xy 131.004765 -153.668532) (xy 131.07888 -153.662259)
			(xy 131.11607 -153.661872) (xy 131.153259 -153.662271) (xy 131.227372 -153.668558) (xy 131.300692 -153.681065)
			(xy 131.372698 -153.699703) (xy 131.407916 -153.711656) (xy 131.416113 -153.71417) (xy 131.433247 -153.71417)
			(xy 131.441444 -153.711656) (xy 131.476659 -153.699689) (xy 131.548662 -153.681037) (xy 131.621984 -153.66853)
			(xy 131.6961 -153.662258) (xy 131.73329 -153.661872) (xy 131.77523 -153.662267) (xy 131.858732 -153.670239)
			(xy 131.941097 -153.686113) (xy 132.02158 -153.709744) (xy 132.099453 -153.740919) (xy 132.165372 -153.774902)
			(xy 188.441847 -153.774902) (xy 188.445843 -153.565016) (xy 188.457828 -153.355434) (xy 188.477782 -153.14646)
			(xy 188.505678 -152.938398) (xy 188.541475 -152.731548) (xy 188.58512 -152.526211) (xy 188.636552 -152.322685)
			(xy 188.695694 -152.121264) (xy 188.762462 -151.922241) (xy 188.836758 -151.725904) (xy 188.918476 -151.532538)
			(xy 189.007495 -151.342423) (xy 189.103688 -151.155835) (xy 189.206915 -150.973044) (xy 189.317026 -150.794316)
			(xy 189.433861 -150.619909) (xy 189.557251 -150.450077) (xy 189.687018 -150.285065) (xy 189.822972 -150.125114)
			(xy 189.964918 -149.970454) (xy 190.112648 -149.82131) (xy 190.26595 -149.677899) (xy 190.4246 -149.540428)
			(xy 190.588369 -149.409096) (xy 190.757019 -149.284095) (xy 190.930305 -149.165604) (xy 191.107977 -149.053797)
			(xy 191.289777 -148.948835) (xy 191.475441 -148.85087) (xy 191.664699 -148.760045) (xy 191.857279 -148.676491)
			(xy 192.0529 -148.600328) (xy 192.251278 -148.531669) (xy 192.452127 -148.470612) (xy 192.655154 -148.417245)
			(xy 192.860067 -148.371647) (xy 193.066566 -148.333882) (xy 193.274353 -148.304007) (xy 193.483128 -148.282064)
			(xy 193.692586 -148.268085) (xy 193.902425 -148.26209) (xy 194.112339 -148.264089) (xy 194.322026 -148.274077)
			(xy 194.53118 -148.292042) (xy 194.739498 -148.317956) (xy 194.946679 -148.351781) (xy 195.152423 -148.39347)
			(xy 195.356429 -148.442962) (xy 195.558404 -148.500184) (xy 195.758054 -148.565054) (xy 195.955089 -148.637478)
			(xy 196.149225 -148.717351) (xy 196.340178 -148.804557) (xy 196.527674 -148.898969) (xy 196.711439 -149.000451)
			(xy 196.891207 -149.108855) (xy 197.066718 -149.224025) (xy 197.237717 -149.345793) (xy 197.403957 -149.473982)
			(xy 197.565196 -149.608408) (xy 197.7212 -149.748875) (xy 197.871743 -149.895179) (xy 198.016607 -150.047108)
			(xy 198.155582 -150.204442) (xy 198.288467 -150.366953) (xy 198.415068 -150.534406) (xy 198.535203 -150.706556)
			(xy 198.648697 -150.883156) (xy 198.755385 -151.063948) (xy 198.855112 -151.248671) (xy 198.947735 -151.437057)
			(xy 199.033119 -151.628832) (xy 199.11114 -151.823719) (xy 199.181685 -152.021435) (xy 199.244652 -152.221693)
			(xy 199.299949 -152.424203) (xy 199.347496 -152.628672) (xy 199.387224 -152.834803) (xy 199.419076 -153.042296)
			(xy 199.443006 -153.250852) (xy 199.458978 -153.460168) (xy 199.46697 -153.66994) (xy 199.467428 -153.766012)
			(xy 272.382243 -153.766012) (xy 272.386239 -153.556126) (xy 272.398224 -153.346544) (xy 272.418178 -153.13757)
			(xy 272.446074 -152.929508) (xy 272.481871 -152.722658) (xy 272.525516 -152.517321) (xy 272.576948 -152.313795)
			(xy 272.63609 -152.112374) (xy 272.702858 -151.913351) (xy 272.777154 -151.717014) (xy 272.858872 -151.523648)
			(xy 272.947891 -151.333533) (xy 273.044084 -151.146945) (xy 273.147311 -150.964154) (xy 273.257422 -150.785426)
			(xy 273.374257 -150.611019) (xy 273.497647 -150.441187) (xy 273.627414 -150.276175) (xy 273.763368 -150.116224)
			(xy 273.905314 -149.961564) (xy 274.053044 -149.81242) (xy 274.206346 -149.669009) (xy 274.364996 -149.531538)
			(xy 274.528765 -149.400206) (xy 274.697415 -149.275205) (xy 274.870701 -149.156714) (xy 275.048373 -149.044907)
			(xy 275.230173 -148.939945) (xy 275.415837 -148.84198) (xy 275.605095 -148.751155) (xy 275.797675 -148.667601)
			(xy 275.993296 -148.591438) (xy 276.191674 -148.522779) (xy 276.392523 -148.461722) (xy 276.59555 -148.408355)
			(xy 276.800463 -148.362757) (xy 277.006962 -148.324992) (xy 277.214749 -148.295117) (xy 277.423524 -148.273174)
			(xy 277.632982 -148.259195) (xy 277.842821 -148.2532) (xy 278.052735 -148.255199) (xy 278.262422 -148.265187)
			(xy 278.471576 -148.283152) (xy 278.679894 -148.309066) (xy 278.887075 -148.342891) (xy 279.092819 -148.38458)
			(xy 279.296825 -148.434072) (xy 279.4988 -148.491294) (xy 279.69845 -148.556164) (xy 279.895485 -148.628588)
			(xy 280.089621 -148.708461) (xy 280.280574 -148.795667) (xy 280.46807 -148.890079) (xy 280.651835 -148.991561)
			(xy 280.831603 -149.099965) (xy 281.007114 -149.215135) (xy 281.178113 -149.336903) (xy 281.344353 -149.465092)
			(xy 281.505592 -149.599518) (xy 281.661596 -149.739985) (xy 281.812139 -149.886289) (xy 281.957003 -150.038218)
			(xy 282.095978 -150.195552) (xy 282.228863 -150.358063) (xy 282.355464 -150.525516) (xy 282.475599 -150.697666)
			(xy 282.589093 -150.874266) (xy 282.695781 -151.055058) (xy 282.795508 -151.239781) (xy 282.888131 -151.428167)
			(xy 282.973515 -151.619942) (xy 283.051536 -151.814829) (xy 283.122081 -152.012545) (xy 283.185048 -152.212803)
			(xy 283.240345 -152.415313) (xy 283.287892 -152.619782) (xy 283.305746 -152.71242) (xy 358.186997 -152.71242)
			(xy 358.191002 -152.606671) (xy 358.202992 -152.501528) (xy 358.222901 -152.397593) (xy 358.250612 -152.295461)
			(xy 358.285969 -152.195717) (xy 358.328767 -152.098933) (xy 358.378763 -152.005663) (xy 358.43567 -151.916442)
			(xy 358.499161 -151.831779) (xy 358.568873 -151.752161) (xy 358.644407 -151.678043) (xy 358.72533 -151.60985)
			(xy 358.811179 -151.547972) (xy 358.901462 -151.492765) (xy 358.995661 -151.444543) (xy 359.093238 -151.403583)
			(xy 359.193633 -151.370121) (xy 359.296271 -151.344347) (xy 359.400564 -151.326409) (xy 359.505915 -151.31641)
			(xy 359.611721 -151.314407) (xy 359.717375 -151.320412) (xy 359.822272 -151.334391) (xy 359.925812 -151.356262)
			(xy 360.027401 -151.385902) (xy 360.126458 -151.42314) (xy 360.222415 -151.467762) (xy 360.314722 -151.519514)
			(xy 360.402851 -151.578099) (xy 360.486297 -151.643181) (xy 360.564581 -151.714387) (xy 360.637256 -151.79131)
			(xy 360.703906 -151.87351) (xy 360.764148 -151.960514) (xy 360.817637 -152.051825) (xy 360.864068 -152.14692)
			(xy 360.903173 -152.245254) (xy 360.93473 -152.346265) (xy 360.958557 -152.449372) (xy 360.974518 -152.553986)
			(xy 360.982522 -152.659508) (xy 360.983022 -152.71242) (xy 360.982522 -152.765332) (xy 360.974518 -152.870854)
			(xy 360.958557 -152.975468) (xy 360.93473 -153.078575) (xy 360.903173 -153.179586) (xy 360.864068 -153.27792)
			(xy 360.817637 -153.373015) (xy 360.764148 -153.464326) (xy 360.703906 -153.55133) (xy 360.637256 -153.63353)
			(xy 360.564581 -153.710453) (xy 360.486297 -153.781659) (xy 360.402851 -153.846741) (xy 360.314722 -153.905326)
			(xy 360.222415 -153.957078) (xy 360.126458 -154.0017) (xy 360.027401 -154.038938) (xy 359.925812 -154.068578)
			(xy 359.822272 -154.090449) (xy 359.717375 -154.104428) (xy 359.611721 -154.110433) (xy 359.505915 -154.10843)
			(xy 359.400564 -154.098431) (xy 359.296271 -154.080493) (xy 359.193633 -154.054719) (xy 359.093238 -154.021257)
			(xy 358.995661 -153.980297) (xy 358.901462 -153.932075) (xy 358.811179 -153.876868) (xy 358.72533 -153.81499)
			(xy 358.644407 -153.746797) (xy 358.568873 -153.672679) (xy 358.499161 -153.593061) (xy 358.43567 -153.508398)
			(xy 358.378763 -153.419177) (xy 358.328767 -153.325907) (xy 358.285969 -153.229123) (xy 358.250612 -153.129379)
			(xy 358.222901 -153.027247) (xy 358.202992 -152.923312) (xy 358.191002 -152.818169) (xy 358.186997 -152.71242)
			(xy 283.305746 -152.71242) (xy 283.32762 -152.825913) (xy 283.359472 -153.033406) (xy 283.383402 -153.241962)
			(xy 283.399374 -153.451278) (xy 283.407366 -153.66105) (xy 283.407866 -153.766012) (xy 283.407366 -153.870974)
			(xy 283.399374 -154.080746) (xy 283.383402 -154.290062) (xy 283.359472 -154.498618) (xy 283.32762 -154.706111)
			(xy 283.287892 -154.912242) (xy 283.240345 -155.116711) (xy 283.185048 -155.319221) (xy 283.122081 -155.519479)
			(xy 283.051536 -155.717195) (xy 282.973515 -155.912082) (xy 282.888131 -156.103857) (xy 282.795508 -156.292243)
			(xy 282.695781 -156.476966) (xy 282.589093 -156.657758) (xy 282.475599 -156.834358) (xy 282.355464 -157.006508)
			(xy 282.228863 -157.173961) (xy 282.095978 -157.336472) (xy 281.957003 -157.493806) (xy 281.812139 -157.645735)
			(xy 281.661596 -157.792039) (xy 281.505592 -157.932506) (xy 281.344353 -158.066932) (xy 281.178113 -158.195121)
			(xy 281.007114 -158.316889) (xy 280.831603 -158.432059) (xy 280.651835 -158.540463) (xy 280.46807 -158.641945)
			(xy 280.280574 -158.736357) (xy 280.089621 -158.823563) (xy 279.895485 -158.903436) (xy 279.69845 -158.97586)
			(xy 279.4988 -159.04073) (xy 279.382794 -159.073596) (xy 343.127076 -159.073596) (xy 343.127653 -159.028827)
			(xy 343.136659 -158.939742) (xy 343.15456 -158.852011) (xy 343.181175 -158.766519) (xy 343.198196 -158.725108)
			(xy 343.201765 -158.715518) (xy 343.201764 -158.695074) (xy 343.198196 -158.685484) (xy 343.181156 -158.644079)
			(xy 343.154522 -158.55859) (xy 343.136619 -158.470856) (xy 343.127627 -158.381767) (xy 343.127076 -158.336996)
			(xy 343.127653 -158.292227) (xy 343.136659 -158.203142) (xy 343.15456 -158.115411) (xy 343.181175 -158.029919)
			(xy 343.198196 -157.988508) (xy 343.201765 -157.978918) (xy 343.201764 -157.958474) (xy 343.198196 -157.948884)
			(xy 343.181156 -157.907479) (xy 343.154522 -157.82199) (xy 343.136619 -157.734256) (xy 343.127627 -157.645167)
			(xy 343.127076 -157.600396) (xy 343.127549 -157.559286) (xy 343.135137 -157.477416) (xy 343.150247 -157.396596)
			(xy 343.172752 -157.317516) (xy 343.202459 -157.240849) (xy 343.239114 -157.167252) (xy 343.282404 -157.097351)
			(xy 343.33196 -157.031743) (xy 343.387359 -156.970988) (xy 343.448129 -156.915605) (xy 343.51375 -156.866067)
			(xy 343.583663 -156.822796) (xy 343.657271 -156.786161) (xy 343.733945 -156.756475) (xy 343.813032 -156.733992)
			(xy 343.893856 -156.718903) (xy 343.975728 -156.711337) (xy 344.016838 -156.710888) (xy 344.058442 -156.711362)
			(xy 344.14129 -156.719094) (xy 344.223055 -156.734524) (xy 344.303022 -156.757517) (xy 344.380495 -156.787874)
			(xy 344.454797 -156.825328) (xy 344.490294 -156.847032) (xy 344.499434 -156.852189) (xy 344.520149 -156.855402)
			(xy 344.540422 -156.850073) (xy 344.548968 -156.843984) (xy 344.582592 -156.818029) (xy 344.653971 -156.771973)
			(xy 344.729414 -156.73293) (xy 344.808235 -156.701255) (xy 344.889716 -156.677237) (xy 344.973116 -156.661094)
			(xy 345.057674 -156.652974) (xy 345.100148 -156.652468) (xy 345.100402 -156.652468) (xy 345.14151 -156.652911)
			(xy 345.223374 -156.660496) (xy 345.30419 -156.6756) (xy 345.383268 -156.698096) (xy 345.459933 -156.727791)
			(xy 345.533532 -156.764433) (xy 345.603437 -156.807707) (xy 345.669051 -156.857246) (xy 345.729816 -156.912627)
			(xy 345.785212 -156.973378) (xy 345.806812 -157.001972) (xy 386.403596 -157.001972) (xy 386.40399 -156.963682)
			(xy 386.410601 -156.887387) (xy 386.423753 -156.811945) (xy 386.44335 -156.737915) (xy 386.45592 -156.701744)
			(xy 386.458586 -156.693311) (xy 386.458577 -156.675637) (xy 386.45592 -156.6672) (xy 386.443367 -156.631026)
			(xy 386.423796 -156.556991) (xy 386.410652 -156.481551) (xy 386.40403 -156.40526) (xy 386.403596 -156.366972)
			(xy 386.404015 -156.328179) (xy 386.410791 -156.25089) (xy 386.424264 -156.174482) (xy 386.44433 -156.099536)
			(xy 386.45719 -156.062934) (xy 386.459858 -156.054502) (xy 386.459846 -156.036827) (xy 386.45719 -156.02839)
			(xy 386.444324 -155.991789) (xy 386.424239 -155.916847) (xy 386.410766 -155.840438) (xy 386.404005 -155.763146)
			(xy 386.403596 -155.724352) (xy 386.404014 -155.686062) (xy 386.410618 -155.609769) (xy 386.423763 -155.534326)
			(xy 386.443354 -155.460295) (xy 386.45592 -155.424124) (xy 386.458596 -155.415693) (xy 386.45858 -155.398017)
			(xy 386.45592 -155.38958) (xy 386.443389 -155.353398) (xy 386.423812 -155.279367) (xy 386.410662 -155.203928)
			(xy 386.404034 -155.12764) (xy 386.403596 -155.089352) (xy 386.40407 -155.049438) (xy 386.411294 -154.969935)
			(xy 386.425601 -154.891398) (xy 386.446874 -154.814455) (xy 386.460492 -154.776932) (xy 386.463345 -154.768269)
			(xy 386.463329 -154.750041) (xy 386.460492 -154.741372) (xy 386.44684 -154.70386) (xy 386.425547 -154.626919)
			(xy 386.411244 -154.548377) (xy 386.404048 -154.468869) (xy 386.403596 -154.428952) (xy 386.404014 -154.390662)
			(xy 386.410618 -154.314369) (xy 386.423763 -154.238926) (xy 386.443354 -154.164895) (xy 386.45592 -154.128724)
			(xy 386.458596 -154.120293) (xy 386.45858 -154.102617) (xy 386.45592 -154.09418) (xy 386.443389 -154.057998)
			(xy 386.423812 -153.983967) (xy 386.410662 -153.908528) (xy 386.404034 -153.83224) (xy 386.403596 -153.793952)
			(xy 386.404007 -153.75284) (xy 386.411599 -153.670969) (xy 386.426714 -153.590147) (xy 386.449223 -153.511065)
			(xy 386.478934 -153.434397) (xy 386.515593 -153.360799) (xy 386.558887 -153.290897) (xy 386.608448 -153.225289)
			(xy 386.663851 -153.164535) (xy 386.724625 -153.109152) (xy 386.79025 -153.059614) (xy 386.860166 -153.016344)
			(xy 386.933777 -152.97971) (xy 387.010455 -152.950026) (xy 387.089545 -152.927544) (xy 387.170372 -152.912457)
			(xy 387.252246 -152.904893) (xy 387.293358 -152.904444) (xy 387.331674 -152.904822) (xy 387.408027 -152.91135)
			(xy 387.483534 -152.924432) (xy 387.557634 -152.94397) (xy 387.59384 -152.956514) (xy 387.602156 -152.9591)
			(xy 387.61956 -152.9591) (xy 387.627876 -152.956514) (xy 387.663994 -152.944008) (xy 387.737908 -152.924522)
			(xy 387.81322 -152.911442) (xy 387.889376 -152.904865) (xy 387.927596 -152.904444) (xy 387.928358 -152.904444)
			(xy 387.969464 -152.904953) (xy 388.051326 -152.912533) (xy 388.13214 -152.927634) (xy 388.211216 -152.950125)
			(xy 388.28788 -152.979816) (xy 388.361478 -153.016453) (xy 388.431382 -153.059723) (xy 388.496996 -153.109258)
			(xy 388.55776 -153.164634) (xy 388.613157 -153.225381) (xy 388.662713 -153.290979) (xy 388.706006 -153.360869)
			(xy 388.742667 -153.434454) (xy 388.772383 -153.511109) (xy 388.7949 -153.590177) (xy 388.810027 -153.670986)
			(xy 388.817634 -153.752846) (xy 388.817889 -153.774394) (xy 436.382169 -153.774394) (xy 436.386165 -153.564508)
			(xy 436.39815 -153.354926) (xy 436.418104 -153.145952) (xy 436.446 -152.93789) (xy 436.481797 -152.73104)
			(xy 436.525442 -152.525703) (xy 436.576874 -152.322177) (xy 436.636016 -152.120756) (xy 436.702784 -151.921733)
			(xy 436.77708 -151.725396) (xy 436.858798 -151.53203) (xy 436.947817 -151.341915) (xy 437.04401 -151.155327)
			(xy 437.147237 -150.972536) (xy 437.257348 -150.793808) (xy 437.374183 -150.619401) (xy 437.497573 -150.449569)
			(xy 437.62734 -150.284557) (xy 437.763294 -150.124606) (xy 437.90524 -149.969946) (xy 438.05297 -149.820802)
			(xy 438.206272 -149.677391) (xy 438.364922 -149.53992) (xy 438.528691 -149.408588) (xy 438.697341 -149.283587)
			(xy 438.870627 -149.165096) (xy 439.048299 -149.053289) (xy 439.230099 -148.948327) (xy 439.415763 -148.850362)
			(xy 439.605021 -148.759537) (xy 439.797601 -148.675983) (xy 439.993222 -148.59982) (xy 440.1916 -148.531161)
			(xy 440.392449 -148.470104) (xy 440.595476 -148.416737) (xy 440.800389 -148.371139) (xy 441.006888 -148.333374)
			(xy 441.214675 -148.303499) (xy 441.42345 -148.281556) (xy 441.632908 -148.267577) (xy 441.842747 -148.261582)
			(xy 442.052661 -148.263581) (xy 442.262348 -148.273569) (xy 442.471502 -148.291534) (xy 442.67982 -148.317448)
			(xy 442.887001 -148.351273) (xy 443.092745 -148.392962) (xy 443.296751 -148.442454) (xy 443.498726 -148.499676)
			(xy 443.698376 -148.564546) (xy 443.895411 -148.63697) (xy 444.089547 -148.716843) (xy 444.2805 -148.804049)
			(xy 444.467996 -148.898461) (xy 444.651761 -148.999943) (xy 444.831529 -149.108347) (xy 445.00704 -149.223517)
			(xy 445.178039 -149.345285) (xy 445.344279 -149.473474) (xy 445.505518 -149.6079) (xy 445.661522 -149.748367)
			(xy 445.812065 -149.894671) (xy 445.956929 -150.0466) (xy 446.095904 -150.203934) (xy 446.228789 -150.366445)
			(xy 446.35539 -150.533898) (xy 446.475525 -150.706048) (xy 446.589019 -150.882648) (xy 446.695707 -151.06344)
			(xy 446.795434 -151.248163) (xy 446.888057 -151.436549) (xy 446.973441 -151.628324) (xy 447.051462 -151.823211)
			(xy 447.122007 -152.020927) (xy 447.184974 -152.221185) (xy 447.240271 -152.423695) (xy 447.287818 -152.628164)
			(xy 447.327546 -152.834295) (xy 447.359398 -153.041788) (xy 447.383328 -153.250344) (xy 447.3993 -153.45966)
			(xy 447.407292 -153.669432) (xy 447.407792 -153.774394) (xy 447.407292 -153.879356) (xy 447.3993 -154.089128)
			(xy 447.383328 -154.298444) (xy 447.359398 -154.507) (xy 447.327546 -154.714493) (xy 447.287818 -154.920624)
			(xy 447.240271 -155.125093) (xy 447.184974 -155.327603) (xy 447.122007 -155.527861) (xy 447.051462 -155.725577)
			(xy 446.973441 -155.920464) (xy 446.888057 -156.112239) (xy 446.795434 -156.300625) (xy 446.695707 -156.485348)
			(xy 446.589019 -156.66614) (xy 446.475525 -156.84274) (xy 446.35539 -157.01489) (xy 446.228789 -157.182343)
			(xy 446.095904 -157.344854) (xy 445.956929 -157.502188) (xy 445.812065 -157.654117) (xy 445.661522 -157.800421)
			(xy 445.505518 -157.940888) (xy 445.344279 -158.075314) (xy 445.178039 -158.203503) (xy 445.00704 -158.325271)
			(xy 444.831529 -158.440441) (xy 444.651761 -158.548845) (xy 444.467996 -158.650327) (xy 444.2805 -158.744739)
			(xy 444.089547 -158.831945) (xy 443.895411 -158.911818) (xy 443.698376 -158.984242) (xy 443.498726 -159.049112)
			(xy 443.296751 -159.106334) (xy 443.092745 -159.155826) (xy 442.887001 -159.197515) (xy 442.67982 -159.23134)
			(xy 442.471502 -159.257254) (xy 442.262348 -159.275219) (xy 442.052661 -159.285207) (xy 441.842747 -159.287206)
			(xy 441.632908 -159.281211) (xy 441.42345 -159.267232) (xy 441.214675 -159.245289) (xy 441.006888 -159.215414)
			(xy 440.800389 -159.177649) (xy 440.595476 -159.132051) (xy 440.392449 -159.078684) (xy 440.1916 -159.017627)
			(xy 439.993222 -158.948968) (xy 439.797601 -158.872805) (xy 439.605021 -158.789251) (xy 439.415763 -158.698426)
			(xy 439.230099 -158.600461) (xy 439.048299 -158.495499) (xy 438.870627 -158.383692) (xy 438.697341 -158.265201)
			(xy 438.528691 -158.1402) (xy 438.364922 -158.008868) (xy 438.206272 -157.871397) (xy 438.05297 -157.727986)
			(xy 437.90524 -157.578842) (xy 437.763294 -157.424182) (xy 437.62734 -157.264231) (xy 437.497573 -157.099219)
			(xy 437.374183 -156.929387) (xy 437.257348 -156.75498) (xy 437.147237 -156.576252) (xy 437.04401 -156.393461)
			(xy 436.947817 -156.206873) (xy 436.858798 -156.016758) (xy 436.77708 -155.823392) (xy 436.702784 -155.627055)
			(xy 436.636016 -155.428032) (xy 436.576874 -155.226611) (xy 436.525442 -155.023085) (xy 436.481797 -154.817748)
			(xy 436.446 -154.610898) (xy 436.418104 -154.402836) (xy 436.39815 -154.193862) (xy 436.386165 -153.98428)
			(xy 436.382169 -153.774394) (xy 388.817889 -153.774394) (xy 388.81812 -153.793952) (xy 388.817702 -153.832242)
			(xy 388.811098 -153.908535) (xy 388.797953 -153.983978) (xy 388.778362 -154.058009) (xy 388.765796 -154.09418)
			(xy 388.763168 -154.102623) (xy 388.763152 -154.120288) (xy 388.765796 -154.128724) (xy 388.778328 -154.164905)
			(xy 388.797905 -154.238937) (xy 388.811055 -154.314375) (xy 388.817683 -154.390664) (xy 388.81812 -154.428952)
			(xy 388.817646 -154.468866) (xy 388.810422 -154.548369) (xy 388.796115 -154.626906) (xy 388.774842 -154.703849)
			(xy 388.761224 -154.741372) (xy 388.758419 -154.750047) (xy 388.758403 -154.768264) (xy 388.761224 -154.776932)
			(xy 388.774878 -154.814443) (xy 388.79617 -154.891385) (xy 388.810472 -154.969927) (xy 388.817668 -155.049435)
			(xy 388.81812 -155.089352) (xy 388.817702 -155.127642) (xy 388.811098 -155.203935) (xy 388.797953 -155.279378)
			(xy 388.778362 -155.353409) (xy 388.765796 -155.38958) (xy 388.763168 -155.398023) (xy 388.763152 -155.415688)
			(xy 388.765796 -155.424124) (xy 388.778328 -155.460305) (xy 388.797905 -155.534337) (xy 388.811055 -155.609775)
			(xy 388.817683 -155.686064) (xy 388.81812 -155.724352) (xy 388.817677 -155.763144) (xy 388.810908 -155.840433)
			(xy 388.797442 -155.916841) (xy 388.777382 -155.991787) (xy 388.764526 -156.02839) (xy 388.761895 -156.036832)
			(xy 388.761883 -156.054497) (xy 388.764526 -156.062934) (xy 388.7774 -156.099532) (xy 388.797482 -156.174476)
			(xy 388.810953 -156.250885) (xy 388.817712 -156.328178) (xy 388.81812 -156.366972) (xy 388.817708 -156.405262)
			(xy 388.811103 -156.481556) (xy 388.797955 -156.556998) (xy 388.778363 -156.631029) (xy 388.765796 -156.6672)
			(xy 388.763157 -156.67564) (xy 388.763148 -156.693308) (xy 388.765796 -156.701744) (xy 388.778334 -156.737923)
			(xy 388.797909 -156.811956) (xy 388.811058 -156.887395) (xy 388.817683 -156.963684) (xy 388.81812 -157.001972)
			(xy 388.817621 -157.043082) (xy 388.810036 -157.124951) (xy 388.794928 -157.20577) (xy 388.772425 -157.284851)
			(xy 388.742721 -157.361517) (xy 388.706068 -157.435115) (xy 388.66278 -157.505016) (xy 388.613226 -157.570624)
			(xy 388.557828 -157.631379) (xy 388.49706 -157.686762) (xy 388.43144 -157.736301) (xy 388.361528 -157.779573)
			(xy 388.287921 -157.816208) (xy 388.211248 -157.845893) (xy 388.132162 -157.868377) (xy 388.051339 -157.883465)
			(xy 387.969468 -157.891031) (xy 387.928358 -157.89148) (xy 387.890041 -157.891126) (xy 387.813688 -157.88459)
			(xy 387.738181 -157.871501) (xy 387.664082 -157.851957) (xy 387.627876 -157.83941) (xy 387.61956 -157.836824)
			(xy 387.602156 -157.836824) (xy 387.59384 -157.83941) (xy 387.557721 -157.851912) (xy 387.483807 -157.871399)
			(xy 387.408495 -157.88448) (xy 387.33234 -157.891059) (xy 387.29412 -157.89148) (xy 387.293358 -157.89148)
			(xy 387.252251 -157.891028) (xy 387.170388 -157.88344) (xy 387.089574 -157.868332) (xy 387.010498 -157.845835)
			(xy 386.933835 -157.816138) (xy 386.860238 -157.779497) (xy 386.790335 -157.736222) (xy 386.724722 -157.686684)
			(xy 386.663959 -157.631304) (xy 386.608563 -157.570555) (xy 386.559008 -157.504955) (xy 386.515715 -157.435063)
			(xy 386.479055 -157.361475) (xy 386.449338 -157.28482) (xy 386.42682 -157.20575) (xy 386.411692 -157.12494)
			(xy 386.404083 -157.043079) (xy 386.403596 -157.001972) (xy 345.806812 -157.001972) (xy 345.834767 -157.03898)
			(xy 345.878059 -157.108874) (xy 345.914719 -157.182463) (xy 345.944433 -157.259121) (xy 345.966949 -157.338193)
			(xy 345.982074 -157.419006) (xy 345.989679 -157.500868) (xy 345.990164 -157.541976) (xy 345.989609 -157.586746)
			(xy 345.980596 -157.675831) (xy 345.962689 -157.763562) (xy 345.936068 -157.849053) (xy 345.919044 -157.890464)
			(xy 345.915494 -157.900059) (xy 345.915485 -157.920497) (xy 345.919044 -157.930088) (xy 345.936056 -157.971436)
			(xy 345.962665 -158.056799) (xy 345.980569 -158.144403) (xy 345.989589 -158.233361) (xy 345.990164 -158.278068)
			(xy 345.990164 -158.279084) (xy 345.98991 -158.290514) (xy 346.016389 -158.296459) (xy 346.068624 -158.311202)
			(xy 346.094304 -158.319978) (xy 346.102501 -158.322492) (xy 346.119635 -158.322492) (xy 346.127832 -158.319978)
			(xy 346.163048 -158.308033) (xy 346.235059 -158.289446) (xy 346.308381 -158.277006) (xy 346.382492 -158.2708)
			(xy 346.419678 -158.270448) (xy 346.456862 -158.27082) (xy 346.53097 -158.277041) (xy 346.60429 -158.289483)
			(xy 346.676301 -158.308056) (xy 346.711524 -158.319978) (xy 346.719721 -158.322492) (xy 346.736855 -158.322492)
			(xy 346.745052 -158.319978) (xy 346.780146 -158.308069) (xy 346.851906 -158.289524) (xy 346.924971 -158.277084)
			(xy 346.998824 -158.270837) (xy 347.035882 -158.270448) (xy 347.036898 -158.270448) (xy 347.078822 -158.270999)
			(xy 347.162292 -158.278969) (xy 347.244625 -158.294837) (xy 347.325078 -158.31846) (xy 347.40292 -158.349624)
			(xy 347.477448 -158.388045) (xy 347.547987 -158.433377) (xy 347.613896 -158.485209) (xy 347.674581 -158.543071)
			(xy 347.72949 -158.60644) (xy 347.778127 -158.674741) (xy 347.820052 -158.747357) (xy 347.854884 -158.823628)
			(xy 347.882308 -158.902865) (xy 347.902076 -158.984351) (xy 347.914009 -159.067346) (xy 347.917999 -159.1511)
			(xy 347.914009 -159.234854) (xy 347.902076 -159.317849) (xy 347.882308 -159.399335) (xy 347.854884 -159.478572)
			(xy 347.820052 -159.554843) (xy 347.778127 -159.627459) (xy 347.72949 -159.69576) (xy 347.674581 -159.759129)
			(xy 347.613896 -159.816991) (xy 347.547987 -159.868823) (xy 347.477448 -159.914155) (xy 347.40292 -159.952576)
			(xy 347.325078 -159.98374) (xy 347.244625 -160.007363) (xy 347.162292 -160.023231) (xy 347.078822 -160.031201)
			(xy 347.036898 -160.031684) (xy 347.035882 -160.031684) (xy 346.998825 -160.031285) (xy 346.924976 -160.025019)
			(xy 346.851913 -160.012575) (xy 346.780153 -159.994041) (xy 346.745052 -159.982154) (xy 346.736855 -159.97964)
			(xy 346.719721 -159.97964) (xy 346.711524 -159.982154) (xy 346.684116 -159.991499) (xy 346.628318 -160.007008)
			(xy 346.600018 -160.013142) (xy 346.590235 -160.015622) (xy 346.573598 -160.027019) (xy 346.562626 -160.04394)
			(xy 346.560394 -160.053782) (xy 346.550929 -160.102889) (xy 346.522417 -160.19875) (xy 346.503498 -160.245044)
			(xy 346.499892 -160.254619) (xy 346.499745 -160.275056) (xy 346.503244 -160.284668) (xy 346.520278 -160.326041)
			(xy 346.546893 -160.41147) (xy 346.564794 -160.499139) (xy 346.5738 -160.588163) (xy 346.574364 -160.632902)
			(xy 346.574364 -160.633156) (xy 346.57386 -160.675504) (xy 346.565809 -160.759818) (xy 346.54978 -160.842984)
			(xy 346.525919 -160.924251) (xy 346.49444 -161.002881) (xy 346.455629 -161.078162) (xy 346.409839 -161.149414)
			(xy 346.357483 -161.21599) (xy 346.299035 -161.277288) (xy 346.235025 -161.332753) (xy 346.166033 -161.381882)
			(xy 346.092683 -161.424231) (xy 346.01564 -161.459415) (xy 345.935601 -161.487117) (xy 345.853292 -161.507085)
			(xy 345.769457 -161.519138) (xy 345.684856 -161.523169) (xy 345.600255 -161.519138) (xy 345.51642 -161.507085)
			(xy 345.434111 -161.487117) (xy 345.354072 -161.459415) (xy 345.277029 -161.424231) (xy 345.203679 -161.381882)
			(xy 345.134687 -161.332753) (xy 345.070677 -161.277288) (xy 345.012229 -161.21599) (xy 344.959873 -161.149414)
			(xy 344.914083 -161.078162) (xy 344.875272 -161.002881) (xy 344.843793 -160.924251) (xy 344.819932 -160.842984)
			(xy 344.803903 -160.759818) (xy 344.795852 -160.675504) (xy 344.795348 -160.633156) (xy 344.795348 -160.632902)
			(xy 344.795938 -160.588164) (xy 344.804948 -160.499143) (xy 344.822847 -160.411476) (xy 344.849453 -160.326048)
			(xy 344.866468 -160.284668) (xy 344.870056 -160.275084) (xy 344.87004 -160.254635) (xy 344.866468 -160.245044)
			(xy 344.849433 -160.203637) (xy 344.822801 -160.118148) (xy 344.804897 -160.030415) (xy 344.795901 -159.941327)
			(xy 344.795348 -159.896556) (xy 344.795678 -159.859467) (xy 344.801776 -159.78554) (xy 344.814009 -159.712377)
			(xy 344.82278 -159.676338) (xy 344.824538 -159.668008) (xy 344.823098 -159.651057) (xy 344.816174 -159.635517)
			(xy 344.810588 -159.629094) (xy 344.770202 -159.586168) (xy 344.758264 -159.588708) (xy 344.749364 -159.591023)
			(xy 344.733871 -159.600904) (xy 344.728038 -159.608012) (xy 344.702891 -159.640664) (xy 344.647483 -159.701681)
			(xy 344.586669 -159.757312) (xy 344.520971 -159.807081) (xy 344.450952 -159.850561) (xy 344.377213 -159.887379)
			(xy 344.300384 -159.917221) (xy 344.221125 -159.93983) (xy 344.140115 -159.955012) (xy 344.058048 -159.962637)
			(xy 344.016838 -159.963104) (xy 343.975733 -159.962551) (xy 343.893874 -159.954971) (xy 343.813062 -159.939871)
			(xy 343.733989 -159.917381) (xy 343.657327 -159.887692) (xy 343.583731 -159.851057) (xy 343.513829 -159.807789)
			(xy 343.448216 -159.758257) (xy 343.387452 -159.702884) (xy 343.332056 -159.642141) (xy 343.2825 -159.576547)
			(xy 343.239206 -159.506661) (xy 343.202543 -159.433078) (xy 343.172826 -159.356428) (xy 343.150306 -159.277363)
			(xy 343.135175 -159.196557) (xy 343.127564 -159.114701) (xy 343.127076 -159.073596) (xy 279.382794 -159.073596)
			(xy 279.296825 -159.097952) (xy 279.092819 -159.147444) (xy 278.887075 -159.189133) (xy 278.679894 -159.222958)
			(xy 278.471576 -159.248872) (xy 278.262422 -159.266837) (xy 278.052735 -159.276825) (xy 277.842821 -159.278824)
			(xy 277.632982 -159.272829) (xy 277.423524 -159.25885) (xy 277.214749 -159.236907) (xy 277.006962 -159.207032)
			(xy 276.800463 -159.169267) (xy 276.59555 -159.123669) (xy 276.392523 -159.070302) (xy 276.191674 -159.009245)
			(xy 275.993296 -158.940586) (xy 275.797675 -158.864423) (xy 275.605095 -158.780869) (xy 275.415837 -158.690044)
			(xy 275.230173 -158.592079) (xy 275.048373 -158.487117) (xy 274.870701 -158.37531) (xy 274.697415 -158.256819)
			(xy 274.528765 -158.131818) (xy 274.364996 -158.000486) (xy 274.206346 -157.863015) (xy 274.053044 -157.719604)
			(xy 273.905314 -157.57046) (xy 273.763368 -157.4158) (xy 273.627414 -157.255849) (xy 273.497647 -157.090837)
			(xy 273.374257 -156.921005) (xy 273.257422 -156.746598) (xy 273.147311 -156.56787) (xy 273.044084 -156.385079)
			(xy 272.947891 -156.198491) (xy 272.858872 -156.008376) (xy 272.777154 -155.81501) (xy 272.702858 -155.618673)
			(xy 272.63609 -155.41965) (xy 272.576948 -155.218229) (xy 272.525516 -155.014703) (xy 272.481871 -154.809366)
			(xy 272.446074 -154.602516) (xy 272.418178 -154.394454) (xy 272.398224 -154.18548) (xy 272.386239 -153.975898)
			(xy 272.382243 -153.766012) (xy 199.467428 -153.766012) (xy 199.46747 -153.774902) (xy 199.46697 -153.879864)
			(xy 199.458978 -154.089636) (xy 199.443006 -154.298952) (xy 199.419076 -154.507508) (xy 199.387224 -154.715001)
			(xy 199.347496 -154.921132) (xy 199.299949 -155.125601) (xy 199.244652 -155.328111) (xy 199.181685 -155.528369)
			(xy 199.11114 -155.726085) (xy 199.033119 -155.920972) (xy 198.947735 -156.112747) (xy 198.855112 -156.301133)
			(xy 198.755385 -156.485856) (xy 198.648697 -156.666648) (xy 198.535203 -156.843248) (xy 198.415068 -157.015398)
			(xy 198.288467 -157.182851) (xy 198.155582 -157.345362) (xy 198.016607 -157.502696) (xy 197.871743 -157.654625)
			(xy 197.7212 -157.800929) (xy 197.565196 -157.941396) (xy 197.403957 -158.075822) (xy 197.237717 -158.204011)
			(xy 197.066718 -158.325779) (xy 196.891207 -158.440949) (xy 196.711439 -158.549353) (xy 196.527674 -158.650835)
			(xy 196.340178 -158.745247) (xy 196.149225 -158.832453) (xy 195.955089 -158.912326) (xy 195.758054 -158.98475)
			(xy 195.558404 -159.04962) (xy 195.356429 -159.106842) (xy 195.152423 -159.156334) (xy 194.946679 -159.198023)
			(xy 194.739498 -159.231848) (xy 194.53118 -159.257762) (xy 194.322026 -159.275727) (xy 194.112339 -159.285715)
			(xy 193.902425 -159.287714) (xy 193.692586 -159.281719) (xy 193.483128 -159.26774) (xy 193.274353 -159.245797)
			(xy 193.066566 -159.215922) (xy 192.860067 -159.178157) (xy 192.655154 -159.132559) (xy 192.452127 -159.079192)
			(xy 192.251278 -159.018135) (xy 192.0529 -158.949476) (xy 191.857279 -158.873313) (xy 191.664699 -158.789759)
			(xy 191.475441 -158.698934) (xy 191.289777 -158.600969) (xy 191.107977 -158.496007) (xy 190.930305 -158.3842)
			(xy 190.757019 -158.265709) (xy 190.588369 -158.140708) (xy 190.4246 -158.009376) (xy 190.26595 -157.871905)
			(xy 190.112648 -157.728494) (xy 189.964918 -157.57935) (xy 189.822972 -157.42469) (xy 189.687018 -157.264739)
			(xy 189.557251 -157.099727) (xy 189.433861 -156.929895) (xy 189.317026 -156.755488) (xy 189.206915 -156.57676)
			(xy 189.103688 -156.393969) (xy 189.007495 -156.207381) (xy 188.918476 -156.017266) (xy 188.836758 -155.8239)
			(xy 188.762462 -155.627563) (xy 188.695694 -155.42854) (xy 188.636552 -155.227119) (xy 188.58512 -155.023593)
			(xy 188.541475 -154.818256) (xy 188.505678 -154.611406) (xy 188.477782 -154.403344) (xy 188.457828 -154.19437)
			(xy 188.445843 -153.984788) (xy 188.441847 -153.774902) (xy 132.165372 -153.774902) (xy 132.17401 -153.779355)
			(xy 132.244575 -153.824704) (xy 132.31051 -153.876555) (xy 132.371218 -153.934439) (xy 132.426149 -153.997832)
			(xy 132.474805 -154.066159) (xy 132.516746 -154.138802) (xy 132.551591 -154.215103) (xy 132.579026 -154.29437)
			(xy 132.598802 -154.375887) (xy 132.61074 -154.458914) (xy 132.614731 -154.5427) (xy 132.61074 -154.626486)
			(xy 132.598802 -154.709513) (xy 132.579026 -154.79103) (xy 132.551591 -154.870297) (xy 132.516746 -154.946598)
			(xy 132.474805 -155.019241) (xy 132.426149 -155.087568) (xy 132.371218 -155.150961) (xy 132.31051 -155.208845)
			(xy 132.244575 -155.260696) (xy 132.17401 -155.306045) (xy 132.099453 -155.344481) (xy 132.02158 -155.375656)
			(xy 131.941097 -155.399287) (xy 131.858732 -155.415161) (xy 131.77523 -155.423133) (xy 131.73329 -155.423616)
			(xy 131.6961 -155.423229) (xy 131.621987 -155.416939) (xy 131.548668 -155.404428) (xy 131.476662 -155.385787)
			(xy 131.441444 -155.373832) (xy 131.433247 -155.371318) (xy 131.416113 -155.371318) (xy 131.407916 -155.373832)
			(xy 131.374578 -155.385154) (xy 131.306486 -155.403082) (xy 131.237181 -155.41552) (xy 131.202176 -155.419298)
			(xy 131.192163 -155.420682) (xy 131.174401 -155.43031) (xy 131.161723 -155.446041) (xy 131.158488 -155.45562)
			(xy 131.151035 -155.480306) (xy 131.133624 -155.528851) (xy 131.12369 -155.552648) (xy 131.120082 -155.562222)
			(xy 131.119936 -155.58266) (xy 131.123436 -155.592272) (xy 131.140471 -155.633645) (xy 131.167086 -155.719073)
			(xy 131.184987 -155.806743) (xy 131.193992 -155.895767) (xy 131.194556 -155.940506) (xy 131.194556 -155.94076)
			(xy 131.194052 -155.983108) (xy 131.186001 -156.067422) (xy 131.169972 -156.150588) (xy 131.146111 -156.231855)
			(xy 131.114632 -156.310485) (xy 131.075821 -156.385766) (xy 131.030031 -156.457018) (xy 130.977675 -156.523594)
			(xy 130.919227 -156.584892) (xy 130.855217 -156.640357) (xy 130.786225 -156.689486) (xy 130.712875 -156.731835)
			(xy 130.635832 -156.767019) (xy 130.555793 -156.794721) (xy 130.473484 -156.814689) (xy 130.389649 -156.826742)
			(xy 130.305048 -156.830773) (xy 130.220447 -156.826742) (xy 130.136612 -156.814689) (xy 130.054303 -156.794721)
			(xy 129.974264 -156.767019) (xy 129.897221 -156.731835) (xy 129.823871 -156.689486) (xy 129.754879 -156.640357)
			(xy 129.690869 -156.584892) (xy 129.632421 -156.523594) (xy 129.580065 -156.457018) (xy 129.534275 -156.385766)
			(xy 129.495464 -156.310485) (xy 129.463985 -156.231855) (xy 129.440124 -156.150588) (xy 129.424095 -156.067422)
			(xy 129.416044 -155.983108) (xy 129.41554 -155.94076) (xy 129.41554 -155.940506) (xy 129.416091 -155.895767)
			(xy 129.425111 -155.806745) (xy 129.443021 -155.719078) (xy 129.46964 -155.633651) (xy 129.48666 -155.592272)
			(xy 129.490247 -155.582688) (xy 129.490232 -155.562239) (xy 129.48666 -155.552648) (xy 129.471663 -155.516314)
			(xy 129.447353 -155.441557) (xy 129.429731 -155.364948) (xy 129.418932 -155.287083) (xy 129.416556 -155.247848)
			(xy 129.415794 -155.233878) (xy 129.400046 -155.21051) (xy 129.29235 -155.160472) (xy 129.264664 -155.16352)
			(xy 129.253234 -155.172156) (xy 129.220015 -155.196974) (xy 129.149739 -155.241) (xy 129.075668 -155.27829)
			(xy 128.998447 -155.308521) (xy 128.918747 -155.33143) (xy 128.83726 -155.346818) (xy 128.754694 -155.354552)
			(xy 128.71323 -155.355036) (xy 128.672115 -155.354573) (xy 128.590235 -155.346988) (xy 128.509404 -155.33188)
			(xy 128.430313 -155.309379) (xy 128.353635 -155.279675) (xy 128.280025 -155.243023) (xy 128.210111 -155.199735)
			(xy 128.144489 -155.150181) (xy 128.08372 -155.094783) (xy 128.028322 -155.034014) (xy 127.978767 -154.968393)
			(xy 127.935479 -154.898479) (xy 127.898826 -154.824869) (xy 127.869122 -154.748191) (xy 127.84662 -154.669099)
			(xy 127.831512 -154.588269) (xy 127.823927 -154.506389) (xy 127.823468 -154.465274) (xy 35.422918 -154.465274)
			(xy 35.41915 -154.49811) (xy 35.387298 -154.705603) (xy 35.34757 -154.911734) (xy 35.300023 -155.116203)
			(xy 35.244726 -155.318713) (xy 35.181759 -155.518971) (xy 35.111214 -155.716687) (xy 35.033193 -155.911574)
			(xy 34.947809 -156.103349) (xy 34.855186 -156.291735) (xy 34.755459 -156.476458) (xy 34.648771 -156.65725)
			(xy 34.535277 -156.83385) (xy 34.415142 -157.006) (xy 34.288541 -157.173453) (xy 34.155656 -157.335964)
			(xy 34.016681 -157.493298) (xy 33.871817 -157.645227) (xy 33.721274 -157.791531) (xy 33.56527 -157.931998)
			(xy 33.404031 -158.066424) (xy 33.237791 -158.194613) (xy 33.066792 -158.316381) (xy 32.891281 -158.431551)
			(xy 32.711513 -158.539955) (xy 32.527748 -158.641437) (xy 32.340252 -158.735849) (xy 32.149299 -158.823055)
			(xy 31.955163 -158.902928) (xy 31.758128 -158.975352) (xy 31.558478 -159.040222) (xy 31.356503 -159.097444)
			(xy 31.152497 -159.146936) (xy 30.946753 -159.188625) (xy 30.739572 -159.22245) (xy 30.531254 -159.248364)
			(xy 30.3221 -159.266329) (xy 30.112413 -159.276317) (xy 29.902499 -159.278316) (xy 29.69266 -159.272321)
			(xy 29.483202 -159.258342) (xy 29.274427 -159.236399) (xy 29.06664 -159.206524) (xy 28.860141 -159.168759)
			(xy 28.655228 -159.123161) (xy 28.452201 -159.069794) (xy 28.251352 -159.008737) (xy 28.052974 -158.940078)
			(xy 27.857353 -158.863915) (xy 27.664773 -158.780361) (xy 27.475515 -158.689536) (xy 27.289851 -158.591571)
			(xy 27.108051 -158.486609) (xy 26.930379 -158.374802) (xy 26.757093 -158.256311) (xy 26.588443 -158.13131)
			(xy 26.424674 -157.999978) (xy 26.266024 -157.862507) (xy 26.112722 -157.719096) (xy 25.964992 -157.569952)
			(xy 25.823046 -157.415292) (xy 25.687092 -157.255341) (xy 25.557325 -157.090329) (xy 25.433935 -156.920497)
			(xy 25.3171 -156.74609) (xy 25.206989 -156.567362) (xy 25.103762 -156.384571) (xy 25.007569 -156.197983)
			(xy 24.91855 -156.007868) (xy 24.836832 -155.814502) (xy 24.762536 -155.618165) (xy 24.695768 -155.419142)
			(xy 24.636626 -155.217721) (xy 24.585194 -155.014195) (xy 24.541549 -154.808858) (xy 24.505752 -154.602008)
			(xy 24.477856 -154.393946) (xy 24.457902 -154.184972) (xy 24.445917 -153.97539) (xy 24.441921 -153.765504)
			(xy 2.509012 -153.765504) (xy 2.509012 -164.097716) (xy 86.129368 -164.097716) (xy 86.129877 -164.05494)
			(xy 86.138089 -163.969783) (xy 86.154448 -163.88581) (xy 86.178803 -163.803797) (xy 86.194392 -163.76396)
			(xy 86.19746 -163.755511) (xy 86.19811 -163.737557) (xy 86.195662 -163.728908) (xy 86.181097 -163.683434)
			(xy 86.160666 -163.590154) (xy 86.150355 -163.495221) (xy 86.149688 -163.447476) (xy 86.150084 -163.409186)
			(xy 86.156694 -163.332892) (xy 86.169846 -163.257449) (xy 86.189443 -163.183419) (xy 86.202012 -163.147248)
			(xy 86.204676 -163.138815) (xy 86.204669 -163.121141) (xy 86.202012 -163.112704) (xy 86.18946 -163.076529)
			(xy 86.169889 -163.002495) (xy 86.156744 -162.927055) (xy 86.150122 -162.850764) (xy 86.149688 -162.812476)
			(xy 86.15013 -162.771365) (xy 86.157719 -162.689494) (xy 86.172832 -162.608673) (xy 86.195339 -162.529592)
			(xy 86.225048 -162.452925) (xy 86.261705 -162.379327) (xy 86.304997 -162.309425) (xy 86.354555 -162.243817)
			(xy 86.409957 -162.183063) (xy 86.470728 -162.12768) (xy 86.536351 -162.078142) (xy 86.606266 -162.034871)
			(xy 86.679876 -161.998237) (xy 86.756552 -161.968552) (xy 86.83564 -161.94607) (xy 86.916466 -161.930982)
			(xy 86.998339 -161.923417) (xy 87.03945 -161.922968) (xy 87.077766 -161.923352) (xy 87.154119 -161.92988)
			(xy 87.229626 -161.94296) (xy 87.303725 -161.962495) (xy 87.339932 -161.975038) (xy 87.348248 -161.977624)
			(xy 87.365652 -161.977624) (xy 87.373968 -161.975038) (xy 87.410177 -161.962503) (xy 87.484279 -161.942985)
			(xy 87.559785 -161.929905) (xy 87.636135 -161.92336) (xy 87.67445 -161.922968) (xy 87.712766 -161.923352)
			(xy 87.789119 -161.92988) (xy 87.864626 -161.94296) (xy 87.938725 -161.962495) (xy 87.974932 -161.975038)
			(xy 87.983248 -161.977624) (xy 88.000652 -161.977624) (xy 88.008968 -161.975038) (xy 88.045177 -161.962503)
			(xy 88.119279 -161.942985) (xy 88.194785 -161.929905) (xy 88.271135 -161.92336) (xy 88.30945 -161.922968)
			(xy 88.347766 -161.923352) (xy 88.424119 -161.92988) (xy 88.499626 -161.94296) (xy 88.573725 -161.962495)
			(xy 88.609932 -161.975038) (xy 88.618248 -161.977624) (xy 88.635652 -161.977624) (xy 88.643968 -161.975038)
			(xy 88.680177 -161.962503) (xy 88.754279 -161.942985) (xy 88.829785 -161.929905) (xy 88.906135 -161.92336)
			(xy 88.94445 -161.922968) (xy 88.982766 -161.923352) (xy 89.059119 -161.92988) (xy 89.134626 -161.94296)
			(xy 89.208725 -161.962495) (xy 89.244932 -161.975038) (xy 89.253248 -161.977624) (xy 89.270652 -161.977624)
			(xy 89.278968 -161.975038) (xy 89.315177 -161.962503) (xy 89.389279 -161.942985) (xy 89.464785 -161.929905)
			(xy 89.541135 -161.92336) (xy 89.57945 -161.922968) (xy 89.62106 -161.923438) (xy 89.703917 -161.931201)
			(xy 89.785687 -161.946663) (xy 89.865658 -161.96969) (xy 89.90457 -161.984436) (xy 89.913248 -161.987466)
			(xy 89.931617 -161.98771) (xy 89.940384 -161.984944) (xy 89.976385 -161.972506) (xy 90.050053 -161.953122)
			(xy 90.125108 -161.940106) (xy 90.201001 -161.933552) (xy 90.239088 -161.933128) (xy 90.23985 -161.933128)
			(xy 90.280956 -161.93366) (xy 90.362817 -161.94124) (xy 90.443629 -161.956339) (xy 90.522705 -161.97883)
			(xy 90.599368 -162.008519) (xy 90.672965 -162.045155) (xy 90.742868 -162.088423) (xy 90.808482 -162.137957)
			(xy 90.869246 -162.193332) (xy 90.924643 -162.254076) (xy 90.974199 -162.319673) (xy 91.017492 -162.389561)
			(xy 91.054154 -162.463145) (xy 91.08387 -162.539798) (xy 91.106389 -162.618865) (xy 91.121517 -162.699672)
			(xy 91.129125 -162.781531) (xy 91.129612 -162.822636) (xy 91.12919 -162.860925) (xy 91.122588 -162.937219)
			(xy 91.109443 -163.012662) (xy 91.089854 -163.086693) (xy 91.077288 -163.122864) (xy 91.076082 -163.126674)
			(xy 119.365268 -163.126674) (xy 119.365838 -163.081905) (xy 119.374847 -162.99282) (xy 119.392749 -162.905089)
			(xy 119.419366 -162.819597) (xy 119.436388 -162.778186) (xy 119.43997 -162.7686) (xy 119.43996 -162.748153)
			(xy 119.436388 -162.738562) (xy 119.41934 -162.69716) (xy 119.392709 -162.61167) (xy 119.374808 -162.523935)
			(xy 119.365818 -162.434845) (xy 119.365268 -162.390074) (xy 119.365838 -162.345305) (xy 119.374847 -162.25622)
			(xy 119.392749 -162.168489) (xy 119.419366 -162.082997) (xy 119.436388 -162.041586) (xy 119.43997 -162.032)
			(xy 119.43996 -162.011553) (xy 119.436388 -162.001962) (xy 119.41934 -161.96056) (xy 119.392709 -161.87507)
			(xy 119.374808 -161.787335) (xy 119.365818 -161.698245) (xy 119.365268 -161.653474) (xy 119.365674 -161.612358)
			(xy 119.373264 -161.530476) (xy 119.388376 -161.449645) (xy 119.410882 -161.370552) (xy 119.440591 -161.293873)
			(xy 119.477247 -161.220263) (xy 119.520539 -161.150349) (xy 119.570097 -161.084728) (xy 119.625499 -161.023959)
			(xy 119.686271 -160.968561) (xy 119.751895 -160.919007) (xy 119.821812 -160.87572) (xy 119.895425 -160.839068)
			(xy 119.972105 -160.809365) (xy 120.051199 -160.786863) (xy 120.132032 -160.771756) (xy 120.213914 -160.764171)
			(xy 120.25503 -160.763712) (xy 120.296641 -160.764173) (xy 120.379498 -160.771953) (xy 120.461267 -160.787431)
			(xy 120.541235 -160.810474) (xy 120.618703 -160.840879) (xy 120.692995 -160.878382) (xy 120.728486 -160.90011)
			(xy 120.737629 -160.905263) (xy 120.758342 -160.90848) (xy 120.778614 -160.903152) (xy 120.78716 -160.897062)
			(xy 120.820789 -160.871071) (xy 120.892183 -160.824946) (xy 120.967654 -160.785845) (xy 121.046512 -160.754124)
			(xy 121.128037 -160.730075) (xy 121.211485 -160.713915) (xy 121.296095 -160.705793) (xy 121.338594 -160.705292)
			(xy 121.379707 -160.705819) (xy 121.461582 -160.713405) (xy 121.542407 -160.728513) (xy 121.621494 -160.751013)
			(xy 121.698168 -160.780715) (xy 121.771774 -160.817365) (xy 121.841684 -160.86065) (xy 121.907303 -160.9102)
			(xy 121.96807 -160.965593) (xy 122.023467 -161.026357) (xy 122.073021 -161.091973) (xy 122.11631 -161.161881)
			(xy 122.152964 -161.235485) (xy 122.18267 -161.312156) (xy 122.205176 -161.391242) (xy 122.220288 -161.472067)
			(xy 122.227879 -161.553941) (xy 122.228356 -161.595054) (xy 122.227793 -161.639824) (xy 122.218783 -161.728909)
			(xy 122.200877 -161.81664) (xy 122.174259 -161.902131) (xy 122.157236 -161.943542) (xy 122.153699 -161.953141)
			(xy 122.153682 -161.973576) (xy 122.157236 -161.983166) (xy 122.17424 -162.024517) (xy 122.200851 -162.109879)
			(xy 122.218758 -162.197482) (xy 122.22778 -162.286439) (xy 122.228356 -162.331146) (xy 122.228356 -162.332162)
			(xy 122.228102 -162.343592) (xy 122.254581 -162.349538) (xy 122.306816 -162.364281) (xy 122.332496 -162.373056)
			(xy 122.340693 -162.37557) (xy 122.357827 -162.37557) (xy 122.366024 -162.373056) (xy 122.40124 -162.361095)
			(xy 122.473244 -162.342441) (xy 122.546565 -162.329932) (xy 122.62068 -162.323659) (xy 122.65787 -162.323272)
			(xy 122.695059 -162.323671) (xy 122.769172 -162.329958) (xy 122.842492 -162.342465) (xy 122.914498 -162.361103)
			(xy 122.949716 -162.373056) (xy 122.957913 -162.37557) (xy 122.975047 -162.37557) (xy 122.983244 -162.373056)
			(xy 123.018459 -162.361089) (xy 123.090462 -162.342437) (xy 123.163784 -162.32993) (xy 123.2379 -162.323658)
			(xy 123.27509 -162.323272) (xy 123.31703 -162.323667) (xy 123.400532 -162.331639) (xy 123.482897 -162.347513)
			(xy 123.56338 -162.371144) (xy 123.641253 -162.402319) (xy 123.71581 -162.440755) (xy 123.786375 -162.486104)
			(xy 123.85231 -162.537955) (xy 123.913018 -162.595839) (xy 123.913877 -162.59683) (xy 376.471695 -162.59683)
			(xy 376.4757 -162.491081) (xy 376.48769 -162.385938) (xy 376.507599 -162.282003) (xy 376.53531 -162.179871)
			(xy 376.570667 -162.080127) (xy 376.613465 -161.983343) (xy 376.663461 -161.890073) (xy 376.720368 -161.800852)
			(xy 376.783859 -161.716189) (xy 376.853571 -161.636571) (xy 376.929105 -161.562453) (xy 377.010028 -161.49426)
			(xy 377.095877 -161.432382) (xy 377.18616 -161.377175) (xy 377.280359 -161.328953) (xy 377.377936 -161.287993)
			(xy 377.478331 -161.254531) (xy 377.580969 -161.228757) (xy 377.685262 -161.210819) (xy 377.790613 -161.20082)
			(xy 377.896419 -161.198817) (xy 378.002073 -161.204822) (xy 378.10697 -161.218801) (xy 378.21051 -161.240672)
			(xy 378.312099 -161.270312) (xy 378.411156 -161.30755) (xy 378.507113 -161.352172) (xy 378.59942 -161.403924)
			(xy 378.687549 -161.462509) (xy 378.770995 -161.527591) (xy 378.849279 -161.598797) (xy 378.921954 -161.67572)
			(xy 378.988604 -161.75792) (xy 379.048846 -161.844924) (xy 379.102335 -161.936235) (xy 379.148766 -162.03133)
			(xy 379.187871 -162.129664) (xy 379.219428 -162.230675) (xy 379.243255 -162.333782) (xy 379.259216 -162.438396)
			(xy 379.26722 -162.543918) (xy 379.26772 -162.59683) (xy 379.26722 -162.649742) (xy 379.266995 -162.65271)
			(xy 385.808735 -162.65271) (xy 385.81274 -162.546961) (xy 385.82473 -162.441818) (xy 385.844639 -162.337883)
			(xy 385.87235 -162.235751) (xy 385.907707 -162.136007) (xy 385.950505 -162.039223) (xy 386.000501 -161.945953)
			(xy 386.057408 -161.856732) (xy 386.120899 -161.772069) (xy 386.190611 -161.692451) (xy 386.266145 -161.618333)
			(xy 386.347068 -161.55014) (xy 386.432917 -161.488262) (xy 386.5232 -161.433055) (xy 386.617399 -161.384833)
			(xy 386.714976 -161.343873) (xy 386.815371 -161.310411) (xy 386.918009 -161.284637) (xy 387.022302 -161.266699)
			(xy 387.127653 -161.2567) (xy 387.233459 -161.254697) (xy 387.339113 -161.260702) (xy 387.44401 -161.274681)
			(xy 387.54755 -161.296552) (xy 387.649139 -161.326192) (xy 387.748196 -161.36343) (xy 387.844153 -161.408052)
			(xy 387.93646 -161.459804) (xy 388.024589 -161.518389) (xy 388.108035 -161.583471) (xy 388.186319 -161.654677)
			(xy 388.231017 -161.701988) (xy 409.929076 -161.701988) (xy 409.92965 -161.657219) (xy 409.938657 -161.568134)
			(xy 409.956559 -161.480403) (xy 409.983175 -161.394911) (xy 410.000196 -161.3535) (xy 410.00377 -161.343912)
			(xy 410.003765 -161.323466) (xy 410.000196 -161.313876) (xy 409.983153 -161.272472) (xy 409.956521 -161.186983)
			(xy 409.938618 -161.099248) (xy 409.929627 -161.010159) (xy 409.929076 -160.965388) (xy 409.92965 -160.920619)
			(xy 409.938657 -160.831534) (xy 409.956559 -160.743803) (xy 409.983175 -160.658311) (xy 410.000196 -160.6169)
			(xy 410.00377 -160.607312) (xy 410.003765 -160.586866) (xy 410.000196 -160.577276) (xy 409.983153 -160.535872)
			(xy 409.956521 -160.450383) (xy 409.938618 -160.362648) (xy 409.929627 -160.273559) (xy 409.929076 -160.228788)
			(xy 409.929541 -160.187678) (xy 409.93713 -160.105808) (xy 409.952241 -160.024988) (xy 409.974747 -159.945907)
			(xy 410.004454 -159.869241) (xy 410.041109 -159.795643) (xy 410.0844 -159.725742) (xy 410.133957 -159.660134)
			(xy 410.189357 -159.59938) (xy 410.250127 -159.543997) (xy 410.315748 -159.494459) (xy 410.385662 -159.451187)
			(xy 410.45927 -159.414553) (xy 410.535944 -159.384867) (xy 410.615031 -159.362384) (xy 410.695856 -159.347295)
			(xy 410.777728 -159.339729) (xy 410.818838 -159.33928) (xy 410.860442 -159.339755) (xy 410.94329 -159.347487)
			(xy 411.025054 -159.362917) (xy 411.105022 -159.38591) (xy 411.182495 -159.416266) (xy 411.256796 -159.45372)
			(xy 411.292294 -159.475424) (xy 411.301434 -159.480582) (xy 411.322149 -159.483796) (xy 411.342422 -159.478466)
			(xy 411.350968 -159.472376) (xy 411.384591 -159.44642) (xy 411.45597 -159.400364) (xy 411.531414 -159.361321)
			(xy 411.610235 -159.329647) (xy 411.691716 -159.305629) (xy 411.775116 -159.289486) (xy 411.859674 -159.281366)
			(xy 411.902148 -159.28086) (xy 411.902402 -159.28086) (xy 411.943509 -159.281311) (xy 412.025374 -159.288895)
			(xy 412.106189 -159.304) (xy 412.185267 -159.326496) (xy 412.261931 -159.356191) (xy 412.33553 -159.392831)
			(xy 412.405434 -159.436106) (xy 412.471048 -159.485644) (xy 412.531813 -159.541025) (xy 412.587209 -159.601775)
			(xy 412.636764 -159.667376) (xy 412.680057 -159.737269) (xy 412.716716 -159.810858) (xy 412.746431 -159.887515)
			(xy 412.768947 -159.966587) (xy 412.784073 -160.047398) (xy 412.791679 -160.129261) (xy 412.792164 -160.170368)
			(xy 412.791606 -160.215138) (xy 412.782594 -160.304223) (xy 412.764688 -160.391954) (xy 412.738068 -160.477445)
			(xy 412.721044 -160.518856) (xy 412.717498 -160.528452) (xy 412.717487 -160.548889) (xy 412.721044 -160.55848)
			(xy 412.738053 -160.599829) (xy 412.764663 -160.685192) (xy 412.782568 -160.772795) (xy 412.791589 -160.861753)
			(xy 412.792164 -160.90646) (xy 412.792164 -160.907476) (xy 412.79191 -160.918906) (xy 412.818389 -160.924851)
			(xy 412.870624 -160.939594) (xy 412.896304 -160.94837) (xy 412.904501 -160.950884) (xy 412.921635 -160.950884)
			(xy 412.929832 -160.94837) (xy 412.96505 -160.936429) (xy 413.037059 -160.91784) (xy 413.110382 -160.905398)
			(xy 413.184492 -160.899192) (xy 413.221678 -160.89884) (xy 413.258862 -160.899213) (xy 413.33297 -160.905434)
			(xy 413.40629 -160.917875) (xy 413.478301 -160.936448) (xy 413.513524 -160.94837) (xy 413.521721 -160.950884)
			(xy 413.538855 -160.950884) (xy 413.547052 -160.94837) (xy 413.582146 -160.93646) (xy 413.653906 -160.917916)
			(xy 413.726971 -160.905476) (xy 413.800824 -160.899229) (xy 413.837882 -160.89884) (xy 413.838898 -160.89884)
			(xy 413.880822 -160.899407) (xy 413.964291 -160.907377) (xy 414.046623 -160.923245) (xy 414.127075 -160.946868)
			(xy 414.204917 -160.978031) (xy 414.279444 -161.016452) (xy 414.349982 -161.061784) (xy 414.415891 -161.113615)
			(xy 414.476575 -161.171477) (xy 414.531484 -161.234845) (xy 414.580121 -161.303146) (xy 414.622045 -161.37576)
			(xy 414.656876 -161.452031) (xy 414.684301 -161.531268) (xy 414.704068 -161.612752) (xy 414.716001 -161.695747)
			(xy 414.719991 -161.7795) (xy 414.716001 -161.863253) (xy 414.704068 -161.946248) (xy 414.684301 -162.027732)
			(xy 414.656876 -162.106969) (xy 414.622045 -162.18324) (xy 414.580121 -162.255854) (xy 414.531484 -162.324155)
			(xy 414.476575 -162.387523) (xy 414.415891 -162.445385) (xy 414.349982 -162.497216) (xy 414.279444 -162.542548)
			(xy 414.204917 -162.580969) (xy 414.127075 -162.612132) (xy 414.046623 -162.635755) (xy 413.964291 -162.651623)
			(xy 413.880822 -162.659593) (xy 413.838898 -162.660076) (xy 413.837882 -162.660076) (xy 413.800825 -162.659672)
			(xy 413.726976 -162.653407) (xy 413.653913 -162.640964) (xy 413.582153 -162.622432) (xy 413.547052 -162.610546)
			(xy 413.538855 -162.608032) (xy 413.521721 -162.608032) (xy 413.513524 -162.610546) (xy 413.484638 -162.620383)
			(xy 413.425785 -162.636529) (xy 413.395922 -162.642804) (xy 413.386334 -162.645159) (xy 413.369889 -162.656054)
			(xy 413.358796 -162.672367) (xy 413.356298 -162.68192) (xy 413.34617 -162.726275) (xy 413.318046 -162.812805)
			(xy 413.300164 -162.85464) (xy 413.296347 -162.864579) (xy 413.296353 -162.885846) (xy 413.300164 -162.895788)
			(xy 413.318394 -162.938388) (xy 413.346909 -163.026556) (xy 413.366099 -163.117213) (xy 413.375757 -163.209373)
			(xy 413.376364 -163.255706) (xy 413.376364 -163.256214) (xy 413.37586 -163.298562) (xy 413.367809 -163.382876)
			(xy 413.35178 -163.466042) (xy 413.327919 -163.547309) (xy 413.29644 -163.625939) (xy 413.257629 -163.70122)
			(xy 413.230169 -163.74395) (xy 431.840894 -163.74395) (xy 431.840894 -163.68945) (xy 431.84865 -163.635505)
			(xy 431.864004 -163.583213) (xy 431.886644 -163.533639) (xy 431.916109 -163.48779) (xy 431.951798 -163.446602)
			(xy 431.992986 -163.410912) (xy 432.038833 -163.381447) (xy 432.088408 -163.358807) (xy 432.140699 -163.343452)
			(xy 432.194644 -163.335695) (xy 432.221894 -163.335208) (xy 433.212494 -163.335208) (xy 433.239748 -163.335638)
			(xy 433.293702 -163.343395) (xy 433.346003 -163.358751) (xy 433.395586 -163.381394) (xy 433.441442 -163.410863)
			(xy 433.482637 -163.446559) (xy 433.518333 -163.487753) (xy 433.547803 -163.533609) (xy 433.570447 -163.583191)
			(xy 433.585804 -163.635492) (xy 433.593561 -163.689446) (xy 433.593561 -163.743954) (xy 433.585804 -163.797908)
			(xy 433.570447 -163.850209) (xy 433.547803 -163.899791) (xy 433.518333 -163.945647) (xy 433.482637 -163.986841)
			(xy 433.441442 -164.022537) (xy 433.395586 -164.052006) (xy 433.346003 -164.074649) (xy 433.293702 -164.090005)
			(xy 433.239748 -164.097762) (xy 433.212494 -164.098224) (xy 432.221894 -164.098224) (xy 432.194644 -164.097705)
			(xy 432.140699 -164.089948) (xy 432.088408 -164.074593) (xy 432.038833 -164.051953) (xy 431.992986 -164.022488)
			(xy 431.951798 -163.986798) (xy 431.916109 -163.94561) (xy 431.886644 -163.899761) (xy 431.864004 -163.850187)
			(xy 431.84865 -163.797895) (xy 431.840894 -163.74395) (xy 413.230169 -163.74395) (xy 413.211839 -163.772472)
			(xy 413.159483 -163.839048) (xy 413.101035 -163.900346) (xy 413.037025 -163.955811) (xy 412.968033 -164.00494)
			(xy 412.894683 -164.047289) (xy 412.81764 -164.082473) (xy 412.737601 -164.110175) (xy 412.655292 -164.130143)
			(xy 412.571457 -164.142196) (xy 412.486856 -164.146227) (xy 412.402255 -164.142196) (xy 412.31842 -164.130143)
			(xy 412.236111 -164.110175) (xy 412.156072 -164.082473) (xy 412.079029 -164.047289) (xy 412.005679 -164.00494)
			(xy 411.936687 -163.955811) (xy 411.872677 -163.900346) (xy 411.814229 -163.839048) (xy 411.761873 -163.772472)
			(xy 411.716083 -163.70122) (xy 411.677272 -163.625939) (xy 411.645793 -163.547309) (xy 411.621932 -163.466042)
			(xy 411.605903 -163.382876) (xy 411.597852 -163.298562) (xy 411.597348 -163.256214) (xy 411.597348 -163.255706)
			(xy 411.597963 -163.209374) (xy 411.607632 -163.117217) (xy 411.626825 -163.026563) (xy 411.655334 -162.938394)
			(xy 411.673548 -162.895788) (xy 411.677348 -162.885844) (xy 411.677353 -162.864582) (xy 411.673548 -162.85464)
			(xy 411.655311 -162.811974) (xy 411.626764 -162.723684) (xy 411.607569 -162.632899) (xy 411.597934 -162.54061)
			(xy 411.597348 -162.494214) (xy 411.597953 -162.446404) (xy 411.608131 -162.351329) (xy 411.617668 -162.304476)
			(xy 411.61964 -162.292071) (xy 411.612727 -162.267957) (xy 411.60446 -162.258502) (xy 411.56382 -162.216338)
			(xy 411.560264 -162.2171) (xy 411.551416 -162.219411) (xy 411.536053 -162.229303) (xy 411.530292 -162.236404)
			(xy 411.505137 -162.269067) (xy 411.449717 -162.33011) (xy 411.388886 -162.385763) (xy 411.323166 -162.435548)
			(xy 411.253121 -162.479037) (xy 411.179352 -162.515858) (xy 411.102492 -162.545694) (xy 411.023201 -162.56829)
			(xy 410.942159 -162.583451) (xy 410.860062 -162.591047) (xy 410.818838 -162.591496) (xy 410.777733 -162.590951)
			(xy 410.695873 -162.583371) (xy 410.615061 -162.568271) (xy 410.535987 -162.54578) (xy 410.459325 -162.516091)
			(xy 410.385729 -162.479456) (xy 410.315826 -162.436187) (xy 410.250213 -162.386655) (xy 410.18945 -162.331281)
			(xy 410.134053 -162.270538) (xy 410.084497 -162.204943) (xy 410.041203 -162.135056) (xy 410.004541 -162.061473)
			(xy 409.974824 -161.984822) (xy 409.952304 -161.905756) (xy 409.937174 -161.82495) (xy 409.929564 -161.743093)
			(xy 409.929076 -161.701988) (xy 388.231017 -161.701988) (xy 388.258994 -161.7316) (xy 388.325644 -161.8138)
			(xy 388.385886 -161.900804) (xy 388.439375 -161.992115) (xy 388.485806 -162.08721) (xy 388.524911 -162.185544)
			(xy 388.556468 -162.286555) (xy 388.580295 -162.389662) (xy 388.596256 -162.494276) (xy 388.60426 -162.599798)
			(xy 388.60476 -162.65271) (xy 388.60426 -162.705622) (xy 388.596256 -162.811144) (xy 388.580295 -162.915758)
			(xy 388.556468 -163.018865) (xy 388.524911 -163.119876) (xy 388.485806 -163.21821) (xy 388.439375 -163.313305)
			(xy 388.385886 -163.404616) (xy 388.325644 -163.49162) (xy 388.258994 -163.57382) (xy 388.186319 -163.650743)
			(xy 388.108035 -163.721949) (xy 388.024589 -163.787031) (xy 387.93646 -163.845616) (xy 387.844153 -163.897368)
			(xy 387.748196 -163.94199) (xy 387.649139 -163.979228) (xy 387.54755 -164.008868) (xy 387.44401 -164.030739)
			(xy 387.339113 -164.044718) (xy 387.233459 -164.050723) (xy 387.127653 -164.04872) (xy 387.022302 -164.038721)
			(xy 386.918009 -164.020783) (xy 386.815371 -163.995009) (xy 386.714976 -163.961547) (xy 386.617399 -163.920587)
			(xy 386.5232 -163.872365) (xy 386.432917 -163.817158) (xy 386.347068 -163.75528) (xy 386.266145 -163.687087)
			(xy 386.190611 -163.612969) (xy 386.120899 -163.533351) (xy 386.057408 -163.448688) (xy 386.000501 -163.359467)
			(xy 385.950505 -163.266197) (xy 385.907707 -163.169413) (xy 385.87235 -163.069669) (xy 385.844639 -162.967537)
			(xy 385.82473 -162.863602) (xy 385.81274 -162.758459) (xy 385.808735 -162.65271) (xy 379.266995 -162.65271)
			(xy 379.259216 -162.755264) (xy 379.243255 -162.859878) (xy 379.219428 -162.962985) (xy 379.187871 -163.063996)
			(xy 379.148766 -163.16233) (xy 379.102335 -163.257425) (xy 379.048846 -163.348736) (xy 378.988604 -163.43574)
			(xy 378.921954 -163.51794) (xy 378.849279 -163.594863) (xy 378.770995 -163.666069) (xy 378.687549 -163.731151)
			(xy 378.59942 -163.789736) (xy 378.507113 -163.841488) (xy 378.411156 -163.88611) (xy 378.312099 -163.923348)
			(xy 378.21051 -163.952988) (xy 378.10697 -163.974859) (xy 378.002073 -163.988838) (xy 377.896419 -163.994843)
			(xy 377.790613 -163.99284) (xy 377.685262 -163.982841) (xy 377.580969 -163.964903) (xy 377.478331 -163.939129)
			(xy 377.377936 -163.905667) (xy 377.280359 -163.864707) (xy 377.18616 -163.816485) (xy 377.095877 -163.761278)
			(xy 377.010028 -163.6994) (xy 376.929105 -163.631207) (xy 376.853571 -163.557089) (xy 376.783859 -163.477471)
			(xy 376.720368 -163.392808) (xy 376.663461 -163.303587) (xy 376.613465 -163.210317) (xy 376.570667 -163.113533)
			(xy 376.53531 -163.013789) (xy 376.507599 -162.911657) (xy 376.48769 -162.807722) (xy 376.4757 -162.702579)
			(xy 376.471695 -162.59683) (xy 123.913877 -162.59683) (xy 123.967949 -162.659232) (xy 124.016605 -162.727559)
			(xy 124.058546 -162.800202) (xy 124.093391 -162.876503) (xy 124.120826 -162.95577) (xy 124.140602 -163.037287)
			(xy 124.15254 -163.120314) (xy 124.156531 -163.2041) (xy 124.15254 -163.287886) (xy 124.140602 -163.370913)
			(xy 124.120826 -163.45243) (xy 124.093391 -163.531697) (xy 124.058546 -163.607998) (xy 124.016605 -163.680641)
			(xy 123.967949 -163.748968) (xy 123.913018 -163.812361) (xy 123.85231 -163.870245) (xy 123.786375 -163.922096)
			(xy 123.71581 -163.967445) (xy 123.641253 -164.005881) (xy 123.56338 -164.037056) (xy 123.482897 -164.060687)
			(xy 123.400532 -164.076561) (xy 123.31703 -164.084533) (xy 123.27509 -164.085016) (xy 123.2379 -164.084629)
			(xy 123.163787 -164.078339) (xy 123.090468 -164.065828) (xy 123.018462 -164.047187) (xy 122.983244 -164.035232)
			(xy 122.975047 -164.032718) (xy 122.957913 -164.032718) (xy 122.949716 -164.035232) (xy 122.907233 -164.049509)
			(xy 122.820068 -164.070379) (xy 122.775726 -164.076888) (xy 122.765804 -164.078672) (xy 122.748385 -164.088778)
			(xy 122.736231 -164.104835) (xy 122.733308 -164.11448) (xy 122.724748 -164.14638) (xy 122.70352 -164.20893)
			(xy 122.69089 -164.239448) (xy 122.687282 -164.249022) (xy 122.687136 -164.26946) (xy 122.690636 -164.279072)
			(xy 122.707671 -164.320445) (xy 122.734286 -164.405873) (xy 122.752187 -164.493543) (xy 122.756237 -164.53358)
			(xy 365.854996 -164.53358) (xy 365.855358 -164.495263) (xy 365.861892 -164.41891) (xy 365.874978 -164.343403)
			(xy 365.89452 -164.269304) (xy 365.907066 -164.233098) (xy 365.909662 -164.224784) (xy 365.909655 -164.207378)
			(xy 365.907066 -164.199062) (xy 365.894569 -164.162941) (xy 365.875081 -164.089028) (xy 365.861998 -164.013717)
			(xy 365.855418 -163.937561) (xy 365.854996 -163.899342) (xy 365.854996 -163.89858) (xy 365.855448 -163.857477)
			(xy 365.863034 -163.775622) (xy 365.878141 -163.694816) (xy 365.900639 -163.615749) (xy 365.930337 -163.539095)
			(xy 365.966981 -163.465508) (xy 366.010258 -163.395615) (xy 366.059799 -163.330014) (xy 366.115181 -163.269264)
			(xy 366.175933 -163.213883) (xy 366.241535 -163.164344) (xy 366.311429 -163.121069) (xy 366.385017 -163.084427)
			(xy 366.461672 -163.054732) (xy 366.54074 -163.032236) (xy 366.621546 -163.017131) (xy 366.703401 -163.009546)
			(xy 366.744504 -163.009072) (xy 366.745266 -163.009072) (xy 366.783487 -163.009474) (xy 366.859645 -163.01604)
			(xy 366.934958 -163.029126) (xy 367.008868 -163.048635) (xy 367.044986 -163.061142) (xy 367.053302 -163.063728)
			(xy 367.070706 -163.063728) (xy 367.079022 -163.061142) (xy 367.115235 -163.04862) (xy 367.189336 -163.029098)
			(xy 367.26484 -163.016015) (xy 367.341189 -163.009466) (xy 367.379504 -163.009072) (xy 367.419718 -163.009498)
			(xy 367.49982 -163.016721) (xy 367.578942 -163.031153) (xy 367.656435 -163.052677) (xy 367.69421 -163.066476)
			(xy 367.702997 -163.069383) (xy 367.721491 -163.069383) (xy 367.730278 -163.066476) (xy 367.768054 -163.052684)
			(xy 367.845551 -163.031177) (xy 367.924672 -163.016746) (xy 368.004771 -163.00951) (xy 368.044984 -163.009072)
			(xy 368.0833 -163.009446) (xy 368.159653 -163.015977) (xy 368.23516 -163.029059) (xy 368.309259 -163.048598)
			(xy 368.345466 -163.061142) (xy 368.353782 -163.063728) (xy 368.371186 -163.063728) (xy 368.379502 -163.061142)
			(xy 368.415717 -163.048626) (xy 368.489817 -163.029103) (xy 368.565321 -163.016017) (xy 368.641669 -163.009467)
			(xy 368.679984 -163.009072) (xy 368.7183 -163.009446) (xy 368.794653 -163.015977) (xy 368.87016 -163.029059)
			(xy 368.944259 -163.048598) (xy 368.980466 -163.061142) (xy 368.988782 -163.063728) (xy 369.006186 -163.063728)
			(xy 369.014502 -163.061142) (xy 369.050717 -163.048626) (xy 369.124817 -163.029103) (xy 369.200321 -163.016017)
			(xy 369.276669 -163.009467) (xy 369.314984 -163.009072) (xy 369.3533 -163.009446) (xy 369.429653 -163.015977)
			(xy 369.50516 -163.029059) (xy 369.579259 -163.048598) (xy 369.615466 -163.061142) (xy 369.623782 -163.063728)
			(xy 369.641186 -163.063728) (xy 369.649502 -163.061142) (xy 369.685717 -163.048626) (xy 369.759817 -163.029103)
			(xy 369.835321 -163.016017) (xy 369.911669 -163.009467) (xy 369.949984 -163.009072) (xy 369.994754 -163.009635)
			(xy 370.083841 -163.018637) (xy 370.171573 -163.03654) (xy 370.257063 -163.063164) (xy 370.298472 -163.080192)
			(xy 370.308063 -163.083757) (xy 370.328505 -163.083757) (xy 370.338096 -163.080192) (xy 370.379479 -163.063183)
			(xy 370.464904 -163.036561) (xy 370.55257 -163.018653) (xy 370.641592 -163.00964) (xy 370.68633 -163.009072)
			(xy 370.686584 -163.009072) (xy 370.727686 -163.009582) (xy 370.809538 -163.017165) (xy 370.890342 -163.032268)
			(xy 370.969408 -163.054763) (xy 371.046061 -163.084457) (xy 371.119647 -163.121096) (xy 371.189538 -163.16437)
			(xy 371.255139 -163.213907) (xy 371.315889 -163.269286) (xy 371.37127 -163.330033) (xy 371.42081 -163.395632)
			(xy 371.464086 -163.465522) (xy 371.500729 -163.539106) (xy 371.530426 -163.615758) (xy 371.552923 -163.694823)
			(xy 371.56803 -163.775626) (xy 371.575616 -163.857478) (xy 371.576092 -163.89858) (xy 371.576092 -163.899342)
			(xy 371.575679 -163.937562) (xy 371.569116 -164.013721) (xy 371.556033 -164.089033) (xy 371.536527 -164.162943)
			(xy 371.524022 -164.199062) (xy 371.521447 -164.207381) (xy 371.52144 -164.224782) (xy 371.524022 -164.233098)
			(xy 371.536535 -164.269314) (xy 371.55606 -164.343414) (xy 371.569146 -164.418917) (xy 371.575697 -164.495265)
			(xy 371.576092 -164.53358) (xy 371.575734 -164.571323) (xy 371.569392 -164.646543) (xy 371.556692 -164.720953)
			(xy 371.537726 -164.794018) (xy 371.525546 -164.829744) (xy 371.522818 -164.838516) (xy 371.52307 -164.85687)
			(xy 371.526054 -164.865558) (xy 371.541045 -164.904681) (xy 371.564495 -164.985121) (xy 371.58028 -165.067409)
			(xy 371.588259 -165.150817) (xy 371.588792 -165.19271) (xy 371.588792 -165.19398) (xy 371.588329 -165.235083)
			(xy 371.580745 -165.316939) (xy 371.565641 -165.397747) (xy 371.543146 -165.476815) (xy 371.51345 -165.553471)
			(xy 371.476808 -165.62706) (xy 371.433533 -165.696954) (xy 371.383993 -165.762556) (xy 371.328611 -165.823308)
			(xy 371.267859 -165.87869) (xy 371.202257 -165.92823) (xy 371.132363 -165.971506) (xy 371.058775 -166.008149)
			(xy 370.982119 -166.037844) (xy 370.90305 -166.06034) (xy 370.822243 -166.075445) (xy 370.740387 -166.083029)
			(xy 370.699284 -166.083488) (xy 370.69903 -166.083488) (xy 370.654291 -166.082927) (xy 370.56527 -166.07391)
			(xy 370.477602 -166.056003) (xy 370.392175 -166.029387) (xy 370.350796 -166.012368) (xy 370.341205 -166.008803)
			(xy 370.320763 -166.008803) (xy 370.311172 -166.012368) (xy 370.269762 -166.029396) (xy 370.184274 -166.056029)
			(xy 370.096542 -166.073935) (xy 370.007454 -166.082933) (xy 369.962684 -166.083488) (xy 369.924367 -166.083126)
			(xy 369.848014 -166.076592) (xy 369.772507 -166.063506) (xy 369.698408 -166.043964) (xy 369.662202 -166.031418)
			(xy 369.653886 -166.028832) (xy 369.636482 -166.028832) (xy 369.628166 -166.031418) (xy 369.591953 -166.043941)
			(xy 369.517852 -166.063463) (xy 369.442348 -166.076546) (xy 369.365999 -166.083094) (xy 369.327684 -166.083488)
			(xy 369.289367 -166.083126) (xy 369.213014 -166.076592) (xy 369.137507 -166.063506) (xy 369.063408 -166.043964)
			(xy 369.027202 -166.031418) (xy 369.018886 -166.028832) (xy 369.001482 -166.028832) (xy 368.993166 -166.031418)
			(xy 368.956953 -166.043941) (xy 368.882852 -166.063463) (xy 368.807348 -166.076546) (xy 368.730999 -166.083094)
			(xy 368.692684 -166.083488) (xy 368.654367 -166.083126) (xy 368.578014 -166.076592) (xy 368.502507 -166.063506)
			(xy 368.428408 -166.043964) (xy 368.392202 -166.031418) (xy 368.383886 -166.028832) (xy 368.366482 -166.028832)
			(xy 368.358166 -166.031418) (xy 368.321953 -166.043941) (xy 368.247852 -166.063463) (xy 368.172348 -166.076546)
			(xy 368.095999 -166.083094) (xy 368.057684 -166.083488) (xy 368.01747 -166.083062) (xy 367.937368 -166.075838)
			(xy 367.858246 -166.061406) (xy 367.780753 -166.039883) (xy 367.742978 -166.026084) (xy 367.734191 -166.023177)
			(xy 367.715697 -166.023177) (xy 367.70691 -166.026084) (xy 367.669134 -166.039877) (xy 367.591637 -166.061385)
			(xy 367.512517 -166.075815) (xy 367.432417 -166.083051) (xy 367.392204 -166.083488) (xy 367.353888 -166.08312)
			(xy 367.277534 -166.076588) (xy 367.202027 -166.063503) (xy 367.127928 -166.043963) (xy 367.091722 -166.031418)
			(xy 367.083406 -166.028832) (xy 367.066002 -166.028832) (xy 367.057686 -166.031418) (xy 367.021563 -166.043908)
			(xy 366.947651 -166.063398) (xy 366.87234 -166.076483) (xy 366.796185 -166.083065) (xy 366.757966 -166.083488)
			(xy 366.757204 -166.083488) (xy 366.7161 -166.083044) (xy 366.634244 -166.075459) (xy 366.553436 -166.060354)
			(xy 366.474367 -166.037857) (xy 366.397711 -166.00816) (xy 366.324122 -165.971516) (xy 366.254228 -165.928239)
			(xy 366.188625 -165.878698) (xy 366.127874 -165.823315) (xy 366.072492 -165.762562) (xy 366.022951 -165.696959)
			(xy 365.979676 -165.627064) (xy 365.943034 -165.553475) (xy 365.913338 -165.476818) (xy 365.890843 -165.397748)
			(xy 365.875739 -165.316941) (xy 365.868155 -165.235084) (xy 365.867696 -165.19398) (xy 365.867696 -165.192964)
			(xy 365.868115 -165.155349) (xy 365.874496 -165.080389) (xy 365.887191 -165.006237) (xy 365.906111 -164.933424)
			(xy 365.918242 -164.897816) (xy 365.920992 -164.889049) (xy 365.920727 -164.87069) (xy 365.917734 -164.862002)
			(xy 365.902679 -164.822733) (xy 365.879172 -164.741978) (xy 365.863391 -164.659366) (xy 365.855475 -164.575633)
			(xy 365.854996 -164.53358) (xy 122.756237 -164.53358) (xy 122.761192 -164.582567) (xy 122.761756 -164.627306)
			(xy 122.761756 -164.62756) (xy 122.761252 -164.669908) (xy 122.753201 -164.754222) (xy 122.737172 -164.837388)
			(xy 122.713311 -164.918655) (xy 122.681832 -164.997285) (xy 122.643021 -165.072566) (xy 122.597231 -165.143818)
			(xy 122.544875 -165.210394) (xy 122.486427 -165.271692) (xy 122.422417 -165.327157) (xy 122.353425 -165.376286)
			(xy 122.280075 -165.418635) (xy 122.203032 -165.453819) (xy 122.122993 -165.481521) (xy 122.040684 -165.501489)
			(xy 121.956849 -165.513542) (xy 121.872248 -165.517573) (xy 121.787647 -165.513542) (xy 121.703812 -165.501489)
			(xy 121.621503 -165.481521) (xy 121.541464 -165.453819) (xy 121.464421 -165.418635) (xy 121.391071 -165.376286)
			(xy 121.322079 -165.327157) (xy 121.258069 -165.271692) (xy 121.199621 -165.210394) (xy 121.147265 -165.143818)
			(xy 121.101475 -165.072566) (xy 121.062664 -164.997285) (xy 121.031185 -164.918655) (xy 121.007324 -164.837388)
			(xy 120.991295 -164.754222) (xy 120.983244 -164.669908) (xy 120.98274 -164.62756) (xy 120.98274 -164.627306)
			(xy 120.983291 -164.582567) (xy 120.992311 -164.493545) (xy 121.010221 -164.405878) (xy 121.03684 -164.320451)
			(xy 121.05386 -164.279072) (xy 121.057447 -164.269488) (xy 121.057432 -164.249039) (xy 121.05386 -164.239448)
			(xy 121.037012 -164.19848) (xy 121.010567 -164.113931) (xy 120.992664 -164.027171) (xy 120.983478 -163.939061)
			(xy 120.98274 -163.89477) (xy 120.982373 -163.885212) (xy 120.975335 -163.867438) (xy 120.962255 -163.853496)
			(xy 120.953784 -163.84905) (xy 120.870726 -163.809934) (xy 120.861899 -163.806187) (xy 120.842781 -163.804911)
			(xy 120.824539 -163.810771) (xy 120.816878 -163.816538) (xy 120.782853 -163.843559) (xy 120.710459 -163.891613)
			(xy 120.633724 -163.93238) (xy 120.55338 -163.965469) (xy 120.470192 -163.990568) (xy 120.384953 -164.007435)
			(xy 120.298476 -164.01591) (xy 120.25503 -164.016436) (xy 120.213915 -164.015973) (xy 120.132035 -164.008388)
			(xy 120.051204 -163.99328) (xy 119.972113 -163.970779) (xy 119.895435 -163.941075) (xy 119.821825 -163.904423)
			(xy 119.751911 -163.861135) (xy 119.686289 -163.811581) (xy 119.62552 -163.756183) (xy 119.570122 -163.695414)
			(xy 119.520567 -163.629793) (xy 119.477279 -163.559879) (xy 119.440626 -163.486269) (xy 119.410922 -163.409591)
			(xy 119.38842 -163.330499) (xy 119.373312 -163.249669) (xy 119.365727 -163.167789) (xy 119.365268 -163.126674)
			(xy 91.076082 -163.126674) (xy 91.074618 -163.131296) (xy 91.074629 -163.148971) (xy 91.077288 -163.157408)
			(xy 91.089816 -163.193591) (xy 91.109393 -163.267622) (xy 91.122545 -163.34306) (xy 91.129174 -163.419348)
			(xy 91.129612 -163.457636) (xy 91.129114 -163.500412) (xy 91.120898 -163.585569) (xy 91.104536 -163.669543)
			(xy 91.080178 -163.751555) (xy 91.064588 -163.791392) (xy 91.061544 -163.799848) (xy 91.060879 -163.817795)
			(xy 91.063318 -163.826444) (xy 91.07787 -163.871922) (xy 91.098306 -163.9652) (xy 91.108623 -164.060131)
			(xy 91.109292 -164.107876) (xy 91.108825 -164.148987) (xy 91.101239 -164.230857) (xy 91.08613 -164.311679)
			(xy 91.063626 -164.390761) (xy 91.033921 -164.467428) (xy 90.997266 -164.541027) (xy 90.953976 -164.610929)
			(xy 90.904419 -164.676538) (xy 90.849019 -164.737293) (xy 90.788249 -164.792677) (xy 90.722626 -164.842215)
			(xy 90.652712 -164.885486) (xy 90.579103 -164.92212) (xy 90.502427 -164.951804) (xy 90.423339 -164.974286)
			(xy 90.342514 -164.989373) (xy 90.260641 -164.996936) (xy 90.21953 -164.997384) (xy 90.177921 -164.996892)
			(xy 90.095064 -164.989136) (xy 90.013294 -164.97368) (xy 89.933323 -164.950659) (xy 89.89441 -164.935916)
			(xy 89.88572 -164.932926) (xy 89.867362 -164.932654) (xy 89.858596 -164.935408) (xy 89.822497 -164.947854)
			(xy 89.748643 -164.967275) (xy 89.673397 -164.980297) (xy 89.597312 -164.986825) (xy 89.55913 -164.987224)
			(xy 89.520814 -164.986846) (xy 89.444461 -164.980317) (xy 89.368954 -164.967235) (xy 89.294855 -164.947698)
			(xy 89.258648 -164.935154) (xy 89.250332 -164.932568) (xy 89.232928 -164.932568) (xy 89.224612 -164.935154)
			(xy 89.188396 -164.947666) (xy 89.114296 -164.96719) (xy 89.038793 -164.980277) (xy 88.962445 -164.986828)
			(xy 88.92413 -164.987224) (xy 88.885814 -164.986846) (xy 88.809461 -164.980317) (xy 88.733954 -164.967235)
			(xy 88.659855 -164.947698) (xy 88.623648 -164.935154) (xy 88.615332 -164.932568) (xy 88.597928 -164.932568)
			(xy 88.589612 -164.935154) (xy 88.553396 -164.947666) (xy 88.479296 -164.96719) (xy 88.403793 -164.980277)
			(xy 88.327445 -164.986828) (xy 88.28913 -164.987224) (xy 88.250814 -164.986846) (xy 88.174461 -164.980317)
			(xy 88.098954 -164.967235) (xy 88.024855 -164.947698) (xy 87.988648 -164.935154) (xy 87.980332 -164.932568)
			(xy 87.962928 -164.932568) (xy 87.954612 -164.935154) (xy 87.918396 -164.947666) (xy 87.844296 -164.96719)
			(xy 87.768793 -164.980277) (xy 87.692445 -164.986828) (xy 87.65413 -164.987224) (xy 87.615814 -164.986846)
			(xy 87.539461 -164.980317) (xy 87.463954 -164.967235) (xy 87.389855 -164.947698) (xy 87.353648 -164.935154)
			(xy 87.345332 -164.932568) (xy 87.327928 -164.932568) (xy 87.319612 -164.935154) (xy 87.283487 -164.947638)
			(xy 87.209575 -164.96713) (xy 87.134265 -164.980216) (xy 87.058111 -164.9868) (xy 87.019892 -164.987224)
			(xy 87.01913 -164.987224) (xy 86.978023 -164.986759) (xy 86.896158 -164.979177) (xy 86.815342 -164.964075)
			(xy 86.736265 -164.941581) (xy 86.659599 -164.911888) (xy 86.586 -164.875249) (xy 86.516095 -164.831976)
			(xy 86.45048 -164.782438) (xy 86.389716 -164.727058) (xy 86.334319 -164.666309) (xy 86.284763 -164.600708)
			(xy 86.241471 -164.530815) (xy 86.204811 -164.457226) (xy 86.175097 -164.380569) (xy 86.152582 -164.301497)
			(xy 86.137457 -164.220686) (xy 86.129853 -164.138823) (xy 86.129368 -164.097716) (xy 2.509012 -164.097716)
			(xy 2.509012 -166.86276) (xy 61.046868 -166.86276) (xy 61.047433 -166.81799) (xy 61.056443 -166.728905)
			(xy 61.074347 -166.641174) (xy 61.100966 -166.555683) (xy 61.117988 -166.514272) (xy 61.121578 -166.504688)
			(xy 61.121563 -166.484239) (xy 61.117988 -166.474648) (xy 61.100968 -166.433235) (xy 61.074329 -166.347749)
			(xy 61.05642 -166.260018) (xy 61.047422 -166.17093) (xy 61.046868 -166.12616) (xy 61.047433 -166.08139)
			(xy 61.056443 -165.992305) (xy 61.074347 -165.904574) (xy 61.100966 -165.819083) (xy 61.117988 -165.777672)
			(xy 61.121578 -165.768088) (xy 61.121563 -165.747639) (xy 61.117988 -165.738048) (xy 61.100968 -165.696635)
			(xy 61.074329 -165.611149) (xy 61.05642 -165.523418) (xy 61.047422 -165.43433) (xy 61.046868 -165.38956)
			(xy 61.047314 -165.348449) (xy 61.054905 -165.266579) (xy 61.070019 -165.185759) (xy 61.092527 -165.106679)
			(xy 61.122236 -165.030013) (xy 61.158893 -164.956415) (xy 61.202185 -164.886514) (xy 61.251743 -164.820907)
			(xy 61.307144 -164.760153) (xy 61.367915 -164.70477) (xy 61.433537 -164.655232) (xy 61.503451 -164.611961)
			(xy 61.57706 -164.575327) (xy 61.653735 -164.545641) (xy 61.732822 -164.523157) (xy 61.813647 -164.508068)
			(xy 61.895519 -164.500502) (xy 61.93663 -164.500052) (xy 61.978234 -164.500535) (xy 62.061081 -164.508266)
			(xy 62.142846 -164.523695) (xy 62.222813 -164.546687) (xy 62.300286 -164.577041) (xy 62.374588 -164.614493)
			(xy 62.410086 -164.636196) (xy 62.419228 -164.641351) (xy 62.439942 -164.644569) (xy 62.460215 -164.639239)
			(xy 62.46876 -164.633148) (xy 62.502383 -164.607191) (xy 62.573762 -164.561136) (xy 62.649206 -164.522094)
			(xy 62.728027 -164.49042) (xy 62.809509 -164.466402) (xy 62.892908 -164.450259) (xy 62.977466 -164.442138)
			(xy 63.01994 -164.441632) (xy 63.020194 -164.441632) (xy 63.0613 -164.442118) (xy 63.143163 -164.449702)
			(xy 63.223977 -164.464805) (xy 63.303052 -164.487299) (xy 63.379716 -164.516993) (xy 63.453313 -164.553631)
			(xy 63.523217 -164.596903) (xy 63.58883 -164.64644) (xy 63.649594 -164.701818) (xy 63.70499 -164.762565)
			(xy 63.754546 -164.828164) (xy 63.797839 -164.898054) (xy 63.8345 -164.971641) (xy 63.864216 -165.048295)
			(xy 63.886734 -165.127364) (xy 63.901861 -165.208173) (xy 63.909469 -165.290034) (xy 63.909956 -165.33114)
			(xy 63.909389 -165.375909) (xy 63.900379 -165.464994) (xy 63.882475 -165.552725) (xy 63.855858 -165.638217)
			(xy 63.838836 -165.679628) (xy 63.83525 -165.689212) (xy 63.835264 -165.709661) (xy 63.838836 -165.719252)
			(xy 63.855836 -165.760605) (xy 63.882448 -165.845966) (xy 63.900356 -165.933568) (xy 63.903248 -165.962076)
			(xy 81.591411 -165.962076) (xy 81.595416 -165.856327) (xy 81.607406 -165.751184) (xy 81.627315 -165.647249)
			(xy 81.655026 -165.545117) (xy 81.690383 -165.445373) (xy 81.733181 -165.348589) (xy 81.783177 -165.255319)
			(xy 81.840084 -165.166098) (xy 81.903575 -165.081435) (xy 81.973287 -165.001817) (xy 82.048821 -164.927699)
			(xy 82.129744 -164.859506) (xy 82.215593 -164.797628) (xy 82.305876 -164.742421) (xy 82.400075 -164.694199)
			(xy 82.497652 -164.653239) (xy 82.598047 -164.619777) (xy 82.700685 -164.594003) (xy 82.804978 -164.576065)
			(xy 82.910329 -164.566066) (xy 83.016135 -164.564063) (xy 83.121789 -164.570068) (xy 83.226686 -164.584047)
			(xy 83.330226 -164.605918) (xy 83.431815 -164.635558) (xy 83.530872 -164.672796) (xy 83.626829 -164.717418)
			(xy 83.719136 -164.76917) (xy 83.807265 -164.827755) (xy 83.890711 -164.892837) (xy 83.968995 -164.964043)
			(xy 84.04167 -165.040966) (xy 84.10832 -165.123166) (xy 84.168562 -165.21017) (xy 84.222051 -165.301481)
			(xy 84.268482 -165.396576) (xy 84.307587 -165.49491) (xy 84.339144 -165.595921) (xy 84.362971 -165.699028)
			(xy 84.378932 -165.803642) (xy 84.386936 -165.909164) (xy 84.387436 -165.962076) (xy 90.989411 -165.962076)
			(xy 90.993416 -165.856327) (xy 91.005406 -165.751184) (xy 91.025315 -165.647249) (xy 91.053026 -165.545117)
			(xy 91.088383 -165.445373) (xy 91.131181 -165.348589) (xy 91.181177 -165.255319) (xy 91.238084 -165.166098)
			(xy 91.301575 -165.081435) (xy 91.371287 -165.001817) (xy 91.446821 -164.927699) (xy 91.527744 -164.859506)
			(xy 91.613593 -164.797628) (xy 91.703876 -164.742421) (xy 91.798075 -164.694199) (xy 91.895652 -164.653239)
			(xy 91.996047 -164.619777) (xy 92.098685 -164.594003) (xy 92.202978 -164.576065) (xy 92.308329 -164.566066)
			(xy 92.414135 -164.564063) (xy 92.519789 -164.570068) (xy 92.624686 -164.584047) (xy 92.728226 -164.605918)
			(xy 92.829815 -164.635558) (xy 92.928872 -164.672796) (xy 93.024829 -164.717418) (xy 93.117136 -164.76917)
			(xy 93.205265 -164.827755) (xy 93.288711 -164.892837) (xy 93.366995 -164.964043) (xy 93.43967 -165.040966)
			(xy 93.50632 -165.123166) (xy 93.566562 -165.21017) (xy 93.620051 -165.301481) (xy 93.666482 -165.396576)
			(xy 93.705587 -165.49491) (xy 93.737144 -165.595921) (xy 93.760971 -165.699028) (xy 93.776932 -165.803642)
			(xy 93.784936 -165.909164) (xy 93.785436 -165.962076) (xy 93.784936 -166.014988) (xy 93.776932 -166.12051)
			(xy 93.760971 -166.225124) (xy 93.737144 -166.328231) (xy 93.705587 -166.429242) (xy 93.666482 -166.527576)
			(xy 93.620051 -166.622671) (xy 93.566562 -166.713982) (xy 93.50632 -166.800986) (xy 93.43967 -166.883186)
			(xy 93.366995 -166.960109) (xy 93.288711 -167.031315) (xy 93.205265 -167.096397) (xy 93.117136 -167.154982)
			(xy 93.024829 -167.206734) (xy 92.928872 -167.251356) (xy 92.829815 -167.288594) (xy 92.728226 -167.318234)
			(xy 92.624686 -167.340105) (xy 92.519789 -167.354084) (xy 92.414135 -167.360089) (xy 92.308329 -167.358086)
			(xy 92.202978 -167.348087) (xy 92.098685 -167.330149) (xy 91.996047 -167.304375) (xy 91.895652 -167.270913)
			(xy 91.798075 -167.229953) (xy 91.703876 -167.181731) (xy 91.613593 -167.126524) (xy 91.527744 -167.064646)
			(xy 91.446821 -166.996453) (xy 91.371287 -166.922335) (xy 91.301575 -166.842717) (xy 91.238084 -166.758054)
			(xy 91.181177 -166.668833) (xy 91.131181 -166.575563) (xy 91.088383 -166.478779) (xy 91.053026 -166.379035)
			(xy 91.025315 -166.276903) (xy 91.005406 -166.172968) (xy 90.993416 -166.067825) (xy 90.989411 -165.962076)
			(xy 84.387436 -165.962076) (xy 84.386936 -166.014988) (xy 84.378932 -166.12051) (xy 84.362971 -166.225124)
			(xy 84.339144 -166.328231) (xy 84.307587 -166.429242) (xy 84.268482 -166.527576) (xy 84.222051 -166.622671)
			(xy 84.168562 -166.713982) (xy 84.10832 -166.800986) (xy 84.04167 -166.883186) (xy 83.968995 -166.960109)
			(xy 83.890711 -167.031315) (xy 83.807265 -167.096397) (xy 83.719136 -167.154982) (xy 83.626829 -167.206734)
			(xy 83.530872 -167.251356) (xy 83.431815 -167.288594) (xy 83.330226 -167.318234) (xy 83.226686 -167.340105)
			(xy 83.121789 -167.354084) (xy 83.016135 -167.360089) (xy 82.910329 -167.358086) (xy 82.804978 -167.348087)
			(xy 82.700685 -167.330149) (xy 82.598047 -167.304375) (xy 82.497652 -167.270913) (xy 82.400075 -167.229953)
			(xy 82.305876 -167.181731) (xy 82.215593 -167.126524) (xy 82.129744 -167.064646) (xy 82.048821 -166.996453)
			(xy 81.973287 -166.922335) (xy 81.903575 -166.842717) (xy 81.840084 -166.758054) (xy 81.783177 -166.668833)
			(xy 81.733181 -166.575563) (xy 81.690383 -166.478779) (xy 81.655026 -166.379035) (xy 81.627315 -166.276903)
			(xy 81.607406 -166.172968) (xy 81.595416 -166.067825) (xy 81.591411 -165.962076) (xy 63.903248 -165.962076)
			(xy 63.909379 -166.022525) (xy 63.909956 -166.067232) (xy 63.909956 -166.068248) (xy 63.909702 -166.079678)
			(xy 63.936181 -166.085625) (xy 63.988416 -166.100367) (xy 64.014096 -166.109142) (xy 64.022293 -166.111656)
			(xy 64.039427 -166.111656) (xy 64.047624 -166.109142) (xy 64.082842 -166.097202) (xy 64.154852 -166.078613)
			(xy 64.228174 -166.066171) (xy 64.302285 -166.059965) (xy 64.33947 -166.059612) (xy 64.376654 -166.059989)
			(xy 64.450761 -166.066209) (xy 64.524081 -166.078649) (xy 64.596093 -166.097221) (xy 64.631316 -166.109142)
			(xy 64.639513 -166.111656) (xy 64.656647 -166.111656) (xy 64.664844 -166.109142) (xy 64.699939 -166.097233)
			(xy 64.771698 -166.078689) (xy 64.844763 -166.066249) (xy 64.918616 -166.060001) (xy 64.955674 -166.059612)
			(xy 64.95669 -166.059612) (xy 64.998618 -166.060035) (xy 65.082094 -166.068005) (xy 65.164434 -166.083874)
			(xy 65.244893 -166.107498) (xy 65.322742 -166.138663) (xy 65.397276 -166.177087) (xy 65.46782 -166.222422)
			(xy 65.533735 -166.274258) (xy 65.594424 -166.332124) (xy 65.649338 -166.395498) (xy 65.69798 -166.463804)
			(xy 65.739908 -166.536425) (xy 65.774743 -166.612703) (xy 65.802169 -166.691946) (xy 65.821939 -166.773438)
			(xy 65.833873 -166.85644) (xy 65.837863 -166.9402) (xy 65.833873 -167.02396) (xy 65.821939 -167.106962)
			(xy 65.802169 -167.188454) (xy 65.774743 -167.267697) (xy 65.739908 -167.343975) (xy 65.69798 -167.416596)
			(xy 65.688295 -167.430196) (xy 351.432876 -167.430196) (xy 351.433453 -167.385427) (xy 351.442459 -167.296342)
			(xy 351.46036 -167.208611) (xy 351.486975 -167.123119) (xy 351.503996 -167.081708) (xy 351.507565 -167.072118)
			(xy 351.507564 -167.051674) (xy 351.503996 -167.042084) (xy 351.486956 -167.000679) (xy 351.460322 -166.91519)
			(xy 351.442419 -166.827456) (xy 351.433427 -166.738367) (xy 351.432876 -166.693596) (xy 351.433453 -166.648827)
			(xy 351.442459 -166.559742) (xy 351.46036 -166.472011) (xy 351.486975 -166.386519) (xy 351.503996 -166.345108)
			(xy 351.507565 -166.335518) (xy 351.507564 -166.315074) (xy 351.503996 -166.305484) (xy 351.486956 -166.264079)
			(xy 351.460322 -166.17859) (xy 351.442419 -166.090856) (xy 351.433427 -166.001767) (xy 351.432876 -165.956996)
			(xy 351.433349 -165.915886) (xy 351.440937 -165.834016) (xy 351.456047 -165.753196) (xy 351.478552 -165.674116)
			(xy 351.508259 -165.597449) (xy 351.544914 -165.523852) (xy 351.588204 -165.453951) (xy 351.63776 -165.388343)
			(xy 351.693159 -165.327588) (xy 351.753929 -165.272205) (xy 351.81955 -165.222667) (xy 351.889463 -165.179396)
			(xy 351.963071 -165.142761) (xy 352.039745 -165.113075) (xy 352.118832 -165.090592) (xy 352.199656 -165.075503)
			(xy 352.281528 -165.067937) (xy 352.322638 -165.067488) (xy 352.364242 -165.067962) (xy 352.44709 -165.075694)
			(xy 352.528855 -165.091124) (xy 352.608822 -165.114117) (xy 352.686295 -165.144474) (xy 352.760597 -165.181928)
			(xy 352.796094 -165.203632) (xy 352.805234 -165.208789) (xy 352.825949 -165.212002) (xy 352.846222 -165.206673)
			(xy 352.854768 -165.200584) (xy 352.888392 -165.174629) (xy 352.959771 -165.128573) (xy 353.035214 -165.08953)
			(xy 353.114035 -165.057855) (xy 353.195516 -165.033837) (xy 353.278916 -165.017694) (xy 353.363474 -165.009574)
			(xy 353.405948 -165.009068) (xy 353.406202 -165.009068) (xy 353.44731 -165.009511) (xy 353.529174 -165.017096)
			(xy 353.60999 -165.0322) (xy 353.689068 -165.054696) (xy 353.765733 -165.084391) (xy 353.839332 -165.121033)
			(xy 353.909237 -165.164307) (xy 353.974851 -165.213846) (xy 354.035616 -165.269227) (xy 354.091012 -165.329978)
			(xy 354.140567 -165.39558) (xy 354.183859 -165.465474) (xy 354.220519 -165.539063) (xy 354.250233 -165.615721)
			(xy 354.272749 -165.694793) (xy 354.287874 -165.775606) (xy 354.295479 -165.857468) (xy 354.295964 -165.898576)
			(xy 354.295409 -165.943346) (xy 354.286396 -166.032431) (xy 354.268489 -166.120162) (xy 354.241868 -166.205653)
			(xy 354.224844 -166.247064) (xy 354.221294 -166.256659) (xy 354.221285 -166.277097) (xy 354.224844 -166.286688)
			(xy 354.241856 -166.328036) (xy 354.268465 -166.413399) (xy 354.286369 -166.501003) (xy 354.289105 -166.527988)
			(xy 401.547076 -166.527988) (xy 401.54765 -166.483219) (xy 401.556657 -166.394134) (xy 401.574559 -166.306403)
			(xy 401.601175 -166.220911) (xy 401.618196 -166.1795) (xy 401.62177 -166.169912) (xy 401.621765 -166.149466)
			(xy 401.618196 -166.139876) (xy 401.601153 -166.098472) (xy 401.574521 -166.012983) (xy 401.556618 -165.925248)
			(xy 401.547627 -165.836159) (xy 401.547076 -165.791388) (xy 401.54765 -165.746619) (xy 401.556657 -165.657534)
			(xy 401.574559 -165.569803) (xy 401.601175 -165.484311) (xy 401.618196 -165.4429) (xy 401.62177 -165.433312)
			(xy 401.621765 -165.412866) (xy 401.618196 -165.403276) (xy 401.601153 -165.361872) (xy 401.574521 -165.276383)
			(xy 401.556618 -165.188648) (xy 401.547627 -165.099559) (xy 401.547076 -165.054788) (xy 401.547541 -165.013678)
			(xy 401.55513 -164.931808) (xy 401.570241 -164.850988) (xy 401.592747 -164.771907) (xy 401.622454 -164.695241)
			(xy 401.659109 -164.621643) (xy 401.7024 -164.551742) (xy 401.751957 -164.486134) (xy 401.807357 -164.42538)
			(xy 401.868127 -164.369997) (xy 401.933748 -164.320459) (xy 402.003662 -164.277187) (xy 402.07727 -164.240553)
			(xy 402.153944 -164.210867) (xy 402.233031 -164.188384) (xy 402.313856 -164.173295) (xy 402.395728 -164.165729)
			(xy 402.436838 -164.16528) (xy 402.478442 -164.165755) (xy 402.56129 -164.173487) (xy 402.643054 -164.188917)
			(xy 402.723022 -164.21191) (xy 402.800495 -164.242266) (xy 402.874796 -164.27972) (xy 402.910294 -164.301424)
			(xy 402.919434 -164.306582) (xy 402.940149 -164.309796) (xy 402.960422 -164.304466) (xy 402.968968 -164.298376)
			(xy 403.002591 -164.27242) (xy 403.07397 -164.226364) (xy 403.149414 -164.187321) (xy 403.228235 -164.155647)
			(xy 403.309716 -164.131629) (xy 403.393116 -164.115486) (xy 403.477674 -164.107366) (xy 403.520148 -164.10686)
			(xy 403.520402 -164.10686) (xy 403.561509 -164.107311) (xy 403.643374 -164.114895) (xy 403.724189 -164.13)
			(xy 403.803267 -164.152496) (xy 403.879931 -164.182191) (xy 403.95353 -164.218831) (xy 404.023434 -164.262106)
			(xy 404.089048 -164.311644) (xy 404.149813 -164.367025) (xy 404.205209 -164.427775) (xy 404.254764 -164.493376)
			(xy 404.298057 -164.563269) (xy 404.334716 -164.636858) (xy 404.364431 -164.713515) (xy 404.386947 -164.792587)
			(xy 404.402073 -164.873398) (xy 404.409679 -164.955261) (xy 404.410164 -164.996368) (xy 404.409606 -165.041138)
			(xy 404.400594 -165.130223) (xy 404.382688 -165.217954) (xy 404.356068 -165.303445) (xy 404.339044 -165.344856)
			(xy 404.335498 -165.354452) (xy 404.335487 -165.374889) (xy 404.339044 -165.38448) (xy 404.356053 -165.425829)
			(xy 404.382663 -165.511192) (xy 404.400568 -165.598795) (xy 404.409589 -165.687753) (xy 404.410164 -165.73246)
			(xy 404.410164 -165.733476) (xy 404.40991 -165.744906) (xy 404.436389 -165.750851) (xy 404.488624 -165.765594)
			(xy 404.514304 -165.77437) (xy 404.522501 -165.776884) (xy 404.539635 -165.776884) (xy 404.547832 -165.77437)
			(xy 404.58305 -165.762429) (xy 404.655059 -165.74384) (xy 404.728382 -165.731398) (xy 404.802492 -165.725192)
			(xy 404.839678 -165.72484) (xy 404.876862 -165.725213) (xy 404.95097 -165.731434) (xy 405.02429 -165.743875)
			(xy 405.096301 -165.762448) (xy 405.131524 -165.77437) (xy 405.139721 -165.776884) (xy 405.156855 -165.776884)
			(xy 405.165052 -165.77437) (xy 405.200146 -165.76246) (xy 405.271906 -165.743916) (xy 405.344971 -165.731476)
			(xy 405.418824 -165.725229) (xy 405.455882 -165.72484) (xy 405.456898 -165.72484) (xy 405.498822 -165.725407)
			(xy 405.582291 -165.733377) (xy 405.664623 -165.749245) (xy 405.745075 -165.772868) (xy 405.822917 -165.804031)
			(xy 405.897444 -165.842452) (xy 405.967982 -165.887784) (xy 406.033891 -165.939615) (xy 406.094575 -165.997477)
			(xy 406.149484 -166.060845) (xy 406.198121 -166.129146) (xy 406.240045 -166.20176) (xy 406.274876 -166.278031)
			(xy 406.302301 -166.357268) (xy 406.322068 -166.438752) (xy 406.334001 -166.521747) (xy 406.337991 -166.6055)
			(xy 406.334001 -166.689253) (xy 406.322068 -166.772248) (xy 406.302301 -166.853732) (xy 406.274876 -166.932969)
			(xy 406.240045 -167.00924) (xy 406.198121 -167.081854) (xy 406.149484 -167.150155) (xy 406.094575 -167.213523)
			(xy 406.033891 -167.271385) (xy 405.967982 -167.323216) (xy 405.897444 -167.368548) (xy 405.822917 -167.406969)
			(xy 405.745075 -167.438132) (xy 405.664623 -167.461755) (xy 405.582291 -167.477623) (xy 405.498822 -167.485593)
			(xy 405.456898 -167.486076) (xy 405.455882 -167.486076) (xy 405.418825 -167.485672) (xy 405.344976 -167.479407)
			(xy 405.271913 -167.466964) (xy 405.200153 -167.448432) (xy 405.165052 -167.436546) (xy 405.156855 -167.434032)
			(xy 405.139721 -167.434032) (xy 405.131524 -167.436546) (xy 405.102638 -167.446383) (xy 405.043785 -167.462529)
			(xy 405.013922 -167.468804) (xy 405.004334 -167.471159) (xy 404.987889 -167.482054) (xy 404.976796 -167.498367)
			(xy 404.974298 -167.50792) (xy 404.96417 -167.552275) (xy 404.936046 -167.638805) (xy 404.918164 -167.68064)
			(xy 404.914347 -167.690579) (xy 404.914353 -167.711846) (xy 404.918164 -167.721788) (xy 404.936394 -167.764388)
			(xy 404.964909 -167.852556) (xy 404.984099 -167.943213) (xy 404.993757 -168.035373) (xy 404.994364 -168.081706)
			(xy 404.994364 -168.082214) (xy 404.99386 -168.124562) (xy 404.985809 -168.208876) (xy 404.96978 -168.292042)
			(xy 404.945919 -168.373309) (xy 404.91444 -168.451939) (xy 404.875629 -168.52722) (xy 404.829839 -168.598472)
			(xy 404.777483 -168.665048) (xy 404.719035 -168.726346) (xy 404.655025 -168.781811) (xy 404.586033 -168.83094)
			(xy 404.512683 -168.873289) (xy 404.43564 -168.908473) (xy 404.355601 -168.936175) (xy 404.273292 -168.956143)
			(xy 404.189457 -168.968196) (xy 404.104856 -168.972227) (xy 404.020255 -168.968196) (xy 403.93642 -168.956143)
			(xy 403.854111 -168.936175) (xy 403.774072 -168.908473) (xy 403.697029 -168.873289) (xy 403.623679 -168.83094)
			(xy 403.554687 -168.781811) (xy 403.490677 -168.726346) (xy 403.432229 -168.665048) (xy 403.379873 -168.598472)
			(xy 403.334083 -168.52722) (xy 403.295272 -168.451939) (xy 403.263793 -168.373309) (xy 403.239932 -168.292042)
			(xy 403.223903 -168.208876) (xy 403.215852 -168.124562) (xy 403.215348 -168.082214) (xy 403.215348 -168.081706)
			(xy 403.215963 -168.035374) (xy 403.225632 -167.943217) (xy 403.244825 -167.852563) (xy 403.273334 -167.764394)
			(xy 403.291548 -167.721788) (xy 403.295348 -167.711844) (xy 403.295353 -167.690582) (xy 403.291548 -167.68064)
			(xy 403.273311 -167.637974) (xy 403.244764 -167.549684) (xy 403.225569 -167.458899) (xy 403.215934 -167.36661)
			(xy 403.215348 -167.320214) (xy 403.215953 -167.272404) (xy 403.226131 -167.177329) (xy 403.235668 -167.130476)
			(xy 403.23764 -167.118071) (xy 403.230727 -167.093957) (xy 403.22246 -167.084502) (xy 403.18182 -167.042338)
			(xy 403.178264 -167.0431) (xy 403.169416 -167.045411) (xy 403.154053 -167.055303) (xy 403.148292 -167.062404)
			(xy 403.123137 -167.095067) (xy 403.067717 -167.15611) (xy 403.006886 -167.211763) (xy 402.941166 -167.261548)
			(xy 402.871121 -167.305037) (xy 402.797352 -167.341858) (xy 402.720492 -167.371694) (xy 402.641201 -167.39429)
			(xy 402.560159 -167.409451) (xy 402.478062 -167.417047) (xy 402.436838 -167.417496) (xy 402.395733 -167.416951)
			(xy 402.313873 -167.409371) (xy 402.233061 -167.394271) (xy 402.153987 -167.37178) (xy 402.077325 -167.342091)
			(xy 402.003729 -167.305456) (xy 401.933826 -167.262187) (xy 401.868213 -167.212655) (xy 401.80745 -167.157281)
			(xy 401.752053 -167.096538) (xy 401.702497 -167.030943) (xy 401.659203 -166.961056) (xy 401.622541 -166.887473)
			(xy 401.592824 -166.810822) (xy 401.570304 -166.731756) (xy 401.555174 -166.65095) (xy 401.547564 -166.569093)
			(xy 401.547076 -166.527988) (xy 354.289105 -166.527988) (xy 354.295389 -166.589961) (xy 354.295964 -166.634668)
			(xy 354.295964 -166.635684) (xy 354.29571 -166.647114) (xy 354.322189 -166.653059) (xy 354.374424 -166.667802)
			(xy 354.400104 -166.676578) (xy 354.408301 -166.679092) (xy 354.425435 -166.679092) (xy 354.433632 -166.676578)
			(xy 354.468848 -166.664633) (xy 354.540859 -166.646046) (xy 354.614181 -166.633606) (xy 354.688292 -166.6274)
			(xy 354.725478 -166.627048) (xy 354.762662 -166.62742) (xy 354.83677 -166.633641) (xy 354.91009 -166.646083)
			(xy 354.982101 -166.664656) (xy 355.017324 -166.676578) (xy 355.025521 -166.679092) (xy 355.042655 -166.679092)
			(xy 355.050852 -166.676578) (xy 355.085946 -166.664669) (xy 355.157706 -166.646124) (xy 355.230771 -166.633684)
			(xy 355.304624 -166.627437) (xy 355.341682 -166.627048) (xy 355.342698 -166.627048) (xy 355.384622 -166.627599)
			(xy 355.468092 -166.635569) (xy 355.550425 -166.651437) (xy 355.630878 -166.67506) (xy 355.70872 -166.706224)
			(xy 355.783248 -166.744645) (xy 355.853787 -166.789977) (xy 355.919696 -166.841809) (xy 355.980381 -166.899671)
			(xy 356.03529 -166.96304) (xy 356.083927 -167.031341) (xy 356.125852 -167.103957) (xy 356.160684 -167.180228)
			(xy 356.188108 -167.259465) (xy 356.207876 -167.340951) (xy 356.219809 -167.423946) (xy 356.223799 -167.5077)
			(xy 356.219809 -167.591454) (xy 356.207876 -167.674449) (xy 356.188108 -167.755935) (xy 356.160684 -167.835172)
			(xy 356.125852 -167.911443) (xy 356.083927 -167.984059) (xy 356.03529 -168.05236) (xy 355.980381 -168.115729)
			(xy 355.919696 -168.173591) (xy 355.853787 -168.225423) (xy 355.783248 -168.270755) (xy 355.70872 -168.309176)
			(xy 355.630878 -168.34034) (xy 355.550425 -168.363963) (xy 355.468092 -168.379831) (xy 355.384622 -168.387801)
			(xy 355.342698 -168.388284) (xy 355.341682 -168.388284) (xy 355.304625 -168.387885) (xy 355.230776 -168.381619)
			(xy 355.157713 -168.369175) (xy 355.085953 -168.350641) (xy 355.050852 -168.338754) (xy 355.042655 -168.33624)
			(xy 355.025521 -168.33624) (xy 355.017324 -168.338754) (xy 354.989546 -168.348208) (xy 354.932984 -168.363843)
			(xy 354.904294 -168.369996) (xy 354.894532 -168.372423) (xy 354.877923 -168.383747) (xy 354.866932 -168.400579)
			(xy 354.86467 -168.410382) (xy 354.855142 -168.457509) (xy 354.827269 -168.549532) (xy 354.809044 -168.594024)
			(xy 354.805459 -168.603609) (xy 354.805473 -168.624057) (xy 354.809044 -168.633648) (xy 354.826071 -168.675024)
			(xy 354.852688 -168.760451) (xy 354.870591 -168.84812) (xy 354.879599 -168.937143) (xy 354.880164 -168.981882)
			(xy 354.880164 -168.982136) (xy 354.87966 -169.024484) (xy 354.871609 -169.108798) (xy 354.85558 -169.191964)
			(xy 354.831719 -169.273231) (xy 354.80024 -169.351861) (xy 354.761429 -169.427142) (xy 354.715639 -169.498394)
			(xy 354.663283 -169.56497) (xy 354.604835 -169.626268) (xy 354.540825 -169.681733) (xy 354.471833 -169.730862)
			(xy 354.398483 -169.773211) (xy 354.32144 -169.808395) (xy 354.241401 -169.836097) (xy 354.159092 -169.856065)
			(xy 354.075257 -169.868118) (xy 353.990656 -169.872149) (xy 353.906055 -169.868118) (xy 353.82222 -169.856065)
			(xy 353.739911 -169.836097) (xy 353.659872 -169.808395) (xy 353.582829 -169.773211) (xy 353.509479 -169.730862)
			(xy 353.440487 -169.681733) (xy 353.376477 -169.626268) (xy 353.318029 -169.56497) (xy 353.265673 -169.498394)
			(xy 353.219883 -169.427142) (xy 353.181072 -169.351861) (xy 353.149593 -169.273231) (xy 353.125732 -169.191964)
			(xy 353.109703 -169.108798) (xy 353.101652 -169.024484) (xy 353.101148 -168.982136) (xy 353.101148 -168.981882)
			(xy 353.101731 -168.937144) (xy 353.110743 -168.848123) (xy 353.128644 -168.760456) (xy 353.155252 -168.675028)
			(xy 353.172268 -168.633648) (xy 353.175811 -168.624051) (xy 353.175824 -168.603615) (xy 353.172268 -168.594024)
			(xy 353.155227 -168.55262) (xy 353.128597 -168.46713) (xy 353.110694 -168.379396) (xy 353.1017 -168.290307)
			(xy 353.101148 -168.245536) (xy 353.10149 -168.209754) (xy 353.107197 -168.138419) (xy 353.118619 -168.067773)
			(xy 353.126802 -168.032938) (xy 353.128529 -168.024629) (xy 353.126997 -168.007741) (xy 353.119979 -167.992303)
			(xy 353.114356 -167.985948) (xy 353.07397 -167.943276) (xy 353.064064 -167.945308) (xy 353.055164 -167.947623)
			(xy 353.039671 -167.957504) (xy 353.033838 -167.964612) (xy 353.008691 -167.997264) (xy 352.953283 -168.058281)
			(xy 352.892469 -168.113912) (xy 352.826771 -168.163681) (xy 352.756752 -168.207161) (xy 352.683013 -168.243979)
			(xy 352.606184 -168.273821) (xy 352.526925 -168.29643) (xy 352.445915 -168.311612) (xy 352.363848 -168.319237)
			(xy 352.322638 -168.319704) (xy 352.281533 -168.319151) (xy 352.199674 -168.311571) (xy 352.118862 -168.296471)
			(xy 352.039789 -168.273981) (xy 351.963127 -168.244292) (xy 351.889531 -168.207657) (xy 351.819629 -168.164389)
			(xy 351.754016 -168.114857) (xy 351.693252 -168.059484) (xy 351.637856 -167.998741) (xy 351.5883 -167.933147)
			(xy 351.545006 -167.863261) (xy 351.508343 -167.789678) (xy 351.478626 -167.713028) (xy 351.456106 -167.633963)
			(xy 351.440975 -167.553157) (xy 351.433364 -167.471301) (xy 351.432876 -167.430196) (xy 65.688295 -167.430196)
			(xy 65.649338 -167.484902) (xy 65.594424 -167.548276) (xy 65.533735 -167.606142) (xy 65.46782 -167.657978)
			(xy 65.397276 -167.703313) (xy 65.322742 -167.741737) (xy 65.244893 -167.772902) (xy 65.164434 -167.796526)
			(xy 65.082094 -167.812395) (xy 64.998618 -167.820365) (xy 64.95669 -167.820848) (xy 64.955674 -167.820848)
			(xy 64.918617 -167.820448) (xy 64.844768 -167.814181) (xy 64.771705 -167.801738) (xy 64.699945 -167.783204)
			(xy 64.664844 -167.771318) (xy 64.656647 -167.768804) (xy 64.639513 -167.768804) (xy 64.631316 -167.771318)
			(xy 64.597889 -167.782662) (xy 64.529607 -167.80059) (xy 64.494918 -167.807132) (xy 64.484907 -167.809437)
			(xy 64.467748 -167.820693) (xy 64.456372 -167.837772) (xy 64.454024 -167.847772) (xy 64.44452 -167.895628)
			(xy 64.416383 -167.989057) (xy 64.39789 -168.034208) (xy 64.394248 -168.043772) (xy 64.394124 -168.064219)
			(xy 64.397636 -168.073832) (xy 64.414658 -168.11521) (xy 64.441276 -168.200636) (xy 64.459181 -168.288304)
			(xy 64.46819 -168.377327) (xy 64.468756 -168.422066) (xy 64.468756 -168.42232) (xy 64.468252 -168.464668)
			(xy 64.460201 -168.548982) (xy 64.444172 -168.632148) (xy 64.420311 -168.713415) (xy 64.388832 -168.792045)
			(xy 64.350021 -168.867326) (xy 64.304231 -168.938578) (xy 64.251875 -169.005154) (xy 64.193427 -169.066452)
			(xy 64.129417 -169.121917) (xy 64.060425 -169.171046) (xy 63.987075 -169.213395) (xy 63.910032 -169.248579)
			(xy 63.829993 -169.276281) (xy 63.747684 -169.296249) (xy 63.663849 -169.308302) (xy 63.579248 -169.312333)
			(xy 63.494647 -169.308302) (xy 63.410812 -169.296249) (xy 63.328503 -169.276281) (xy 63.248464 -169.248579)
			(xy 63.171421 -169.213395) (xy 63.098071 -169.171046) (xy 63.029079 -169.121917) (xy 62.965069 -169.066452)
			(xy 62.906621 -169.005154) (xy 62.854265 -168.938578) (xy 62.808475 -168.867326) (xy 62.769664 -168.792045)
			(xy 62.738185 -168.713415) (xy 62.714324 -168.632148) (xy 62.698295 -168.548982) (xy 62.690244 -168.464668)
			(xy 62.68974 -168.42232) (xy 62.68974 -168.422066) (xy 62.690311 -168.377328) (xy 62.699325 -168.288306)
			(xy 62.71723 -168.200639) (xy 62.743842 -168.115211) (xy 62.76086 -168.073832) (xy 62.764412 -168.064238)
			(xy 62.76442 -168.043799) (xy 62.76086 -168.034208) (xy 62.743813 -167.992806) (xy 62.717185 -167.907315)
			(xy 62.699284 -167.81958) (xy 62.690292 -167.730491) (xy 62.68974 -167.68572) (xy 62.689828 -167.668048)
			(xy 62.691224 -167.632732) (xy 62.692534 -167.615108) (xy 62.692907 -167.605036) (xy 62.68662 -167.585904)
			(xy 62.673425 -167.57069) (xy 62.664594 -167.565832) (xy 62.566296 -167.516556) (xy 62.535816 -167.520366)
			(xy 62.524132 -167.53078) (xy 62.493735 -167.556935) (xy 62.428993 -167.604263) (xy 62.360251 -167.645567)
			(xy 62.288069 -167.680512) (xy 62.213032 -167.708812) (xy 62.135751 -167.730238) (xy 62.056854 -167.744617)
			(xy 61.976982 -167.75183) (xy 61.936884 -167.752268) (xy 61.93663 -167.752268) (xy 61.895524 -167.751759)
			(xy 61.813662 -167.744177) (xy 61.732849 -167.729076) (xy 61.653773 -167.706584) (xy 61.57711 -167.676893)
			(xy 61.503513 -167.640256) (xy 61.433609 -167.596985) (xy 61.367995 -167.547451) (xy 61.307231 -167.492074)
			(xy 61.251835 -167.431328) (xy 61.202279 -167.36573) (xy 61.158986 -167.295841) (xy 61.122325 -167.222256)
			(xy 61.092608 -167.145602) (xy 61.07009 -167.066534) (xy 61.054963 -166.985725) (xy 61.047355 -166.903866)
			(xy 61.046868 -166.86276) (xy 2.509012 -166.86276) (xy 2.509012 -170.29303) (xy 8.7249 -170.29303)
			(xy 8.7249 -169.42943) (xy 8.725386 -169.402179) (xy 8.733142 -169.348231) (xy 8.748497 -169.295936)
			(xy 8.771139 -169.246359) (xy 8.800605 -169.200509) (xy 8.836296 -169.159318) (xy 8.877487 -169.123627)
			(xy 8.923337 -169.094161) (xy 8.972914 -169.071519) (xy 9.025209 -169.056164) (xy 9.079157 -169.048408)
			(xy 9.133659 -169.048408) (xy 9.187607 -169.056164) (xy 9.239902 -169.071519) (xy 9.289479 -169.094161)
			(xy 9.335329 -169.123627) (xy 9.37652 -169.159318) (xy 9.412211 -169.200509) (xy 9.441677 -169.246359)
			(xy 9.464319 -169.295936) (xy 9.479674 -169.348231) (xy 9.48743 -169.402179) (xy 9.487916 -169.42943)
			(xy 9.487916 -169.857674) (xy 111.084868 -169.857674) (xy 111.085438 -169.812905) (xy 111.094447 -169.72382)
			(xy 111.112349 -169.636089) (xy 111.138966 -169.550597) (xy 111.155988 -169.509186) (xy 111.15957 -169.4996)
			(xy 111.15956 -169.479153) (xy 111.155988 -169.469562) (xy 111.13894 -169.42816) (xy 111.112309 -169.34267)
			(xy 111.094408 -169.254935) (xy 111.085418 -169.165845) (xy 111.084868 -169.121074) (xy 111.085438 -169.076305)
			(xy 111.094447 -168.98722) (xy 111.112349 -168.899489) (xy 111.138966 -168.813997) (xy 111.155988 -168.772586)
			(xy 111.15957 -168.763) (xy 111.15956 -168.742553) (xy 111.155988 -168.732962) (xy 111.13894 -168.69156)
			(xy 111.112309 -168.60607) (xy 111.094408 -168.518335) (xy 111.085418 -168.429245) (xy 111.084868 -168.384474)
			(xy 111.085274 -168.343358) (xy 111.092864 -168.261476) (xy 111.107976 -168.180645) (xy 111.130482 -168.101552)
			(xy 111.160191 -168.024873) (xy 111.196847 -167.951263) (xy 111.240139 -167.881349) (xy 111.289697 -167.815728)
			(xy 111.345099 -167.754959) (xy 111.405871 -167.699561) (xy 111.471495 -167.650007) (xy 111.541412 -167.60672)
			(xy 111.615025 -167.570068) (xy 111.691705 -167.540365) (xy 111.770799 -167.517863) (xy 111.851632 -167.502756)
			(xy 111.933514 -167.495171) (xy 111.97463 -167.494712) (xy 112.016241 -167.495173) (xy 112.099098 -167.502953)
			(xy 112.180867 -167.518431) (xy 112.260835 -167.541474) (xy 112.338303 -167.571879) (xy 112.412595 -167.609382)
			(xy 112.448086 -167.63111) (xy 112.457229 -167.636263) (xy 112.477942 -167.63948) (xy 112.498214 -167.634152)
			(xy 112.50676 -167.628062) (xy 112.540389 -167.602071) (xy 112.611783 -167.555946) (xy 112.687254 -167.516845)
			(xy 112.766112 -167.485124) (xy 112.847637 -167.461075) (xy 112.931085 -167.444915) (xy 113.015695 -167.436793)
			(xy 113.058194 -167.436292) (xy 113.099307 -167.436819) (xy 113.181182 -167.444405) (xy 113.262007 -167.459513)
			(xy 113.341094 -167.482013) (xy 113.417768 -167.511715) (xy 113.491374 -167.548365) (xy 113.561284 -167.59165)
			(xy 113.626903 -167.6412) (xy 113.68767 -167.696593) (xy 113.743067 -167.757357) (xy 113.792621 -167.822973)
			(xy 113.83591 -167.892881) (xy 113.872564 -167.966485) (xy 113.90227 -168.043156) (xy 113.924776 -168.122242)
			(xy 113.939888 -168.203067) (xy 113.947479 -168.284941) (xy 113.947956 -168.326054) (xy 113.947393 -168.370824)
			(xy 113.938383 -168.459909) (xy 113.920477 -168.54764) (xy 113.893859 -168.633131) (xy 113.876836 -168.674542)
			(xy 113.873299 -168.684141) (xy 113.873282 -168.704576) (xy 113.876836 -168.714166) (xy 113.89384 -168.755517)
			(xy 113.920451 -168.840879) (xy 113.938358 -168.928482) (xy 113.94738 -169.017439) (xy 113.947956 -169.062146)
			(xy 113.947956 -169.063162) (xy 113.947702 -169.074592) (xy 113.974181 -169.080538) (xy 114.026416 -169.095281)
			(xy 114.052096 -169.104056) (xy 114.060293 -169.10657) (xy 114.077427 -169.10657) (xy 114.085624 -169.104056)
			(xy 114.12084 -169.092095) (xy 114.192844 -169.073441) (xy 114.266165 -169.060932) (xy 114.34028 -169.054659)
			(xy 114.37747 -169.054272) (xy 114.414659 -169.054671) (xy 114.488772 -169.060958) (xy 114.562092 -169.073465)
			(xy 114.634098 -169.092103) (xy 114.669316 -169.104056) (xy 114.677513 -169.10657) (xy 114.694647 -169.10657)
			(xy 114.702844 -169.104056) (xy 114.738059 -169.092089) (xy 114.810062 -169.073437) (xy 114.883384 -169.06093)
			(xy 114.9575 -169.054658) (xy 114.99469 -169.054272) (xy 115.03663 -169.054667) (xy 115.120132 -169.062639)
			(xy 115.202497 -169.078513) (xy 115.28298 -169.102144) (xy 115.360853 -169.133319) (xy 115.43541 -169.171755)
			(xy 115.505975 -169.217104) (xy 115.57191 -169.268955) (xy 115.632618 -169.326839) (xy 115.687549 -169.390232)
			(xy 115.736205 -169.458559) (xy 115.778146 -169.531202) (xy 115.812991 -169.607503) (xy 115.840426 -169.68677)
			(xy 115.860202 -169.768287) (xy 115.87214 -169.851314) (xy 115.876131 -169.9351) (xy 115.87214 -170.018886)
			(xy 115.860202 -170.101913) (xy 115.840426 -170.18343) (xy 115.812991 -170.262697) (xy 115.778146 -170.338998)
			(xy 115.736205 -170.411641) (xy 115.687549 -170.479968) (xy 115.632618 -170.543361) (xy 115.57191 -170.601245)
			(xy 115.505975 -170.653096) (xy 115.498571 -170.657854) (xy 161.052951 -170.657854) (xy 161.052951 -170.603346)
			(xy 161.060709 -170.549393) (xy 161.076066 -170.497093) (xy 161.09871 -170.447511) (xy 161.12818 -170.401657)
			(xy 161.163876 -170.360463) (xy 161.205071 -170.324769) (xy 161.250927 -170.295301) (xy 161.30051 -170.27266)
			(xy 161.352811 -170.257305) (xy 161.406764 -170.24955) (xy 161.434018 -170.249088) (xy 162.297618 -170.249088)
			(xy 162.324868 -170.249583) (xy 162.378813 -170.257342) (xy 162.431105 -170.272698) (xy 162.48068 -170.29534)
			(xy 162.526528 -170.324806) (xy 162.567715 -170.360498) (xy 162.603404 -170.401687) (xy 162.632869 -170.447536)
			(xy 162.655508 -170.497111) (xy 162.670862 -170.549404) (xy 162.678618 -170.60335) (xy 162.678618 -170.65785)
			(xy 162.670862 -170.711796) (xy 162.655508 -170.764089) (xy 162.632869 -170.813664) (xy 162.603404 -170.859513)
			(xy 162.567715 -170.900702) (xy 162.526528 -170.936394) (xy 162.48068 -170.96586) (xy 162.431105 -170.988502)
			(xy 162.378813 -171.003858) (xy 162.324868 -171.011617) (xy 162.297618 -171.012104) (xy 161.434018 -171.012104)
			(xy 161.406764 -171.01165) (xy 161.352811 -171.003895) (xy 161.30051 -170.98854) (xy 161.250927 -170.965899)
			(xy 161.205071 -170.936431) (xy 161.163876 -170.900737) (xy 161.12818 -170.859543) (xy 161.09871 -170.813689)
			(xy 161.076066 -170.764107) (xy 161.060709 -170.711807) (xy 161.052951 -170.657854) (xy 115.498571 -170.657854)
			(xy 115.43541 -170.698445) (xy 115.360853 -170.736881) (xy 115.28298 -170.768056) (xy 115.202497 -170.791687)
			(xy 115.120132 -170.807561) (xy 115.03663 -170.815533) (xy 114.99469 -170.816016) (xy 114.9575 -170.815629)
			(xy 114.883387 -170.809339) (xy 114.810068 -170.796828) (xy 114.738062 -170.778187) (xy 114.702844 -170.766232)
			(xy 114.694647 -170.763718) (xy 114.677513 -170.763718) (xy 114.669316 -170.766232) (xy 114.625188 -170.781068)
			(xy 114.534574 -170.80245) (xy 114.488468 -170.808904) (xy 114.478735 -170.810567) (xy 114.461516 -170.820188)
			(xy 114.449244 -170.83563) (xy 114.44605 -170.844972) (xy 114.43848 -170.870441) (xy 114.420685 -170.920512)
			(xy 114.41049 -170.945048) (xy 114.406882 -170.954622) (xy 114.406736 -170.97506) (xy 114.410236 -170.984672)
			(xy 114.427271 -171.026045) (xy 114.453886 -171.111473) (xy 114.471787 -171.199143) (xy 114.480792 -171.288167)
			(xy 114.481356 -171.332906) (xy 114.481356 -171.33316) (xy 114.480852 -171.375508) (xy 114.472801 -171.459822)
			(xy 114.456772 -171.542988) (xy 114.432911 -171.624255) (xy 114.401432 -171.702885) (xy 114.362621 -171.778166)
			(xy 114.316831 -171.849418) (xy 114.264475 -171.915994) (xy 114.206027 -171.977292) (xy 114.142017 -172.032757)
			(xy 114.073025 -172.081886) (xy 113.999675 -172.124235) (xy 113.922632 -172.159419) (xy 113.842593 -172.187121)
			(xy 113.760284 -172.207089) (xy 113.676449 -172.219142) (xy 113.591848 -172.223173) (xy 113.507247 -172.219142)
			(xy 113.423412 -172.207089) (xy 113.341103 -172.187121) (xy 113.261064 -172.159419) (xy 113.184021 -172.124235)
			(xy 113.110671 -172.081886) (xy 113.041679 -172.032757) (xy 112.977669 -171.977292) (xy 112.919221 -171.915994)
			(xy 112.866865 -171.849418) (xy 112.821075 -171.778166) (xy 112.782264 -171.702885) (xy 112.750785 -171.624255)
			(xy 112.726924 -171.542988) (xy 112.710895 -171.459822) (xy 112.702844 -171.375508) (xy 112.70234 -171.33316)
			(xy 112.70234 -171.332906) (xy 112.702891 -171.288167) (xy 112.711911 -171.199145) (xy 112.729821 -171.111478)
			(xy 112.75644 -171.026051) (xy 112.77346 -170.984672) (xy 112.777047 -170.975088) (xy 112.777032 -170.954639)
			(xy 112.77346 -170.945048) (xy 112.757652 -170.906707) (xy 112.732373 -170.827716) (xy 112.714548 -170.746717)
			(xy 112.70433 -170.664411) (xy 112.702594 -170.622976) (xy 112.702594 -170.622722) (xy 112.701955 -170.613271)
			(xy 112.694549 -170.595846) (xy 112.681333 -170.582289) (xy 112.672876 -170.578018) (xy 112.589818 -170.540172)
			(xy 112.581121 -170.536666) (xy 112.562416 -170.535564) (xy 112.544562 -170.541248) (xy 112.536986 -170.546776)
			(xy 112.536986 -170.54703) (xy 112.536478 -170.54703) (xy 112.502475 -170.574102) (xy 112.430107 -170.622247)
			(xy 112.353386 -170.663099) (xy 112.273043 -170.696267) (xy 112.189846 -170.721435) (xy 112.104591 -170.738363)
			(xy 112.01809 -170.746889) (xy 111.97463 -170.747436) (xy 111.933515 -170.746973) (xy 111.851635 -170.739388)
			(xy 111.770804 -170.72428) (xy 111.691713 -170.701779) (xy 111.615035 -170.672075) (xy 111.541425 -170.635423)
			(xy 111.471511 -170.592135) (xy 111.405889 -170.542581) (xy 111.34512 -170.487183) (xy 111.289722 -170.426414)
			(xy 111.240167 -170.360793) (xy 111.196879 -170.290879) (xy 111.160226 -170.217269) (xy 111.130522 -170.140591)
			(xy 111.10802 -170.061499) (xy 111.092912 -169.980669) (xy 111.085327 -169.898789) (xy 111.084868 -169.857674)
			(xy 9.487916 -169.857674) (xy 9.487916 -170.29303) (xy 9.48743 -170.320281) (xy 9.479674 -170.374229)
			(xy 9.464319 -170.426524) (xy 9.441677 -170.476101) (xy 9.412211 -170.521951) (xy 9.37652 -170.563142)
			(xy 9.335329 -170.598833) (xy 9.289479 -170.628299) (xy 9.239902 -170.650941) (xy 9.187607 -170.666296)
			(xy 9.133659 -170.674052) (xy 9.079157 -170.674052) (xy 9.025209 -170.666296) (xy 8.972914 -170.650941)
			(xy 8.923337 -170.628299) (xy 8.877487 -170.598833) (xy 8.836296 -170.563142) (xy 8.800605 -170.521951)
			(xy 8.771139 -170.476101) (xy 8.748497 -170.426524) (xy 8.733142 -170.374229) (xy 8.725386 -170.320281)
			(xy 8.7249 -170.29303) (xy 2.509012 -170.29303) (xy 2.509012 -173.07814) (xy 8.7249 -173.07814) (xy 8.7249 -172.21454)
			(xy 8.725386 -172.187289) (xy 8.733142 -172.133341) (xy 8.748497 -172.081046) (xy 8.771139 -172.031469)
			(xy 8.800605 -171.985619) (xy 8.836296 -171.944428) (xy 8.877487 -171.908737) (xy 8.923337 -171.879271)
			(xy 8.972914 -171.856629) (xy 9.025209 -171.841274) (xy 9.079157 -171.833518) (xy 9.133659 -171.833518)
			(xy 9.187607 -171.841274) (xy 9.239902 -171.856629) (xy 9.289479 -171.879271) (xy 9.335329 -171.908737)
			(xy 9.37652 -171.944428) (xy 9.412211 -171.985619) (xy 9.441677 -172.031469) (xy 9.464319 -172.081046)
			(xy 9.479674 -172.133341) (xy 9.48743 -172.187289) (xy 9.487916 -172.21454) (xy 9.487916 -173.07814)
			(xy 9.48743 -173.105391) (xy 9.479674 -173.159339) (xy 9.464319 -173.211634) (xy 9.441677 -173.261211)
			(xy 9.412211 -173.307061) (xy 9.37652 -173.348252) (xy 9.335329 -173.383943) (xy 9.289479 -173.413409)
			(xy 9.239902 -173.436051) (xy 9.187607 -173.451406) (xy 9.133659 -173.459162) (xy 9.079157 -173.459162)
			(xy 9.025209 -173.451406) (xy 8.972914 -173.436051) (xy 8.923337 -173.413409) (xy 8.877487 -173.383943)
			(xy 8.836296 -173.348252) (xy 8.800605 -173.307061) (xy 8.771139 -173.261211) (xy 8.748497 -173.211634)
			(xy 8.733142 -173.159339) (xy 8.725386 -173.105391) (xy 8.7249 -173.07814) (xy 2.509012 -173.07814)
			(xy 2.509012 -175.848264) (xy 8.7249 -175.848264) (xy 8.7249 -174.984664) (xy 8.725386 -174.957413)
			(xy 8.733142 -174.903465) (xy 8.748497 -174.85117) (xy 8.771139 -174.801593) (xy 8.800605 -174.755743)
			(xy 8.836296 -174.714552) (xy 8.877487 -174.678861) (xy 8.923337 -174.649395) (xy 8.972914 -174.626753)
			(xy 9.025209 -174.611398) (xy 9.079157 -174.603642) (xy 9.133659 -174.603642) (xy 9.187607 -174.611398)
			(xy 9.239902 -174.626753) (xy 9.289479 -174.649395) (xy 9.335329 -174.678861) (xy 9.37652 -174.714552)
			(xy 9.412211 -174.755743) (xy 9.441677 -174.801593) (xy 9.464319 -174.85117) (xy 9.479674 -174.903465)
			(xy 9.48743 -174.957413) (xy 9.487916 -174.984664) (xy 9.487916 -175.559974) (xy 69.360288 -175.559974)
			(xy 69.360857 -175.515205) (xy 69.369865 -175.42612) (xy 69.387768 -175.338388) (xy 69.414386 -175.252897)
			(xy 69.431408 -175.211486) (xy 69.434989 -175.2019) (xy 69.43498 -175.181453) (xy 69.431408 -175.171862)
			(xy 69.414355 -175.130462) (xy 69.387726 -175.044971) (xy 69.369827 -174.957236) (xy 69.360838 -174.868145)
			(xy 69.360288 -174.823374) (xy 69.360857 -174.778605) (xy 69.369865 -174.68952) (xy 69.387768 -174.601788)
			(xy 69.414386 -174.516297) (xy 69.431408 -174.474886) (xy 69.434989 -174.4653) (xy 69.43498 -174.444853)
			(xy 69.431408 -174.435262) (xy 69.414355 -174.393862) (xy 69.387726 -174.308371) (xy 69.369827 -174.220636)
			(xy 69.360838 -174.131545) (xy 69.360288 -174.086774) (xy 69.360674 -174.045657) (xy 69.368264 -173.963775)
			(xy 69.383377 -173.882942) (xy 69.405884 -173.803848) (xy 69.435593 -173.727169) (xy 69.47225 -173.653557)
			(xy 69.515543 -173.583643) (xy 69.565103 -173.518021) (xy 69.620506 -173.457252) (xy 69.681279 -173.401854)
			(xy 69.746905 -173.3523) (xy 69.816824 -173.309013) (xy 69.890438 -173.272362) (xy 69.96712 -173.24266)
			(xy 70.046216 -173.220159) (xy 70.12705 -173.205053) (xy 70.208933 -173.19747) (xy 70.25005 -173.197012)
			(xy 70.29166 -173.197513) (xy 70.374516 -173.205285) (xy 70.456284 -173.220756) (xy 70.536252 -173.243791)
			(xy 70.613721 -173.274189) (xy 70.688014 -173.311686) (xy 70.723506 -173.33341) (xy 70.73264 -173.338581)
			(xy 70.753359 -173.341792) (xy 70.773635 -173.336456) (xy 70.78218 -173.330362) (xy 70.815836 -173.304408)
			(xy 70.887226 -173.258279) (xy 70.962691 -173.219173) (xy 71.041544 -173.187448) (xy 71.123065 -173.163392)
			(xy 71.20651 -173.147226) (xy 71.291116 -173.139097) (xy 71.333614 -173.138592) (xy 71.374727 -173.139099)
			(xy 71.456602 -173.146687) (xy 71.537428 -173.161797) (xy 71.616516 -173.1843) (xy 71.693189 -173.214003)
			(xy 71.703445 -173.21911) (xy 393.739116 -173.21911) (xy 393.739743 -173.172708) (xy 393.749432 -173.08041)
			(xy 393.768686 -172.989625) (xy 393.797294 -172.90134) (xy 393.81557 -172.858684) (xy 393.819371 -172.84874)
			(xy 393.819374 -172.827478) (xy 393.81557 -172.817536) (xy 393.797307 -172.774875) (xy 393.768715 -172.686587)
			(xy 393.749458 -172.595804) (xy 393.739745 -172.503511) (xy 393.739116 -172.45711) (xy 393.739622 -172.415997)
			(xy 393.747208 -172.33412) (xy 393.762316 -172.253293) (xy 393.784818 -172.174205) (xy 393.81452 -172.097531)
			(xy 393.851171 -172.023924) (xy 393.894457 -171.954012) (xy 393.944008 -171.888393) (xy 393.999403 -171.827626)
			(xy 394.060168 -171.772229) (xy 394.125786 -171.722675) (xy 394.195696 -171.679387) (xy 394.269301 -171.642733)
			(xy 394.345975 -171.613028) (xy 394.425062 -171.590524) (xy 394.505889 -171.575413) (xy 394.587765 -171.567824)
			(xy 394.628878 -171.567348) (xy 394.670013 -171.567796) (xy 394.75193 -171.575416) (xy 394.832794 -171.590566)
			(xy 394.911913 -171.613115) (xy 394.988614 -171.642872) (xy 395.06224 -171.679583) (xy 395.132163 -171.722933)
			(xy 395.197785 -171.772553) (xy 395.258547 -171.828019) (xy 395.313929 -171.888856) (xy 395.339062 -171.921424)
			(xy 395.345281 -171.928954) (xy 395.36201 -171.939002) (xy 395.371574 -171.940982) (xy 395.41286 -171.948033)
			(xy 395.493962 -171.968978) (xy 395.572736 -171.997455) (xy 395.648484 -172.033212) (xy 395.720535 -172.075931)
			(xy 395.78825 -172.125234) (xy 395.851031 -172.180685) (xy 395.908321 -172.241793) (xy 395.959613 -172.308015)
			(xy 396.004452 -172.378766) (xy 396.042441 -172.453419) (xy 396.073244 -172.531313) (xy 396.096588 -172.611757)
			(xy 396.112266 -172.69404) (xy 396.120139 -172.777432) (xy 396.12062 -172.819314) (xy 396.120152 -172.860082)
			(xy 396.112652 -172.941273) (xy 396.097752 -173.021436) (xy 396.075577 -173.099899) (xy 396.046313 -173.176003)
			(xy 396.028672 -173.21276) (xy 396.024359 -173.222451) (xy 396.023438 -173.243625) (xy 396.026894 -173.253654)
			(xy 396.041217 -173.292003) (xy 396.063564 -173.370761) (xy 396.07857 -173.451241) (xy 396.086111 -173.53276)
			(xy 396.086584 -173.573694) (xy 396.086007 -173.618463) (xy 396.077001 -173.707548) (xy 396.0591 -173.795279)
			(xy 396.032485 -173.880771) (xy 396.015464 -173.922182) (xy 396.011903 -173.931774) (xy 396.0119 -173.952215)
			(xy 396.015464 -173.961806) (xy 396.032477 -174.003153) (xy 396.059087 -174.088517) (xy 396.076991 -174.17612)
			(xy 396.08601 -174.265079) (xy 396.086584 -174.309786) (xy 396.086584 -174.310802) (xy 396.08633 -174.322232)
			(xy 396.112809 -174.328178) (xy 396.165044 -174.342921) (xy 396.190724 -174.351696) (xy 396.198921 -174.35421)
			(xy 396.216055 -174.35421) (xy 396.224252 -174.351696) (xy 396.259466 -174.339729) (xy 396.33147 -174.321076)
			(xy 396.404792 -174.308569) (xy 396.478908 -174.302297) (xy 396.516098 -174.301912) (xy 396.553288 -174.302301)
			(xy 396.627401 -174.30859) (xy 396.70072 -174.3211) (xy 396.772726 -174.339741) (xy 396.807944 -174.351696)
			(xy 396.816141 -174.35421) (xy 396.833275 -174.35421) (xy 396.841472 -174.351696) (xy 396.876685 -174.339723)
			(xy 396.948689 -174.321072) (xy 397.022011 -174.308567) (xy 397.096127 -174.302297) (xy 397.133318 -174.301912)
			(xy 397.175254 -174.302444) (xy 397.258746 -174.310418) (xy 397.341102 -174.326292) (xy 397.421577 -174.349923)
			(xy 397.49944 -174.381096) (xy 397.573988 -174.41953) (xy 397.644545 -174.464875) (xy 397.710473 -174.516722)
			(xy 397.771173 -174.574601) (xy 397.826097 -174.637988) (xy 397.874747 -174.706309) (xy 397.916683 -174.778944)
			(xy 397.951524 -174.855237) (xy 397.978955 -174.934497) (xy 397.998729 -175.016005) (xy 398.010665 -175.099023)
			(xy 398.014656 -175.1828) (xy 398.010665 -175.266577) (xy 397.998729 -175.349595) (xy 397.978955 -175.431103)
			(xy 397.951524 -175.510363) (xy 397.916683 -175.586656) (xy 397.874747 -175.659291) (xy 397.826097 -175.727612)
			(xy 397.771173 -175.790999) (xy 397.710473 -175.848878) (xy 397.644545 -175.900725) (xy 397.573988 -175.94607)
			(xy 397.49944 -175.984504) (xy 397.421577 -176.015677) (xy 397.341102 -176.039308) (xy 397.258746 -176.055182)
			(xy 397.175254 -176.063156) (xy 397.133318 -176.063656) (xy 397.096129 -176.063259) (xy 397.022016 -176.056971)
			(xy 396.948696 -176.044464) (xy 396.87669 -176.025825) (xy 396.841472 -176.013872) (xy 396.833275 -176.011358)
			(xy 396.816141 -176.011358) (xy 396.807944 -176.013872) (xy 396.778999 -176.023726) (xy 396.720017 -176.039869)
			(xy 396.690088 -176.04613) (xy 396.680511 -176.048515) (xy 396.664071 -176.059402) (xy 396.652972 -176.0757)
			(xy 396.650464 -176.085246) (xy 396.640294 -176.12901) (xy 396.612299 -176.21439) (xy 396.594584 -176.25568)
			(xy 396.590807 -176.265631) (xy 396.590789 -176.286886) (xy 396.594584 -176.296828) (xy 396.612789 -176.339438)
			(xy 396.641312 -176.427603) (xy 396.660509 -176.518256) (xy 396.670174 -176.610414) (xy 396.670784 -176.656746)
			(xy 396.670784 -176.657254) (xy 396.67028 -176.699602) (xy 396.662229 -176.783916) (xy 396.6462 -176.867082)
			(xy 396.622339 -176.948349) (xy 396.59086 -177.026979) (xy 396.552049 -177.10226) (xy 396.506259 -177.173512)
			(xy 396.453903 -177.240088) (xy 396.395455 -177.301386) (xy 396.331445 -177.356851) (xy 396.262453 -177.40598)
			(xy 396.189103 -177.448329) (xy 396.11206 -177.483513) (xy 396.032021 -177.511215) (xy 395.949712 -177.531183)
			(xy 395.865877 -177.543236) (xy 395.781276 -177.547267) (xy 395.696675 -177.543236) (xy 395.61284 -177.531183)
			(xy 395.530531 -177.511215) (xy 395.450492 -177.483513) (xy 395.373449 -177.448329) (xy 395.300099 -177.40598)
			(xy 395.231107 -177.356851) (xy 395.167097 -177.301386) (xy 395.108649 -177.240088) (xy 395.056293 -177.173512)
			(xy 395.010503 -177.10226) (xy 394.971692 -177.026979) (xy 394.940213 -176.948349) (xy 394.916352 -176.867082)
			(xy 394.900323 -176.783916) (xy 394.892272 -176.699602) (xy 394.891768 -176.657254) (xy 394.891768 -176.656746)
			(xy 394.892395 -176.610415) (xy 394.902061 -176.518257) (xy 394.92125 -176.427603) (xy 394.949756 -176.339434)
			(xy 394.967968 -176.296828) (xy 394.971802 -176.286894) (xy 394.971784 -176.265622) (xy 394.967968 -176.25568)
			(xy 394.949707 -176.213025) (xy 394.921167 -176.12473) (xy 394.901979 -176.033943) (xy 394.89235 -175.941651)
			(xy 394.891768 -175.895254) (xy 394.89209 -175.858508) (xy 394.898067 -175.785262) (xy 394.903706 -175.74895)
			(xy 394.905149 -175.737024) (xy 394.898112 -175.714088) (xy 394.890244 -175.705008) (xy 394.824966 -175.637698)
			(xy 394.80236 -175.629824) (xy 394.790168 -175.631602) (xy 394.748357 -175.636737) (xy 394.664175 -175.639973)
			(xy 394.580064 -175.635239) (xy 394.496776 -175.622575) (xy 394.415059 -175.602096) (xy 394.335643 -175.573985)
			(xy 394.259239 -175.538493) (xy 394.186532 -175.495939) (xy 394.118173 -175.446704) (xy 394.054773 -175.391227)
			(xy 393.996901 -175.330007) (xy 393.945075 -175.26359) (xy 393.899757 -175.192573) (xy 393.861356 -175.11759)
			(xy 393.830213 -175.039313) (xy 393.806608 -174.958443) (xy 393.790753 -174.875704) (xy 393.782789 -174.791836)
			(xy 393.782296 -174.749714) (xy 393.782793 -174.706976) (xy 393.790968 -174.621894) (xy 393.807264 -174.537986)
			(xy 393.831529 -174.456028) (xy 393.847066 -174.416212) (xy 393.850705 -174.406179) (xy 393.85003 -174.384863)
			(xy 393.845796 -174.375064) (xy 393.828734 -174.338786) (xy 393.800425 -174.263775) (xy 393.778984 -174.18652)
			(xy 393.764586 -174.107649) (xy 393.757348 -174.027801) (xy 393.756896 -173.987714) (xy 393.757452 -173.943459)
			(xy 393.766275 -173.855391) (xy 393.783795 -173.768633) (xy 393.809839 -173.684042) (xy 393.826492 -173.643036)
			(xy 393.830085 -173.632871) (xy 393.829579 -173.611348) (xy 393.825476 -173.60138) (xy 393.808875 -173.565511)
			(xy 393.781358 -173.491412) (xy 393.760529 -173.415162) (xy 393.746554 -173.337364) (xy 393.739543 -173.258632)
			(xy 393.739116 -173.21911) (xy 71.703445 -173.21911) (xy 71.766795 -173.250654) (xy 71.836706 -173.29394)
			(xy 71.902324 -173.343492) (xy 71.963091 -173.398886) (xy 72.018488 -173.459651) (xy 72.068042 -173.525268)
			(xy 72.11133 -173.595177) (xy 72.147984 -173.668781) (xy 72.17769 -173.745454) (xy 72.200196 -173.82454)
			(xy 72.215308 -173.905366) (xy 72.222899 -173.987241) (xy 72.223376 -174.028354) (xy 72.22282 -174.073124)
			(xy 72.213808 -174.162209) (xy 72.195901 -174.24994) (xy 72.16928 -174.335431) (xy 72.152256 -174.376842)
			(xy 72.148718 -174.38644) (xy 72.148701 -174.406876) (xy 72.152256 -174.416466) (xy 72.169272 -174.457846)
			(xy 72.195896 -174.543271) (xy 72.213802 -174.630939) (xy 72.222811 -174.719961) (xy 72.223376 -174.7647)
			(xy 72.223376 -174.765208) (xy 72.223122 -174.77867) (xy 72.249601 -174.784615) (xy 72.301836 -174.799358)
			(xy 72.327516 -174.808134) (xy 72.335713 -174.810648) (xy 72.352847 -174.810648) (xy 72.361044 -174.808134)
			(xy 72.39626 -174.796188) (xy 72.46827 -174.777601) (xy 72.541593 -174.765161) (xy 72.615704 -174.758956)
			(xy 72.65289 -174.758604) (xy 72.690074 -174.75897) (xy 72.764182 -174.765192) (xy 72.837502 -174.777635)
			(xy 72.909513 -174.796211) (xy 72.944736 -174.808134) (xy 72.952933 -174.810648) (xy 72.970067 -174.810648)
			(xy 72.978264 -174.808134) (xy 73.013366 -174.796247) (xy 73.085122 -174.777697) (xy 73.158185 -174.765251)
			(xy 73.232036 -174.758997) (xy 73.269094 -174.758604) (xy 73.27011 -174.758604) (xy 73.312036 -174.759059)
			(xy 73.395508 -174.767031) (xy 73.477845 -174.7829) (xy 73.5583 -174.806525) (xy 73.636145 -174.83769)
			(xy 73.710676 -174.876114) (xy 73.781216 -174.921448) (xy 73.847128 -174.973283) (xy 73.907814 -175.031148)
			(xy 73.962725 -175.094519) (xy 74.011364 -175.162823) (xy 74.053289 -175.235441) (xy 74.088123 -175.311716)
			(xy 74.115548 -175.390956) (xy 74.135316 -175.472444) (xy 74.14725 -175.555443) (xy 74.15124 -175.6392)
			(xy 74.14725 -175.722957) (xy 74.135316 -175.805956) (xy 74.115548 -175.887444) (xy 74.088123 -175.966684)
			(xy 74.053289 -176.042959) (xy 74.01685 -176.106074) (xy 102.855268 -176.106074) (xy 102.855838 -176.061305)
			(xy 102.864847 -175.97222) (xy 102.882749 -175.884489) (xy 102.909366 -175.798997) (xy 102.926388 -175.757586)
			(xy 102.92997 -175.748) (xy 102.92996 -175.727553) (xy 102.926388 -175.717962) (xy 102.90934 -175.67656)
			(xy 102.882709 -175.59107) (xy 102.864808 -175.503335) (xy 102.855818 -175.414245) (xy 102.855268 -175.369474)
			(xy 102.855838 -175.324705) (xy 102.864847 -175.23562) (xy 102.882749 -175.147889) (xy 102.909366 -175.062397)
			(xy 102.926388 -175.020986) (xy 102.92997 -175.0114) (xy 102.92996 -174.990953) (xy 102.926388 -174.981362)
			(xy 102.90934 -174.93996) (xy 102.882709 -174.85447) (xy 102.864808 -174.766735) (xy 102.855818 -174.677645)
			(xy 102.855268 -174.632874) (xy 102.855674 -174.591758) (xy 102.863264 -174.509876) (xy 102.878376 -174.429045)
			(xy 102.900882 -174.349952) (xy 102.930591 -174.273273) (xy 102.967247 -174.199663) (xy 103.010539 -174.129749)
			(xy 103.060097 -174.064128) (xy 103.115499 -174.003359) (xy 103.176271 -173.947961) (xy 103.241895 -173.898407)
			(xy 103.311812 -173.85512) (xy 103.385425 -173.818468) (xy 103.462105 -173.788765) (xy 103.541199 -173.766263)
			(xy 103.622032 -173.751156) (xy 103.703914 -173.743571) (xy 103.74503 -173.743112) (xy 103.786641 -173.743573)
			(xy 103.869498 -173.751353) (xy 103.951267 -173.766831) (xy 104.031235 -173.789874) (xy 104.108703 -173.820279)
			(xy 104.182995 -173.857782) (xy 104.218486 -173.87951) (xy 104.227629 -173.884663) (xy 104.248342 -173.88788)
			(xy 104.268614 -173.882552) (xy 104.27716 -173.876462) (xy 104.310789 -173.850471) (xy 104.382183 -173.804346)
			(xy 104.457654 -173.765245) (xy 104.536512 -173.733524) (xy 104.618037 -173.709475) (xy 104.701485 -173.693315)
			(xy 104.786095 -173.685193) (xy 104.828594 -173.684692) (xy 104.869707 -173.685219) (xy 104.951582 -173.692805)
			(xy 105.032407 -173.707913) (xy 105.111494 -173.730413) (xy 105.188168 -173.760115) (xy 105.261774 -173.796765)
			(xy 105.331684 -173.84005) (xy 105.397303 -173.8896) (xy 105.45807 -173.944993) (xy 105.513467 -174.005757)
			(xy 105.563021 -174.071373) (xy 105.60631 -174.141281) (xy 105.642964 -174.214885) (xy 105.67267 -174.291556)
			(xy 105.695176 -174.370642) (xy 105.710288 -174.451467) (xy 105.717879 -174.533341) (xy 105.718356 -174.574454)
			(xy 105.717793 -174.619224) (xy 105.708783 -174.708309) (xy 105.690877 -174.79604) (xy 105.664259 -174.881531)
			(xy 105.647236 -174.922942) (xy 105.643699 -174.932541) (xy 105.643682 -174.952976) (xy 105.647236 -174.962566)
			(xy 105.66424 -175.003917) (xy 105.690851 -175.089279) (xy 105.708758 -175.176882) (xy 105.71778 -175.265839)
			(xy 105.718356 -175.310546) (xy 105.718356 -175.311562) (xy 105.718102 -175.322992) (xy 105.744581 -175.328938)
			(xy 105.796816 -175.343681) (xy 105.822496 -175.352456) (xy 105.830693 -175.35497) (xy 105.847827 -175.35497)
			(xy 105.856024 -175.352456) (xy 105.89124 -175.340495) (xy 105.963244 -175.321841) (xy 106.036565 -175.309332)
			(xy 106.11068 -175.303059) (xy 106.14787 -175.302672) (xy 106.185059 -175.303071) (xy 106.259172 -175.309358)
			(xy 106.332492 -175.321865) (xy 106.404498 -175.340503) (xy 106.439716 -175.352456) (xy 106.447913 -175.35497)
			(xy 106.465047 -175.35497) (xy 106.473244 -175.352456) (xy 106.508459 -175.340489) (xy 106.580462 -175.321837)
			(xy 106.653784 -175.30933) (xy 106.7279 -175.303058) (xy 106.76509 -175.302672) (xy 106.80703 -175.303067)
			(xy 106.890532 -175.311039) (xy 106.972897 -175.326913) (xy 107.05338 -175.350544) (xy 107.131253 -175.381719)
			(xy 107.20581 -175.420155) (xy 107.276375 -175.465504) (xy 107.34231 -175.517355) (xy 107.403018 -175.575239)
			(xy 107.457949 -175.638632) (xy 107.505577 -175.705516) (xy 359.713276 -175.705516) (xy 359.713826 -175.660746)
			(xy 359.72284 -175.571661) (xy 359.740749 -175.48393) (xy 359.767371 -175.398439) (xy 359.784396 -175.357028)
			(xy 359.787954 -175.347435) (xy 359.78796 -175.326994) (xy 359.784396 -175.317404) (xy 359.767362 -175.275997)
			(xy 359.740727 -175.190508) (xy 359.722822 -175.102775) (xy 359.713828 -175.013687) (xy 359.713276 -174.968916)
			(xy 359.713826 -174.924146) (xy 359.72284 -174.835061) (xy 359.740749 -174.74733) (xy 359.767371 -174.661839)
			(xy 359.784396 -174.620428) (xy 359.787954 -174.610835) (xy 359.78796 -174.590394) (xy 359.784396 -174.580804)
			(xy 359.767362 -174.539397) (xy 359.740727 -174.453908) (xy 359.722822 -174.366175) (xy 359.713828 -174.277087)
			(xy 359.713276 -174.232316) (xy 359.713768 -174.191206) (xy 359.721354 -174.109337) (xy 359.736463 -174.028517)
			(xy 359.758966 -173.949437) (xy 359.788671 -173.872771) (xy 359.825324 -173.799173) (xy 359.868613 -173.729272)
			(xy 359.918168 -173.663664) (xy 359.973567 -173.602909) (xy 360.034335 -173.547526) (xy 360.099955 -173.497988)
			(xy 360.169867 -173.454716) (xy 360.243474 -173.418081) (xy 360.320148 -173.388396) (xy 360.399234 -173.365912)
			(xy 360.480057 -173.350823) (xy 360.561928 -173.343257) (xy 360.603038 -173.342808) (xy 360.644642 -173.343279)
			(xy 360.72749 -173.351011) (xy 360.809255 -173.366441) (xy 360.889223 -173.389435) (xy 360.966695 -173.419793)
			(xy 361.040997 -173.457248) (xy 361.076494 -173.478952) (xy 361.08563 -173.48412) (xy 361.106349 -173.487339)
			(xy 361.126625 -173.482001) (xy 361.135168 -173.475904) (xy 361.168794 -173.449952) (xy 361.240172 -173.403895)
			(xy 361.315615 -173.364851) (xy 361.394436 -173.333176) (xy 361.475917 -173.309157) (xy 361.559316 -173.293014)
			(xy 361.643874 -173.284894) (xy 361.686348 -173.284388) (xy 361.686602 -173.284388) (xy 361.72771 -173.284811)
			(xy 361.809576 -173.292396) (xy 361.890393 -173.307501) (xy 361.969472 -173.329998) (xy 362.046138 -173.359694)
			(xy 362.119738 -173.396336) (xy 362.189643 -173.439612) (xy 362.255258 -173.489152) (xy 362.316023 -173.544534)
			(xy 362.371419 -173.605287) (xy 362.420974 -173.67089) (xy 362.464266 -173.740786) (xy 362.500925 -173.814377)
			(xy 362.530638 -173.891036) (xy 362.553153 -173.97011) (xy 362.568276 -174.050924) (xy 362.57588 -174.132788)
			(xy 362.576364 -174.173896) (xy 362.575781 -174.218665) (xy 362.566776 -174.307749) (xy 362.548877 -174.395481)
			(xy 362.522264 -174.480972) (xy 362.505244 -174.522384) (xy 362.501683 -174.531976) (xy 362.501681 -174.552417)
			(xy 362.505244 -174.562008) (xy 362.522284 -174.603413) (xy 362.548917 -174.688902) (xy 362.56682 -174.776636)
			(xy 362.575812 -174.865725) (xy 362.576364 -174.910496) (xy 362.575094 -174.953676) (xy 362.575044 -174.965402)
			(xy 362.584373 -174.986895) (xy 362.602231 -175.002063) (xy 362.613448 -175.005492) (xy 362.632331 -175.010413)
			(xy 362.669682 -175.021721) (xy 362.688124 -175.028098) (xy 362.696321 -175.030612) (xy 362.713455 -175.030612)
			(xy 362.721652 -175.028098) (xy 362.756876 -175.016176) (xy 362.828883 -174.997583) (xy 362.902204 -174.985136)
			(xy 362.976313 -174.978924) (xy 363.013498 -174.978568) (xy 363.050682 -174.978934) (xy 363.12479 -174.985156)
			(xy 363.19811 -174.997599) (xy 363.270121 -175.016175) (xy 363.305344 -175.028098) (xy 363.313541 -175.030612)
			(xy 363.330675 -175.030612) (xy 363.338872 -175.028098) (xy 363.373974 -175.016212) (xy 363.44573 -174.997661)
			(xy 363.518793 -174.985214) (xy 363.592644 -174.978961) (xy 363.629702 -174.978568) (xy 363.630718 -174.978568)
			(xy 363.672642 -174.979095) (xy 363.75611 -174.987067) (xy 363.838443 -175.002937) (xy 363.918894 -175.026561)
			(xy 363.996736 -175.057726) (xy 364.071262 -175.096148) (xy 364.141799 -175.141481) (xy 364.207708 -175.193313)
			(xy 364.268391 -175.251175) (xy 364.323299 -175.314544) (xy 364.371935 -175.382845) (xy 364.413859 -175.45546)
			(xy 364.44869 -175.531731) (xy 364.476114 -175.610968) (xy 364.495881 -175.692452) (xy 364.507814 -175.775447)
			(xy 364.511804 -175.8592) (xy 364.507814 -175.942953) (xy 364.495881 -176.025948) (xy 364.476114 -176.107432)
			(xy 364.44869 -176.186669) (xy 364.413859 -176.26294) (xy 364.371935 -176.335555) (xy 364.323299 -176.403856)
			(xy 364.268391 -176.467225) (xy 364.207708 -176.525087) (xy 364.141799 -176.576919) (xy 364.071262 -176.622252)
			(xy 363.996736 -176.660674) (xy 363.918894 -176.691839) (xy 363.838443 -176.715463) (xy 363.75611 -176.731333)
			(xy 363.672642 -176.739305) (xy 363.630718 -176.739804) (xy 363.629702 -176.739804) (xy 363.592645 -176.739398)
			(xy 363.518796 -176.733134) (xy 363.445733 -176.720692) (xy 363.373973 -176.70216) (xy 363.338872 -176.690274)
			(xy 363.330675 -176.68776) (xy 363.313541 -176.68776) (xy 363.305344 -176.690274) (xy 363.271298 -176.701763)
			(xy 363.201741 -176.719817) (xy 363.166406 -176.726342) (xy 363.157048 -176.728326) (xy 363.140733 -176.738296)
			(xy 363.129218 -176.75356) (xy 363.126274 -176.762664) (xy 363.118487 -176.78918) (xy 363.100057 -176.841287)
			(xy 363.089444 -176.866804) (xy 363.085871 -176.876392) (xy 363.085877 -176.896837) (xy 363.089444 -176.906428)
			(xy 363.106465 -176.947806) (xy 363.133084 -177.033233) (xy 363.150988 -177.120901) (xy 363.159998 -177.209923)
			(xy 363.160564 -177.254662) (xy 363.160564 -177.254916) (xy 363.16006 -177.297264) (xy 363.152009 -177.381578)
			(xy 363.13598 -177.464744) (xy 363.112119 -177.546011) (xy 363.08064 -177.624641) (xy 363.041829 -177.699922)
			(xy 362.996039 -177.771174) (xy 362.943683 -177.83775) (xy 362.885235 -177.899048) (xy 362.821225 -177.954513)
			(xy 362.752233 -178.003642) (xy 362.678883 -178.045991) (xy 362.60184 -178.081175) (xy 362.521801 -178.108877)
			(xy 362.439492 -178.128845) (xy 362.355657 -178.140898) (xy 362.271056 -178.144929) (xy 362.186455 -178.140898)
			(xy 362.10262 -178.128845) (xy 362.020311 -178.108877) (xy 361.940272 -178.081175) (xy 361.863229 -178.045991)
			(xy 361.789879 -178.003642) (xy 361.720887 -177.954513) (xy 361.656877 -177.899048) (xy 361.598429 -177.83775)
			(xy 361.546073 -177.771174) (xy 361.500283 -177.699922) (xy 361.461472 -177.624641) (xy 361.429993 -177.546011)
			(xy 361.406132 -177.464744) (xy 361.390103 -177.381578) (xy 361.382052 -177.297264) (xy 361.381548 -177.254916)
			(xy 361.381548 -177.254662) (xy 361.382124 -177.209924) (xy 361.391138 -177.120903) (xy 361.409041 -177.033235)
			(xy 361.435651 -176.947807) (xy 361.452668 -176.906428) (xy 361.456222 -176.896834) (xy 361.456228 -176.876395)
			(xy 361.452668 -176.866804) (xy 361.435658 -176.825422) (xy 361.409036 -176.739997) (xy 361.391129 -176.65233)
			(xy 361.382115 -176.563308) (xy 361.381548 -176.51857) (xy 361.381548 -176.518316) (xy 361.38189 -176.482968)
			(xy 361.387504 -176.412495) (xy 361.39869 -176.34269) (xy 361.406694 -176.308258) (xy 361.409002 -176.295757)
			(xy 361.402463 -176.271224) (xy 361.394248 -176.261522) (xy 361.353608 -176.218596) (xy 361.34421 -176.220628)
			(xy 361.335443 -176.222892) (xy 361.32021 -176.232657) (xy 361.314492 -176.239678) (xy 361.289344 -176.272353)
			(xy 361.233931 -176.333418) (xy 361.173106 -176.389094) (xy 361.10739 -176.438902) (xy 361.037347 -176.482416)
			(xy 360.963578 -176.519263) (xy 360.886716 -176.549126) (xy 360.807421 -176.571748) (xy 360.726373 -176.586937)
			(xy 360.644268 -176.594561) (xy 360.603038 -176.595024) (xy 360.561931 -176.594551) (xy 360.480067 -176.58697)
			(xy 360.399251 -176.571868) (xy 360.320173 -176.549375) (xy 360.243508 -176.519683) (xy 360.169909 -176.483044)
			(xy 360.100004 -176.439772) (xy 360.034389 -176.390235) (xy 359.973624 -176.334856) (xy 359.918228 -176.274107)
			(xy 359.868672 -176.208506) (xy 359.825379 -176.138613) (xy 359.78872 -176.065025) (xy 359.759005 -175.988368)
			(xy 359.73649 -175.909296) (xy 359.721365 -175.828485) (xy 359.713761 -175.746623) (xy 359.713276 -175.705516)
			(xy 107.505577 -175.705516) (xy 107.506605 -175.706959) (xy 107.548546 -175.779602) (xy 107.583391 -175.855903)
			(xy 107.610826 -175.93517) (xy 107.630602 -176.016687) (xy 107.64254 -176.099714) (xy 107.646531 -176.1835)
			(xy 107.64254 -176.267286) (xy 107.630602 -176.350313) (xy 107.610826 -176.43183) (xy 107.583391 -176.511097)
			(xy 107.548546 -176.587398) (xy 107.506605 -176.660041) (xy 107.457949 -176.728368) (xy 107.403018 -176.791761)
			(xy 107.34231 -176.849645) (xy 107.276375 -176.901496) (xy 107.20581 -176.946845) (xy 107.131253 -176.985281)
			(xy 107.05338 -177.016456) (xy 106.972897 -177.040087) (xy 106.890532 -177.055961) (xy 106.80703 -177.063933)
			(xy 106.76509 -177.064416) (xy 106.7279 -177.064029) (xy 106.653787 -177.057739) (xy 106.580468 -177.045228)
			(xy 106.508462 -177.026587) (xy 106.473244 -177.014632) (xy 106.465047 -177.012118) (xy 106.447913 -177.012118)
			(xy 106.439716 -177.014632) (xy 106.394061 -177.029945) (xy 106.300252 -177.051713) (xy 106.252518 -177.058066)
			(xy 106.242041 -177.059824) (xy 106.223772 -177.070618) (xy 106.211473 -177.087908) (xy 106.20883 -177.098198)
			(xy 106.199325 -177.142161) (xy 106.1726 -177.22805) (xy 106.15549 -177.269648) (xy 106.151882 -177.279222)
			(xy 106.151736 -177.29966) (xy 106.155236 -177.309272) (xy 106.172271 -177.350645) (xy 106.198886 -177.436073)
			(xy 106.216787 -177.523743) (xy 106.225792 -177.612767) (xy 106.226356 -177.657506) (xy 106.226356 -177.65776)
			(xy 106.225852 -177.700108) (xy 106.217801 -177.784422) (xy 106.201772 -177.867588) (xy 106.177911 -177.948855)
			(xy 106.146432 -178.027485) (xy 106.107621 -178.102766) (xy 106.061831 -178.174018) (xy 106.009475 -178.240594)
			(xy 105.951027 -178.301892) (xy 105.887017 -178.357357) (xy 105.818025 -178.406486) (xy 105.744675 -178.448835)
			(xy 105.667632 -178.484019) (xy 105.587593 -178.511721) (xy 105.505284 -178.531689) (xy 105.421449 -178.543742)
			(xy 105.336848 -178.547773) (xy 105.252247 -178.543742) (xy 105.168412 -178.531689) (xy 105.086103 -178.511721)
			(xy 105.006064 -178.484019) (xy 104.929021 -178.448835) (xy 104.855671 -178.406486) (xy 104.786679 -178.357357)
			(xy 104.722669 -178.301892) (xy 104.664221 -178.240594) (xy 104.611865 -178.174018) (xy 104.566075 -178.102766)
			(xy 104.527264 -178.027485) (xy 104.495785 -177.948855) (xy 104.471924 -177.867588) (xy 104.455895 -177.784422)
			(xy 104.447844 -177.700108) (xy 104.44734 -177.65776) (xy 104.44734 -177.657506) (xy 104.447891 -177.612767)
			(xy 104.456911 -177.523745) (xy 104.474821 -177.436078) (xy 104.50144 -177.350651) (xy 104.51846 -177.309272)
			(xy 104.522047 -177.299688) (xy 104.522032 -177.279239) (xy 104.51846 -177.269648) (xy 104.501426 -177.228241)
			(xy 104.474794 -177.142752) (xy 104.456889 -177.055019) (xy 104.447894 -176.965931) (xy 104.44734 -176.92116)
			(xy 104.447594 -176.89703) (xy 104.44745 -176.887477) (xy 104.440882 -176.869548) (xy 104.428227 -176.855249)
			(xy 104.419908 -176.850548) (xy 104.33812 -176.808638) (xy 104.329507 -176.804642) (xy 104.310627 -176.802733)
			(xy 104.292347 -176.807824) (xy 104.284526 -176.81321) (xy 104.284526 -176.813464) (xy 104.284018 -176.813464)
			(xy 104.250823 -176.838169) (xy 104.180649 -176.882028) (xy 104.106709 -176.919187) (xy 104.029639 -176.949324)
			(xy 103.950105 -176.97218) (xy 103.868793 -176.987556) (xy 103.786406 -176.995321) (xy 103.74503 -176.995836)
			(xy 103.703915 -176.995373) (xy 103.622035 -176.987788) (xy 103.541204 -176.97268) (xy 103.462113 -176.950179)
			(xy 103.385435 -176.920475) (xy 103.311825 -176.883823) (xy 103.241911 -176.840535) (xy 103.176289 -176.790981)
			(xy 103.11552 -176.735583) (xy 103.060122 -176.674814) (xy 103.010567 -176.609193) (xy 102.967279 -176.539279)
			(xy 102.930626 -176.465669) (xy 102.900922 -176.388991) (xy 102.87842 -176.309899) (xy 102.863312 -176.229069)
			(xy 102.855727 -176.147189) (xy 102.855268 -176.106074) (xy 74.01685 -176.106074) (xy 74.011364 -176.115577)
			(xy 73.962725 -176.183881) (xy 73.907814 -176.247252) (xy 73.847128 -176.305117) (xy 73.781216 -176.356952)
			(xy 73.710676 -176.402286) (xy 73.636145 -176.44071) (xy 73.5583 -176.471875) (xy 73.477845 -176.4955)
			(xy 73.395508 -176.511369) (xy 73.312036 -176.519341) (xy 73.27011 -176.51984) (xy 73.269094 -176.51984)
			(xy 73.232037 -176.519434) (xy 73.158188 -176.51317) (xy 73.085125 -176.500728) (xy 73.013365 -176.482196)
			(xy 72.978264 -176.47031) (xy 72.970067 -176.467796) (xy 72.952933 -176.467796) (xy 72.944736 -176.47031)
			(xy 72.910756 -176.481853) (xy 72.841327 -176.500034) (xy 72.806052 -176.506632) (xy 72.796116 -176.508916)
			(xy 72.779041 -176.520017) (xy 72.767603 -176.536869) (xy 72.765158 -176.546764) (xy 72.755578 -176.591455)
			(xy 72.728473 -176.67875) (xy 72.711056 -176.721008) (xy 72.70748 -176.730595) (xy 72.707488 -176.751041)
			(xy 72.711056 -176.760632) (xy 72.728073 -176.802012) (xy 72.754694 -176.887437) (xy 72.7726 -176.975105)
			(xy 72.78161 -177.064127) (xy 72.782176 -177.108866) (xy 72.782176 -177.10912) (xy 72.781672 -177.151468)
			(xy 72.773621 -177.235782) (xy 72.757592 -177.318948) (xy 72.733731 -177.400215) (xy 72.702252 -177.478845)
			(xy 72.663441 -177.554126) (xy 72.617651 -177.625378) (xy 72.565295 -177.691954) (xy 72.506847 -177.753252)
			(xy 72.442837 -177.808717) (xy 72.373845 -177.857846) (xy 72.300495 -177.900195) (xy 72.223452 -177.935379)
			(xy 72.143413 -177.963081) (xy 72.061104 -177.983049) (xy 71.977269 -177.995102) (xy 71.892668 -177.999133)
			(xy 71.808067 -177.995102) (xy 71.724232 -177.983049) (xy 71.641923 -177.963081) (xy 71.561884 -177.935379)
			(xy 71.484841 -177.900195) (xy 71.411491 -177.857846) (xy 71.342499 -177.808717) (xy 71.278489 -177.753252)
			(xy 71.220041 -177.691954) (xy 71.167685 -177.625378) (xy 71.121895 -177.554126) (xy 71.083084 -177.478845)
			(xy 71.051605 -177.400215) (xy 71.027744 -177.318948) (xy 71.011715 -177.235782) (xy 71.003664 -177.151468)
			(xy 71.00316 -177.10912) (xy 71.00316 -177.108866) (xy 71.003737 -177.064128) (xy 71.01275 -176.975107)
			(xy 71.030653 -176.887439) (xy 71.057263 -176.802011) (xy 71.07428 -176.760632) (xy 71.077831 -176.751038)
			(xy 71.077839 -176.730599) (xy 71.07428 -176.721008) (xy 71.057235 -176.679605) (xy 71.030605 -176.594115)
			(xy 71.012704 -176.50638) (xy 71.003712 -176.417291) (xy 71.00316 -176.37252) (xy 71.003216 -176.357395)
			(xy 71.004231 -176.327162) (xy 71.005192 -176.312068) (xy 71.005427 -176.302019) (xy 70.999034 -176.282984)
			(xy 70.985815 -176.267867) (xy 70.976998 -176.263046) (xy 70.8787 -176.214532) (xy 70.84822 -176.218596)
			(xy 70.83679 -176.228756) (xy 70.806403 -176.254854) (xy 70.741691 -176.302073) (xy 70.672994 -176.343279)
			(xy 70.60087 -176.378141) (xy 70.525902 -176.406374) (xy 70.4487 -176.427751) (xy 70.369887 -176.442098)
			(xy 70.290104 -176.449298) (xy 70.25005 -176.449736) (xy 70.208935 -176.449254) (xy 70.127056 -176.441671)
			(xy 70.046226 -176.426565) (xy 69.967134 -176.404065) (xy 69.890456 -176.374363) (xy 69.816846 -176.337712)
			(xy 69.746932 -176.294426) (xy 69.68131 -176.244873) (xy 69.620541 -176.189476) (xy 69.565143 -176.128708)
			(xy 69.515588 -176.063088) (xy 69.472299 -175.993175) (xy 69.435647 -175.919566) (xy 69.405943 -175.842889)
			(xy 69.383441 -175.763798) (xy 69.368332 -175.682968) (xy 69.360747 -175.601089) (xy 69.360288 -175.559974)
			(xy 9.487916 -175.559974) (xy 9.487916 -175.848264) (xy 9.48743 -175.875515) (xy 9.479674 -175.929463)
			(xy 9.464319 -175.981758) (xy 9.441677 -176.031335) (xy 9.412211 -176.077185) (xy 9.37652 -176.118376)
			(xy 9.335329 -176.154067) (xy 9.289479 -176.183533) (xy 9.239902 -176.206175) (xy 9.187607 -176.22153)
			(xy 9.133659 -176.229286) (xy 9.079157 -176.229286) (xy 9.025209 -176.22153) (xy 8.972914 -176.206175)
			(xy 8.923337 -176.183533) (xy 8.877487 -176.154067) (xy 8.836296 -176.118376) (xy 8.800605 -176.077185)
			(xy 8.771139 -176.031335) (xy 8.748497 -175.981758) (xy 8.733142 -175.929463) (xy 8.725386 -175.875515)
			(xy 8.7249 -175.848264) (xy 2.509012 -175.848264) (xy 2.509012 -178.618388) (xy 8.7249 -178.618388)
			(xy 8.7249 -177.754788) (xy 8.725386 -177.727537) (xy 8.733142 -177.673589) (xy 8.748497 -177.621294)
			(xy 8.771139 -177.571717) (xy 8.800605 -177.525867) (xy 8.836296 -177.484676) (xy 8.877487 -177.448985)
			(xy 8.923337 -177.419519) (xy 8.972914 -177.396877) (xy 9.025209 -177.381522) (xy 9.079157 -177.373766)
			(xy 9.133659 -177.373766) (xy 9.187607 -177.381522) (xy 9.239902 -177.396877) (xy 9.289479 -177.419519)
			(xy 9.335329 -177.448985) (xy 9.37652 -177.484676) (xy 9.412211 -177.525867) (xy 9.441677 -177.571717)
			(xy 9.464319 -177.621294) (xy 9.479674 -177.673589) (xy 9.48743 -177.727537) (xy 9.487916 -177.754788)
			(xy 9.487916 -178.618388) (xy 9.48743 -178.645639) (xy 9.479674 -178.699587) (xy 9.464319 -178.751882)
			(xy 9.44304 -178.798474) (xy 77.963268 -178.798474) (xy 77.963886 -178.752072) (xy 77.973579 -178.659774)
			(xy 77.992835 -178.568989) (xy 78.021445 -178.480704) (xy 78.039722 -178.438048) (xy 78.043541 -178.42811)
			(xy 78.043531 -178.406843) (xy 78.039722 -178.3969) (xy 78.021451 -178.354243) (xy 77.99286 -178.265953)
			(xy 77.973605 -178.175169) (xy 77.963896 -178.082875) (xy 77.963268 -178.036474) (xy 77.963674 -177.995358)
			(xy 77.971264 -177.913476) (xy 77.986376 -177.832645) (xy 78.008882 -177.753552) (xy 78.038591 -177.676873)
			(xy 78.075247 -177.603263) (xy 78.118539 -177.533349) (xy 78.168097 -177.467728) (xy 78.223499 -177.406959)
			(xy 78.284271 -177.351561) (xy 78.349895 -177.302007) (xy 78.419812 -177.25872) (xy 78.493425 -177.222068)
			(xy 78.570105 -177.192365) (xy 78.649199 -177.169863) (xy 78.730032 -177.154756) (xy 78.811914 -177.147171)
			(xy 78.85303 -177.146712) (xy 78.893848 -177.147168) (xy 78.975141 -177.154659) (xy 79.055405 -177.169568)
			(xy 79.133966 -177.191768) (xy 79.210162 -177.221072) (xy 79.283352 -177.257234) (xy 79.352922 -177.29995)
			(xy 79.418285 -177.348861) (xy 79.478892 -177.403555) (xy 79.534233 -177.463571) (xy 79.559404 -177.495708)
			(xy 79.565179 -177.502627) (xy 79.580393 -177.512264) (xy 79.589122 -177.514504) (xy 79.631283 -177.524073)
			(xy 79.713687 -177.550242) (xy 79.793163 -177.584282) (xy 79.868962 -177.625872) (xy 79.940368 -177.67462)
			(xy 80.006708 -177.730066) (xy 80.067355 -177.791686) (xy 80.121738 -177.8589) (xy 80.169343 -177.931073)
			(xy 80.209721 -178.007525) (xy 80.242492 -178.087533) (xy 80.267345 -178.170343) (xy 80.284047 -178.255173)
			(xy 80.29244 -178.341224) (xy 80.292956 -178.384454) (xy 80.292766 -178.411062) (xy 80.289588 -178.464184)
			(xy 80.286606 -178.490626) (xy 80.285833 -178.501873) (xy 80.292962 -178.523233) (xy 80.300322 -178.531774)
			(xy 80.329261 -178.562798) (xy 80.381784 -178.629432) (xy 80.427728 -178.700761) (xy 80.466676 -178.776139)
			(xy 80.498274 -178.854881) (xy 80.522235 -178.936272) (xy 80.538342 -179.019574) (xy 80.546449 -179.104032)
			(xy 80.546956 -179.146454) (xy 80.546393 -179.191224) (xy 80.537383 -179.280309) (xy 80.519477 -179.36804)
			(xy 80.492859 -179.453531) (xy 80.475836 -179.494942) (xy 80.472299 -179.504541) (xy 80.472282 -179.524976)
			(xy 80.475836 -179.534566) (xy 80.49284 -179.575917) (xy 80.519451 -179.661279) (xy 80.537358 -179.748882)
			(xy 80.54638 -179.837839) (xy 80.546956 -179.882546) (xy 80.546956 -179.883562) (xy 80.546702 -179.894992)
			(xy 80.573181 -179.900938) (xy 80.625416 -179.915681) (xy 80.651096 -179.924456) (xy 80.659293 -179.92697)
			(xy 80.676427 -179.92697) (xy 80.684624 -179.924456) (xy 80.71984 -179.912495) (xy 80.791844 -179.893841)
			(xy 80.865165 -179.881332) (xy 80.93928 -179.875059) (xy 80.97647 -179.874672) (xy 81.013659 -179.875071)
			(xy 81.087772 -179.881358) (xy 81.161092 -179.893865) (xy 81.233098 -179.912503) (xy 81.268316 -179.924456)
			(xy 81.276513 -179.92697) (xy 81.293647 -179.92697) (xy 81.301844 -179.924456) (xy 81.337059 -179.912489)
			(xy 81.409062 -179.893837) (xy 81.482384 -179.88133) (xy 81.5565 -179.875058) (xy 81.59369 -179.874672)
			(xy 81.63563 -179.875067) (xy 81.719132 -179.883039) (xy 81.801497 -179.898913) (xy 81.88198 -179.922544)
			(xy 81.959853 -179.953719) (xy 82.03441 -179.992155) (xy 82.104975 -180.037504) (xy 82.17091 -180.089355)
			(xy 82.231618 -180.147239) (xy 82.286549 -180.210632) (xy 82.335205 -180.278959) (xy 82.377146 -180.351602)
			(xy 82.411991 -180.427903) (xy 82.439426 -180.50717) (xy 82.459202 -180.588687) (xy 82.462267 -180.610002)
			(xy 86.081108 -180.610002) (xy 86.081685 -180.565233) (xy 86.090691 -180.476148) (xy 86.108592 -180.388417)
			(xy 86.135207 -180.302925) (xy 86.152228 -180.261514) (xy 86.155792 -180.251923) (xy 86.155793 -180.231481)
			(xy 86.152228 -180.22189) (xy 86.135186 -180.180486) (xy 86.108554 -180.094996) (xy 86.090651 -180.007262)
			(xy 86.081659 -179.918173) (xy 86.081108 -179.873402) (xy 86.081685 -179.828633) (xy 86.090691 -179.739548)
			(xy 86.108592 -179.651817) (xy 86.135207 -179.566325) (xy 86.152228 -179.524914) (xy 86.155792 -179.515323)
			(xy 86.155793 -179.494881) (xy 86.152228 -179.48529) (xy 86.135186 -179.443886) (xy 86.108554 -179.358396)
			(xy 86.090651 -179.270662) (xy 86.081659 -179.181573) (xy 86.081108 -179.136802) (xy 86.081615 -179.095689)
			(xy 86.089201 -179.013813) (xy 86.10431 -178.932986) (xy 86.126812 -178.853898) (xy 86.156515 -178.777224)
			(xy 86.193165 -178.703617) (xy 86.236451 -178.633706) (xy 86.286003 -178.568087) (xy 86.341397 -178.50732)
			(xy 86.402163 -178.451923) (xy 86.46778 -178.402369) (xy 86.537689 -178.359081) (xy 86.611295 -178.322428)
			(xy 86.687968 -178.292722) (xy 86.767055 -178.270217) (xy 86.847881 -178.255106) (xy 86.929757 -178.247516)
			(xy 86.97087 -178.24704) (xy 87.01248 -178.247527) (xy 87.095336 -178.255301) (xy 87.177105 -178.270774)
			(xy 87.257073 -178.293812) (xy 87.334542 -178.324213) (xy 87.408835 -178.361712) (xy 87.444326 -178.383438)
			(xy 87.453453 -178.388623) (xy 87.474176 -178.391826) (xy 87.494454 -178.386485) (xy 87.503 -178.38039)
			(xy 87.536641 -178.354416) (xy 87.608034 -178.30829) (xy 87.683503 -178.269188) (xy 87.762359 -178.237466)
			(xy 87.843882 -178.213414) (xy 87.927328 -178.19725) (xy 88.011936 -178.189124) (xy 88.054434 -178.18862)
			(xy 88.095548 -178.18908) (xy 88.177426 -178.19667) (xy 88.258254 -178.211782) (xy 88.337343 -178.234287)
			(xy 88.414018 -178.263994) (xy 88.487625 -178.300648) (xy 88.557536 -178.343937) (xy 88.623155 -178.393491)
			(xy 88.683922 -178.448889) (xy 88.739319 -178.509657) (xy 88.788872 -178.575277) (xy 88.83216 -178.645189)
			(xy 88.868813 -178.718797) (xy 88.898518 -178.795473) (xy 88.921021 -178.874562) (xy 88.936132 -178.95539)
			(xy 88.94372 -179.037268) (xy 88.944196 -179.078382) (xy 88.943648 -179.123152) (xy 88.934633 -179.212238)
			(xy 88.916724 -179.299969) (xy 88.890101 -179.38546) (xy 88.873076 -179.42687) (xy 88.869521 -179.436464)
			(xy 88.869514 -179.456904) (xy 88.873076 -179.466494) (xy 88.890086 -179.507843) (xy 88.916696 -179.593206)
			(xy 88.934602 -179.680809) (xy 88.943621 -179.769767) (xy 88.944196 -179.814474) (xy 88.944196 -179.81549)
			(xy 88.943942 -179.82692) (xy 88.970422 -179.832862) (xy 89.022656 -179.847607) (xy 89.048336 -179.856384)
			(xy 89.056533 -179.858898) (xy 89.073667 -179.858898) (xy 89.081864 -179.856384) (xy 89.117077 -179.844413)
			(xy 89.189082 -179.825761) (xy 89.262404 -179.813256) (xy 89.33652 -179.806985) (xy 89.37371 -179.8066)
			(xy 89.4109 -179.806986) (xy 89.485013 -179.813277) (xy 89.558333 -179.825787) (xy 89.630338 -179.844429)
			(xy 89.665556 -179.856384) (xy 89.673753 -179.858898) (xy 89.690887 -179.858898) (xy 89.699084 -179.856384)
			(xy 89.734295 -179.844408) (xy 89.8063 -179.825757) (xy 89.879623 -179.813253) (xy 89.953739 -179.806984)
			(xy 89.99093 -179.8066) (xy 90.032865 -179.807156) (xy 90.116355 -179.815131) (xy 90.198709 -179.831006)
			(xy 90.279182 -179.854637) (xy 90.357043 -179.885811) (xy 90.431589 -179.924244) (xy 90.502144 -179.969589)
			(xy 90.56807 -180.021436) (xy 90.628768 -180.079314) (xy 90.683691 -180.1427) (xy 90.732339 -180.211019)
			(xy 90.774274 -180.283653) (xy 90.809114 -180.359944) (xy 90.836544 -180.439202) (xy 90.856317 -180.520708)
			(xy 90.868253 -180.603725) (xy 90.869375 -180.627274) (xy 94.473268 -180.627274) (xy 94.473838 -180.582505)
			(xy 94.482847 -180.49342) (xy 94.500749 -180.405689) (xy 94.527366 -180.320197) (xy 94.544388 -180.278786)
			(xy 94.54797 -180.2692) (xy 94.54796 -180.248753) (xy 94.544388 -180.239162) (xy 94.52734 -180.19776)
			(xy 94.500709 -180.11227) (xy 94.482808 -180.024535) (xy 94.473818 -179.935445) (xy 94.473268 -179.890674)
			(xy 94.473838 -179.845905) (xy 94.482847 -179.75682) (xy 94.500749 -179.669089) (xy 94.527366 -179.583597)
			(xy 94.544388 -179.542186) (xy 94.54797 -179.5326) (xy 94.54796 -179.512153) (xy 94.544388 -179.502562)
			(xy 94.52734 -179.46116) (xy 94.500709 -179.37567) (xy 94.482808 -179.287935) (xy 94.473818 -179.198845)
			(xy 94.473268 -179.154074) (xy 94.473674 -179.112958) (xy 94.481264 -179.031076) (xy 94.496376 -178.950245)
			(xy 94.518882 -178.871152) (xy 94.548591 -178.794473) (xy 94.585247 -178.720863) (xy 94.628539 -178.650949)
			(xy 94.678097 -178.585328) (xy 94.733499 -178.524559) (xy 94.794271 -178.469161) (xy 94.859895 -178.419607)
			(xy 94.929812 -178.37632) (xy 95.003425 -178.339668) (xy 95.080105 -178.309965) (xy 95.159199 -178.287463)
			(xy 95.240032 -178.272356) (xy 95.321914 -178.264771) (xy 95.36303 -178.264312) (xy 95.404641 -178.264773)
			(xy 95.487498 -178.272553) (xy 95.569267 -178.288031) (xy 95.649235 -178.311074) (xy 95.726703 -178.341479)
			(xy 95.800995 -178.378982) (xy 95.836486 -178.40071) (xy 95.845629 -178.405863) (xy 95.866342 -178.40908)
			(xy 95.886614 -178.403752) (xy 95.89516 -178.397662) (xy 95.928789 -178.371671) (xy 96.000183 -178.325546)
			(xy 96.075654 -178.286445) (xy 96.154512 -178.254724) (xy 96.236037 -178.230675) (xy 96.319485 -178.214515)
			(xy 96.404095 -178.206393) (xy 96.446594 -178.205892) (xy 96.487707 -178.206419) (xy 96.569582 -178.214005)
			(xy 96.650407 -178.229113) (xy 96.729494 -178.251613) (xy 96.806168 -178.281315) (xy 96.879774 -178.317965)
			(xy 96.949684 -178.36125) (xy 97.015303 -178.4108) (xy 97.07607 -178.466193) (xy 97.131467 -178.526957)
			(xy 97.181021 -178.592573) (xy 97.22431 -178.662481) (xy 97.260964 -178.736085) (xy 97.29067 -178.812756)
			(xy 97.313176 -178.891842) (xy 97.328288 -178.972667) (xy 97.335879 -179.054541) (xy 97.336356 -179.095654)
			(xy 97.335793 -179.140424) (xy 97.329275 -179.204874) (xy 368.074448 -179.204874) (xy 368.075006 -179.161932)
			(xy 368.083288 -179.076448) (xy 368.099773 -178.99216) (xy 368.124306 -178.909855) (xy 368.15666 -178.830297)
			(xy 368.196533 -178.75423) (xy 368.243554 -178.682361) (xy 368.297284 -178.615359) (xy 368.357224 -178.55385)
			(xy 368.422813 -178.498405) (xy 368.493443 -178.449542) (xy 368.568454 -178.407716) (xy 368.607594 -178.390042)
			(xy 368.615999 -178.385919) (xy 368.629281 -178.372745) (xy 368.633502 -178.364388) (xy 368.645948 -178.33721)
			(xy 368.64947 -178.328554) (xy 368.650638 -178.309919) (xy 368.648234 -178.300888) (xy 368.635415 -178.257999)
			(xy 368.617464 -178.170297) (xy 368.608423 -178.081234) (xy 368.607848 -178.036474) (xy 368.608352 -177.994113)
			(xy 368.616405 -177.909776) (xy 368.632439 -177.826586) (xy 368.656307 -177.745296) (xy 368.687795 -177.666644)
			(xy 368.726617 -177.591341) (xy 368.77242 -177.520069) (xy 368.824791 -177.453473) (xy 368.883256 -177.392158)
			(xy 368.947284 -177.336677) (xy 369.016296 -177.287534) (xy 369.089666 -177.245174) (xy 369.166731 -177.209979)
			(xy 369.246793 -177.18227) (xy 369.329126 -177.162296) (xy 369.412985 -177.150239) (xy 369.49761 -177.146208)
			(xy 369.582235 -177.150239) (xy 369.666094 -177.162296) (xy 369.748427 -177.18227) (xy 369.828489 -177.209979)
			(xy 369.905554 -177.245174) (xy 369.978924 -177.287534) (xy 370.047936 -177.336677) (xy 370.111964 -177.392158)
			(xy 370.170429 -177.453473) (xy 370.2228 -177.520069) (xy 370.268603 -177.591341) (xy 370.307425 -177.666644)
			(xy 370.338913 -177.745296) (xy 370.362781 -177.826586) (xy 370.378815 -177.909776) (xy 370.386868 -177.994113)
			(xy 370.387372 -178.036474) (xy 370.387372 -178.036728) (xy 370.386948 -178.075094) (xy 370.380306 -178.151538)
			(xy 370.367099 -178.227125) (xy 370.357654 -178.264312) (xy 370.35562 -178.273261) (xy 370.357441 -178.291512)
			(xy 370.365595 -178.307941) (xy 370.37903 -178.320427) (xy 370.387372 -178.324256) (xy 370.427603 -178.341379)
			(xy 370.50477 -178.382506) (xy 370.577528 -178.431007) (xy 370.645175 -178.486413) (xy 370.707059 -178.548191)
			(xy 370.762582 -178.615743) (xy 370.811207 -178.688417) (xy 370.852467 -178.765513) (xy 370.885962 -178.846285)
			(xy 370.911369 -178.929954) (xy 370.928442 -179.015713) (xy 370.937018 -179.102733) (xy 370.937536 -179.146454)
			(xy 370.936975 -179.191224) (xy 370.927964 -179.280309) (xy 370.910058 -179.36804) (xy 370.883439 -179.453531)
			(xy 370.866416 -179.494942) (xy 370.86288 -179.504541) (xy 370.862862 -179.524975) (xy 370.866416 -179.534566)
			(xy 370.883441 -179.575977) (xy 370.910078 -179.661464) (xy 370.927986 -179.749196) (xy 370.936982 -179.838284)
			(xy 370.937536 -179.883054) (xy 370.937282 -179.903882) (xy 370.937631 -179.91519) (xy 370.946776 -179.935848)
			(xy 370.963889 -179.950596) (xy 370.97462 -179.954174) (xy 370.989618 -179.95835) (xy 371.019344 -179.967623)
			(xy 371.034056 -179.972716) (xy 371.042253 -179.97523) (xy 371.059387 -179.97523) (xy 371.067584 -179.972716)
			(xy 371.102796 -179.960741) (xy 371.174801 -179.94209) (xy 371.248123 -179.929585) (xy 371.322239 -179.923316)
			(xy 371.35943 -179.922932) (xy 371.396619 -179.923339) (xy 371.470732 -179.929623) (xy 371.544052 -179.942128)
			(xy 371.616058 -179.960764) (xy 371.651276 -179.972716) (xy 371.659473 -179.97523) (xy 371.676607 -179.97523)
			(xy 371.684804 -179.972716) (xy 371.720023 -179.960763) (xy 371.792025 -179.942106) (xy 371.865345 -179.929595)
			(xy 371.93946 -179.923319) (xy 371.97665 -179.922932) (xy 372.01859 -179.923405) (xy 372.10209 -179.931374)
			(xy 372.184455 -179.947244) (xy 372.264938 -179.970872) (xy 372.34281 -180.002043) (xy 372.417367 -180.040476)
			(xy 372.487932 -180.085822) (xy 372.553868 -180.137671) (xy 372.614576 -180.195553) (xy 372.669507 -180.258944)
			(xy 372.718163 -180.327269) (xy 372.760105 -180.39991) (xy 372.794951 -180.476209) (xy 372.822386 -180.555475)
			(xy 372.842162 -180.63699) (xy 372.848069 -180.678074) (xy 376.477276 -180.678074) (xy 376.477846 -180.633305)
			(xy 376.486854 -180.54422) (xy 376.504757 -180.456489) (xy 376.531374 -180.370997) (xy 376.548396 -180.329586)
			(xy 376.551978 -180.32) (xy 376.551968 -180.299553) (xy 376.548396 -180.289962) (xy 376.531349 -180.24856)
			(xy 376.504717 -180.16307) (xy 376.486816 -180.075335) (xy 376.477826 -179.986245) (xy 376.477276 -179.941474)
			(xy 376.477846 -179.896705) (xy 376.486854 -179.80762) (xy 376.504757 -179.719889) (xy 376.531374 -179.634397)
			(xy 376.548396 -179.592986) (xy 376.551978 -179.5834) (xy 376.551968 -179.562953) (xy 376.548396 -179.553362)
			(xy 376.531349 -179.51196) (xy 376.504717 -179.42647) (xy 376.486816 -179.338735) (xy 376.477826 -179.249645)
			(xy 376.477276 -179.204874) (xy 376.477674 -179.163758) (xy 376.485264 -179.081876) (xy 376.500376 -179.001043)
			(xy 376.522883 -178.92195) (xy 376.552591 -178.845272) (xy 376.589248 -178.771661) (xy 376.632541 -178.701747)
			(xy 376.682099 -178.636125) (xy 376.737501 -178.575356) (xy 376.798274 -178.519958) (xy 376.863899 -178.470404)
			(xy 376.933817 -178.427117) (xy 377.00743 -178.390466) (xy 377.084111 -178.360763) (xy 377.163206 -178.338262)
			(xy 377.244039 -178.323155) (xy 377.325922 -178.315571) (xy 377.367038 -178.315112) (xy 377.408648 -178.315619)
			(xy 377.491503 -178.323389) (xy 377.573272 -178.338859) (xy 377.65324 -178.361894) (xy 377.730709 -178.392291)
			(xy 377.805002 -178.429786) (xy 377.840494 -178.45151) (xy 377.849633 -178.45667) (xy 377.870349 -178.459885)
			(xy 377.890623 -178.454554) (xy 377.899168 -178.448462) (xy 377.932829 -178.422514) (xy 378.004217 -178.376384)
			(xy 378.079682 -178.337278) (xy 378.158534 -178.305551) (xy 378.240054 -178.281495) (xy 378.323498 -178.265328)
			(xy 378.408104 -178.257198) (xy 378.450602 -178.256692) (xy 378.491715 -178.257211) (xy 378.57359 -178.264798)
			(xy 378.654416 -178.279906) (xy 378.733503 -178.302408) (xy 378.810176 -178.33211) (xy 378.883782 -178.368761)
			(xy 378.953693 -178.412046) (xy 379.019312 -178.461597) (xy 379.080078 -178.51699) (xy 379.135475 -178.577755)
			(xy 379.185029 -178.643371) (xy 379.228318 -178.713279) (xy 379.264972 -178.786883) (xy 379.294678 -178.863555)
			(xy 379.317184 -178.942641) (xy 379.332296 -179.023466) (xy 379.339887 -179.105341) (xy 379.340364 -179.146454)
			(xy 379.339801 -179.191224) (xy 379.330791 -179.280309) (xy 379.312886 -179.36804) (xy 379.286267 -179.453531)
			(xy 379.269244 -179.494942) (xy 379.265706 -179.50454) (xy 379.265689 -179.524976) (xy 379.269244 -179.534566)
			(xy 379.286249 -179.575917) (xy 379.31286 -179.661279) (xy 379.330766 -179.748882) (xy 379.339788 -179.837839)
			(xy 379.340364 -179.882546) (xy 379.340364 -179.883562) (xy 379.34011 -179.894992) (xy 379.366589 -179.900938)
			(xy 379.418824 -179.915681) (xy 379.444504 -179.924456) (xy 379.452701 -179.92697) (xy 379.469835 -179.92697)
			(xy 379.478032 -179.924456) (xy 379.513248 -179.912493) (xy 379.585251 -179.893839) (xy 379.658572 -179.881331)
			(xy 379.732688 -179.875058) (xy 379.769878 -179.874672) (xy 379.807067 -179.875069) (xy 379.88118 -179.881356)
			(xy 379.9545 -179.893864) (xy 380.026506 -179.912502) (xy 380.061724 -179.924456) (xy 380.069921 -179.92697)
			(xy 380.087055 -179.92697) (xy 380.095252 -179.924456) (xy 380.130466 -179.912487) (xy 380.20247 -179.893835)
			(xy 380.275792 -179.881329) (xy 380.349908 -179.875057) (xy 380.387098 -179.874672) (xy 380.429038 -179.875067)
			(xy 380.512539 -179.88304) (xy 380.594904 -179.898915) (xy 380.675386 -179.922546) (xy 380.753258 -179.953722)
			(xy 380.827814 -179.992158) (xy 380.898379 -180.037507) (xy 380.964314 -180.089358) (xy 381.025021 -180.147242)
			(xy 381.079951 -180.210635) (xy 381.128607 -180.278962) (xy 381.170547 -180.351604) (xy 381.205392 -180.427905)
			(xy 381.232827 -180.507172) (xy 381.252602 -180.588688) (xy 381.26454 -180.671715) (xy 381.264843 -180.678074)
			(xy 384.808476 -180.678074) (xy 384.809046 -180.633305) (xy 384.818054 -180.54422) (xy 384.835957 -180.456489)
			(xy 384.862574 -180.370997) (xy 384.879596 -180.329586) (xy 384.883178 -180.32) (xy 384.883168 -180.299553)
			(xy 384.879596 -180.289962) (xy 384.862549 -180.24856) (xy 384.835917 -180.16307) (xy 384.818016 -180.075335)
			(xy 384.809026 -179.986245) (xy 384.808476 -179.941474) (xy 384.809046 -179.896705) (xy 384.818054 -179.80762)
			(xy 384.835957 -179.719889) (xy 384.862574 -179.634397) (xy 384.879596 -179.592986) (xy 384.883178 -179.5834)
			(xy 384.883168 -179.562953) (xy 384.879596 -179.553362) (xy 384.862549 -179.51196) (xy 384.835917 -179.42647)
			(xy 384.818016 -179.338735) (xy 384.809026 -179.249645) (xy 384.808476 -179.204874) (xy 384.808874 -179.163758)
			(xy 384.816464 -179.081876) (xy 384.831576 -179.001043) (xy 384.854083 -178.92195) (xy 384.883791 -178.845272)
			(xy 384.920448 -178.771661) (xy 384.963741 -178.701747) (xy 385.013299 -178.636125) (xy 385.068701 -178.575356)
			(xy 385.129474 -178.519958) (xy 385.195099 -178.470404) (xy 385.265017 -178.427117) (xy 385.33863 -178.390466)
			(xy 385.415311 -178.360763) (xy 385.494406 -178.338262) (xy 385.575239 -178.323155) (xy 385.657122 -178.315571)
			(xy 385.698238 -178.315112) (xy 385.739848 -178.315619) (xy 385.822703 -178.323389) (xy 385.904472 -178.338859)
			(xy 385.98444 -178.361894) (xy 386.061909 -178.392291) (xy 386.136202 -178.429786) (xy 386.171694 -178.45151)
			(xy 386.180833 -178.45667) (xy 386.201549 -178.459885) (xy 386.221823 -178.454554) (xy 386.230368 -178.448462)
			(xy 386.264029 -178.422514) (xy 386.335417 -178.376384) (xy 386.410882 -178.337278) (xy 386.489734 -178.305551)
			(xy 386.571254 -178.281495) (xy 386.654698 -178.265328) (xy 386.739304 -178.257198) (xy 386.781802 -178.256692)
			(xy 386.822915 -178.257211) (xy 386.90479 -178.264798) (xy 386.985616 -178.279906) (xy 387.064703 -178.302408)
			(xy 387.141376 -178.33211) (xy 387.214982 -178.368761) (xy 387.284893 -178.412046) (xy 387.350512 -178.461597)
			(xy 387.411278 -178.51699) (xy 387.466675 -178.577755) (xy 387.516229 -178.643371) (xy 387.559518 -178.713279)
			(xy 387.596172 -178.786883) (xy 387.625878 -178.863555) (xy 387.648384 -178.942641) (xy 387.663496 -179.023466)
			(xy 387.671087 -179.105341) (xy 387.671564 -179.146454) (xy 387.671001 -179.191224) (xy 387.661991 -179.280309)
			(xy 387.644086 -179.36804) (xy 387.617467 -179.453531) (xy 387.600444 -179.494942) (xy 387.596906 -179.50454)
			(xy 387.596889 -179.524976) (xy 387.600444 -179.534566) (xy 387.617449 -179.575917) (xy 387.64406 -179.661279)
			(xy 387.661966 -179.748882) (xy 387.670988 -179.837839) (xy 387.671564 -179.882546) (xy 387.671564 -179.883562)
			(xy 387.67131 -179.894992) (xy 387.697789 -179.900938) (xy 387.750024 -179.915681) (xy 387.775704 -179.924456)
			(xy 387.783901 -179.92697) (xy 387.801035 -179.92697) (xy 387.809232 -179.924456) (xy 387.844448 -179.912493)
			(xy 387.916451 -179.893839) (xy 387.989772 -179.881331) (xy 388.063888 -179.875058) (xy 388.101078 -179.874672)
			(xy 388.138267 -179.875069) (xy 388.21238 -179.881356) (xy 388.2857 -179.893864) (xy 388.357706 -179.912502)
			(xy 388.392924 -179.924456) (xy 388.401121 -179.92697) (xy 388.418255 -179.92697) (xy 388.426452 -179.924456)
			(xy 388.461666 -179.912487) (xy 388.53367 -179.893835) (xy 388.606992 -179.881329) (xy 388.681108 -179.875057)
			(xy 388.718298 -179.874672) (xy 388.760238 -179.875067) (xy 388.843739 -179.88304) (xy 388.926104 -179.898915)
			(xy 389.006586 -179.922546) (xy 389.084458 -179.953722) (xy 389.159014 -179.992158) (xy 389.229579 -180.037507)
			(xy 389.295514 -180.089358) (xy 389.356221 -180.147242) (xy 389.411151 -180.210635) (xy 389.459807 -180.278962)
			(xy 389.501747 -180.351604) (xy 389.536592 -180.427905) (xy 389.564027 -180.507172) (xy 389.583802 -180.588688)
			(xy 389.59574 -180.671715) (xy 389.599731 -180.7555) (xy 389.59574 -180.839285) (xy 389.583802 -180.922312)
			(xy 389.564027 -181.003828) (xy 389.536592 -181.083095) (xy 389.501747 -181.159396) (xy 389.459807 -181.232038)
			(xy 389.411151 -181.300365) (xy 389.356221 -181.363758) (xy 389.295514 -181.421642) (xy 389.229579 -181.473493)
			(xy 389.159014 -181.518842) (xy 389.084458 -181.557278) (xy 389.006586 -181.588454) (xy 388.926104 -181.612085)
			(xy 388.843739 -181.62796) (xy 388.760238 -181.635933) (xy 388.718298 -181.636416) (xy 388.681108 -181.636027)
			(xy 388.606996 -181.629737) (xy 388.533676 -181.617227) (xy 388.46167 -181.598587) (xy 388.426452 -181.586632)
			(xy 388.418255 -181.584118) (xy 388.401121 -181.584118) (xy 388.392924 -181.586632) (xy 388.365208 -181.596078)
			(xy 388.308773 -181.611711) (xy 388.280148 -181.617874) (xy 388.270401 -181.620348) (xy 388.25379 -181.63165)
			(xy 388.242792 -181.648464) (xy 388.240524 -181.65826) (xy 388.231054 -181.705587) (xy 388.203179 -181.797995)
			(xy 388.184898 -181.842664) (xy 388.181281 -181.852235) (xy 388.18114 -181.872676) (xy 388.184644 -181.882288)
			(xy 388.201684 -181.923659) (xy 388.228298 -182.009088) (xy 388.246197 -182.096758) (xy 388.255201 -182.185783)
			(xy 388.255764 -182.230522) (xy 388.255764 -182.230776) (xy 388.25526 -182.273124) (xy 388.247209 -182.357438)
			(xy 388.23118 -182.440604) (xy 388.207319 -182.521871) (xy 388.17584 -182.600501) (xy 388.137029 -182.675782)
			(xy 388.091239 -182.747034) (xy 388.038883 -182.81361) (xy 387.980435 -182.874908) (xy 387.916425 -182.930373)
			(xy 387.847433 -182.979502) (xy 387.774083 -183.021851) (xy 387.69704 -183.057035) (xy 387.617001 -183.084737)
			(xy 387.534692 -183.104705) (xy 387.450857 -183.116758) (xy 387.366256 -183.120789) (xy 387.281655 -183.116758)
			(xy 387.19782 -183.104705) (xy 387.115511 -183.084737) (xy 387.035472 -183.057035) (xy 386.958429 -183.021851)
			(xy 386.885079 -182.979502) (xy 386.816087 -182.930373) (xy 386.752077 -182.874908) (xy 386.693629 -182.81361)
			(xy 386.641273 -182.747034) (xy 386.595483 -182.675782) (xy 386.556672 -182.600501) (xy 386.525193 -182.521871)
			(xy 386.501332 -182.440604) (xy 386.485303 -182.357438) (xy 386.477252 -182.273124) (xy 386.476748 -182.230776)
			(xy 386.476748 -182.230522) (xy 386.477311 -182.185784) (xy 386.486329 -182.096762) (xy 386.504235 -182.009095)
			(xy 386.53085 -181.923667) (xy 386.547868 -181.882288) (xy 386.551445 -181.872701) (xy 386.551436 -181.852255)
			(xy 386.547868 -181.842664) (xy 386.53084 -181.801254) (xy 386.504206 -181.715766) (xy 386.4863 -181.628034)
			(xy 386.477302 -181.538946) (xy 386.476748 -181.494176) (xy 386.477087 -181.458262) (xy 386.482864 -181.386666)
			(xy 386.494395 -181.315769) (xy 386.502656 -181.280816) (xy 386.504356 -181.272508) (xy 386.502799 -181.255633)
			(xy 386.495808 -181.240195) (xy 386.49021 -181.233826) (xy 386.44957 -181.1909) (xy 386.43941 -181.193186)
			(xy 386.430637 -181.195432) (xy 386.415405 -181.205208) (xy 386.409692 -181.212236) (xy 386.384552 -181.244927)
			(xy 386.329156 -181.306026) (xy 386.268343 -181.361734) (xy 386.202634 -181.411575) (xy 386.132593 -181.455119)
			(xy 386.058822 -181.491993) (xy 385.981955 -181.521881) (xy 385.902652 -181.544524) (xy 385.821593 -181.55973)
			(xy 385.739474 -181.567368) (xy 385.698238 -181.567836) (xy 385.657123 -181.567365) (xy 385.575243 -181.559781)
			(xy 385.494413 -181.544674) (xy 385.415321 -181.522173) (xy 385.338643 -181.49247) (xy 385.265033 -181.455819)
			(xy 385.195119 -181.412532) (xy 385.129497 -181.362978) (xy 385.068728 -181.30758) (xy 385.01333 -181.246812)
			(xy 384.963775 -181.181191) (xy 384.920487 -181.111277) (xy 384.883834 -181.037668) (xy 384.854131 -180.96099)
			(xy 384.831629 -180.881899) (xy 384.81652 -180.801068) (xy 384.808935 -180.719189) (xy 384.808476 -180.678074)
			(xy 381.264843 -180.678074) (xy 381.268531 -180.7555) (xy 381.26454 -180.839285) (xy 381.252602 -180.922312)
			(xy 381.232827 -181.003828) (xy 381.205392 -181.083095) (xy 381.170547 -181.159396) (xy 381.128607 -181.232038)
			(xy 381.079951 -181.300365) (xy 381.025021 -181.363758) (xy 380.964314 -181.421642) (xy 380.898379 -181.473493)
			(xy 380.827814 -181.518842) (xy 380.753258 -181.557278) (xy 380.675386 -181.588454) (xy 380.594904 -181.612085)
			(xy 380.512539 -181.62796) (xy 380.429038 -181.635933) (xy 380.387098 -181.636416) (xy 380.349908 -181.636027)
			(xy 380.275796 -181.629737) (xy 380.202476 -181.617227) (xy 380.13047 -181.598587) (xy 380.095252 -181.586632)
			(xy 380.087055 -181.584118) (xy 380.069921 -181.584118) (xy 380.061724 -181.586632) (xy 380.034008 -181.596078)
			(xy 379.977573 -181.611711) (xy 379.948948 -181.617874) (xy 379.939201 -181.620348) (xy 379.92259 -181.63165)
			(xy 379.911592 -181.648464) (xy 379.909324 -181.65826) (xy 379.899854 -181.705587) (xy 379.871979 -181.797995)
			(xy 379.853698 -181.842664) (xy 379.850081 -181.852235) (xy 379.84994 -181.872676) (xy 379.853444 -181.882288)
			(xy 379.870484 -181.923659) (xy 379.897098 -182.009088) (xy 379.914997 -182.096758) (xy 379.924001 -182.185783)
			(xy 379.924564 -182.230522) (xy 379.924564 -182.230776) (xy 379.92406 -182.273124) (xy 379.916009 -182.357438)
			(xy 379.89998 -182.440604) (xy 379.876119 -182.521871) (xy 379.84464 -182.600501) (xy 379.805829 -182.675782)
			(xy 379.760039 -182.747034) (xy 379.707683 -182.81361) (xy 379.649235 -182.874908) (xy 379.585225 -182.930373)
			(xy 379.516233 -182.979502) (xy 379.442883 -183.021851) (xy 379.36584 -183.057035) (xy 379.285801 -183.084737)
			(xy 379.203492 -183.104705) (xy 379.119657 -183.116758) (xy 379.035056 -183.120789) (xy 378.950455 -183.116758)
			(xy 378.86662 -183.104705) (xy 378.784311 -183.084737) (xy 378.704272 -183.057035) (xy 378.627229 -183.021851)
			(xy 378.553879 -182.979502) (xy 378.484887 -182.930373) (xy 378.420877 -182.874908) (xy 378.362429 -182.81361)
			(xy 378.310073 -182.747034) (xy 378.264283 -182.675782) (xy 378.225472 -182.600501) (xy 378.193993 -182.521871)
			(xy 378.170132 -182.440604) (xy 378.154103 -182.357438) (xy 378.146052 -182.273124) (xy 378.145548 -182.230776)
			(xy 378.145548 -182.230522) (xy 378.146111 -182.185784) (xy 378.155129 -182.096762) (xy 378.173035 -182.009095)
			(xy 378.19965 -181.923667) (xy 378.216668 -181.882288) (xy 378.220245 -181.872701) (xy 378.220236 -181.852255)
			(xy 378.216668 -181.842664) (xy 378.19964 -181.801254) (xy 378.173006 -181.715766) (xy 378.1551 -181.628034)
			(xy 378.146102 -181.538946) (xy 378.145548 -181.494176) (xy 378.145887 -181.458262) (xy 378.151664 -181.386666)
			(xy 378.163195 -181.315769) (xy 378.171456 -181.280816) (xy 378.173156 -181.272508) (xy 378.171599 -181.255633)
			(xy 378.164608 -181.240195) (xy 378.15901 -181.233826) (xy 378.11837 -181.1909) (xy 378.10821 -181.193186)
			(xy 378.099437 -181.195432) (xy 378.084205 -181.205208) (xy 378.078492 -181.212236) (xy 378.053352 -181.244927)
			(xy 377.997956 -181.306026) (xy 377.937143 -181.361734) (xy 377.871434 -181.411575) (xy 377.801393 -181.455119)
			(xy 377.727622 -181.491993) (xy 377.650755 -181.521881) (xy 377.571452 -181.544524) (xy 377.490393 -181.55973)
			(xy 377.408274 -181.567368) (xy 377.367038 -181.567836) (xy 377.325923 -181.567365) (xy 377.244043 -181.559781)
			(xy 377.163213 -181.544674) (xy 377.084121 -181.522173) (xy 377.007443 -181.49247) (xy 376.933833 -181.455819)
			(xy 376.863919 -181.412532) (xy 376.798297 -181.362978) (xy 376.737528 -181.30758) (xy 376.68213 -181.246812)
			(xy 376.632575 -181.181191) (xy 376.589287 -181.111277) (xy 376.552634 -181.037668) (xy 376.522931 -180.96099)
			(xy 376.500429 -180.881899) (xy 376.48532 -180.801068) (xy 376.477735 -180.719189) (xy 376.477276 -180.678074)
			(xy 372.848069 -180.678074) (xy 372.8541 -180.720015) (xy 372.858091 -180.8038) (xy 372.8541 -180.887585)
			(xy 372.842162 -180.97061) (xy 372.822386 -181.052125) (xy 372.794951 -181.131391) (xy 372.760105 -181.20769)
			(xy 372.718163 -181.280331) (xy 372.669507 -181.348656) (xy 372.614576 -181.412047) (xy 372.553868 -181.469929)
			(xy 372.487932 -181.521778) (xy 372.417367 -181.567124) (xy 372.34281 -181.605557) (xy 372.264938 -181.636728)
			(xy 372.184455 -181.660356) (xy 372.10209 -181.676226) (xy 372.01859 -181.684195) (xy 371.97665 -181.684676)
			(xy 371.939461 -181.684274) (xy 371.865348 -181.677988) (xy 371.792028 -181.665482) (xy 371.720022 -181.646845)
			(xy 371.684804 -181.634892) (xy 371.676607 -181.632378) (xy 371.659473 -181.632378) (xy 371.651276 -181.634892)
			(xy 371.611916 -181.648156) (xy 371.531285 -181.66812) (xy 371.449135 -181.680416) (xy 371.40769 -181.683152)
			(xy 371.397889 -181.684131) (xy 371.380113 -181.692579) (xy 371.36683 -181.707102) (xy 371.362986 -181.716172)
			(xy 371.348 -181.753764) (xy 371.344428 -181.763418) (xy 371.344429 -181.783987) (xy 371.348 -181.793642)
			(xy 371.365038 -181.835014) (xy 371.391656 -181.920442) (xy 371.409557 -182.008112) (xy 371.418559 -182.097137)
			(xy 371.41912 -182.141876) (xy 371.418616 -182.184237) (xy 371.410563 -182.268574) (xy 371.394529 -182.351764)
			(xy 371.370661 -182.433054) (xy 371.339173 -182.511706) (xy 371.300351 -182.587009) (xy 371.254548 -182.658281)
			(xy 371.202177 -182.724877) (xy 371.143712 -182.786192) (xy 371.079684 -182.841673) (xy 371.010672 -182.890816)
			(xy 370.937302 -182.933176) (xy 370.860237 -182.968371) (xy 370.780175 -182.99608) (xy 370.697842 -183.016054)
			(xy 370.613983 -183.028111) (xy 370.529358 -183.032143) (xy 370.444733 -183.028111) (xy 370.360874 -183.016054)
			(xy 370.278541 -182.99608) (xy 370.198479 -182.968371) (xy 370.121414 -182.933176) (xy 370.048044 -182.890816)
			(xy 369.979032 -182.841673) (xy 369.915004 -182.786192) (xy 369.856539 -182.724877) (xy 369.804168 -182.658281)
			(xy 369.758365 -182.587009) (xy 369.719543 -182.511706) (xy 369.688055 -182.433054) (xy 369.664187 -182.351764)
			(xy 369.648153 -182.268574) (xy 369.6401 -182.184237) (xy 369.639596 -182.141876) (xy 369.640165 -182.097107)
			(xy 369.649173 -182.008022) (xy 369.667076 -181.92029) (xy 369.693694 -181.834799) (xy 369.710716 -181.793388)
			(xy 369.714296 -181.783802) (xy 369.714287 -181.763355) (xy 369.710716 -181.753764) (xy 369.693665 -181.712364)
			(xy 369.667035 -181.626872) (xy 369.649135 -181.539137) (xy 369.640146 -181.450047) (xy 369.639596 -181.405276)
			(xy 369.639771 -181.384669) (xy 369.641804 -181.343504) (xy 369.64366 -181.32298) (xy 369.644023 -181.312283)
			(xy 369.63707 -181.292069) (xy 369.630198 -181.283864) (xy 369.57127 -181.22011) (xy 369.551204 -181.211728)
			(xy 369.540282 -181.211982) (xy 369.523264 -181.212236) (xy 369.522756 -181.212236) (xy 369.481649 -181.211766)
			(xy 369.399787 -181.204159) (xy 369.318976 -181.189032) (xy 369.239905 -181.166515) (xy 369.163248 -181.136799)
			(xy 369.08966 -181.100138) (xy 369.019768 -181.056844) (xy 368.954168 -181.007287) (xy 368.893419 -180.95189)
			(xy 368.83804 -180.891125) (xy 368.788503 -180.825509) (xy 368.745231 -180.755604) (xy 368.708592 -180.682005)
			(xy 368.678899 -180.605339) (xy 368.656406 -180.526261) (xy 368.641304 -180.445446) (xy 368.633721 -180.363581)
			(xy 368.633248 -180.322474) (xy 368.6337 -180.283493) (xy 368.640575 -180.205835) (xy 368.654226 -180.129077)
			(xy 368.663982 -180.091334) (xy 368.666037 -180.082278) (xy 368.664208 -180.063813) (xy 368.655908 -180.047218)
			(xy 368.642231 -180.034679) (xy 368.633756 -180.030882) (xy 368.596114 -180.015301) (xy 368.523548 -179.97826)
			(xy 368.454673 -179.934739) (xy 368.390066 -179.885102) (xy 368.330268 -179.829767) (xy 368.27578 -179.769195)
			(xy 368.227059 -179.703896) (xy 368.184512 -179.634415) (xy 368.148496 -179.561335) (xy 368.119314 -179.485268)
			(xy 368.097208 -179.406851) (xy 368.082365 -179.326741) (xy 368.074909 -179.24561) (xy 368.074448 -179.204874)
			(xy 97.329275 -179.204874) (xy 97.326783 -179.229509) (xy 97.308877 -179.31724) (xy 97.282259 -179.402731)
			(xy 97.265236 -179.444142) (xy 97.261699 -179.453741) (xy 97.261682 -179.474176) (xy 97.265236 -179.483766)
			(xy 97.28224 -179.525117) (xy 97.308851 -179.610479) (xy 97.326758 -179.698082) (xy 97.33578 -179.787039)
			(xy 97.336356 -179.831746) (xy 97.336356 -179.832762) (xy 97.336102 -179.844192) (xy 97.362581 -179.850138)
			(xy 97.414816 -179.864881) (xy 97.440496 -179.873656) (xy 97.448693 -179.87617) (xy 97.465827 -179.87617)
			(xy 97.474024 -179.873656) (xy 97.50924 -179.861695) (xy 97.581244 -179.843041) (xy 97.654565 -179.830532)
			(xy 97.72868 -179.824259) (xy 97.76587 -179.823872) (xy 97.803059 -179.824271) (xy 97.877172 -179.830558)
			(xy 97.950492 -179.843065) (xy 98.022498 -179.861703) (xy 98.057716 -179.873656) (xy 98.065913 -179.87617)
			(xy 98.083047 -179.87617) (xy 98.091244 -179.873656) (xy 98.126459 -179.861689) (xy 98.198462 -179.843037)
			(xy 98.271784 -179.83053) (xy 98.3459 -179.824258) (xy 98.38309 -179.823872) (xy 98.42503 -179.824267)
			(xy 98.508532 -179.832239) (xy 98.590897 -179.848113) (xy 98.67138 -179.871744) (xy 98.749253 -179.902919)
			(xy 98.82381 -179.941355) (xy 98.894375 -179.986704) (xy 98.96031 -180.038555) (xy 99.021018 -180.096439)
			(xy 99.075949 -180.159832) (xy 99.124605 -180.228159) (xy 99.166546 -180.300802) (xy 99.201391 -180.377103)
			(xy 99.228826 -180.45637) (xy 99.248602 -180.537887) (xy 99.26054 -180.620914) (xy 99.264531 -180.7047)
			(xy 99.26054 -180.788486) (xy 99.248602 -180.871513) (xy 99.228826 -180.95303) (xy 99.201391 -181.032297)
			(xy 99.166546 -181.108598) (xy 99.124605 -181.181241) (xy 99.075949 -181.249568) (xy 99.021018 -181.312961)
			(xy 98.96031 -181.370845) (xy 98.894375 -181.422696) (xy 98.82381 -181.468045) (xy 98.749253 -181.506481)
			(xy 98.67138 -181.537656) (xy 98.590897 -181.561287) (xy 98.508532 -181.577161) (xy 98.42503 -181.585133)
			(xy 98.38309 -181.585616) (xy 98.3459 -181.585229) (xy 98.271787 -181.578939) (xy 98.198468 -181.566428)
			(xy 98.126462 -181.547787) (xy 98.091244 -181.535832) (xy 98.083047 -181.533318) (xy 98.065913 -181.533318)
			(xy 98.057716 -181.535832) (xy 98.015534 -181.549982) (xy 97.929009 -181.570726) (xy 97.884996 -181.577234)
			(xy 97.875031 -181.57898) (xy 97.85759 -181.589205) (xy 97.845466 -181.605383) (xy 97.842578 -181.61508)
			(xy 97.833805 -181.648299) (xy 97.811813 -181.713397) (xy 97.798636 -181.745128) (xy 97.79505 -181.754712)
			(xy 97.795064 -181.775161) (xy 97.798636 -181.784752) (xy 97.815664 -181.826127) (xy 97.842281 -181.911555)
			(xy 97.860184 -181.999224) (xy 97.869191 -182.088247) (xy 97.869756 -182.132986) (xy 97.869756 -182.13324)
			(xy 97.869252 -182.175588) (xy 97.861201 -182.259902) (xy 97.845172 -182.343068) (xy 97.821311 -182.424335)
			(xy 97.789832 -182.502965) (xy 97.751021 -182.578246) (xy 97.705231 -182.649498) (xy 97.652875 -182.716074)
			(xy 97.594427 -182.777372) (xy 97.530417 -182.832837) (xy 97.461425 -182.881966) (xy 97.388075 -182.924315)
			(xy 97.311032 -182.959499) (xy 97.230993 -182.987201) (xy 97.148684 -183.007169) (xy 97.064849 -183.019222)
			(xy 96.980248 -183.023253) (xy 96.895647 -183.019222) (xy 96.811812 -183.007169) (xy 96.729503 -182.987201)
			(xy 96.649464 -182.959499) (xy 96.572421 -182.924315) (xy 96.499071 -182.881966) (xy 96.430079 -182.832837)
			(xy 96.366069 -182.777372) (xy 96.307621 -182.716074) (xy 96.255265 -182.649498) (xy 96.209475 -182.578246)
			(xy 96.170664 -182.502965) (xy 96.139185 -182.424335) (xy 96.115324 -182.343068) (xy 96.099295 -182.259902)
			(xy 96.091244 -182.175588) (xy 96.09074 -182.13324) (xy 96.09074 -182.132986) (xy 96.091318 -182.088248)
			(xy 96.10033 -181.999226) (xy 96.118232 -181.911559) (xy 96.144843 -181.826131) (xy 96.16186 -181.784752)
			(xy 96.165401 -181.775154) (xy 96.165416 -181.754718) (xy 96.16186 -181.745128) (xy 96.144825 -181.703755)
			(xy 96.11821 -181.618327) (xy 96.100309 -181.530657) (xy 96.091304 -181.441633) (xy 96.09074 -181.396894)
			(xy 96.09074 -181.395878) (xy 96.090368 -181.38632) (xy 96.083332 -181.368547) (xy 96.070254 -181.354605)
			(xy 96.061784 -181.350158) (xy 95.965264 -181.304184) (xy 95.936308 -181.30774) (xy 95.924878 -181.317138)
			(xy 95.890853 -181.344159) (xy 95.818459 -181.392213) (xy 95.741724 -181.43298) (xy 95.66138 -181.466069)
			(xy 95.578192 -181.491168) (xy 95.492953 -181.508035) (xy 95.406476 -181.51651) (xy 95.36303 -181.517036)
			(xy 95.321915 -181.516573) (xy 95.240035 -181.508988) (xy 95.159204 -181.49388) (xy 95.080113 -181.471379)
			(xy 95.003435 -181.441675) (xy 94.929825 -181.405023) (xy 94.859911 -181.361735) (xy 94.794289 -181.312181)
			(xy 94.73352 -181.256783) (xy 94.678122 -181.196014) (xy 94.628567 -181.130393) (xy 94.585279 -181.060479)
			(xy 94.548626 -180.986869) (xy 94.518922 -180.910191) (xy 94.49642 -180.831099) (xy 94.481312 -180.750269)
			(xy 94.473727 -180.668389) (xy 94.473268 -180.627274) (xy 90.869375 -180.627274) (xy 90.872244 -180.6875)
			(xy 90.868253 -180.771275) (xy 90.856317 -180.854292) (xy 90.836544 -180.935798) (xy 90.809114 -181.015056)
			(xy 90.774274 -181.091347) (xy 90.732339 -181.163981) (xy 90.683691 -181.2323) (xy 90.628768 -181.295686)
			(xy 90.56807 -181.353564) (xy 90.502144 -181.405411) (xy 90.431589 -181.450756) (xy 90.357043 -181.489189)
			(xy 90.279182 -181.520363) (xy 90.198709 -181.543994) (xy 90.116355 -181.559869) (xy 90.032865 -181.567844)
			(xy 89.99093 -181.568344) (xy 89.953741 -181.567944) (xy 89.879628 -181.561657) (xy 89.806308 -181.54915)
			(xy 89.734302 -181.530513) (xy 89.699084 -181.51856) (xy 89.690887 -181.516046) (xy 89.673753 -181.516046)
			(xy 89.665556 -181.51856) (xy 89.630433 -181.5305) (xy 89.558617 -181.54912) (xy 89.485489 -181.561626)
			(xy 89.411567 -181.56793) (xy 89.374472 -181.568344) (xy 89.372948 -181.568344) (xy 89.365328 -181.56809)
			(xy 89.355809 -181.6135) (xy 89.328579 -181.702202) (xy 89.310972 -181.745128) (xy 89.307384 -181.754712)
			(xy 89.307399 -181.775161) (xy 89.310972 -181.784752) (xy 89.327996 -181.826163) (xy 89.354632 -181.91165)
			(xy 89.37254 -181.999382) (xy 89.381538 -182.08847) (xy 89.382092 -182.13324) (xy 89.381588 -182.175601)
			(xy 89.373535 -182.259938) (xy 89.357501 -182.343128) (xy 89.333633 -182.424418) (xy 89.302145 -182.50307)
			(xy 89.263323 -182.578373) (xy 89.21752 -182.649645) (xy 89.165149 -182.716241) (xy 89.106684 -182.777556)
			(xy 89.042656 -182.833037) (xy 88.973644 -182.88218) (xy 88.900274 -182.92454) (xy 88.823209 -182.959735)
			(xy 88.743147 -182.987444) (xy 88.660814 -183.007418) (xy 88.576955 -183.019475) (xy 88.49233 -183.023507)
			(xy 88.407705 -183.019475) (xy 88.323846 -183.007418) (xy 88.241513 -182.987444) (xy 88.161451 -182.959735)
			(xy 88.084386 -182.92454) (xy 88.011016 -182.88218) (xy 87.942004 -182.833037) (xy 87.877976 -182.777556)
			(xy 87.819511 -182.716241) (xy 87.76714 -182.649645) (xy 87.721337 -182.578373) (xy 87.682515 -182.50307)
			(xy 87.651027 -182.424418) (xy 87.627159 -182.343128) (xy 87.611125 -182.259938) (xy 87.603072 -182.175601)
			(xy 87.602568 -182.13324) (xy 87.603127 -182.08847) (xy 87.612138 -181.999385) (xy 87.630045 -181.911654)
			(xy 87.656665 -181.826163) (xy 87.673688 -181.784752) (xy 87.677232 -181.775155) (xy 87.677247 -181.754718)
			(xy 87.673688 -181.745128) (xy 87.65877 -181.708939) (xy 87.634581 -181.634489) (xy 87.617023 -181.558202)
			(xy 87.606232 -181.480668) (xy 87.603838 -181.441598) (xy 87.602983 -181.432757) (xy 87.596138 -181.416387)
			(xy 87.58411 -181.403342) (xy 87.576406 -181.398926) (xy 87.486236 -181.352444) (xy 87.459312 -181.35346)
			(xy 87.447882 -181.360826) (xy 87.412209 -181.38294) (xy 87.337447 -181.421096) (xy 87.259425 -181.452047)
			(xy 87.178837 -181.475518) (xy 87.096397 -181.4913) (xy 87.012838 -181.499253) (xy 86.97087 -181.499764)
			(xy 86.929755 -181.499316) (xy 86.847877 -181.491726) (xy 86.767048 -181.476614) (xy 86.687959 -181.454109)
			(xy 86.611283 -181.424402) (xy 86.537675 -181.387748) (xy 86.467763 -181.344458) (xy 86.402144 -181.294902)
			(xy 86.341376 -181.239504) (xy 86.28598 -181.178735) (xy 86.236426 -181.113114) (xy 86.193139 -181.043201)
			(xy 86.156487 -180.969592) (xy 86.126782 -180.892915) (xy 86.10428 -180.813824) (xy 86.08917 -180.732995)
			(xy 86.081583 -180.651117) (xy 86.081108 -180.610002) (xy 82.462267 -180.610002) (xy 82.47114 -180.671714)
			(xy 82.475131 -180.7555) (xy 82.47114 -180.839286) (xy 82.459202 -180.922313) (xy 82.439426 -181.00383)
			(xy 82.411991 -181.083097) (xy 82.377146 -181.159398) (xy 82.335205 -181.232041) (xy 82.286549 -181.300368)
			(xy 82.231618 -181.363761) (xy 82.17091 -181.421645) (xy 82.104975 -181.473496) (xy 82.03441 -181.518845)
			(xy 81.959853 -181.557281) (xy 81.88198 -181.588456) (xy 81.801497 -181.612087) (xy 81.719132 -181.627961)
			(xy 81.63563 -181.635933) (xy 81.59369 -181.636416) (xy 81.5565 -181.636029) (xy 81.482387 -181.629739)
			(xy 81.409068 -181.617228) (xy 81.337062 -181.598587) (xy 81.301844 -181.586632) (xy 81.293647 -181.584118)
			(xy 81.276513 -181.584118) (xy 81.268316 -181.586632) (xy 81.24011 -181.596266) (xy 81.182657 -181.612157)
			(xy 81.153508 -181.618382) (xy 81.143879 -181.620834) (xy 81.127394 -181.631892) (xy 81.116335 -181.648377)
			(xy 81.113884 -181.658006) (xy 81.104396 -181.702491) (xy 81.07755 -181.789404) (xy 81.06029 -181.831488)
			(xy 81.056659 -181.841055) (xy 81.056528 -181.861499) (xy 81.060036 -181.871112) (xy 81.077051 -181.912492)
			(xy 81.103672 -181.997918) (xy 81.121578 -182.085585) (xy 81.130589 -182.174608) (xy 81.131156 -182.219346)
			(xy 81.131156 -182.2196) (xy 81.130652 -182.261948) (xy 81.122601 -182.346262) (xy 81.106572 -182.429428)
			(xy 81.082711 -182.510695) (xy 81.051232 -182.589325) (xy 81.012421 -182.664606) (xy 80.966631 -182.735858)
			(xy 80.914275 -182.802434) (xy 80.855827 -182.863732) (xy 80.791817 -182.919197) (xy 80.722825 -182.968326)
			(xy 80.649475 -183.010675) (xy 80.572432 -183.045859) (xy 80.492393 -183.073561) (xy 80.410084 -183.093529)
			(xy 80.326249 -183.105582) (xy 80.241648 -183.109613) (xy 80.157047 -183.105582) (xy 80.073212 -183.093529)
			(xy 79.990903 -183.073561) (xy 79.910864 -183.045859) (xy 79.833821 -183.010675) (xy 79.760471 -182.968326)
			(xy 79.691479 -182.919197) (xy 79.627469 -182.863732) (xy 79.569021 -182.802434) (xy 79.516665 -182.735858)
			(xy 79.470875 -182.664606) (xy 79.432064 -182.589325) (xy 79.400585 -182.510695) (xy 79.376724 -182.429428)
			(xy 79.360695 -182.346262) (xy 79.352644 -182.261948) (xy 79.35214 -182.2196) (xy 79.35214 -182.219346)
			(xy 79.352704 -182.174608) (xy 79.361721 -182.085586) (xy 79.379627 -181.997918) (xy 79.406242 -181.912491)
			(xy 79.42326 -181.871112) (xy 79.426824 -181.861521) (xy 79.426824 -181.841079) (xy 79.42326 -181.831488)
			(xy 79.406239 -181.790076) (xy 79.379604 -181.704589) (xy 79.361695 -181.616857) (xy 79.352696 -181.52777)
			(xy 79.35214 -181.483) (xy 79.352578 -181.44277) (xy 79.359832 -181.362636) (xy 79.366618 -181.32298)
			(xy 79.366618 -181.322726) (xy 79.368105 -181.310829) (xy 79.361202 -181.287898) (xy 79.35341 -181.278784)
			(xy 79.287878 -181.210204) (xy 79.265018 -181.202076) (xy 79.252826 -181.203854) (xy 79.222877 -181.207733)
			(xy 79.162627 -181.21193) (xy 79.13243 -181.212236) (xy 79.091315 -181.211773) (xy 79.009435 -181.204188)
			(xy 78.928604 -181.18908) (xy 78.849513 -181.166579) (xy 78.772835 -181.136875) (xy 78.699225 -181.100223)
			(xy 78.629311 -181.056935) (xy 78.563689 -181.007381) (xy 78.50292 -180.951983) (xy 78.447522 -180.891214)
			(xy 78.397967 -180.825593) (xy 78.354679 -180.755679) (xy 78.318026 -180.682069) (xy 78.288322 -180.605391)
			(xy 78.26582 -180.526299) (xy 78.250712 -180.445469) (xy 78.243127 -180.363589) (xy 78.242668 -180.322474)
			(xy 78.243154 -180.279736) (xy 78.251333 -180.194653) (xy 78.267631 -180.110746) (xy 78.2919 -180.028788)
			(xy 78.307438 -179.988972) (xy 78.311043 -179.978929) (xy 78.310391 -179.957622) (xy 78.306168 -179.947824)
			(xy 78.289089 -179.911553) (xy 78.260784 -179.836541) (xy 78.239347 -179.759284) (xy 78.224953 -179.680411)
			(xy 78.217719 -179.600562) (xy 78.217268 -179.560474) (xy 78.21746 -179.533866) (xy 78.220637 -179.480744)
			(xy 78.223618 -179.454302) (xy 78.224368 -179.443055) (xy 78.217254 -179.421697) (xy 78.209902 -179.413154)
			(xy 78.180933 -179.382157) (xy 78.128411 -179.31552) (xy 78.082469 -179.244186) (xy 78.043525 -179.168805)
			(xy 78.011931 -179.090059) (xy 77.987974 -179.008663) (xy 77.971872 -178.925358) (xy 77.963772 -178.840898)
			(xy 77.963268 -178.798474) (xy 9.44304 -178.798474) (xy 9.441677 -178.801459) (xy 9.412211 -178.847309)
			(xy 9.37652 -178.8885) (xy 9.335329 -178.924191) (xy 9.289479 -178.953657) (xy 9.239902 -178.976299)
			(xy 9.187607 -178.991654) (xy 9.133659 -178.99941) (xy 9.079157 -178.99941) (xy 9.025209 -178.991654)
			(xy 8.972914 -178.976299) (xy 8.923337 -178.953657) (xy 8.877487 -178.924191) (xy 8.836296 -178.8885)
			(xy 8.800605 -178.847309) (xy 8.771139 -178.801459) (xy 8.748497 -178.751882) (xy 8.733142 -178.699587)
			(xy 8.725386 -178.645639) (xy 8.7249 -178.618388) (xy 2.509012 -178.618388) (xy 2.509012 -190.64715)
			(xy 220.414866 -190.64715) (xy 220.414866 -190.59265) (xy 220.422621 -190.538705) (xy 220.437974 -190.486413)
			(xy 220.460612 -190.436837) (xy 220.490075 -190.390988) (xy 220.525762 -190.349798) (xy 220.566948 -190.314105)
			(xy 220.612793 -190.284636) (xy 220.662366 -190.261992) (xy 220.714656 -190.246632) (xy 220.7686 -190.238869)
			(xy 220.79585 -190.23838) (xy 221.78645 -190.23838) (xy 221.813704 -190.238864) (xy 221.867659 -190.246615)
			(xy 221.919961 -190.261966) (xy 221.969546 -190.284605) (xy 222.015404 -190.314071) (xy 222.056601 -190.349763)
			(xy 222.092299 -190.390956) (xy 222.121771 -190.43681) (xy 222.144416 -190.486392) (xy 222.159775 -190.538692)
			(xy 222.167533 -190.592646) (xy 222.167533 -190.647154) (xy 222.159775 -190.701108) (xy 222.144416 -190.753408)
			(xy 222.121771 -190.80299) (xy 222.092299 -190.848844) (xy 222.056601 -190.890037) (xy 222.015404 -190.925729)
			(xy 221.969546 -190.955195) (xy 221.919961 -190.977834) (xy 221.867659 -190.993185) (xy 221.813704 -191.000936)
			(xy 221.78645 -191.001396) (xy 220.79585 -191.001396) (xy 220.7686 -191.000931) (xy 220.714656 -190.993168)
			(xy 220.662366 -190.977808) (xy 220.612793 -190.955164) (xy 220.566948 -190.925695) (xy 220.525762 -190.890002)
			(xy 220.490075 -190.848812) (xy 220.460612 -190.802963) (xy 220.437974 -190.753387) (xy 220.422621 -190.701095)
			(xy 220.414866 -190.64715) (xy 2.509012 -190.64715) (xy 2.509012 -194.296284) (xy 255.545336 -194.296284)
			(xy 255.545336 -193.432684) (xy 255.545822 -193.405415) (xy 255.553584 -193.351431) (xy 255.568949 -193.299101)
			(xy 255.591606 -193.249491) (xy 255.621092 -193.20361) (xy 255.656807 -193.162393) (xy 255.698024 -193.126678)
			(xy 255.743905 -193.097192) (xy 255.793515 -193.074535) (xy 255.845845 -193.05917) (xy 255.899829 -193.051408)
			(xy 255.954367 -193.051408) (xy 256.008351 -193.05917) (xy 256.060681 -193.074535) (xy 256.110291 -193.097192)
			(xy 256.156172 -193.126678) (xy 256.197389 -193.162393) (xy 256.233104 -193.20361) (xy 256.26259 -193.249491)
			(xy 256.285247 -193.299101) (xy 256.300612 -193.351431) (xy 256.308374 -193.405415) (xy 256.30886 -193.432684)
			(xy 256.30886 -194.296284) (xy 256.308374 -194.323553) (xy 256.300612 -194.377537) (xy 256.285247 -194.429867)
			(xy 256.26259 -194.479477) (xy 256.25414 -194.492626) (xy 260.09346 -194.492626) (xy 260.09346 -193.502026)
			(xy 260.093946 -193.474757) (xy 260.101708 -193.420773) (xy 260.117073 -193.368443) (xy 260.13973 -193.318833)
			(xy 260.169216 -193.272952) (xy 260.204931 -193.231735) (xy 260.246148 -193.19602) (xy 260.292029 -193.166534)
			(xy 260.341639 -193.143877) (xy 260.393969 -193.128512) (xy 260.447953 -193.12075) (xy 260.502491 -193.12075)
			(xy 260.556475 -193.128512) (xy 260.608805 -193.143877) (xy 260.658415 -193.166534) (xy 260.704296 -193.19602)
			(xy 260.745513 -193.231735) (xy 260.781228 -193.272952) (xy 260.810714 -193.318833) (xy 260.833371 -193.368443)
			(xy 260.848736 -193.420773) (xy 260.856498 -193.474757) (xy 260.856984 -193.502026) (xy 260.856984 -194.492626)
			(xy 260.856498 -194.519895) (xy 260.848736 -194.573879) (xy 260.833371 -194.626209) (xy 260.810714 -194.675819)
			(xy 260.781228 -194.7217) (xy 260.745513 -194.762917) (xy 260.704296 -194.798632) (xy 260.658415 -194.828118)
			(xy 260.608805 -194.850775) (xy 260.556475 -194.86614) (xy 260.502491 -194.873902) (xy 260.447953 -194.873902)
			(xy 260.393969 -194.86614) (xy 260.341639 -194.850775) (xy 260.292029 -194.828118) (xy 260.246148 -194.798632)
			(xy 260.204931 -194.762917) (xy 260.169216 -194.7217) (xy 260.13973 -194.675819) (xy 260.117073 -194.626209)
			(xy 260.101708 -194.573879) (xy 260.093946 -194.519895) (xy 260.09346 -194.492626) (xy 256.25414 -194.492626)
			(xy 256.233104 -194.525358) (xy 256.197389 -194.566575) (xy 256.156172 -194.60229) (xy 256.110291 -194.631776)
			(xy 256.060681 -194.654433) (xy 256.008351 -194.669798) (xy 255.954367 -194.67756) (xy 255.899829 -194.67756)
			(xy 255.845845 -194.669798) (xy 255.793515 -194.654433) (xy 255.743905 -194.631776) (xy 255.698024 -194.60229)
			(xy 255.656807 -194.566575) (xy 255.621092 -194.525358) (xy 255.591606 -194.479477) (xy 255.568949 -194.429867)
			(xy 255.553584 -194.377537) (xy 255.545822 -194.323553) (xy 255.545336 -194.296284) (xy 2.509012 -194.296284)
			(xy 2.509012 -197.582536) (xy 20.958048 -197.582536) (xy 20.958048 -197.087998) (xy 20.958379 -197.08256)
			(xy 20.966072 -197.074874) (xy 20.97151 -197.074536) (xy 21.487638 -197.074536) (xy 21.495447 -197.074207)
			(xy 21.510319 -197.069433) (xy 21.516848 -197.065138) (xy 21.537937 -197.050789) (xy 21.583598 -197.028058)
			(xy 21.632204 -197.012599) (xy 21.682607 -197.004776) (xy 21.733613 -197.004776) (xy 21.784016 -197.012599)
			(xy 21.832622 -197.028058) (xy 21.878283 -197.050789) (xy 21.899372 -197.065138) (xy 21.905914 -197.069411)
			(xy 21.920776 -197.074207) (xy 21.928582 -197.074536) (xy 22.44471 -197.074536) (xy 22.450075 -197.075044)
			(xy 22.45766 -197.082633) (xy 22.458172 -197.087998) (xy 22.458172 -197.582536) (xy 28.502356 -197.582536)
			(xy 28.502356 -197.087998) (xy 28.502824 -197.08269) (xy 28.510265 -197.075118) (xy 28.515564 -197.074536)
			(xy 29.031692 -197.074536) (xy 29.039503 -197.07423) (xy 29.054375 -197.06944) (xy 29.060902 -197.065138)
			(xy 29.081991 -197.050789) (xy 29.127652 -197.028058) (xy 29.176258 -197.012599) (xy 29.226661 -197.004776)
			(xy 29.277667 -197.004776) (xy 29.32807 -197.012599) (xy 29.376676 -197.028058) (xy 29.422337 -197.050789)
			(xy 29.443426 -197.065138) (xy 29.449956 -197.069432) (xy 29.464827 -197.074214) (xy 29.472636 -197.074536)
			(xy 29.988764 -197.074536) (xy 29.994102 -197.074855) (xy 30.001648 -197.082406) (xy 30.001972 -197.087744)
			(xy 30.001972 -197.088252) (xy 30.001972 -197.582536) (xy 36.046156 -197.582536) (xy 36.046156 -197.087998)
			(xy 36.046624 -197.08269) (xy 36.054065 -197.075118) (xy 36.059364 -197.074536) (xy 36.575492 -197.074536)
			(xy 36.583303 -197.07423) (xy 36.598175 -197.06944) (xy 36.604702 -197.065138) (xy 36.625791 -197.050789)
			(xy 36.671452 -197.028058) (xy 36.720058 -197.012599) (xy 36.770461 -197.004776) (xy 36.821467 -197.004776)
			(xy 36.87187 -197.012599) (xy 36.920476 -197.028058) (xy 36.966137 -197.050789) (xy 36.987226 -197.065138)
			(xy 36.993756 -197.069432) (xy 37.008627 -197.074214) (xy 37.016436 -197.074536) (xy 37.532564 -197.074536)
			(xy 37.537902 -197.074855) (xy 37.545448 -197.082406) (xy 37.545772 -197.087744) (xy 37.545772 -197.088252)
			(xy 37.545772 -197.582536) (xy 43.589956 -197.582536) (xy 43.589956 -197.087998) (xy 43.59028 -197.082559)
			(xy 43.597978 -197.074872) (xy 43.603418 -197.074536) (xy 44.119546 -197.074536) (xy 44.127355 -197.07421)
			(xy 44.142227 -197.069434) (xy 44.148756 -197.065138) (xy 44.169845 -197.050789) (xy 44.215506 -197.028058)
			(xy 44.264112 -197.012599) (xy 44.314515 -197.004776) (xy 44.365521 -197.004776) (xy 44.415924 -197.012599)
			(xy 44.46453 -197.028058) (xy 44.510191 -197.050789) (xy 44.53128 -197.065138) (xy 44.53782 -197.069414)
			(xy 44.552683 -197.074208) (xy 44.56049 -197.074536) (xy 45.076618 -197.074536) (xy 45.081984 -197.075038)
			(xy 45.089568 -197.082632) (xy 45.09008 -197.087998) (xy 45.09008 -197.582536) (xy 51.134264 -197.582536)
			(xy 51.134264 -197.087998) (xy 51.134725 -197.082688) (xy 51.142171 -197.075116) (xy 51.147472 -197.074536)
			(xy 51.6636 -197.074536) (xy 51.671411 -197.074233) (xy 51.686283 -197.069441) (xy 51.69281 -197.065138)
			(xy 51.713899 -197.050789) (xy 51.75956 -197.028058) (xy 51.808166 -197.012599) (xy 51.858569 -197.004776)
			(xy 51.909575 -197.004776) (xy 51.959978 -197.012599) (xy 52.008584 -197.028058) (xy 52.054245 -197.050789)
			(xy 52.075334 -197.065138) (xy 52.081862 -197.069435) (xy 52.096735 -197.074216) (xy 52.104544 -197.074536)
			(xy 52.620672 -197.074536) (xy 52.626011 -197.07485) (xy 52.633557 -197.082404) (xy 52.63388 -197.087744)
			(xy 52.63388 -197.088252) (xy 52.63388 -197.582536) (xy 58.678064 -197.582536) (xy 58.678064 -197.087998)
			(xy 58.67838 -197.082557) (xy 58.686084 -197.074869) (xy 58.691526 -197.074536) (xy 60.164726 -197.074536)
			(xy 60.170093 -197.075033) (xy 60.177676 -197.082631) (xy 60.178188 -197.087998) (xy 60.178188 -197.582536)
			(xy 167.778176 -197.582536) (xy 167.778176 -197.087998) (xy 167.778626 -197.082685) (xy 167.78608 -197.075112)
			(xy 167.791384 -197.074536) (xy 169.264584 -197.074536) (xy 169.269925 -197.074842) (xy 169.277469 -197.082402)
			(xy 169.277792 -197.087744) (xy 169.277792 -197.582536) (xy 175.321976 -197.582536) (xy 175.321976 -197.087998)
			(xy 175.322282 -197.082554) (xy 175.329993 -197.074865) (xy 175.335438 -197.074536) (xy 175.851566 -197.074536)
			(xy 175.859376 -197.074219) (xy 175.874248 -197.069436) (xy 175.880776 -197.065138) (xy 175.901865 -197.050789)
			(xy 175.947526 -197.028058) (xy 175.996132 -197.012599) (xy 176.046535 -197.004776) (xy 176.097541 -197.004776)
			(xy 176.147944 -197.012599) (xy 176.19655 -197.028058) (xy 176.242211 -197.050789) (xy 176.2633 -197.065138)
			(xy 176.269836 -197.069422) (xy 176.284702 -197.074211) (xy 176.29251 -197.074536) (xy 176.808638 -197.074536)
			(xy 176.814006 -197.075025) (xy 176.821589 -197.082629) (xy 176.8221 -197.087998) (xy 176.8221 -197.582536)
			(xy 182.866284 -197.582536) (xy 182.866284 -197.087998) (xy 182.866727 -197.082683) (xy 182.874186 -197.07511)
			(xy 182.879492 -197.074536) (xy 183.39562 -197.074536) (xy 183.403432 -197.074242) (xy 183.418304 -197.069444)
			(xy 183.42483 -197.065138) (xy 183.445919 -197.050789) (xy 183.49158 -197.028058) (xy 183.540186 -197.012599)
			(xy 183.590589 -197.004776) (xy 183.641595 -197.004776) (xy 183.691998 -197.012599) (xy 183.740604 -197.028058)
			(xy 183.786265 -197.050789) (xy 183.807354 -197.065138) (xy 183.813878 -197.069443) (xy 183.828754 -197.074219)
			(xy 183.836564 -197.074536) (xy 184.352692 -197.074536) (xy 184.358034 -197.074836) (xy 184.365578 -197.082401)
			(xy 184.3659 -197.087744) (xy 184.3659 -197.088252) (xy 184.3659 -197.582536) (xy 190.410084 -197.582536)
			(xy 190.410084 -197.087998) (xy 190.410382 -197.082552) (xy 190.418098 -197.074863) (xy 190.423546 -197.074536)
			(xy 190.939674 -197.074536) (xy 190.947484 -197.074222) (xy 190.962356 -197.069437) (xy 190.968884 -197.065138)
			(xy 190.989973 -197.050789) (xy 191.035634 -197.028058) (xy 191.08424 -197.012599) (xy 191.134643 -197.004776)
			(xy 191.185649 -197.004776) (xy 191.236052 -197.012599) (xy 191.284658 -197.028058) (xy 191.330319 -197.050789)
			(xy 191.351408 -197.065138) (xy 191.357942 -197.069425) (xy 191.37281 -197.074212) (xy 191.380618 -197.074536)
			(xy 191.896746 -197.074536) (xy 191.902115 -197.07502) (xy 191.909698 -197.082627) (xy 191.910208 -197.087998)
			(xy 191.910208 -197.582536) (xy 197.954392 -197.582536) (xy 197.954392 -197.087998) (xy 197.954916 -197.082705)
			(xy 197.962319 -197.075136) (xy 197.9676 -197.074536) (xy 198.483728 -197.074536) (xy 198.49154 -197.074245)
			(xy 198.506412 -197.069445) (xy 198.512938 -197.065138) (xy 198.534027 -197.050789) (xy 198.579688 -197.028058)
			(xy 198.628294 -197.012599) (xy 198.678697 -197.004776) (xy 198.729703 -197.004776) (xy 198.780106 -197.012599)
			(xy 198.828712 -197.028058) (xy 198.874373 -197.050789) (xy 198.895462 -197.065138) (xy 198.902006 -197.069407)
			(xy 198.916866 -197.074205) (xy 198.924672 -197.074536) (xy 199.4408 -197.074536) (xy 199.446143 -197.074831)
			(xy 199.453687 -197.0824) (xy 199.454008 -197.087744) (xy 199.454008 -197.088252) (xy 199.454008 -197.582536)
			(xy 205.498192 -197.582536) (xy 205.498192 -197.087998) (xy 205.498716 -197.082705) (xy 205.506119 -197.075136)
			(xy 205.5114 -197.074536) (xy 206.027528 -197.074536) (xy 206.03534 -197.074245) (xy 206.050212 -197.069445)
			(xy 206.056738 -197.065138) (xy 206.077827 -197.050789) (xy 206.123488 -197.028058) (xy 206.172094 -197.012599)
			(xy 206.222497 -197.004776) (xy 206.273503 -197.004776) (xy 206.323906 -197.012599) (xy 206.372512 -197.028058)
			(xy 206.418173 -197.050789) (xy 206.439262 -197.065138) (xy 206.445806 -197.069407) (xy 206.458544 -197.07352)
			(xy 255.545336 -197.07352) (xy 255.545336 -196.20992) (xy 255.545822 -196.182651) (xy 255.553584 -196.128667)
			(xy 255.568949 -196.076337) (xy 255.591606 -196.026727) (xy 255.621092 -195.980846) (xy 255.656807 -195.939629)
			(xy 255.698024 -195.903914) (xy 255.743905 -195.874428) (xy 255.793515 -195.851771) (xy 255.845845 -195.836406)
			(xy 255.899829 -195.828644) (xy 255.954367 -195.828644) (xy 256.008351 -195.836406) (xy 256.060681 -195.851771)
			(xy 256.110291 -195.874428) (xy 256.156172 -195.903914) (xy 256.197389 -195.939629) (xy 256.233104 -195.980846)
			(xy 256.26259 -196.026727) (xy 256.285247 -196.076337) (xy 256.300612 -196.128667) (xy 256.308374 -196.182651)
			(xy 256.30886 -196.20992) (xy 256.30886 -197.07352) (xy 256.308374 -197.100789) (xy 256.300612 -197.154773)
			(xy 256.285247 -197.207103) (xy 256.26259 -197.256713) (xy 256.233104 -197.302594) (xy 256.197389 -197.343811)
			(xy 256.156172 -197.379526) (xy 256.110291 -197.409012) (xy 256.060681 -197.431669) (xy 256.008351 -197.447034)
			(xy 255.954367 -197.454796) (xy 255.899829 -197.454796) (xy 255.845845 -197.447034) (xy 255.793515 -197.431669)
			(xy 255.743905 -197.409012) (xy 255.698024 -197.379526) (xy 255.656807 -197.343811) (xy 255.621092 -197.302594)
			(xy 255.591606 -197.256713) (xy 255.568949 -197.207103) (xy 255.553584 -197.154773) (xy 255.545822 -197.100789)
			(xy 255.545336 -197.07352) (xy 206.458544 -197.07352) (xy 206.460666 -197.074205) (xy 206.468472 -197.074536)
			(xy 206.9846 -197.074536) (xy 206.989943 -197.074831) (xy 206.997487 -197.0824) (xy 206.997808 -197.087744)
			(xy 206.997808 -197.088252) (xy 206.997808 -197.582282) (xy 268.898116 -197.582282) (xy 268.898116 -197.087744)
			(xy 268.898459 -197.082412) (xy 268.905992 -197.074867) (xy 268.911324 -197.074536) (xy 268.911832 -197.074536)
			(xy 269.427706 -197.074536) (xy 269.435517 -197.074235) (xy 269.450389 -197.069441) (xy 269.456916 -197.065138)
			(xy 269.478005 -197.050789) (xy 269.523666 -197.028058) (xy 269.572272 -197.012599) (xy 269.622675 -197.004776)
			(xy 269.673681 -197.004776) (xy 269.724084 -197.012599) (xy 269.77269 -197.028058) (xy 269.818351 -197.050789)
			(xy 269.83944 -197.065138) (xy 269.845967 -197.069437) (xy 269.86084 -197.074216) (xy 269.86865 -197.074536)
			(xy 270.384778 -197.074536) (xy 270.390079 -197.075037) (xy 270.397651 -197.082454) (xy 270.39824 -197.087744)
			(xy 270.39824 -197.582282) (xy 270.398224 -197.582536) (xy 276.442424 -197.582536) (xy 276.442424 -197.582028)
			(xy 276.442424 -197.087744) (xy 276.44276 -197.08241) (xy 276.450298 -197.074864) (xy 276.455632 -197.074536)
			(xy 276.97176 -197.074536) (xy 276.97957 -197.074216) (xy 276.994442 -197.069435) (xy 277.00097 -197.065138)
			(xy 277.022059 -197.050789) (xy 277.06772 -197.028058) (xy 277.116326 -197.012599) (xy 277.166729 -197.004776)
			(xy 277.217735 -197.004776) (xy 277.268138 -197.012599) (xy 277.316744 -197.028058) (xy 277.362405 -197.050789)
			(xy 277.383494 -197.065138) (xy 277.390031 -197.06942) (xy 277.404897 -197.07421) (xy 277.412704 -197.074536)
			(xy 277.928832 -197.074536) (xy 277.934179 -197.07481) (xy 277.941721 -197.082395) (xy 277.94204 -197.087744)
			(xy 277.94204 -197.582282) (xy 277.942017 -197.582536) (xy 283.986224 -197.582536) (xy 283.986224 -197.582028)
			(xy 283.986224 -197.087744) (xy 283.98656 -197.08241) (xy 283.994098 -197.074864) (xy 283.999432 -197.074536)
			(xy 284.51556 -197.074536) (xy 284.52337 -197.074216) (xy 284.538242 -197.069435) (xy 284.54477 -197.065138)
			(xy 284.565859 -197.050789) (xy 284.61152 -197.028058) (xy 284.660126 -197.012599) (xy 284.710529 -197.004776)
			(xy 284.761535 -197.004776) (xy 284.811938 -197.012599) (xy 284.860544 -197.028058) (xy 284.906205 -197.050789)
			(xy 284.927294 -197.065138) (xy 284.933831 -197.06942) (xy 284.948697 -197.07421) (xy 284.956504 -197.074536)
			(xy 285.472632 -197.074536) (xy 285.477979 -197.07481) (xy 285.485521 -197.082395) (xy 285.48584 -197.087744)
			(xy 285.48584 -197.582282) (xy 291.530024 -197.582282) (xy 291.530024 -197.087744) (xy 291.53036 -197.08241)
			(xy 291.537898 -197.074864) (xy 291.543232 -197.074536) (xy 291.54374 -197.074536) (xy 292.059614 -197.074536)
			(xy 292.067426 -197.074239) (xy 292.082297 -197.069442) (xy 292.088824 -197.065138) (xy 292.109913 -197.050789)
			(xy 292.155574 -197.028058) (xy 292.20418 -197.012599) (xy 292.254583 -197.004776) (xy 292.305589 -197.004776)
			(xy 292.355992 -197.012599) (xy 292.404598 -197.028058) (xy 292.450259 -197.050789) (xy 292.471348 -197.065138)
			(xy 292.477873 -197.06944) (xy 292.492748 -197.074218) (xy 292.500558 -197.074536) (xy 293.016686 -197.074536)
			(xy 293.021988 -197.075032) (xy 293.029559 -197.082453) (xy 293.030148 -197.087744) (xy 293.030148 -197.582282)
			(xy 293.030132 -197.582536) (xy 299.074332 -197.582536) (xy 299.074332 -197.582028) (xy 299.074332 -197.087744)
			(xy 299.07466 -197.082408) (xy 299.082204 -197.074862) (xy 299.08754 -197.074536) (xy 299.603668 -197.074536)
			(xy 299.611478 -197.074219) (xy 299.62635 -197.069437) (xy 299.632878 -197.065138) (xy 299.653967 -197.050789)
			(xy 299.699628 -197.028058) (xy 299.748234 -197.012599) (xy 299.798637 -197.004776) (xy 299.849643 -197.004776)
			(xy 299.900046 -197.012599) (xy 299.948652 -197.028058) (xy 299.994313 -197.050789) (xy 300.015402 -197.065138)
			(xy 300.021937 -197.069423) (xy 300.036804 -197.074211) (xy 300.044612 -197.074536) (xy 300.56074 -197.074536)
			(xy 300.566089 -197.074804) (xy 300.57363 -197.082394) (xy 300.573948 -197.087744) (xy 300.573948 -197.582282)
			(xy 306.618132 -197.582282) (xy 306.618132 -197.087744) (xy 306.61846 -197.082408) (xy 306.626004 -197.074862)
			(xy 306.63134 -197.074536) (xy 306.631848 -197.074536) (xy 308.104794 -197.074536) (xy 308.110097 -197.075027)
			(xy 308.117668 -197.082452) (xy 308.118256 -197.087744) (xy 308.118256 -197.582282) (xy 308.11824 -197.582536)
			(xy 415.718244 -197.582536) (xy 415.718244 -197.087744) (xy 415.718819 -197.082498) (xy 415.72621 -197.075056)
			(xy 415.731452 -197.074536) (xy 417.204652 -197.074536) (xy 417.209988 -197.074864) (xy 417.217535 -197.082408)
			(xy 417.21786 -197.087744) (xy 417.21786 -197.582282) (xy 423.262044 -197.582282) (xy 423.262044 -197.087744)
			(xy 423.262619 -197.082498) (xy 423.27001 -197.075056) (xy 423.275252 -197.074536) (xy 423.27576 -197.074536)
			(xy 423.791634 -197.074536) (xy 423.799443 -197.074205) (xy 423.814315 -197.069432) (xy 423.820844 -197.065138)
			(xy 423.841933 -197.050789) (xy 423.887594 -197.028058) (xy 423.9362 -197.012599) (xy 423.986603 -197.004776)
			(xy 424.037609 -197.004776) (xy 424.088012 -197.012599) (xy 424.136618 -197.028058) (xy 424.182279 -197.050789)
			(xy 424.203368 -197.065138) (xy 424.209911 -197.06941) (xy 424.224772 -197.074206) (xy 424.232578 -197.074536)
			(xy 424.748706 -197.074536) (xy 424.75401 -197.075019) (xy 424.761581 -197.08245) (xy 424.762168 -197.087744)
			(xy 424.762168 -197.582282) (xy 424.762151 -197.582536) (xy 430.806352 -197.582536) (xy 430.806352 -197.582028)
			(xy 430.806352 -197.087744) (xy 430.806752 -197.082427) (xy 430.814246 -197.074886) (xy 430.81956 -197.074536)
			(xy 431.335688 -197.074536) (xy 431.343499 -197.074228) (xy 431.358371 -197.069439) (xy 431.364898 -197.065138)
			(xy 431.385987 -197.050789) (xy 431.431648 -197.028058) (xy 431.480254 -197.012599) (xy 431.530657 -197.004776)
			(xy 431.581663 -197.004776) (xy 431.632066 -197.012599) (xy 431.680672 -197.028058) (xy 431.726333 -197.050789)
			(xy 431.747422 -197.065138) (xy 431.753953 -197.06943) (xy 431.768823 -197.074214) (xy 431.776632 -197.074536)
			(xy 432.29276 -197.074536) (xy 432.298098 -197.074858) (xy 432.305643 -197.082406) (xy 432.305968 -197.087744)
			(xy 432.305968 -197.582282) (xy 438.350152 -197.582282) (xy 438.350152 -197.087744) (xy 438.350552 -197.082427)
			(xy 438.358046 -197.074886) (xy 438.36336 -197.074536) (xy 438.363868 -197.074536) (xy 438.879742 -197.074536)
			(xy 438.887551 -197.074208) (xy 438.902423 -197.069433) (xy 438.908952 -197.065138) (xy 438.930041 -197.050789)
			(xy 438.975702 -197.028058) (xy 439.024308 -197.012599) (xy 439.074711 -197.004776) (xy 439.125717 -197.004776)
			(xy 439.17612 -197.012599) (xy 439.224726 -197.028058) (xy 439.270387 -197.050789) (xy 439.291476 -197.065138)
			(xy 439.298017 -197.069413) (xy 439.31288 -197.074207) (xy 439.320686 -197.074536) (xy 439.836814 -197.074536)
			(xy 439.842119 -197.075014) (xy 439.849689 -197.082449) (xy 439.850276 -197.087744) (xy 439.850276 -197.582282)
			(xy 439.850259 -197.582536) (xy 445.89446 -197.582536) (xy 445.89446 -197.582028) (xy 445.89446 -197.087744)
			(xy 445.894853 -197.082425) (xy 445.902351 -197.074884) (xy 445.907668 -197.074536) (xy 446.423796 -197.074536)
			(xy 446.431607 -197.074231) (xy 446.446479 -197.06944) (xy 446.453006 -197.065138) (xy 446.474095 -197.050789)
			(xy 446.519756 -197.028058) (xy 446.568362 -197.012599) (xy 446.618765 -197.004776) (xy 446.669771 -197.004776)
			(xy 446.720174 -197.012599) (xy 446.76878 -197.028058) (xy 446.814441 -197.050789) (xy 446.83553 -197.065138)
			(xy 446.842059 -197.069434) (xy 446.856931 -197.074215) (xy 446.86474 -197.074536) (xy 447.380868 -197.074536)
			(xy 447.386207 -197.074853) (xy 447.393752 -197.082405) (xy 447.394076 -197.087744) (xy 447.394076 -197.582282)
			(xy 447.394052 -197.582536) (xy 453.43826 -197.582536) (xy 453.43826 -197.582028) (xy 453.43826 -197.087744)
			(xy 453.438653 -197.082425) (xy 453.446151 -197.074884) (xy 453.451468 -197.074536) (xy 453.967596 -197.074536)
			(xy 453.975407 -197.074231) (xy 453.990279 -197.06944) (xy 453.996806 -197.065138) (xy 454.017895 -197.050789)
			(xy 454.063556 -197.028058) (xy 454.112162 -197.012599) (xy 454.162565 -197.004776) (xy 454.213571 -197.004776)
			(xy 454.263974 -197.012599) (xy 454.31258 -197.028058) (xy 454.358241 -197.050789) (xy 454.37933 -197.065138)
			(xy 454.385859 -197.069434) (xy 454.400731 -197.074215) (xy 454.40854 -197.074536) (xy 454.924668 -197.074536)
			(xy 454.930007 -197.074853) (xy 454.937552 -197.082405) (xy 454.937876 -197.087744) (xy 454.937876 -197.582282)
			(xy 454.937367 -197.58758) (xy 454.929955 -197.595152) (xy 454.924668 -197.595744) (xy 454.408794 -197.595744)
			(xy 454.400983 -197.596048) (xy 454.386111 -197.60084) (xy 454.379584 -197.605142) (xy 454.358464 -197.619493)
			(xy 454.312739 -197.64222) (xy 454.264066 -197.657649) (xy 454.213599 -197.665415) (xy 454.188068 -197.665848)
			(xy 454.162537 -197.66543) (xy 454.112072 -197.657649) (xy 454.0634 -197.642215) (xy 454.017673 -197.619492)
			(xy 453.996552 -197.605142) (xy 453.990028 -197.600838) (xy 453.975152 -197.596062) (xy 453.967342 -197.595744)
			(xy 453.451468 -197.595744) (xy 453.44621 -197.59523) (xy 453.438771 -197.587794) (xy 453.43826 -197.582536)
			(xy 447.394052 -197.582536) (xy 447.393567 -197.58758) (xy 447.386155 -197.595152) (xy 447.380868 -197.595744)
			(xy 446.864994 -197.595744) (xy 446.857183 -197.596048) (xy 446.842311 -197.60084) (xy 446.835784 -197.605142)
			(xy 446.814664 -197.619493) (xy 446.768939 -197.64222) (xy 446.720266 -197.657649) (xy 446.669799 -197.665415)
			(xy 446.644268 -197.665848) (xy 446.618737 -197.66543) (xy 446.568272 -197.657649) (xy 446.5196 -197.642215)
			(xy 446.473873 -197.619492) (xy 446.452752 -197.605142) (xy 446.446228 -197.600838) (xy 446.431352 -197.596062)
			(xy 446.423542 -197.595744) (xy 445.907668 -197.595744) (xy 445.90241 -197.59523) (xy 445.894971 -197.587794)
			(xy 445.89446 -197.582536) (xy 439.850259 -197.582536) (xy 439.84991 -197.587711) (xy 439.842242 -197.595397)
			(xy 439.836814 -197.595744) (xy 439.32094 -197.595744) (xy 439.313131 -197.596067) (xy 439.298259 -197.600846)
			(xy 439.29173 -197.605142) (xy 439.270625 -197.619517) (xy 439.224895 -197.642238) (xy 439.176217 -197.657661)
			(xy 439.125746 -197.665419) (xy 439.100214 -197.665848) (xy 439.074684 -197.665407) (xy 439.02422 -197.657633)
			(xy 438.975548 -197.642205) (xy 438.92982 -197.619489) (xy 438.908698 -197.605142) (xy 438.902164 -197.600855)
			(xy 438.887296 -197.596069) (xy 438.879488 -197.595744) (xy 438.363614 -197.595744) (xy 438.358177 -197.59541)
			(xy 438.350489 -197.587719) (xy 438.350152 -197.582282) (xy 432.305968 -197.582282) (xy 432.305466 -197.587582)
			(xy 432.298049 -197.595154) (xy 432.29276 -197.595744) (xy 431.776886 -197.595744) (xy 431.769075 -197.596044)
			(xy 431.754203 -197.600839) (xy 431.747676 -197.605142) (xy 431.726558 -197.619497) (xy 431.680833 -197.642222)
			(xy 431.632159 -197.657651) (xy 431.581691 -197.665416) (xy 431.55616 -197.665848) (xy 431.530629 -197.665434)
			(xy 431.480164 -197.657652) (xy 431.431491 -197.642216) (xy 431.385765 -197.619493) (xy 431.364644 -197.605142)
			(xy 431.358122 -197.600835) (xy 431.343245 -197.596061) (xy 431.335434 -197.595744) (xy 430.81956 -197.595744)
			(xy 430.814301 -197.595236) (xy 430.806863 -197.587795) (xy 430.806352 -197.582536) (xy 424.762151 -197.582536)
			(xy 424.761809 -197.587713) (xy 424.754136 -197.5954) (xy 424.748706 -197.595744) (xy 424.232832 -197.595744)
			(xy 424.225022 -197.596064) (xy 424.210151 -197.600845) (xy 424.203622 -197.605142) (xy 424.182491 -197.619477)
			(xy 424.136771 -197.642207) (xy 424.0881 -197.657641) (xy 424.037636 -197.665412) (xy 424.012106 -197.665848)
			(xy 423.986576 -197.665411) (xy 423.936112 -197.657636) (xy 423.887439 -197.642207) (xy 423.841712 -197.61949)
			(xy 423.82059 -197.605142) (xy 423.814057 -197.600852) (xy 423.799188 -197.596068) (xy 423.79138 -197.595744)
			(xy 423.275506 -197.595744) (xy 423.270068 -197.595415) (xy 423.26238 -197.587721) (xy 423.262044 -197.582282)
			(xy 417.21786 -197.582282) (xy 417.217365 -197.587584) (xy 417.209943 -197.595156) (xy 417.204652 -197.595744)
			(xy 415.731452 -197.595744) (xy 415.726192 -197.595241) (xy 415.718755 -197.587796) (xy 415.718244 -197.582536)
			(xy 308.11824 -197.582536) (xy 308.117908 -197.587716) (xy 308.110228 -197.595403) (xy 308.104794 -197.595744)
			(xy 306.631594 -197.595744) (xy 306.626154 -197.595423) (xy 306.618467 -197.587723) (xy 306.618132 -197.582282)
			(xy 300.573948 -197.582282) (xy 300.573464 -197.587587) (xy 300.566035 -197.59516) (xy 300.56074 -197.595744)
			(xy 300.044866 -197.595744) (xy 300.037058 -197.596078) (xy 300.022186 -197.600849) (xy 300.015656 -197.605142)
			(xy 299.994543 -197.619505) (xy 299.948816 -197.642229) (xy 299.90014 -197.657655) (xy 299.849672 -197.665417)
			(xy 299.82414 -197.665848) (xy 299.79861 -197.665394) (xy 299.748147 -197.657624) (xy 299.699475 -197.6422)
			(xy 299.653746 -197.619488) (xy 299.632624 -197.605142) (xy 299.626084 -197.600865) (xy 299.611221 -197.596073)
			(xy 299.603414 -197.595744) (xy 299.08754 -197.595744) (xy 299.082222 -197.59535) (xy 299.074681 -197.587852)
			(xy 299.074332 -197.582536) (xy 293.030132 -197.582536) (xy 293.029807 -197.587718) (xy 293.022122 -197.595406)
			(xy 293.016686 -197.595744) (xy 292.500812 -197.595744) (xy 292.493002 -197.596056) (xy 292.47813 -197.600842)
			(xy 292.471602 -197.605142) (xy 292.450477 -197.619485) (xy 292.404754 -197.642214) (xy 292.356082 -197.657645)
			(xy 292.305617 -197.665414) (xy 292.280086 -197.665848) (xy 292.254555 -197.665421) (xy 292.204091 -197.657643)
			(xy 292.155418 -197.642211) (xy 292.109691 -197.619491) (xy 292.08857 -197.605142) (xy 292.082042 -197.600845)
			(xy 292.067169 -197.596065) (xy 292.05936 -197.595744) (xy 291.543486 -197.595744) (xy 291.538045 -197.595428)
			(xy 291.530359 -197.587724) (xy 291.530024 -197.582282) (xy 285.48584 -197.582282) (xy 285.485363 -197.587589)
			(xy 285.477929 -197.595162) (xy 285.472632 -197.595744) (xy 284.956758 -197.595744) (xy 284.948949 -197.596075)
			(xy 284.934078 -197.600848) (xy 284.927548 -197.605142) (xy 284.906438 -197.619509) (xy 284.86071 -197.642232)
			(xy 284.812033 -197.657657) (xy 284.761564 -197.665418) (xy 284.736032 -197.665848) (xy 284.710502 -197.665398)
			(xy 284.660039 -197.657627) (xy 284.611366 -197.642202) (xy 284.565638 -197.619488) (xy 284.544516 -197.605142)
			(xy 284.537978 -197.600862) (xy 284.523113 -197.596071) (xy 284.515306 -197.595744) (xy 283.999432 -197.595744)
			(xy 283.994182 -197.595188) (xy 283.986739 -197.587784) (xy 283.986224 -197.582536) (xy 277.942017 -197.582536)
			(xy 277.941563 -197.587589) (xy 277.934129 -197.595162) (xy 277.928832 -197.595744) (xy 277.412958 -197.595744)
			(xy 277.405149 -197.596075) (xy 277.390278 -197.600848) (xy 277.383748 -197.605142) (xy 277.362638 -197.619509)
			(xy 277.31691 -197.642232) (xy 277.268233 -197.657657) (xy 277.217764 -197.665418) (xy 277.192232 -197.665848)
			(xy 277.166702 -197.665398) (xy 277.116239 -197.657627) (xy 277.067566 -197.642202) (xy 277.021838 -197.619488)
			(xy 277.000716 -197.605142) (xy 276.994178 -197.600862) (xy 276.979313 -197.596071) (xy 276.971506 -197.595744)
			(xy 276.455632 -197.595744) (xy 276.450382 -197.595188) (xy 276.442939 -197.587784) (xy 276.442424 -197.582536)
			(xy 270.398224 -197.582536) (xy 270.397907 -197.58772) (xy 270.390216 -197.595408) (xy 270.384778 -197.595744)
			(xy 269.868904 -197.595744) (xy 269.861093 -197.596052) (xy 269.846222 -197.600841) (xy 269.839694 -197.605142)
			(xy 269.818571 -197.619489) (xy 269.772848 -197.642216) (xy 269.724175 -197.657647) (xy 269.673709 -197.665415)
			(xy 269.648178 -197.665848) (xy 269.622647 -197.665425) (xy 269.572183 -197.657646) (xy 269.52351 -197.642213)
			(xy 269.477783 -197.619492) (xy 269.456662 -197.605142) (xy 269.450136 -197.600842) (xy 269.435262 -197.596064)
			(xy 269.427452 -197.595744) (xy 268.911578 -197.595744) (xy 268.906207 -197.595262) (xy 268.898622 -197.587654)
			(xy 268.898116 -197.582282) (xy 206.997808 -197.582282) (xy 206.997808 -197.582536) (xy 206.997329 -197.587803)
			(xy 206.989868 -197.595243) (xy 206.9846 -197.595744) (xy 206.468726 -197.595744) (xy 206.460849 -197.596008)
			(xy 206.445846 -197.600808) (xy 206.439262 -197.605142) (xy 206.418185 -197.619534) (xy 206.37254 -197.642363)
			(xy 206.323934 -197.65792) (xy 206.273517 -197.665839) (xy 206.248 -197.666356) (xy 206.222479 -197.665891)
			(xy 206.17205 -197.657991) (xy 206.123439 -197.642424) (xy 206.077802 -197.619561) (xy 206.056738 -197.605142)
			(xy 206.050137 -197.600843) (xy 206.035144 -197.596046) (xy 206.027274 -197.595744) (xy 205.5114 -197.595744)
			(xy 205.506146 -197.595209) (xy 205.498706 -197.587789) (xy 205.498192 -197.582536) (xy 199.454008 -197.582536)
			(xy 199.453529 -197.587803) (xy 199.446068 -197.595243) (xy 199.4408 -197.595744) (xy 198.924926 -197.595744)
			(xy 198.917049 -197.596008) (xy 198.902046 -197.600808) (xy 198.895462 -197.605142) (xy 198.874385 -197.619534)
			(xy 198.82874 -197.642363) (xy 198.780134 -197.65792) (xy 198.729717 -197.665839) (xy 198.7042 -197.666356)
			(xy 198.678679 -197.665891) (xy 198.62825 -197.657991) (xy 198.579639 -197.642424) (xy 198.534002 -197.619561)
			(xy 198.512938 -197.605142) (xy 198.506337 -197.600843) (xy 198.491344 -197.596046) (xy 198.483474 -197.595744)
			(xy 197.9676 -197.595744) (xy 197.962346 -197.595209) (xy 197.954906 -197.587789) (xy 197.954392 -197.582536)
			(xy 191.910208 -197.582536) (xy 191.909729 -197.587803) (xy 191.902268 -197.595243) (xy 191.897 -197.595744)
			(xy 191.896492 -197.595744) (xy 191.380872 -197.595744) (xy 191.372997 -197.596028) (xy 191.357993 -197.600815)
			(xy 191.351408 -197.605142) (xy 191.330346 -197.619558) (xy 191.284696 -197.642381) (xy 191.236085 -197.657932)
			(xy 191.185664 -197.665843) (xy 191.160146 -197.666356) (xy 191.134626 -197.665868) (xy 191.084198 -197.657975)
			(xy 191.035586 -197.642414) (xy 190.989948 -197.619558) (xy 190.968884 -197.605142) (xy 190.962295 -197.600822)
			(xy 190.947293 -197.596038) (xy 190.93942 -197.595744) (xy 190.423546 -197.595744) (xy 190.418244 -197.595245)
			(xy 190.410669 -197.587827) (xy 190.410084 -197.582536) (xy 184.3659 -197.582536) (xy 184.365428 -197.587805)
			(xy 184.357963 -197.595246) (xy 184.352692 -197.595744) (xy 183.836818 -197.595744) (xy 183.828945 -197.596048)
			(xy 183.813941 -197.600821) (xy 183.807354 -197.605142) (xy 183.786279 -197.619538) (xy 183.740634 -197.642365)
			(xy 183.692027 -197.657922) (xy 183.641609 -197.66584) (xy 183.616092 -197.666356) (xy 183.590573 -197.665845)
			(xy 183.540146 -197.657958) (xy 183.491534 -197.642405) (xy 183.445895 -197.619555) (xy 183.42483 -197.605142)
			(xy 183.418231 -197.60084) (xy 183.403237 -197.596044) (xy 183.395366 -197.595744) (xy 182.879492 -197.595744)
			(xy 182.874237 -197.595214) (xy 182.866797 -197.58779) (xy 182.866284 -197.582536) (xy 176.8221 -197.582536)
			(xy 176.821628 -197.587805) (xy 176.814163 -197.595246) (xy 176.808892 -197.595744) (xy 176.808384 -197.595744)
			(xy 176.292764 -197.595744) (xy 176.284889 -197.596025) (xy 176.269885 -197.600814) (xy 176.2633 -197.605142)
			(xy 176.242212 -197.619518) (xy 176.196571 -197.64235) (xy 176.147968 -197.657912) (xy 176.097554 -197.665836)
			(xy 176.072038 -197.666356) (xy 176.046517 -197.665872) (xy 175.99609 -197.657977) (xy 175.947478 -197.642416)
			(xy 175.90184 -197.619559) (xy 175.880776 -197.605142) (xy 175.874189 -197.600819) (xy 175.859186 -197.596037)
			(xy 175.851312 -197.595744) (xy 175.335438 -197.595744) (xy 175.330135 -197.59525) (xy 175.322561 -197.587828)
			(xy 175.321976 -197.582536) (xy 169.277792 -197.582536) (xy 169.277327 -197.587807) (xy 169.269857 -197.595248)
			(xy 169.264584 -197.595744) (xy 167.791384 -197.595744) (xy 167.786128 -197.59522) (xy 167.778688 -197.587791)
			(xy 167.778176 -197.582536) (xy 60.178188 -197.582536) (xy 60.177727 -197.587808) (xy 60.170254 -197.595249)
			(xy 60.16498 -197.595744) (xy 60.164472 -197.595744) (xy 58.691526 -197.595744) (xy 58.686221 -197.595258)
			(xy 58.678648 -197.58783) (xy 58.678064 -197.582536) (xy 52.63388 -197.582536) (xy 52.633426 -197.58781)
			(xy 52.625948 -197.595252) (xy 52.620672 -197.595744) (xy 52.104798 -197.595744) (xy 52.096924 -197.59604)
			(xy 52.08192 -197.600818) (xy 52.075334 -197.605142) (xy 52.054265 -197.619546) (xy 52.008617 -197.642372)
			(xy 51.960009 -197.657926) (xy 51.909589 -197.665841) (xy 51.884072 -197.666356) (xy 51.858552 -197.665855)
			(xy 51.808125 -197.657965) (xy 51.759513 -197.642409) (xy 51.713875 -197.619556) (xy 51.69281 -197.605142)
			(xy 51.686215 -197.600832) (xy 51.671218 -197.596042) (xy 51.663346 -197.595744) (xy 51.147472 -197.595744)
			(xy 51.142215 -197.595228) (xy 51.134775 -197.587793) (xy 51.134264 -197.582536) (xy 45.09008 -197.582536)
			(xy 45.089626 -197.58781) (xy 45.082148 -197.595252) (xy 45.076872 -197.595744) (xy 45.076364 -197.595744)
			(xy 44.560744 -197.595744) (xy 44.552868 -197.596016) (xy 44.537864 -197.60081) (xy 44.53128 -197.605142)
			(xy 44.510198 -197.619526) (xy 44.464555 -197.642357) (xy 44.41595 -197.657916) (xy 44.365534 -197.665838)
			(xy 44.340018 -197.666356) (xy 44.314497 -197.665882) (xy 44.264069 -197.657984) (xy 44.215457 -197.64242)
			(xy 44.16982 -197.61956) (xy 44.148756 -197.605142) (xy 44.142174 -197.600811) (xy 44.127167 -197.596034)
			(xy 44.119292 -197.595744) (xy 43.603418 -197.595744) (xy 43.598112 -197.595263) (xy 43.590539 -197.587832)
			(xy 43.589956 -197.582536) (xy 37.545772 -197.582536) (xy 37.545325 -197.587812) (xy 37.537842 -197.595254)
			(xy 37.532564 -197.595744) (xy 37.01669 -197.595744) (xy 37.008816 -197.596036) (xy 36.993812 -197.600817)
			(xy 36.987226 -197.605142) (xy 36.966159 -197.61955) (xy 36.920511 -197.642375) (xy 36.871901 -197.657928)
			(xy 36.821482 -197.665842) (xy 36.795964 -197.666356) (xy 36.770444 -197.665859) (xy 36.720017 -197.657968)
			(xy 36.671405 -197.642411) (xy 36.625767 -197.619557) (xy 36.604702 -197.605142) (xy 36.598109 -197.600829)
			(xy 36.58311 -197.59604) (xy 36.575238 -197.595744) (xy 36.059364 -197.595744) (xy 36.054106 -197.595233)
			(xy 36.046667 -197.587794) (xy 36.046156 -197.582536) (xy 30.001972 -197.582536) (xy 30.001525 -197.587812)
			(xy 29.994042 -197.595254) (xy 29.988764 -197.595744) (xy 29.47289 -197.595744) (xy 29.465016 -197.596036)
			(xy 29.450012 -197.600817) (xy 29.443426 -197.605142) (xy 29.422359 -197.61955) (xy 29.376711 -197.642375)
			(xy 29.328101 -197.657928) (xy 29.277682 -197.665842) (xy 29.252164 -197.666356) (xy 29.226644 -197.665859)
			(xy 29.176217 -197.657968) (xy 29.127605 -197.642411) (xy 29.081967 -197.619557) (xy 29.060902 -197.605142)
			(xy 29.054309 -197.600829) (xy 29.03931 -197.59604) (xy 29.031438 -197.595744) (xy 28.515564 -197.595744)
			(xy 28.510306 -197.595233) (xy 28.502867 -197.587794) (xy 28.502356 -197.582536) (xy 22.458172 -197.582536)
			(xy 22.457725 -197.587812) (xy 22.450242 -197.595254) (xy 22.444964 -197.595744) (xy 22.444456 -197.595744)
			(xy 21.928836 -197.595744) (xy 21.92096 -197.596013) (xy 21.905956 -197.600809) (xy 21.899372 -197.605142)
			(xy 21.878292 -197.61953) (xy 21.832648 -197.642359) (xy 21.784043 -197.657918) (xy 21.733626 -197.665838)
			(xy 21.70811 -197.666356) (xy 21.682589 -197.665886) (xy 21.632161 -197.657987) (xy 21.583549 -197.642421)
			(xy 21.537912 -197.61956) (xy 21.516848 -197.605142) (xy 21.510267 -197.600808) (xy 21.495259 -197.596032)
			(xy 21.487384 -197.595744) (xy 20.97151 -197.595744) (xy 20.966203 -197.595269) (xy 20.95863 -197.587833)
			(xy 20.958048 -197.582536) (xy 2.509012 -197.582536) (xy 2.509012 -198.43242) (xy 16.85798 -198.43242)
			(xy 16.85798 -197.937882) (xy 16.858271 -197.932434) (xy 16.865993 -197.924747) (xy 16.871442 -197.92442)
			(xy 17.38757 -197.92442) (xy 17.39538 -197.924107) (xy 17.410252 -197.919322) (xy 17.41678 -197.915022)
			(xy 17.437869 -197.900673) (xy 17.48353 -197.877942) (xy 17.532136 -197.862483) (xy 17.582539 -197.85466)
			(xy 17.633545 -197.85466) (xy 17.683948 -197.862483) (xy 17.732554 -197.877942) (xy 17.778215 -197.900673)
			(xy 17.799304 -197.915022) (xy 17.80584 -197.919306) (xy 17.820706 -197.924095) (xy 17.828514 -197.92442)
			(xy 18.344642 -197.92442) (xy 18.350007 -197.924921) (xy 18.357589 -197.932516) (xy 18.358104 -197.937882)
			(xy 18.358104 -198.43242) (xy 24.402288 -198.43242) (xy 24.402288 -197.937882) (xy 24.402717 -197.932564)
			(xy 24.410186 -197.924991) (xy 24.415496 -197.92442) (xy 24.931624 -197.92442) (xy 24.939436 -197.92413)
			(xy 24.954308 -197.919329) (xy 24.960834 -197.915022) (xy 24.981923 -197.900673) (xy 25.027584 -197.877942)
			(xy 25.07619 -197.862483) (xy 25.126593 -197.85466) (xy 25.177599 -197.85466) (xy 25.228002 -197.862483)
			(xy 25.276608 -197.877942) (xy 25.322269 -197.900673) (xy 25.343358 -197.915022) (xy 25.349882 -197.919327)
			(xy 25.364758 -197.924103) (xy 25.372568 -197.92442) (xy 25.888696 -197.92442) (xy 25.894034 -197.924732)
			(xy 25.901577 -197.932289) (xy 25.901904 -197.937628) (xy 25.901904 -197.938136) (xy 25.901904 -198.43242)
			(xy 31.946088 -198.43242) (xy 31.946088 -197.937882) (xy 31.946517 -197.932564) (xy 31.953986 -197.924991)
			(xy 31.959296 -197.92442) (xy 32.475424 -197.92442) (xy 32.483236 -197.92413) (xy 32.498108 -197.919329)
			(xy 32.504634 -197.915022) (xy 32.525723 -197.900673) (xy 32.571384 -197.877942) (xy 32.61999 -197.862483)
			(xy 32.670393 -197.85466) (xy 32.721399 -197.85466) (xy 32.771802 -197.862483) (xy 32.820408 -197.877942)
			(xy 32.866069 -197.900673) (xy 32.887158 -197.915022) (xy 32.893682 -197.919327) (xy 32.908558 -197.924103)
			(xy 32.916368 -197.92442) (xy 33.432496 -197.92442) (xy 33.437834 -197.924732) (xy 33.445377 -197.932289)
			(xy 33.445704 -197.937628) (xy 33.445704 -197.938136) (xy 33.445704 -198.43242) (xy 39.489888 -198.43242)
			(xy 39.489888 -197.937882) (xy 39.490433 -197.932528) (xy 39.497997 -197.924946) (xy 39.50335 -197.92442)
			(xy 40.019478 -197.92442) (xy 40.027289 -197.92411) (xy 40.042161 -197.919323) (xy 40.048688 -197.915022)
			(xy 40.069777 -197.900673) (xy 40.115438 -197.877942) (xy 40.164044 -197.862483) (xy 40.214447 -197.85466)
			(xy 40.265453 -197.85466) (xy 40.315856 -197.862483) (xy 40.364462 -197.877942) (xy 40.410123 -197.900673)
			(xy 40.431212 -197.915022) (xy 40.437746 -197.919309) (xy 40.452614 -197.924096) (xy 40.460422 -197.92442)
			(xy 40.97655 -197.92442) (xy 40.981916 -197.924916) (xy 40.989497 -197.932515) (xy 40.990012 -197.937882)
			(xy 40.990012 -198.43242) (xy 47.034196 -198.43242) (xy 47.034196 -197.937882) (xy 47.034706 -197.932586)
			(xy 47.042119 -197.925018) (xy 47.047404 -197.92442) (xy 47.563532 -197.92442) (xy 47.571341 -197.924091)
			(xy 47.586213 -197.919317) (xy 47.592742 -197.915022) (xy 47.613831 -197.900673) (xy 47.659492 -197.877942)
			(xy 47.708098 -197.862483) (xy 47.758501 -197.85466) (xy 47.809507 -197.85466) (xy 47.85991 -197.862483)
			(xy 47.908516 -197.877942) (xy 47.954177 -197.900673) (xy 47.975266 -197.915022) (xy 47.98181 -197.919292)
			(xy 47.99667 -197.924089) (xy 48.004476 -197.92442) (xy 48.520604 -197.92442) (xy 48.525944 -197.924727)
			(xy 48.533486 -197.932288) (xy 48.533812 -197.937628) (xy 48.533812 -197.938136) (xy 48.533812 -198.43242)
			(xy 54.577996 -198.43242) (xy 54.577996 -197.937882) (xy 54.578534 -197.932526) (xy 54.586103 -197.924944)
			(xy 54.591458 -197.92442) (xy 56.064658 -197.92442) (xy 56.070083 -197.924806) (xy 56.07777 -197.932459)
			(xy 56.07812 -197.937882) (xy 56.07812 -198.43242) (xy 163.678108 -198.43242) (xy 163.678108 -197.937882)
			(xy 163.678607 -197.932583) (xy 163.686028 -197.925015) (xy 163.691316 -197.92442) (xy 165.164516 -197.92442)
			(xy 165.169857 -197.924719) (xy 165.177399 -197.932286) (xy 165.177724 -197.937628) (xy 165.177724 -197.938136)
			(xy 165.177724 -198.43242) (xy 171.221908 -198.43242) (xy 171.221908 -197.937882) (xy 171.222435 -197.932523)
			(xy 171.230012 -197.92494) (xy 171.23537 -197.92442) (xy 171.751498 -197.92442) (xy 171.759309 -197.924119)
			(xy 171.774181 -197.919326) (xy 171.780708 -197.915022) (xy 171.801797 -197.900673) (xy 171.847458 -197.877942)
			(xy 171.896064 -197.862483) (xy 171.946467 -197.85466) (xy 171.997473 -197.85466) (xy 172.047876 -197.862483)
			(xy 172.096482 -197.877942) (xy 172.142143 -197.900673) (xy 172.163232 -197.915022) (xy 172.169762 -197.919317)
			(xy 172.184633 -197.924099) (xy 172.192442 -197.92442) (xy 172.70857 -197.92442) (xy 172.713996 -197.924798)
			(xy 172.721683 -197.932457) (xy 172.722032 -197.937882) (xy 172.722032 -198.43242) (xy 178.766216 -198.43242)
			(xy 178.766216 -197.937882) (xy 178.766708 -197.932581) (xy 178.774134 -197.925012) (xy 178.779424 -197.92442)
			(xy 179.295552 -197.92442) (xy 179.303362 -197.924099) (xy 179.318234 -197.91932) (xy 179.324762 -197.915022)
			(xy 179.345851 -197.900673) (xy 179.391512 -197.877942) (xy 179.440118 -197.862483) (xy 179.490521 -197.85466)
			(xy 179.541527 -197.85466) (xy 179.59193 -197.862483) (xy 179.640536 -197.877942) (xy 179.686197 -197.900673)
			(xy 179.707286 -197.915022) (xy 179.713826 -197.919299) (xy 179.728689 -197.924092) (xy 179.736496 -197.92442)
			(xy 180.252624 -197.92442) (xy 180.257966 -197.924714) (xy 180.265507 -197.932284) (xy 180.265832 -197.937628)
			(xy 180.265832 -197.938136) (xy 180.265832 -198.43242) (xy 186.310016 -198.43242) (xy 186.310016 -197.937882)
			(xy 186.310536 -197.932521) (xy 186.318117 -197.924938) (xy 186.323478 -197.92442) (xy 186.839606 -197.92442)
			(xy 186.847418 -197.924122) (xy 186.86229 -197.919327) (xy 186.868816 -197.915022) (xy 186.889905 -197.900673)
			(xy 186.935566 -197.877942) (xy 186.984172 -197.862483) (xy 187.034575 -197.85466) (xy 187.085581 -197.85466)
			(xy 187.135984 -197.862483) (xy 187.18459 -197.877942) (xy 187.230251 -197.900673) (xy 187.25134 -197.915022)
			(xy 187.257868 -197.91932) (xy 187.27274 -197.9241) (xy 187.28055 -197.92442) (xy 187.796678 -197.92442)
			(xy 187.802105 -197.924792) (xy 187.809792 -197.932456) (xy 187.81014 -197.937882) (xy 187.81014 -198.43242)
			(xy 193.854324 -198.43242) (xy 193.854324 -197.937882) (xy 193.854809 -197.932579) (xy 193.862239 -197.92501)
			(xy 193.867532 -197.92442) (xy 194.38366 -197.92442) (xy 194.39147 -197.924103) (xy 194.406342 -197.919321)
			(xy 194.41287 -197.915022) (xy 194.433959 -197.900673) (xy 194.47962 -197.877942) (xy 194.528226 -197.862483)
			(xy 194.578629 -197.85466) (xy 194.629635 -197.85466) (xy 194.680038 -197.862483) (xy 194.728644 -197.877942)
			(xy 194.774305 -197.900673) (xy 194.795394 -197.915022) (xy 194.801932 -197.919302) (xy 194.816797 -197.924094)
			(xy 194.824604 -197.92442) (xy 195.340732 -197.92442) (xy 195.346005 -197.924876) (xy 195.353448 -197.932352)
			(xy 195.35394 -197.937628) (xy 195.35394 -197.938136) (xy 195.35394 -198.43242) (xy 201.398124 -198.43242)
			(xy 201.398124 -197.937882) (xy 201.398609 -197.932579) (xy 201.406039 -197.92501) (xy 201.411332 -197.92442)
			(xy 201.92746 -197.92442) (xy 201.93527 -197.924103) (xy 201.950142 -197.919321) (xy 201.95667 -197.915022)
			(xy 201.977759 -197.900673) (xy 202.02342 -197.877942) (xy 202.072026 -197.862483) (xy 202.122429 -197.85466)
			(xy 202.173435 -197.85466) (xy 202.223838 -197.862483) (xy 202.272444 -197.877942) (xy 202.318105 -197.900673)
			(xy 202.339194 -197.915022) (xy 202.345732 -197.919302) (xy 202.360597 -197.924094) (xy 202.368404 -197.92442)
			(xy 202.884532 -197.92442) (xy 202.889805 -197.924876) (xy 202.897248 -197.932352) (xy 202.89774 -197.937628)
			(xy 202.89774 -197.938136) (xy 202.89774 -198.432166) (xy 264.798048 -198.432166) (xy 264.798048 -197.937628)
			(xy 264.798609 -197.932379) (xy 264.80601 -197.924938) (xy 264.811256 -197.92442) (xy 264.811764 -197.92442)
			(xy 265.327638 -197.92442) (xy 265.335447 -197.924093) (xy 265.350319 -197.919318) (xy 265.356848 -197.915022)
			(xy 265.377937 -197.900673) (xy 265.423598 -197.877942) (xy 265.472204 -197.862483) (xy 265.522607 -197.85466)
			(xy 265.573613 -197.85466) (xy 265.624016 -197.862483) (xy 265.672622 -197.877942) (xy 265.718283 -197.900673)
			(xy 265.739372 -197.915022) (xy 265.745915 -197.919294) (xy 265.760776 -197.92409) (xy 265.768582 -197.92442)
			(xy 266.28471 -197.92442) (xy 266.290011 -197.924914) (xy 266.29758 -197.932338) (xy 266.298172 -197.937628)
			(xy 266.298172 -198.432166) (xy 266.298155 -198.43242) (xy 272.342356 -198.43242) (xy 272.342356 -198.431912)
			(xy 272.342356 -197.937628) (xy 272.34291 -197.932377) (xy 272.350316 -197.924935) (xy 272.355564 -197.92442)
			(xy 272.871692 -197.92442) (xy 272.879503 -197.924116) (xy 272.894375 -197.919325) (xy 272.900902 -197.915022)
			(xy 272.921991 -197.900673) (xy 272.967652 -197.877942) (xy 273.016258 -197.862483) (xy 273.066661 -197.85466)
			(xy 273.117667 -197.85466) (xy 273.16807 -197.862483) (xy 273.216676 -197.877942) (xy 273.262337 -197.900673)
			(xy 273.283426 -197.915022) (xy 273.289957 -197.919315) (xy 273.304827 -197.924098) (xy 273.312636 -197.92442)
			(xy 273.828764 -197.92442) (xy 273.834098 -197.924754) (xy 273.841643 -197.932294) (xy 273.841972 -197.937628)
			(xy 273.841972 -198.432166) (xy 273.841947 -198.43242) (xy 279.886156 -198.43242) (xy 279.886156 -198.431912)
			(xy 279.886156 -197.937628) (xy 279.88671 -197.932377) (xy 279.894116 -197.924935) (xy 279.899364 -197.92442)
			(xy 280.415492 -197.92442) (xy 280.423303 -197.924116) (xy 280.438175 -197.919325) (xy 280.444702 -197.915022)
			(xy 280.465791 -197.900673) (xy 280.511452 -197.877942) (xy 280.560058 -197.862483) (xy 280.610461 -197.85466)
			(xy 280.661467 -197.85466) (xy 280.71187 -197.862483) (xy 280.760476 -197.877942) (xy 280.806137 -197.900673)
			(xy 280.827226 -197.915022) (xy 280.833757 -197.919315) (xy 280.848627 -197.924098) (xy 280.856436 -197.92442)
			(xy 281.372564 -197.92442) (xy 281.377898 -197.924754) (xy 281.385443 -197.932294) (xy 281.385772 -197.937628)
			(xy 281.385772 -198.432166) (xy 287.429956 -198.432166) (xy 287.429956 -197.937628) (xy 287.43051 -197.932377)
			(xy 287.437916 -197.924935) (xy 287.443164 -197.92442) (xy 287.443672 -197.92442) (xy 287.959546 -197.92442)
			(xy 287.967355 -197.924097) (xy 287.982228 -197.919319) (xy 287.988756 -197.915022) (xy 288.009845 -197.900673)
			(xy 288.055506 -197.877942) (xy 288.104112 -197.862483) (xy 288.154515 -197.85466) (xy 288.205521 -197.85466)
			(xy 288.255924 -197.862483) (xy 288.30453 -197.877942) (xy 288.350191 -197.900673) (xy 288.37128 -197.915022)
			(xy 288.377821 -197.919297) (xy 288.392684 -197.924092) (xy 288.40049 -197.92442) (xy 288.916618 -197.92442)
			(xy 288.92192 -197.924909) (xy 288.929489 -197.932336) (xy 288.93008 -197.937628) (xy 288.93008 -198.432166)
			(xy 288.930062 -198.43242) (xy 294.974264 -198.43242) (xy 294.974264 -198.431912) (xy 294.974264 -197.937628)
			(xy 294.97481 -197.932375) (xy 294.982222 -197.924933) (xy 294.987472 -197.92442) (xy 295.5036 -197.92442)
			(xy 295.511412 -197.92412) (xy 295.526283 -197.919326) (xy 295.53281 -197.915022) (xy 295.553899 -197.900673)
			(xy 295.59956 -197.877942) (xy 295.648166 -197.862483) (xy 295.698569 -197.85466) (xy 295.749575 -197.85466)
			(xy 295.799978 -197.862483) (xy 295.848584 -197.877942) (xy 295.894245 -197.900673) (xy 295.915334 -197.915022)
			(xy 295.921863 -197.919318) (xy 295.936735 -197.924099) (xy 295.944544 -197.92442) (xy 296.460672 -197.92442)
			(xy 296.466007 -197.924748) (xy 296.473552 -197.932293) (xy 296.47388 -197.937628) (xy 296.47388 -198.432166)
			(xy 302.518064 -198.432166) (xy 302.518064 -197.937628) (xy 302.51861 -197.932375) (xy 302.526022 -197.924933)
			(xy 302.531272 -197.92442) (xy 304.004726 -197.92442) (xy 304.010029 -197.924904) (xy 304.017597 -197.932335)
			(xy 304.018188 -197.937628) (xy 304.018188 -198.432166) (xy 304.01817 -198.43242) (xy 411.618176 -198.43242)
			(xy 411.618176 -198.431912) (xy 411.618176 -197.937628) (xy 411.618544 -197.932303) (xy 411.62606 -197.924762)
			(xy 411.631384 -197.92442) (xy 413.104584 -197.92442) (xy 413.109921 -197.92474) (xy 413.117465 -197.932291)
			(xy 413.117792 -197.937628) (xy 413.117792 -198.432166) (xy 419.161976 -198.432166) (xy 419.161976 -197.937628)
			(xy 419.162344 -197.932303) (xy 419.16986 -197.924762) (xy 419.175184 -197.92442) (xy 419.175692 -197.92442)
			(xy 419.691566 -197.92442) (xy 419.699376 -197.924105) (xy 419.714248 -197.919321) (xy 419.720776 -197.915022)
			(xy 419.741865 -197.900673) (xy 419.787526 -197.877942) (xy 419.836132 -197.862483) (xy 419.886535 -197.85466)
			(xy 419.937541 -197.85466) (xy 419.987944 -197.862483) (xy 420.03655 -197.877942) (xy 420.082211 -197.900673)
			(xy 420.1033 -197.915022) (xy 420.109837 -197.919305) (xy 420.124703 -197.924094) (xy 420.13251 -197.92442)
			(xy 420.648638 -197.92442) (xy 420.653942 -197.924896) (xy 420.66151 -197.932333) (xy 420.6621 -197.937628)
			(xy 420.6621 -198.432166) (xy 420.662073 -198.43242) (xy 426.706284 -198.43242) (xy 426.706284 -198.431912)
			(xy 426.706284 -197.937628) (xy 426.706645 -197.932301) (xy 426.714166 -197.924759) (xy 426.719492 -197.92442)
			(xy 427.23562 -197.92442) (xy 427.243432 -197.924128) (xy 427.258304 -197.919328) (xy 427.26483 -197.915022)
			(xy 427.285919 -197.900673) (xy 427.33158 -197.877942) (xy 427.380186 -197.862483) (xy 427.430589 -197.85466)
			(xy 427.481595 -197.85466) (xy 427.531998 -197.862483) (xy 427.580604 -197.877942) (xy 427.626265 -197.900673)
			(xy 427.647354 -197.915022) (xy 427.653879 -197.919325) (xy 427.668754 -197.924102) (xy 427.676564 -197.92442)
			(xy 428.192692 -197.92442) (xy 428.19803 -197.924735) (xy 428.205573 -197.932289) (xy 428.2059 -197.937628)
			(xy 428.2059 -198.432166) (xy 434.250084 -198.432166) (xy 434.250084 -197.937628) (xy 434.250445 -197.932301)
			(xy 434.257966 -197.924759) (xy 434.263292 -197.92442) (xy 434.2638 -197.92442) (xy 434.779674 -197.92442)
			(xy 434.787485 -197.924109) (xy 434.802356 -197.919322) (xy 434.808884 -197.915022) (xy 434.829973 -197.900673)
			(xy 434.875634 -197.877942) (xy 434.92424 -197.862483) (xy 434.974643 -197.85466) (xy 435.025649 -197.85466)
			(xy 435.076052 -197.862483) (xy 435.124658 -197.877942) (xy 435.170319 -197.900673) (xy 435.191408 -197.915022)
			(xy 435.197943 -197.919308) (xy 435.21281 -197.924096) (xy 435.220618 -197.92442) (xy 435.736746 -197.92442)
			(xy 435.742039 -197.924957) (xy 435.749612 -197.932348) (xy 435.750208 -197.937628) (xy 435.750208 -198.432166)
			(xy 435.750181 -198.43242) (xy 441.794392 -198.43242) (xy 441.794392 -198.431912) (xy 441.794392 -197.937628)
			(xy 441.794745 -197.932299) (xy 441.802272 -197.924757) (xy 441.8076 -197.92442) (xy 442.323728 -197.92442)
			(xy 442.331541 -197.924131) (xy 442.346412 -197.91933) (xy 442.352938 -197.915022) (xy 442.374027 -197.900673)
			(xy 442.419688 -197.877942) (xy 442.468294 -197.862483) (xy 442.518697 -197.85466) (xy 442.569703 -197.85466)
			(xy 442.620106 -197.862483) (xy 442.668712 -197.877942) (xy 442.714373 -197.900673) (xy 442.735462 -197.915022)
			(xy 442.742007 -197.91929) (xy 442.756867 -197.924089) (xy 442.764672 -197.92442) (xy 443.2808 -197.92442)
			(xy 443.286139 -197.924729) (xy 443.293682 -197.932288) (xy 443.294008 -197.937628) (xy 443.294008 -198.432166)
			(xy 443.293982 -198.43242) (xy 449.338192 -198.43242) (xy 449.338192 -198.431912) (xy 449.338192 -197.937628)
			(xy 449.338545 -197.932299) (xy 449.346072 -197.924757) (xy 449.3514 -197.92442) (xy 449.867528 -197.92442)
			(xy 449.875341 -197.924131) (xy 449.890212 -197.91933) (xy 449.896738 -197.915022) (xy 449.917827 -197.900673)
			(xy 449.963488 -197.877942) (xy 450.012094 -197.862483) (xy 450.062497 -197.85466) (xy 450.113503 -197.85466)
			(xy 450.163906 -197.862483) (xy 450.212512 -197.877942) (xy 450.258173 -197.900673) (xy 450.279262 -197.915022)
			(xy 450.285807 -197.91929) (xy 450.300667 -197.924089) (xy 450.308472 -197.92442) (xy 450.8246 -197.92442)
			(xy 450.829939 -197.924729) (xy 450.837482 -197.932288) (xy 450.837808 -197.937628) (xy 450.837808 -198.432166)
			(xy 450.83726 -198.437455) (xy 450.829876 -198.445025) (xy 450.8246 -198.445628) (xy 450.308726 -198.445628)
			(xy 450.300916 -198.445948) (xy 450.286045 -198.450729) (xy 450.279516 -198.455026) (xy 450.258385 -198.469361)
			(xy 450.212665 -198.492092) (xy 450.163995 -198.507526) (xy 450.11353 -198.515297) (xy 450.088 -198.515732)
			(xy 450.062469 -198.515301) (xy 450.012005 -198.507525) (xy 449.963333 -198.492094) (xy 449.917605 -198.469375)
			(xy 449.896484 -198.455026) (xy 449.889954 -198.450733) (xy 449.875083 -198.445951) (xy 449.867274 -198.445628)
			(xy 449.3514 -198.445628) (xy 449.346142 -198.445107) (xy 449.338701 -198.437677) (xy 449.338192 -198.43242)
			(xy 443.293982 -198.43242) (xy 443.29346 -198.437455) (xy 443.286076 -198.445025) (xy 443.2808 -198.445628)
			(xy 442.764926 -198.445628) (xy 442.757116 -198.445948) (xy 442.742245 -198.450729) (xy 442.735716 -198.455026)
			(xy 442.714585 -198.469361) (xy 442.668865 -198.492092) (xy 442.620195 -198.507526) (xy 442.56973 -198.515297)
			(xy 442.5442 -198.515732) (xy 442.518669 -198.515301) (xy 442.468205 -198.507525) (xy 442.419533 -198.492094)
			(xy 442.373805 -198.469375) (xy 442.352684 -198.455026) (xy 442.346154 -198.450733) (xy 442.331283 -198.445951)
			(xy 442.323474 -198.445628) (xy 441.8076 -198.445628) (xy 441.802342 -198.445107) (xy 441.794901 -198.437677)
			(xy 441.794392 -198.43242) (xy 435.750181 -198.43242) (xy 435.749631 -198.437515) (xy 435.742092 -198.4451)
			(xy 435.736746 -198.445628) (xy 435.220872 -198.445628) (xy 435.21306 -198.445925) (xy 435.198189 -198.450722)
			(xy 435.191662 -198.455026) (xy 435.170546 -198.469385) (xy 435.124821 -198.49211) (xy 435.076146 -198.507538)
			(xy 435.025678 -198.515301) (xy 435.000146 -198.515732) (xy 434.974616 -198.515278) (xy 434.924153 -198.507509)
			(xy 434.87548 -198.492085) (xy 434.829752 -198.469372) (xy 434.80863 -198.455026) (xy 434.802089 -198.45075)
			(xy 434.787226 -198.445957) (xy 434.77942 -198.445628) (xy 434.263546 -198.445628) (xy 434.258109 -198.445287)
			(xy 434.250418 -198.437603) (xy 434.250084 -198.432166) (xy 428.2059 -198.432166) (xy 428.205359 -198.437457)
			(xy 428.19797 -198.445028) (xy 428.192692 -198.445628) (xy 427.676818 -198.445628) (xy 427.669008 -198.445944)
			(xy 427.654136 -198.450728) (xy 427.647608 -198.455026) (xy 427.62648 -198.469365) (xy 427.580758 -198.492095)
			(xy 427.532087 -198.507528) (xy 427.481622 -198.515297) (xy 427.456092 -198.515732) (xy 427.430561 -198.515305)
			(xy 427.380097 -198.507527) (xy 427.331424 -198.492096) (xy 427.285697 -198.469375) (xy 427.264576 -198.455026)
			(xy 427.258047 -198.45073) (xy 427.243175 -198.445949) (xy 427.235366 -198.445628) (xy 426.719492 -198.445628)
			(xy 426.714233 -198.445113) (xy 426.706792 -198.437678) (xy 426.706284 -198.43242) (xy 420.662073 -198.43242)
			(xy 420.661531 -198.437517) (xy 420.653986 -198.445102) (xy 420.648638 -198.445628) (xy 420.132764 -198.445628)
			(xy 420.124956 -198.445964) (xy 420.110084 -198.450734) (xy 420.103554 -198.455026) (xy 420.082441 -198.469388)
			(xy 420.036714 -198.492113) (xy 419.988038 -198.507539) (xy 419.93757 -198.515302) (xy 419.912038 -198.515732)
			(xy 419.886508 -198.515282) (xy 419.836045 -198.507511) (xy 419.787372 -198.492086) (xy 419.741644 -198.469372)
			(xy 419.720522 -198.455026) (xy 419.713983 -198.450747) (xy 419.699119 -198.445956) (xy 419.691312 -198.445628)
			(xy 419.175438 -198.445628) (xy 419.17 -198.445292) (xy 419.16231 -198.437604) (xy 419.161976 -198.432166)
			(xy 413.117792 -198.432166) (xy 413.117258 -198.437459) (xy 413.109864 -198.44503) (xy 413.104584 -198.445628)
			(xy 411.631384 -198.445628) (xy 411.626124 -198.445118) (xy 411.618683 -198.43768) (xy 411.618176 -198.43242)
			(xy 304.01817 -198.43242) (xy 304.017801 -198.43759) (xy 304.010148 -198.445276) (xy 304.004726 -198.445628)
			(xy 302.531526 -198.445628) (xy 302.526086 -198.4453) (xy 302.518397 -198.437606) (xy 302.518064 -198.432166)
			(xy 296.47388 -198.432166) (xy 296.473357 -198.437462) (xy 296.465955 -198.445033) (xy 296.460672 -198.445628)
			(xy 295.944798 -198.445628) (xy 295.936987 -198.445936) (xy 295.922116 -198.450725) (xy 295.915588 -198.455026)
			(xy 295.894465 -198.469374) (xy 295.848742 -198.492101) (xy 295.800069 -198.507532) (xy 295.749603 -198.515299)
			(xy 295.724072 -198.515732) (xy 295.698541 -198.515315) (xy 295.648076 -198.507534) (xy 295.599403 -198.4921)
			(xy 295.553677 -198.469377) (xy 295.532556 -198.455026) (xy 295.526032 -198.450722) (xy 295.511156 -198.445947)
			(xy 295.503346 -198.445628) (xy 294.987472 -198.445628) (xy 294.982211 -198.445126) (xy 294.974771 -198.437682)
			(xy 294.974264 -198.43242) (xy 288.930062 -198.43242) (xy 288.9297 -198.437592) (xy 288.922043 -198.445279)
			(xy 288.916618 -198.445628) (xy 288.400744 -198.445628) (xy 288.392935 -198.445956) (xy 288.378064 -198.450732)
			(xy 288.371534 -198.455026) (xy 288.350426 -198.469397) (xy 288.304698 -198.492119) (xy 288.25602 -198.507544)
			(xy 288.20555 -198.515303) (xy 288.180018 -198.515732) (xy 288.154488 -198.515292) (xy 288.104024 -198.507518)
			(xy 288.055351 -198.49209) (xy 288.009624 -198.469374) (xy 287.988502 -198.455026) (xy 287.981968 -198.45074)
			(xy 287.9671 -198.445953) (xy 287.959292 -198.445628) (xy 287.443418 -198.445628) (xy 287.437977 -198.445305)
			(xy 287.430288 -198.437607) (xy 287.429956 -198.432166) (xy 281.385772 -198.432166) (xy 281.385256 -198.437463)
			(xy 281.377849 -198.445036) (xy 281.372564 -198.445628) (xy 280.85669 -198.445628) (xy 280.848879 -198.445933)
			(xy 280.834007 -198.450724) (xy 280.82748 -198.455026) (xy 280.806359 -198.469377) (xy 280.760636 -198.492104)
			(xy 280.711962 -198.507534) (xy 280.661495 -198.5153) (xy 280.635964 -198.515732) (xy 280.610433 -198.515319)
			(xy 280.559968 -198.507537) (xy 280.511295 -198.492101) (xy 280.465569 -198.469377) (xy 280.444448 -198.455026)
			(xy 280.437926 -198.450719) (xy 280.423049 -198.445945) (xy 280.415238 -198.445628) (xy 279.899364 -198.445628)
			(xy 279.894102 -198.445131) (xy 279.886663 -198.437683) (xy 279.886156 -198.43242) (xy 273.841947 -198.43242)
			(xy 273.841456 -198.437463) (xy 273.834049 -198.445036) (xy 273.828764 -198.445628) (xy 273.31289 -198.445628)
			(xy 273.305079 -198.445933) (xy 273.290207 -198.450724) (xy 273.28368 -198.455026) (xy 273.262559 -198.469377)
			(xy 273.216836 -198.492104) (xy 273.168162 -198.507534) (xy 273.117695 -198.5153) (xy 273.092164 -198.515732)
			(xy 273.066633 -198.515319) (xy 273.016168 -198.507537) (xy 272.967495 -198.492101) (xy 272.921769 -198.469377)
			(xy 272.900648 -198.455026) (xy 272.894126 -198.450719) (xy 272.879249 -198.445945) (xy 272.871438 -198.445628)
			(xy 272.355564 -198.445628) (xy 272.350302 -198.445131) (xy 272.342863 -198.437683) (xy 272.342356 -198.43242)
			(xy 266.298155 -198.43242) (xy 266.297799 -198.437594) (xy 266.290137 -198.445281) (xy 266.28471 -198.445628)
			(xy 265.768836 -198.445628) (xy 265.761027 -198.445953) (xy 265.746155 -198.450731) (xy 265.739626 -198.455026)
			(xy 265.718493 -198.469357) (xy 265.672773 -198.492089) (xy 265.624104 -198.507524) (xy 265.57364 -198.515296)
			(xy 265.54811 -198.515732) (xy 265.52258 -198.515296) (xy 265.472116 -198.507521) (xy 265.423443 -198.492092)
			(xy 265.377716 -198.469374) (xy 265.356594 -198.455026) (xy 265.350061 -198.450736) (xy 265.335192 -198.445952)
			(xy 265.327384 -198.445628) (xy 264.81151 -198.445628) (xy 264.806068 -198.445311) (xy 264.798379 -198.437608)
			(xy 264.798048 -198.432166) (xy 202.89774 -198.432166) (xy 202.89774 -198.43242) (xy 202.897222 -198.437677)
			(xy 202.889789 -198.445117) (xy 202.884532 -198.445628) (xy 202.368658 -198.445628) (xy 202.360783 -198.445909)
			(xy 202.345779 -198.450697) (xy 202.339194 -198.455026) (xy 202.318107 -198.469403) (xy 202.272466 -198.492235)
			(xy 202.223863 -198.507797) (xy 202.173448 -198.515721) (xy 202.147932 -198.51624) (xy 202.122412 -198.515744)
			(xy 202.071986 -198.50785) (xy 202.023374 -198.492292) (xy 201.977736 -198.46944) (xy 201.95667 -198.455026)
			(xy 201.950085 -198.450699) (xy 201.93508 -198.445919) (xy 201.927206 -198.445628) (xy 201.411332 -198.445628)
			(xy 201.406009 -198.445254) (xy 201.398467 -198.437742) (xy 201.398124 -198.43242) (xy 195.35394 -198.43242)
			(xy 195.353422 -198.437677) (xy 195.345989 -198.445117) (xy 195.340732 -198.445628) (xy 194.824858 -198.445628)
			(xy 194.816983 -198.445909) (xy 194.801979 -198.450697) (xy 194.795394 -198.455026) (xy 194.774307 -198.469403)
			(xy 194.728666 -198.492235) (xy 194.680063 -198.507797) (xy 194.629648 -198.515721) (xy 194.604132 -198.51624)
			(xy 194.578612 -198.515744) (xy 194.528186 -198.50785) (xy 194.479574 -198.492292) (xy 194.433936 -198.46944)
			(xy 194.41287 -198.455026) (xy 194.406285 -198.450699) (xy 194.39128 -198.445919) (xy 194.383406 -198.445628)
			(xy 193.867532 -198.445628) (xy 193.862209 -198.445254) (xy 193.854667 -198.437742) (xy 193.854324 -198.43242)
			(xy 187.81014 -198.43242) (xy 187.809622 -198.437677) (xy 187.802189 -198.445117) (xy 187.796932 -198.445628)
			(xy 187.796424 -198.445628) (xy 187.280804 -198.445628) (xy 187.272931 -198.445929) (xy 187.257927 -198.450704)
			(xy 187.25134 -198.455026) (xy 187.230268 -198.469426) (xy 187.184621 -198.492253) (xy 187.136014 -198.507809)
			(xy 187.085595 -198.515725) (xy 187.060078 -198.51624) (xy 187.034559 -198.515721) (xy 186.984134 -198.507834)
			(xy 186.935522 -198.492283) (xy 186.889882 -198.469437) (xy 186.868816 -198.455026) (xy 186.862221 -198.450717)
			(xy 186.847224 -198.445926) (xy 186.839352 -198.445628) (xy 186.323478 -198.445628) (xy 186.318164 -198.445188)
			(xy 186.310592 -198.437726) (xy 186.310016 -198.43242) (xy 180.265832 -198.43242) (xy 180.265321 -198.437679)
			(xy 180.257883 -198.445119) (xy 180.252624 -198.445628) (xy 179.73675 -198.445628) (xy 179.728875 -198.445905)
			(xy 179.713871 -198.450696) (xy 179.707286 -198.455026) (xy 179.686201 -198.469406) (xy 179.640559 -198.492238)
			(xy 179.591955 -198.507799) (xy 179.54154 -198.515721) (xy 179.516024 -198.51624) (xy 179.490504 -198.515748)
			(xy 179.440077 -198.507853) (xy 179.391466 -198.492294) (xy 179.345827 -198.46944) (xy 179.324762 -198.455026)
			(xy 179.318179 -198.450696) (xy 179.303172 -198.445918) (xy 179.295298 -198.445628) (xy 178.779424 -198.445628)
			(xy 178.7741 -198.445259) (xy 178.766559 -198.437743) (xy 178.766216 -198.43242) (xy 172.722032 -198.43242)
			(xy 172.721521 -198.437679) (xy 172.714083 -198.445119) (xy 172.708824 -198.445628) (xy 172.708316 -198.445628)
			(xy 172.192696 -198.445628) (xy 172.184822 -198.445925) (xy 172.169819 -198.450703) (xy 172.163232 -198.455026)
			(xy 172.142162 -198.469429) (xy 172.096515 -198.492256) (xy 172.047906 -198.50781) (xy 171.997487 -198.515725)
			(xy 171.97197 -198.51624) (xy 171.946451 -198.515725) (xy 171.896025 -198.507837) (xy 171.847414 -198.492284)
			(xy 171.801774 -198.469437) (xy 171.780708 -198.455026) (xy 171.774115 -198.450714) (xy 171.759116 -198.445925)
			(xy 171.751244 -198.445628) (xy 171.23537 -198.445628) (xy 171.230055 -198.445193) (xy 171.222483 -198.437728)
			(xy 171.221908 -198.43242) (xy 165.177724 -198.43242) (xy 165.17722 -198.437681) (xy 165.169777 -198.445122)
			(xy 165.164516 -198.445628) (xy 163.691316 -198.445628) (xy 163.68606 -198.445097) (xy 163.678618 -198.437675)
			(xy 163.678108 -198.43242) (xy 56.07812 -198.43242) (xy 56.07762 -198.437682) (xy 56.070175 -198.445123)
			(xy 56.064912 -198.445628) (xy 54.591458 -198.445628) (xy 54.586141 -198.445201) (xy 54.578571 -198.43773)
			(xy 54.577996 -198.43242) (xy 48.533812 -198.43242) (xy 48.533319 -198.437684) (xy 48.525869 -198.445125)
			(xy 48.520604 -198.445628) (xy 48.00473 -198.445628) (xy 47.996854 -198.445897) (xy 47.98185 -198.450694)
			(xy 47.975266 -198.455026) (xy 47.954187 -198.469415) (xy 47.908543 -198.492244) (xy 47.859937 -198.507803)
			(xy 47.809521 -198.515723) (xy 47.784004 -198.51624) (xy 47.758484 -198.515758) (xy 47.708057 -198.50786)
			(xy 47.659445 -198.492298) (xy 47.613807 -198.469441) (xy 47.592742 -198.455026) (xy 47.586164 -198.450688)
			(xy 47.571153 -198.445915) (xy 47.563278 -198.445628) (xy 47.047404 -198.445628) (xy 47.042147 -198.445105)
			(xy 47.034705 -198.437677) (xy 47.034196 -198.43242) (xy 40.990012 -198.43242) (xy 40.989519 -198.437684)
			(xy 40.982069 -198.445125) (xy 40.976804 -198.445628) (xy 40.976296 -198.445628) (xy 40.460676 -198.445628)
			(xy 40.452802 -198.445916) (xy 40.437798 -198.4507) (xy 40.431212 -198.455026) (xy 40.410148 -198.469438)
			(xy 40.364498 -198.492262) (xy 40.315888 -198.507815) (xy 40.265468 -198.515727) (xy 40.23995 -198.51624)
			(xy 40.214431 -198.515735) (xy 40.164005 -198.507844) (xy 40.115393 -198.492288) (xy 40.069754 -198.469438)
			(xy 40.048688 -198.455026) (xy 40.042099 -198.450706) (xy 40.027097 -198.445922) (xy 40.019224 -198.445628)
			(xy 39.50335 -198.445628) (xy 39.498044 -198.44514) (xy 39.490469 -198.437715) (xy 39.489888 -198.43242)
			(xy 33.445704 -198.43242) (xy 33.445218 -198.437686) (xy 33.437763 -198.445128) (xy 33.432496 -198.445628)
			(xy 32.916622 -198.445628) (xy 32.908749 -198.445937) (xy 32.893745 -198.450706) (xy 32.887158 -198.455026)
			(xy 32.866081 -198.469418) (xy 32.820436 -198.492247) (xy 32.77183 -198.507805) (xy 32.721413 -198.515723)
			(xy 32.695896 -198.51624) (xy 32.670375 -198.515762) (xy 32.619948 -198.507863) (xy 32.571337 -198.492299)
			(xy 32.525699 -198.469442) (xy 32.504634 -198.455026) (xy 32.498035 -198.450724) (xy 32.483041 -198.445929)
			(xy 32.47517 -198.445628) (xy 31.959296 -198.445628) (xy 31.954038 -198.44511) (xy 31.946596 -198.437678)
			(xy 31.946088 -198.43242) (xy 25.901904 -198.43242) (xy 25.901418 -198.437686) (xy 25.893963 -198.445128)
			(xy 25.888696 -198.445628) (xy 25.372822 -198.445628) (xy 25.364949 -198.445937) (xy 25.349945 -198.450706)
			(xy 25.343358 -198.455026) (xy 25.322281 -198.469418) (xy 25.276636 -198.492247) (xy 25.22803 -198.507805)
			(xy 25.177613 -198.515723) (xy 25.152096 -198.51624) (xy 25.126575 -198.515762) (xy 25.076148 -198.507863)
			(xy 25.027537 -198.492299) (xy 24.981899 -198.469442) (xy 24.960834 -198.455026) (xy 24.954235 -198.450724)
			(xy 24.939241 -198.445929) (xy 24.93137 -198.445628) (xy 24.415496 -198.445628) (xy 24.410238 -198.44511)
			(xy 24.402796 -198.437678) (xy 24.402288 -198.43242) (xy 18.358104 -198.43242) (xy 18.357618 -198.437686)
			(xy 18.350163 -198.445128) (xy 18.344896 -198.445628) (xy 18.344388 -198.445628) (xy 17.828768 -198.445628)
			(xy 17.820893 -198.445913) (xy 17.805889 -198.450699) (xy 17.799304 -198.455026) (xy 17.778214 -198.469398)
			(xy 17.732574 -198.492232) (xy 17.683972 -198.507795) (xy 17.633558 -198.51572) (xy 17.608042 -198.51624)
			(xy 17.582522 -198.515739) (xy 17.532096 -198.507847) (xy 17.483485 -198.49229) (xy 17.437846 -198.469439)
			(xy 17.41678 -198.455026) (xy 17.410193 -198.450703) (xy 17.39519 -198.445921) (xy 17.387316 -198.445628)
			(xy 16.871442 -198.445628) (xy 16.866135 -198.445145) (xy 16.85856 -198.437716) (xy 16.85798 -198.43242)
			(xy 2.509012 -198.43242) (xy 2.509012 -199.282558) (xy 20.958048 -199.282558) (xy 20.958048 -198.78802)
			(xy 20.958603 -198.78277) (xy 20.966009 -198.775329) (xy 20.971256 -198.774812) (xy 20.971764 -198.774812)
			(xy 21.487638 -198.774812) (xy 21.495447 -198.774487) (xy 21.510319 -198.76971) (xy 21.516848 -198.765414)
			(xy 21.537937 -198.751065) (xy 21.583598 -198.728334) (xy 21.632204 -198.712875) (xy 21.682607 -198.705052)
			(xy 21.733613 -198.705052) (xy 21.784016 -198.712875) (xy 21.832622 -198.728334) (xy 21.878283 -198.751065)
			(xy 21.899372 -198.765414) (xy 21.905916 -198.769685) (xy 21.920776 -198.774482) (xy 21.928582 -198.774812)
			(xy 22.44471 -198.774812) (xy 22.450009 -198.775313) (xy 22.457578 -198.782732) (xy 22.458172 -198.78802)
			(xy 22.458172 -199.282558) (xy 22.458154 -199.282812) (xy 28.502356 -199.282812) (xy 28.502356 -199.282304)
			(xy 28.502356 -198.78802) (xy 28.502904 -198.782768) (xy 28.510314 -198.775326) (xy 28.515564 -198.774812)
			(xy 29.031692 -198.774812) (xy 29.039503 -198.77451) (xy 29.054375 -198.769717) (xy 29.060902 -198.765414)
			(xy 29.081991 -198.751065) (xy 29.127652 -198.728334) (xy 29.176258 -198.712875) (xy 29.226661 -198.705052)
			(xy 29.277667 -198.705052) (xy 29.32807 -198.712875) (xy 29.376676 -198.728334) (xy 29.422337 -198.751065)
			(xy 29.443426 -198.765414) (xy 29.449957 -198.769706) (xy 29.464827 -198.77449) (xy 29.472636 -198.774812)
			(xy 29.988764 -198.774812) (xy 29.994096 -198.775153) (xy 30.001641 -198.782688) (xy 30.001972 -198.78802)
			(xy 30.001972 -199.282558) (xy 30.001947 -199.282812) (xy 36.046156 -199.282812) (xy 36.046156 -199.282304)
			(xy 36.046156 -198.78802) (xy 36.046704 -198.782768) (xy 36.054114 -198.775326) (xy 36.059364 -198.774812)
			(xy 36.575492 -198.774812) (xy 36.583303 -198.77451) (xy 36.598175 -198.769717) (xy 36.604702 -198.765414)
			(xy 36.625791 -198.751065) (xy 36.671452 -198.728334) (xy 36.720058 -198.712875) (xy 36.770461 -198.705052)
			(xy 36.821467 -198.705052) (xy 36.87187 -198.712875) (xy 36.920476 -198.728334) (xy 36.966137 -198.751065)
			(xy 36.987226 -198.765414) (xy 36.993757 -198.769706) (xy 37.008627 -198.77449) (xy 37.016436 -198.774812)
			(xy 37.532564 -198.774812) (xy 37.537896 -198.775153) (xy 37.545441 -198.782688) (xy 37.545772 -198.78802)
			(xy 37.545772 -199.282558) (xy 43.589956 -199.282558) (xy 43.589956 -198.78802) (xy 43.590504 -198.782768)
			(xy 43.597914 -198.775326) (xy 43.603164 -198.774812) (xy 43.603672 -198.774812) (xy 44.119546 -198.774812)
			(xy 44.127356 -198.77449) (xy 44.142228 -198.769711) (xy 44.148756 -198.765414) (xy 44.169845 -198.751065)
			(xy 44.215506 -198.728334) (xy 44.264112 -198.712875) (xy 44.314515 -198.705052) (xy 44.365521 -198.705052)
			(xy 44.415924 -198.712875) (xy 44.46453 -198.728334) (xy 44.510191 -198.751065) (xy 44.53128 -198.765414)
			(xy 44.537822 -198.769688) (xy 44.552684 -198.774483) (xy 44.56049 -198.774812) (xy 45.076618 -198.774812)
			(xy 45.081918 -198.775308) (xy 45.089486 -198.782731) (xy 45.09008 -198.78802) (xy 45.09008 -199.282558)
			(xy 45.090062 -199.282812) (xy 51.134264 -199.282812) (xy 51.134264 -199.282304) (xy 51.134264 -198.78802)
			(xy 51.134805 -198.782766) (xy 51.14222 -198.775324) (xy 51.147472 -198.774812) (xy 51.6636 -198.774812)
			(xy 51.671412 -198.774513) (xy 51.686284 -198.769718) (xy 51.69281 -198.765414) (xy 51.713899 -198.751065)
			(xy 51.75956 -198.728334) (xy 51.808166 -198.712875) (xy 51.858569 -198.705052) (xy 51.909575 -198.705052)
			(xy 51.959978 -198.712875) (xy 52.008584 -198.728334) (xy 52.054245 -198.751065) (xy 52.075334 -198.765414)
			(xy 52.081864 -198.769709) (xy 52.096735 -198.774491) (xy 52.104544 -198.774812) (xy 52.620672 -198.774812)
			(xy 52.626005 -198.775147) (xy 52.633549 -198.782687) (xy 52.63388 -198.78802) (xy 52.63388 -199.282558)
			(xy 58.678064 -199.282558) (xy 58.678064 -198.78802) (xy 58.678605 -198.782766) (xy 58.68602 -198.775324)
			(xy 58.691272 -198.774812) (xy 58.69178 -198.774812) (xy 60.164726 -198.774812) (xy 60.170027 -198.775303)
			(xy 60.177595 -198.78273) (xy 60.178188 -198.78802) (xy 60.178188 -199.282558) (xy 60.17817 -199.282812)
			(xy 167.778176 -199.282812) (xy 167.778176 -198.78802) (xy 167.778538 -198.782694) (xy 167.786059 -198.775153)
			(xy 167.791384 -198.774812) (xy 169.264584 -198.774812) (xy 169.269919 -198.77514) (xy 169.277462 -198.782685)
			(xy 169.277792 -198.78802) (xy 169.277792 -199.282558) (xy 175.321976 -199.282558) (xy 175.321976 -198.78802)
			(xy 175.322338 -198.782694) (xy 175.329859 -198.775153) (xy 175.335184 -198.774812) (xy 175.335692 -198.774812)
			(xy 175.851566 -198.774812) (xy 175.859376 -198.774499) (xy 175.874248 -198.769714) (xy 175.880776 -198.765414)
			(xy 175.901865 -198.751065) (xy 175.947526 -198.728334) (xy 175.996132 -198.712875) (xy 176.046535 -198.705052)
			(xy 176.097541 -198.705052) (xy 176.147944 -198.712875) (xy 176.19655 -198.728334) (xy 176.242211 -198.751065)
			(xy 176.2633 -198.765414) (xy 176.269837 -198.769696) (xy 176.284703 -198.774486) (xy 176.29251 -198.774812)
			(xy 176.808638 -198.774812) (xy 176.81394 -198.775295) (xy 176.821507 -198.782728) (xy 176.8221 -198.78802)
			(xy 176.8221 -199.282558) (xy 176.822081 -199.282812) (xy 182.866284 -199.282812) (xy 182.866284 -199.282304)
			(xy 182.866284 -198.78802) (xy 182.866639 -198.782692) (xy 182.874165 -198.775151) (xy 182.879492 -198.774812)
			(xy 183.39562 -198.774812) (xy 183.403432 -198.774521) (xy 183.418304 -198.769721) (xy 183.42483 -198.765414)
			(xy 183.445919 -198.751065) (xy 183.49158 -198.728334) (xy 183.540186 -198.712875) (xy 183.590589 -198.705052)
			(xy 183.641595 -198.705052) (xy 183.691998 -198.712875) (xy 183.740604 -198.728334) (xy 183.786265 -198.751065)
			(xy 183.807354 -198.765414) (xy 183.813879 -198.769717) (xy 183.828754 -198.774494) (xy 183.836564 -198.774812)
			(xy 184.352692 -198.774812) (xy 184.358028 -198.775134) (xy 184.365571 -198.782684) (xy 184.3659 -198.78802)
			(xy 184.3659 -199.282558) (xy 190.410084 -199.282558) (xy 190.410084 -198.78802) (xy 190.410439 -198.782692)
			(xy 190.417965 -198.775151) (xy 190.423292 -198.774812) (xy 190.4238 -198.774812) (xy 190.939674 -198.774812)
			(xy 190.947485 -198.774502) (xy 190.962357 -198.769715) (xy 190.968884 -198.765414) (xy 190.989973 -198.751065)
			(xy 191.035634 -198.728334) (xy 191.08424 -198.712875) (xy 191.134643 -198.705052) (xy 191.185649 -198.705052)
			(xy 191.236052 -198.712875) (xy 191.284658 -198.728334) (xy 191.330319 -198.751065) (xy 191.351408 -198.765414)
			(xy 191.357943 -198.769699) (xy 191.37281 -198.774488) (xy 191.380618 -198.774812) (xy 191.896746 -198.774812)
			(xy 191.902037 -198.775356) (xy 191.90961 -198.782742) (xy 191.910208 -198.78802) (xy 191.910208 -199.282558)
			(xy 191.91018 -199.282812) (xy 197.954392 -199.282812) (xy 197.954392 -199.282304) (xy 197.954392 -198.78802)
			(xy 197.95474 -198.78269) (xy 197.962271 -198.775148) (xy 197.9676 -198.774812) (xy 198.483728 -198.774812)
			(xy 198.491541 -198.774525) (xy 198.506413 -198.769722) (xy 198.512938 -198.765414) (xy 198.534027 -198.751065)
			(xy 198.579688 -198.728334) (xy 198.628294 -198.712875) (xy 198.678697 -198.705052) (xy 198.729703 -198.705052)
			(xy 198.780106 -198.712875) (xy 198.828712 -198.728334) (xy 198.874373 -198.751065) (xy 198.895462 -198.765414)
			(xy 198.902008 -198.769681) (xy 198.916867 -198.774481) (xy 198.924672 -198.774812) (xy 199.4408 -198.774812)
			(xy 199.446137 -198.775129) (xy 199.453679 -198.782682) (xy 199.454008 -198.78802) (xy 199.454008 -199.282558)
			(xy 199.453981 -199.282812) (xy 205.498192 -199.282812) (xy 205.498192 -199.282304) (xy 205.498192 -198.78802)
			(xy 205.49854 -198.78269) (xy 205.506071 -198.775148) (xy 205.5114 -198.774812) (xy 206.027528 -198.774812)
			(xy 206.035341 -198.774525) (xy 206.050213 -198.769722) (xy 206.056738 -198.765414) (xy 206.077827 -198.751065)
			(xy 206.123488 -198.728334) (xy 206.172094 -198.712875) (xy 206.222497 -198.705052) (xy 206.273503 -198.705052)
			(xy 206.323906 -198.712875) (xy 206.372512 -198.728334) (xy 206.418173 -198.751065) (xy 206.439262 -198.765414)
			(xy 206.445808 -198.769681) (xy 206.460667 -198.774481) (xy 206.468472 -198.774812) (xy 206.9846 -198.774812)
			(xy 206.989937 -198.775129) (xy 206.997479 -198.782682) (xy 206.997808 -198.78802) (xy 206.997808 -199.282558)
			(xy 206.997254 -199.287846) (xy 206.989874 -199.295417) (xy 206.9846 -199.29602) (xy 206.468726 -199.29602)
			(xy 206.460917 -199.296341) (xy 206.446045 -199.301122) (xy 206.439516 -199.305418) (xy 206.418385 -199.319753)
			(xy 206.372665 -199.342484) (xy 206.323994 -199.357918) (xy 206.27353 -199.365689) (xy 206.248 -199.366124)
			(xy 206.222469 -199.365695) (xy 206.172005 -199.357918) (xy 206.123332 -199.342487) (xy 206.077605 -199.319767)
			(xy 206.056484 -199.305418) (xy 206.049954 -199.301124) (xy 206.035083 -199.296343) (xy 206.027274 -199.29602)
			(xy 205.5114 -199.29602) (xy 205.50614 -199.295506) (xy 205.498698 -199.288071) (xy 205.498192 -199.282812)
			(xy 199.453981 -199.282812) (xy 199.453454 -199.287846) (xy 199.446074 -199.295417) (xy 199.4408 -199.29602)
			(xy 198.924926 -199.29602) (xy 198.917117 -199.296341) (xy 198.902245 -199.301122) (xy 198.895716 -199.305418)
			(xy 198.874585 -199.319753) (xy 198.828865 -199.342484) (xy 198.780194 -199.357918) (xy 198.72973 -199.365689)
			(xy 198.7042 -199.366124) (xy 198.678669 -199.365695) (xy 198.628205 -199.357918) (xy 198.579532 -199.342487)
			(xy 198.533805 -199.319767) (xy 198.512684 -199.305418) (xy 198.506154 -199.301124) (xy 198.491283 -199.296343)
			(xy 198.483474 -199.29602) (xy 197.9676 -199.29602) (xy 197.96234 -199.295506) (xy 197.954898 -199.288071)
			(xy 197.954392 -199.282812) (xy 191.91018 -199.282812) (xy 191.909626 -199.287906) (xy 191.90209 -199.295491)
			(xy 191.896746 -199.29602) (xy 191.380872 -199.29602) (xy 191.37306 -199.296318) (xy 191.358189 -199.301115)
			(xy 191.351662 -199.305418) (xy 191.330546 -199.319776) (xy 191.28482 -199.342502) (xy 191.236145 -199.357929)
			(xy 191.185678 -199.365693) (xy 191.160146 -199.366124) (xy 191.134616 -199.365672) (xy 191.084153 -199.357902)
			(xy 191.03548 -199.342477) (xy 190.989752 -199.319764) (xy 190.96863 -199.305418) (xy 190.96209 -199.301142)
			(xy 190.947227 -199.296349) (xy 190.93942 -199.29602) (xy 190.423546 -199.29602) (xy 190.418107 -199.295686)
			(xy 190.410416 -199.287997) (xy 190.410084 -199.282558) (xy 184.3659 -199.282558) (xy 184.365353 -199.287848)
			(xy 184.357968 -199.295419) (xy 184.352692 -199.29602) (xy 183.836818 -199.29602) (xy 183.829008 -199.296338)
			(xy 183.814137 -199.301121) (xy 183.807608 -199.305418) (xy 183.786479 -199.319756) (xy 183.740758 -199.342486)
			(xy 183.692087 -199.35792) (xy 183.641622 -199.365689) (xy 183.616092 -199.366124) (xy 183.590561 -199.365699)
			(xy 183.540097 -199.357921) (xy 183.491424 -199.342488) (xy 183.445697 -199.319768) (xy 183.424576 -199.305418)
			(xy 183.418048 -199.301121) (xy 183.403175 -199.296341) (xy 183.395366 -199.29602) (xy 182.879492 -199.29602)
			(xy 182.874231 -199.295512) (xy 182.86679 -199.288073) (xy 182.866284 -199.282812) (xy 176.822081 -199.282812)
			(xy 176.821696 -199.287978) (xy 176.814056 -199.295664) (xy 176.808638 -199.29602) (xy 176.292764 -199.29602)
			(xy 176.284956 -199.296358) (xy 176.270084 -199.301127) (xy 176.263554 -199.305418) (xy 176.24244 -199.319779)
			(xy 176.196714 -199.342504) (xy 176.148038 -199.357931) (xy 176.09757 -199.365693) (xy 176.072038 -199.366124)
			(xy 176.046508 -199.365676) (xy 175.996044 -199.357905) (xy 175.947372 -199.342479) (xy 175.901644 -199.319765)
			(xy 175.880522 -199.305418) (xy 175.873984 -199.301138) (xy 175.859119 -199.296348) (xy 175.851312 -199.29602)
			(xy 175.335438 -199.29602) (xy 175.329998 -199.295691) (xy 175.322307 -199.287998) (xy 175.321976 -199.282558)
			(xy 169.277792 -199.282558) (xy 169.277253 -199.28785) (xy 169.269863 -199.295421) (xy 169.264584 -199.29602)
			(xy 167.791384 -199.29602) (xy 167.786122 -199.295517) (xy 167.778681 -199.288074) (xy 167.778176 -199.282812)
			(xy 60.17817 -199.282812) (xy 60.177795 -199.287981) (xy 60.170147 -199.295668) (xy 60.164726 -199.29602)
			(xy 58.691526 -199.29602) (xy 58.686084 -199.295699) (xy 58.678394 -199.288) (xy 58.678064 -199.282558)
			(xy 52.63388 -199.282558) (xy 52.633351 -199.287853) (xy 52.625954 -199.295425) (xy 52.620672 -199.29602)
			(xy 52.104798 -199.29602) (xy 52.096987 -199.296329) (xy 52.082116 -199.301118) (xy 52.075588 -199.305418)
			(xy 52.054465 -199.319765) (xy 52.008742 -199.342493) (xy 51.960069 -199.357924) (xy 51.909603 -199.365691)
			(xy 51.884072 -199.366124) (xy 51.858541 -199.365709) (xy 51.808076 -199.357928) (xy 51.759403 -199.342492)
			(xy 51.713677 -199.319769) (xy 51.692556 -199.305418) (xy 51.686032 -199.301113) (xy 51.671156 -199.296338)
			(xy 51.663346 -199.29602) (xy 51.147472 -199.29602) (xy 51.142209 -199.295525) (xy 51.134768 -199.288076)
			(xy 51.134264 -199.282812) (xy 45.090062 -199.282812) (xy 45.089694 -199.287983) (xy 45.082041 -199.29567)
			(xy 45.076618 -199.29602) (xy 44.560744 -199.29602) (xy 44.552935 -199.296349) (xy 44.538064 -199.301124)
			(xy 44.531534 -199.305418) (xy 44.510426 -199.319788) (xy 44.464697 -199.342511) (xy 44.41602 -199.357935)
			(xy 44.36555 -199.365695) (xy 44.340018 -199.366124) (xy 44.314488 -199.365686) (xy 44.264024 -199.357912)
			(xy 44.215351 -199.342483) (xy 44.169624 -199.319766) (xy 44.148502 -199.305418) (xy 44.141968 -199.301131)
			(xy 44.1271 -199.296345) (xy 44.119292 -199.29602) (xy 43.603418 -199.29602) (xy 43.597975 -199.295705)
			(xy 43.590286 -199.288001) (xy 43.589956 -199.282558) (xy 37.545772 -199.282558) (xy 37.54525 -199.287854)
			(xy 37.537848 -199.295427) (xy 37.532564 -199.29602) (xy 37.01669 -199.29602) (xy 37.008879 -199.296326)
			(xy 36.994008 -199.301117) (xy 36.98748 -199.305418) (xy 36.966359 -199.319768) (xy 36.920635 -199.342496)
			(xy 36.871962 -199.357926) (xy 36.821495 -199.365692) (xy 36.795964 -199.366124) (xy 36.770433 -199.365713)
			(xy 36.719967 -199.35793) (xy 36.671295 -199.342494) (xy 36.625569 -199.31977) (xy 36.604448 -199.305418)
			(xy 36.597926 -199.30111) (xy 36.583049 -199.296337) (xy 36.575238 -199.29602) (xy 36.059364 -199.29602)
			(xy 36.0541 -199.29553) (xy 36.04666 -199.288077) (xy 36.046156 -199.282812) (xy 30.001947 -199.282812)
			(xy 30.00145 -199.287854) (xy 29.994048 -199.295427) (xy 29.988764 -199.29602) (xy 29.47289 -199.29602)
			(xy 29.465079 -199.296326) (xy 29.450208 -199.301117) (xy 29.44368 -199.305418) (xy 29.422559 -199.319768)
			(xy 29.376835 -199.342496) (xy 29.328162 -199.357926) (xy 29.277695 -199.365692) (xy 29.252164 -199.366124)
			(xy 29.226633 -199.365713) (xy 29.176167 -199.35793) (xy 29.127495 -199.342494) (xy 29.081769 -199.31977)
			(xy 29.060648 -199.305418) (xy 29.054126 -199.30111) (xy 29.039249 -199.296337) (xy 29.031438 -199.29602)
			(xy 28.515564 -199.29602) (xy 28.5103 -199.29553) (xy 28.50286 -199.288077) (xy 28.502356 -199.282812)
			(xy 22.458154 -199.282812) (xy 22.457793 -199.287985) (xy 22.450135 -199.295673) (xy 22.44471 -199.29602)
			(xy 21.928836 -199.29602) (xy 21.921027 -199.296345) (xy 21.906155 -199.301123) (xy 21.899626 -199.305418)
			(xy 21.878492 -199.319748) (xy 21.832773 -199.34248) (xy 21.784103 -199.357916) (xy 21.73364 -199.365688)
			(xy 21.70811 -199.366124) (xy 21.68258 -199.36569) (xy 21.632115 -199.357914) (xy 21.583443 -199.342485)
			(xy 21.537715 -199.319767) (xy 21.516594 -199.305418) (xy 21.510062 -199.301128) (xy 21.495192 -199.296344)
			(xy 21.487384 -199.29602) (xy 20.97151 -199.29602) (xy 20.966066 -199.29571) (xy 20.958377 -199.288003)
			(xy 20.958048 -199.282558) (xy 2.509012 -199.282558) (xy 2.509012 -200.132442) (xy 16.85798 -200.132442)
			(xy 16.85798 -199.637904) (xy 16.858496 -199.632645) (xy 16.865929 -199.625202) (xy 16.871188 -199.624696)
			(xy 16.871696 -199.624696) (xy 17.38757 -199.624696) (xy 17.395379 -199.62437) (xy 17.410251 -199.619593)
			(xy 17.41678 -199.615298) (xy 17.437869 -199.600949) (xy 17.48353 -199.578218) (xy 17.532136 -199.562759)
			(xy 17.582539 -199.554936) (xy 17.633545 -199.554936) (xy 17.683948 -199.562759) (xy 17.732554 -199.578218)
			(xy 17.778215 -199.600949) (xy 17.799304 -199.615298) (xy 17.805835 -199.619589) (xy 17.820706 -199.624372)
			(xy 17.828514 -199.624696) (xy 18.344642 -199.624696) (xy 18.349941 -199.62519) (xy 18.357507 -199.632615)
			(xy 18.358104 -199.637904) (xy 18.358104 -200.132442) (xy 18.358079 -200.132696) (xy 24.402288 -200.132696)
			(xy 24.402288 -200.132188) (xy 24.402288 -199.637904) (xy 24.402797 -199.632643) (xy 24.410235 -199.6252)
			(xy 24.415496 -199.624696) (xy 24.931624 -199.624696) (xy 24.939435 -199.624393) (xy 24.954306 -199.6196)
			(xy 24.960834 -199.615298) (xy 24.981923 -199.600949) (xy 25.027584 -199.578218) (xy 25.07619 -199.562759)
			(xy 25.126593 -199.554936) (xy 25.177599 -199.554936) (xy 25.228002 -199.562759) (xy 25.276608 -199.578218)
			(xy 25.322269 -199.600949) (xy 25.343358 -199.615298) (xy 25.349877 -199.61961) (xy 25.364757 -199.62438)
			(xy 25.372568 -199.624696) (xy 25.888696 -199.624696) (xy 25.894029 -199.62503) (xy 25.90157 -199.632571)
			(xy 25.901904 -199.637904) (xy 25.901904 -200.132442) (xy 25.90188 -200.132696) (xy 31.946088 -200.132696)
			(xy 31.946088 -200.132188) (xy 31.946088 -199.637904) (xy 31.946597 -199.632643) (xy 31.954035 -199.6252)
			(xy 31.959296 -199.624696) (xy 32.475424 -199.624696) (xy 32.483235 -199.624393) (xy 32.498106 -199.6196)
			(xy 32.504634 -199.615298) (xy 32.525723 -199.600949) (xy 32.571384 -199.578218) (xy 32.61999 -199.562759)
			(xy 32.670393 -199.554936) (xy 32.721399 -199.554936) (xy 32.771802 -199.562759) (xy 32.820408 -199.578218)
			(xy 32.866069 -199.600949) (xy 32.887158 -199.615298) (xy 32.893677 -199.61961) (xy 32.908557 -199.62438)
			(xy 32.916368 -199.624696) (xy 33.432496 -199.624696) (xy 33.437829 -199.62503) (xy 33.44537 -199.632571)
			(xy 33.445704 -199.637904) (xy 33.445704 -200.132442) (xy 39.489888 -200.132442) (xy 39.489888 -199.637904)
			(xy 39.490397 -199.632643) (xy 39.497835 -199.6252) (xy 39.503096 -199.624696) (xy 39.503604 -199.624696)
			(xy 40.019478 -199.624696) (xy 40.027287 -199.624374) (xy 40.042159 -199.619594) (xy 40.048688 -199.615298)
			(xy 40.069777 -199.600949) (xy 40.115438 -199.578218) (xy 40.164044 -199.562759) (xy 40.214447 -199.554936)
			(xy 40.265453 -199.554936) (xy 40.315856 -199.562759) (xy 40.364462 -199.578218) (xy 40.410123 -199.600949)
			(xy 40.431212 -199.615298) (xy 40.437742 -199.619592) (xy 40.452613 -199.624374) (xy 40.460422 -199.624696)
			(xy 40.97655 -199.624696) (xy 40.981838 -199.625252) (xy 40.989409 -199.63263) (xy 40.990012 -199.637904)
			(xy 40.990012 -200.132442) (xy 40.989987 -200.132696) (xy 47.034196 -200.132696) (xy 47.034196 -200.132188)
			(xy 47.034196 -199.637904) (xy 47.03453 -199.632571) (xy 47.042071 -199.62503) (xy 47.047404 -199.624696)
			(xy 47.563532 -199.624696) (xy 47.571339 -199.624354) (xy 47.586211 -199.619587) (xy 47.592742 -199.615298)
			(xy 47.613831 -199.600949) (xy 47.659492 -199.578218) (xy 47.708098 -199.562759) (xy 47.758501 -199.554936)
			(xy 47.809507 -199.554936) (xy 47.85991 -199.562759) (xy 47.908516 -199.578218) (xy 47.954177 -199.600949)
			(xy 47.975266 -199.615298) (xy 47.981806 -199.619575) (xy 47.996669 -199.624367) (xy 48.004476 -199.624696)
			(xy 48.520604 -199.624696) (xy 48.525868 -199.625192) (xy 48.533311 -199.632639) (xy 48.533812 -199.637904)
			(xy 48.533812 -200.132442) (xy 54.577996 -200.132442) (xy 54.577996 -199.637904) (xy 54.57833 -199.632571)
			(xy 54.585871 -199.62503) (xy 54.591204 -199.624696) (xy 56.064658 -199.624696) (xy 56.069947 -199.625246)
			(xy 56.077518 -199.632629) (xy 56.07812 -199.637904) (xy 56.07812 -200.132442) (xy 56.078099 -200.132696)
			(xy 163.678108 -200.132696) (xy 163.678108 -200.132188) (xy 163.678108 -199.637904) (xy 163.678431 -199.632568)
			(xy 163.68598 -199.625026) (xy 163.691316 -199.624696) (xy 165.164516 -199.624696) (xy 165.169782 -199.625184)
			(xy 165.177224 -199.632638) (xy 165.177724 -199.637904) (xy 165.177724 -200.132442) (xy 171.221908 -200.132442)
			(xy 171.221908 -199.637904) (xy 171.222231 -199.632568) (xy 171.22978 -199.625026) (xy 171.235116 -199.624696)
			(xy 171.235624 -199.624696) (xy 171.751498 -199.624696) (xy 171.759308 -199.624382) (xy 171.774179 -199.619596)
			(xy 171.780708 -199.615298) (xy 171.801797 -199.600949) (xy 171.847458 -199.578218) (xy 171.896064 -199.562759)
			(xy 171.946467 -199.554936) (xy 171.997473 -199.554936) (xy 172.047876 -199.562759) (xy 172.096482 -199.578218)
			(xy 172.142143 -199.600949) (xy 172.163232 -199.615298) (xy 172.169757 -199.6196) (xy 172.184632 -199.624376)
			(xy 172.192442 -199.624696) (xy 172.70857 -199.624696) (xy 172.71386 -199.625238) (xy 172.721431 -199.632627)
			(xy 172.722032 -199.637904) (xy 172.722032 -200.132442) (xy 172.72201 -200.132696) (xy 178.766216 -200.132696)
			(xy 178.766216 -200.132188) (xy 178.766216 -199.637904) (xy 178.766532 -199.632566) (xy 178.774086 -199.625024)
			(xy 178.779424 -199.624696) (xy 179.295552 -199.624696) (xy 179.30336 -199.624363) (xy 179.318232 -199.61959)
			(xy 179.324762 -199.615298) (xy 179.345851 -199.600949) (xy 179.391512 -199.578218) (xy 179.440118 -199.562759)
			(xy 179.490521 -199.554936) (xy 179.541527 -199.554936) (xy 179.59193 -199.562759) (xy 179.640536 -199.578218)
			(xy 179.686197 -199.600949) (xy 179.707286 -199.615298) (xy 179.713821 -199.619583) (xy 179.728688 -199.62437)
			(xy 179.736496 -199.624696) (xy 180.252624 -199.624696) (xy 180.257891 -199.625179) (xy 180.265332 -199.632636)
			(xy 180.265832 -199.637904) (xy 180.265832 -200.132442) (xy 186.310016 -200.132442) (xy 186.310016 -199.637904)
			(xy 186.310332 -199.632566) (xy 186.317886 -199.625024) (xy 186.323224 -199.624696) (xy 186.323732 -199.624696)
			(xy 186.839606 -199.624696) (xy 186.847416 -199.624386) (xy 186.862288 -199.619597) (xy 186.868816 -199.615298)
			(xy 186.889905 -199.600949) (xy 186.935566 -199.578218) (xy 186.984172 -199.562759) (xy 187.034575 -199.554936)
			(xy 187.085581 -199.554936) (xy 187.135984 -199.562759) (xy 187.18459 -199.578218) (xy 187.230251 -199.600949)
			(xy 187.25134 -199.615298) (xy 187.257863 -199.619603) (xy 187.27274 -199.624378) (xy 187.28055 -199.624696)
			(xy 187.796678 -199.624696) (xy 187.801969 -199.625232) (xy 187.809539 -199.632625) (xy 187.81014 -199.637904)
			(xy 187.81014 -200.132442) (xy 187.810118 -200.132696) (xy 193.854324 -200.132696) (xy 193.854324 -200.132188)
			(xy 193.854324 -199.637904) (xy 193.854633 -199.632565) (xy 193.862192 -199.625022) (xy 193.867532 -199.624696)
			(xy 194.38366 -199.624696) (xy 194.391469 -199.624366) (xy 194.40634 -199.619591) (xy 194.41287 -199.615298)
			(xy 194.433959 -199.600949) (xy 194.47962 -199.578218) (xy 194.528226 -199.562759) (xy 194.578629 -199.554936)
			(xy 194.629635 -199.554936) (xy 194.680038 -199.562759) (xy 194.728644 -199.578218) (xy 194.774305 -199.600949)
			(xy 194.795394 -199.615298) (xy 194.801928 -199.619586) (xy 194.816796 -199.624371) (xy 194.824604 -199.624696)
			(xy 195.340732 -199.624696) (xy 195.346 -199.625174) (xy 195.353441 -199.632635) (xy 195.35394 -199.637904)
			(xy 195.35394 -200.132442) (xy 195.353919 -200.132696) (xy 201.398124 -200.132696) (xy 201.398124 -200.132188)
			(xy 201.398124 -199.637904) (xy 201.398433 -199.632565) (xy 201.405992 -199.625022) (xy 201.411332 -199.624696)
			(xy 201.92746 -199.624696) (xy 201.935269 -199.624366) (xy 201.95014 -199.619591) (xy 201.95667 -199.615298)
			(xy 201.977759 -199.600949) (xy 202.02342 -199.578218) (xy 202.072026 -199.562759) (xy 202.122429 -199.554936)
			(xy 202.173435 -199.554936) (xy 202.223838 -199.562759) (xy 202.272444 -199.578218) (xy 202.318105 -199.600949)
			(xy 202.339194 -199.615298) (xy 202.345728 -199.619586) (xy 202.360596 -199.624371) (xy 202.368404 -199.624696)
			(xy 202.884532 -199.624696) (xy 202.8898 -199.625174) (xy 202.897241 -199.632635) (xy 202.89774 -199.637904)
			(xy 202.89774 -199.868028) (xy 255.545336 -199.868028) (xy 255.545336 -199.004428) (xy 255.545822 -198.977159)
			(xy 255.553584 -198.923175) (xy 255.568949 -198.870845) (xy 255.591606 -198.821235) (xy 255.621092 -198.775354)
			(xy 255.656807 -198.734137) (xy 255.698024 -198.698422) (xy 255.743905 -198.668936) (xy 255.793515 -198.646279)
			(xy 255.845845 -198.630914) (xy 255.899829 -198.623152) (xy 255.954367 -198.623152) (xy 256.008351 -198.630914)
			(xy 256.060681 -198.646279) (xy 256.110291 -198.668936) (xy 256.156172 -198.698422) (xy 256.197389 -198.734137)
			(xy 256.233104 -198.775354) (xy 256.26259 -198.821235) (xy 256.285247 -198.870845) (xy 256.300612 -198.923175)
			(xy 256.308374 -198.977159) (xy 256.30886 -199.004428) (xy 256.30886 -199.282304) (xy 268.898116 -199.282304)
			(xy 268.898116 -198.787766) (xy 268.898626 -198.782403) (xy 268.906215 -198.774821) (xy 268.911578 -198.774304)
			(xy 269.427706 -198.774304) (xy 269.435516 -198.773992) (xy 269.450388 -198.769205) (xy 269.456916 -198.764906)
			(xy 269.478005 -198.750557) (xy 269.523666 -198.727826) (xy 269.572272 -198.712367) (xy 269.622675 -198.704544)
			(xy 269.673681 -198.704544) (xy 269.724084 -198.712367) (xy 269.77269 -198.727826) (xy 269.818351 -198.750557)
			(xy 269.83944 -198.764906) (xy 269.845963 -198.769212) (xy 269.86084 -198.773986) (xy 269.86865 -198.774304)
			(xy 270.384778 -198.774304) (xy 270.390131 -198.774862) (xy 270.397716 -198.782415) (xy 270.39824 -198.787766)
			(xy 270.39824 -199.282304) (xy 276.442424 -199.282304) (xy 276.442424 -198.787766) (xy 276.442899 -198.782461)
			(xy 276.450337 -198.774893) (xy 276.455632 -198.774304) (xy 276.97176 -198.774304) (xy 276.979568 -198.773973)
			(xy 276.99444 -198.769199) (xy 277.00097 -198.764906) (xy 277.022059 -198.750557) (xy 277.06772 -198.727826)
			(xy 277.116326 -198.712367) (xy 277.166729 -198.704544) (xy 277.217735 -198.704544) (xy 277.268138 -198.712367)
			(xy 277.316744 -198.727826) (xy 277.362405 -198.750557) (xy 277.383494 -198.764906) (xy 277.390027 -198.769194)
			(xy 277.404896 -198.773979) (xy 277.412704 -198.774304) (xy 277.928832 -198.774304) (xy 277.934102 -198.774775)
			(xy 277.941543 -198.782241) (xy 277.94204 -198.787512) (xy 277.94204 -198.78802) (xy 277.94204 -199.282304)
			(xy 283.986224 -199.282304) (xy 283.986224 -198.787766) (xy 283.986699 -198.782461) (xy 283.994137 -198.774893)
			(xy 283.999432 -198.774304) (xy 284.51556 -198.774304) (xy 284.523368 -198.773973) (xy 284.53824 -198.769199)
			(xy 284.54477 -198.764906) (xy 284.565859 -198.750557) (xy 284.61152 -198.727826) (xy 284.660126 -198.712367)
			(xy 284.710529 -198.704544) (xy 284.761535 -198.704544) (xy 284.811938 -198.712367) (xy 284.860544 -198.727826)
			(xy 284.906205 -198.750557) (xy 284.927294 -198.764906) (xy 284.933827 -198.769194) (xy 284.948696 -198.773979)
			(xy 284.956504 -198.774304) (xy 285.472632 -198.774304) (xy 285.477902 -198.774775) (xy 285.485343 -198.782241)
			(xy 285.48584 -198.787512) (xy 285.48584 -198.78802) (xy 285.48584 -199.282304) (xy 291.530024 -199.282304)
			(xy 291.530024 -198.787766) (xy 291.530526 -198.782401) (xy 291.538121 -198.774818) (xy 291.543486 -198.774304)
			(xy 292.059614 -198.774304) (xy 292.067425 -198.773996) (xy 292.082296 -198.769206) (xy 292.088824 -198.764906)
			(xy 292.109913 -198.750557) (xy 292.155574 -198.727826) (xy 292.20418 -198.712367) (xy 292.254583 -198.704544)
			(xy 292.305589 -198.704544) (xy 292.355992 -198.712367) (xy 292.404598 -198.727826) (xy 292.450259 -198.750557)
			(xy 292.471348 -198.764906) (xy 292.477869 -198.769215) (xy 292.492747 -198.773987) (xy 292.500558 -198.774304)
			(xy 293.016686 -198.774304) (xy 293.02204 -198.774856) (xy 293.029625 -198.782414) (xy 293.030148 -198.787766)
			(xy 293.030148 -199.282304) (xy 299.074332 -199.282304) (xy 299.074332 -198.787766) (xy 299.0748 -198.78246)
			(xy 299.082243 -198.774891) (xy 299.08754 -198.774304) (xy 299.603668 -198.774304) (xy 299.611477 -198.773976)
			(xy 299.626348 -198.7692) (xy 299.632878 -198.764906) (xy 299.653967 -198.750557) (xy 299.699628 -198.727826)
			(xy 299.748234 -198.712367) (xy 299.798637 -198.704544) (xy 299.849643 -198.704544) (xy 299.900046 -198.712367)
			(xy 299.948652 -198.727826) (xy 299.994313 -198.750557) (xy 300.015402 -198.764906) (xy 300.021933 -198.769197)
			(xy 300.036804 -198.77398) (xy 300.044612 -198.774304) (xy 300.56074 -198.774304) (xy 300.566011 -198.774769)
			(xy 300.573452 -198.78224) (xy 300.573948 -198.787512) (xy 300.573948 -198.78802) (xy 300.573948 -199.282304)
			(xy 306.618132 -199.282304) (xy 306.618132 -198.787766) (xy 306.618627 -198.782399) (xy 306.626226 -198.774816)
			(xy 306.631594 -198.774304) (xy 308.104794 -198.774304) (xy 308.110149 -198.774851) (xy 308.117733 -198.782412)
			(xy 308.118256 -198.787766) (xy 308.118256 -199.282304) (xy 415.718244 -199.282304) (xy 415.718244 -198.787766)
			(xy 415.718701 -198.782457) (xy 415.726151 -198.774887) (xy 415.731452 -198.774304) (xy 417.204652 -198.774304)
			(xy 417.209981 -198.774661) (xy 417.217525 -198.782184) (xy 417.21786 -198.787512) (xy 417.21786 -199.282304)
			(xy 423.262044 -199.282304) (xy 423.262044 -198.787766) (xy 423.262528 -198.782396) (xy 423.270135 -198.774812)
			(xy 423.275506 -198.774304) (xy 423.791634 -198.774304) (xy 423.799441 -198.773962) (xy 423.814313 -198.769195)
			(xy 423.820844 -198.764906) (xy 423.841933 -198.750557) (xy 423.887594 -198.727826) (xy 423.9362 -198.712367)
			(xy 423.986603 -198.704544) (xy 424.037609 -198.704544) (xy 424.088012 -198.712367) (xy 424.136618 -198.727826)
			(xy 424.182279 -198.750557) (xy 424.203368 -198.764906) (xy 424.209907 -198.769184) (xy 424.224771 -198.773975)
			(xy 424.232578 -198.774304) (xy 424.748706 -198.774304) (xy 424.754063 -198.774843) (xy 424.761646 -198.782411)
			(xy 424.762168 -198.787766) (xy 424.762168 -199.282304) (xy 430.806352 -199.282304) (xy 430.806352 -198.787766)
			(xy 430.806802 -198.782455) (xy 430.814257 -198.774885) (xy 430.81956 -198.774304) (xy 431.335688 -198.774304)
			(xy 431.343498 -198.773985) (xy 431.358369 -198.769202) (xy 431.364898 -198.764906) (xy 431.385987 -198.750557)
			(xy 431.431648 -198.727826) (xy 431.480254 -198.712367) (xy 431.530657 -198.704544) (xy 431.581663 -198.704544)
			(xy 431.632066 -198.712367) (xy 431.680672 -198.727826) (xy 431.726333 -198.750557) (xy 431.747422 -198.764906)
			(xy 431.753949 -198.769205) (xy 431.768823 -198.773983) (xy 431.776632 -198.774304) (xy 432.29276 -198.774304)
			(xy 432.29809 -198.774655) (xy 432.305634 -198.782183) (xy 432.305968 -198.787512) (xy 432.305968 -198.78802)
			(xy 432.305968 -199.282304) (xy 438.350152 -199.282304) (xy 438.350152 -198.787766) (xy 438.350629 -198.782395)
			(xy 438.358241 -198.77481) (xy 438.363614 -198.774304) (xy 438.879742 -198.774304) (xy 438.88755 -198.773965)
			(xy 438.902421 -198.769196) (xy 438.908952 -198.764906) (xy 438.930041 -198.750557) (xy 438.975702 -198.727826)
			(xy 439.024308 -198.712367) (xy 439.074711 -198.704544) (xy 439.125717 -198.704544) (xy 439.17612 -198.712367)
			(xy 439.224726 -198.727826) (xy 439.270387 -198.750557) (xy 439.291476 -198.764906) (xy 439.298013 -198.769187)
			(xy 439.312879 -198.773976) (xy 439.320686 -198.774304) (xy 439.836814 -198.774304) (xy 439.842171 -198.774838)
			(xy 439.849754 -198.782409) (xy 439.850276 -198.787766) (xy 439.850276 -199.282304) (xy 445.89446 -199.282304)
			(xy 445.89446 -198.787766) (xy 445.894903 -198.782453) (xy 445.902363 -198.774883) (xy 445.907668 -198.774304)
			(xy 446.423796 -198.774304) (xy 446.431606 -198.773988) (xy 446.446477 -198.769203) (xy 446.453006 -198.764906)
			(xy 446.474095 -198.750557) (xy 446.519756 -198.727826) (xy 446.568362 -198.712367) (xy 446.618765 -198.704544)
			(xy 446.669771 -198.704544) (xy 446.720174 -198.712367) (xy 446.76878 -198.727826) (xy 446.814441 -198.750557)
			(xy 446.83553 -198.764906) (xy 446.842055 -198.769208) (xy 446.85693 -198.773984) (xy 446.86474 -198.774304)
			(xy 447.380868 -198.774304) (xy 447.386199 -198.77465) (xy 447.393742 -198.782182) (xy 447.394076 -198.787512)
			(xy 447.394076 -198.78802) (xy 447.394076 -199.282304) (xy 453.43826 -199.282304) (xy 453.43826 -198.787766)
			(xy 453.438703 -198.782453) (xy 453.446163 -198.774883) (xy 453.451468 -198.774304) (xy 453.967596 -198.774304)
			(xy 453.975406 -198.773988) (xy 453.990277 -198.769203) (xy 453.996806 -198.764906) (xy 454.017895 -198.750557)
			(xy 454.063556 -198.727826) (xy 454.112162 -198.712367) (xy 454.162565 -198.704544) (xy 454.213571 -198.704544)
			(xy 454.263974 -198.712367) (xy 454.31258 -198.727826) (xy 454.358241 -198.750557) (xy 454.37933 -198.764906)
			(xy 454.385855 -198.769208) (xy 454.40073 -198.773984) (xy 454.40854 -198.774304) (xy 454.924668 -198.774304)
			(xy 454.929999 -198.77465) (xy 454.937542 -198.782182) (xy 454.937876 -198.787512) (xy 454.937876 -198.78802)
			(xy 454.937876 -199.282304) (xy 454.937573 -199.287645) (xy 454.930009 -199.295187) (xy 454.924668 -199.295512)
			(xy 454.408794 -199.295512) (xy 454.400921 -199.295811) (xy 454.385917 -199.300587) (xy 454.37933 -199.30491)
			(xy 454.358259 -199.319312) (xy 454.312612 -199.342139) (xy 454.264004 -199.357694) (xy 454.213585 -199.365609)
			(xy 454.188068 -199.366124) (xy 454.162549 -199.365613) (xy 454.112123 -199.357724) (xy 454.063511 -199.34217)
			(xy 454.017872 -199.319322) (xy 453.996806 -199.30491) (xy 453.990214 -199.300595) (xy 453.975214 -199.295808)
			(xy 453.967342 -199.295512) (xy 453.451468 -199.295512) (xy 453.446202 -199.295027) (xy 453.438762 -199.287571)
			(xy 453.43826 -199.282304) (xy 447.394076 -199.282304) (xy 447.393773 -199.287645) (xy 447.386209 -199.295187)
			(xy 447.380868 -199.295512) (xy 446.864994 -199.295512) (xy 446.857121 -199.295811) (xy 446.842117 -199.300587)
			(xy 446.83553 -199.30491) (xy 446.814459 -199.319312) (xy 446.768812 -199.342139) (xy 446.720204 -199.357694)
			(xy 446.669785 -199.365609) (xy 446.644268 -199.366124) (xy 446.618749 -199.365613) (xy 446.568323 -199.357724)
			(xy 446.519711 -199.34217) (xy 446.474072 -199.319322) (xy 446.453006 -199.30491) (xy 446.446414 -199.300595)
			(xy 446.431414 -199.295808) (xy 446.423542 -199.295512) (xy 445.907668 -199.295512) (xy 445.902402 -199.295027)
			(xy 445.894962 -199.287571) (xy 445.89446 -199.282304) (xy 439.850276 -199.282304) (xy 439.849973 -199.287645)
			(xy 439.842409 -199.295187) (xy 439.837068 -199.295512) (xy 439.83656 -199.295512) (xy 439.32094 -199.295512)
			(xy 439.313065 -199.295788) (xy 439.298061 -199.30058) (xy 439.291476 -199.30491) (xy 439.270393 -199.319292)
			(xy 439.22475 -199.342124) (xy 439.176146 -199.357685) (xy 439.12573 -199.365606) (xy 439.100214 -199.366124)
			(xy 439.074694 -199.36564) (xy 439.024267 -199.357743) (xy 438.975655 -199.342181) (xy 438.930017 -199.319325)
			(xy 438.908952 -199.30491) (xy 438.902372 -199.300574) (xy 438.887363 -199.2958) (xy 438.879488 -199.295512)
			(xy 438.363614 -199.295512) (xy 438.3583 -199.295062) (xy 438.350726 -199.287609) (xy 438.350152 -199.282304)
			(xy 432.305968 -199.282304) (xy 432.305672 -199.287647) (xy 432.298104 -199.29519) (xy 432.29276 -199.295512)
			(xy 431.776886 -199.295512) (xy 431.769012 -199.295807) (xy 431.754008 -199.300586) (xy 431.747422 -199.30491)
			(xy 431.726354 -199.319316) (xy 431.680706 -199.342142) (xy 431.632097 -199.357696) (xy 431.581678 -199.36561)
			(xy 431.55616 -199.366124) (xy 431.530641 -199.365617) (xy 431.480215 -199.357727) (xy 431.431603 -199.342172)
			(xy 431.385964 -199.319322) (xy 431.364898 -199.30491) (xy 431.358308 -199.300592) (xy 431.343307 -199.295807)
			(xy 431.335434 -199.295512) (xy 430.81956 -199.295512) (xy 430.814293 -199.295032) (xy 430.806853 -199.287572)
			(xy 430.806352 -199.282304) (xy 424.762168 -199.282304) (xy 424.761872 -199.287647) (xy 424.754304 -199.29519)
			(xy 424.74896 -199.295512) (xy 424.748452 -199.295512) (xy 424.232832 -199.295512) (xy 424.224956 -199.295784)
			(xy 424.209953 -199.300579) (xy 424.203368 -199.30491) (xy 424.182287 -199.319296) (xy 424.136644 -199.342127)
			(xy 424.088039 -199.357686) (xy 424.037622 -199.365606) (xy 424.012106 -199.366124) (xy 423.986585 -199.365644)
			(xy 423.936158 -199.357746) (xy 423.887547 -199.342183) (xy 423.841909 -199.319326) (xy 423.820844 -199.30491)
			(xy 423.814266 -199.300571) (xy 423.799256 -199.295799) (xy 423.79138 -199.295512) (xy 423.275506 -199.295512)
			(xy 423.270191 -199.295067) (xy 423.262617 -199.28761) (xy 423.262044 -199.282304) (xy 417.21786 -199.282304)
			(xy 417.217571 -199.287649) (xy 417.209998 -199.295192) (xy 417.204652 -199.295512) (xy 415.731452 -199.295512)
			(xy 415.726184 -199.295037) (xy 415.718745 -199.287573) (xy 415.718244 -199.282304) (xy 308.118256 -199.282304)
			(xy 308.117713 -199.287556) (xy 308.110298 -199.294995) (xy 308.105048 -199.295512) (xy 308.10454 -199.295512)
			(xy 306.631594 -199.295512) (xy 306.626278 -199.295075) (xy 306.618704 -199.287612) (xy 306.618132 -199.282304)
			(xy 300.573948 -199.282304) (xy 300.573412 -199.287558) (xy 300.565992 -199.294998) (xy 300.56074 -199.295512)
			(xy 300.044866 -199.295512) (xy 300.036992 -199.295799) (xy 300.021988 -199.300584) (xy 300.015402 -199.30491)
			(xy 299.994311 -199.319281) (xy 299.948672 -199.342115) (xy 299.90007 -199.357679) (xy 299.849656 -199.365604)
			(xy 299.82414 -199.366124) (xy 299.79862 -199.365627) (xy 299.748194 -199.357734) (xy 299.699582 -199.342176)
			(xy 299.653943 -199.319324) (xy 299.632878 -199.30491) (xy 299.626293 -199.300585) (xy 299.611288 -199.295804)
			(xy 299.603414 -199.295512) (xy 299.08754 -199.295512) (xy 299.082214 -199.295147) (xy 299.074671 -199.287629)
			(xy 299.074332 -199.282304) (xy 293.030148 -199.282304) (xy 293.029612 -199.287558) (xy 293.022192 -199.294998)
			(xy 293.01694 -199.295512) (xy 293.016432 -199.295512) (xy 292.500812 -199.295512) (xy 292.492939 -199.295819)
			(xy 292.477936 -199.30059) (xy 292.471348 -199.30491) (xy 292.450272 -199.319304) (xy 292.404627 -199.342133)
			(xy 292.356021 -199.357691) (xy 292.305603 -199.365608) (xy 292.280086 -199.366124) (xy 292.254567 -199.365604)
			(xy 292.204142 -199.357718) (xy 292.15553 -199.342167) (xy 292.10989 -199.319321) (xy 292.088824 -199.30491)
			(xy 292.082228 -199.300602) (xy 292.067232 -199.295811) (xy 292.05936 -199.295512) (xy 291.543486 -199.295512)
			(xy 291.538169 -199.29508) (xy 291.530596 -199.287613) (xy 291.530024 -199.282304) (xy 285.48584 -199.282304)
			(xy 285.485311 -199.28756) (xy 285.477887 -199.295) (xy 285.472632 -199.295512) (xy 284.956758 -199.295512)
			(xy 284.948883 -199.295796) (xy 284.93388 -199.300583) (xy 284.927294 -199.30491) (xy 284.906206 -199.319285)
			(xy 284.860565 -199.342118) (xy 284.811962 -199.357681) (xy 284.761548 -199.365605) (xy 284.736032 -199.366124)
			(xy 284.710512 -199.365631) (xy 284.660085 -199.357737) (xy 284.611474 -199.342178) (xy 284.565835 -199.319324)
			(xy 284.54477 -199.30491) (xy 284.538186 -199.300581) (xy 284.52318 -199.295803) (xy 284.515306 -199.295512)
			(xy 283.999432 -199.295512) (xy 283.994105 -199.295152) (xy 283.986563 -199.28763) (xy 283.986224 -199.282304)
			(xy 277.94204 -199.282304) (xy 277.941511 -199.28756) (xy 277.934087 -199.295) (xy 277.928832 -199.295512)
			(xy 277.412958 -199.295512) (xy 277.405083 -199.295796) (xy 277.39008 -199.300583) (xy 277.383494 -199.30491)
			(xy 277.362406 -199.319285) (xy 277.316765 -199.342118) (xy 277.268162 -199.357681) (xy 277.217748 -199.365605)
			(xy 277.192232 -199.366124) (xy 277.166712 -199.365631) (xy 277.116285 -199.357737) (xy 277.067674 -199.342178)
			(xy 277.022035 -199.319324) (xy 277.00097 -199.30491) (xy 276.994386 -199.300581) (xy 276.97938 -199.295803)
			(xy 276.971506 -199.295512) (xy 276.455632 -199.295512) (xy 276.450305 -199.295152) (xy 276.442763 -199.28763)
			(xy 276.442424 -199.282304) (xy 270.39824 -199.282304) (xy 270.397711 -199.28756) (xy 270.390287 -199.295)
			(xy 270.385032 -199.295512) (xy 270.384524 -199.295512) (xy 269.868904 -199.295512) (xy 269.861031 -199.295815)
			(xy 269.846027 -199.300589) (xy 269.83944 -199.30491) (xy 269.818367 -199.319308) (xy 269.772721 -199.342136)
			(xy 269.724113 -199.357692) (xy 269.673695 -199.365609) (xy 269.648178 -199.366124) (xy 269.622659 -199.365608)
			(xy 269.572233 -199.357721) (xy 269.523622 -199.342168) (xy 269.477982 -199.319321) (xy 269.456916 -199.30491)
			(xy 269.450322 -199.300599) (xy 269.435324 -199.29581) (xy 269.427452 -199.295512) (xy 268.911578 -199.295512)
			(xy 268.90626 -199.295086) (xy 268.898687 -199.287615) (xy 268.898116 -199.282304) (xy 256.30886 -199.282304)
			(xy 256.30886 -199.868028) (xy 256.308374 -199.895297) (xy 256.300612 -199.949281) (xy 256.285247 -200.001611)
			(xy 256.26259 -200.051221) (xy 256.233104 -200.097102) (xy 256.202702 -200.132188) (xy 264.798048 -200.132188)
			(xy 264.798048 -199.63765) (xy 264.798518 -199.632278) (xy 264.806136 -199.624694) (xy 264.81151 -199.624188)
			(xy 265.327638 -199.624188) (xy 265.335446 -199.62385) (xy 265.350317 -199.619081) (xy 265.356848 -199.61479)
			(xy 265.377937 -199.600441) (xy 265.423598 -199.57771) (xy 265.472204 -199.562251) (xy 265.522607 -199.554428)
			(xy 265.573613 -199.554428) (xy 265.624016 -199.562251) (xy 265.672622 -199.57771) (xy 265.718283 -199.600441)
			(xy 265.739372 -199.61479) (xy 265.745911 -199.619068) (xy 265.760775 -199.62386) (xy 265.768582 -199.624188)
			(xy 266.28471 -199.624188) (xy 266.290063 -199.624739) (xy 266.297645 -199.632298) (xy 266.298172 -199.63765)
			(xy 266.298172 -200.132188) (xy 272.342356 -200.132188) (xy 272.342356 -199.63765) (xy 272.342858 -199.632348)
			(xy 272.350273 -199.624773) (xy 272.355564 -199.624188) (xy 272.871692 -199.624188) (xy 272.879502 -199.623873)
			(xy 272.894373 -199.619088) (xy 272.900902 -199.61479) (xy 272.921991 -199.600441) (xy 272.967652 -199.57771)
			(xy 273.016258 -199.562251) (xy 273.066661 -199.554428) (xy 273.117667 -199.554428) (xy 273.16807 -199.562251)
			(xy 273.216676 -199.57771) (xy 273.262337 -199.600441) (xy 273.283426 -199.61479) (xy 273.289953 -199.619089)
			(xy 273.304826 -199.623867) (xy 273.312636 -199.624188) (xy 273.828764 -199.624188) (xy 273.834091 -199.624551)
			(xy 273.841633 -199.632071) (xy 273.841972 -199.637396) (xy 273.841972 -199.637904) (xy 273.841972 -200.132188)
			(xy 279.886156 -200.132188) (xy 279.886156 -199.63765) (xy 279.886658 -199.632348) (xy 279.894073 -199.624773)
			(xy 279.899364 -199.624188) (xy 280.415492 -199.624188) (xy 280.423302 -199.623873) (xy 280.438173 -199.619088)
			(xy 280.444702 -199.61479) (xy 280.465791 -199.600441) (xy 280.511452 -199.57771) (xy 280.560058 -199.562251)
			(xy 280.610461 -199.554428) (xy 280.661467 -199.554428) (xy 280.71187 -199.562251) (xy 280.760476 -199.57771)
			(xy 280.806137 -199.600441) (xy 280.827226 -199.61479) (xy 280.833753 -199.619089) (xy 280.848626 -199.623867)
			(xy 280.856436 -199.624188) (xy 281.372564 -199.624188) (xy 281.377891 -199.624551) (xy 281.385433 -199.632071)
			(xy 281.385772 -199.637396) (xy 281.385772 -199.637904) (xy 281.385772 -200.132188) (xy 287.429956 -200.132188)
			(xy 287.429956 -199.63765) (xy 287.430419 -199.632276) (xy 287.438041 -199.624692) (xy 287.443418 -199.624188)
			(xy 287.959546 -199.624188) (xy 287.967354 -199.623854) (xy 287.982226 -199.619082) (xy 287.988756 -199.61479)
			(xy 288.009845 -199.600441) (xy 288.055506 -199.57771) (xy 288.104112 -199.562251) (xy 288.154515 -199.554428)
			(xy 288.205521 -199.554428) (xy 288.255924 -199.562251) (xy 288.30453 -199.57771) (xy 288.350191 -199.600441)
			(xy 288.37128 -199.61479) (xy 288.377817 -199.619071) (xy 288.392683 -199.623861) (xy 288.40049 -199.624188)
			(xy 288.916618 -199.624188) (xy 288.921972 -199.624733) (xy 288.929554 -199.632297) (xy 288.93008 -199.63765)
			(xy 288.93008 -200.132188) (xy 294.974264 -200.132188) (xy 294.974264 -199.63765) (xy 294.974759 -199.632346)
			(xy 294.982179 -199.624771) (xy 294.987472 -199.624188) (xy 295.5036 -199.624188) (xy 295.51141 -199.623876)
			(xy 295.526282 -199.619089) (xy 295.53281 -199.61479) (xy 295.553899 -199.600441) (xy 295.59956 -199.57771)
			(xy 295.648166 -199.562251) (xy 295.698569 -199.554428) (xy 295.749575 -199.554428) (xy 295.799978 -199.562251)
			(xy 295.848584 -199.57771) (xy 295.894245 -199.600441) (xy 295.915334 -199.61479) (xy 295.921859 -199.619092)
			(xy 295.936734 -199.623869) (xy 295.944544 -199.624188) (xy 296.460672 -199.624188) (xy 296.466 -199.624545)
			(xy 296.473542 -199.632069) (xy 296.47388 -199.637396) (xy 296.47388 -199.637904) (xy 296.47388 -200.132188)
			(xy 302.518064 -200.132188) (xy 302.518064 -199.63765) (xy 302.51852 -199.632274) (xy 302.526147 -199.62469)
			(xy 302.531526 -199.624188) (xy 304.004726 -199.624188) (xy 304.010081 -199.624728) (xy 304.017662 -199.632296)
			(xy 304.018188 -199.63765) (xy 304.018188 -200.132188) (xy 411.618176 -200.132188) (xy 411.618176 -199.63765)
			(xy 411.618661 -199.632343) (xy 411.626088 -199.624767) (xy 411.631384 -199.624188) (xy 413.104584 -199.624188)
			(xy 413.109913 -199.624537) (xy 413.117455 -199.632067) (xy 413.117792 -199.637396) (xy 413.117792 -199.637904)
			(xy 413.117792 -200.132188) (xy 419.161976 -200.132188) (xy 419.161976 -199.63765) (xy 419.162421 -199.632271)
			(xy 419.170056 -199.624686) (xy 419.175438 -199.624188) (xy 419.691566 -199.624188) (xy 419.699375 -199.623862)
			(xy 419.714247 -199.619085) (xy 419.720776 -199.61479) (xy 419.741865 -199.600441) (xy 419.787526 -199.57771)
			(xy 419.836132 -199.562251) (xy 419.886535 -199.554428) (xy 419.937541 -199.554428) (xy 419.987944 -199.562251)
			(xy 420.03655 -199.57771) (xy 420.082211 -199.600441) (xy 420.1033 -199.61479) (xy 420.109833 -199.619079)
			(xy 420.124702 -199.623864) (xy 420.13251 -199.624188) (xy 420.648638 -199.624188) (xy 420.653994 -199.62472)
			(xy 420.661575 -199.632294) (xy 420.6621 -199.63765) (xy 420.6621 -200.132188) (xy 426.706284 -200.132188)
			(xy 426.706284 -199.63765) (xy 426.706762 -199.632342) (xy 426.714194 -199.624765) (xy 426.719492 -199.624188)
			(xy 427.23562 -199.624188) (xy 427.243431 -199.623885) (xy 427.258302 -199.619092) (xy 427.26483 -199.61479)
			(xy 427.285919 -199.600441) (xy 427.33158 -199.57771) (xy 427.380186 -199.562251) (xy 427.430589 -199.554428)
			(xy 427.481595 -199.554428) (xy 427.531998 -199.562251) (xy 427.580604 -199.57771) (xy 427.626265 -199.600441)
			(xy 427.647354 -199.61479) (xy 427.653875 -199.6191) (xy 427.668753 -199.623872) (xy 427.676564 -199.624188)
			(xy 428.192692 -199.624188) (xy 428.198022 -199.624532) (xy 428.205563 -199.632066) (xy 428.2059 -199.637396)
			(xy 428.2059 -199.637904) (xy 428.2059 -200.132188) (xy 434.250084 -200.132188) (xy 434.250084 -199.63765)
			(xy 434.250522 -199.632269) (xy 434.258162 -199.624684) (xy 434.263546 -199.624188) (xy 434.779674 -199.624188)
			(xy 434.787483 -199.623865) (xy 434.802355 -199.619086) (xy 434.808884 -199.61479) (xy 434.829973 -199.600441)
			(xy 434.875634 -199.57771) (xy 434.92424 -199.562251) (xy 434.974643 -199.554428) (xy 435.025649 -199.554428)
			(xy 435.076052 -199.562251) (xy 435.124658 -199.57771) (xy 435.170319 -199.600441) (xy 435.191408 -199.61479)
			(xy 435.197939 -199.619082) (xy 435.212809 -199.623865) (xy 435.220618 -199.624188) (xy 435.736746 -199.624188)
			(xy 435.742103 -199.624715) (xy 435.749684 -199.632293) (xy 435.750208 -199.63765) (xy 435.750208 -200.132188)
			(xy 441.794392 -200.132188) (xy 441.794392 -199.63765) (xy 441.794951 -199.632363) (xy 441.802327 -199.624792)
			(xy 441.8076 -199.624188) (xy 442.323728 -199.624188) (xy 442.331539 -199.623888) (xy 442.346411 -199.619093)
			(xy 442.352938 -199.61479) (xy 442.374027 -199.600441) (xy 442.419688 -199.57771) (xy 442.468294 -199.562251)
			(xy 442.518697 -199.554428) (xy 442.569703 -199.554428) (xy 442.620106 -199.562251) (xy 442.668712 -199.57771)
			(xy 442.714373 -199.600441) (xy 442.735462 -199.61479) (xy 442.742003 -199.619065) (xy 442.756866 -199.623858)
			(xy 442.764672 -199.624188) (xy 443.2808 -199.624188) (xy 443.286062 -199.624694) (xy 443.293504 -199.632134)
			(xy 443.294008 -199.637396) (xy 443.294008 -199.637904) (xy 443.294008 -200.132188) (xy 449.338192 -200.132188)
			(xy 449.338192 -199.63765) (xy 449.338751 -199.632363) (xy 449.346127 -199.624792) (xy 449.3514 -199.624188)
			(xy 449.867528 -199.624188) (xy 449.875339 -199.623888) (xy 449.890211 -199.619093) (xy 449.896738 -199.61479)
			(xy 449.917827 -199.600441) (xy 449.963488 -199.57771) (xy 450.012094 -199.562251) (xy 450.062497 -199.554428)
			(xy 450.113503 -199.554428) (xy 450.163906 -199.562251) (xy 450.212512 -199.57771) (xy 450.258173 -199.600441)
			(xy 450.279262 -199.61479) (xy 450.285803 -199.619065) (xy 450.300666 -199.623858) (xy 450.308472 -199.624188)
			(xy 450.8246 -199.624188) (xy 450.829862 -199.624694) (xy 450.837304 -199.632134) (xy 450.837808 -199.637396)
			(xy 450.837808 -199.637904) (xy 450.837808 -200.132188) (xy 450.837465 -200.137519) (xy 450.82993 -200.14506)
			(xy 450.8246 -200.145396) (xy 450.308726 -200.145396) (xy 450.300849 -200.145652) (xy 450.285844 -200.150457)
			(xy 450.279262 -200.154794) (xy 450.258189 -200.169192) (xy 450.212542 -200.192018) (xy 450.163935 -200.207573)
			(xy 450.113517 -200.215491) (xy 450.088 -200.216008) (xy 450.062479 -200.215534) (xy 450.012052 -200.207634)
			(xy 449.96344 -200.19207) (xy 449.917802 -200.169211) (xy 449.896738 -200.154794) (xy 449.89014 -200.15049)
			(xy 449.875145 -200.145697) (xy 449.867274 -200.145396) (xy 449.3514 -200.145396) (xy 449.346065 -200.145072)
			(xy 449.338523 -200.137524) (xy 449.338192 -200.132188) (xy 443.294008 -200.132188) (xy 443.293665 -200.137519)
			(xy 443.28613 -200.14506) (xy 443.2808 -200.145396) (xy 442.764926 -200.145396) (xy 442.757049 -200.145652)
			(xy 442.742044 -200.150457) (xy 442.735462 -200.154794) (xy 442.714389 -200.169192) (xy 442.668742 -200.192018)
			(xy 442.620135 -200.207573) (xy 442.569717 -200.215491) (xy 442.5442 -200.216008) (xy 442.518679 -200.215534)
			(xy 442.468252 -200.207634) (xy 442.41964 -200.19207) (xy 442.374002 -200.169211) (xy 442.352938 -200.154794)
			(xy 442.34634 -200.15049) (xy 442.331345 -200.145697) (xy 442.323474 -200.145396) (xy 441.8076 -200.145396)
			(xy 441.802265 -200.145072) (xy 441.794723 -200.137524) (xy 441.794392 -200.132188) (xy 435.750208 -200.132188)
			(xy 435.749865 -200.137519) (xy 435.74233 -200.14506) (xy 435.737 -200.145396) (xy 435.736492 -200.145396)
			(xy 435.220872 -200.145396) (xy 435.212996 -200.145671) (xy 435.197992 -200.150463) (xy 435.191408 -200.154794)
			(xy 435.17035 -200.169216) (xy 435.124698 -200.192036) (xy 435.076086 -200.207585) (xy 435.025664 -200.215495)
			(xy 435.000146 -200.216008) (xy 434.974626 -200.215511) (xy 434.9242 -200.207618) (xy 434.875588 -200.192061)
			(xy 434.829949 -200.169208) (xy 434.808884 -200.154794) (xy 434.802298 -200.150469) (xy 434.787294 -200.145689)
			(xy 434.77942 -200.145396) (xy 434.263546 -200.145396) (xy 434.258256 -200.14485) (xy 434.250684 -200.137465)
			(xy 434.250084 -200.132188) (xy 428.2059 -200.132188) (xy 428.205564 -200.137521) (xy 428.198024 -200.145063)
			(xy 428.192692 -200.145396) (xy 427.676818 -200.145396) (xy 427.668944 -200.145691) (xy 427.65394 -200.150469)
			(xy 427.647354 -200.154794) (xy 427.626283 -200.169196) (xy 427.580636 -200.192021) (xy 427.532028 -200.207575)
			(xy 427.481609 -200.215492) (xy 427.456092 -200.216008) (xy 427.430573 -200.215488) (xy 427.380147 -200.207602)
			(xy 427.331536 -200.192051) (xy 427.285896 -200.169205) (xy 427.26483 -200.154794) (xy 427.258234 -200.150487)
			(xy 427.243237 -200.145695) (xy 427.235366 -200.145396) (xy 426.719492 -200.145396) (xy 426.714156 -200.145078)
			(xy 426.706614 -200.137525) (xy 426.706284 -200.132188) (xy 420.6621 -200.132188) (xy 420.661764 -200.137521)
			(xy 420.654224 -200.145063) (xy 420.648892 -200.145396) (xy 420.648384 -200.145396) (xy 420.132764 -200.145396)
			(xy 420.124888 -200.145668) (xy 420.109884 -200.150462) (xy 420.1033 -200.154794) (xy 420.082217 -200.169176)
			(xy 420.036573 -200.192005) (xy 419.987969 -200.207565) (xy 419.937554 -200.215488) (xy 419.912038 -200.216008)
			(xy 419.886518 -200.215515) (xy 419.836091 -200.207621) (xy 419.78748 -200.192062) (xy 419.741841 -200.169209)
			(xy 419.720776 -200.154794) (xy 419.714192 -200.150466) (xy 419.699186 -200.145688) (xy 419.691312 -200.145396)
			(xy 419.175438 -200.145396) (xy 419.170147 -200.144856) (xy 419.162576 -200.137466) (xy 419.161976 -200.132188)
			(xy 413.117792 -200.132188) (xy 413.117463 -200.137522) (xy 413.109919 -200.145065) (xy 413.104584 -200.145396)
			(xy 411.631384 -200.145396) (xy 411.626116 -200.144915) (xy 411.618674 -200.137457) (xy 411.618176 -200.132188)
			(xy 304.018188 -200.132188) (xy 304.017863 -200.137523) (xy 304.010316 -200.145066) (xy 304.00498 -200.145396)
			(xy 302.531526 -200.145396) (xy 302.526233 -200.144864) (xy 302.518663 -200.137468) (xy 302.518064 -200.132188)
			(xy 296.47388 -200.132188) (xy 296.473562 -200.137525) (xy 296.46601 -200.145069) (xy 296.460672 -200.145396)
			(xy 295.944798 -200.145396) (xy 295.936923 -200.145683) (xy 295.921919 -200.150466) (xy 295.915334 -200.154794)
			(xy 295.894269 -200.169204) (xy 295.848619 -200.192027) (xy 295.800009 -200.207579) (xy 295.74959 -200.215493)
			(xy 295.724072 -200.216008) (xy 295.698553 -200.215498) (xy 295.648127 -200.207609) (xy 295.599515 -200.192055)
			(xy 295.553876 -200.169206) (xy 295.53281 -200.154794) (xy 295.526218 -200.150479) (xy 295.511218 -200.145693)
			(xy 295.503346 -200.145396) (xy 294.987472 -200.145396) (xy 294.982203 -200.144923) (xy 294.974761 -200.137459)
			(xy 294.974264 -200.132188) (xy 288.93008 -200.132188) (xy 288.929762 -200.137525) (xy 288.92221 -200.145069)
			(xy 288.916872 -200.145396) (xy 288.916364 -200.145396) (xy 288.400744 -200.145396) (xy 288.392867 -200.14566)
			(xy 288.377863 -200.150459) (xy 288.37128 -200.154794) (xy 288.350202 -200.169185) (xy 288.304557 -200.192012)
			(xy 288.255951 -200.20757) (xy 288.205535 -200.21549) (xy 288.180018 -200.216008) (xy 288.154498 -200.215525)
			(xy 288.10407 -200.207628) (xy 288.055459 -200.192066) (xy 288.009821 -200.16921) (xy 287.988756 -200.154794)
			(xy 287.982176 -200.150459) (xy 287.967167 -200.145685) (xy 287.959292 -200.145396) (xy 287.443418 -200.145396)
			(xy 287.438124 -200.144869) (xy 287.430554 -200.137469) (xy 287.429956 -200.132188) (xy 281.385772 -200.132188)
			(xy 281.385461 -200.137527) (xy 281.377904 -200.145071) (xy 281.372564 -200.145396) (xy 280.85669 -200.145396)
			(xy 280.848815 -200.145679) (xy 280.833811 -200.150465) (xy 280.827226 -200.154794) (xy 280.806163 -200.169208)
			(xy 280.760513 -200.19203) (xy 280.711902 -200.207581) (xy 280.661482 -200.215494) (xy 280.635964 -200.216008)
			(xy 280.610445 -200.215502) (xy 280.560018 -200.207612) (xy 280.511407 -200.192057) (xy 280.465768 -200.169207)
			(xy 280.444702 -200.154794) (xy 280.438112 -200.150476) (xy 280.423111 -200.145691) (xy 280.415238 -200.145396)
			(xy 279.899364 -200.145396) (xy 279.894094 -200.144928) (xy 279.886653 -200.13746) (xy 279.886156 -200.132188)
			(xy 273.841972 -200.132188) (xy 273.841661 -200.137527) (xy 273.834104 -200.145071) (xy 273.828764 -200.145396)
			(xy 273.31289 -200.145396) (xy 273.305015 -200.145679) (xy 273.290011 -200.150465) (xy 273.283426 -200.154794)
			(xy 273.262363 -200.169208) (xy 273.216713 -200.19203) (xy 273.168102 -200.207581) (xy 273.117682 -200.215494)
			(xy 273.092164 -200.216008) (xy 273.066645 -200.215502) (xy 273.016218 -200.207612) (xy 272.967607 -200.192057)
			(xy 272.921968 -200.169207) (xy 272.900902 -200.154794) (xy 272.894312 -200.150476) (xy 272.879311 -200.145691)
			(xy 272.871438 -200.145396) (xy 272.355564 -200.145396) (xy 272.350294 -200.144928) (xy 272.342853 -200.13746)
			(xy 272.342356 -200.132188) (xy 266.298172 -200.132188) (xy 266.297861 -200.137527) (xy 266.290304 -200.145071)
			(xy 266.284964 -200.145396) (xy 266.284456 -200.145396) (xy 265.768836 -200.145396) (xy 265.760959 -200.145656)
			(xy 265.745955 -200.150458) (xy 265.739372 -200.154794) (xy 265.718296 -200.169188) (xy 265.67265 -200.192015)
			(xy 265.624044 -200.207571) (xy 265.573627 -200.21549) (xy 265.54811 -200.216008) (xy 265.522589 -200.215529)
			(xy 265.472162 -200.207631) (xy 265.423551 -200.192068) (xy 265.377913 -200.16921) (xy 265.356848 -200.154794)
			(xy 265.35027 -200.150455) (xy 265.33526 -200.145683) (xy 265.327384 -200.145396) (xy 264.81151 -200.145396)
			(xy 264.806215 -200.144875) (xy 264.798646 -200.137471) (xy 264.798048 -200.132188) (xy 256.202702 -200.132188)
			(xy 256.197389 -200.138319) (xy 256.156172 -200.174034) (xy 256.110291 -200.20352) (xy 256.060681 -200.226177)
			(xy 256.008351 -200.241542) (xy 255.954367 -200.249304) (xy 255.899829 -200.249304) (xy 255.845845 -200.241542)
			(xy 255.793515 -200.226177) (xy 255.743905 -200.20352) (xy 255.698024 -200.174034) (xy 255.656807 -200.138319)
			(xy 255.621092 -200.097102) (xy 255.591606 -200.051221) (xy 255.568949 -200.001611) (xy 255.553584 -199.949281)
			(xy 255.545822 -199.895297) (xy 255.545336 -199.868028) (xy 202.89774 -199.868028) (xy 202.89774 -200.132442)
			(xy 202.897303 -200.137756) (xy 202.889838 -200.145326) (xy 202.884532 -200.145904) (xy 202.368658 -200.145904)
			(xy 202.36085 -200.146241) (xy 202.345978 -200.151011) (xy 202.339448 -200.155302) (xy 202.318335 -200.169664)
			(xy 202.272608 -200.192389) (xy 202.223932 -200.207816) (xy 202.173464 -200.215578) (xy 202.147932 -200.216008)
			(xy 202.122403 -200.215548) (xy 202.07194 -200.207778) (xy 202.023268 -200.192355) (xy 201.977539 -200.169646)
			(xy 201.956416 -200.155302) (xy 201.94988 -200.151018) (xy 201.935013 -200.146231) (xy 201.927206 -200.145904)
			(xy 201.411332 -200.145904) (xy 201.406003 -200.145551) (xy 201.39846 -200.138024) (xy 201.398124 -200.132696)
			(xy 195.353919 -200.132696) (xy 195.353503 -200.137756) (xy 195.346038 -200.145326) (xy 195.340732 -200.145904)
			(xy 194.824858 -200.145904) (xy 194.81705 -200.146241) (xy 194.802178 -200.151011) (xy 194.795648 -200.155302)
			(xy 194.774535 -200.169664) (xy 194.728808 -200.192389) (xy 194.680132 -200.207816) (xy 194.629664 -200.215578)
			(xy 194.604132 -200.216008) (xy 194.578603 -200.215548) (xy 194.52814 -200.207778) (xy 194.479468 -200.192355)
			(xy 194.433739 -200.169646) (xy 194.412616 -200.155302) (xy 194.40608 -200.151018) (xy 194.391213 -200.146231)
			(xy 194.383406 -200.145904) (xy 193.867532 -200.145904) (xy 193.862203 -200.145551) (xy 193.85466 -200.138024)
			(xy 193.854324 -200.132696) (xy 187.810118 -200.132696) (xy 187.809675 -200.137816) (xy 187.802055 -200.145401)
			(xy 187.796678 -200.145904) (xy 187.280804 -200.145904) (xy 187.272994 -200.146219) (xy 187.258123 -200.151004)
			(xy 187.251594 -200.155302) (xy 187.230468 -200.169644) (xy 187.184746 -200.192374) (xy 187.136074 -200.207806)
			(xy 187.085609 -200.215574) (xy 187.060078 -200.216008) (xy 187.034548 -200.215575) (xy 186.984084 -200.207796)
			(xy 186.935412 -200.192366) (xy 186.889684 -200.169649) (xy 186.868562 -200.155302) (xy 186.862038 -200.150998)
			(xy 186.847162 -200.146223) (xy 186.839352 -200.145904) (xy 186.323478 -200.145904) (xy 186.318122 -200.145368)
			(xy 186.31054 -200.137798) (xy 186.310016 -200.132442) (xy 180.265832 -200.132442) (xy 180.265402 -200.137758)
			(xy 180.257933 -200.145328) (xy 180.252624 -200.145904) (xy 179.73675 -200.145904) (xy 179.728942 -200.146238)
			(xy 179.71407 -200.15101) (xy 179.70754 -200.155302) (xy 179.686429 -200.169668) (xy 179.640702 -200.192392)
			(xy 179.592025 -200.207818) (xy 179.541556 -200.215579) (xy 179.516024 -200.216008) (xy 179.490495 -200.215552)
			(xy 179.440032 -200.20778) (xy 179.39136 -200.192357) (xy 179.345631 -200.169646) (xy 179.324508 -200.155302)
			(xy 179.317974 -200.151015) (xy 179.303106 -200.146229) (xy 179.295298 -200.145904) (xy 178.779424 -200.145904)
			(xy 178.774094 -200.145557) (xy 178.766551 -200.138025) (xy 178.766216 -200.132696) (xy 172.72201 -200.132696)
			(xy 172.721575 -200.137818) (xy 172.713949 -200.145403) (xy 172.70857 -200.145904) (xy 172.192696 -200.145904)
			(xy 172.184886 -200.146215) (xy 172.170014 -200.151003) (xy 172.163486 -200.155302) (xy 172.142362 -200.169648)
			(xy 172.096639 -200.192377) (xy 172.047967 -200.207808) (xy 171.997501 -200.215575) (xy 171.97197 -200.216008)
			(xy 171.94644 -200.215579) (xy 171.895976 -200.207799) (xy 171.847304 -200.192368) (xy 171.801576 -200.16965)
			(xy 171.780454 -200.155302) (xy 171.773932 -200.150994) (xy 171.759055 -200.146222) (xy 171.751244 -200.145904)
			(xy 171.23537 -200.145904) (xy 171.230013 -200.145374) (xy 171.222431 -200.137799) (xy 171.221908 -200.132442)
			(xy 165.177724 -200.132442) (xy 165.177301 -200.13776) (xy 165.169827 -200.145331) (xy 165.164516 -200.145904)
			(xy 163.691316 -200.145904) (xy 163.685985 -200.145562) (xy 163.678443 -200.138027) (xy 163.678108 -200.132696)
			(xy 56.078099 -200.132696) (xy 56.077673 -200.137821) (xy 56.07004 -200.145407) (xy 56.064658 -200.145904)
			(xy 54.591458 -200.145904) (xy 54.586099 -200.145382) (xy 54.578518 -200.137801) (xy 54.577996 -200.132442)
			(xy 48.533812 -200.132442) (xy 48.533399 -200.137763) (xy 48.525918 -200.145334) (xy 48.520604 -200.145904)
			(xy 48.00473 -200.145904) (xy 47.996921 -200.14623) (xy 47.982049 -200.151007) (xy 47.97552 -200.155302)
			(xy 47.954386 -200.169633) (xy 47.908667 -200.192365) (xy 47.859998 -200.207801) (xy 47.809534 -200.215572)
			(xy 47.784004 -200.216008) (xy 47.758474 -200.215562) (xy 47.708011 -200.207787) (xy 47.659339 -200.192361)
			(xy 47.613611 -200.169648) (xy 47.592488 -200.155302) (xy 47.585958 -200.151008) (xy 47.571087 -200.146226)
			(xy 47.563278 -200.145904) (xy 47.047404 -200.145904) (xy 47.042071 -200.14557) (xy 47.03453 -200.138029)
			(xy 47.034196 -200.132696) (xy 40.989987 -200.132696) (xy 40.989483 -200.137799) (xy 40.981907 -200.14538)
			(xy 40.97655 -200.145904) (xy 40.460676 -200.145904) (xy 40.452865 -200.146207) (xy 40.437994 -200.151)
			(xy 40.431466 -200.155302) (xy 40.410347 -200.169656) (xy 40.364623 -200.192383) (xy 40.315949 -200.207812)
			(xy 40.265481 -200.215577) (xy 40.23995 -200.216008) (xy 40.214421 -200.215539) (xy 40.163959 -200.207771)
			(xy 40.115287 -200.192352) (xy 40.069557 -200.169645) (xy 40.048434 -200.155302) (xy 40.041894 -200.151025)
			(xy 40.027031 -200.146233) (xy 40.019224 -200.145904) (xy 39.50335 -200.145904) (xy 39.49799 -200.145387)
			(xy 39.49041 -200.137802) (xy 39.489888 -200.132442) (xy 33.445704 -200.132442) (xy 33.44521 -200.137741)
			(xy 33.437785 -200.145307) (xy 33.432496 -200.145904) (xy 32.916622 -200.145904) (xy 32.908813 -200.146226)
			(xy 32.893941 -200.151006) (xy 32.887412 -200.155302) (xy 32.866281 -200.169636) (xy 32.820561 -200.192368)
			(xy 32.77189 -200.207802) (xy 32.721426 -200.215573) (xy 32.695896 -200.216008) (xy 32.670366 -200.215566)
			(xy 32.619903 -200.20779) (xy 32.571231 -200.192363) (xy 32.525503 -200.169648) (xy 32.50438 -200.155302)
			(xy 32.497852 -200.151004) (xy 32.482979 -200.146225) (xy 32.47517 -200.145904) (xy 31.959296 -200.145904)
			(xy 31.954032 -200.145408) (xy 31.946589 -200.137961) (xy 31.946088 -200.132696) (xy 25.90188 -200.132696)
			(xy 25.90141 -200.137741) (xy 25.893985 -200.145307) (xy 25.888696 -200.145904) (xy 25.372822 -200.145904)
			(xy 25.365013 -200.146226) (xy 25.350141 -200.151006) (xy 25.343612 -200.155302) (xy 25.322481 -200.169636)
			(xy 25.276761 -200.192368) (xy 25.22809 -200.207802) (xy 25.177626 -200.215573) (xy 25.152096 -200.216008)
			(xy 25.126566 -200.215566) (xy 25.076103 -200.20779) (xy 25.027431 -200.192363) (xy 24.981703 -200.169648)
			(xy 24.96058 -200.155302) (xy 24.954052 -200.151004) (xy 24.939179 -200.146225) (xy 24.93137 -200.145904)
			(xy 24.415496 -200.145904) (xy 24.410232 -200.145408) (xy 24.402789 -200.137961) (xy 24.402288 -200.132696)
			(xy 18.358079 -200.132696) (xy 18.357582 -200.137801) (xy 18.350001 -200.145382) (xy 18.344642 -200.145904)
			(xy 17.828768 -200.145904) (xy 17.820961 -200.146246) (xy 17.806089 -200.151013) (xy 17.799558 -200.155302)
			(xy 17.778442 -200.16966) (xy 17.732716 -200.192386) (xy 17.684041 -200.207814) (xy 17.633574 -200.215577)
			(xy 17.608042 -200.216008) (xy 17.582513 -200.215543) (xy 17.532051 -200.207774) (xy 17.483378 -200.192353)
			(xy 17.437649 -200.169645) (xy 17.416526 -200.155302) (xy 17.409988 -200.151022) (xy 17.395123 -200.146232)
			(xy 17.387316 -200.145904) (xy 16.871442 -200.145904) (xy 16.866093 -200.145326) (xy 16.858507 -200.137788)
			(xy 16.85798 -200.132442) (xy 2.509012 -200.132442) (xy 2.509012 -200.98258) (xy 20.958048 -200.98258)
			(xy 20.958048 -200.488042) (xy 20.958409 -200.48261) (xy 20.966079 -200.474921) (xy 20.97151 -200.47458)
			(xy 21.487638 -200.47458) (xy 21.495446 -200.474243) (xy 21.510318 -200.469473) (xy 21.516848 -200.465182)
			(xy 21.537937 -200.450833) (xy 21.583598 -200.428102) (xy 21.632204 -200.412643) (xy 21.682607 -200.40482)
			(xy 21.733613 -200.40482) (xy 21.784016 -200.412643) (xy 21.832622 -200.428102) (xy 21.878283 -200.450833)
			(xy 21.899372 -200.465182) (xy 21.905912 -200.469459) (xy 21.920775 -200.474251) (xy 21.928582 -200.47458)
			(xy 22.44471 -200.47458) (xy 22.450156 -200.474877) (xy 22.457844 -200.482594) (xy 22.458172 -200.488042)
			(xy 22.458172 -200.98258) (xy 28.502356 -200.98258) (xy 28.502356 -200.488042) (xy 28.502853 -200.482739)
			(xy 28.510272 -200.475165) (xy 28.515564 -200.47458) (xy 29.031692 -200.47458) (xy 29.039502 -200.474266)
			(xy 29.054374 -200.469481) (xy 29.060902 -200.465182) (xy 29.081991 -200.450833) (xy 29.127652 -200.428102)
			(xy 29.176258 -200.412643) (xy 29.226661 -200.40482) (xy 29.277667 -200.40482) (xy 29.32807 -200.412643)
			(xy 29.376676 -200.428102) (xy 29.422337 -200.450833) (xy 29.443426 -200.465182) (xy 29.449954 -200.46948)
			(xy 29.464827 -200.474259) (xy 29.472636 -200.47458) (xy 29.988764 -200.47458) (xy 29.994089 -200.47495)
			(xy 30.001631 -200.482465) (xy 30.001972 -200.487788) (xy 30.001972 -200.488296) (xy 30.001972 -200.98258)
			(xy 36.046156 -200.98258) (xy 36.046156 -200.488042) (xy 36.046653 -200.482739) (xy 36.054072 -200.475165)
			(xy 36.059364 -200.47458) (xy 36.575492 -200.47458) (xy 36.583302 -200.474266) (xy 36.598174 -200.469481)
			(xy 36.604702 -200.465182) (xy 36.625791 -200.450833) (xy 36.671452 -200.428102) (xy 36.720058 -200.412643)
			(xy 36.770461 -200.40482) (xy 36.821467 -200.40482) (xy 36.87187 -200.412643) (xy 36.920476 -200.428102)
			(xy 36.966137 -200.450833) (xy 36.987226 -200.465182) (xy 36.993754 -200.46948) (xy 37.008627 -200.474259)
			(xy 37.016436 -200.47458) (xy 37.532564 -200.47458) (xy 37.537889 -200.47495) (xy 37.545431 -200.482465)
			(xy 37.545772 -200.487788) (xy 37.545772 -200.488296) (xy 37.545772 -200.98258) (xy 43.589956 -200.98258)
			(xy 43.589956 -200.488042) (xy 43.590309 -200.482608) (xy 43.597985 -200.474919) (xy 43.603418 -200.47458)
			(xy 44.119546 -200.47458) (xy 44.127354 -200.474247) (xy 44.142226 -200.469474) (xy 44.148756 -200.465182)
			(xy 44.169845 -200.450833) (xy 44.215506 -200.428102) (xy 44.264112 -200.412643) (xy 44.314515 -200.40482)
			(xy 44.365521 -200.40482) (xy 44.415924 -200.412643) (xy 44.46453 -200.428102) (xy 44.510191 -200.450833)
			(xy 44.53128 -200.465182) (xy 44.537818 -200.469462) (xy 44.552683 -200.474252) (xy 44.56049 -200.47458)
			(xy 45.076618 -200.47458) (xy 45.082066 -200.474871) (xy 45.089753 -200.482593) (xy 45.09008 -200.488042)
			(xy 45.09008 -200.98258) (xy 51.134264 -200.98258) (xy 51.134264 -200.488042) (xy 51.134754 -200.482737)
			(xy 51.142178 -200.475162) (xy 51.147472 -200.47458) (xy 51.6636 -200.47458) (xy 51.67141 -200.47427)
			(xy 51.686282 -200.469482) (xy 51.69281 -200.465182) (xy 51.713899 -200.450833) (xy 51.75956 -200.428102)
			(xy 51.808166 -200.412643) (xy 51.858569 -200.40482) (xy 51.909575 -200.40482) (xy 51.959978 -200.412643)
			(xy 52.008584 -200.428102) (xy 52.054245 -200.450833) (xy 52.075334 -200.465182) (xy 52.08186 -200.469483)
			(xy 52.096734 -200.47426) (xy 52.104544 -200.47458) (xy 52.620672 -200.47458) (xy 52.625998 -200.474944)
			(xy 52.63354 -200.482463) (xy 52.63388 -200.487788) (xy 52.63388 -200.488296) (xy 52.63388 -200.98258)
			(xy 58.678064 -200.98258) (xy 58.678064 -200.488042) (xy 58.67841 -200.482606) (xy 58.686091 -200.474917)
			(xy 58.691526 -200.47458) (xy 60.164726 -200.47458) (xy 60.170175 -200.474866) (xy 60.177862 -200.482592)
			(xy 60.178188 -200.488042) (xy 60.178188 -200.98258) (xy 167.778176 -200.98258) (xy 167.778176 -200.488042)
			(xy 167.778655 -200.482734) (xy 167.786087 -200.475159) (xy 167.791384 -200.47458) (xy 169.264584 -200.47458)
			(xy 169.269911 -200.474936) (xy 169.277452 -200.482462) (xy 169.277792 -200.487788) (xy 169.277792 -200.98258)
			(xy 175.321976 -200.98258) (xy 175.321976 -200.488042) (xy 175.322311 -200.482604) (xy 175.33 -200.474913)
			(xy 175.335438 -200.47458) (xy 175.851566 -200.47458) (xy 175.859375 -200.474255) (xy 175.874247 -200.469477)
			(xy 175.880776 -200.465182) (xy 175.901865 -200.450833) (xy 175.947526 -200.428102) (xy 175.996132 -200.412643)
			(xy 176.046535 -200.40482) (xy 176.097541 -200.40482) (xy 176.147944 -200.412643) (xy 176.19655 -200.428102)
			(xy 176.242211 -200.450833) (xy 176.2633 -200.465182) (xy 176.269833 -200.46947) (xy 176.284702 -200.474255)
			(xy 176.29251 -200.47458) (xy 176.808638 -200.47458) (xy 176.814088 -200.474858) (xy 176.821774 -200.48259)
			(xy 176.8221 -200.488042) (xy 176.8221 -200.98258) (xy 182.866284 -200.98258) (xy 182.866284 -200.488042)
			(xy 182.866756 -200.482733) (xy 182.874192 -200.475156) (xy 182.879492 -200.47458) (xy 183.39562 -200.47458)
			(xy 183.403431 -200.474278) (xy 183.418303 -200.469484) (xy 183.42483 -200.465182) (xy 183.445919 -200.450833)
			(xy 183.49158 -200.428102) (xy 183.540186 -200.412643) (xy 183.590589 -200.40482) (xy 183.641595 -200.40482)
			(xy 183.691998 -200.412643) (xy 183.740604 -200.428102) (xy 183.786265 -200.450833) (xy 183.807354 -200.465182)
			(xy 183.813875 -200.469491) (xy 183.828753 -200.474263) (xy 183.836564 -200.47458) (xy 184.352692 -200.47458)
			(xy 184.357951 -200.475099) (xy 184.365393 -200.48253) (xy 184.3659 -200.487788) (xy 184.3659 -200.488296)
			(xy 184.3659 -200.98258) (xy 190.410084 -200.98258) (xy 190.410084 -200.488042) (xy 190.410412 -200.482602)
			(xy 190.418106 -200.47491) (xy 190.423546 -200.47458) (xy 190.939674 -200.47458) (xy 190.947483 -200.474259)
			(xy 190.962355 -200.469478) (xy 190.968884 -200.465182) (xy 190.989973 -200.450833) (xy 191.035634 -200.428102)
			(xy 191.08424 -200.412643) (xy 191.134643 -200.40482) (xy 191.185649 -200.40482) (xy 191.236052 -200.412643)
			(xy 191.284658 -200.428102) (xy 191.330319 -200.450833) (xy 191.351408 -200.465182) (xy 191.35794 -200.469473)
			(xy 191.37281 -200.474256) (xy 191.380618 -200.47458) (xy 191.896746 -200.47458) (xy 191.902126 -200.475024)
			(xy 191.909711 -200.482659) (xy 191.910208 -200.488042) (xy 191.910208 -200.98258) (xy 197.954392 -200.98258)
			(xy 197.954392 -200.488042) (xy 197.954946 -200.482754) (xy 197.962326 -200.475183) (xy 197.9676 -200.47458)
			(xy 198.483728 -200.47458) (xy 198.49154 -200.474282) (xy 198.506411 -200.469485) (xy 198.512938 -200.465182)
			(xy 198.534027 -200.450833) (xy 198.579688 -200.428102) (xy 198.628294 -200.412643) (xy 198.678697 -200.40482)
			(xy 198.729703 -200.40482) (xy 198.780106 -200.412643) (xy 198.828712 -200.428102) (xy 198.874373 -200.450833)
			(xy 198.895462 -200.465182) (xy 198.902004 -200.469455) (xy 198.916866 -200.47425) (xy 198.924672 -200.47458)
			(xy 199.4408 -200.47458) (xy 199.44606 -200.475094) (xy 199.453502 -200.482529) (xy 199.454008 -200.487788)
			(xy 199.454008 -200.488296) (xy 199.454008 -200.98258) (xy 205.498192 -200.98258) (xy 205.498192 -200.488042)
			(xy 205.498746 -200.482754) (xy 205.506126 -200.475183) (xy 205.5114 -200.47458) (xy 206.027528 -200.47458)
			(xy 206.03534 -200.474282) (xy 206.050211 -200.469485) (xy 206.056738 -200.465182) (xy 206.077827 -200.450833)
			(xy 206.123488 -200.428102) (xy 206.172094 -200.412643) (xy 206.222497 -200.40482) (xy 206.273503 -200.40482)
			(xy 206.323906 -200.412643) (xy 206.372512 -200.428102) (xy 206.418173 -200.450833) (xy 206.439262 -200.465182)
			(xy 206.445804 -200.469455) (xy 206.460666 -200.47425) (xy 206.468472 -200.47458) (xy 206.9846 -200.47458)
			(xy 206.98986 -200.475094) (xy 206.997302 -200.482529) (xy 206.997808 -200.487788) (xy 206.997808 -200.488296)
			(xy 206.997808 -200.982326) (xy 268.898116 -200.982326) (xy 268.898116 -200.487788) (xy 268.898421 -200.482448)
			(xy 268.905983 -200.474907) (xy 268.911324 -200.47458) (xy 268.911832 -200.47458) (xy 269.427706 -200.47458)
			(xy 269.435517 -200.474272) (xy 269.450388 -200.469483) (xy 269.456916 -200.465182) (xy 269.478005 -200.450833)
			(xy 269.523666 -200.428102) (xy 269.572272 -200.412643) (xy 269.622675 -200.40482) (xy 269.673681 -200.40482)
			(xy 269.724084 -200.412643) (xy 269.77269 -200.428102) (xy 269.818351 -200.450833) (xy 269.83944 -200.465182)
			(xy 269.845965 -200.469485) (xy 269.86084 -200.474261) (xy 269.86865 -200.47458) (xy 270.384778 -200.47458)
			(xy 270.390089 -200.475043) (xy 270.397663 -200.482486) (xy 270.39824 -200.487788) (xy 270.39824 -200.982326)
			(xy 270.398218 -200.98258) (xy 276.442424 -200.98258) (xy 276.442424 -200.982072) (xy 276.442424 -200.487788)
			(xy 276.442722 -200.482446) (xy 276.450289 -200.474904) (xy 276.455632 -200.47458) (xy 276.97176 -200.47458)
			(xy 276.979569 -200.474253) (xy 276.994441 -200.469477) (xy 277.00097 -200.465182) (xy 277.022059 -200.450833)
			(xy 277.06772 -200.428102) (xy 277.116326 -200.412643) (xy 277.166729 -200.40482) (xy 277.217735 -200.40482)
			(xy 277.268138 -200.412643) (xy 277.316744 -200.428102) (xy 277.362405 -200.450833) (xy 277.383494 -200.465182)
			(xy 277.390029 -200.469468) (xy 277.404896 -200.474254) (xy 277.412704 -200.47458) (xy 277.928832 -200.47458)
			(xy 277.934096 -200.475072) (xy 277.941536 -200.482524) (xy 277.94204 -200.487788) (xy 277.94204 -200.982326)
			(xy 277.942019 -200.98258) (xy 283.986224 -200.98258) (xy 283.986224 -200.982072) (xy 283.986224 -200.487788)
			(xy 283.986522 -200.482446) (xy 283.994089 -200.474904) (xy 283.999432 -200.47458) (xy 284.51556 -200.47458)
			(xy 284.523369 -200.474253) (xy 284.538241 -200.469477) (xy 284.54477 -200.465182) (xy 284.565859 -200.450833)
			(xy 284.61152 -200.428102) (xy 284.660126 -200.412643) (xy 284.710529 -200.40482) (xy 284.761535 -200.40482)
			(xy 284.811938 -200.412643) (xy 284.860544 -200.428102) (xy 284.906205 -200.450833) (xy 284.927294 -200.465182)
			(xy 284.933829 -200.469468) (xy 284.948696 -200.474254) (xy 284.956504 -200.47458) (xy 285.472632 -200.47458)
			(xy 285.477896 -200.475072) (xy 285.485336 -200.482524) (xy 285.48584 -200.487788) (xy 285.48584 -200.982326)
			(xy 291.530024 -200.982326) (xy 291.530024 -200.487788) (xy 291.530322 -200.482446) (xy 291.537889 -200.474904)
			(xy 291.543232 -200.47458) (xy 291.54374 -200.47458) (xy 292.059614 -200.47458) (xy 292.067425 -200.474276)
			(xy 292.082296 -200.469484) (xy 292.088824 -200.465182) (xy 292.109913 -200.450833) (xy 292.155574 -200.428102)
			(xy 292.20418 -200.412643) (xy 292.254583 -200.40482) (xy 292.305589 -200.40482) (xy 292.355992 -200.412643)
			(xy 292.404598 -200.428102) (xy 292.450259 -200.450833) (xy 292.471348 -200.465182) (xy 292.477871 -200.469488)
			(xy 292.492747 -200.474262) (xy 292.500558 -200.47458) (xy 293.016686 -200.47458) (xy 293.021998 -200.475037)
			(xy 293.029572 -200.482485) (xy 293.030148 -200.487788) (xy 293.030148 -200.982326) (xy 293.030125 -200.98258)
			(xy 299.074332 -200.98258) (xy 299.074332 -200.982072) (xy 299.074332 -200.487788) (xy 299.074623 -200.482444)
			(xy 299.082195 -200.474902) (xy 299.08754 -200.47458) (xy 299.603668 -200.47458) (xy 299.611477 -200.474256)
			(xy 299.626349 -200.469478) (xy 299.632878 -200.465182) (xy 299.653967 -200.450833) (xy 299.699628 -200.428102)
			(xy 299.748234 -200.412643) (xy 299.798637 -200.40482) (xy 299.849643 -200.40482) (xy 299.900046 -200.412643)
			(xy 299.948652 -200.428102) (xy 299.994313 -200.450833) (xy 300.015402 -200.465182) (xy 300.021935 -200.469471)
			(xy 300.036804 -200.474255) (xy 300.044612 -200.47458) (xy 300.56074 -200.47458) (xy 300.566005 -200.475067)
			(xy 300.573444 -200.482522) (xy 300.573948 -200.487788) (xy 300.573948 -200.982326) (xy 306.618132 -200.982326)
			(xy 306.618132 -200.487788) (xy 306.618423 -200.482444) (xy 306.625995 -200.474902) (xy 306.63134 -200.47458)
			(xy 306.631848 -200.47458) (xy 308.104794 -200.47458) (xy 308.110107 -200.475032) (xy 308.117681 -200.482484)
			(xy 308.118256 -200.487788) (xy 308.118256 -200.982326) (xy 308.118233 -200.98258) (xy 415.718244 -200.98258)
			(xy 415.718244 -200.487788) (xy 415.718782 -200.482535) (xy 415.726201 -200.475096) (xy 415.731452 -200.47458)
			(xy 417.204652 -200.47458) (xy 417.209975 -200.474958) (xy 417.217518 -200.482467) (xy 417.21786 -200.487788)
			(xy 417.21786 -200.982326) (xy 423.262044 -200.982326) (xy 423.262044 -200.487788) (xy 423.262582 -200.482535)
			(xy 423.270001 -200.475096) (xy 423.275252 -200.47458) (xy 423.27576 -200.47458) (xy 423.791634 -200.47458)
			(xy 423.799442 -200.474241) (xy 423.814313 -200.469473) (xy 423.820844 -200.465182) (xy 423.841933 -200.450833)
			(xy 423.887594 -200.428102) (xy 423.9362 -200.412643) (xy 423.986603 -200.40482) (xy 424.037609 -200.40482)
			(xy 424.088012 -200.412643) (xy 424.136618 -200.428102) (xy 424.182279 -200.450833) (xy 424.203368 -200.465182)
			(xy 424.209909 -200.469458) (xy 424.224772 -200.47425) (xy 424.232578 -200.47458) (xy 424.748706 -200.47458)
			(xy 424.75402 -200.475024) (xy 424.761593 -200.482482) (xy 424.762168 -200.487788) (xy 424.762168 -200.982326)
			(xy 424.762144 -200.98258) (xy 430.806352 -200.98258) (xy 430.806352 -200.982072) (xy 430.806352 -200.487788)
			(xy 430.806883 -200.482534) (xy 430.814307 -200.475094) (xy 430.81956 -200.47458) (xy 431.335688 -200.47458)
			(xy 431.343498 -200.474265) (xy 431.35837 -200.46948) (xy 431.364898 -200.465182) (xy 431.385987 -200.450833)
			(xy 431.431648 -200.428102) (xy 431.480254 -200.412643) (xy 431.530657 -200.40482) (xy 431.581663 -200.40482)
			(xy 431.632066 -200.412643) (xy 431.680672 -200.428102) (xy 431.726333 -200.450833) (xy 431.747422 -200.465182)
			(xy 431.753951 -200.469478) (xy 431.768823 -200.474258) (xy 431.776632 -200.47458) (xy 432.29276 -200.47458)
			(xy 432.298084 -200.474953) (xy 432.305626 -200.482465) (xy 432.305968 -200.487788) (xy 432.305968 -200.982326)
			(xy 438.350152 -200.982326) (xy 438.350152 -200.487788) (xy 438.350683 -200.482534) (xy 438.358107 -200.475094)
			(xy 438.36336 -200.47458) (xy 438.363868 -200.47458) (xy 438.879742 -200.47458) (xy 438.88755 -200.474245)
			(xy 438.902422 -200.469474) (xy 438.908952 -200.465182) (xy 438.930041 -200.450833) (xy 438.975702 -200.428102)
			(xy 439.024308 -200.412643) (xy 439.074711 -200.40482) (xy 439.125717 -200.40482) (xy 439.17612 -200.412643)
			(xy 439.224726 -200.428102) (xy 439.270387 -200.450833) (xy 439.291476 -200.465182) (xy 439.298015 -200.469461)
			(xy 439.312879 -200.474252) (xy 439.320686 -200.47458) (xy 439.836814 -200.47458) (xy 439.842129 -200.475019)
			(xy 439.849702 -200.482481) (xy 439.850276 -200.487788) (xy 439.850276 -200.982326) (xy 439.850252 -200.98258)
			(xy 445.89446 -200.98258) (xy 445.89446 -200.982072) (xy 445.89446 -200.487788) (xy 445.894984 -200.482532)
			(xy 445.902412 -200.475092) (xy 445.907668 -200.47458) (xy 446.423796 -200.47458) (xy 446.431606 -200.474268)
			(xy 446.446478 -200.469481) (xy 446.453006 -200.465182) (xy 446.474095 -200.450833) (xy 446.519756 -200.428102)
			(xy 446.568362 -200.412643) (xy 446.618765 -200.40482) (xy 446.669771 -200.40482) (xy 446.720174 -200.412643)
			(xy 446.76878 -200.428102) (xy 446.814441 -200.450833) (xy 446.83553 -200.465182) (xy 446.842057 -200.469481)
			(xy 446.85693 -200.474259) (xy 446.86474 -200.47458) (xy 447.380868 -200.47458) (xy 447.386193 -200.474947)
			(xy 447.393735 -200.482464) (xy 447.394076 -200.487788) (xy 447.394076 -200.982326) (xy 447.394053 -200.98258)
			(xy 453.43826 -200.98258) (xy 453.43826 -200.982072) (xy 453.43826 -200.487788) (xy 453.438784 -200.482532)
			(xy 453.446212 -200.475092) (xy 453.451468 -200.47458) (xy 453.967596 -200.47458) (xy 453.975406 -200.474268)
			(xy 453.990278 -200.469481) (xy 453.996806 -200.465182) (xy 454.017895 -200.450833) (xy 454.063556 -200.428102)
			(xy 454.112162 -200.412643) (xy 454.162565 -200.40482) (xy 454.213571 -200.40482) (xy 454.263974 -200.412643)
			(xy 454.31258 -200.428102) (xy 454.358241 -200.450833) (xy 454.37933 -200.465182) (xy 454.385857 -200.469481)
			(xy 454.40073 -200.474259) (xy 454.40854 -200.47458) (xy 454.924668 -200.47458) (xy 454.929993 -200.474947)
			(xy 454.937535 -200.482464) (xy 454.937876 -200.487788) (xy 454.937876 -200.982326) (xy 454.937396 -200.98763)
			(xy 454.929962 -200.995198) (xy 454.924668 -200.995788) (xy 454.408794 -200.995788) (xy 454.400982 -200.996084)
			(xy 454.38611 -201.000881) (xy 454.379584 -201.005186) (xy 454.358467 -201.019542) (xy 454.312741 -201.042266)
			(xy 454.264067 -201.057694) (xy 454.213599 -201.065459) (xy 454.188068 -201.065892) (xy 454.162537 -201.065467)
			(xy 454.112073 -201.057686) (xy 454.063401 -201.042254) (xy 454.017674 -201.019535) (xy 453.996552 -201.005186)
			(xy 453.990025 -201.000886) (xy 453.975152 -200.996107) (xy 453.967342 -200.995788) (xy 453.451468 -200.995788)
			(xy 453.446197 -200.995325) (xy 453.438755 -200.987853) (xy 453.43826 -200.98258) (xy 447.394053 -200.98258)
			(xy 447.393596 -200.98763) (xy 447.386162 -200.995198) (xy 447.380868 -200.995788) (xy 446.864994 -200.995788)
			(xy 446.857182 -200.996084) (xy 446.84231 -201.000881) (xy 446.835784 -201.005186) (xy 446.814667 -201.019542)
			(xy 446.768941 -201.042266) (xy 446.720267 -201.057694) (xy 446.669799 -201.065459) (xy 446.644268 -201.065892)
			(xy 446.618737 -201.065467) (xy 446.568273 -201.057686) (xy 446.519601 -201.042254) (xy 446.473874 -201.019535)
			(xy 446.452752 -201.005186) (xy 446.446225 -201.000886) (xy 446.431352 -200.996107) (xy 446.423542 -200.995788)
			(xy 445.907668 -200.995788) (xy 445.902397 -200.995325) (xy 445.894955 -200.987853) (xy 445.89446 -200.98258)
			(xy 439.850252 -200.98258) (xy 439.849768 -200.98769) (xy 439.842178 -200.995273) (xy 439.836814 -200.995788)
			(xy 439.32094 -200.995788) (xy 439.31313 -200.996104) (xy 439.298258 -201.000887) (xy 439.29173 -201.005186)
			(xy 439.270628 -201.019566) (xy 439.224897 -201.042285) (xy 439.176218 -201.057706) (xy 439.125747 -201.065463)
			(xy 439.100214 -201.065892) (xy 439.074684 -201.065443) (xy 439.024221 -201.05767) (xy 438.975549 -201.042245)
			(xy 438.929821 -201.019532) (xy 438.908698 -201.005186) (xy 438.902161 -201.000903) (xy 438.887295 -200.996113)
			(xy 438.879488 -200.995788) (xy 438.363614 -200.995788) (xy 438.358258 -200.995243) (xy 438.350673 -200.98768)
			(xy 438.350152 -200.982326) (xy 432.305968 -200.982326) (xy 432.305495 -200.987631) (xy 432.298056 -200.9952)
			(xy 432.29276 -200.995788) (xy 431.776886 -200.995788) (xy 431.769074 -200.996081) (xy 431.754202 -201.00088)
			(xy 431.747676 -201.005186) (xy 431.726561 -201.019546) (xy 431.680835 -201.042269) (xy 431.632159 -201.057696)
			(xy 431.581691 -201.06546) (xy 431.55616 -201.065892) (xy 431.530629 -201.065471) (xy 431.480165 -201.057689)
			(xy 431.431493 -201.042256) (xy 431.385766 -201.019535) (xy 431.364644 -201.005186) (xy 431.358119 -201.000883)
			(xy 431.343244 -200.996105) (xy 431.335434 -200.995788) (xy 430.81956 -200.995788) (xy 430.814287 -200.99533)
			(xy 430.806846 -200.987855) (xy 430.806352 -200.98258) (xy 424.762144 -200.98258) (xy 424.761667 -200.987692)
			(xy 424.754072 -200.995275) (xy 424.748706 -200.995788) (xy 424.232832 -200.995788) (xy 424.225022 -200.9961)
			(xy 424.21015 -201.000886) (xy 424.203622 -201.005186) (xy 424.182494 -201.019526) (xy 424.136772 -201.042254)
			(xy 424.088101 -201.057686) (xy 424.037636 -201.065457) (xy 424.012106 -201.065892) (xy 423.986576 -201.065447)
			(xy 423.936113 -201.057673) (xy 423.88744 -201.042246) (xy 423.841712 -201.019532) (xy 423.82059 -201.005186)
			(xy 423.814055 -201.0009) (xy 423.799188 -200.996112) (xy 423.79138 -200.995788) (xy 423.275506 -200.995788)
			(xy 423.270149 -200.995248) (xy 423.262564 -200.987682) (xy 423.262044 -200.982326) (xy 417.21786 -200.982326)
			(xy 417.217394 -200.987633) (xy 417.20995 -200.995203) (xy 417.204652 -200.995788) (xy 415.731452 -200.995788)
			(xy 415.726179 -200.995335) (xy 415.718738 -200.987856) (xy 415.718244 -200.98258) (xy 308.118233 -200.98258)
			(xy 308.117766 -200.987694) (xy 308.110164 -200.995279) (xy 308.104794 -200.995788) (xy 306.631594 -200.995788)
			(xy 306.626236 -200.995256) (xy 306.618652 -200.987684) (xy 306.618132 -200.982326) (xy 300.573948 -200.982326)
			(xy 300.573493 -200.987636) (xy 300.566041 -200.995206) (xy 300.56074 -200.995788) (xy 300.044866 -200.995788)
			(xy 300.037057 -200.996115) (xy 300.022185 -201.00089) (xy 300.015656 -201.005186) (xy 299.994547 -201.019554)
			(xy 299.948818 -201.042276) (xy 299.900141 -201.0577) (xy 299.849672 -201.065462) (xy 299.82414 -201.065892)
			(xy 299.798611 -201.06543) (xy 299.748148 -201.057661) (xy 299.699476 -201.042239) (xy 299.653747 -201.01953)
			(xy 299.632624 -201.005186) (xy 299.626081 -201.000913) (xy 299.61122 -200.996117) (xy 299.603414 -200.995788)
			(xy 299.08754 -200.995788) (xy 299.082208 -200.995444) (xy 299.074664 -200.987911) (xy 299.074332 -200.98258)
			(xy 293.030125 -200.98258) (xy 293.029665 -200.987696) (xy 293.022058 -200.995281) (xy 293.016686 -200.995788)
			(xy 292.500812 -200.995788) (xy 292.493001 -200.996092) (xy 292.478129 -201.000883) (xy 292.471602 -201.005186)
			(xy 292.45048 -201.019535) (xy 292.404756 -201.04226) (xy 292.356083 -201.05769) (xy 292.305617 -201.065458)
			(xy 292.280086 -201.065892) (xy 292.254556 -201.065458) (xy 292.204092 -201.05768) (xy 292.15542 -201.04225)
			(xy 292.109692 -201.019533) (xy 292.08857 -201.005186) (xy 292.082039 -201.000893) (xy 292.067169 -200.996109)
			(xy 292.05936 -200.995788) (xy 291.543486 -200.995788) (xy 291.538127 -200.995261) (xy 291.530543 -200.987685)
			(xy 291.530024 -200.982326) (xy 285.48584 -200.982326) (xy 285.485392 -200.987638) (xy 285.477936 -200.995209)
			(xy 285.472632 -200.995788) (xy 284.956758 -200.995788) (xy 284.948949 -200.996111) (xy 284.934076 -201.000889)
			(xy 284.927548 -201.005186) (xy 284.906441 -201.019558) (xy 284.860712 -201.042279) (xy 284.812034 -201.057702)
			(xy 284.761564 -201.065462) (xy 284.736032 -201.065892) (xy 284.710503 -201.065434) (xy 284.66004 -201.057664)
			(xy 284.611367 -201.042241) (xy 284.565639 -201.01953) (xy 284.544516 -201.005186) (xy 284.537975 -201.00091)
			(xy 284.523113 -200.996116) (xy 284.515306 -200.995788) (xy 283.999432 -200.995788) (xy 283.994099 -200.99545)
			(xy 283.986555 -200.987912) (xy 283.986224 -200.98258) (xy 277.942019 -200.98258) (xy 277.941592 -200.987638)
			(xy 277.934136 -200.995209) (xy 277.928832 -200.995788) (xy 277.412958 -200.995788) (xy 277.405149 -200.996111)
			(xy 277.390276 -201.000889) (xy 277.383748 -201.005186) (xy 277.362641 -201.019558) (xy 277.316912 -201.042279)
			(xy 277.268234 -201.057702) (xy 277.217764 -201.065462) (xy 277.192232 -201.065892) (xy 277.166703 -201.065434)
			(xy 277.11624 -201.057664) (xy 277.067567 -201.042241) (xy 277.021839 -201.01953) (xy 277.000716 -201.005186)
			(xy 276.994175 -201.00091) (xy 276.979313 -200.996116) (xy 276.971506 -200.995788) (xy 276.455632 -200.995788)
			(xy 276.450299 -200.99545) (xy 276.442755 -200.987912) (xy 276.442424 -200.98258) (xy 270.398218 -200.98258)
			(xy 270.397765 -200.987698) (xy 270.390152 -200.995284) (xy 270.384778 -200.995788) (xy 269.868904 -200.995788)
			(xy 269.861092 -200.996089) (xy 269.846221 -201.000882) (xy 269.839694 -201.005186) (xy 269.818574 -201.019538)
			(xy 269.772849 -201.042263) (xy 269.724176 -201.057692) (xy 269.673709 -201.065459) (xy 269.648178 -201.065892)
			(xy 269.622648 -201.065462) (xy 269.572184 -201.057683) (xy 269.523511 -201.042252) (xy 269.477784 -201.019534)
			(xy 269.456662 -201.005186) (xy 269.450133 -201.00089) (xy 269.435261 -200.996108) (xy 269.427452 -200.995788)
			(xy 268.911578 -200.995788) (xy 268.906218 -200.995267) (xy 268.898635 -200.987686) (xy 268.898116 -200.982326)
			(xy 206.997808 -200.982326) (xy 206.997808 -200.98258) (xy 206.99746 -200.98791) (xy 206.989929 -200.995452)
			(xy 206.9846 -200.995788) (xy 206.468726 -200.995788) (xy 206.460849 -200.996045) (xy 206.445845 -201.000849)
			(xy 206.439262 -201.005186) (xy 206.418189 -201.019583) (xy 206.372542 -201.042409) (xy 206.323935 -201.057965)
			(xy 206.273517 -201.065883) (xy 206.248 -201.0664) (xy 206.222479 -201.065927) (xy 206.172052 -201.058028)
			(xy 206.12344 -201.042463) (xy 206.077802 -201.019603) (xy 206.056738 -201.005186) (xy 206.050141 -201.000882)
			(xy 206.035145 -200.996089) (xy 206.027274 -200.995788) (xy 205.5114 -200.995788) (xy 205.506063 -200.995471)
			(xy 205.498521 -200.987918) (xy 205.498192 -200.98258) (xy 199.454008 -200.98258) (xy 199.45366 -200.98791)
			(xy 199.446129 -200.995452) (xy 199.4408 -200.995788) (xy 198.924926 -200.995788) (xy 198.917049 -200.996045)
			(xy 198.902045 -201.000849) (xy 198.895462 -201.005186) (xy 198.874389 -201.019583) (xy 198.828742 -201.042409)
			(xy 198.780135 -201.057965) (xy 198.729717 -201.065883) (xy 198.7042 -201.0664) (xy 198.678679 -201.065927)
			(xy 198.628252 -201.058028) (xy 198.57964 -201.042463) (xy 198.534002 -201.019603) (xy 198.512938 -201.005186)
			(xy 198.506341 -201.000882) (xy 198.491345 -200.996089) (xy 198.483474 -200.995788) (xy 197.9676 -200.995788)
			(xy 197.962263 -200.995471) (xy 197.954721 -200.987918) (xy 197.954392 -200.98258) (xy 191.910208 -200.98258)
			(xy 191.90986 -200.98791) (xy 191.902329 -200.995452) (xy 191.897 -200.995788) (xy 191.896492 -200.995788)
			(xy 191.380872 -200.995788) (xy 191.372996 -200.996065) (xy 191.357992 -201.000855) (xy 191.351408 -201.005186)
			(xy 191.33035 -201.019607) (xy 191.284698 -201.042427) (xy 191.236086 -201.057977) (xy 191.185664 -201.065887)
			(xy 191.160146 -201.0664) (xy 191.134626 -201.065904) (xy 191.084199 -201.058012) (xy 191.035588 -201.042453)
			(xy 190.989949 -201.0196) (xy 190.968884 -201.005186) (xy 190.962299 -201.000861) (xy 190.947294 -200.996081)
			(xy 190.93942 -200.995788) (xy 190.423546 -200.995788) (xy 190.418254 -200.99525) (xy 190.410682 -200.987859)
			(xy 190.410084 -200.98258) (xy 184.3659 -200.98258) (xy 184.365559 -200.987912) (xy 184.358023 -200.995454)
			(xy 184.352692 -200.995788) (xy 183.836818 -200.995788) (xy 183.828944 -200.996084) (xy 183.81394 -201.000861)
			(xy 183.807354 -201.005186) (xy 183.786283 -201.019587) (xy 183.740635 -201.042412) (xy 183.692027 -201.057967)
			(xy 183.641609 -201.065884) (xy 183.616092 -201.0664) (xy 183.590573 -201.065881) (xy 183.540147 -201.057996)
			(xy 183.491536 -201.042444) (xy 183.445896 -201.019597) (xy 183.42483 -201.005186) (xy 183.418234 -201.000878)
			(xy 183.403237 -200.996087) (xy 183.395366 -200.995788) (xy 182.879492 -200.995788) (xy 182.874154 -200.995477)
			(xy 182.866612 -200.987919) (xy 182.866284 -200.98258) (xy 176.8221 -200.98258) (xy 176.821759 -200.987912)
			(xy 176.814223 -200.995454) (xy 176.808892 -200.995788) (xy 176.808384 -200.995788) (xy 176.292764 -200.995788)
			(xy 176.284888 -200.996061) (xy 176.269884 -201.000854) (xy 176.2633 -201.005186) (xy 176.242216 -201.019567)
			(xy 176.196573 -201.042397) (xy 176.147969 -201.057957) (xy 176.097554 -201.06588) (xy 176.072038 -201.0664)
			(xy 176.046518 -201.065908) (xy 175.996091 -201.058014) (xy 175.947479 -201.042455) (xy 175.901841 -201.019601)
			(xy 175.880776 -201.005186) (xy 175.874192 -201.000858) (xy 175.859186 -200.996079) (xy 175.851312 -200.995788)
			(xy 175.335438 -200.995788) (xy 175.330145 -200.995255) (xy 175.322573 -200.98786) (xy 175.321976 -200.98258)
			(xy 169.277792 -200.98258) (xy 169.277458 -200.987914) (xy 169.269917 -200.995457) (xy 169.264584 -200.995788)
			(xy 167.791384 -200.995788) (xy 167.786045 -200.995482) (xy 167.778503 -200.98792) (xy 167.778176 -200.98258)
			(xy 60.178188 -200.98258) (xy 60.177858 -200.987915) (xy 60.170315 -200.995458) (xy 60.16498 -200.995788)
			(xy 60.164472 -200.995788) (xy 58.691526 -200.995788) (xy 58.686231 -200.995263) (xy 58.678661 -200.987862)
			(xy 58.678064 -200.98258) (xy 52.63388 -200.98258) (xy 52.633557 -200.987916) (xy 52.626009 -200.99546)
			(xy 52.620672 -200.995788) (xy 52.104798 -200.995788) (xy 52.096923 -200.996076) (xy 52.081919 -201.000859)
			(xy 52.075334 -201.005186) (xy 52.054268 -201.019596) (xy 52.008619 -201.042419) (xy 51.960009 -201.057971)
			(xy 51.90959 -201.065885) (xy 51.884072 -201.0664) (xy 51.858553 -201.065891) (xy 51.808126 -201.058003)
			(xy 51.759515 -201.042448) (xy 51.713876 -201.019599) (xy 51.69281 -201.005186) (xy 51.686219 -201.000871)
			(xy 51.671218 -200.996084) (xy 51.663346 -200.995788) (xy 51.147472 -200.995788) (xy 51.142201 -200.995322)
			(xy 51.134759 -200.987853) (xy 51.134264 -200.98258) (xy 45.09008 -200.98258) (xy 45.089757 -200.987916)
			(xy 45.082209 -200.99546) (xy 45.076872 -200.995788) (xy 45.076364 -200.995788) (xy 44.560744 -200.995788)
			(xy 44.552867 -200.996053) (xy 44.537863 -201.000852) (xy 44.53128 -201.005186) (xy 44.510202 -201.019576)
			(xy 44.464557 -201.042403) (xy 44.415951 -201.057961) (xy 44.365535 -201.065882) (xy 44.340018 -201.0664)
			(xy 44.314497 -201.065918) (xy 44.26407 -201.058021) (xy 44.215459 -201.042459) (xy 44.169821 -201.019602)
			(xy 44.148756 -201.005186) (xy 44.142177 -201.00085) (xy 44.127167 -200.996076) (xy 44.119292 -200.995788)
			(xy 43.603418 -200.995788) (xy 43.598122 -200.995268) (xy 43.590552 -200.987864) (xy 43.589956 -200.98258)
			(xy 37.545772 -200.98258) (xy 37.545456 -200.987918) (xy 37.537903 -200.995463) (xy 37.532564 -200.995788)
			(xy 37.01669 -200.995788) (xy 37.008815 -200.996073) (xy 36.993811 -201.000858) (xy 36.987226 -201.005186)
			(xy 36.966163 -201.019599) (xy 36.920512 -201.042421) (xy 36.871902 -201.057973) (xy 36.821482 -201.065886)
			(xy 36.795964 -201.0664) (xy 36.770444 -201.065895) (xy 36.720018 -201.058005) (xy 36.671406 -201.04245)
			(xy 36.625767 -201.019599) (xy 36.604702 -201.005186) (xy 36.598113 -201.000868) (xy 36.583111 -200.996083)
			(xy 36.575238 -200.995788) (xy 36.059364 -200.995788) (xy 36.054092 -200.995327) (xy 36.046651 -200.987854)
			(xy 36.046156 -200.98258) (xy 30.001972 -200.98258) (xy 30.001656 -200.987918) (xy 29.994103 -200.995463)
			(xy 29.988764 -200.995788) (xy 29.47289 -200.995788) (xy 29.465015 -200.996073) (xy 29.450011 -201.000858)
			(xy 29.443426 -201.005186) (xy 29.422363 -201.019599) (xy 29.376712 -201.042421) (xy 29.328102 -201.057973)
			(xy 29.277682 -201.065886) (xy 29.252164 -201.0664) (xy 29.226644 -201.065895) (xy 29.176218 -201.058005)
			(xy 29.127606 -201.04245) (xy 29.081967 -201.019599) (xy 29.060902 -201.005186) (xy 29.054313 -201.000868)
			(xy 29.039311 -200.996083) (xy 29.031438 -200.995788) (xy 28.515564 -200.995788) (xy 28.510292 -200.995327)
			(xy 28.502851 -200.987854) (xy 28.502356 -200.98258) (xy 22.458172 -200.98258) (xy 22.457856 -200.987918)
			(xy 22.450303 -200.995463) (xy 22.444964 -200.995788) (xy 22.444456 -200.995788) (xy 21.928836 -200.995788)
			(xy 21.920959 -200.996049) (xy 21.905955 -201.00085) (xy 21.899372 -201.005186) (xy 21.878296 -201.019579)
			(xy 21.83265 -201.042406) (xy 21.784044 -201.057963) (xy 21.733627 -201.065882) (xy 21.70811 -201.0664)
			(xy 21.682589 -201.065922) (xy 21.632162 -201.058024) (xy 21.58355 -201.042461) (xy 21.537912 -201.019603)
			(xy 21.516848 -201.005186) (xy 21.510271 -201.000847) (xy 21.49526 -200.996075) (xy 21.487384 -200.995788)
			(xy 20.97151 -200.995788) (xy 20.966213 -200.995274) (xy 20.958643 -200.987865) (xy 20.958048 -200.98258)
			(xy 2.509012 -200.98258) (xy 2.509012 -201.832464) (xy 16.85798 -201.832464) (xy 16.85798 -201.337926)
			(xy 16.858301 -201.332484) (xy 16.866 -201.324794) (xy 16.871442 -201.324464) (xy 17.38757 -201.324464)
			(xy 17.39538 -201.324143) (xy 17.410251 -201.319363) (xy 17.41678 -201.315066) (xy 17.437869 -201.300717)
			(xy 17.48353 -201.277986) (xy 17.532136 -201.262527) (xy 17.582539 -201.254704) (xy 17.633545 -201.254704)
			(xy 17.683948 -201.262527) (xy 17.732554 -201.277986) (xy 17.778215 -201.300717) (xy 17.799304 -201.315066)
			(xy 17.805837 -201.319354) (xy 17.820706 -201.32414) (xy 17.828514 -201.324464) (xy 18.344642 -201.324464)
			(xy 18.350017 -201.324925) (xy 18.357602 -201.332548) (xy 18.358104 -201.337926) (xy 18.358104 -201.832464)
			(xy 20.958048 -201.832464) (xy 20.958048 -201.337926) (xy 20.958398 -201.332492) (xy 20.966077 -201.324804)
			(xy 20.97151 -201.324464) (xy 21.487638 -201.324464) (xy 21.495446 -201.32413) (xy 21.510318 -201.319358)
			(xy 21.516848 -201.315066) (xy 21.537937 -201.300717) (xy 21.583598 -201.277986) (xy 21.632204 -201.262527)
			(xy 21.682607 -201.254704) (xy 21.733613 -201.254704) (xy 21.784016 -201.262527) (xy 21.832622 -201.277986)
			(xy 21.878283 -201.300717) (xy 21.899372 -201.315066) (xy 21.905913 -201.319342) (xy 21.920776 -201.324135)
			(xy 21.928582 -201.324464) (xy 22.44471 -201.324464) (xy 22.450153 -201.324775) (xy 22.45784 -201.332483)
			(xy 22.458172 -201.337926) (xy 22.458172 -201.832464) (xy 24.402288 -201.832464) (xy 24.402288 -201.337926)
			(xy 24.402746 -201.332614) (xy 24.410193 -201.325038) (xy 24.415496 -201.324464) (xy 24.931624 -201.324464)
			(xy 24.939436 -201.324167) (xy 24.954307 -201.31937) (xy 24.960834 -201.315066) (xy 24.981923 -201.300717)
			(xy 25.027584 -201.277986) (xy 25.07619 -201.262527) (xy 25.126593 -201.254704) (xy 25.177599 -201.254704)
			(xy 25.228002 -201.262527) (xy 25.276608 -201.277986) (xy 25.322269 -201.300717) (xy 25.343358 -201.315066)
			(xy 25.349879 -201.319375) (xy 25.364757 -201.324147) (xy 25.372568 -201.324464) (xy 25.888696 -201.324464)
			(xy 25.893952 -201.324994) (xy 25.901393 -201.332418) (xy 25.901904 -201.337672) (xy 25.901904 -201.33818)
			(xy 25.901904 -201.832464) (xy 28.502356 -201.832464) (xy 28.502356 -201.337926) (xy 28.502842 -201.332621)
			(xy 28.51027 -201.325048) (xy 28.515564 -201.324464) (xy 29.031692 -201.324464) (xy 29.039502 -201.324153)
			(xy 29.054374 -201.319366) (xy 29.060902 -201.315066) (xy 29.081991 -201.300717) (xy 29.127652 -201.277986)
			(xy 29.176258 -201.262527) (xy 29.226661 -201.254704) (xy 29.277667 -201.254704) (xy 29.32807 -201.262527)
			(xy 29.376676 -201.277986) (xy 29.422337 -201.300717) (xy 29.443426 -201.315066) (xy 29.449955 -201.319363)
			(xy 29.464827 -201.324143) (xy 29.472636 -201.324464) (xy 29.988764 -201.324464) (xy 29.994085 -201.324848)
			(xy 30.001626 -201.332353) (xy 30.001972 -201.337672) (xy 30.001972 -201.33818) (xy 30.001972 -201.832464)
			(xy 31.946088 -201.832464) (xy 31.946088 -201.337926) (xy 31.946546 -201.332614) (xy 31.953993 -201.325038)
			(xy 31.959296 -201.324464) (xy 32.475424 -201.324464) (xy 32.483236 -201.324167) (xy 32.498107 -201.31937)
			(xy 32.504634 -201.315066) (xy 32.525723 -201.300717) (xy 32.571384 -201.277986) (xy 32.61999 -201.262527)
			(xy 32.670393 -201.254704) (xy 32.721399 -201.254704) (xy 32.771802 -201.262527) (xy 32.820408 -201.277986)
			(xy 32.866069 -201.300717) (xy 32.887158 -201.315066) (xy 32.893679 -201.319375) (xy 32.908557 -201.324147)
			(xy 32.916368 -201.324464) (xy 33.432496 -201.324464) (xy 33.437752 -201.324994) (xy 33.445193 -201.332418)
			(xy 33.445704 -201.337672) (xy 33.445704 -201.33818) (xy 33.445704 -201.832464) (xy 36.046156 -201.832464)
			(xy 36.046156 -201.337926) (xy 36.046642 -201.332621) (xy 36.05407 -201.325048) (xy 36.059364 -201.324464)
			(xy 36.575492 -201.324464) (xy 36.583302 -201.324153) (xy 36.598174 -201.319366) (xy 36.604702 -201.315066)
			(xy 36.625791 -201.300717) (xy 36.671452 -201.277986) (xy 36.720058 -201.262527) (xy 36.770461 -201.254704)
			(xy 36.821467 -201.254704) (xy 36.87187 -201.262527) (xy 36.920476 -201.277986) (xy 36.966137 -201.300717)
			(xy 36.987226 -201.315066) (xy 36.993755 -201.319363) (xy 37.008627 -201.324143) (xy 37.016436 -201.324464)
			(xy 37.532564 -201.324464) (xy 37.537885 -201.324848) (xy 37.545426 -201.332353) (xy 37.545772 -201.337672)
			(xy 37.545772 -201.33818) (xy 37.545772 -201.832464) (xy 39.489888 -201.832464) (xy 39.489888 -201.337926)
			(xy 39.490463 -201.332577) (xy 39.498004 -201.324993) (xy 39.50335 -201.324464) (xy 40.019478 -201.324464)
			(xy 40.027288 -201.324147) (xy 40.042159 -201.319364) (xy 40.048688 -201.315066) (xy 40.069777 -201.300717)
			(xy 40.115438 -201.277986) (xy 40.164044 -201.262527) (xy 40.214447 -201.254704) (xy 40.265453 -201.254704)
			(xy 40.315856 -201.262527) (xy 40.364462 -201.277986) (xy 40.410123 -201.300717) (xy 40.431212 -201.315066)
			(xy 40.437744 -201.319357) (xy 40.452613 -201.324141) (xy 40.460422 -201.324464) (xy 40.97655 -201.324464)
			(xy 40.981926 -201.32492) (xy 40.98951 -201.332547) (xy 40.990012 -201.337926) (xy 40.990012 -201.832464)
			(xy 43.589956 -201.832464) (xy 43.589956 -201.337926) (xy 43.590298 -201.33249) (xy 43.597982 -201.324802)
			(xy 43.603418 -201.324464) (xy 44.119546 -201.324464) (xy 44.127355 -201.324133) (xy 44.142226 -201.31936)
			(xy 44.148756 -201.315066) (xy 44.169845 -201.300717) (xy 44.215506 -201.277986) (xy 44.264112 -201.262527)
			(xy 44.314515 -201.254704) (xy 44.365521 -201.254704) (xy 44.415924 -201.262527) (xy 44.46453 -201.277986)
			(xy 44.510191 -201.300717) (xy 44.53128 -201.315066) (xy 44.537819 -201.319345) (xy 44.552683 -201.324136)
			(xy 44.56049 -201.324464) (xy 45.076618 -201.324464) (xy 45.082062 -201.32477) (xy 45.089748 -201.332481)
			(xy 45.09008 -201.337926) (xy 45.09008 -201.832464) (xy 47.034196 -201.832464) (xy 47.034196 -201.337926)
			(xy 47.034735 -201.332635) (xy 47.042126 -201.325065) (xy 47.047404 -201.324464) (xy 47.563532 -201.324464)
			(xy 47.57134 -201.324127) (xy 47.586212 -201.319358) (xy 47.592742 -201.315066) (xy 47.613831 -201.300717)
			(xy 47.659492 -201.277986) (xy 47.708098 -201.262527) (xy 47.758501 -201.254704) (xy 47.809507 -201.254704)
			(xy 47.85991 -201.262527) (xy 47.908516 -201.277986) (xy 47.954177 -201.300717) (xy 47.975266 -201.315066)
			(xy 47.981808 -201.31934) (xy 47.99667 -201.324134) (xy 48.004476 -201.324464) (xy 48.520604 -201.324464)
			(xy 48.525861 -201.324989) (xy 48.533301 -201.332416) (xy 48.533812 -201.337672) (xy 48.533812 -201.33818)
			(xy 48.533812 -201.832464) (xy 51.134264 -201.832464) (xy 51.134264 -201.337926) (xy 51.134743 -201.332619)
			(xy 51.142175 -201.325045) (xy 51.147472 -201.324464) (xy 51.6636 -201.324464) (xy 51.671411 -201.324157)
			(xy 51.686282 -201.319367) (xy 51.69281 -201.315066) (xy 51.713899 -201.300717) (xy 51.75956 -201.277986)
			(xy 51.808166 -201.262527) (xy 51.858569 -201.254704) (xy 51.909575 -201.254704) (xy 51.959978 -201.262527)
			(xy 52.008584 -201.277986) (xy 52.054245 -201.300717) (xy 52.075334 -201.315066) (xy 52.081861 -201.319366)
			(xy 52.096734 -201.324144) (xy 52.104544 -201.324464) (xy 52.620672 -201.324464) (xy 52.625925 -201.32501)
			(xy 52.633367 -201.332422) (xy 52.63388 -201.337672) (xy 52.63388 -201.33818) (xy 52.63388 -201.832464)
			(xy 54.577996 -201.832464) (xy 54.577996 -201.337926) (xy 54.578563 -201.332575) (xy 54.58611 -201.324991)
			(xy 54.591458 -201.324464) (xy 56.064658 -201.324464) (xy 56.070094 -201.32481) (xy 56.077783 -201.332491)
			(xy 56.07812 -201.337926) (xy 56.07812 -201.832464) (xy 58.678064 -201.832464) (xy 58.678064 -201.337926)
			(xy 58.678399 -201.332488) (xy 58.686088 -201.324799) (xy 58.691526 -201.324464) (xy 60.164726 -201.324464)
			(xy 60.170099 -201.324936) (xy 60.177685 -201.332551) (xy 60.178188 -201.337926) (xy 60.178188 -201.832464)
			(xy 163.678108 -201.832464) (xy 163.678108 -201.337926) (xy 163.678637 -201.332632) (xy 163.686035 -201.325062)
			(xy 163.691316 -201.324464) (xy 165.164516 -201.324464) (xy 165.169774 -201.324981) (xy 165.177214 -201.332414)
			(xy 165.177724 -201.337672) (xy 165.177724 -201.33818) (xy 165.177724 -201.832464) (xy 167.778176 -201.832464)
			(xy 167.778176 -201.337926) (xy 167.778645 -201.332617) (xy 167.786084 -201.325042) (xy 167.791384 -201.324464)
			(xy 169.264584 -201.324464) (xy 169.269838 -201.325002) (xy 169.27728 -201.33242) (xy 169.277792 -201.337672)
			(xy 169.277792 -201.832464) (xy 171.221908 -201.832464) (xy 171.221908 -201.337926) (xy 171.222465 -201.332572)
			(xy 171.230019 -201.324987) (xy 171.23537 -201.324464) (xy 171.751498 -201.324464) (xy 171.759309 -201.324156)
			(xy 171.77418 -201.319367) (xy 171.780708 -201.315066) (xy 171.801797 -201.300717) (xy 171.847458 -201.277986)
			(xy 171.896064 -201.262527) (xy 171.946467 -201.254704) (xy 171.997473 -201.254704) (xy 172.047876 -201.262527)
			(xy 172.096482 -201.277986) (xy 172.142143 -201.300717) (xy 172.163232 -201.315066) (xy 172.169759 -201.319365)
			(xy 172.184632 -201.324144) (xy 172.192442 -201.324464) (xy 172.70857 -201.324464) (xy 172.714007 -201.324802)
			(xy 172.721696 -201.332489) (xy 172.722032 -201.337926) (xy 172.722032 -201.832464) (xy 175.321976 -201.832464)
			(xy 175.321976 -201.337926) (xy 175.3223 -201.332485) (xy 175.329997 -201.324796) (xy 175.335438 -201.324464)
			(xy 175.851566 -201.324464) (xy 175.859375 -201.324142) (xy 175.874247 -201.319362) (xy 175.880776 -201.315066)
			(xy 175.901865 -201.300717) (xy 175.947526 -201.277986) (xy 175.996132 -201.262527) (xy 176.046535 -201.254704)
			(xy 176.097541 -201.254704) (xy 176.147944 -201.262527) (xy 176.19655 -201.277986) (xy 176.242211 -201.300717)
			(xy 176.2633 -201.315066) (xy 176.269834 -201.319353) (xy 176.284702 -201.324139) (xy 176.29251 -201.324464)
			(xy 176.808638 -201.324464) (xy 176.814013 -201.324928) (xy 176.821598 -201.332549) (xy 176.8221 -201.337926)
			(xy 176.8221 -201.832464) (xy 178.766216 -201.832464) (xy 178.766216 -201.337926) (xy 178.766738 -201.332631)
			(xy 178.774141 -201.325059) (xy 178.779424 -201.324464) (xy 179.295552 -201.324464) (xy 179.303361 -201.324136)
			(xy 179.318233 -201.31936) (xy 179.324762 -201.315066) (xy 179.345851 -201.300717) (xy 179.391512 -201.277986)
			(xy 179.440118 -201.262527) (xy 179.490521 -201.254704) (xy 179.541527 -201.254704) (xy 179.59193 -201.262527)
			(xy 179.640536 -201.277986) (xy 179.686197 -201.300717) (xy 179.707286 -201.315066) (xy 179.713823 -201.319347)
			(xy 179.728689 -201.324137) (xy 179.736496 -201.324464) (xy 180.252624 -201.324464) (xy 180.257883 -201.324976)
			(xy 180.265322 -201.332413) (xy 180.265832 -201.337672) (xy 180.265832 -201.33818) (xy 180.265832 -201.832464)
			(xy 182.866284 -201.832464) (xy 182.866284 -201.337926) (xy 182.866746 -201.332615) (xy 182.87419 -201.32504)
			(xy 182.879492 -201.324464) (xy 183.39562 -201.324464) (xy 183.403432 -201.324165) (xy 183.418303 -201.31937)
			(xy 183.42483 -201.315066) (xy 183.445919 -201.300717) (xy 183.49158 -201.277986) (xy 183.540186 -201.262527)
			(xy 183.590589 -201.254704) (xy 183.641595 -201.254704) (xy 183.691998 -201.262527) (xy 183.740604 -201.277986)
			(xy 183.786265 -201.300717) (xy 183.807354 -201.315066) (xy 183.813876 -201.319373) (xy 183.828753 -201.324147)
			(xy 183.836564 -201.324464) (xy 184.352692 -201.324464) (xy 184.357947 -201.324997) (xy 184.365389 -201.332418)
			(xy 184.3659 -201.337672) (xy 184.3659 -201.33818) (xy 184.3659 -201.832464) (xy 186.310016 -201.832464)
			(xy 186.310016 -201.337926) (xy 186.310394 -201.3325) (xy 186.318053 -201.324814) (xy 186.323478 -201.324464)
			(xy 186.839606 -201.324464) (xy 186.847417 -201.324159) (xy 186.862289 -201.319368) (xy 186.868816 -201.315066)
			(xy 186.889905 -201.300717) (xy 186.935566 -201.277986) (xy 186.984172 -201.262527) (xy 187.034575 -201.254704)
			(xy 187.085581 -201.254704) (xy 187.135984 -201.262527) (xy 187.18459 -201.277986) (xy 187.230251 -201.300717)
			(xy 187.25134 -201.315066) (xy 187.257865 -201.319368) (xy 187.27274 -201.324145) (xy 187.28055 -201.324464)
			(xy 187.796678 -201.324464) (xy 187.802116 -201.324797) (xy 187.809805 -201.332488) (xy 187.81014 -201.337926)
			(xy 187.81014 -201.832464) (xy 190.410084 -201.832464) (xy 190.410084 -201.337926) (xy 190.410401 -201.332483)
			(xy 190.418103 -201.324793) (xy 190.423546 -201.324464) (xy 190.939674 -201.324464) (xy 190.947484 -201.324145)
			(xy 190.962355 -201.319363) (xy 190.968884 -201.315066) (xy 190.989973 -201.300717) (xy 191.035634 -201.277986)
			(xy 191.08424 -201.262527) (xy 191.134643 -201.254704) (xy 191.185649 -201.254704) (xy 191.236052 -201.262527)
			(xy 191.284658 -201.277986) (xy 191.330319 -201.300717) (xy 191.351408 -201.315066) (xy 191.357941 -201.319356)
			(xy 191.37281 -201.32414) (xy 191.380618 -201.324464) (xy 191.896746 -201.324464) (xy 191.902122 -201.324923)
			(xy 191.909706 -201.332548) (xy 191.910208 -201.337926) (xy 191.910208 -201.832464) (xy 193.854324 -201.832464)
			(xy 193.854324 -201.337926) (xy 193.854839 -201.332629) (xy 193.862246 -201.325057) (xy 193.867532 -201.324464)
			(xy 194.38366 -201.324464) (xy 194.391469 -201.324139) (xy 194.406341 -201.319361) (xy 194.41287 -201.315066)
			(xy 194.433959 -201.300717) (xy 194.47962 -201.277986) (xy 194.528226 -201.262527) (xy 194.578629 -201.254704)
			(xy 194.629635 -201.254704) (xy 194.680038 -201.262527) (xy 194.728644 -201.277986) (xy 194.774305 -201.300717)
			(xy 194.795394 -201.315066) (xy 194.80193 -201.31935) (xy 194.816796 -201.324138) (xy 194.824604 -201.324464)
			(xy 195.340732 -201.324464) (xy 195.345992 -201.324971) (xy 195.353431 -201.332412) (xy 195.35394 -201.337672)
			(xy 195.35394 -201.33818) (xy 195.35394 -201.832464) (xy 197.954392 -201.832464) (xy 197.954392 -201.337926)
			(xy 197.954935 -201.332636) (xy 197.962323 -201.325066) (xy 197.9676 -201.324464) (xy 198.483728 -201.324464)
			(xy 198.49154 -201.324168) (xy 198.506411 -201.319371) (xy 198.512938 -201.315066) (xy 198.534027 -201.300717)
			(xy 198.579688 -201.277986) (xy 198.628294 -201.262527) (xy 198.678697 -201.254704) (xy 198.729703 -201.254704)
			(xy 198.780106 -201.262527) (xy 198.828712 -201.277986) (xy 198.874373 -201.300717) (xy 198.895462 -201.315066)
			(xy 198.902005 -201.319338) (xy 198.916866 -201.324133) (xy 198.924672 -201.324464) (xy 199.4408 -201.324464)
			(xy 199.446056 -201.324992) (xy 199.453497 -201.332417) (xy 199.454008 -201.337672) (xy 199.454008 -201.33818)
			(xy 199.454008 -201.832464) (xy 201.398124 -201.832464) (xy 201.398124 -201.337926) (xy 201.398639 -201.332629)
			(xy 201.406046 -201.325057) (xy 201.411332 -201.324464) (xy 201.92746 -201.324464) (xy 201.935269 -201.324139)
			(xy 201.950141 -201.319361) (xy 201.95667 -201.315066) (xy 201.977759 -201.300717) (xy 202.02342 -201.277986)
			(xy 202.072026 -201.262527) (xy 202.122429 -201.254704) (xy 202.173435 -201.254704) (xy 202.223838 -201.262527)
			(xy 202.272444 -201.277986) (xy 202.318105 -201.300717) (xy 202.339194 -201.315066) (xy 202.34573 -201.31935)
			(xy 202.360596 -201.324138) (xy 202.368404 -201.324464) (xy 202.884532 -201.324464) (xy 202.889792 -201.324971)
			(xy 202.897231 -201.332412) (xy 202.89774 -201.337672) (xy 202.89774 -201.33818) (xy 202.89774 -201.832464)
			(xy 205.498192 -201.832464) (xy 205.498192 -201.337926) (xy 205.498735 -201.332636) (xy 205.506123 -201.325066)
			(xy 205.5114 -201.324464) (xy 206.027528 -201.324464) (xy 206.03534 -201.324168) (xy 206.050211 -201.319371)
			(xy 206.056738 -201.315066) (xy 206.077827 -201.300717) (xy 206.123488 -201.277986) (xy 206.172094 -201.262527)
			(xy 206.222497 -201.254704) (xy 206.273503 -201.254704) (xy 206.323906 -201.262527) (xy 206.372512 -201.277986)
			(xy 206.418173 -201.300717) (xy 206.439262 -201.315066) (xy 206.445805 -201.319338) (xy 206.460666 -201.324133)
			(xy 206.468472 -201.324464) (xy 206.9846 -201.324464) (xy 206.989856 -201.324992) (xy 206.997297 -201.332417)
			(xy 206.997808 -201.337672) (xy 206.997808 -201.33818) (xy 206.997808 -201.832464) (xy 206.997449 -201.837792)
			(xy 206.989927 -201.845335) (xy 206.9846 -201.845672) (xy 206.468726 -201.845672) (xy 206.460849 -201.845932)
			(xy 206.445845 -201.850734) (xy 206.439262 -201.85507) (xy 206.418187 -201.869466) (xy 206.372541 -201.892292)
			(xy 206.323934 -201.907849) (xy 206.273517 -201.915767) (xy 206.248 -201.916284) (xy 206.222479 -201.915814)
			(xy 206.172051 -201.907914) (xy 206.123439 -201.892348) (xy 206.077802 -201.869488) (xy 206.056738 -201.85507)
			(xy 206.050136 -201.850774) (xy 206.035144 -201.845974) (xy 206.027274 -201.845672) (xy 205.5114 -201.845672)
			(xy 205.506059 -201.84537) (xy 205.498516 -201.837806) (xy 205.498192 -201.832464) (xy 202.89774 -201.832464)
			(xy 202.897352 -201.837784) (xy 202.88985 -201.845325) (xy 202.884532 -201.845672) (xy 202.368658 -201.845672)
			(xy 202.360782 -201.845946) (xy 202.345778 -201.850739) (xy 202.339194 -201.85507) (xy 202.31811 -201.869452)
			(xy 202.272467 -201.892282) (xy 202.223863 -201.907842) (xy 202.173448 -201.915765) (xy 202.147932 -201.916284)
			(xy 202.122412 -201.915798) (xy 202.071984 -201.907903) (xy 202.023373 -201.892342) (xy 201.977735 -201.869486)
			(xy 201.95667 -201.85507) (xy 201.950083 -201.850747) (xy 201.93508 -201.845964) (xy 201.927206 -201.845672)
			(xy 201.411332 -201.845672) (xy 201.405995 -201.845348) (xy 201.39845 -201.837801) (xy 201.398124 -201.832464)
			(xy 199.454008 -201.832464) (xy 199.453649 -201.837792) (xy 199.446127 -201.845335) (xy 199.4408 -201.845672)
			(xy 198.924926 -201.845672) (xy 198.917049 -201.845932) (xy 198.902045 -201.850734) (xy 198.895462 -201.85507)
			(xy 198.874387 -201.869466) (xy 198.828741 -201.892292) (xy 198.780134 -201.907849) (xy 198.729717 -201.915767)
			(xy 198.7042 -201.916284) (xy 198.678679 -201.915814) (xy 198.628251 -201.907914) (xy 198.579639 -201.892348)
			(xy 198.534002 -201.869488) (xy 198.512938 -201.85507) (xy 198.506336 -201.850774) (xy 198.491344 -201.845974)
			(xy 198.483474 -201.845672) (xy 197.9676 -201.845672) (xy 197.962259 -201.84537) (xy 197.954716 -201.837806)
			(xy 197.954392 -201.832464) (xy 195.35394 -201.832464) (xy 195.353552 -201.837784) (xy 195.34605 -201.845325)
			(xy 195.340732 -201.845672) (xy 194.824858 -201.845672) (xy 194.816982 -201.845946) (xy 194.801978 -201.850739)
			(xy 194.795394 -201.85507) (xy 194.77431 -201.869452) (xy 194.728667 -201.892282) (xy 194.680063 -201.907842)
			(xy 194.629648 -201.915765) (xy 194.604132 -201.916284) (xy 194.578612 -201.915798) (xy 194.528184 -201.907903)
			(xy 194.479573 -201.892342) (xy 194.433935 -201.869486) (xy 194.41287 -201.85507) (xy 194.406283 -201.850747)
			(xy 194.39128 -201.845964) (xy 194.383406 -201.845672) (xy 193.867532 -201.845672) (xy 193.862195 -201.845348)
			(xy 193.85465 -201.837801) (xy 193.854324 -201.832464) (xy 191.910208 -201.832464) (xy 191.909849 -201.837792)
			(xy 191.902327 -201.845335) (xy 191.897 -201.845672) (xy 191.896492 -201.845672) (xy 191.380872 -201.845672)
			(xy 191.372997 -201.845952) (xy 191.357993 -201.85074) (xy 191.351408 -201.85507) (xy 191.330348 -201.869489)
			(xy 191.284697 -201.89231) (xy 191.236085 -201.90786) (xy 191.185664 -201.915771) (xy 191.160146 -201.916284)
			(xy 191.134626 -201.915791) (xy 191.084199 -201.907898) (xy 191.035587 -201.892339) (xy 190.989949 -201.869485)
			(xy 190.968884 -201.85507) (xy 190.962294 -201.850753) (xy 190.947293 -201.845966) (xy 190.93942 -201.845672)
			(xy 190.423546 -201.845672) (xy 190.41825 -201.845148) (xy 190.410677 -201.837748) (xy 190.410084 -201.832464)
			(xy 187.81014 -201.832464) (xy 187.809752 -201.837784) (xy 187.80225 -201.845325) (xy 187.796932 -201.845672)
			(xy 187.796424 -201.845672) (xy 187.280804 -201.845672) (xy 187.27293 -201.845965) (xy 187.257926 -201.850745)
			(xy 187.25134 -201.85507) (xy 187.230271 -201.869475) (xy 187.184623 -201.8923) (xy 187.136014 -201.907854)
			(xy 187.085595 -201.915769) (xy 187.060078 -201.916284) (xy 187.034559 -201.915775) (xy 186.984132 -201.907887)
			(xy 186.935521 -201.892333) (xy 186.889881 -201.869483) (xy 186.868816 -201.85507) (xy 186.862219 -201.850765)
			(xy 186.847223 -201.845971) (xy 186.839352 -201.845672) (xy 186.323478 -201.845672) (xy 186.318174 -201.845193)
			(xy 186.310605 -201.837758) (xy 186.310016 -201.832464) (xy 184.3659 -201.832464) (xy 184.365548 -201.837793)
			(xy 184.358021 -201.845337) (xy 184.352692 -201.845672) (xy 183.836818 -201.845672) (xy 183.828944 -201.845971)
			(xy 183.81394 -201.850746) (xy 183.807354 -201.85507) (xy 183.786281 -201.869469) (xy 183.740635 -201.892295)
			(xy 183.692027 -201.907851) (xy 183.641609 -201.915768) (xy 183.616092 -201.916284) (xy 183.590573 -201.915768)
			(xy 183.540147 -201.907882) (xy 183.491535 -201.89233) (xy 183.445896 -201.869482) (xy 183.42483 -201.85507)
			(xy 183.418229 -201.85077) (xy 183.403237 -201.845973) (xy 183.395366 -201.845672) (xy 182.879492 -201.845672)
			(xy 182.87415 -201.845375) (xy 182.866607 -201.837807) (xy 182.866284 -201.832464) (xy 180.265832 -201.832464)
			(xy 180.265451 -201.837786) (xy 180.257944 -201.845327) (xy 180.252624 -201.845672) (xy 179.73675 -201.845672)
			(xy 179.728874 -201.845942) (xy 179.71387 -201.850738) (xy 179.707286 -201.85507) (xy 179.686205 -201.869455)
			(xy 179.640561 -201.892284) (xy 179.591956 -201.907844) (xy 179.54154 -201.915765) (xy 179.516024 -201.916284)
			(xy 179.490503 -201.915802) (xy 179.440076 -201.907906) (xy 179.391464 -201.892344) (xy 179.345826 -201.869486)
			(xy 179.324762 -201.85507) (xy 179.318177 -201.850744) (xy 179.303172 -201.845963) (xy 179.295298 -201.845672)
			(xy 178.779424 -201.845672) (xy 178.774086 -201.845353) (xy 178.766542 -201.837802) (xy 178.766216 -201.832464)
			(xy 176.8221 -201.832464) (xy 176.821748 -201.837793) (xy 176.814221 -201.845337) (xy 176.808892 -201.845672)
			(xy 176.808384 -201.845672) (xy 176.292764 -201.845672) (xy 176.284888 -201.845948) (xy 176.269884 -201.850739)
			(xy 176.2633 -201.85507) (xy 176.242215 -201.869449) (xy 176.196572 -201.89228) (xy 176.147969 -201.907841)
			(xy 176.097554 -201.915764) (xy 176.072038 -201.916284) (xy 176.046518 -201.915795) (xy 175.996091 -201.907901)
			(xy 175.947479 -201.892341) (xy 175.901841 -201.869485) (xy 175.880776 -201.85507) (xy 175.874188 -201.85075)
			(xy 175.859185 -201.845965) (xy 175.851312 -201.845672) (xy 175.335438 -201.845672) (xy 175.330141 -201.845153)
			(xy 175.322569 -201.837749) (xy 175.321976 -201.832464) (xy 172.722032 -201.832464) (xy 172.721651 -201.837786)
			(xy 172.714144 -201.845327) (xy 172.708824 -201.845672) (xy 172.708316 -201.845672) (xy 172.192696 -201.845672)
			(xy 172.184822 -201.845962) (xy 172.169817 -201.850744) (xy 172.163232 -201.85507) (xy 172.142166 -201.869478)
			(xy 172.096517 -201.892302) (xy 172.047907 -201.907855) (xy 171.997488 -201.915769) (xy 171.97197 -201.916284)
			(xy 171.94645 -201.915779) (xy 171.896024 -201.90789) (xy 171.847412 -201.892334) (xy 171.801773 -201.869483)
			(xy 171.780708 -201.85507) (xy 171.774112 -201.850762) (xy 171.759116 -201.84597) (xy 171.751244 -201.845672)
			(xy 171.23537 -201.845672) (xy 171.230065 -201.845198) (xy 171.222496 -201.83776) (xy 171.221908 -201.832464)
			(xy 169.277792 -201.832464) (xy 169.277447 -201.837795) (xy 169.269915 -201.845339) (xy 169.264584 -201.845672)
			(xy 167.791384 -201.845672) (xy 167.786041 -201.845381) (xy 167.778498 -201.837809) (xy 167.778176 -201.832464)
			(xy 165.177724 -201.832464) (xy 165.177351 -201.837788) (xy 165.169838 -201.84533) (xy 165.164516 -201.845672)
			(xy 163.691316 -201.845672) (xy 163.685977 -201.845359) (xy 163.678433 -201.837803) (xy 163.678108 -201.832464)
			(xy 60.178188 -201.832464) (xy 60.177847 -201.837796) (xy 60.170312 -201.845341) (xy 60.16498 -201.845672)
			(xy 60.164472 -201.845672) (xy 58.691526 -201.845672) (xy 58.686228 -201.845161) (xy 58.678656 -201.837751)
			(xy 58.678064 -201.832464) (xy 56.07812 -201.832464) (xy 56.07775 -201.837789) (xy 56.070235 -201.845331)
			(xy 56.064912 -201.845672) (xy 54.591458 -201.845672) (xy 54.586151 -201.845206) (xy 54.578583 -201.837762)
			(xy 54.577996 -201.832464) (xy 52.63388 -201.832464) (xy 52.633546 -201.837798) (xy 52.626006 -201.845343)
			(xy 52.620672 -201.845672) (xy 52.104798 -201.845672) (xy 52.096924 -201.845963) (xy 52.081919 -201.850744)
			(xy 52.075334 -201.85507) (xy 52.054267 -201.869478) (xy 52.008618 -201.892302) (xy 51.960009 -201.907855)
			(xy 51.90959 -201.915769) (xy 51.884072 -201.916284) (xy 51.858552 -201.915778) (xy 51.808126 -201.907889)
			(xy 51.759514 -201.892334) (xy 51.713875 -201.869483) (xy 51.69281 -201.85507) (xy 51.686214 -201.850763)
			(xy 51.671218 -201.84597) (xy 51.663346 -201.845672) (xy 51.147472 -201.845672) (xy 51.142127 -201.845388)
			(xy 51.134586 -201.83781) (xy 51.134264 -201.832464) (xy 48.533812 -201.832464) (xy 48.533449 -201.837791)
			(xy 48.525929 -201.845333) (xy 48.520604 -201.845672) (xy 48.00473 -201.845672) (xy 47.996853 -201.845934)
			(xy 47.981849 -201.850735) (xy 47.975266 -201.85507) (xy 47.95419 -201.869464) (xy 47.908544 -201.892291)
			(xy 47.859938 -201.907848) (xy 47.809521 -201.915767) (xy 47.784004 -201.916284) (xy 47.758483 -201.915812)
			(xy 47.708055 -201.907913) (xy 47.659444 -201.892348) (xy 47.613806 -201.869488) (xy 47.592742 -201.85507)
			(xy 47.586161 -201.850736) (xy 47.571153 -201.84596) (xy 47.563278 -201.845672) (xy 47.047404 -201.845672)
			(xy 47.042064 -201.845367) (xy 47.03452 -201.837805) (xy 47.034196 -201.832464) (xy 45.09008 -201.832464)
			(xy 45.089746 -201.837798) (xy 45.082206 -201.845343) (xy 45.076872 -201.845672) (xy 45.076364 -201.845672)
			(xy 44.560744 -201.845672) (xy 44.552868 -201.84594) (xy 44.537864 -201.850737) (xy 44.53128 -201.85507)
			(xy 44.5102 -201.869458) (xy 44.464556 -201.892286) (xy 44.415951 -201.907845) (xy 44.365534 -201.915766)
			(xy 44.340018 -201.916284) (xy 44.314497 -201.915805) (xy 44.26407 -201.907908) (xy 44.215458 -201.892345)
			(xy 44.16982 -201.869487) (xy 44.148756 -201.85507) (xy 44.142172 -201.850742) (xy 44.127166 -201.845962)
			(xy 44.119292 -201.845672) (xy 43.603418 -201.845672) (xy 43.598119 -201.845166) (xy 43.590547 -201.837752)
			(xy 43.589956 -201.832464) (xy 40.990012 -201.832464) (xy 40.989649 -201.837791) (xy 40.982129 -201.845333)
			(xy 40.976804 -201.845672) (xy 40.976296 -201.845672) (xy 40.460676 -201.845672) (xy 40.452801 -201.845953)
			(xy 40.437797 -201.850741) (xy 40.431212 -201.85507) (xy 40.410151 -201.869487) (xy 40.3645 -201.892309)
			(xy 40.315889 -201.90786) (xy 40.265468 -201.915771) (xy 40.23995 -201.916284) (xy 40.21443 -201.915789)
			(xy 40.164003 -201.907897) (xy 40.115391 -201.892338) (xy 40.069753 -201.869485) (xy 40.048688 -201.85507)
			(xy 40.042097 -201.850754) (xy 40.027097 -201.845967) (xy 40.019224 -201.845672) (xy 39.50335 -201.845672)
			(xy 39.498055 -201.845145) (xy 39.490482 -201.837747) (xy 39.489888 -201.832464) (xy 37.545772 -201.832464)
			(xy 37.545446 -201.8378) (xy 37.5379 -201.845346) (xy 37.532564 -201.845672) (xy 37.01669 -201.845672)
			(xy 37.008815 -201.845959) (xy 36.993811 -201.850743) (xy 36.987226 -201.85507) (xy 36.966161 -201.869481)
			(xy 36.920512 -201.892304) (xy 36.871902 -201.907857) (xy 36.821482 -201.91577) (xy 36.795964 -201.916284)
			(xy 36.770444 -201.915782) (xy 36.720018 -201.907892) (xy 36.671406 -201.892335) (xy 36.625767 -201.869484)
			(xy 36.604702 -201.85507) (xy 36.598108 -201.85076) (xy 36.58311 -201.845969) (xy 36.575238 -201.845672)
			(xy 36.059364 -201.845672) (xy 36.054088 -201.845225) (xy 36.046646 -201.837742) (xy 36.046156 -201.832464)
			(xy 33.445704 -201.832464) (xy 33.445349 -201.837792) (xy 33.437824 -201.845336) (xy 33.432496 -201.845672)
			(xy 32.916622 -201.845672) (xy 32.908749 -201.845973) (xy 32.893744 -201.850747) (xy 32.887158 -201.85507)
			(xy 32.866084 -201.869467) (xy 32.820438 -201.892294) (xy 32.771831 -201.90785) (xy 32.721413 -201.915767)
			(xy 32.695896 -201.916284) (xy 32.670375 -201.915816) (xy 32.619947 -201.907916) (xy 32.571335 -201.892349)
			(xy 32.525698 -201.869488) (xy 32.504634 -201.85507) (xy 32.498033 -201.850772) (xy 32.48304 -201.845973)
			(xy 32.47517 -201.845672) (xy 31.959296 -201.845672) (xy 31.953954 -201.845372) (xy 31.946412 -201.837807)
			(xy 31.946088 -201.832464) (xy 30.001972 -201.832464) (xy 30.001646 -201.8378) (xy 29.9941 -201.845346)
			(xy 29.988764 -201.845672) (xy 29.47289 -201.845672) (xy 29.465015 -201.845959) (xy 29.450011 -201.850743)
			(xy 29.443426 -201.85507) (xy 29.422361 -201.869481) (xy 29.376712 -201.892304) (xy 29.328102 -201.907857)
			(xy 29.277682 -201.91577) (xy 29.252164 -201.916284) (xy 29.226644 -201.915782) (xy 29.176218 -201.907892)
			(xy 29.127606 -201.892335) (xy 29.081967 -201.869484) (xy 29.060902 -201.85507) (xy 29.054308 -201.85076)
			(xy 29.03931 -201.845969) (xy 29.031438 -201.845672) (xy 28.515564 -201.845672) (xy 28.510288 -201.845225)
			(xy 28.502846 -201.837742) (xy 28.502356 -201.832464) (xy 25.901904 -201.832464) (xy 25.901549 -201.837792)
			(xy 25.894024 -201.845336) (xy 25.888696 -201.845672) (xy 25.372822 -201.845672) (xy 25.364949 -201.845973)
			(xy 25.349944 -201.850747) (xy 25.343358 -201.85507) (xy 25.322284 -201.869467) (xy 25.276638 -201.892294)
			(xy 25.228031 -201.90785) (xy 25.177613 -201.915767) (xy 25.152096 -201.916284) (xy 25.126575 -201.915816)
			(xy 25.076147 -201.907916) (xy 25.027535 -201.892349) (xy 24.981898 -201.869488) (xy 24.960834 -201.85507)
			(xy 24.954233 -201.850772) (xy 24.93924 -201.845973) (xy 24.93137 -201.845672) (xy 24.415496 -201.845672)
			(xy 24.410154 -201.845372) (xy 24.402612 -201.837807) (xy 24.402288 -201.832464) (xy 22.458172 -201.832464)
			(xy 22.457846 -201.8378) (xy 22.4503 -201.845346) (xy 22.444964 -201.845672) (xy 22.444456 -201.845672)
			(xy 21.928836 -201.845672) (xy 21.920959 -201.845936) (xy 21.905955 -201.850736) (xy 21.899372 -201.85507)
			(xy 21.878294 -201.869461) (xy 21.832649 -201.892289) (xy 21.784043 -201.907847) (xy 21.733627 -201.915766)
			(xy 21.70811 -201.916284) (xy 21.682589 -201.915809) (xy 21.632162 -201.907911) (xy 21.58355 -201.892346)
			(xy 21.537912 -201.869487) (xy 21.516848 -201.85507) (xy 21.510266 -201.850739) (xy 21.495259 -201.845961)
			(xy 21.487384 -201.845672) (xy 20.97151 -201.845672) (xy 20.96621 -201.845172) (xy 20.958639 -201.837753)
			(xy 20.958048 -201.832464) (xy 18.358104 -201.832464) (xy 18.357749 -201.837792) (xy 18.350224 -201.845336)
			(xy 18.344896 -201.845672) (xy 18.344388 -201.845672) (xy 17.828768 -201.845672) (xy 17.820893 -201.84595)
			(xy 17.805888 -201.85074) (xy 17.799304 -201.85507) (xy 17.778218 -201.869447) (xy 17.732576 -201.892278)
			(xy 17.683973 -201.90784) (xy 17.633558 -201.915764) (xy 17.608042 -201.916284) (xy 17.582522 -201.915793)
			(xy 17.532095 -201.9079) (xy 17.483483 -201.89234) (xy 17.437845 -201.869485) (xy 17.41678 -201.85507)
			(xy 17.410191 -201.850751) (xy 17.395189 -201.845965) (xy 17.387316 -201.845672) (xy 16.871442 -201.845672)
			(xy 16.866146 -201.84515) (xy 16.858573 -201.837748) (xy 16.85798 -201.832464) (xy 2.509012 -201.832464)
			(xy 2.509012 -202.682348) (xy 16.85798 -202.682348) (xy 16.85798 -202.18781) (xy 16.85829 -202.182366)
			(xy 16.865997 -202.174677) (xy 16.871442 -202.174348) (xy 17.38757 -202.174348) (xy 17.39538 -202.17403)
			(xy 17.410252 -202.169248) (xy 17.41678 -202.16495) (xy 17.437869 -202.150601) (xy 17.48353 -202.12787)
			(xy 17.532136 -202.112411) (xy 17.582539 -202.104588) (xy 17.633545 -202.104588) (xy 17.683948 -202.112411)
			(xy 17.732554 -202.12787) (xy 17.778215 -202.150601) (xy 17.799304 -202.16495) (xy 17.805838 -202.169237)
			(xy 17.820706 -202.174023) (xy 17.828514 -202.174348) (xy 18.344642 -202.174348) (xy 18.350014 -202.174823)
			(xy 18.357597 -202.182437) (xy 18.358104 -202.18781) (xy 18.358104 -202.682348) (xy 24.402288 -202.682348)
			(xy 24.402288 -202.18781) (xy 24.402736 -202.182496) (xy 24.41019 -202.174922) (xy 24.415496 -202.174348)
			(xy 24.931624 -202.174348) (xy 24.939436 -202.174053) (xy 24.954308 -202.169255) (xy 24.960834 -202.16495)
			(xy 24.981923 -202.150601) (xy 25.027584 -202.12787) (xy 25.07619 -202.112411) (xy 25.126593 -202.104588)
			(xy 25.177599 -202.104588) (xy 25.228002 -202.112411) (xy 25.276608 -202.12787) (xy 25.322269 -202.150601)
			(xy 25.343358 -202.16495) (xy 25.34988 -202.169257) (xy 25.364757 -202.174031) (xy 25.372568 -202.174348)
			(xy 25.888696 -202.174348) (xy 25.893948 -202.174893) (xy 25.901388 -202.182306) (xy 25.901904 -202.187556)
			(xy 25.901904 -202.188064) (xy 25.901904 -202.682348) (xy 31.946088 -202.682348) (xy 31.946088 -202.18781)
			(xy 31.946536 -202.182496) (xy 31.95399 -202.174922) (xy 31.959296 -202.174348) (xy 32.475424 -202.174348)
			(xy 32.483236 -202.174053) (xy 32.498108 -202.169255) (xy 32.504634 -202.16495) (xy 32.525723 -202.150601)
			(xy 32.571384 -202.12787) (xy 32.61999 -202.112411) (xy 32.670393 -202.104588) (xy 32.721399 -202.104588)
			(xy 32.771802 -202.112411) (xy 32.820408 -202.12787) (xy 32.866069 -202.150601) (xy 32.887158 -202.16495)
			(xy 32.89368 -202.169257) (xy 32.908557 -202.174031) (xy 32.916368 -202.174348) (xy 33.432496 -202.174348)
			(xy 33.437748 -202.174893) (xy 33.445188 -202.182306) (xy 33.445704 -202.187556) (xy 33.445704 -202.188064)
			(xy 33.445704 -202.682348) (xy 39.489888 -202.682348) (xy 39.489888 -202.18781) (xy 39.490452 -202.182459)
			(xy 39.498002 -202.174876) (xy 39.50335 -202.174348) (xy 40.019478 -202.174348) (xy 40.027288 -202.174034)
			(xy 40.04216 -202.169249) (xy 40.048688 -202.16495) (xy 40.069777 -202.150601) (xy 40.115438 -202.12787)
			(xy 40.164044 -202.112411) (xy 40.214447 -202.104588) (xy 40.265453 -202.104588) (xy 40.315856 -202.112411)
			(xy 40.364462 -202.12787) (xy 40.410123 -202.150601) (xy 40.431212 -202.16495) (xy 40.437745 -202.16924)
			(xy 40.452614 -202.174025) (xy 40.460422 -202.174348) (xy 40.97655 -202.174348) (xy 40.981922 -202.174818)
			(xy 40.989506 -202.182436) (xy 40.990012 -202.18781) (xy 40.990012 -202.682348) (xy 47.034196 -202.682348)
			(xy 47.034196 -202.18781) (xy 47.034724 -202.182517) (xy 47.042123 -202.174948) (xy 47.047404 -202.174348)
			(xy 47.563532 -202.174348) (xy 47.57134 -202.174014) (xy 47.586212 -202.169243) (xy 47.592742 -202.16495)
			(xy 47.613831 -202.150601) (xy 47.659492 -202.12787) (xy 47.708098 -202.112411) (xy 47.758501 -202.104588)
			(xy 47.809507 -202.104588) (xy 47.85991 -202.112411) (xy 47.908516 -202.12787) (xy 47.954177 -202.150601)
			(xy 47.975266 -202.16495) (xy 47.981809 -202.169222) (xy 47.99667 -202.174018) (xy 48.004476 -202.174348)
			(xy 48.520604 -202.174348) (xy 48.525857 -202.174887) (xy 48.533297 -202.182305) (xy 48.533812 -202.187556)
			(xy 48.533812 -202.188064) (xy 48.533812 -202.682348) (xy 54.577996 -202.682348) (xy 54.577996 -202.18781)
			(xy 54.578553 -202.182457) (xy 54.586107 -202.174874) (xy 54.591458 -202.174348) (xy 56.064658 -202.174348)
			(xy 56.07009 -202.174709) (xy 56.077779 -202.182379) (xy 56.07812 -202.18781) (xy 56.07812 -202.682348)
			(xy 163.678108 -202.682348) (xy 163.678108 -202.18781) (xy 163.678626 -202.182514) (xy 163.686032 -202.174944)
			(xy 163.691316 -202.174348) (xy 165.164516 -202.174348) (xy 165.16977 -202.174879) (xy 165.177209 -202.182303)
			(xy 165.177724 -202.187556) (xy 165.177724 -202.188064) (xy 165.177724 -202.682348) (xy 171.221908 -202.682348)
			(xy 171.221908 -202.18781) (xy 171.222454 -202.182455) (xy 171.230016 -202.17487) (xy 171.23537 -202.174348)
			(xy 171.751498 -202.174348) (xy 171.759309 -202.174042) (xy 171.774181 -202.169252) (xy 171.780708 -202.16495)
			(xy 171.801797 -202.150601) (xy 171.847458 -202.12787) (xy 171.896064 -202.112411) (xy 171.946467 -202.104588)
			(xy 171.997473 -202.104588) (xy 172.047876 -202.112411) (xy 172.096482 -202.12787) (xy 172.142143 -202.150601)
			(xy 172.163232 -202.16495) (xy 172.16976 -202.169247) (xy 172.184633 -202.174027) (xy 172.192442 -202.174348)
			(xy 172.70857 -202.174348) (xy 172.714003 -202.174701) (xy 172.721691 -202.182377) (xy 172.722032 -202.18781)
			(xy 172.722032 -202.682348) (xy 178.766216 -202.682348) (xy 178.766216 -202.18781) (xy 178.766727 -202.182513)
			(xy 178.774138 -202.174942) (xy 178.779424 -202.174348) (xy 179.295552 -202.174348) (xy 179.303361 -202.174023)
			(xy 179.318233 -202.169246) (xy 179.324762 -202.16495) (xy 179.345851 -202.150601) (xy 179.391512 -202.12787)
			(xy 179.440118 -202.112411) (xy 179.490521 -202.104588) (xy 179.541527 -202.104588) (xy 179.59193 -202.112411)
			(xy 179.640536 -202.12787) (xy 179.686197 -202.150601) (xy 179.707286 -202.16495) (xy 179.713824 -202.16923)
			(xy 179.728689 -202.174021) (xy 179.736496 -202.174348) (xy 180.252624 -202.174348) (xy 180.257879 -202.174874)
			(xy 180.265318 -202.182302) (xy 180.265832 -202.187556) (xy 180.265832 -202.188064) (xy 180.265832 -202.682348)
			(xy 186.310016 -202.682348) (xy 186.310016 -202.18781) (xy 186.310555 -202.182453) (xy 186.318122 -202.174868)
			(xy 186.323478 -202.174348) (xy 186.839606 -202.174348) (xy 186.847417 -202.174046) (xy 186.862289 -202.169253)
			(xy 186.868816 -202.16495) (xy 186.889905 -202.150601) (xy 186.935566 -202.12787) (xy 186.984172 -202.112411)
			(xy 187.034575 -202.104588) (xy 187.085581 -202.104588) (xy 187.135984 -202.112411) (xy 187.18459 -202.12787)
			(xy 187.230251 -202.150601) (xy 187.25134 -202.16495) (xy 187.257866 -202.16925) (xy 187.27274 -202.174029)
			(xy 187.28055 -202.174348) (xy 187.796678 -202.174348) (xy 187.802112 -202.174695) (xy 187.8098 -202.182376)
			(xy 187.81014 -202.18781) (xy 187.81014 -202.682348) (xy 193.854324 -202.682348) (xy 193.854324 -202.18781)
			(xy 193.854828 -202.182511) (xy 193.862244 -202.17494) (xy 193.867532 -202.174348) (xy 194.38366 -202.174348)
			(xy 194.391469 -202.174026) (xy 194.406341 -202.169247) (xy 194.41287 -202.16495) (xy 194.433959 -202.150601)
			(xy 194.47962 -202.12787) (xy 194.528226 -202.112411) (xy 194.578629 -202.104588) (xy 194.629635 -202.104588)
			(xy 194.680038 -202.112411) (xy 194.728644 -202.12787) (xy 194.774305 -202.150601) (xy 194.795394 -202.16495)
			(xy 194.801931 -202.169233) (xy 194.816797 -202.174022) (xy 194.824604 -202.174348) (xy 195.340732 -202.174348)
			(xy 195.345988 -202.174869) (xy 195.353426 -202.1823) (xy 195.35394 -202.187556) (xy 195.35394 -202.188064)
			(xy 195.35394 -202.682348) (xy 201.398124 -202.682348) (xy 201.398124 -202.18781) (xy 201.398628 -202.182511)
			(xy 201.406044 -202.17494) (xy 201.411332 -202.174348) (xy 201.92746 -202.174348) (xy 201.935269 -202.174026)
			(xy 201.950141 -202.169247) (xy 201.95667 -202.16495) (xy 201.977759 -202.150601) (xy 202.02342 -202.12787)
			(xy 202.072026 -202.112411) (xy 202.122429 -202.104588) (xy 202.173435 -202.104588) (xy 202.223838 -202.112411)
			(xy 202.272444 -202.12787) (xy 202.318105 -202.150601) (xy 202.339194 -202.16495) (xy 202.345731 -202.169233)
			(xy 202.360597 -202.174022) (xy 202.368404 -202.174348) (xy 202.884532 -202.174348) (xy 202.889788 -202.174869)
			(xy 202.897226 -202.1823) (xy 202.89774 -202.187556) (xy 202.89774 -202.188064) (xy 202.89774 -202.662536)
			(xy 255.545336 -202.662536) (xy 255.545336 -201.798936) (xy 255.545822 -201.771667) (xy 255.553584 -201.717683)
			(xy 255.568949 -201.665353) (xy 255.591606 -201.615743) (xy 255.621092 -201.569862) (xy 255.656807 -201.528645)
			(xy 255.698024 -201.49293) (xy 255.743905 -201.463444) (xy 255.793515 -201.440787) (xy 255.845845 -201.425422)
			(xy 255.899829 -201.41766) (xy 255.954367 -201.41766) (xy 256.008351 -201.425422) (xy 256.060681 -201.440787)
			(xy 256.110291 -201.463444) (xy 256.156172 -201.49293) (xy 256.197389 -201.528645) (xy 256.233104 -201.569862)
			(xy 256.26259 -201.615743) (xy 256.285247 -201.665353) (xy 256.300612 -201.717683) (xy 256.308374 -201.771667)
			(xy 256.30886 -201.798936) (xy 256.30886 -201.83221) (xy 264.798048 -201.83221) (xy 264.798048 -201.337672)
			(xy 264.798571 -201.332416) (xy 264.806001 -201.324978) (xy 264.811256 -201.324464) (xy 264.811764 -201.324464)
			(xy 265.327638 -201.324464) (xy 265.335446 -201.32413) (xy 265.350318 -201.319358) (xy 265.356848 -201.315066)
			(xy 265.377937 -201.300717) (xy 265.423598 -201.277986) (xy 265.472204 -201.262527) (xy 265.522607 -201.254704)
			(xy 265.573613 -201.254704) (xy 265.624016 -201.262527) (xy 265.672622 -201.277986) (xy 265.718283 -201.300717)
			(xy 265.739372 -201.315066) (xy 265.745913 -201.319342) (xy 265.760776 -201.324135) (xy 265.768582 -201.324464)
			(xy 266.28471 -201.324464) (xy 266.290021 -201.324919) (xy 266.297593 -201.33237) (xy 266.298172 -201.337672)
			(xy 266.298172 -201.83221) (xy 268.898116 -201.83221) (xy 268.898116 -201.337672) (xy 268.898578 -201.3324)
			(xy 268.90605 -201.324958) (xy 268.911324 -201.324464) (xy 268.911832 -201.324464) (xy 269.427706 -201.324464)
			(xy 269.435517 -201.324159) (xy 269.450389 -201.319368) (xy 269.456916 -201.315066) (xy 269.478005 -201.300717)
			(xy 269.523666 -201.277986) (xy 269.572272 -201.262527) (xy 269.622675 -201.254704) (xy 269.673681 -201.254704)
			(xy 269.724084 -201.262527) (xy 269.77269 -201.277986) (xy 269.818351 -201.300717) (xy 269.83944 -201.315066)
			(xy 269.845965 -201.319368) (xy 269.86084 -201.324145) (xy 269.86865 -201.324464) (xy 270.384778 -201.324464)
			(xy 270.390085 -201.324941) (xy 270.397659 -201.332375) (xy 270.39824 -201.337672) (xy 270.39824 -201.83221)
			(xy 270.398225 -201.832464) (xy 272.342356 -201.832464) (xy 272.342356 -201.831956) (xy 272.342356 -201.337672)
			(xy 272.342872 -201.332415) (xy 272.350307 -201.324975) (xy 272.355564 -201.324464) (xy 272.871692 -201.324464)
			(xy 272.879502 -201.324153) (xy 272.894374 -201.319366) (xy 272.900902 -201.315066) (xy 272.921991 -201.300717)
			(xy 272.967652 -201.277986) (xy 273.016258 -201.262527) (xy 273.066661 -201.254704) (xy 273.117667 -201.254704)
			(xy 273.16807 -201.262527) (xy 273.216676 -201.277986) (xy 273.262337 -201.300717) (xy 273.283426 -201.315066)
			(xy 273.289955 -201.319363) (xy 273.304827 -201.324143) (xy 273.312636 -201.324464) (xy 273.828764 -201.324464)
			(xy 273.834085 -201.324848) (xy 273.841626 -201.332353) (xy 273.841972 -201.337672) (xy 273.841972 -201.83221)
			(xy 273.841949 -201.832464) (xy 276.442424 -201.832464) (xy 276.442424 -201.831956) (xy 276.442424 -201.337672)
			(xy 276.442711 -201.332328) (xy 276.450287 -201.324787) (xy 276.455632 -201.324464) (xy 276.97176 -201.324464)
			(xy 276.979569 -201.324139) (xy 276.994441 -201.319361) (xy 277.00097 -201.315066) (xy 277.022059 -201.300717)
			(xy 277.06772 -201.277986) (xy 277.116326 -201.262527) (xy 277.166729 -201.254704) (xy 277.217735 -201.254704)
			(xy 277.268138 -201.262527) (xy 277.316744 -201.277986) (xy 277.362405 -201.300717) (xy 277.383494 -201.315066)
			(xy 277.39003 -201.31935) (xy 277.404896 -201.324138) (xy 277.412704 -201.324464) (xy 277.928832 -201.324464)
			(xy 277.934092 -201.324971) (xy 277.941531 -201.332412) (xy 277.94204 -201.337672) (xy 277.94204 -201.83221)
			(xy 277.942018 -201.832464) (xy 279.886156 -201.832464) (xy 279.886156 -201.831956) (xy 279.886156 -201.337672)
			(xy 279.886672 -201.332415) (xy 279.894107 -201.324975) (xy 279.899364 -201.324464) (xy 280.415492 -201.324464)
			(xy 280.423302 -201.324153) (xy 280.438174 -201.319366) (xy 280.444702 -201.315066) (xy 280.465791 -201.300717)
			(xy 280.511452 -201.277986) (xy 280.560058 -201.262527) (xy 280.610461 -201.254704) (xy 280.661467 -201.254704)
			(xy 280.71187 -201.262527) (xy 280.760476 -201.277986) (xy 280.806137 -201.300717) (xy 280.827226 -201.315066)
			(xy 280.833755 -201.319363) (xy 280.848627 -201.324143) (xy 280.856436 -201.324464) (xy 281.372564 -201.324464)
			(xy 281.377885 -201.324848) (xy 281.385426 -201.332353) (xy 281.385772 -201.337672) (xy 281.385772 -201.83221)
			(xy 281.385749 -201.832464) (xy 283.986224 -201.832464) (xy 283.986224 -201.831956) (xy 283.986224 -201.337672)
			(xy 283.986511 -201.332328) (xy 283.994087 -201.324787) (xy 283.999432 -201.324464) (xy 284.51556 -201.324464)
			(xy 284.523369 -201.324139) (xy 284.538241 -201.319361) (xy 284.54477 -201.315066) (xy 284.565859 -201.300717)
			(xy 284.61152 -201.277986) (xy 284.660126 -201.262527) (xy 284.710529 -201.254704) (xy 284.761535 -201.254704)
			(xy 284.811938 -201.262527) (xy 284.860544 -201.277986) (xy 284.906205 -201.300717) (xy 284.927294 -201.315066)
			(xy 284.93383 -201.31935) (xy 284.948696 -201.324138) (xy 284.956504 -201.324464) (xy 285.472632 -201.324464)
			(xy 285.477892 -201.324971) (xy 285.485331 -201.332412) (xy 285.48584 -201.337672) (xy 285.48584 -201.83221)
			(xy 287.429956 -201.83221) (xy 287.429956 -201.337672) (xy 287.430472 -201.332415) (xy 287.437907 -201.324975)
			(xy 287.443164 -201.324464) (xy 287.443672 -201.324464) (xy 287.959546 -201.324464) (xy 287.967355 -201.324133)
			(xy 287.982226 -201.31936) (xy 287.988756 -201.315066) (xy 288.009845 -201.300717) (xy 288.055506 -201.277986)
			(xy 288.104112 -201.262527) (xy 288.154515 -201.254704) (xy 288.205521 -201.254704) (xy 288.255924 -201.262527)
			(xy 288.30453 -201.277986) (xy 288.350191 -201.300717) (xy 288.37128 -201.315066) (xy 288.377819 -201.319345)
			(xy 288.392683 -201.324136) (xy 288.40049 -201.324464) (xy 288.916618 -201.324464) (xy 288.92193 -201.324914)
			(xy 288.929502 -201.332368) (xy 288.93008 -201.337672) (xy 288.93008 -201.83221) (xy 291.530024 -201.83221)
			(xy 291.530024 -201.337672) (xy 291.530311 -201.332328) (xy 291.537887 -201.324787) (xy 291.543232 -201.324464)
			(xy 291.54374 -201.324464) (xy 292.059614 -201.324464) (xy 292.067425 -201.324162) (xy 292.082297 -201.319369)
			(xy 292.088824 -201.315066) (xy 292.109913 -201.300717) (xy 292.155574 -201.277986) (xy 292.20418 -201.262527)
			(xy 292.254583 -201.254704) (xy 292.305589 -201.254704) (xy 292.355992 -201.262527) (xy 292.404598 -201.277986)
			(xy 292.450259 -201.300717) (xy 292.471348 -201.315066) (xy 292.477872 -201.319371) (xy 292.492748 -201.324146)
			(xy 292.500558 -201.324464) (xy 293.016686 -201.324464) (xy 293.021994 -201.324935) (xy 293.029567 -201.332374)
			(xy 293.030148 -201.337672) (xy 293.030148 -201.83221) (xy 293.030133 -201.832464) (xy 294.974264 -201.832464)
			(xy 294.974264 -201.831956) (xy 294.974264 -201.337672) (xy 294.974773 -201.332413) (xy 294.982213 -201.324973)
			(xy 294.987472 -201.324464) (xy 295.5036 -201.324464) (xy 295.511411 -201.324157) (xy 295.526282 -201.319367)
			(xy 295.53281 -201.315066) (xy 295.553899 -201.300717) (xy 295.59956 -201.277986) (xy 295.648166 -201.262527)
			(xy 295.698569 -201.254704) (xy 295.749575 -201.254704) (xy 295.799978 -201.262527) (xy 295.848584 -201.277986)
			(xy 295.894245 -201.300717) (xy 295.915334 -201.315066) (xy 295.921861 -201.319366) (xy 295.936734 -201.324144)
			(xy 295.944544 -201.324464) (xy 296.460672 -201.324464) (xy 296.465925 -201.32501) (xy 296.473367 -201.332422)
			(xy 296.47388 -201.337672) (xy 296.47388 -201.83221) (xy 296.473856 -201.832464) (xy 299.074332 -201.832464)
			(xy 299.074332 -201.831956) (xy 299.074332 -201.337672) (xy 299.074612 -201.332326) (xy 299.082192 -201.324784)
			(xy 299.08754 -201.324464) (xy 299.603668 -201.324464) (xy 299.611477 -201.324143) (xy 299.626349 -201.319362)
			(xy 299.632878 -201.315066) (xy 299.653967 -201.300717) (xy 299.699628 -201.277986) (xy 299.748234 -201.262527)
			(xy 299.798637 -201.254704) (xy 299.849643 -201.254704) (xy 299.900046 -201.262527) (xy 299.948652 -201.277986)
			(xy 299.994313 -201.300717) (xy 300.015402 -201.315066) (xy 300.021936 -201.319353) (xy 300.036804 -201.324139)
			(xy 300.044612 -201.324464) (xy 300.56074 -201.324464) (xy 300.566001 -201.324965) (xy 300.57344 -201.332411)
			(xy 300.573948 -201.337672) (xy 300.573948 -201.83221) (xy 302.518064 -201.83221) (xy 302.518064 -201.337672)
			(xy 302.518573 -201.332413) (xy 302.526013 -201.324973) (xy 302.531272 -201.324464) (xy 304.004726 -201.324464)
			(xy 304.010039 -201.324909) (xy 304.01761 -201.332367) (xy 304.018188 -201.337672) (xy 304.018188 -201.83221)
			(xy 306.618132 -201.83221) (xy 306.618132 -201.337672) (xy 306.618412 -201.332326) (xy 306.625992 -201.324784)
			(xy 306.63134 -201.324464) (xy 306.631848 -201.324464) (xy 308.104794 -201.324464) (xy 308.110103 -201.32493)
			(xy 308.117676 -201.332372) (xy 308.118256 -201.337672) (xy 308.118256 -201.83221) (xy 308.118232 -201.832464)
			(xy 411.618176 -201.832464) (xy 411.618176 -201.831956) (xy 411.618176 -201.337672) (xy 411.618674 -201.33241)
			(xy 411.626121 -201.32497) (xy 411.631384 -201.324464) (xy 413.104584 -201.324464) (xy 413.109838 -201.325002)
			(xy 413.11728 -201.33242) (xy 413.117792 -201.337672) (xy 413.117792 -201.83221) (xy 413.117768 -201.832464)
			(xy 415.718244 -201.832464) (xy 415.718244 -201.337672) (xy 415.718771 -201.332417) (xy 415.726198 -201.324979)
			(xy 415.731452 -201.324464) (xy 417.204652 -201.324464) (xy 417.209971 -201.324857) (xy 417.217513 -201.332355)
			(xy 417.21786 -201.337672) (xy 417.21786 -201.83221) (xy 419.161976 -201.83221) (xy 419.161976 -201.337672)
			(xy 419.162474 -201.33241) (xy 419.169921 -201.32497) (xy 419.175184 -201.324464) (xy 419.175692 -201.324464)
			(xy 419.691566 -201.324464) (xy 419.699375 -201.324142) (xy 419.714247 -201.319362) (xy 419.720776 -201.315066)
			(xy 419.741865 -201.300717) (xy 419.787526 -201.277986) (xy 419.836132 -201.262527) (xy 419.886535 -201.254704)
			(xy 419.937541 -201.254704) (xy 419.987944 -201.262527) (xy 420.03655 -201.277986) (xy 420.082211 -201.300717)
			(xy 420.1033 -201.315066) (xy 420.109834 -201.319353) (xy 420.124702 -201.324139) (xy 420.13251 -201.324464)
			(xy 420.648638 -201.324464) (xy 420.653952 -201.324901) (xy 420.661523 -201.332365) (xy 420.6621 -201.337672)
			(xy 420.6621 -201.83221) (xy 423.262044 -201.83221) (xy 423.262044 -201.337672) (xy 423.262571 -201.332417)
			(xy 423.269998 -201.324979) (xy 423.275252 -201.324464) (xy 423.27576 -201.324464) (xy 423.791634 -201.324464)
			(xy 423.799442 -201.324128) (xy 423.814314 -201.319358) (xy 423.820844 -201.315066) (xy 423.841933 -201.300717)
			(xy 423.887594 -201.277986) (xy 423.9362 -201.262527) (xy 423.986603 -201.254704) (xy 424.037609 -201.254704)
			(xy 424.088012 -201.262527) (xy 424.136618 -201.277986) (xy 424.182279 -201.300717) (xy 424.203368 -201.315066)
			(xy 424.209909 -201.31934) (xy 424.224772 -201.324134) (xy 424.232578 -201.324464) (xy 424.748706 -201.324464)
			(xy 424.754017 -201.324922) (xy 424.761589 -201.33237) (xy 424.762168 -201.337672) (xy 424.762168 -201.83221)
			(xy 424.762144 -201.832464) (xy 426.706284 -201.832464) (xy 426.706284 -201.831956) (xy 426.706284 -201.337672)
			(xy 426.706775 -201.332408) (xy 426.714227 -201.324967) (xy 426.719492 -201.324464) (xy 427.23562 -201.324464)
			(xy 427.243432 -201.324165) (xy 427.258303 -201.31937) (xy 427.26483 -201.315066) (xy 427.285919 -201.300717)
			(xy 427.33158 -201.277986) (xy 427.380186 -201.262527) (xy 427.430589 -201.254704) (xy 427.481595 -201.254704)
			(xy 427.531998 -201.262527) (xy 427.580604 -201.277986) (xy 427.626265 -201.300717) (xy 427.647354 -201.315066)
			(xy 427.653876 -201.319373) (xy 427.668753 -201.324147) (xy 427.676564 -201.324464) (xy 428.192692 -201.324464)
			(xy 428.197947 -201.324997) (xy 428.205389 -201.332418) (xy 428.2059 -201.337672) (xy 428.2059 -201.83221)
			(xy 428.205875 -201.832464) (xy 430.806352 -201.832464) (xy 430.806352 -201.831956) (xy 430.806352 -201.337672)
			(xy 430.806872 -201.332415) (xy 430.814304 -201.324977) (xy 430.81956 -201.324464) (xy 431.335688 -201.324464)
			(xy 431.343498 -201.324151) (xy 431.35837 -201.319365) (xy 431.364898 -201.315066) (xy 431.385987 -201.300717)
			(xy 431.431648 -201.277986) (xy 431.480254 -201.262527) (xy 431.530657 -201.254704) (xy 431.581663 -201.254704)
			(xy 431.632066 -201.262527) (xy 431.680672 -201.277986) (xy 431.726333 -201.300717) (xy 431.747422 -201.315066)
			(xy 431.753951 -201.319361) (xy 431.768823 -201.324142) (xy 431.776632 -201.324464) (xy 432.29276 -201.324464)
			(xy 432.29808 -201.324851) (xy 432.305622 -201.332354) (xy 432.305968 -201.337672) (xy 432.305968 -201.83221)
			(xy 434.250084 -201.83221) (xy 434.250084 -201.337672) (xy 434.250575 -201.332408) (xy 434.258027 -201.324967)
			(xy 434.263292 -201.324464) (xy 434.2638 -201.324464) (xy 434.779674 -201.324464) (xy 434.787484 -201.324145)
			(xy 434.802355 -201.319363) (xy 434.808884 -201.315066) (xy 434.829973 -201.300717) (xy 434.875634 -201.277986)
			(xy 434.92424 -201.262527) (xy 434.974643 -201.254704) (xy 435.025649 -201.254704) (xy 435.076052 -201.262527)
			(xy 435.124658 -201.277986) (xy 435.170319 -201.300717) (xy 435.191408 -201.315066) (xy 435.197941 -201.319356)
			(xy 435.21281 -201.32414) (xy 435.220618 -201.324464) (xy 435.736746 -201.324464) (xy 435.742049 -201.324962)
			(xy 435.749625 -201.33238) (xy 435.750208 -201.337672) (xy 435.750208 -201.83221) (xy 438.350152 -201.83221)
			(xy 438.350152 -201.337672) (xy 438.350672 -201.332415) (xy 438.358104 -201.324977) (xy 438.36336 -201.324464)
			(xy 438.363868 -201.324464) (xy 438.879742 -201.324464) (xy 438.88755 -201.324132) (xy 438.902422 -201.319359)
			(xy 438.908952 -201.315066) (xy 438.930041 -201.300717) (xy 438.975702 -201.277986) (xy 439.024308 -201.262527)
			(xy 439.074711 -201.254704) (xy 439.125717 -201.254704) (xy 439.17612 -201.262527) (xy 439.224726 -201.277986)
			(xy 439.270387 -201.300717) (xy 439.291476 -201.315066) (xy 439.298016 -201.319343) (xy 439.312879 -201.324135)
			(xy 439.320686 -201.324464) (xy 439.836814 -201.324464) (xy 439.842125 -201.324917) (xy 439.849697 -201.332369)
			(xy 439.850276 -201.337672) (xy 439.850276 -201.83221) (xy 439.850251 -201.832464) (xy 441.794392 -201.832464)
			(xy 441.794392 -201.831956) (xy 441.794392 -201.337672) (xy 441.794876 -201.332406) (xy 441.802333 -201.324965)
			(xy 441.8076 -201.324464) (xy 442.323728 -201.324464) (xy 442.33154 -201.324168) (xy 442.346411 -201.319371)
			(xy 442.352938 -201.315066) (xy 442.374027 -201.300717) (xy 442.419688 -201.277986) (xy 442.468294 -201.262527)
			(xy 442.518697 -201.254704) (xy 442.569703 -201.254704) (xy 442.620106 -201.262527) (xy 442.668712 -201.277986)
			(xy 442.714373 -201.300717) (xy 442.735462 -201.315066) (xy 442.742005 -201.319338) (xy 442.756866 -201.324133)
			(xy 442.764672 -201.324464) (xy 443.2808 -201.324464) (xy 443.286056 -201.324992) (xy 443.293497 -201.332417)
			(xy 443.294008 -201.337672) (xy 443.294008 -201.83221) (xy 443.293983 -201.832464) (xy 445.89446 -201.832464)
			(xy 445.89446 -201.831956) (xy 445.89446 -201.337672) (xy 445.894973 -201.332414) (xy 445.90241 -201.324974)
			(xy 445.907668 -201.324464) (xy 446.423796 -201.324464) (xy 446.431607 -201.324155) (xy 446.446478 -201.319366)
			(xy 446.453006 -201.315066) (xy 446.474095 -201.300717) (xy 446.519756 -201.277986) (xy 446.568362 -201.262527)
			(xy 446.618765 -201.254704) (xy 446.669771 -201.254704) (xy 446.720174 -201.262527) (xy 446.76878 -201.277986)
			(xy 446.814441 -201.300717) (xy 446.83553 -201.315066) (xy 446.842058 -201.319364) (xy 446.856931 -201.324143)
			(xy 446.86474 -201.324464) (xy 447.380868 -201.324464) (xy 447.386189 -201.324846) (xy 447.39373 -201.332352)
			(xy 447.394076 -201.337672) (xy 447.394076 -201.83221) (xy 447.394052 -201.832464) (xy 449.338192 -201.832464)
			(xy 449.338192 -201.831956) (xy 449.338192 -201.337672) (xy 449.338676 -201.332406) (xy 449.346133 -201.324965)
			(xy 449.3514 -201.324464) (xy 449.867528 -201.324464) (xy 449.87534 -201.324168) (xy 449.890211 -201.319371)
			(xy 449.896738 -201.315066) (xy 449.917827 -201.300717) (xy 449.963488 -201.277986) (xy 450.012094 -201.262527)
			(xy 450.062497 -201.254704) (xy 450.113503 -201.254704) (xy 450.163906 -201.262527) (xy 450.212512 -201.277986)
			(xy 450.258173 -201.300717) (xy 450.279262 -201.315066) (xy 450.285805 -201.319338) (xy 450.300666 -201.324133)
			(xy 450.308472 -201.324464) (xy 450.8246 -201.324464) (xy 450.829856 -201.324992) (xy 450.837297 -201.332417)
			(xy 450.837808 -201.337672) (xy 450.837808 -201.83221) (xy 450.837783 -201.832464) (xy 453.43826 -201.832464)
			(xy 453.43826 -201.831956) (xy 453.43826 -201.337672) (xy 453.438773 -201.332414) (xy 453.44621 -201.324974)
			(xy 453.451468 -201.324464) (xy 453.967596 -201.324464) (xy 453.975407 -201.324155) (xy 453.990278 -201.319366)
			(xy 453.996806 -201.315066) (xy 454.017895 -201.300717) (xy 454.063556 -201.277986) (xy 454.112162 -201.262527)
			(xy 454.162565 -201.254704) (xy 454.213571 -201.254704) (xy 454.263974 -201.262527) (xy 454.31258 -201.277986)
			(xy 454.358241 -201.300717) (xy 454.37933 -201.315066) (xy 454.385858 -201.319364) (xy 454.400731 -201.324143)
			(xy 454.40854 -201.324464) (xy 454.924668 -201.324464) (xy 454.929989 -201.324846) (xy 454.93753 -201.332352)
			(xy 454.937876 -201.337672) (xy 454.937876 -201.83221) (xy 454.937385 -201.837512) (xy 454.929959 -201.845081)
			(xy 454.924668 -201.845672) (xy 454.408794 -201.845672) (xy 454.400982 -201.845971) (xy 454.386111 -201.850766)
			(xy 454.379584 -201.85507) (xy 454.358466 -201.869425) (xy 454.312741 -201.892149) (xy 454.264066 -201.907578)
			(xy 454.213599 -201.915343) (xy 454.188068 -201.915776) (xy 454.162537 -201.915353) (xy 454.112073 -201.907573)
			(xy 454.063401 -201.89214) (xy 454.017674 -201.869419) (xy 453.996552 -201.85507) (xy 453.990026 -201.850768)
			(xy 453.975152 -201.84599) (xy 453.967342 -201.845672) (xy 453.451468 -201.845672) (xy 453.446123 -201.845391)
			(xy 453.438582 -201.837811) (xy 453.43826 -201.832464) (xy 450.837783 -201.832464) (xy 450.837289 -201.837504)
			(xy 450.829882 -201.845072) (xy 450.8246 -201.845672) (xy 450.308726 -201.845672) (xy 450.300916 -201.845985)
			(xy 450.286044 -201.85077) (xy 450.279516 -201.85507) (xy 450.258389 -201.869411) (xy 450.212667 -201.892139)
			(xy 450.163995 -201.907571) (xy 450.11353 -201.915341) (xy 450.088 -201.915776) (xy 450.06247 -201.915337)
			(xy 450.012006 -201.907562) (xy 449.963334 -201.892133) (xy 449.917606 -201.869417) (xy 449.896484 -201.85507)
			(xy 449.889951 -201.850781) (xy 449.875082 -201.845995) (xy 449.867274 -201.845672) (xy 449.3514 -201.845672)
			(xy 449.346059 -201.84537) (xy 449.338516 -201.837806) (xy 449.338192 -201.832464) (xy 447.394052 -201.832464)
			(xy 447.393585 -201.837512) (xy 447.386159 -201.845081) (xy 447.380868 -201.845672) (xy 446.864994 -201.845672)
			(xy 446.857182 -201.845971) (xy 446.842311 -201.850766) (xy 446.835784 -201.85507) (xy 446.814666 -201.869425)
			(xy 446.768941 -201.892149) (xy 446.720266 -201.907578) (xy 446.669799 -201.915343) (xy 446.644268 -201.915776)
			(xy 446.618737 -201.915353) (xy 446.568273 -201.907573) (xy 446.519601 -201.89214) (xy 446.473874 -201.869419)
			(xy 446.452752 -201.85507) (xy 446.446226 -201.850768) (xy 446.431352 -201.84599) (xy 446.423542 -201.845672)
			(xy 445.907668 -201.845672) (xy 445.902323 -201.845391) (xy 445.894782 -201.837811) (xy 445.89446 -201.832464)
			(xy 443.293983 -201.832464) (xy 443.293489 -201.837504) (xy 443.286082 -201.845072) (xy 443.2808 -201.845672)
			(xy 442.764926 -201.845672) (xy 442.757116 -201.845985) (xy 442.742244 -201.85077) (xy 442.735716 -201.85507)
			(xy 442.714589 -201.869411) (xy 442.668867 -201.892139) (xy 442.620195 -201.907571) (xy 442.56973 -201.915341)
			(xy 442.5442 -201.915776) (xy 442.51867 -201.915337) (xy 442.468206 -201.907562) (xy 442.419534 -201.892133)
			(xy 442.373806 -201.869417) (xy 442.352684 -201.85507) (xy 442.346151 -201.850781) (xy 442.331282 -201.845995)
			(xy 442.323474 -201.845672) (xy 441.8076 -201.845672) (xy 441.802259 -201.84537) (xy 441.794716 -201.837806)
			(xy 441.794392 -201.832464) (xy 439.850251 -201.832464) (xy 439.849758 -201.837572) (xy 439.842176 -201.845156)
			(xy 439.836814 -201.845672) (xy 439.32094 -201.845672) (xy 439.31313 -201.845991) (xy 439.298258 -201.850772)
			(xy 439.29173 -201.85507) (xy 439.270627 -201.869448) (xy 439.224896 -201.892168) (xy 439.176217 -201.90759)
			(xy 439.125747 -201.915347) (xy 439.100214 -201.915776) (xy 439.074684 -201.91533) (xy 439.024221 -201.907557)
			(xy 438.975548 -201.89213) (xy 438.92982 -201.869416) (xy 438.908698 -201.85507) (xy 438.902162 -201.850786)
			(xy 438.887296 -201.845997) (xy 438.879488 -201.845672) (xy 438.363614 -201.845672) (xy 438.358184 -201.845312)
			(xy 438.350497 -201.83764) (xy 438.350152 -201.83221) (xy 435.750208 -201.83221) (xy 435.749661 -201.837564)
			(xy 435.742099 -201.845147) (xy 435.736746 -201.845672) (xy 435.220872 -201.845672) (xy 435.21306 -201.845962)
			(xy 435.198188 -201.850763) (xy 435.191662 -201.85507) (xy 435.17055 -201.869434) (xy 435.124822 -201.892157)
			(xy 435.076146 -201.907583) (xy 435.025678 -201.915345) (xy 435.000146 -201.915776) (xy 434.974617 -201.915314)
			(xy 434.924154 -201.907546) (xy 434.875482 -201.892124) (xy 434.829753 -201.869414) (xy 434.80863 -201.85507)
			(xy 434.802087 -201.850798) (xy 434.787226 -201.846002) (xy 434.77942 -201.845672) (xy 434.263546 -201.845672)
			(xy 434.25812 -201.845291) (xy 434.250432 -201.837635) (xy 434.250084 -201.83221) (xy 432.305968 -201.83221)
			(xy 432.305484 -201.837514) (xy 432.298053 -201.845084) (xy 432.29276 -201.845672) (xy 431.776886 -201.845672)
			(xy 431.769074 -201.845968) (xy 431.754202 -201.850765) (xy 431.747676 -201.85507) (xy 431.72656 -201.869428)
			(xy 431.680834 -201.892152) (xy 431.632159 -201.90758) (xy 431.581691 -201.915344) (xy 431.55616 -201.915776)
			(xy 431.530629 -201.915357) (xy 431.480165 -201.907576) (xy 431.431492 -201.892141) (xy 431.385765 -201.86942)
			(xy 431.364644 -201.85507) (xy 431.35812 -201.850765) (xy 431.343244 -201.845989) (xy 431.335434 -201.845672)
			(xy 430.81956 -201.845672) (xy 430.814284 -201.845228) (xy 430.806841 -201.837743) (xy 430.806352 -201.832464)
			(xy 428.205875 -201.832464) (xy 428.205388 -201.837506) (xy 428.197977 -201.845074) (xy 428.192692 -201.845672)
			(xy 427.676818 -201.845672) (xy 427.669007 -201.845981) (xy 427.654135 -201.850769) (xy 427.647608 -201.85507)
			(xy 427.626483 -201.869414) (xy 427.58076 -201.892141) (xy 427.532088 -201.907573) (xy 427.481623 -201.915342)
			(xy 427.456092 -201.915776) (xy 427.430562 -201.915341) (xy 427.380098 -201.907565) (xy 427.331426 -201.892135)
			(xy 427.285698 -201.869418) (xy 427.264576 -201.85507) (xy 427.258045 -201.850778) (xy 427.243175 -201.845994)
			(xy 427.235366 -201.845672) (xy 426.719492 -201.845672) (xy 426.71415 -201.845375) (xy 426.706607 -201.837807)
			(xy 426.706284 -201.832464) (xy 424.762144 -201.832464) (xy 424.761657 -201.837574) (xy 424.75407 -201.845158)
			(xy 424.748706 -201.845672) (xy 424.232832 -201.845672) (xy 424.225022 -201.845987) (xy 424.21015 -201.850771)
			(xy 424.203622 -201.85507) (xy 424.182493 -201.869408) (xy 424.136772 -201.892137) (xy 424.088101 -201.90757)
			(xy 424.037636 -201.91534) (xy 424.012106 -201.915776) (xy 423.986576 -201.915334) (xy 423.936112 -201.90756)
			(xy 423.88744 -201.892132) (xy 423.841712 -201.869417) (xy 423.82059 -201.85507) (xy 423.814056 -201.850783)
			(xy 423.799188 -201.845996) (xy 423.79138 -201.845672) (xy 423.275506 -201.845672) (xy 423.270145 -201.845147)
			(xy 423.26256 -201.83757) (xy 423.262044 -201.83221) (xy 420.6621 -201.83221) (xy 420.66156 -201.837566)
			(xy 420.653993 -201.845149) (xy 420.648638 -201.845672) (xy 420.132764 -201.845672) (xy 420.124955 -201.846001)
			(xy 420.110083 -201.850775) (xy 420.103554 -201.85507) (xy 420.082444 -201.869437) (xy 420.036716 -201.89216)
			(xy 419.988039 -201.907584) (xy 419.93757 -201.915346) (xy 419.912038 -201.915776) (xy 419.886509 -201.915318)
			(xy 419.836046 -201.907549) (xy 419.787373 -201.892125) (xy 419.741645 -201.869415) (xy 419.720522 -201.85507)
			(xy 419.713981 -201.850795) (xy 419.699118 -201.846001) (xy 419.691312 -201.845672) (xy 419.175438 -201.845672)
			(xy 419.170011 -201.845296) (xy 419.162323 -201.837636) (xy 419.161976 -201.83221) (xy 417.21786 -201.83221)
			(xy 417.217383 -201.837515) (xy 417.209948 -201.845086) (xy 417.204652 -201.845672) (xy 415.731452 -201.845672)
			(xy 415.726175 -201.845233) (xy 415.718733 -201.837744) (xy 415.718244 -201.832464) (xy 413.117768 -201.832464)
			(xy 413.117287 -201.837508) (xy 413.109871 -201.845077) (xy 413.104584 -201.845672) (xy 411.631384 -201.845672)
			(xy 411.626041 -201.845381) (xy 411.618498 -201.837809) (xy 411.618176 -201.832464) (xy 308.118232 -201.832464)
			(xy 308.117756 -201.837577) (xy 308.110161 -201.845162) (xy 308.104794 -201.845672) (xy 306.631594 -201.845672)
			(xy 306.626232 -201.845155) (xy 306.618647 -201.837572) (xy 306.618132 -201.83221) (xy 304.018188 -201.83221)
			(xy 304.017659 -201.837569) (xy 304.010084 -201.845152) (xy 304.004726 -201.845672) (xy 302.531526 -201.845672)
			(xy 302.526097 -201.845304) (xy 302.51841 -201.837638) (xy 302.518064 -201.83221) (xy 300.573948 -201.83221)
			(xy 300.573482 -201.837518) (xy 300.566039 -201.845089) (xy 300.56074 -201.845672) (xy 300.044866 -201.845672)
			(xy 300.037057 -201.846002) (xy 300.022185 -201.850775) (xy 300.015656 -201.85507) (xy 299.994546 -201.869437)
			(xy 299.948818 -201.892159) (xy 299.900141 -201.907584) (xy 299.849672 -201.915345) (xy 299.82414 -201.915776)
			(xy 299.798611 -201.915317) (xy 299.748148 -201.907548) (xy 299.699475 -201.892125) (xy 299.653747 -201.869415)
			(xy 299.632624 -201.85507) (xy 299.626082 -201.850796) (xy 299.61122 -201.846001) (xy 299.603414 -201.845672)
			(xy 299.08754 -201.845672) (xy 299.082204 -201.845343) (xy 299.074659 -201.837799) (xy 299.074332 -201.832464)
			(xy 296.473856 -201.832464) (xy 296.473386 -201.837511) (xy 296.465962 -201.84508) (xy 296.460672 -201.845672)
			(xy 295.944798 -201.845672) (xy 295.936987 -201.845973) (xy 295.922115 -201.850766) (xy 295.915588 -201.85507)
			(xy 295.894469 -201.869423) (xy 295.848744 -201.892148) (xy 295.80007 -201.907577) (xy 295.749603 -201.915343)
			(xy 295.724072 -201.915776) (xy 295.698541 -201.915351) (xy 295.648077 -201.907572) (xy 295.599405 -201.892139)
			(xy 295.553678 -201.869419) (xy 295.532556 -201.85507) (xy 295.526029 -201.85077) (xy 295.511156 -201.845991)
			(xy 295.503346 -201.845672) (xy 294.987472 -201.845672) (xy 294.982127 -201.845388) (xy 294.974586 -201.83781)
			(xy 294.974264 -201.832464) (xy 293.030133 -201.832464) (xy 293.029826 -201.83765) (xy 293.022126 -201.845336)
			(xy 293.016686 -201.845672) (xy 292.500812 -201.845672) (xy 292.493001 -201.845979) (xy 292.478129 -201.850768)
			(xy 292.471602 -201.85507) (xy 292.450479 -201.869417) (xy 292.404755 -201.892143) (xy 292.356083 -201.907574)
			(xy 292.305617 -201.915342) (xy 292.280086 -201.915776) (xy 292.254556 -201.915344) (xy 292.204092 -201.907567)
			(xy 292.155419 -201.892136) (xy 292.109692 -201.869418) (xy 292.08857 -201.85507) (xy 292.08204 -201.850775)
			(xy 292.067169 -201.845993) (xy 292.05936 -201.845672) (xy 291.543486 -201.845672) (xy 291.538123 -201.84516)
			(xy 291.530539 -201.837573) (xy 291.530024 -201.83221) (xy 288.93008 -201.83221) (xy 288.929558 -201.837571)
			(xy 288.921978 -201.845155) (xy 288.916618 -201.845672) (xy 288.400744 -201.845672) (xy 288.392934 -201.845992)
			(xy 288.378062 -201.850772) (xy 288.371534 -201.85507) (xy 288.35043 -201.869446) (xy 288.304699 -201.892166)
			(xy 288.256021 -201.907589) (xy 288.20555 -201.915347) (xy 288.180018 -201.915776) (xy 288.154488 -201.915328)
			(xy 288.104025 -201.907555) (xy 288.055352 -201.89213) (xy 288.009624 -201.869416) (xy 287.988502 -201.85507)
			(xy 287.981965 -201.850787) (xy 287.967099 -201.845998) (xy 287.959292 -201.845672) (xy 287.443418 -201.845672)
			(xy 287.437988 -201.84531) (xy 287.430301 -201.837639) (xy 287.429956 -201.83221) (xy 285.48584 -201.83221)
			(xy 285.485381 -201.83752) (xy 285.477933 -201.845092) (xy 285.472632 -201.845672) (xy 284.956758 -201.845672)
			(xy 284.948949 -201.845998) (xy 284.934077 -201.850774) (xy 284.927548 -201.85507) (xy 284.90644 -201.86944)
			(xy 284.860711 -201.892162) (xy 284.812034 -201.907586) (xy 284.761564 -201.915346) (xy 284.736032 -201.915776)
			(xy 284.710502 -201.915321) (xy 284.660039 -201.907551) (xy 284.611367 -201.892127) (xy 284.565639 -201.869415)
			(xy 284.544516 -201.85507) (xy 284.537976 -201.850793) (xy 284.523113 -201.846) (xy 284.515306 -201.845672)
			(xy 283.999432 -201.845672) (xy 283.994095 -201.845348) (xy 283.98655 -201.837801) (xy 283.986224 -201.832464)
			(xy 281.385749 -201.832464) (xy 281.385285 -201.837513) (xy 281.377856 -201.845082) (xy 281.372564 -201.845672)
			(xy 280.85669 -201.845672) (xy 280.848878 -201.845969) (xy 280.834007 -201.850765) (xy 280.82748 -201.85507)
			(xy 280.806363 -201.869426) (xy 280.760637 -201.892151) (xy 280.711963 -201.907579) (xy 280.661495 -201.915344)
			(xy 280.635964 -201.915776) (xy 280.610433 -201.915355) (xy 280.559969 -201.907574) (xy 280.511296 -201.89214)
			(xy 280.465569 -201.869419) (xy 280.444448 -201.85507) (xy 280.437923 -201.850767) (xy 280.423048 -201.84599)
			(xy 280.415238 -201.845672) (xy 279.899364 -201.845672) (xy 279.894088 -201.845225) (xy 279.886646 -201.837742)
			(xy 279.886156 -201.832464) (xy 277.942018 -201.832464) (xy 277.941581 -201.83752) (xy 277.934133 -201.845092)
			(xy 277.928832 -201.845672) (xy 277.412958 -201.845672) (xy 277.405149 -201.845998) (xy 277.390277 -201.850774)
			(xy 277.383748 -201.85507) (xy 277.36264 -201.86944) (xy 277.316911 -201.892162) (xy 277.268234 -201.907586)
			(xy 277.217764 -201.915346) (xy 277.192232 -201.915776) (xy 277.166702 -201.915321) (xy 277.116239 -201.907551)
			(xy 277.067567 -201.892127) (xy 277.021839 -201.869415) (xy 277.000716 -201.85507) (xy 276.994176 -201.850793)
			(xy 276.979313 -201.846) (xy 276.971506 -201.845672) (xy 276.455632 -201.845672) (xy 276.450295 -201.845348)
			(xy 276.44275 -201.837801) (xy 276.442424 -201.832464) (xy 273.841949 -201.832464) (xy 273.841485 -201.837513)
			(xy 273.834056 -201.845082) (xy 273.828764 -201.845672) (xy 273.31289 -201.845672) (xy 273.305078 -201.845969)
			(xy 273.290207 -201.850765) (xy 273.28368 -201.85507) (xy 273.262563 -201.869426) (xy 273.216837 -201.892151)
			(xy 273.168163 -201.907579) (xy 273.117695 -201.915344) (xy 273.092164 -201.915776) (xy 273.066633 -201.915355)
			(xy 273.016169 -201.907574) (xy 272.967496 -201.89214) (xy 272.921769 -201.869419) (xy 272.900648 -201.85507)
			(xy 272.894123 -201.850767) (xy 272.879248 -201.84599) (xy 272.871438 -201.845672) (xy 272.355564 -201.845672)
			(xy 272.350288 -201.845225) (xy 272.342846 -201.837742) (xy 272.342356 -201.832464) (xy 270.398225 -201.832464)
			(xy 270.397925 -201.837652) (xy 270.39022 -201.845338) (xy 270.384778 -201.845672) (xy 269.868904 -201.845672)
			(xy 269.861093 -201.845975) (xy 269.846221 -201.850767) (xy 269.839694 -201.85507) (xy 269.818573 -201.86942)
			(xy 269.772849 -201.892146) (xy 269.724175 -201.907576) (xy 269.673709 -201.915343) (xy 269.648178 -201.915776)
			(xy 269.622647 -201.915348) (xy 269.572183 -201.907569) (xy 269.523511 -201.892138) (xy 269.477784 -201.869419)
			(xy 269.456662 -201.85507) (xy 269.450134 -201.850772) (xy 269.435261 -201.845992) (xy 269.427452 -201.845672)
			(xy 268.911578 -201.845672) (xy 268.906214 -201.845165) (xy 268.89863 -201.837575) (xy 268.898116 -201.83221)
			(xy 266.298172 -201.83221) (xy 266.297657 -201.837573) (xy 266.290073 -201.845157) (xy 266.28471 -201.845672)
			(xy 265.768836 -201.845672) (xy 265.761026 -201.845989) (xy 265.746154 -201.850771) (xy 265.739626 -201.85507)
			(xy 265.718496 -201.869406) (xy 265.672775 -201.892135) (xy 265.624104 -201.907569) (xy 265.57364 -201.91534)
			(xy 265.54811 -201.915776) (xy 265.52258 -201.915332) (xy 265.472117 -201.907558) (xy 265.423444 -201.892131)
			(xy 265.377716 -201.869416) (xy 265.356594 -201.85507) (xy 265.350059 -201.850784) (xy 265.335192 -201.845997)
			(xy 265.327384 -201.845672) (xy 264.81151 -201.845672) (xy 264.80615 -201.845144) (xy 264.798564 -201.837569)
			(xy 264.798048 -201.83221) (xy 256.30886 -201.83221) (xy 256.30886 -202.662536) (xy 256.308511 -202.682094)
			(xy 264.798048 -202.682094) (xy 264.798048 -202.187556) (xy 264.798561 -202.182299) (xy 264.805999 -202.174861)
			(xy 264.811256 -202.174348) (xy 264.811764 -202.174348) (xy 265.327638 -202.174348) (xy 265.335447 -202.174017)
			(xy 265.350318 -202.169244) (xy 265.356848 -202.16495) (xy 265.377937 -202.150601) (xy 265.423598 -202.12787)
			(xy 265.472204 -202.112411) (xy 265.522607 -202.104588) (xy 265.573613 -202.104588) (xy 265.624016 -202.112411)
			(xy 265.672622 -202.12787) (xy 265.718283 -202.150601) (xy 265.739372 -202.16495) (xy 265.745913 -202.169224)
			(xy 265.760776 -202.174019) (xy 265.768582 -202.174348) (xy 266.28471 -202.174348) (xy 266.290017 -202.174817)
			(xy 266.297588 -202.182258) (xy 266.298172 -202.187556) (xy 266.298172 -202.682094) (xy 266.298147 -202.682348)
			(xy 272.342356 -202.682348) (xy 272.342356 -202.68184) (xy 272.342356 -202.187556) (xy 272.342862 -202.182297)
			(xy 272.350304 -202.174859) (xy 272.355564 -202.174348) (xy 272.871692 -202.174348) (xy 272.879503 -202.174039)
			(xy 272.894374 -202.169251) (xy 272.900902 -202.16495) (xy 272.921991 -202.150601) (xy 272.967652 -202.12787)
			(xy 273.016258 -202.112411) (xy 273.066661 -202.104588) (xy 273.117667 -202.104588) (xy 273.16807 -202.112411)
			(xy 273.216676 -202.12787) (xy 273.262337 -202.150601) (xy 273.283426 -202.16495) (xy 273.289955 -202.169245)
			(xy 273.304827 -202.174027) (xy 273.312636 -202.174348) (xy 273.828764 -202.174348) (xy 273.834012 -202.174914)
			(xy 273.841454 -202.182311) (xy 273.841972 -202.187556) (xy 273.841972 -202.682094) (xy 273.841948 -202.682348)
			(xy 279.886156 -202.682348) (xy 279.886156 -202.68184) (xy 279.886156 -202.187556) (xy 279.886662 -202.182297)
			(xy 279.894104 -202.174859) (xy 279.899364 -202.174348) (xy 280.415492 -202.174348) (xy 280.423303 -202.174039)
			(xy 280.438174 -202.169251) (xy 280.444702 -202.16495) (xy 280.465791 -202.150601) (xy 280.511452 -202.12787)
			(xy 280.560058 -202.112411) (xy 280.610461 -202.104588) (xy 280.661467 -202.104588) (xy 280.71187 -202.112411)
			(xy 280.760476 -202.12787) (xy 280.806137 -202.150601) (xy 280.827226 -202.16495) (xy 280.833755 -202.169245)
			(xy 280.848627 -202.174027) (xy 280.856436 -202.174348) (xy 281.372564 -202.174348) (xy 281.377812 -202.174914)
			(xy 281.385254 -202.182311) (xy 281.385772 -202.187556) (xy 281.385772 -202.682094) (xy 287.429956 -202.682094)
			(xy 287.429956 -202.187556) (xy 287.430462 -202.182297) (xy 287.437904 -202.174859) (xy 287.443164 -202.174348)
			(xy 287.443672 -202.174348) (xy 287.959546 -202.174348) (xy 287.967355 -202.17402) (xy 287.982227 -202.169245)
			(xy 287.988756 -202.16495) (xy 288.009845 -202.150601) (xy 288.055506 -202.12787) (xy 288.104112 -202.112411)
			(xy 288.154515 -202.104588) (xy 288.205521 -202.104588) (xy 288.255924 -202.112411) (xy 288.30453 -202.12787)
			(xy 288.350191 -202.150601) (xy 288.37128 -202.16495) (xy 288.37782 -202.169227) (xy 288.392683 -202.17402)
			(xy 288.40049 -202.174348) (xy 288.916618 -202.174348) (xy 288.921926 -202.174812) (xy 288.929497 -202.182257)
			(xy 288.93008 -202.187556) (xy 288.93008 -202.682094) (xy 288.930055 -202.682348) (xy 294.974264 -202.682348)
			(xy 294.974264 -202.68184) (xy 294.974264 -202.187556) (xy 294.974763 -202.182295) (xy 294.98221 -202.174856)
			(xy 294.987472 -202.174348) (xy 295.5036 -202.174348) (xy 295.511411 -202.174043) (xy 295.526283 -202.169252)
			(xy 295.53281 -202.16495) (xy 295.553899 -202.150601) (xy 295.59956 -202.12787) (xy 295.648166 -202.112411)
			(xy 295.698569 -202.104588) (xy 295.749575 -202.104588) (xy 295.799978 -202.112411) (xy 295.848584 -202.12787)
			(xy 295.894245 -202.150601) (xy 295.915334 -202.16495) (xy 295.921862 -202.169248) (xy 295.936735 -202.174028)
			(xy 295.944544 -202.174348) (xy 296.460672 -202.174348) (xy 296.465921 -202.174909) (xy 296.473362 -202.18231)
			(xy 296.47388 -202.187556) (xy 296.47388 -202.682094) (xy 302.518064 -202.682094) (xy 302.518064 -202.187556)
			(xy 302.518563 -202.182295) (xy 302.52601 -202.174856) (xy 302.531272 -202.174348) (xy 304.004726 -202.174348)
			(xy 304.010035 -202.174807) (xy 304.017605 -202.182256) (xy 304.018188 -202.187556) (xy 304.018188 -202.682094)
			(xy 304.018162 -202.682348) (xy 411.618176 -202.682348) (xy 411.618176 -202.68184) (xy 411.618176 -202.187556)
			(xy 411.618664 -202.182292) (xy 411.626119 -202.174853) (xy 411.631384 -202.174348) (xy 413.104584 -202.174348)
			(xy 413.109834 -202.174901) (xy 413.117275 -202.182308) (xy 413.117792 -202.187556) (xy 413.117792 -202.682094)
			(xy 419.161976 -202.682094) (xy 419.161976 -202.187556) (xy 419.162464 -202.182292) (xy 419.169919 -202.174853)
			(xy 419.175184 -202.174348) (xy 419.175692 -202.174348) (xy 419.691566 -202.174348) (xy 419.699376 -202.174028)
			(xy 419.714247 -202.169247) (xy 419.720776 -202.16495) (xy 419.741865 -202.150601) (xy 419.787526 -202.12787)
			(xy 419.836132 -202.112411) (xy 419.886535 -202.104588) (xy 419.937541 -202.104588) (xy 419.987944 -202.112411)
			(xy 420.03655 -202.12787) (xy 420.082211 -202.150601) (xy 420.1033 -202.16495) (xy 420.109835 -202.169235)
			(xy 420.124702 -202.174023) (xy 420.13251 -202.174348) (xy 420.648638 -202.174348) (xy 420.653949 -202.174799)
			(xy 420.661518 -202.182254) (xy 420.6621 -202.187556) (xy 420.6621 -202.682094) (xy 420.662074 -202.682348)
			(xy 426.706284 -202.682348) (xy 426.706284 -202.68184) (xy 426.706284 -202.187556) (xy 426.706765 -202.18229)
			(xy 426.714225 -202.17485) (xy 426.719492 -202.174348) (xy 427.23562 -202.174348) (xy 427.243432 -202.174052)
			(xy 427.258304 -202.169255) (xy 427.26483 -202.16495) (xy 427.285919 -202.150601) (xy 427.33158 -202.12787)
			(xy 427.380186 -202.112411) (xy 427.430589 -202.104588) (xy 427.481595 -202.104588) (xy 427.531998 -202.112411)
			(xy 427.580604 -202.12787) (xy 427.626265 -202.150601) (xy 427.647354 -202.16495) (xy 427.653877 -202.169256)
			(xy 427.668753 -202.174031) (xy 427.676564 -202.174348) (xy 428.192692 -202.174348) (xy 428.197943 -202.174895)
			(xy 428.205384 -202.182307) (xy 428.2059 -202.187556) (xy 428.2059 -202.682094) (xy 434.250084 -202.682094)
			(xy 434.250084 -202.187556) (xy 434.250565 -202.18229) (xy 434.258025 -202.17485) (xy 434.263292 -202.174348)
			(xy 434.2638 -202.174348) (xy 434.779674 -202.174348) (xy 434.787484 -202.174032) (xy 434.802356 -202.169248)
			(xy 434.808884 -202.16495) (xy 434.829973 -202.150601) (xy 434.875634 -202.12787) (xy 434.92424 -202.112411)
			(xy 434.974643 -202.104588) (xy 435.025649 -202.104588) (xy 435.076052 -202.112411) (xy 435.124658 -202.12787)
			(xy 435.170319 -202.150601) (xy 435.191408 -202.16495) (xy 435.197941 -202.169238) (xy 435.21281 -202.174024)
			(xy 435.220618 -202.174348) (xy 435.736746 -202.174348) (xy 435.742046 -202.17486) (xy 435.74962 -202.182268)
			(xy 435.750208 -202.187556) (xy 435.750208 -202.682094) (xy 435.750182 -202.682348) (xy 441.794392 -202.682348)
			(xy 441.794392 -202.68184) (xy 441.794392 -202.187556) (xy 441.794866 -202.182288) (xy 441.80233 -202.174848)
			(xy 441.8076 -202.174348) (xy 442.323728 -202.174348) (xy 442.33154 -202.174055) (xy 442.346412 -202.169256)
			(xy 442.352938 -202.16495) (xy 442.374027 -202.150601) (xy 442.419688 -202.12787) (xy 442.468294 -202.112411)
			(xy 442.518697 -202.104588) (xy 442.569703 -202.104588) (xy 442.620106 -202.112411) (xy 442.668712 -202.12787)
			(xy 442.714373 -202.150601) (xy 442.735462 -202.16495) (xy 442.742006 -202.169221) (xy 442.756866 -202.174017)
			(xy 442.764672 -202.174348) (xy 443.2808 -202.174348) (xy 443.286052 -202.17489) (xy 443.293492 -202.182306)
			(xy 443.294008 -202.187556) (xy 443.294008 -202.682094) (xy 443.293983 -202.682348) (xy 449.338192 -202.682348)
			(xy 449.338192 -202.68184) (xy 449.338192 -202.187556) (xy 449.338666 -202.182288) (xy 449.34613 -202.174848)
			(xy 449.3514 -202.174348) (xy 449.867528 -202.174348) (xy 449.87534 -202.174055) (xy 449.890212 -202.169256)
			(xy 449.896738 -202.16495) (xy 449.917827 -202.150601) (xy 449.963488 -202.12787) (xy 450.012094 -202.112411)
			(xy 450.062497 -202.104588) (xy 450.113503 -202.104588) (xy 450.163906 -202.112411) (xy 450.212512 -202.12787)
			(xy 450.258173 -202.150601) (xy 450.279262 -202.16495) (xy 450.285806 -202.169221) (xy 450.300666 -202.174017)
			(xy 450.308472 -202.174348) (xy 450.8246 -202.174348) (xy 450.829852 -202.17489) (xy 450.837292 -202.182306)
			(xy 450.837808 -202.187556) (xy 450.837808 -202.682094) (xy 450.837279 -202.687386) (xy 450.82988 -202.694955)
			(xy 450.8246 -202.695556) (xy 450.308726 -202.695556) (xy 450.300916 -202.695871) (xy 450.286044 -202.700655)
			(xy 450.279516 -202.704954) (xy 450.258388 -202.719293) (xy 450.212666 -202.742022) (xy 450.163995 -202.757455)
			(xy 450.11353 -202.765225) (xy 450.088 -202.76566) (xy 450.06247 -202.765224) (xy 450.012006 -202.757448)
			(xy 449.963333 -202.742019) (xy 449.917606 -202.719302) (xy 449.896484 -202.704954) (xy 449.889952 -202.700663)
			(xy 449.875083 -202.695879) (xy 449.867274 -202.695556) (xy 449.3514 -202.695556) (xy 449.346149 -202.69501)
			(xy 449.338709 -202.687597) (xy 449.338192 -202.682348) (xy 443.293983 -202.682348) (xy 443.293479 -202.687386)
			(xy 443.28608 -202.694955) (xy 443.2808 -202.695556) (xy 442.764926 -202.695556) (xy 442.757116 -202.695871)
			(xy 442.742244 -202.700655) (xy 442.735716 -202.704954) (xy 442.714588 -202.719293) (xy 442.668866 -202.742022)
			(xy 442.620195 -202.757455) (xy 442.56973 -202.765225) (xy 442.5442 -202.76566) (xy 442.51867 -202.765224)
			(xy 442.468206 -202.757448) (xy 442.419533 -202.742019) (xy 442.373806 -202.719302) (xy 442.352684 -202.704954)
			(xy 442.346152 -202.700663) (xy 442.331283 -202.695879) (xy 442.323474 -202.695556) (xy 441.8076 -202.695556)
			(xy 441.802349 -202.69501) (xy 441.794909 -202.687597) (xy 441.794392 -202.682348) (xy 435.750182 -202.682348)
			(xy 435.74965 -202.687446) (xy 435.742096 -202.69503) (xy 435.736746 -202.695556) (xy 435.220872 -202.695556)
			(xy 435.21306 -202.695848) (xy 435.198188 -202.700648) (xy 435.191662 -202.704954) (xy 435.170549 -202.719316)
			(xy 435.124822 -202.74204) (xy 435.076146 -202.757466) (xy 435.025678 -202.765229) (xy 435.000146 -202.76566)
			(xy 434.974617 -202.765201) (xy 434.924154 -202.757432) (xy 434.875481 -202.74201) (xy 434.829753 -202.719299)
			(xy 434.80863 -202.704954) (xy 434.802088 -202.700681) (xy 434.787226 -202.695886) (xy 434.77942 -202.695556)
			(xy 434.263546 -202.695556) (xy 434.258116 -202.695189) (xy 434.250427 -202.687523) (xy 434.250084 -202.682094)
			(xy 428.2059 -202.682094) (xy 428.205378 -202.687388) (xy 428.197974 -202.694957) (xy 428.192692 -202.695556)
			(xy 427.676818 -202.695556) (xy 427.669008 -202.695868) (xy 427.654136 -202.700654) (xy 427.647608 -202.704954)
			(xy 427.626482 -202.719296) (xy 427.58076 -202.742024) (xy 427.532088 -202.757456) (xy 427.481623 -202.765226)
			(xy 427.456092 -202.76566) (xy 427.430562 -202.765228) (xy 427.380097 -202.757451) (xy 427.331425 -202.742021)
			(xy 427.285698 -202.719302) (xy 427.264576 -202.704954) (xy 427.258046 -202.70066) (xy 427.243175 -202.695878)
			(xy 427.235366 -202.695556) (xy 426.719492 -202.695556) (xy 426.71424 -202.695016) (xy 426.7068 -202.687599)
			(xy 426.706284 -202.682348) (xy 420.662074 -202.682348) (xy 420.66155 -202.687448) (xy 420.65399 -202.695032)
			(xy 420.648638 -202.695556) (xy 420.132764 -202.695556) (xy 420.124955 -202.695888) (xy 420.110083 -202.70066)
			(xy 420.103554 -202.704954) (xy 420.082443 -202.71932) (xy 420.036715 -202.742043) (xy 419.988039 -202.757468)
			(xy 419.93757 -202.76523) (xy 419.912038 -202.76566) (xy 419.886508 -202.765205) (xy 419.836045 -202.757435)
			(xy 419.787373 -202.742011) (xy 419.741645 -202.719299) (xy 419.720522 -202.704954) (xy 419.713982 -202.700678)
			(xy 419.699119 -202.695885) (xy 419.691312 -202.695556) (xy 419.175438 -202.695556) (xy 419.170007 -202.695195)
			(xy 419.162318 -202.687524) (xy 419.161976 -202.682094) (xy 413.117792 -202.682094) (xy 413.117277 -202.68739)
			(xy 413.109868 -202.69496) (xy 413.104584 -202.695556) (xy 411.631384 -202.695556) (xy 411.626131 -202.695021)
			(xy 411.618692 -202.6876) (xy 411.618176 -202.682348) (xy 304.018162 -202.682348) (xy 304.017648 -202.687451)
			(xy 304.010082 -202.695036) (xy 304.004726 -202.695556) (xy 302.531526 -202.695556) (xy 302.526093 -202.695203)
			(xy 302.518405 -202.687526) (xy 302.518064 -202.682094) (xy 296.47388 -202.682094) (xy 296.473375 -202.687393)
			(xy 296.46596 -202.694963) (xy 296.460672 -202.695556) (xy 295.944798 -202.695556) (xy 295.936987 -202.69586)
			(xy 295.922115 -202.700652) (xy 295.915588 -202.704954) (xy 295.894467 -202.719305) (xy 295.848743 -202.742031)
			(xy 295.80007 -202.757461) (xy 295.749603 -202.765227) (xy 295.724072 -202.76566) (xy 295.698541 -202.765238)
			(xy 295.648077 -202.757458) (xy 295.599404 -202.742025) (xy 295.553677 -202.719304) (xy 295.532556 -202.704954)
			(xy 295.52603 -202.700652) (xy 295.511156 -202.695875) (xy 295.503346 -202.695556) (xy 294.987472 -202.695556)
			(xy 294.982217 -202.695029) (xy 294.974779 -202.687602) (xy 294.974264 -202.682348) (xy 288.930055 -202.682348)
			(xy 288.929548 -202.687453) (xy 288.921976 -202.695038) (xy 288.916618 -202.695556) (xy 288.400744 -202.695556)
			(xy 288.392935 -202.695879) (xy 288.378063 -202.700658) (xy 288.371534 -202.704954) (xy 288.350429 -202.719328)
			(xy 288.304699 -202.742049) (xy 288.256021 -202.757472) (xy 288.20555 -202.765231) (xy 288.180018 -202.76566)
			(xy 288.154488 -202.765215) (xy 288.104025 -202.757442) (xy 288.055352 -202.742015) (xy 288.009624 -202.719301)
			(xy 287.988502 -202.704954) (xy 287.981966 -202.70067) (xy 287.9671 -202.695882) (xy 287.959292 -202.695556)
			(xy 287.443418 -202.695556) (xy 287.437984 -202.695208) (xy 287.430297 -202.687528) (xy 287.429956 -202.682094)
			(xy 281.385772 -202.682094) (xy 281.385274 -202.687395) (xy 281.377854 -202.694965) (xy 281.372564 -202.695556)
			(xy 280.85669 -202.695556) (xy 280.848878 -202.695856) (xy 280.834007 -202.70065) (xy 280.82748 -202.704954)
			(xy 280.806362 -202.719308) (xy 280.760637 -202.742034) (xy 280.711962 -202.757462) (xy 280.661495 -202.765228)
			(xy 280.635964 -202.76566) (xy 280.610433 -202.765242) (xy 280.559968 -202.757461) (xy 280.511296 -202.742026)
			(xy 280.465569 -202.719304) (xy 280.444448 -202.704954) (xy 280.437924 -202.700649) (xy 280.423048 -202.695874)
			(xy 280.415238 -202.695556) (xy 279.899364 -202.695556) (xy 279.894109 -202.695034) (xy 279.886671 -202.687603)
			(xy 279.886156 -202.682348) (xy 273.841948 -202.682348) (xy 273.841474 -202.687395) (xy 273.834054 -202.694965)
			(xy 273.828764 -202.695556) (xy 273.31289 -202.695556) (xy 273.305078 -202.695856) (xy 273.290207 -202.70065)
			(xy 273.28368 -202.704954) (xy 273.262562 -202.719308) (xy 273.216837 -202.742034) (xy 273.168162 -202.757462)
			(xy 273.117695 -202.765228) (xy 273.092164 -202.76566) (xy 273.066633 -202.765242) (xy 273.016168 -202.757461)
			(xy 272.967496 -202.742026) (xy 272.921769 -202.719304) (xy 272.900648 -202.704954) (xy 272.894124 -202.700649)
			(xy 272.879248 -202.695874) (xy 272.871438 -202.695556) (xy 272.355564 -202.695556) (xy 272.350309 -202.695034)
			(xy 272.342871 -202.687603) (xy 272.342356 -202.682348) (xy 266.298147 -202.682348) (xy 266.297647 -202.687455)
			(xy 266.29007 -202.69504) (xy 266.28471 -202.695556) (xy 265.768836 -202.695556) (xy 265.761026 -202.695876)
			(xy 265.746155 -202.700657) (xy 265.739626 -202.704954) (xy 265.718495 -202.719288) (xy 265.672774 -202.742018)
			(xy 265.624104 -202.757453) (xy 265.57364 -202.765224) (xy 265.54811 -202.76566) (xy 265.52258 -202.765219)
			(xy 265.472116 -202.757445) (xy 265.423444 -202.742017) (xy 265.377716 -202.719301) (xy 265.356594 -202.704954)
			(xy 265.35006 -202.700667) (xy 265.335192 -202.69588) (xy 265.327384 -202.695556) (xy 264.81151 -202.695556)
			(xy 264.806075 -202.695214) (xy 264.798388 -202.687529) (xy 264.798048 -202.682094) (xy 256.308511 -202.682094)
			(xy 256.308374 -202.689805) (xy 256.300612 -202.743789) (xy 256.285247 -202.796119) (xy 256.26259 -202.845729)
			(xy 256.233104 -202.89161) (xy 256.197389 -202.932827) (xy 256.156172 -202.968542) (xy 256.110291 -202.998028)
			(xy 256.060681 -203.020685) (xy 256.008351 -203.03605) (xy 255.954367 -203.043812) (xy 255.899829 -203.043812)
			(xy 255.845845 -203.03605) (xy 255.793515 -203.020685) (xy 255.743905 -202.998028) (xy 255.698024 -202.968542)
			(xy 255.656807 -202.932827) (xy 255.621092 -202.89161) (xy 255.591606 -202.845729) (xy 255.568949 -202.796119)
			(xy 255.553584 -202.743789) (xy 255.545822 -202.689805) (xy 255.545336 -202.662536) (xy 202.89774 -202.662536)
			(xy 202.89774 -202.682348) (xy 202.89724 -202.687609) (xy 202.889793 -202.695047) (xy 202.884532 -202.695556)
			(xy 202.368658 -202.695556) (xy 202.360782 -202.695832) (xy 202.345779 -202.700624) (xy 202.339194 -202.704954)
			(xy 202.318109 -202.719334) (xy 202.272467 -202.742165) (xy 202.223863 -202.757726) (xy 202.173448 -202.765649)
			(xy 202.147932 -202.766168) (xy 202.122411 -202.765685) (xy 202.071984 -202.75779) (xy 202.023372 -202.742228)
			(xy 201.977734 -202.719371) (xy 201.95667 -202.704954) (xy 201.950084 -202.70063) (xy 201.93508 -202.695848)
			(xy 201.927206 -202.695556) (xy 201.411332 -202.695556) (xy 201.406084 -202.694989) (xy 201.398643 -202.687592)
			(xy 201.398124 -202.682348) (xy 195.35394 -202.682348) (xy 195.35344 -202.687609) (xy 195.345993 -202.695047)
			(xy 195.340732 -202.695556) (xy 194.824858 -202.695556) (xy 194.816982 -202.695832) (xy 194.801979 -202.700624)
			(xy 194.795394 -202.704954) (xy 194.774309 -202.719334) (xy 194.728667 -202.742165) (xy 194.680063 -202.757726)
			(xy 194.629648 -202.765649) (xy 194.604132 -202.766168) (xy 194.578611 -202.765685) (xy 194.528184 -202.75779)
			(xy 194.479572 -202.742228) (xy 194.433934 -202.719371) (xy 194.41287 -202.704954) (xy 194.406284 -202.70063)
			(xy 194.39128 -202.695848) (xy 194.383406 -202.695556) (xy 193.867532 -202.695556) (xy 193.862284 -202.694989)
			(xy 193.854843 -202.687592) (xy 193.854324 -202.682348) (xy 187.81014 -202.682348) (xy 187.80964 -202.687609)
			(xy 187.802193 -202.695047) (xy 187.796932 -202.695556) (xy 187.796424 -202.695556) (xy 187.280804 -202.695556)
			(xy 187.27293 -202.695852) (xy 187.257926 -202.70063) (xy 187.25134 -202.704954) (xy 187.23027 -202.719357)
			(xy 187.184622 -202.742183) (xy 187.136014 -202.757737) (xy 187.085595 -202.765653) (xy 187.060078 -202.766168)
			(xy 187.034558 -202.765662) (xy 186.984132 -202.757773) (xy 186.93552 -202.742218) (xy 186.889881 -202.719368)
			(xy 186.868816 -202.704954) (xy 186.862219 -202.700648) (xy 186.847223 -202.695855) (xy 186.839352 -202.695556)
			(xy 186.323478 -202.695556) (xy 186.31817 -202.695091) (xy 186.3106 -202.687647) (xy 186.310016 -202.682348)
			(xy 180.265832 -202.682348) (xy 180.265339 -202.687611) (xy 180.257888 -202.695049) (xy 180.252624 -202.695556)
			(xy 179.73675 -202.695556) (xy 179.728874 -202.695829) (xy 179.71387 -202.700623) (xy 179.707286 -202.704954)
			(xy 179.686203 -202.719337) (xy 179.64056 -202.742167) (xy 179.591956 -202.757727) (xy 179.54154 -202.765649)
			(xy 179.516024 -202.766168) (xy 179.490503 -202.765689) (xy 179.440076 -202.757792) (xy 179.391464 -202.742229)
			(xy 179.345826 -202.719371) (xy 179.324762 -202.704954) (xy 179.318178 -202.700627) (xy 179.303172 -202.695847)
			(xy 179.295298 -202.695556) (xy 178.779424 -202.695556) (xy 178.774176 -202.694994) (xy 178.766735 -202.687593)
			(xy 178.766216 -202.682348) (xy 172.722032 -202.682348) (xy 172.721539 -202.687611) (xy 172.714088 -202.695049)
			(xy 172.708824 -202.695556) (xy 172.708316 -202.695556) (xy 172.192696 -202.695556) (xy 172.184822 -202.695849)
			(xy 172.169818 -202.700629) (xy 172.163232 -202.704954) (xy 172.142164 -202.719361) (xy 172.096516 -202.742185)
			(xy 172.047907 -202.757739) (xy 171.997488 -202.765653) (xy 171.97197 -202.766168) (xy 171.94645 -202.765666)
			(xy 171.896024 -202.757776) (xy 171.847412 -202.74222) (xy 171.801773 -202.719368) (xy 171.780708 -202.704954)
			(xy 171.774113 -202.700645) (xy 171.759116 -202.695853) (xy 171.751244 -202.695556) (xy 171.23537 -202.695556)
			(xy 171.230061 -202.695096) (xy 171.222491 -202.687648) (xy 171.221908 -202.682348) (xy 165.177724 -202.682348)
			(xy 165.177239 -202.687613) (xy 165.169782 -202.695051) (xy 165.164516 -202.695556) (xy 163.691316 -202.695556)
			(xy 163.686067 -202.695) (xy 163.678626 -202.687595) (xy 163.678108 -202.682348) (xy 56.07812 -202.682348)
			(xy 56.077638 -202.687614) (xy 56.070179 -202.695053) (xy 56.064912 -202.695556) (xy 54.591458 -202.695556)
			(xy 54.586148 -202.695104) (xy 54.578579 -202.68765) (xy 54.577996 -202.682348) (xy 48.533812 -202.682348)
			(xy 48.533337 -202.687616) (xy 48.525873 -202.695055) (xy 48.520604 -202.695556) (xy 48.00473 -202.695556)
			(xy 47.996853 -202.69582) (xy 47.981849 -202.70062) (xy 47.975266 -202.704954) (xy 47.954189 -202.719346)
			(xy 47.908544 -202.742174) (xy 47.859938 -202.757732) (xy 47.809521 -202.765651) (xy 47.784004 -202.766168)
			(xy 47.758483 -202.765699) (xy 47.708055 -202.757799) (xy 47.659443 -202.742233) (xy 47.613806 -202.719372)
			(xy 47.592742 -202.704954) (xy 47.586162 -202.700619) (xy 47.571153 -202.695844) (xy 47.563278 -202.695556)
			(xy 47.047404 -202.695556) (xy 47.042153 -202.695008) (xy 47.034713 -202.687597) (xy 47.034196 -202.682348)
			(xy 40.990012 -202.682348) (xy 40.989537 -202.687616) (xy 40.982073 -202.695055) (xy 40.976804 -202.695556)
			(xy 40.976296 -202.695556) (xy 40.460676 -202.695556) (xy 40.452801 -202.69584) (xy 40.437797 -202.700626)
			(xy 40.431212 -202.704954) (xy 40.41015 -202.719369) (xy 40.3645 -202.742192) (xy 40.315889 -202.757743)
			(xy 40.265468 -202.765655) (xy 40.23995 -202.766168) (xy 40.21443 -202.765676) (xy 40.164003 -202.757783)
			(xy 40.115391 -202.742224) (xy 40.069753 -202.719369) (xy 40.048688 -202.704954) (xy 40.042098 -202.700637)
			(xy 40.027097 -202.69585) (xy 40.019224 -202.695556) (xy 39.50335 -202.695556) (xy 39.498051 -202.695043)
			(xy 39.490477 -202.687635) (xy 39.489888 -202.682348) (xy 33.445704 -202.682348) (xy 33.445237 -202.687618)
			(xy 33.437767 -202.695057) (xy 33.432496 -202.695556) (xy 32.916622 -202.695556) (xy 32.908749 -202.69586)
			(xy 32.893745 -202.700632) (xy 32.887158 -202.704954) (xy 32.866083 -202.719349) (xy 32.820437 -202.742177)
			(xy 32.771831 -202.757733) (xy 32.721413 -202.765651) (xy 32.695896 -202.766168) (xy 32.670375 -202.765703)
			(xy 32.619947 -202.757802) (xy 32.571335 -202.742235) (xy 32.525698 -202.719373) (xy 32.504634 -202.704954)
			(xy 32.498033 -202.700655) (xy 32.48304 -202.695857) (xy 32.47517 -202.695556) (xy 31.959296 -202.695556)
			(xy 31.954044 -202.695013) (xy 31.946605 -202.687598) (xy 31.946088 -202.682348) (xy 25.901904 -202.682348)
			(xy 25.901437 -202.687618) (xy 25.893967 -202.695057) (xy 25.888696 -202.695556) (xy 25.372822 -202.695556)
			(xy 25.364949 -202.69586) (xy 25.349945 -202.700632) (xy 25.343358 -202.704954) (xy 25.322283 -202.719349)
			(xy 25.276637 -202.742177) (xy 25.228031 -202.757733) (xy 25.177613 -202.765651) (xy 25.152096 -202.766168)
			(xy 25.126575 -202.765703) (xy 25.076147 -202.757802) (xy 25.027535 -202.742235) (xy 24.981898 -202.719373)
			(xy 24.960834 -202.704954) (xy 24.954233 -202.700655) (xy 24.93924 -202.695857) (xy 24.93137 -202.695556)
			(xy 24.415496 -202.695556) (xy 24.410244 -202.695013) (xy 24.402805 -202.687598) (xy 24.402288 -202.682348)
			(xy 18.358104 -202.682348) (xy 18.357637 -202.687618) (xy 18.350167 -202.695057) (xy 18.344896 -202.695556)
			(xy 18.344388 -202.695556) (xy 17.828768 -202.695556) (xy 17.820893 -202.695837) (xy 17.805889 -202.700625)
			(xy 17.799304 -202.704954) (xy 17.778216 -202.71933) (xy 17.732575 -202.742161) (xy 17.683972 -202.757724)
			(xy 17.633558 -202.765648) (xy 17.608042 -202.766168) (xy 17.582522 -202.76568) (xy 17.532094 -202.757786)
			(xy 17.483483 -202.742226) (xy 17.437845 -202.71937) (xy 17.41678 -202.704954) (xy 17.410192 -202.700634)
			(xy 17.395189 -202.695849) (xy 17.387316 -202.695556) (xy 16.871442 -202.695556) (xy 16.866142 -202.695048)
			(xy 16.858568 -202.687637) (xy 16.85798 -202.682348) (xy 2.509012 -202.682348) (xy 2.509012 -203.532486)
			(xy 20.958048 -203.532486) (xy 20.958048 -203.037948) (xy 20.958455 -203.032633) (xy 20.965943 -203.025092)
			(xy 20.971256 -203.02474) (xy 20.971764 -203.02474) (xy 21.487638 -203.02474) (xy 21.495447 -203.02441)
			(xy 21.510319 -203.019636) (xy 21.516848 -203.015342) (xy 21.537937 -203.000993) (xy 21.583598 -202.978262)
			(xy 21.632204 -202.962803) (xy 21.682607 -202.95498) (xy 21.733613 -202.95498) (xy 21.784016 -202.962803)
			(xy 21.832622 -202.978262) (xy 21.878283 -203.000993) (xy 21.899372 -203.015342) (xy 21.905914 -203.019616)
			(xy 21.920776 -203.024411) (xy 21.928582 -203.02474) (xy 22.44471 -203.02474) (xy 22.450015 -203.025217)
			(xy 22.457586 -203.032652) (xy 22.458172 -203.037948) (xy 22.458172 -203.532486) (xy 22.458155 -203.53274)
			(xy 28.502356 -203.53274) (xy 28.502356 -203.532232) (xy 28.502356 -203.037948) (xy 28.502756 -203.032631)
			(xy 28.510249 -203.02509) (xy 28.515564 -203.02474) (xy 29.031692 -203.02474) (xy 29.039503 -203.024433)
			(xy 29.054375 -203.019643) (xy 29.060902 -203.015342) (xy 29.081991 -203.000993) (xy 29.127652 -202.978262)
			(xy 29.176258 -202.962803) (xy 29.226661 -202.95498) (xy 29.277667 -202.95498) (xy 29.32807 -202.962803)
			(xy 29.376676 -202.978262) (xy 29.422337 -203.000993) (xy 29.443426 -203.015342) (xy 29.449956 -203.019636)
			(xy 29.464827 -203.024418) (xy 29.472636 -203.02474) (xy 29.988764 -203.02474) (xy 29.994103 -203.025056)
			(xy 30.001649 -203.032609) (xy 30.001972 -203.037948) (xy 30.001972 -203.532486) (xy 30.001948 -203.53274)
			(xy 36.046156 -203.53274) (xy 36.046156 -203.532232) (xy 36.046156 -203.037948) (xy 36.046556 -203.032631)
			(xy 36.054049 -203.02509) (xy 36.059364 -203.02474) (xy 36.575492 -203.02474) (xy 36.583303 -203.024433)
			(xy 36.598175 -203.019643) (xy 36.604702 -203.015342) (xy 36.625791 -203.000993) (xy 36.671452 -202.978262)
			(xy 36.720058 -202.962803) (xy 36.770461 -202.95498) (xy 36.821467 -202.95498) (xy 36.87187 -202.962803)
			(xy 36.920476 -202.978262) (xy 36.966137 -203.000993) (xy 36.987226 -203.015342) (xy 36.993756 -203.019636)
			(xy 37.008627 -203.024418) (xy 37.016436 -203.02474) (xy 37.532564 -203.02474) (xy 37.537903 -203.025056)
			(xy 37.545449 -203.032609) (xy 37.545772 -203.037948) (xy 37.545772 -203.532486) (xy 43.589956 -203.532486)
			(xy 43.589956 -203.037948) (xy 43.590356 -203.032631) (xy 43.597849 -203.02509) (xy 43.603164 -203.02474)
			(xy 43.603672 -203.02474) (xy 44.119546 -203.02474) (xy 44.127355 -203.024413) (xy 44.142227 -203.019637)
			(xy 44.148756 -203.015342) (xy 44.169845 -203.000993) (xy 44.215506 -202.978262) (xy 44.264112 -202.962803)
			(xy 44.314515 -202.95498) (xy 44.365521 -202.95498) (xy 44.415924 -202.962803) (xy 44.46453 -202.978262)
			(xy 44.510191 -203.000993) (xy 44.53128 -203.015342) (xy 44.53782 -203.019619) (xy 44.552683 -203.024412)
			(xy 44.56049 -203.02474) (xy 45.076618 -203.02474) (xy 45.081924 -203.025211) (xy 45.089495 -203.032651)
			(xy 45.09008 -203.037948) (xy 45.09008 -203.532486) (xy 45.090054 -203.53274) (xy 51.134264 -203.53274)
			(xy 51.134264 -203.532232) (xy 51.134264 -203.037948) (xy 51.134657 -203.032629) (xy 51.142155 -203.025087)
			(xy 51.147472 -203.02474) (xy 51.6636 -203.02474) (xy 51.671411 -203.024436) (xy 51.686283 -203.019644)
			(xy 51.69281 -203.015342) (xy 51.713899 -203.000993) (xy 51.75956 -202.978262) (xy 51.808166 -202.962803)
			(xy 51.858569 -202.95498) (xy 51.909575 -202.95498) (xy 51.959978 -202.962803) (xy 52.008584 -202.978262)
			(xy 52.054245 -203.000993) (xy 52.075334 -203.015342) (xy 52.081862 -203.019639) (xy 52.096735 -203.02442)
			(xy 52.104544 -203.02474) (xy 52.620672 -203.02474) (xy 52.626012 -203.02505) (xy 52.633558 -203.032607)
			(xy 52.63388 -203.037948) (xy 52.63388 -203.532486) (xy 58.678064 -203.532486) (xy 58.678064 -203.037948)
			(xy 58.678457 -203.032629) (xy 58.685955 -203.025087) (xy 58.691272 -203.02474) (xy 58.69178 -203.02474)
			(xy 60.164726 -203.02474) (xy 60.170033 -203.025206) (xy 60.177603 -203.03265) (xy 60.178188 -203.037948)
			(xy 60.178188 -203.532486) (xy 60.178162 -203.53274) (xy 167.778176 -203.53274) (xy 167.778176 -203.037948)
			(xy 167.778558 -203.032626) (xy 167.786064 -203.025083) (xy 167.791384 -203.02474) (xy 169.264584 -203.02474)
			(xy 169.269926 -203.025042) (xy 169.277471 -203.032605) (xy 169.277792 -203.037948) (xy 169.277792 -203.532486)
			(xy 175.321976 -203.532486) (xy 175.321976 -203.037948) (xy 175.322358 -203.032626) (xy 175.329864 -203.025083)
			(xy 175.335184 -203.02474) (xy 175.335692 -203.02474) (xy 175.851566 -203.02474) (xy 175.859376 -203.024422)
			(xy 175.874248 -203.01964) (xy 175.880776 -203.015342) (xy 175.901865 -203.000993) (xy 175.947526 -202.978262)
			(xy 175.996132 -202.962803) (xy 176.046535 -202.95498) (xy 176.097541 -202.95498) (xy 176.147944 -202.962803)
			(xy 176.19655 -202.978262) (xy 176.242211 -203.000993) (xy 176.2633 -203.015342) (xy 176.269836 -203.019626)
			(xy 176.284702 -203.024415) (xy 176.29251 -203.02474) (xy 176.808638 -203.02474) (xy 176.813947 -203.025198)
			(xy 176.821516 -203.032648) (xy 176.8221 -203.037948) (xy 176.8221 -203.532486) (xy 176.822074 -203.53274)
			(xy 182.866284 -203.53274) (xy 182.866284 -203.532232) (xy 182.866284 -203.037948) (xy 182.866659 -203.032624)
			(xy 182.87417 -203.025081) (xy 182.879492 -203.02474) (xy 183.39562 -203.02474) (xy 183.403432 -203.024445)
			(xy 183.418304 -203.019647) (xy 183.42483 -203.015342) (xy 183.445919 -203.000993) (xy 183.49158 -202.978262)
			(xy 183.540186 -202.962803) (xy 183.590589 -202.95498) (xy 183.641595 -202.95498) (xy 183.691998 -202.962803)
			(xy 183.740604 -202.978262) (xy 183.786265 -203.000993) (xy 183.807354 -203.015342) (xy 183.813878 -203.019647)
			(xy 183.828754 -203.024423) (xy 183.836564 -203.02474) (xy 184.352692 -203.02474) (xy 184.358035 -203.025037)
			(xy 184.365579 -203.032604) (xy 184.3659 -203.037948) (xy 184.3659 -203.532486) (xy 190.410084 -203.532486)
			(xy 190.410084 -203.037948) (xy 190.410459 -203.032624) (xy 190.41797 -203.025081) (xy 190.423292 -203.02474)
			(xy 190.4238 -203.02474) (xy 190.939674 -203.02474) (xy 190.947484 -203.024425) (xy 190.962356 -203.019641)
			(xy 190.968884 -203.015342) (xy 190.989973 -203.000993) (xy 191.035634 -202.978262) (xy 191.08424 -202.962803)
			(xy 191.134643 -202.95498) (xy 191.185649 -202.95498) (xy 191.236052 -202.962803) (xy 191.284658 -202.978262)
			(xy 191.330319 -203.000993) (xy 191.351408 -203.015342) (xy 191.357942 -203.019629) (xy 191.37281 -203.024416)
			(xy 191.380618 -203.02474) (xy 191.896746 -203.02474) (xy 191.902044 -203.025259) (xy 191.909618 -203.032663)
			(xy 191.910208 -203.037948) (xy 191.910208 -203.532486) (xy 191.910181 -203.53274) (xy 197.954392 -203.53274)
			(xy 197.954392 -203.532232) (xy 197.954392 -203.037948) (xy 197.954759 -203.032622) (xy 197.962276 -203.025079)
			(xy 197.9676 -203.02474) (xy 198.483728 -203.02474) (xy 198.49154 -203.024449) (xy 198.506412 -203.019648)
			(xy 198.512938 -203.015342) (xy 198.534027 -203.000993) (xy 198.579688 -202.978262) (xy 198.628294 -202.962803)
			(xy 198.678697 -202.95498) (xy 198.729703 -202.95498) (xy 198.780106 -202.962803) (xy 198.828712 -202.978262)
			(xy 198.874373 -203.000993) (xy 198.895462 -203.015342) (xy 198.902006 -203.019612) (xy 198.916866 -203.024409)
			(xy 198.924672 -203.02474) (xy 199.4408 -203.02474) (xy 199.446144 -203.025031) (xy 199.453688 -203.032603)
			(xy 199.454008 -203.037948) (xy 199.454008 -203.532486) (xy 199.453982 -203.53274) (xy 205.498192 -203.53274)
			(xy 205.498192 -203.532232) (xy 205.498192 -203.037948) (xy 205.498559 -203.032622) (xy 205.506076 -203.025079)
			(xy 205.5114 -203.02474) (xy 206.027528 -203.02474) (xy 206.03534 -203.024449) (xy 206.050212 -203.019648)
			(xy 206.056738 -203.015342) (xy 206.077827 -203.000993) (xy 206.123488 -202.978262) (xy 206.172094 -202.962803)
			(xy 206.222497 -202.95498) (xy 206.273503 -202.95498) (xy 206.323906 -202.962803) (xy 206.372512 -202.978262)
			(xy 206.418173 -203.000993) (xy 206.439262 -203.015342) (xy 206.445806 -203.019612) (xy 206.460666 -203.024409)
			(xy 206.468472 -203.02474) (xy 206.9846 -203.02474) (xy 206.989944 -203.025031) (xy 206.997488 -203.032603)
			(xy 206.997808 -203.037948) (xy 206.997808 -203.532232) (xy 268.898116 -203.532232) (xy 268.898116 -203.037694)
			(xy 268.898644 -203.032335) (xy 268.906219 -203.02475) (xy 268.911578 -203.024232) (xy 269.427706 -203.024232)
			(xy 269.435518 -203.023932) (xy 269.450389 -203.019138) (xy 269.456916 -203.014834) (xy 269.478005 -203.000485)
			(xy 269.523666 -202.977754) (xy 269.572272 -202.962295) (xy 269.622675 -202.954472) (xy 269.673681 -202.954472)
			(xy 269.724084 -202.962295) (xy 269.77269 -202.977754) (xy 269.818351 -203.000485) (xy 269.83944 -203.014834)
			(xy 269.845967 -203.019133) (xy 269.86084 -203.023912) (xy 269.86865 -203.024232) (xy 270.384778 -203.024232)
			(xy 270.390208 -203.024594) (xy 270.397895 -203.032264) (xy 270.39824 -203.037694) (xy 270.39824 -203.532232)
			(xy 276.442424 -203.532232) (xy 276.442424 -203.037694) (xy 276.442917 -203.032393) (xy 276.450341 -203.024823)
			(xy 276.455632 -203.024232) (xy 276.97176 -203.024232) (xy 276.97957 -203.023913) (xy 276.994442 -203.019132)
			(xy 277.00097 -203.014834) (xy 277.022059 -203.000485) (xy 277.06772 -202.977754) (xy 277.116326 -202.962295)
			(xy 277.166729 -202.954472) (xy 277.217735 -202.954472) (xy 277.268138 -202.962295) (xy 277.316744 -202.977754)
			(xy 277.362405 -203.000485) (xy 277.383494 -203.014834) (xy 277.390031 -203.019115) (xy 277.404897 -203.023906)
			(xy 277.412704 -203.024232) (xy 277.928832 -203.024232) (xy 277.934178 -203.024509) (xy 277.94172 -203.032092)
			(xy 277.94204 -203.03744) (xy 277.94204 -203.037948) (xy 277.94204 -203.532232) (xy 283.986224 -203.532232)
			(xy 283.986224 -203.037694) (xy 283.986717 -203.032393) (xy 283.994141 -203.024823) (xy 283.999432 -203.024232)
			(xy 284.51556 -203.024232) (xy 284.52337 -203.023913) (xy 284.538242 -203.019132) (xy 284.54477 -203.014834)
			(xy 284.565859 -203.000485) (xy 284.61152 -202.977754) (xy 284.660126 -202.962295) (xy 284.710529 -202.954472)
			(xy 284.761535 -202.954472) (xy 284.811938 -202.962295) (xy 284.860544 -202.977754) (xy 284.906205 -203.000485)
			(xy 284.927294 -203.014834) (xy 284.933831 -203.019115) (xy 284.948697 -203.023906) (xy 284.956504 -203.024232)
			(xy 285.472632 -203.024232) (xy 285.477978 -203.024509) (xy 285.48552 -203.032092) (xy 285.48584 -203.03744)
			(xy 285.48584 -203.037948) (xy 285.48584 -203.532232) (xy 291.530024 -203.532232) (xy 291.530024 -203.037694)
			(xy 291.530545 -203.032333) (xy 291.538125 -203.024748) (xy 291.543486 -203.024232) (xy 292.059614 -203.024232)
			(xy 292.067426 -203.023936) (xy 292.082298 -203.019139) (xy 292.088824 -203.014834) (xy 292.109913 -203.000485)
			(xy 292.155574 -202.977754) (xy 292.20418 -202.962295) (xy 292.254583 -202.954472) (xy 292.305589 -202.954472)
			(xy 292.355992 -202.962295) (xy 292.404598 -202.977754) (xy 292.450259 -203.000485) (xy 292.471348 -203.014834)
			(xy 292.477873 -203.019136) (xy 292.492748 -203.023914) (xy 292.500558 -203.024232) (xy 293.016686 -203.024232)
			(xy 293.022117 -203.024588) (xy 293.029804 -203.032263) (xy 293.030148 -203.037694) (xy 293.030148 -203.532232)
			(xy 299.074332 -203.532232) (xy 299.074332 -203.037694) (xy 299.074818 -203.032391) (xy 299.082247 -203.024821)
			(xy 299.08754 -203.024232) (xy 299.603668 -203.024232) (xy 299.611478 -203.023916) (xy 299.62635 -203.019133)
			(xy 299.632878 -203.014834) (xy 299.653967 -203.000485) (xy 299.699628 -202.977754) (xy 299.748234 -202.962295)
			(xy 299.798637 -202.954472) (xy 299.849643 -202.954472) (xy 299.900046 -202.962295) (xy 299.948652 -202.977754)
			(xy 299.994313 -203.000485) (xy 300.015402 -203.014834) (xy 300.021938 -203.019118) (xy 300.036804 -203.023907)
			(xy 300.044612 -203.024232) (xy 300.56074 -203.024232) (xy 300.566017 -203.024672) (xy 300.57346 -203.03216)
			(xy 300.573948 -203.03744) (xy 300.573948 -203.037948) (xy 300.573948 -203.532232) (xy 306.618132 -203.532232)
			(xy 306.618132 -203.037694) (xy 306.618646 -203.032331) (xy 306.626231 -203.024746) (xy 306.631594 -203.024232)
			(xy 308.104794 -203.024232) (xy 308.110156 -203.024754) (xy 308.117742 -203.032333) (xy 308.118256 -203.037694)
			(xy 308.118256 -203.532232) (xy 415.718244 -203.532232) (xy 415.718244 -203.037694) (xy 415.71872 -203.032388)
			(xy 415.726156 -203.024817) (xy 415.731452 -203.024232) (xy 417.204652 -203.024232) (xy 417.209987 -203.024563)
			(xy 417.217534 -203.032105) (xy 417.21786 -203.03744) (xy 417.21786 -203.532232) (xy 423.262044 -203.532232)
			(xy 423.262044 -203.037694) (xy 423.262547 -203.032328) (xy 423.270139 -203.024742) (xy 423.275506 -203.024232)
			(xy 423.791634 -203.024232) (xy 423.799443 -203.023902) (xy 423.814315 -203.019128) (xy 423.820844 -203.014834)
			(xy 423.841933 -203.000485) (xy 423.887594 -202.977754) (xy 423.9362 -202.962295) (xy 423.986603 -202.954472)
			(xy 424.037609 -202.954472) (xy 424.088012 -202.962295) (xy 424.136618 -202.977754) (xy 424.182279 -203.000485)
			(xy 424.203368 -203.014834) (xy 424.209911 -203.019105) (xy 424.224772 -203.023902) (xy 424.232578 -203.024232)
			(xy 424.748706 -203.024232) (xy 424.754069 -203.024746) (xy 424.761654 -203.032331) (xy 424.762168 -203.037694)
			(xy 424.762168 -203.532232) (xy 430.806352 -203.532232) (xy 430.806352 -203.037694) (xy 430.80682 -203.032386)
			(xy 430.814262 -203.024815) (xy 430.81956 -203.024232) (xy 431.335688 -203.024232) (xy 431.343499 -203.023925)
			(xy 431.358371 -203.019135) (xy 431.364898 -203.014834) (xy 431.385987 -203.000485) (xy 431.431648 -202.977754)
			(xy 431.480254 -202.962295) (xy 431.530657 -202.954472) (xy 431.581663 -202.954472) (xy 431.632066 -202.962295)
			(xy 431.680672 -202.977754) (xy 431.726333 -203.000485) (xy 431.747422 -203.014834) (xy 431.753953 -203.019126)
			(xy 431.768823 -203.02391) (xy 431.776632 -203.024232) (xy 432.29276 -203.024232) (xy 432.298097 -203.024558)
			(xy 432.305642 -203.032103) (xy 432.305968 -203.03744) (xy 432.305968 -203.037948) (xy 432.305968 -203.532232)
			(xy 438.350152 -203.532232) (xy 438.350152 -203.037694) (xy 438.350477 -203.032255) (xy 438.358175 -203.024569)
			(xy 438.363614 -203.024232) (xy 438.879742 -203.024232) (xy 438.887551 -203.023905) (xy 438.902423 -203.019129)
			(xy 438.908952 -203.014834) (xy 438.930041 -203.000485) (xy 438.975702 -202.977754) (xy 439.024308 -202.962295)
			(xy 439.074711 -202.954472) (xy 439.125717 -202.954472) (xy 439.17612 -202.962295) (xy 439.224726 -202.977754)
			(xy 439.270387 -203.000485) (xy 439.291476 -203.014834) (xy 439.298017 -203.019108) (xy 439.31288 -203.023903)
			(xy 439.320686 -203.024232) (xy 439.836814 -203.024232) (xy 439.842178 -203.024741) (xy 439.849763 -203.03233)
			(xy 439.850276 -203.037694) (xy 439.850276 -203.532232) (xy 445.89446 -203.532232) (xy 445.89446 -203.037694)
			(xy 445.894921 -203.032384) (xy 445.902367 -203.024812) (xy 445.907668 -203.024232) (xy 446.423796 -203.024232)
			(xy 446.431607 -203.023928) (xy 446.446479 -203.019136) (xy 446.453006 -203.014834) (xy 446.474095 -203.000485)
			(xy 446.519756 -202.977754) (xy 446.568362 -202.962295) (xy 446.618765 -202.954472) (xy 446.669771 -202.954472)
			(xy 446.720174 -202.962295) (xy 446.76878 -202.977754) (xy 446.814441 -203.000485) (xy 446.83553 -203.014834)
			(xy 446.842059 -203.019129) (xy 446.856931 -203.023911) (xy 446.86474 -203.024232) (xy 447.380868 -203.024232)
			(xy 447.386206 -203.024552) (xy 447.393751 -203.032102) (xy 447.394076 -203.03744) (xy 447.394076 -203.037948)
			(xy 447.394076 -203.532232) (xy 453.43826 -203.532232) (xy 453.43826 -203.037694) (xy 453.438721 -203.032384)
			(xy 453.446167 -203.024812) (xy 453.451468 -203.024232) (xy 453.967596 -203.024232) (xy 453.975407 -203.023928)
			(xy 453.990279 -203.019136) (xy 453.996806 -203.014834) (xy 454.017895 -203.000485) (xy 454.063556 -202.977754)
			(xy 454.112162 -202.962295) (xy 454.162565 -202.954472) (xy 454.213571 -202.954472) (xy 454.263974 -202.962295)
			(xy 454.31258 -202.977754) (xy 454.358241 -203.000485) (xy 454.37933 -203.014834) (xy 454.385859 -203.019129)
			(xy 454.400731 -203.023911) (xy 454.40854 -203.024232) (xy 454.924668 -203.024232) (xy 454.930006 -203.024552)
			(xy 454.937551 -203.032102) (xy 454.937876 -203.03744) (xy 454.937876 -203.037948) (xy 454.937876 -203.532232)
			(xy 454.937423 -203.537506) (xy 454.929945 -203.544949) (xy 454.924668 -203.54544) (xy 454.408794 -203.54544)
			(xy 454.40092 -203.545735) (xy 454.385916 -203.550514) (xy 454.37933 -203.554838) (xy 454.358262 -203.569244)
			(xy 454.312614 -203.592069) (xy 454.264005 -203.607623) (xy 454.213586 -203.615537) (xy 454.188068 -203.616052)
			(xy 454.162549 -203.615536) (xy 454.112124 -203.607648) (xy 454.063512 -203.592095) (xy 454.017872 -203.569249)
			(xy 453.996806 -203.554838) (xy 453.990213 -203.550526) (xy 453.975214 -203.545737) (xy 453.967342 -203.54544)
			(xy 453.451468 -203.54544) (xy 453.446209 -203.54493) (xy 453.43877 -203.537491) (xy 453.43826 -203.532232)
			(xy 447.394076 -203.532232) (xy 447.393623 -203.537506) (xy 447.386145 -203.544949) (xy 447.380868 -203.54544)
			(xy 446.864994 -203.54544) (xy 446.85712 -203.545735) (xy 446.842116 -203.550514) (xy 446.83553 -203.554838)
			(xy 446.814462 -203.569244) (xy 446.768814 -203.592069) (xy 446.720205 -203.607623) (xy 446.669786 -203.615537)
			(xy 446.644268 -203.616052) (xy 446.618749 -203.615536) (xy 446.568324 -203.607648) (xy 446.519712 -203.592095)
			(xy 446.474072 -203.569249) (xy 446.453006 -203.554838) (xy 446.446413 -203.550526) (xy 446.431414 -203.545737)
			(xy 446.423542 -203.54544) (xy 445.907668 -203.54544) (xy 445.902409 -203.54493) (xy 445.89497 -203.537491)
			(xy 445.89446 -203.532232) (xy 439.850276 -203.532232) (xy 439.849823 -203.537506) (xy 439.842345 -203.544949)
			(xy 439.837068 -203.54544) (xy 439.83656 -203.54544) (xy 439.32094 -203.54544) (xy 439.313064 -203.545711)
			(xy 439.29806 -203.550506) (xy 439.291476 -203.554838) (xy 439.270395 -203.569224) (xy 439.224751 -203.592054)
			(xy 439.176147 -203.607613) (xy 439.12573 -203.615534) (xy 439.100214 -203.616052) (xy 439.074694 -203.615563)
			(xy 439.024267 -203.607667) (xy 438.975656 -203.592106) (xy 438.930017 -203.569252) (xy 438.908952 -203.554838)
			(xy 438.902371 -203.550505) (xy 438.887363 -203.545729) (xy 438.879488 -203.54544) (xy 438.363614 -203.54544)
			(xy 438.358307 -203.544965) (xy 438.350734 -203.537529) (xy 438.350152 -203.532232) (xy 432.305968 -203.532232)
			(xy 432.305691 -203.537578) (xy 432.298108 -203.54512) (xy 432.29276 -203.54544) (xy 431.776886 -203.54544)
			(xy 431.769012 -203.545731) (xy 431.754008 -203.550513) (xy 431.747422 -203.554838) (xy 431.726356 -203.569247)
			(xy 431.680707 -203.592072) (xy 431.632098 -203.607625) (xy 431.581678 -203.615538) (xy 431.55616 -203.616052)
			(xy 431.530641 -203.61554) (xy 431.480215 -203.607651) (xy 431.431604 -203.592097) (xy 431.385964 -203.569249)
			(xy 431.364898 -203.554838) (xy 431.358306 -203.550523) (xy 431.343306 -203.545736) (xy 431.335434 -203.54544)
			(xy 430.81956 -203.54544) (xy 430.8143 -203.544935) (xy 430.806862 -203.537492) (xy 430.806352 -203.532232)
			(xy 424.762168 -203.532232) (xy 424.761891 -203.537578) (xy 424.754308 -203.54512) (xy 424.74896 -203.54544)
			(xy 424.748452 -203.54544) (xy 424.232832 -203.54544) (xy 424.224956 -203.545708) (xy 424.209952 -203.550505)
			(xy 424.203368 -203.554838) (xy 424.182289 -203.569227) (xy 424.136645 -203.592056) (xy 424.088039 -203.607615)
			(xy 424.037623 -203.615535) (xy 424.012106 -203.616052) (xy 423.986586 -203.615567) (xy 423.936159 -203.607669)
			(xy 423.887548 -203.592108) (xy 423.841909 -203.569253) (xy 423.820844 -203.554838) (xy 423.814264 -203.550502)
			(xy 423.799255 -203.545728) (xy 423.79138 -203.54544) (xy 423.275506 -203.54544) (xy 423.270198 -203.544971)
			(xy 423.262625 -203.537531) (xy 423.262044 -203.532232) (xy 417.21786 -203.532232) (xy 417.21759 -203.53758)
			(xy 417.210002 -203.545122) (xy 417.204652 -203.54544) (xy 415.731452 -203.54544) (xy 415.726191 -203.54494)
			(xy 415.718753 -203.537493) (xy 415.718244 -203.532232) (xy 308.118256 -203.532232) (xy 308.117731 -203.537487)
			(xy 308.110302 -203.544925) (xy 308.105048 -203.54544) (xy 308.10454 -203.54544) (xy 306.631594 -203.54544)
			(xy 306.626284 -203.544979) (xy 306.618712 -203.537533) (xy 306.618132 -203.532232) (xy 300.573948 -203.532232)
			(xy 300.573431 -203.537489) (xy 300.565997 -203.544927) (xy 300.56074 -203.54544) (xy 300.044866 -203.54544)
			(xy 300.036991 -203.545722) (xy 300.021987 -203.55051) (xy 300.015402 -203.554838) (xy 299.994314 -203.569213)
			(xy 299.948673 -203.592045) (xy 299.90007 -203.607608) (xy 299.849656 -203.615532) (xy 299.82414 -203.616052)
			(xy 299.79862 -203.61555) (xy 299.748194 -203.607658) (xy 299.699583 -203.592101) (xy 299.653944 -203.569251)
			(xy 299.632878 -203.554838) (xy 299.626291 -203.550515) (xy 299.611288 -203.545733) (xy 299.603414 -203.54544)
			(xy 299.08754 -203.54544) (xy 299.082221 -203.545049) (xy 299.07468 -203.537549) (xy 299.074332 -203.532232)
			(xy 293.030148 -203.532232) (xy 293.029631 -203.537489) (xy 293.022197 -203.544927) (xy 293.01694 -203.54544)
			(xy 293.016432 -203.54544) (xy 292.500812 -203.54544) (xy 292.492939 -203.545742) (xy 292.477935 -203.550516)
			(xy 292.471348 -203.554838) (xy 292.450275 -203.569236) (xy 292.404628 -203.592063) (xy 292.356021 -203.607619)
			(xy 292.305603 -203.615536) (xy 292.280086 -203.616052) (xy 292.254567 -203.615527) (xy 292.204142 -203.607641)
			(xy 292.155531 -203.592092) (xy 292.109891 -203.569248) (xy 292.088824 -203.554838) (xy 292.082227 -203.550533)
			(xy 292.067231 -203.54574) (xy 292.05936 -203.54544) (xy 291.543486 -203.54544) (xy 291.538176 -203.544984)
			(xy 291.530604 -203.537534) (xy 291.530024 -203.532232) (xy 285.48584 -203.532232) (xy 285.48533 -203.537491)
			(xy 285.477891 -203.54493) (xy 285.472632 -203.54544) (xy 284.956758 -203.54544) (xy 284.948883 -203.545719)
			(xy 284.933879 -203.550509) (xy 284.927294 -203.554838) (xy 284.906208 -203.569216) (xy 284.860566 -203.592048)
			(xy 284.811963 -203.607609) (xy 284.761548 -203.615533) (xy 284.736032 -203.616052) (xy 284.710512 -203.615554)
			(xy 284.660086 -203.60766) (xy 284.611475 -203.592103) (xy 284.565836 -203.569251) (xy 284.54477 -203.554838)
			(xy 284.538185 -203.550512) (xy 284.52318 -203.545732) (xy 284.515306 -203.54544) (xy 283.999432 -203.54544)
			(xy 283.994181 -203.544887) (xy 283.986738 -203.537481) (xy 283.986224 -203.532232) (xy 277.94204 -203.532232)
			(xy 277.94153 -203.537491) (xy 277.934091 -203.54493) (xy 277.928832 -203.54544) (xy 277.412958 -203.54544)
			(xy 277.405083 -203.545719) (xy 277.390079 -203.550509) (xy 277.383494 -203.554838) (xy 277.362408 -203.569216)
			(xy 277.316766 -203.592048) (xy 277.268163 -203.607609) (xy 277.217748 -203.615533) (xy 277.192232 -203.616052)
			(xy 277.166712 -203.615554) (xy 277.116286 -203.60766) (xy 277.067675 -203.592103) (xy 277.022036 -203.569251)
			(xy 277.00097 -203.554838) (xy 276.994385 -203.550512) (xy 276.97938 -203.545732) (xy 276.971506 -203.54544)
			(xy 276.455632 -203.54544) (xy 276.450381 -203.544887) (xy 276.442938 -203.537481) (xy 276.442424 -203.532232)
			(xy 270.39824 -203.532232) (xy 270.39773 -203.537491) (xy 270.390291 -203.54493) (xy 270.385032 -203.54544)
			(xy 270.384524 -203.54544) (xy 269.868904 -203.54544) (xy 269.86103 -203.545739) (xy 269.846027 -203.550515)
			(xy 269.83944 -203.554838) (xy 269.818369 -203.569239) (xy 269.772722 -203.592066) (xy 269.724114 -203.607621)
			(xy 269.673695 -203.615537) (xy 269.648178 -203.616052) (xy 269.622659 -203.615531) (xy 269.572234 -203.607644)
			(xy 269.523623 -203.592093) (xy 269.477983 -203.569248) (xy 269.456916 -203.554838) (xy 269.45032 -203.55053)
			(xy 269.435324 -203.545738) (xy 269.427452 -203.54544) (xy 268.911578 -203.54544) (xy 268.906266 -203.544989)
			(xy 268.898695 -203.537535) (xy 268.898116 -203.532232) (xy 206.997808 -203.532232) (xy 206.997808 -203.532486)
			(xy 206.997273 -203.537777) (xy 206.989879 -203.545346) (xy 206.9846 -203.545948) (xy 206.468726 -203.545948)
			(xy 206.460916 -203.546265) (xy 206.446044 -203.551048) (xy 206.439516 -203.555346) (xy 206.418387 -203.569684)
			(xy 206.372666 -203.592413) (xy 206.323995 -203.607847) (xy 206.27353 -203.615617) (xy 206.248 -203.616052)
			(xy 206.22247 -203.615618) (xy 206.172006 -203.607842) (xy 206.123333 -203.592412) (xy 206.077606 -203.569694)
			(xy 206.056484 -203.555346) (xy 206.049953 -203.551054) (xy 206.035083 -203.546271) (xy 206.027274 -203.545948)
			(xy 205.5114 -203.545948) (xy 205.506147 -203.545409) (xy 205.498707 -203.537992) (xy 205.498192 -203.53274)
			(xy 199.453982 -203.53274) (xy 199.453473 -203.537777) (xy 199.446079 -203.545346) (xy 199.4408 -203.545948)
			(xy 198.924926 -203.545948) (xy 198.917116 -203.546265) (xy 198.902244 -203.551048) (xy 198.895716 -203.555346)
			(xy 198.874587 -203.569684) (xy 198.828866 -203.592413) (xy 198.780195 -203.607847) (xy 198.72973 -203.615617)
			(xy 198.7042 -203.616052) (xy 198.67867 -203.615618) (xy 198.628206 -203.607842) (xy 198.579533 -203.592412)
			(xy 198.533806 -203.569694) (xy 198.512684 -203.555346) (xy 198.506153 -203.551054) (xy 198.491283 -203.546271)
			(xy 198.483474 -203.545948) (xy 197.9676 -203.545948) (xy 197.962347 -203.545409) (xy 197.954907 -203.537992)
			(xy 197.954392 -203.53274) (xy 191.910181 -203.53274) (xy 191.909645 -203.537837) (xy 191.902095 -203.545421)
			(xy 191.896746 -203.545948) (xy 191.380872 -203.545948) (xy 191.37306 -203.546242) (xy 191.358188 -203.55104)
			(xy 191.351662 -203.555346) (xy 191.330548 -203.569707) (xy 191.284822 -203.592431) (xy 191.236146 -203.607858)
			(xy 191.185678 -203.615621) (xy 191.160146 -203.616052) (xy 191.134617 -203.615595) (xy 191.084153 -203.607825)
			(xy 191.035481 -203.592402) (xy 190.989753 -203.569691) (xy 190.96863 -203.555346) (xy 190.962088 -203.551072)
			(xy 190.947226 -203.546278) (xy 190.93942 -203.545948) (xy 190.423546 -203.545948) (xy 190.418114 -203.545589)
			(xy 190.410424 -203.537917) (xy 190.410084 -203.532486) (xy 184.3659 -203.532486) (xy 184.365372 -203.537779)
			(xy 184.357973 -203.545349) (xy 184.352692 -203.545948) (xy 183.836818 -203.545948) (xy 183.829008 -203.546261)
			(xy 183.814136 -203.551047) (xy 183.807608 -203.555346) (xy 183.786481 -203.569687) (xy 183.740759 -203.592416)
			(xy 183.692088 -203.607848) (xy 183.641623 -203.615617) (xy 183.616092 -203.616052) (xy 183.590561 -203.615622)
			(xy 183.540097 -203.607844) (xy 183.491425 -203.592413) (xy 183.445698 -203.569695) (xy 183.424576 -203.555346)
			(xy 183.418046 -203.551051) (xy 183.403175 -203.54627) (xy 183.395366 -203.545948) (xy 182.879492 -203.545948)
			(xy 182.874238 -203.545415) (xy 182.866798 -203.537993) (xy 182.866284 -203.53274) (xy 176.822074 -203.53274)
			(xy 176.821544 -203.537839) (xy 176.813989 -203.545423) (xy 176.808638 -203.545948) (xy 176.292764 -203.545948)
			(xy 176.284956 -203.546281) (xy 176.270084 -203.551053) (xy 176.263554 -203.555346) (xy 176.242442 -203.569711)
			(xy 176.196715 -203.592434) (xy 176.148039 -203.60786) (xy 176.09757 -203.615622) (xy 176.072038 -203.616052)
			(xy 176.046508 -203.615599) (xy 175.996045 -203.607828) (xy 175.947373 -203.592404) (xy 175.901644 -203.569692)
			(xy 175.880522 -203.555346) (xy 175.873982 -203.551069) (xy 175.859119 -203.546276) (xy 175.851312 -203.545948)
			(xy 175.335438 -203.545948) (xy 175.330005 -203.545594) (xy 175.322316 -203.537919) (xy 175.321976 -203.532486)
			(xy 169.277792 -203.532486) (xy 169.277271 -203.537781) (xy 169.269867 -203.545351) (xy 169.264584 -203.545948)
			(xy 167.791384 -203.545948) (xy 167.786129 -203.54542) (xy 167.778689 -203.537994) (xy 167.778176 -203.53274)
			(xy 60.178162 -203.53274) (xy 60.177643 -203.537842) (xy 60.17008 -203.545427) (xy 60.164726 -203.545948)
			(xy 58.691526 -203.545948) (xy 58.686091 -203.545602) (xy 58.678403 -203.53792) (xy 58.678064 -203.532486)
			(xy 52.63388 -203.532486) (xy 52.63337 -203.537784) (xy 52.625958 -203.545354) (xy 52.620672 -203.545948)
			(xy 52.104798 -203.545948) (xy 52.096987 -203.546253) (xy 52.082115 -203.551044) (xy 52.075588 -203.555346)
			(xy 52.054467 -203.569696) (xy 52.008743 -203.592423) (xy 51.960069 -203.607853) (xy 51.909603 -203.615619)
			(xy 51.884072 -203.616052) (xy 51.858541 -203.615632) (xy 51.808076 -203.607851) (xy 51.759404 -203.592417)
			(xy 51.713677 -203.569696) (xy 51.692556 -203.555346) (xy 51.686031 -203.551044) (xy 51.671156 -203.546267)
			(xy 51.663346 -203.545948) (xy 51.147472 -203.545948) (xy 51.142215 -203.545428) (xy 51.134777 -203.537996)
			(xy 51.134264 -203.53274) (xy 45.090054 -203.53274) (xy 45.089542 -203.537844) (xy 45.081975 -203.545429)
			(xy 45.076618 -203.545948) (xy 44.560744 -203.545948) (xy 44.552935 -203.546272) (xy 44.538063 -203.55105)
			(xy 44.531534 -203.555346) (xy 44.510428 -203.569719) (xy 44.464699 -203.592441) (xy 44.41602 -203.607864)
			(xy 44.36555 -203.615623) (xy 44.340018 -203.616052) (xy 44.314488 -203.615609) (xy 44.264024 -203.607835)
			(xy 44.215352 -203.592408) (xy 44.169624 -203.569693) (xy 44.148502 -203.555346) (xy 44.141967 -203.551061)
			(xy 44.1271 -203.546273) (xy 44.119292 -203.545948) (xy 43.603418 -203.545948) (xy 43.597982 -203.545607)
			(xy 43.590294 -203.537922) (xy 43.589956 -203.532486) (xy 37.545772 -203.532486) (xy 37.545269 -203.537786)
			(xy 37.537853 -203.545357) (xy 37.532564 -203.545948) (xy 37.01669 -203.545948) (xy 37.008879 -203.546249)
			(xy 36.994007 -203.551043) (xy 36.98748 -203.555346) (xy 36.966361 -203.569699) (xy 36.920636 -203.592425)
			(xy 36.871962 -203.607854) (xy 36.821495 -203.61562) (xy 36.795964 -203.616052) (xy 36.770433 -203.615636)
			(xy 36.719968 -203.607854) (xy 36.671296 -203.592419) (xy 36.625569 -203.569696) (xy 36.604448 -203.555346)
			(xy 36.597925 -203.551041) (xy 36.583048 -203.546266) (xy 36.575238 -203.545948) (xy 36.059364 -203.545948)
			(xy 36.054107 -203.545433) (xy 36.046668 -203.537997) (xy 36.046156 -203.53274) (xy 30.001948 -203.53274)
			(xy 30.001469 -203.537786) (xy 29.994053 -203.545357) (xy 29.988764 -203.545948) (xy 29.47289 -203.545948)
			(xy 29.465079 -203.546249) (xy 29.450207 -203.551043) (xy 29.44368 -203.555346) (xy 29.422561 -203.569699)
			(xy 29.376836 -203.592425) (xy 29.328162 -203.607854) (xy 29.277695 -203.61562) (xy 29.252164 -203.616052)
			(xy 29.226633 -203.615636) (xy 29.176168 -203.607854) (xy 29.127496 -203.592419) (xy 29.081769 -203.569696)
			(xy 29.060648 -203.555346) (xy 29.054125 -203.551041) (xy 29.039248 -203.546266) (xy 29.031438 -203.545948)
			(xy 28.515564 -203.545948) (xy 28.510307 -203.545433) (xy 28.502868 -203.537997) (xy 28.502356 -203.53274)
			(xy 22.458155 -203.53274) (xy 22.457812 -203.537916) (xy 22.45014 -203.545603) (xy 22.44471 -203.545948)
			(xy 21.928836 -203.545948) (xy 21.921026 -203.546269) (xy 21.906155 -203.551049) (xy 21.899626 -203.555346)
			(xy 21.878494 -203.56968) (xy 21.832774 -203.59241) (xy 21.784104 -203.607844) (xy 21.73364 -203.615616)
			(xy 21.70811 -203.616052) (xy 21.68258 -203.615613) (xy 21.632116 -203.607838) (xy 21.583444 -203.59241)
			(xy 21.537716 -203.569693) (xy 21.516594 -203.555346) (xy 21.51006 -203.551058) (xy 21.495192 -203.546272)
			(xy 21.487384 -203.545948) (xy 20.97151 -203.545948) (xy 20.966073 -203.545613) (xy 20.958386 -203.537923)
			(xy 20.958048 -203.532486) (xy 2.509012 -203.532486) (xy 2.509012 -204.38237) (xy 16.85798 -204.38237)
			(xy 16.85798 -203.887832) (xy 16.858347 -203.882507) (xy 16.865864 -203.874965) (xy 16.871188 -203.874624)
			(xy 16.871696 -203.874624) (xy 17.38757 -203.874624) (xy 17.39538 -203.87431) (xy 17.410252 -203.869526)
			(xy 17.41678 -203.865226) (xy 17.437869 -203.850877) (xy 17.48353 -203.828146) (xy 17.532136 -203.812687)
			(xy 17.582539 -203.804864) (xy 17.633545 -203.804864) (xy 17.683948 -203.812687) (xy 17.732554 -203.828146)
			(xy 17.778215 -203.850877) (xy 17.799304 -203.865226) (xy 17.80584 -203.86951) (xy 17.820706 -203.874299)
			(xy 17.828514 -203.874624) (xy 18.344642 -203.874624) (xy 18.349948 -203.875093) (xy 18.357515 -203.882536)
			(xy 18.358104 -203.887832) (xy 18.358104 -204.38237) (xy 18.358077 -204.382624) (xy 24.402288 -204.382624)
			(xy 24.402288 -204.382116) (xy 24.402288 -203.887832) (xy 24.402648 -203.882505) (xy 24.41017 -203.874963)
			(xy 24.415496 -203.874624) (xy 24.931624 -203.874624) (xy 24.939436 -203.874333) (xy 24.954308 -203.869533)
			(xy 24.960834 -203.865226) (xy 24.981923 -203.850877) (xy 25.027584 -203.828146) (xy 25.07619 -203.812687)
			(xy 25.126593 -203.804864) (xy 25.177599 -203.804864) (xy 25.228002 -203.812687) (xy 25.276608 -203.828146)
			(xy 25.322269 -203.850877) (xy 25.343358 -203.865226) (xy 25.349882 -203.869531) (xy 25.364758 -203.874307)
			(xy 25.372568 -203.874624) (xy 25.888696 -203.874624) (xy 25.894035 -203.874933) (xy 25.901578 -203.882492)
			(xy 25.901904 -203.887832) (xy 25.901904 -204.38237) (xy 25.901878 -204.382624) (xy 31.946088 -204.382624)
			(xy 31.946088 -204.382116) (xy 31.946088 -203.887832) (xy 31.946448 -203.882505) (xy 31.95397 -203.874963)
			(xy 31.959296 -203.874624) (xy 32.475424 -203.874624) (xy 32.483236 -203.874333) (xy 32.498108 -203.869533)
			(xy 32.504634 -203.865226) (xy 32.525723 -203.850877) (xy 32.571384 -203.828146) (xy 32.61999 -203.812687)
			(xy 32.670393 -203.804864) (xy 32.721399 -203.804864) (xy 32.771802 -203.812687) (xy 32.820408 -203.828146)
			(xy 32.866069 -203.850877) (xy 32.887158 -203.865226) (xy 32.893682 -203.869531) (xy 32.908558 -203.874307)
			(xy 32.916368 -203.874624) (xy 33.432496 -203.874624) (xy 33.437835 -203.874933) (xy 33.445378 -203.882492)
			(xy 33.445704 -203.887832) (xy 33.445704 -204.38237) (xy 39.489888 -204.38237) (xy 39.489888 -203.887832)
			(xy 39.490248 -203.882505) (xy 39.49777 -203.874963) (xy 39.503096 -203.874624) (xy 39.503604 -203.874624)
			(xy 40.019478 -203.874624) (xy 40.027289 -203.874314) (xy 40.042161 -203.869527) (xy 40.048688 -203.865226)
			(xy 40.069777 -203.850877) (xy 40.115438 -203.828146) (xy 40.164044 -203.812687) (xy 40.214447 -203.804864)
			(xy 40.265453 -203.804864) (xy 40.315856 -203.812687) (xy 40.364462 -203.828146) (xy 40.410123 -203.850877)
			(xy 40.431212 -203.865226) (xy 40.437746 -203.869514) (xy 40.452614 -203.8743) (xy 40.460422 -203.874624)
			(xy 40.97655 -203.874624) (xy 40.981844 -203.875155) (xy 40.989417 -203.88255) (xy 40.990012 -203.887832)
			(xy 40.990012 -204.38237) (xy 40.989985 -204.382624) (xy 47.034196 -204.382624) (xy 47.034196 -204.382116)
			(xy 47.034196 -203.887832) (xy 47.034549 -203.882503) (xy 47.042076 -203.87496) (xy 47.047404 -203.874624)
			(xy 47.563532 -203.874624) (xy 47.571341 -203.874294) (xy 47.586213 -203.869521) (xy 47.592742 -203.865226)
			(xy 47.613831 -203.850877) (xy 47.659492 -203.828146) (xy 47.708098 -203.812687) (xy 47.758501 -203.804864)
			(xy 47.809507 -203.804864) (xy 47.85991 -203.812687) (xy 47.908516 -203.828146) (xy 47.954177 -203.850877)
			(xy 47.975266 -203.865226) (xy 47.98181 -203.869496) (xy 47.99667 -203.874294) (xy 48.004476 -203.874624)
			(xy 48.520604 -203.874624) (xy 48.525945 -203.874927) (xy 48.533487 -203.882491) (xy 48.533812 -203.887832)
			(xy 48.533812 -204.38237) (xy 54.577996 -204.38237) (xy 54.577996 -203.887832) (xy 54.578349 -203.882503)
			(xy 54.585876 -203.87496) (xy 54.591204 -203.874624) (xy 56.064658 -203.874624) (xy 56.069953 -203.875149)
			(xy 56.077526 -203.882549) (xy 56.07812 -203.887832) (xy 56.07812 -204.38237) (xy 56.078105 -204.382624)
			(xy 163.678108 -204.382624) (xy 163.678108 -204.382116) (xy 163.678108 -203.887832) (xy 163.67845 -203.8825)
			(xy 163.685985 -203.874956) (xy 163.691316 -203.874624) (xy 165.164516 -203.874624) (xy 165.169858 -203.874919)
			(xy 165.1774 -203.882488) (xy 165.177724 -203.887832) (xy 165.177724 -204.38237) (xy 171.221908 -204.38237)
			(xy 171.221908 -203.887832) (xy 171.22225 -203.8825) (xy 171.229785 -203.874956) (xy 171.235116 -203.874624)
			(xy 171.235624 -203.874624) (xy 171.751498 -203.874624) (xy 171.759309 -203.874322) (xy 171.774181 -203.869529)
			(xy 171.780708 -203.865226) (xy 171.801797 -203.850877) (xy 171.847458 -203.828146) (xy 171.896064 -203.812687)
			(xy 171.946467 -203.804864) (xy 171.997473 -203.804864) (xy 172.047876 -203.812687) (xy 172.096482 -203.828146)
			(xy 172.142143 -203.850877) (xy 172.163232 -203.865226) (xy 172.169761 -203.869521) (xy 172.184633 -203.874303)
			(xy 172.192442 -203.874624) (xy 172.70857 -203.874624) (xy 172.713867 -203.875141) (xy 172.721439 -203.882547)
			(xy 172.722032 -203.887832) (xy 172.722032 -204.38237) (xy 172.722016 -204.382624) (xy 178.766216 -204.382624)
			(xy 178.766216 -204.382116) (xy 178.766216 -203.887832) (xy 178.766551 -203.882498) (xy 178.77409 -203.874954)
			(xy 178.779424 -203.874624) (xy 179.295552 -203.874624) (xy 179.303362 -203.874303) (xy 179.318234 -203.869523)
			(xy 179.324762 -203.865226) (xy 179.345851 -203.850877) (xy 179.391512 -203.828146) (xy 179.440118 -203.812687)
			(xy 179.490521 -203.804864) (xy 179.541527 -203.804864) (xy 179.59193 -203.812687) (xy 179.640536 -203.828146)
			(xy 179.686197 -203.850877) (xy 179.707286 -203.865226) (xy 179.713826 -203.869504) (xy 179.728689 -203.874296)
			(xy 179.736496 -203.874624) (xy 180.252624 -203.874624) (xy 180.257967 -203.874914) (xy 180.265509 -203.882487)
			(xy 180.265832 -203.887832) (xy 180.265832 -204.38237) (xy 186.310016 -204.38237) (xy 186.310016 -203.887832)
			(xy 186.310351 -203.882498) (xy 186.31789 -203.874954) (xy 186.323224 -203.874624) (xy 186.323732 -203.874624)
			(xy 186.839606 -203.874624) (xy 186.847418 -203.874326) (xy 186.862289 -203.86953) (xy 186.868816 -203.865226)
			(xy 186.889905 -203.850877) (xy 186.935566 -203.828146) (xy 186.984172 -203.812687) (xy 187.034575 -203.804864)
			(xy 187.085581 -203.804864) (xy 187.135984 -203.812687) (xy 187.18459 -203.828146) (xy 187.230251 -203.850877)
			(xy 187.25134 -203.865226) (xy 187.257868 -203.869524) (xy 187.27274 -203.874304) (xy 187.28055 -203.874624)
			(xy 187.796678 -203.874624) (xy 187.801976 -203.875136) (xy 187.809547 -203.882546) (xy 187.81014 -203.887832)
			(xy 187.81014 -204.38237) (xy 187.810124 -204.382624) (xy 193.854324 -204.382624) (xy 193.854324 -204.382116)
			(xy 193.854324 -203.887832) (xy 193.854652 -203.882496) (xy 193.862196 -203.874952) (xy 193.867532 -203.874624)
			(xy 194.38366 -203.874624) (xy 194.39147 -203.874306) (xy 194.406342 -203.869524) (xy 194.41287 -203.865226)
			(xy 194.433959 -203.850877) (xy 194.47962 -203.828146) (xy 194.528226 -203.812687) (xy 194.578629 -203.804864)
			(xy 194.629635 -203.804864) (xy 194.680038 -203.812687) (xy 194.728644 -203.828146) (xy 194.774305 -203.850877)
			(xy 194.795394 -203.865226) (xy 194.801932 -203.869507) (xy 194.816797 -203.874298) (xy 194.824604 -203.874624)
			(xy 195.340732 -203.874624) (xy 195.346006 -203.875077) (xy 195.353449 -203.882555) (xy 195.35394 -203.887832)
			(xy 195.35394 -204.38237) (xy 195.353917 -204.382624) (xy 201.398124 -204.382624) (xy 201.398124 -204.382116)
			(xy 201.398124 -203.887832) (xy 201.398452 -203.882496) (xy 201.405996 -203.874952) (xy 201.411332 -203.874624)
			(xy 201.92746 -203.874624) (xy 201.93527 -203.874306) (xy 201.950142 -203.869524) (xy 201.95667 -203.865226)
			(xy 201.977759 -203.850877) (xy 202.02342 -203.828146) (xy 202.072026 -203.812687) (xy 202.122429 -203.804864)
			(xy 202.173435 -203.804864) (xy 202.223838 -203.812687) (xy 202.272444 -203.828146) (xy 202.318105 -203.850877)
			(xy 202.339194 -203.865226) (xy 202.345732 -203.869507) (xy 202.360597 -203.874298) (xy 202.368404 -203.874624)
			(xy 202.884532 -203.874624) (xy 202.889806 -203.875077) (xy 202.897249 -203.882555) (xy 202.89774 -203.887832)
			(xy 202.89774 -204.38237) (xy 202.897255 -204.387675) (xy 202.889827 -204.395249) (xy 202.884532 -204.395832)
			(xy 202.368658 -204.395832) (xy 202.36085 -204.396165) (xy 202.345978 -204.400937) (xy 202.339448 -204.40523)
			(xy 202.318337 -204.419595) (xy 202.272609 -204.442319) (xy 202.223933 -204.457745) (xy 202.173464 -204.465506)
			(xy 202.147932 -204.465936) (xy 202.122402 -204.465489) (xy 202.071938 -204.457717) (xy 202.023266 -204.442291)
			(xy 201.977538 -204.419577) (xy 201.956416 -204.40523) (xy 201.949878 -204.400949) (xy 201.935013 -204.396159)
			(xy 201.927206 -204.395832) (xy 201.411332 -204.395832) (xy 201.40601 -204.395454) (xy 201.398469 -204.387945)
			(xy 201.398124 -204.382624) (xy 195.353917 -204.382624) (xy 195.353455 -204.387675) (xy 195.346027 -204.395249)
			(xy 195.340732 -204.395832) (xy 194.824858 -204.395832) (xy 194.81705 -204.396165) (xy 194.802178 -204.400937)
			(xy 194.795648 -204.40523) (xy 194.774537 -204.419595) (xy 194.728809 -204.442319) (xy 194.680133 -204.457745)
			(xy 194.629664 -204.465506) (xy 194.604132 -204.465936) (xy 194.578602 -204.465489) (xy 194.528138 -204.457717)
			(xy 194.479466 -204.442291) (xy 194.433738 -204.419577) (xy 194.412616 -204.40523) (xy 194.406078 -204.400949)
			(xy 194.391213 -204.396159) (xy 194.383406 -204.395832) (xy 193.867532 -204.395832) (xy 193.86221 -204.395454)
			(xy 193.854669 -204.387945) (xy 193.854324 -204.382624) (xy 187.810124 -204.382624) (xy 187.809798 -204.387806)
			(xy 187.802114 -204.395495) (xy 187.796678 -204.395832) (xy 187.280804 -204.395832) (xy 187.272993 -204.396142)
			(xy 187.258122 -204.40093) (xy 187.251594 -204.40523) (xy 187.23047 -204.419575) (xy 187.184747 -204.442304)
			(xy 187.136075 -204.457735) (xy 187.085609 -204.465502) (xy 187.060078 -204.465936) (xy 187.034547 -204.465516)
			(xy 186.984082 -204.457736) (xy 186.93541 -204.442302) (xy 186.889683 -204.41958) (xy 186.868562 -204.40523)
			(xy 186.862036 -204.400929) (xy 186.847162 -204.396151) (xy 186.839352 -204.395832) (xy 186.323478 -204.395832)
			(xy 186.318033 -204.395532) (xy 186.310346 -204.387816) (xy 186.310016 -204.38237) (xy 180.265832 -204.38237)
			(xy 180.265354 -204.387677) (xy 180.257921 -204.395252) (xy 180.252624 -204.395832) (xy 179.73675 -204.395832)
			(xy 179.728941 -204.396162) (xy 179.71407 -204.400936) (xy 179.70754 -204.40523) (xy 179.686431 -204.419599)
			(xy 179.640703 -204.442322) (xy 179.592026 -204.457746) (xy 179.541556 -204.465507) (xy 179.516024 -204.465936)
			(xy 179.490494 -204.465493) (xy 179.44003 -204.45772) (xy 179.391358 -204.442293) (xy 179.34563 -204.419577)
			(xy 179.324508 -204.40523) (xy 179.317972 -204.400946) (xy 179.303106 -204.396158) (xy 179.295298 -204.395832)
			(xy 178.779424 -204.395832) (xy 178.77417 -204.395292) (xy 178.766727 -204.387876) (xy 178.766216 -204.382624)
			(xy 172.722016 -204.382624) (xy 172.721697 -204.387808) (xy 172.714008 -204.395497) (xy 172.70857 -204.395832)
			(xy 172.192696 -204.395832) (xy 172.184885 -204.396138) (xy 172.170014 -204.400929) (xy 172.163486 -204.40523)
			(xy 172.142364 -204.419579) (xy 172.096641 -204.442306) (xy 172.047967 -204.457737) (xy 171.997501 -204.465503)
			(xy 171.97197 -204.465936) (xy 171.946439 -204.46552) (xy 171.895974 -204.457738) (xy 171.847302 -204.442304)
			(xy 171.801575 -204.419581) (xy 171.780454 -204.40523) (xy 171.77393 -204.400925) (xy 171.759054 -204.39615)
			(xy 171.751244 -204.395832) (xy 171.23537 -204.395832) (xy 171.229995 -204.395367) (xy 171.222409 -204.387747)
			(xy 171.221908 -204.38237) (xy 165.177724 -204.38237) (xy 165.177253 -204.387679) (xy 165.169815 -204.395254)
			(xy 165.164516 -204.395832) (xy 163.691316 -204.395832) (xy 163.686061 -204.395297) (xy 163.678619 -204.387878)
			(xy 163.678108 -204.382624) (xy 56.078105 -204.382624) (xy 56.077796 -204.387811) (xy 56.070099 -204.395501)
			(xy 56.064658 -204.395832) (xy 54.591458 -204.395832) (xy 54.586082 -204.395375) (xy 54.578497 -204.387749)
			(xy 54.577996 -204.38237) (xy 48.533812 -204.38237) (xy 48.533351 -204.387682) (xy 48.525907 -204.395257)
			(xy 48.520604 -204.395832) (xy 48.00473 -204.395832) (xy 47.996921 -204.396153) (xy 47.982049 -204.400934)
			(xy 47.97552 -204.40523) (xy 47.954389 -204.419564) (xy 47.908669 -204.442295) (xy 47.859998 -204.457729)
			(xy 47.809534 -204.465501) (xy 47.784004 -204.465936) (xy 47.758474 -204.465503) (xy 47.708009 -204.457727)
			(xy 47.659337 -204.442297) (xy 47.61361 -204.419578) (xy 47.592488 -204.40523) (xy 47.585957 -204.400939)
			(xy 47.571087 -204.396155) (xy 47.563278 -204.395832) (xy 47.047404 -204.395832) (xy 47.042148 -204.395305)
			(xy 47.034706 -204.387879) (xy 47.034196 -204.382624) (xy 40.989985 -204.382624) (xy 40.989435 -204.387718)
			(xy 40.981895 -204.395303) (xy 40.97655 -204.395832) (xy 40.460676 -204.395832) (xy 40.452864 -204.39613)
			(xy 40.437993 -204.400926) (xy 40.431466 -204.40523) (xy 40.41035 -204.419588) (xy 40.364624 -204.442313)
			(xy 40.315949 -204.457741) (xy 40.265481 -204.465505) (xy 40.23995 -204.465936) (xy 40.21442 -204.46548)
			(xy 40.163957 -204.457711) (xy 40.115285 -204.442287) (xy 40.069556 -204.419576) (xy 40.048434 -204.40523)
			(xy 40.041892 -204.400956) (xy 40.02703 -204.396162) (xy 40.019224 -204.395832) (xy 39.50335 -204.395832)
			(xy 39.497973 -204.39538) (xy 39.490388 -204.38775) (xy 39.489888 -204.38237) (xy 33.445704 -204.38237)
			(xy 33.445162 -204.38766) (xy 33.437773 -204.395231) (xy 33.432496 -204.395832) (xy 32.916622 -204.395832)
			(xy 32.908812 -204.396149) (xy 32.89394 -204.400932) (xy 32.887412 -204.40523) (xy 32.866283 -204.419568)
			(xy 32.820562 -204.442298) (xy 32.771891 -204.457731) (xy 32.721426 -204.465501) (xy 32.695896 -204.465936)
			(xy 32.670365 -204.465507) (xy 32.619901 -204.457729) (xy 32.571229 -204.442298) (xy 32.525501 -204.419579)
			(xy 32.50438 -204.40523) (xy 32.49785 -204.400935) (xy 32.482979 -204.396154) (xy 32.47517 -204.395832)
			(xy 31.959296 -204.395832) (xy 31.954038 -204.395311) (xy 31.946597 -204.387881) (xy 31.946088 -204.382624)
			(xy 25.901878 -204.382624) (xy 25.901362 -204.38766) (xy 25.893973 -204.395231) (xy 25.888696 -204.395832)
			(xy 25.372822 -204.395832) (xy 25.365012 -204.396149) (xy 25.35014 -204.400932) (xy 25.343612 -204.40523)
			(xy 25.322483 -204.419568) (xy 25.276762 -204.442298) (xy 25.228091 -204.457731) (xy 25.177626 -204.465501)
			(xy 25.152096 -204.465936) (xy 25.126565 -204.465507) (xy 25.076101 -204.457729) (xy 25.027429 -204.442298)
			(xy 24.981701 -204.419579) (xy 24.96058 -204.40523) (xy 24.95405 -204.400935) (xy 24.939179 -204.396154)
			(xy 24.93137 -204.395832) (xy 24.415496 -204.395832) (xy 24.410238 -204.395311) (xy 24.402797 -204.387881)
			(xy 24.402288 -204.382624) (xy 18.358077 -204.382624) (xy 18.357534 -204.38772) (xy 18.349989 -204.395305)
			(xy 18.344642 -204.395832) (xy 17.828768 -204.395832) (xy 17.82096 -204.396169) (xy 17.806088 -204.400939)
			(xy 17.799558 -204.40523) (xy 17.778444 -204.419591) (xy 17.732718 -204.442316) (xy 17.684042 -204.457743)
			(xy 17.633574 -204.465505) (xy 17.608042 -204.465936) (xy 17.582512 -204.465484) (xy 17.532049 -204.457713)
			(xy 17.483376 -204.442289) (xy 17.437648 -204.419576) (xy 17.416526 -204.40523) (xy 17.409986 -204.400953)
			(xy 17.395123 -204.396161) (xy 17.387316 -204.395832) (xy 16.871442 -204.395832) (xy 16.866006 -204.39549)
			(xy 16.858315 -204.387806) (xy 16.85798 -204.38237) (xy 2.509012 -204.38237) (xy 2.509012 -205.232508)
			(xy 20.958048 -205.232508) (xy 20.958048 -204.73797) (xy 20.958531 -204.7326) (xy 20.966139 -204.725015)
			(xy 20.97151 -204.724508) (xy 21.487638 -204.724508) (xy 21.495446 -204.724167) (xy 21.510317 -204.7194)
			(xy 21.516848 -204.71511) (xy 21.537937 -204.700761) (xy 21.583598 -204.67803) (xy 21.632204 -204.662571)
			(xy 21.682607 -204.654748) (xy 21.733613 -204.654748) (xy 21.784016 -204.662571) (xy 21.832622 -204.67803)
			(xy 21.878283 -204.700761) (xy 21.899372 -204.71511) (xy 21.90591 -204.71939) (xy 21.920775 -204.72418)
			(xy 21.928582 -204.724508) (xy 22.44471 -204.724508) (xy 22.450068 -204.725041) (xy 22.457651 -204.732613)
			(xy 22.458172 -204.73797) (xy 22.458172 -205.232508) (xy 28.502356 -205.232508) (xy 28.502356 -204.73797)
			(xy 28.502805 -204.732658) (xy 28.510261 -204.725088) (xy 28.515564 -204.724508) (xy 29.031692 -204.724508)
			(xy 29.039502 -204.72419) (xy 29.054373 -204.719407) (xy 29.060902 -204.71511) (xy 29.081991 -204.700761)
			(xy 29.127652 -204.67803) (xy 29.176258 -204.662571) (xy 29.226661 -204.654748) (xy 29.277667 -204.654748)
			(xy 29.32807 -204.662571) (xy 29.376676 -204.67803) (xy 29.422337 -204.700761) (xy 29.443426 -204.71511)
			(xy 29.449952 -204.719411) (xy 29.464826 -204.724188) (xy 29.472636 -204.724508) (xy 29.988764 -204.724508)
			(xy 29.994095 -204.724853) (xy 30.001639 -204.732385) (xy 30.001972 -204.737716) (xy 30.001972 -204.738224)
			(xy 30.001972 -205.232508) (xy 36.046156 -205.232508) (xy 36.046156 -204.73797) (xy 36.046605 -204.732658)
			(xy 36.054061 -204.725088) (xy 36.059364 -204.724508) (xy 36.575492 -204.724508) (xy 36.583302 -204.72419)
			(xy 36.598173 -204.719407) (xy 36.604702 -204.71511) (xy 36.625791 -204.700761) (xy 36.671452 -204.67803)
			(xy 36.720058 -204.662571) (xy 36.770461 -204.654748) (xy 36.821467 -204.654748) (xy 36.87187 -204.662571)
			(xy 36.920476 -204.67803) (xy 36.966137 -204.700761) (xy 36.987226 -204.71511) (xy 36.993752 -204.719411)
			(xy 37.008626 -204.724188) (xy 37.016436 -204.724508) (xy 37.532564 -204.724508) (xy 37.537895 -204.724853)
			(xy 37.545439 -204.732385) (xy 37.545772 -204.737716) (xy 37.545772 -204.738224) (xy 37.545772 -205.232508)
			(xy 43.589956 -205.232508) (xy 43.589956 -204.73797) (xy 43.590432 -204.732598) (xy 43.598044 -204.725013)
			(xy 43.603418 -204.724508) (xy 44.119546 -204.724508) (xy 44.127354 -204.72417) (xy 44.142225 -204.719401)
			(xy 44.148756 -204.71511) (xy 44.169845 -204.700761) (xy 44.215506 -204.67803) (xy 44.264112 -204.662571)
			(xy 44.314515 -204.654748) (xy 44.365521 -204.654748) (xy 44.415924 -204.662571) (xy 44.46453 -204.67803)
			(xy 44.510191 -204.700761) (xy 44.53128 -204.71511) (xy 44.537816 -204.719393) (xy 44.552683 -204.724181)
			(xy 44.56049 -204.724508) (xy 45.076618 -204.724508) (xy 45.081977 -204.725035) (xy 45.08956 -204.732612)
			(xy 45.09008 -204.73797) (xy 45.09008 -205.232508) (xy 51.134264 -205.232508) (xy 51.134264 -204.73797)
			(xy 51.134706 -204.732656) (xy 51.142166 -204.725086) (xy 51.147472 -204.724508) (xy 51.6636 -204.724508)
			(xy 51.67141 -204.724193) (xy 51.686281 -204.719408) (xy 51.69281 -204.71511) (xy 51.713899 -204.700761)
			(xy 51.75956 -204.67803) (xy 51.808166 -204.662571) (xy 51.858569 -204.654748) (xy 51.909575 -204.654748)
			(xy 51.959978 -204.662571) (xy 52.008584 -204.67803) (xy 52.054245 -204.700761) (xy 52.075334 -204.71511)
			(xy 52.081858 -204.719414) (xy 52.096734 -204.724189) (xy 52.104544 -204.724508) (xy 52.620672 -204.724508)
			(xy 52.626004 -204.724847) (xy 52.633548 -204.732384) (xy 52.63388 -204.737716) (xy 52.63388 -204.738224)
			(xy 52.63388 -205.232508) (xy 58.678064 -205.232508) (xy 58.678064 -204.73797) (xy 58.678533 -204.732596)
			(xy 58.68615 -204.725011) (xy 58.691526 -204.724508) (xy 60.164726 -204.724508) (xy 60.170086 -204.72503)
			(xy 60.177668 -204.73261) (xy 60.178188 -204.73797) (xy 60.178188 -205.232508) (xy 167.778176 -205.232508)
			(xy 167.778176 -204.73797) (xy 167.778607 -204.732654) (xy 167.786075 -204.725082) (xy 167.791384 -204.724508)
			(xy 169.264584 -204.724508) (xy 169.269918 -204.724839) (xy 169.277461 -204.732382) (xy 169.277792 -204.737716)
			(xy 169.277792 -205.232508) (xy 175.321976 -205.232508) (xy 175.321976 -204.73797) (xy 175.322263 -204.732522)
			(xy 175.329988 -204.724835) (xy 175.335438 -204.724508) (xy 175.851566 -204.724508) (xy 175.859375 -204.724179)
			(xy 175.874246 -204.719403) (xy 175.880776 -204.71511) (xy 175.901865 -204.700761) (xy 175.947526 -204.67803)
			(xy 175.996132 -204.662571) (xy 176.046535 -204.654748) (xy 176.097541 -204.654748) (xy 176.147944 -204.662571)
			(xy 176.19655 -204.67803) (xy 176.242211 -204.700761) (xy 176.2633 -204.71511) (xy 176.269832 -204.719401)
			(xy 176.284702 -204.724184) (xy 176.29251 -204.724508) (xy 176.808638 -204.724508) (xy 176.813999 -204.725022)
			(xy 176.821581 -204.732608) (xy 176.8221 -204.73797) (xy 176.8221 -205.232508) (xy 182.866284 -205.232508)
			(xy 182.866284 -204.73797) (xy 182.866708 -204.732652) (xy 182.874181 -204.72508) (xy 182.879492 -204.724508)
			(xy 183.39562 -204.724508) (xy 183.403431 -204.724201) (xy 183.418302 -204.71941) (xy 183.42483 -204.71511)
			(xy 183.445919 -204.700761) (xy 183.49158 -204.67803) (xy 183.540186 -204.662571) (xy 183.590589 -204.654748)
			(xy 183.641595 -204.654748) (xy 183.691998 -204.662571) (xy 183.740604 -204.67803) (xy 183.786265 -204.700761)
			(xy 183.807354 -204.71511) (xy 183.813874 -204.719422) (xy 183.828753 -204.724192) (xy 183.836564 -204.724508)
			(xy 184.352692 -204.724508) (xy 184.358027 -204.724834) (xy 184.36557 -204.732381) (xy 184.3659 -204.737716)
			(xy 184.3659 -204.738224) (xy 184.3659 -205.232508) (xy 190.410084 -205.232508) (xy 190.410084 -204.73797)
			(xy 190.410364 -204.73252) (xy 190.418094 -204.724833) (xy 190.423546 -204.724508) (xy 190.939674 -204.724508)
			(xy 190.947483 -204.724182) (xy 190.962354 -204.719404) (xy 190.968884 -204.71511) (xy 190.989973 -204.700761)
			(xy 191.035634 -204.67803) (xy 191.08424 -204.662571) (xy 191.134643 -204.654748) (xy 191.185649 -204.654748)
			(xy 191.236052 -204.662571) (xy 191.284658 -204.67803) (xy 191.330319 -204.700761) (xy 191.351408 -204.71511)
			(xy 191.357938 -204.719404) (xy 191.372809 -204.724185) (xy 191.380618 -204.724508) (xy 191.896746 -204.724508)
			(xy 191.902108 -204.725017) (xy 191.90969 -204.732607) (xy 191.910208 -204.73797) (xy 191.910208 -205.232508)
			(xy 197.954392 -205.232508) (xy 197.954392 -204.73797) (xy 197.954897 -204.732673) (xy 197.962314 -204.725107)
			(xy 197.9676 -204.724508) (xy 198.483728 -204.724508) (xy 198.491539 -204.724205) (xy 198.50641 -204.719411)
			(xy 198.512938 -204.71511) (xy 198.534027 -204.700761) (xy 198.579688 -204.67803) (xy 198.628294 -204.662571)
			(xy 198.678697 -204.654748) (xy 198.729703 -204.654748) (xy 198.780106 -204.662571) (xy 198.828712 -204.67803)
			(xy 198.874373 -204.700761) (xy 198.895462 -204.71511) (xy 198.902002 -204.719386) (xy 198.916866 -204.724178)
			(xy 198.924672 -204.724508) (xy 199.4408 -204.724508) (xy 199.446136 -204.724828) (xy 199.453678 -204.732379)
			(xy 199.454008 -204.737716) (xy 199.454008 -204.738224) (xy 199.454008 -205.232508) (xy 205.498192 -205.232508)
			(xy 205.498192 -204.73797) (xy 205.498697 -204.732673) (xy 205.506114 -204.725107) (xy 205.5114 -204.724508)
			(xy 206.027528 -204.724508) (xy 206.035339 -204.724205) (xy 206.05021 -204.719411) (xy 206.056738 -204.71511)
			(xy 206.077827 -204.700761) (xy 206.123488 -204.67803) (xy 206.172094 -204.662571) (xy 206.222497 -204.654748)
			(xy 206.273503 -204.654748) (xy 206.323906 -204.662571) (xy 206.372512 -204.67803) (xy 206.418173 -204.700761)
			(xy 206.439262 -204.71511) (xy 206.445802 -204.719386) (xy 206.460666 -204.724178) (xy 206.468472 -204.724508)
			(xy 206.9846 -204.724508) (xy 206.989936 -204.724828) (xy 206.997478 -204.732379) (xy 206.997808 -204.737716)
			(xy 206.997808 -204.738224) (xy 206.997808 -205.232508) (xy 206.997311 -205.237772) (xy 206.989864 -205.245214)
			(xy 206.9846 -205.245716) (xy 206.468726 -205.245716) (xy 206.46085 -205.245985) (xy 206.445846 -205.250782)
			(xy 206.439262 -205.255114) (xy 206.418183 -205.269503) (xy 206.372539 -205.292333) (xy 206.323933 -205.307892)
			(xy 206.273517 -205.315811) (xy 206.248 -205.316328) (xy 206.222479 -205.31585) (xy 206.172052 -205.307951)
			(xy 206.123441 -205.292388) (xy 206.077803 -205.26953) (xy 206.056738 -205.255114) (xy 206.050139 -205.250812)
			(xy 206.035145 -205.246017) (xy 206.027274 -205.245716) (xy 205.5114 -205.245716) (xy 205.506139 -205.245206)
			(xy 205.498697 -205.237768) (xy 205.498192 -205.232508) (xy 199.454008 -205.232508) (xy 199.453511 -205.237772)
			(xy 199.446064 -205.245214) (xy 199.4408 -205.245716) (xy 198.924926 -205.245716) (xy 198.91705 -205.245985)
			(xy 198.902046 -205.250782) (xy 198.895462 -205.255114) (xy 198.874383 -205.269503) (xy 198.828739 -205.292333)
			(xy 198.780133 -205.307892) (xy 198.729717 -205.315811) (xy 198.7042 -205.316328) (xy 198.678679 -205.31585)
			(xy 198.628252 -205.307951) (xy 198.579641 -205.292388) (xy 198.534003 -205.26953) (xy 198.512938 -205.255114)
			(xy 198.506339 -205.250812) (xy 198.491345 -205.246017) (xy 198.483474 -205.245716) (xy 197.9676 -205.245716)
			(xy 197.962339 -205.245206) (xy 197.954897 -205.237768) (xy 197.954392 -205.232508) (xy 191.910208 -205.232508)
			(xy 191.909711 -205.237772) (xy 191.902264 -205.245214) (xy 191.897 -205.245716) (xy 191.896492 -205.245716)
			(xy 191.380872 -205.245716) (xy 191.372998 -205.246005) (xy 191.357994 -205.250788) (xy 191.351408 -205.255114)
			(xy 191.330344 -205.269526) (xy 191.284695 -205.292351) (xy 191.236084 -205.307903) (xy 191.185664 -205.315815)
			(xy 191.160146 -205.316328) (xy 191.134626 -205.315827) (xy 191.0842 -205.307935) (xy 191.035589 -205.292378)
			(xy 190.98995 -205.269527) (xy 190.968884 -205.255114) (xy 190.962297 -205.250791) (xy 190.947294 -205.246009)
			(xy 190.93942 -205.245716) (xy 190.423546 -205.245716) (xy 190.418237 -205.245241) (xy 190.410661 -205.237807)
			(xy 190.410084 -205.232508) (xy 184.3659 -205.232508) (xy 184.36541 -205.237774) (xy 184.357958 -205.245216)
			(xy 184.352692 -205.245716) (xy 183.836818 -205.245716) (xy 183.828945 -205.246025) (xy 183.813942 -205.250795)
			(xy 183.807354 -205.255114) (xy 183.786277 -205.269506) (xy 183.740632 -205.292336) (xy 183.692026 -205.307893)
			(xy 183.641609 -205.315812) (xy 183.616092 -205.316328) (xy 183.590573 -205.315804) (xy 183.540148 -205.307919)
			(xy 183.491536 -205.292369) (xy 183.445896 -205.269524) (xy 183.42483 -205.255114) (xy 183.418233 -205.250809)
			(xy 183.403237 -205.246016) (xy 183.395366 -205.245716) (xy 182.879492 -205.245716) (xy 182.87423 -205.245211)
			(xy 182.866789 -205.23777) (xy 182.866284 -205.232508) (xy 176.8221 -205.232508) (xy 176.82161 -205.237774)
			(xy 176.814158 -205.245216) (xy 176.808892 -205.245716) (xy 176.808384 -205.245716) (xy 176.292764 -205.245716)
			(xy 176.284889 -205.246001) (xy 176.269886 -205.250787) (xy 176.2633 -205.255114) (xy 176.24221 -205.269487)
			(xy 176.19657 -205.29232) (xy 176.147968 -205.307884) (xy 176.097554 -205.315808) (xy 176.072038 -205.316328)
			(xy 176.046518 -205.315831) (xy 175.996092 -205.307938) (xy 175.94748 -205.29238) (xy 175.901841 -205.269528)
			(xy 175.880776 -205.255114) (xy 175.874191 -205.250788) (xy 175.859186 -205.246008) (xy 175.851312 -205.245716)
			(xy 175.335438 -205.245716) (xy 175.330128 -205.245246) (xy 175.322552 -205.237808) (xy 175.321976 -205.232508)
			(xy 169.277792 -205.232508) (xy 169.277477 -205.237845) (xy 169.269922 -205.245387) (xy 169.264584 -205.245716)
			(xy 167.791384 -205.245716) (xy 167.786121 -205.245217) (xy 167.77868 -205.237771) (xy 167.778176 -205.232508)
			(xy 60.178188 -205.232508) (xy 60.177877 -205.237846) (xy 60.170319 -205.245388) (xy 60.16498 -205.245716)
			(xy 60.164472 -205.245716) (xy 58.691526 -205.245716) (xy 58.686215 -205.245254) (xy 58.67864 -205.23781)
			(xy 58.678064 -205.232508) (xy 52.63388 -205.232508) (xy 52.633576 -205.237848) (xy 52.626013 -205.24539)
			(xy 52.620672 -205.245716) (xy 52.104798 -205.245716) (xy 52.096925 -205.246016) (xy 52.081921 -205.250792)
			(xy 52.075334 -205.255114) (xy 52.054263 -205.269515) (xy 52.008616 -205.292342) (xy 51.960008 -205.307898)
			(xy 51.909589 -205.315813) (xy 51.884072 -205.316328) (xy 51.858553 -205.315814) (xy 51.808127 -205.307926)
			(xy 51.759516 -205.292373) (xy 51.713876 -205.269526) (xy 51.69281 -205.255114) (xy 51.686217 -205.250801)
			(xy 51.671218 -205.246013) (xy 51.663346 -205.245716) (xy 51.147472 -205.245716) (xy 51.142208 -205.245225)
			(xy 51.134767 -205.237773) (xy 51.134264 -205.232508) (xy 45.09008 -205.232508) (xy 45.089776 -205.237848)
			(xy 45.082213 -205.24539) (xy 45.076872 -205.245716) (xy 45.076364 -205.245716) (xy 44.560744 -205.245716)
			(xy 44.552869 -205.245993) (xy 44.537865 -205.250785) (xy 44.53128 -205.255114) (xy 44.510196 -205.269495)
			(xy 44.464554 -205.292327) (xy 44.41595 -205.307888) (xy 44.365534 -205.31581) (xy 44.340018 -205.316328)
			(xy 44.314498 -205.315841) (xy 44.264071 -205.307945) (xy 44.215459 -205.292384) (xy 44.169821 -205.269529)
			(xy 44.148756 -205.255114) (xy 44.142175 -205.25078) (xy 44.127167 -205.246005) (xy 44.119292 -205.245716)
			(xy 43.603418 -205.245716) (xy 43.598106 -205.24526) (xy 43.590531 -205.237811) (xy 43.589956 -205.232508)
			(xy 37.545772 -205.232508) (xy 37.545475 -205.23785) (xy 37.537907 -205.245393) (xy 37.532564 -205.245716)
			(xy 37.01669 -205.245716) (xy 37.008816 -205.246012) (xy 36.993812 -205.250791) (xy 36.987226 -205.255114)
			(xy 36.966157 -205.269518) (xy 36.920509 -205.292345) (xy 36.871901 -205.307899) (xy 36.821481 -205.315814)
			(xy 36.795964 -205.316328) (xy 36.770445 -205.315818) (xy 36.720019 -205.307929) (xy 36.671407 -205.292375)
			(xy 36.625768 -205.269526) (xy 36.604702 -205.255114) (xy 36.598111 -205.250798) (xy 36.583111 -205.246012)
			(xy 36.575238 -205.245716) (xy 36.059364 -205.245716) (xy 36.054099 -205.24523) (xy 36.046659 -205.237774)
			(xy 36.046156 -205.232508) (xy 30.001972 -205.232508) (xy 30.001675 -205.23785) (xy 29.994107 -205.245393)
			(xy 29.988764 -205.245716) (xy 29.47289 -205.245716) (xy 29.465016 -205.246012) (xy 29.450012 -205.250791)
			(xy 29.443426 -205.255114) (xy 29.422357 -205.269518) (xy 29.376709 -205.292345) (xy 29.328101 -205.307899)
			(xy 29.277681 -205.315814) (xy 29.252164 -205.316328) (xy 29.226645 -205.315818) (xy 29.176219 -205.307929)
			(xy 29.127607 -205.292375) (xy 29.081968 -205.269526) (xy 29.060902 -205.255114) (xy 29.054311 -205.250798)
			(xy 29.039311 -205.246012) (xy 29.031438 -205.245716) (xy 28.515564 -205.245716) (xy 28.510299 -205.24523)
			(xy 28.502859 -205.237774) (xy 28.502356 -205.232508) (xy 22.458172 -205.232508) (xy 22.457875 -205.23785)
			(xy 22.450307 -205.245393) (xy 22.444964 -205.245716) (xy 22.444456 -205.245716) (xy 21.928836 -205.245716)
			(xy 21.92096 -205.245989) (xy 21.905957 -205.250784) (xy 21.899372 -205.255114) (xy 21.87829 -205.269499)
			(xy 21.832647 -205.29233) (xy 21.784042 -205.307889) (xy 21.733626 -205.31581) (xy 21.70811 -205.316328)
			(xy 21.68259 -205.315845) (xy 21.632163 -205.307948) (xy 21.583551 -205.292386) (xy 21.537913 -205.26953)
			(xy 21.516848 -205.255114) (xy 21.510269 -205.250777) (xy 21.495259 -205.246004) (xy 21.487384 -205.245716)
			(xy 20.97151 -205.245716) (xy 20.966197 -205.245265) (xy 20.958623 -205.237813) (xy 20.958048 -205.232508)
			(xy 2.509012 -205.232508) (xy 2.509012 -205.439772) (xy 255.545336 -205.439772) (xy 255.545336 -204.576172)
			(xy 255.545822 -204.548903) (xy 255.553584 -204.494919) (xy 255.568949 -204.442589) (xy 255.591606 -204.392979)
			(xy 255.621092 -204.347098) (xy 255.656807 -204.305881) (xy 255.698024 -204.270166) (xy 255.743905 -204.24068)
			(xy 255.793515 -204.218023) (xy 255.845845 -204.202658) (xy 255.899829 -204.194896) (xy 255.954367 -204.194896)
			(xy 256.008351 -204.202658) (xy 256.060681 -204.218023) (xy 256.110291 -204.24068) (xy 256.156172 -204.270166)
			(xy 256.197389 -204.305881) (xy 256.233104 -204.347098) (xy 256.255609 -204.382116) (xy 264.798048 -204.382116)
			(xy 264.798048 -203.887578) (xy 264.798537 -203.882209) (xy 264.80614 -203.874624) (xy 264.81151 -203.874116)
			(xy 265.327638 -203.874116) (xy 265.335447 -203.87379) (xy 265.350319 -203.869014) (xy 265.356848 -203.864718)
			(xy 265.377937 -203.850369) (xy 265.423598 -203.827638) (xy 265.472204 -203.812179) (xy 265.522607 -203.804356)
			(xy 265.573613 -203.804356) (xy 265.624016 -203.812179) (xy 265.672622 -203.827638) (xy 265.718283 -203.850369)
			(xy 265.739372 -203.864718) (xy 265.745915 -203.868989) (xy 265.760776 -203.873786) (xy 265.768582 -203.874116)
			(xy 266.28471 -203.874116) (xy 266.29007 -203.874642) (xy 266.297654 -203.882219) (xy 266.298172 -203.887578)
			(xy 266.298172 -204.382116) (xy 272.342356 -204.382116) (xy 272.342356 -203.887578) (xy 272.34281 -203.882267)
			(xy 272.350262 -203.874697) (xy 272.355564 -203.874116) (xy 272.871692 -203.874116) (xy 272.879503 -203.873813)
			(xy 272.894375 -203.869021) (xy 272.900902 -203.864718) (xy 272.921991 -203.850369) (xy 272.967652 -203.827638)
			(xy 273.016258 -203.812179) (xy 273.066661 -203.804356) (xy 273.117667 -203.804356) (xy 273.16807 -203.812179)
			(xy 273.216676 -203.827638) (xy 273.262337 -203.850369) (xy 273.283426 -203.864718) (xy 273.289957 -203.86901)
			(xy 273.304827 -203.873794) (xy 273.312636 -203.874116) (xy 273.828764 -203.874116) (xy 273.834097 -203.874453)
			(xy 273.841642 -203.881991) (xy 273.841972 -203.887324) (xy 273.841972 -203.887832) (xy 273.841972 -204.382116)
			(xy 279.886156 -204.382116) (xy 279.886156 -203.887578) (xy 279.88661 -203.882267) (xy 279.894062 -203.874697)
			(xy 279.899364 -203.874116) (xy 280.415492 -203.874116) (xy 280.423303 -203.873813) (xy 280.438175 -203.869021)
			(xy 280.444702 -203.864718) (xy 280.465791 -203.850369) (xy 280.511452 -203.827638) (xy 280.560058 -203.812179)
			(xy 280.610461 -203.804356) (xy 280.661467 -203.804356) (xy 280.71187 -203.812179) (xy 280.760476 -203.827638)
			(xy 280.806137 -203.850369) (xy 280.827226 -203.864718) (xy 280.833757 -203.86901) (xy 280.848627 -203.873794)
			(xy 280.856436 -203.874116) (xy 281.372564 -203.874116) (xy 281.377897 -203.874453) (xy 281.385442 -203.881991)
			(xy 281.385772 -203.887324) (xy 281.385772 -203.887832) (xy 281.385772 -204.382116) (xy 287.429956 -204.382116)
			(xy 287.429956 -203.887578) (xy 287.430438 -203.882207) (xy 287.438046 -203.874622) (xy 287.443418 -203.874116)
			(xy 287.959546 -203.874116) (xy 287.967356 -203.873794) (xy 287.982228 -203.869015) (xy 287.988756 -203.864718)
			(xy 288.009845 -203.850369) (xy 288.055506 -203.827638) (xy 288.104112 -203.812179) (xy 288.154515 -203.804356)
			(xy 288.205521 -203.804356) (xy 288.255924 -203.812179) (xy 288.30453 -203.827638) (xy 288.350191 -203.850369)
			(xy 288.37128 -203.864718) (xy 288.377821 -203.868993) (xy 288.392684 -203.873787) (xy 288.40049 -203.874116)
			(xy 288.916618 -203.874116) (xy 288.921979 -203.874636) (xy 288.929562 -203.882217) (xy 288.93008 -203.887578)
			(xy 288.93008 -204.382116) (xy 294.974264 -204.382116) (xy 294.974264 -203.887578) (xy 294.974711 -203.882266)
			(xy 294.982168 -203.874694) (xy 294.987472 -203.874116) (xy 295.5036 -203.874116) (xy 295.511412 -203.873816)
			(xy 295.526283 -203.869022) (xy 295.53281 -203.864718) (xy 295.553899 -203.850369) (xy 295.59956 -203.827638)
			(xy 295.648166 -203.812179) (xy 295.698569 -203.804356) (xy 295.749575 -203.804356) (xy 295.799978 -203.812179)
			(xy 295.848584 -203.827638) (xy 295.894245 -203.850369) (xy 295.915334 -203.864718) (xy 295.921863 -203.869013)
			(xy 295.936735 -203.873795) (xy 295.944544 -203.874116) (xy 296.460672 -203.874116) (xy 296.466006 -203.874448)
			(xy 296.473551 -203.88199) (xy 296.47388 -203.887324) (xy 296.47388 -203.887832) (xy 296.47388 -204.382116)
			(xy 302.518064 -204.382116) (xy 302.518064 -203.887578) (xy 302.518367 -203.882134) (xy 302.526081 -203.874448)
			(xy 302.531526 -203.874116) (xy 304.004726 -203.874116) (xy 304.010088 -203.874631) (xy 304.017671 -203.882216)
			(xy 304.018188 -203.887578) (xy 304.018188 -204.382116) (xy 411.618176 -204.382116) (xy 411.618176 -203.887578)
			(xy 411.618613 -203.882263) (xy 411.626076 -203.874691) (xy 411.631384 -203.874116) (xy 413.104584 -203.874116)
			(xy 413.10992 -203.87444) (xy 413.117463 -203.881988) (xy 413.117792 -203.887324) (xy 413.117792 -203.887832)
			(xy 413.117792 -204.382116) (xy 419.161976 -204.382116) (xy 419.161976 -203.887578) (xy 419.162268 -203.882131)
			(xy 419.169989 -203.874444) (xy 419.175438 -203.874116) (xy 419.691566 -203.874116) (xy 419.699376 -203.873802)
			(xy 419.714248 -203.869018) (xy 419.720776 -203.864718) (xy 419.741865 -203.850369) (xy 419.787526 -203.827638)
			(xy 419.836132 -203.812179) (xy 419.886535 -203.804356) (xy 419.937541 -203.804356) (xy 419.987944 -203.812179)
			(xy 420.03655 -203.827638) (xy 420.082211 -203.850369) (xy 420.1033 -203.864718) (xy 420.109837 -203.869)
			(xy 420.124703 -203.87379) (xy 420.13251 -203.874116) (xy 420.648638 -203.874116) (xy 420.654001 -203.874623)
			(xy 420.661583 -203.882214) (xy 420.6621 -203.887578) (xy 420.6621 -204.382116) (xy 426.706284 -204.382116)
			(xy 426.706284 -203.887578) (xy 426.706714 -203.882261) (xy 426.714182 -203.874688) (xy 426.719492 -203.874116)
			(xy 427.23562 -203.874116) (xy 427.243432 -203.873825) (xy 427.258304 -203.869025) (xy 427.26483 -203.864718)
			(xy 427.285919 -203.850369) (xy 427.33158 -203.827638) (xy 427.380186 -203.812179) (xy 427.430589 -203.804356)
			(xy 427.481595 -203.804356) (xy 427.531998 -203.812179) (xy 427.580604 -203.827638) (xy 427.626265 -203.850369)
			(xy 427.647354 -203.864718) (xy 427.653879 -203.869021) (xy 427.668754 -203.873798) (xy 427.676564 -203.874116)
			(xy 428.192692 -203.874116) (xy 428.198029 -203.874434) (xy 428.205572 -203.881987) (xy 428.2059 -203.887324)
			(xy 428.2059 -203.887832) (xy 428.2059 -204.382116) (xy 434.250084 -204.382116) (xy 434.250084 -203.887578)
			(xy 434.250369 -203.882129) (xy 434.258095 -203.874442) (xy 434.263546 -203.874116) (xy 434.779674 -203.874116)
			(xy 434.787485 -203.873805) (xy 434.802357 -203.869019) (xy 434.808884 -203.864718) (xy 434.829973 -203.850369)
			(xy 434.875634 -203.827638) (xy 434.92424 -203.812179) (xy 434.974643 -203.804356) (xy 435.025649 -203.804356)
			(xy 435.076052 -203.812179) (xy 435.124658 -203.827638) (xy 435.170319 -203.850369) (xy 435.191408 -203.864718)
			(xy 435.197943 -203.869003) (xy 435.21281 -203.873792) (xy 435.220618 -203.874116) (xy 435.736746 -203.874116)
			(xy 435.74211 -203.874618) (xy 435.749692 -203.882213) (xy 435.750208 -203.887578) (xy 435.750208 -204.382116)
			(xy 441.794392 -204.382116) (xy 441.794392 -203.887578) (xy 441.794903 -203.882282) (xy 441.802316 -203.874715)
			(xy 441.8076 -203.874116) (xy 442.323728 -203.874116) (xy 442.331541 -203.873828) (xy 442.346412 -203.869026)
			(xy 442.352938 -203.864718) (xy 442.374027 -203.850369) (xy 442.419688 -203.827638) (xy 442.468294 -203.812179)
			(xy 442.518697 -203.804356) (xy 442.569703 -203.804356) (xy 442.620106 -203.812179) (xy 442.668712 -203.827638)
			(xy 442.714373 -203.850369) (xy 442.735462 -203.864718) (xy 442.742008 -203.868986) (xy 442.756867 -203.873785)
			(xy 442.764672 -203.874116) (xy 443.2808 -203.874116) (xy 443.286138 -203.874429) (xy 443.293681 -203.881985)
			(xy 443.294008 -203.887324) (xy 443.294008 -203.887832) (xy 443.294008 -204.382116) (xy 449.338192 -204.382116)
			(xy 449.338192 -203.887578) (xy 449.338703 -203.882282) (xy 449.346116 -203.874715) (xy 449.3514 -203.874116)
			(xy 449.867528 -203.874116) (xy 449.875341 -203.873828) (xy 449.890212 -203.869026) (xy 449.896738 -203.864718)
			(xy 449.917827 -203.850369) (xy 449.963488 -203.827638) (xy 450.012094 -203.812179) (xy 450.062497 -203.804356)
			(xy 450.113503 -203.804356) (xy 450.163906 -203.812179) (xy 450.212512 -203.827638) (xy 450.258173 -203.850369)
			(xy 450.279262 -203.864718) (xy 450.285808 -203.868986) (xy 450.300667 -203.873785) (xy 450.308472 -203.874116)
			(xy 450.8246 -203.874116) (xy 450.829938 -203.874429) (xy 450.837481 -203.881985) (xy 450.837808 -203.887324)
			(xy 450.837808 -203.887832) (xy 450.837808 -204.382116) (xy 450.837316 -204.387381) (xy 450.829865 -204.394822)
			(xy 450.8246 -204.395324) (xy 450.308726 -204.395324) (xy 450.30085 -204.395592) (xy 450.285846 -204.40039)
			(xy 450.279262 -204.404722) (xy 450.258183 -204.419112) (xy 450.212539 -204.441941) (xy 450.163934 -204.4575)
			(xy 450.113517 -204.465419) (xy 450.088 -204.465936) (xy 450.062479 -204.465457) (xy 450.012052 -204.457558)
			(xy 449.963441 -204.441995) (xy 449.917803 -204.419138) (xy 449.896738 -204.404722) (xy 449.890138 -204.400421)
			(xy 449.875145 -204.395625) (xy 449.867274 -204.395324) (xy 449.3514 -204.395324) (xy 449.346141 -204.394807)
			(xy 449.3387 -204.387374) (xy 449.338192 -204.382116) (xy 443.294008 -204.382116) (xy 443.293516 -204.387381)
			(xy 443.286065 -204.394822) (xy 443.2808 -204.395324) (xy 442.764926 -204.395324) (xy 442.75705 -204.395592)
			(xy 442.742046 -204.40039) (xy 442.735462 -204.404722) (xy 442.714383 -204.419112) (xy 442.668739 -204.441941)
			(xy 442.620134 -204.4575) (xy 442.569717 -204.465419) (xy 442.5442 -204.465936) (xy 442.518679 -204.465457)
			(xy 442.468252 -204.457558) (xy 442.419641 -204.441995) (xy 442.374003 -204.419138) (xy 442.352938 -204.404722)
			(xy 442.346338 -204.400421) (xy 442.331345 -204.395625) (xy 442.323474 -204.395324) (xy 441.8076 -204.395324)
			(xy 441.802341 -204.394807) (xy 441.7949 -204.387374) (xy 441.794392 -204.382116) (xy 435.750208 -204.382116)
			(xy 435.749716 -204.387381) (xy 435.742265 -204.394822) (xy 435.737 -204.395324) (xy 435.736492 -204.395324)
			(xy 435.220872 -204.395324) (xy 435.212998 -204.395611) (xy 435.197994 -204.400396) (xy 435.191408 -204.404722)
			(xy 435.170345 -204.419135) (xy 435.124695 -204.441959) (xy 435.076085 -204.457511) (xy 435.025664 -204.465423)
			(xy 435.000146 -204.465936) (xy 434.974626 -204.465434) (xy 434.9242 -204.457542) (xy 434.875589 -204.441985)
			(xy 434.82995 -204.419135) (xy 434.808884 -204.404722) (xy 434.802296 -204.4004) (xy 434.787293 -204.395617)
			(xy 434.77942 -204.395324) (xy 434.263546 -204.395324) (xy 434.258239 -204.394842) (xy 434.250663 -204.387413)
			(xy 434.250084 -204.382116) (xy 428.2059 -204.382116) (xy 428.205415 -204.387383) (xy 428.19796 -204.394825)
			(xy 428.192692 -204.395324) (xy 427.676818 -204.395324) (xy 427.668945 -204.395632) (xy 427.653941 -204.400402)
			(xy 427.647354 -204.404722) (xy 427.626278 -204.419115) (xy 427.580633 -204.441944) (xy 427.532026 -204.457502)
			(xy 427.481609 -204.46542) (xy 427.456092 -204.465936) (xy 427.430573 -204.465411) (xy 427.380148 -204.457526)
			(xy 427.331537 -204.441976) (xy 427.285897 -204.419132) (xy 427.26483 -204.404722) (xy 427.258232 -204.400418)
			(xy 427.243237 -204.395624) (xy 427.235366 -204.395324) (xy 426.719492 -204.395324) (xy 426.714232 -204.394812)
			(xy 426.706791 -204.387376) (xy 426.706284 -204.382116) (xy 420.6621 -204.382116) (xy 420.661615 -204.387383)
			(xy 420.65416 -204.394825) (xy 420.648892 -204.395324) (xy 420.648384 -204.395324) (xy 420.132764 -204.395324)
			(xy 420.124889 -204.395608) (xy 420.109885 -204.400395) (xy 420.1033 -204.404722) (xy 420.082211 -204.419096)
			(xy 420.03657 -204.441929) (xy 419.987968 -204.457492) (xy 419.937554 -204.465416) (xy 419.912038 -204.465936)
			(xy 419.886518 -204.465438) (xy 419.836092 -204.457545) (xy 419.78748 -204.441987) (xy 419.741842 -204.419135)
			(xy 419.720776 -204.404722) (xy 419.71419 -204.400397) (xy 419.699186 -204.395616) (xy 419.691312 -204.395324)
			(xy 419.175438 -204.395324) (xy 419.17013 -204.394847) (xy 419.162555 -204.387414) (xy 419.161976 -204.382116)
			(xy 413.117792 -204.382116) (xy 413.117315 -204.387385) (xy 413.109854 -204.394827) (xy 413.104584 -204.395324)
			(xy 411.631384 -204.395324) (xy 411.626123 -204.394818) (xy 411.618682 -204.387377) (xy 411.618176 -204.382116)
			(xy 304.018188 -204.382116) (xy 304.017882 -204.387455) (xy 304.01032 -204.394997) (xy 304.00498 -204.395324)
			(xy 302.531526 -204.395324) (xy 302.526217 -204.394855) (xy 302.518642 -204.387416) (xy 302.518064 -204.382116)
			(xy 296.47388 -204.382116) (xy 296.473581 -204.387457) (xy 296.466014 -204.394999) (xy 296.460672 -204.395324)
			(xy 295.944798 -204.395324) (xy 295.936925 -204.395623) (xy 295.921921 -204.400399) (xy 295.915334 -204.404722)
			(xy 295.894263 -204.419124) (xy 295.848616 -204.441951) (xy 295.800008 -204.457506) (xy 295.749589 -204.465421)
			(xy 295.724072 -204.465936) (xy 295.698553 -204.465421) (xy 295.648127 -204.457533) (xy 295.599516 -204.44198)
			(xy 295.553876 -204.419133) (xy 295.53281 -204.404722) (xy 295.526217 -204.40041) (xy 295.511218 -204.395621)
			(xy 295.503346 -204.395324) (xy 294.987472 -204.395324) (xy 294.98221 -204.394826) (xy 294.97477 -204.387379)
			(xy 294.974264 -204.382116) (xy 288.93008 -204.382116) (xy 288.929781 -204.387457) (xy 288.922214 -204.394999)
			(xy 288.916872 -204.395324) (xy 288.916364 -204.395324) (xy 288.400744 -204.395324) (xy 288.392868 -204.395599)
			(xy 288.377865 -204.400392) (xy 288.37128 -204.404722) (xy 288.350196 -204.419104) (xy 288.304554 -204.441935)
			(xy 288.25595 -204.457496) (xy 288.205534 -204.465418) (xy 288.180018 -204.465936) (xy 288.154498 -204.465448)
			(xy 288.104071 -204.457552) (xy 288.05546 -204.441991) (xy 288.009821 -204.419137) (xy 287.988756 -204.404722)
			(xy 287.982175 -204.40039) (xy 287.967167 -204.395613) (xy 287.959292 -204.395324) (xy 287.443418 -204.395324)
			(xy 287.438108 -204.394861) (xy 287.430533 -204.387417) (xy 287.429956 -204.382116) (xy 281.385772 -204.382116)
			(xy 281.385481 -204.387459) (xy 281.377909 -204.395002) (xy 281.372564 -204.395324) (xy 280.85669 -204.395324)
			(xy 280.848816 -204.395619) (xy 280.833812 -204.400398) (xy 280.827226 -204.404722) (xy 280.806157 -204.419127)
			(xy 280.76051 -204.441953) (xy 280.711901 -204.457507) (xy 280.661482 -204.465422) (xy 280.635964 -204.465936)
			(xy 280.610445 -204.465425) (xy 280.560019 -204.457536) (xy 280.511408 -204.441982) (xy 280.465768 -204.419134)
			(xy 280.444702 -204.404722) (xy 280.43811 -204.400407) (xy 280.42311 -204.39562) (xy 280.415238 -204.395324)
			(xy 279.899364 -204.395324) (xy 279.894101 -204.394831) (xy 279.886661 -204.38738) (xy 279.886156 -204.382116)
			(xy 273.841972 -204.382116) (xy 273.841681 -204.387459) (xy 273.834109 -204.395002) (xy 273.828764 -204.395324)
			(xy 273.31289 -204.395324) (xy 273.305016 -204.395619) (xy 273.290012 -204.400398) (xy 273.283426 -204.404722)
			(xy 273.262357 -204.419127) (xy 273.21671 -204.441953) (xy 273.168101 -204.457507) (xy 273.117682 -204.465422)
			(xy 273.092164 -204.465936) (xy 273.066645 -204.465425) (xy 273.016219 -204.457536) (xy 272.967608 -204.441982)
			(xy 272.921968 -204.419134) (xy 272.900902 -204.404722) (xy 272.89431 -204.400407) (xy 272.87931 -204.39562)
			(xy 272.871438 -204.395324) (xy 272.355564 -204.395324) (xy 272.350301 -204.394831) (xy 272.342861 -204.38738)
			(xy 272.342356 -204.382116) (xy 266.298172 -204.382116) (xy 266.297881 -204.387459) (xy 266.290309 -204.395002)
			(xy 266.284964 -204.395324) (xy 266.284456 -204.395324) (xy 265.768836 -204.395324) (xy 265.76096 -204.395596)
			(xy 265.745956 -204.400391) (xy 265.739372 -204.404722) (xy 265.718291 -204.419108) (xy 265.672647 -204.441938)
			(xy 265.624043 -204.457498) (xy 265.573626 -204.465418) (xy 265.54811 -204.465936) (xy 265.52259 -204.465452)
			(xy 265.472163 -204.457555) (xy 265.423551 -204.441993) (xy 265.377913 -204.419137) (xy 265.356848 -204.404722)
			(xy 265.350268 -204.400386) (xy 265.335259 -204.395612) (xy 265.327384 -204.395324) (xy 264.81151 -204.395324)
			(xy 264.806199 -204.394866) (xy 264.798625 -204.387418) (xy 264.798048 -204.382116) (xy 256.255609 -204.382116)
			(xy 256.26259 -204.392979) (xy 256.285247 -204.442589) (xy 256.300612 -204.494919) (xy 256.308374 -204.548903)
			(xy 256.30886 -204.576172) (xy 256.30886 -205.232254) (xy 268.898116 -205.232254) (xy 268.898116 -204.737716)
			(xy 268.89844 -204.73238) (xy 268.905988 -204.724837) (xy 268.911324 -204.724508) (xy 268.911832 -204.724508)
			(xy 269.427706 -204.724508) (xy 269.435516 -204.724196) (xy 269.450387 -204.719408) (xy 269.456916 -204.71511)
			(xy 269.478005 -204.700761) (xy 269.523666 -204.67803) (xy 269.572272 -204.662571) (xy 269.622675 -204.654748)
			(xy 269.673681 -204.654748) (xy 269.724084 -204.662571) (xy 269.77269 -204.67803) (xy 269.818351 -204.700761)
			(xy 269.83944 -204.71511) (xy 269.845963 -204.719416) (xy 269.86084 -204.72419) (xy 269.86865 -204.724508)
			(xy 270.384778 -204.724508) (xy 270.390072 -204.725034) (xy 270.397643 -204.732434) (xy 270.39824 -204.737716)
			(xy 270.39824 -205.232254) (xy 270.398224 -205.232508) (xy 276.442424 -205.232508) (xy 276.442424 -205.232)
			(xy 276.442424 -204.737716) (xy 276.442741 -204.732378) (xy 276.450294 -204.724834) (xy 276.455632 -204.724508)
			(xy 276.97176 -204.724508) (xy 276.979568 -204.724176) (xy 276.99444 -204.719402) (xy 277.00097 -204.71511)
			(xy 277.022059 -204.700761) (xy 277.06772 -204.67803) (xy 277.116326 -204.662571) (xy 277.166729 -204.654748)
			(xy 277.217735 -204.654748) (xy 277.268138 -204.662571) (xy 277.316744 -204.67803) (xy 277.362405 -204.700761)
			(xy 277.383494 -204.71511) (xy 277.390027 -204.719399) (xy 277.404896 -204.724183) (xy 277.412704 -204.724508)
			(xy 277.928832 -204.724508) (xy 277.934102 -204.724975) (xy 277.941544 -204.732444) (xy 277.94204 -204.737716)
			(xy 277.94204 -205.232254) (xy 277.942016 -205.232508) (xy 283.986224 -205.232508) (xy 283.986224 -205.232)
			(xy 283.986224 -204.737716) (xy 283.986541 -204.732378) (xy 283.994094 -204.724834) (xy 283.999432 -204.724508)
			(xy 284.51556 -204.724508) (xy 284.523368 -204.724176) (xy 284.53824 -204.719402) (xy 284.54477 -204.71511)
			(xy 284.565859 -204.700761) (xy 284.61152 -204.67803) (xy 284.660126 -204.662571) (xy 284.710529 -204.654748)
			(xy 284.761535 -204.654748) (xy 284.811938 -204.662571) (xy 284.860544 -204.67803) (xy 284.906205 -204.700761)
			(xy 284.927294 -204.71511) (xy 284.933827 -204.719399) (xy 284.948696 -204.724183) (xy 284.956504 -204.724508)
			(xy 285.472632 -204.724508) (xy 285.477902 -204.724975) (xy 285.485344 -204.732444) (xy 285.48584 -204.737716)
			(xy 285.48584 -205.232254) (xy 291.530024 -205.232254) (xy 291.530024 -204.737716) (xy 291.530341 -204.732378)
			(xy 291.537894 -204.724834) (xy 291.543232 -204.724508) (xy 291.54374 -204.724508) (xy 292.059614 -204.724508)
			(xy 292.067424 -204.724199) (xy 292.082296 -204.71941) (xy 292.088824 -204.71511) (xy 292.109913 -204.700761)
			(xy 292.155574 -204.67803) (xy 292.20418 -204.662571) (xy 292.254583 -204.654748) (xy 292.305589 -204.654748)
			(xy 292.355992 -204.662571) (xy 292.404598 -204.67803) (xy 292.450259 -204.700761) (xy 292.471348 -204.71511)
			(xy 292.477869 -204.719419) (xy 292.492747 -204.724191) (xy 292.500558 -204.724508) (xy 293.016686 -204.724508)
			(xy 293.021981 -204.725029) (xy 293.029551 -204.732433) (xy 293.030148 -204.737716) (xy 293.030148 -205.232254)
			(xy 293.030131 -205.232508) (xy 299.074332 -205.232508) (xy 299.074332 -205.232) (xy 299.074332 -204.737716)
			(xy 299.074641 -204.732376) (xy 299.0822 -204.724832) (xy 299.08754 -204.724508) (xy 299.603668 -204.724508)
			(xy 299.611477 -204.724179) (xy 299.626348 -204.719404) (xy 299.632878 -204.71511) (xy 299.653967 -204.700761)
			(xy 299.699628 -204.67803) (xy 299.748234 -204.662571) (xy 299.798637 -204.654748) (xy 299.849643 -204.654748)
			(xy 299.900046 -204.662571) (xy 299.948652 -204.67803) (xy 299.994313 -204.700761) (xy 300.015402 -204.71511)
			(xy 300.021933 -204.719402) (xy 300.036803 -204.724184) (xy 300.044612 -204.724508) (xy 300.56074 -204.724508)
			(xy 300.566012 -204.72497) (xy 300.573453 -204.732442) (xy 300.573948 -204.737716) (xy 300.573948 -205.232254)
			(xy 306.618132 -205.232254) (xy 306.618132 -204.737716) (xy 306.618441 -204.732376) (xy 306.626 -204.724832)
			(xy 306.63134 -204.724508) (xy 306.631848 -204.724508) (xy 308.104794 -204.724508) (xy 308.11009 -204.725023)
			(xy 308.11766 -204.732432) (xy 308.118256 -204.737716) (xy 308.118256 -205.232254) (xy 308.118239 -205.232508)
			(xy 415.718244 -205.232508) (xy 415.718244 -204.737716) (xy 415.7188 -204.732467) (xy 415.726205 -204.725026)
			(xy 415.731452 -204.724508) (xy 417.204652 -204.724508) (xy 417.209982 -204.724861) (xy 417.217526 -204.732387)
			(xy 417.21786 -204.737716) (xy 417.21786 -205.232254) (xy 423.262044 -205.232254) (xy 423.262044 -204.737716)
			(xy 423.2626 -204.732467) (xy 423.270005 -204.725026) (xy 423.275252 -204.724508) (xy 423.27576 -204.724508)
			(xy 423.791634 -204.724508) (xy 423.799441 -204.724165) (xy 423.814313 -204.719399) (xy 423.820844 -204.71511)
			(xy 423.841933 -204.700761) (xy 423.887594 -204.67803) (xy 423.9362 -204.662571) (xy 423.986603 -204.654748)
			(xy 424.037609 -204.654748) (xy 424.088012 -204.662571) (xy 424.136618 -204.67803) (xy 424.182279 -204.700761)
			(xy 424.203368 -204.71511) (xy 424.209907 -204.719389) (xy 424.224771 -204.724179) (xy 424.232578 -204.724508)
			(xy 424.748706 -204.724508) (xy 424.754003 -204.725015) (xy 424.761572 -204.73243) (xy 424.762168 -204.737716)
			(xy 424.762168 -205.232254) (xy 424.76215 -205.232508) (xy 430.806352 -205.232508) (xy 430.806352 -205.232)
			(xy 430.806352 -204.737716) (xy 430.806901 -204.732465) (xy 430.814311 -204.725024) (xy 430.81956 -204.724508)
			(xy 431.335688 -204.724508) (xy 431.343497 -204.724188) (xy 431.358369 -204.719406) (xy 431.364898 -204.71511)
			(xy 431.385987 -204.700761) (xy 431.431648 -204.67803) (xy 431.480254 -204.662571) (xy 431.530657 -204.654748)
			(xy 431.581663 -204.654748) (xy 431.632066 -204.662571) (xy 431.680672 -204.67803) (xy 431.726333 -204.700761)
			(xy 431.747422 -204.71511) (xy 431.753949 -204.719409) (xy 431.768822 -204.724187) (xy 431.776632 -204.724508)
			(xy 432.29276 -204.724508) (xy 432.298091 -204.724855) (xy 432.305635 -204.732386) (xy 432.305968 -204.737716)
			(xy 432.305968 -205.232254) (xy 438.350152 -205.232254) (xy 438.350152 -204.737716) (xy 438.350701 -204.732465)
			(xy 438.358111 -204.725024) (xy 438.36336 -204.724508) (xy 438.363868 -204.724508) (xy 438.879742 -204.724508)
			(xy 438.88755 -204.724168) (xy 438.902421 -204.7194) (xy 438.908952 -204.71511) (xy 438.930041 -204.700761)
			(xy 438.975702 -204.67803) (xy 439.024308 -204.662571) (xy 439.074711 -204.654748) (xy 439.125717 -204.654748)
			(xy 439.17612 -204.662571) (xy 439.224726 -204.67803) (xy 439.270387 -204.700761) (xy 439.291476 -204.71511)
			(xy 439.298013 -204.719392) (xy 439.312879 -204.72418) (xy 439.320686 -204.724508) (xy 439.836814 -204.724508)
			(xy 439.842112 -204.72501) (xy 439.849681 -204.732429) (xy 439.850276 -204.737716) (xy 439.850276 -205.232254)
			(xy 439.850258 -205.232508) (xy 445.89446 -205.232508) (xy 445.89446 -205.232) (xy 445.89446 -204.737716)
			(xy 445.895002 -204.732463) (xy 445.902417 -204.725021) (xy 445.907668 -204.724508) (xy 446.423796 -204.724508)
			(xy 446.431606 -204.724191) (xy 446.446477 -204.719407) (xy 446.453006 -204.71511) (xy 446.474095 -204.700761)
			(xy 446.519756 -204.67803) (xy 446.568362 -204.662571) (xy 446.618765 -204.654748) (xy 446.669771 -204.654748)
			(xy 446.720174 -204.662571) (xy 446.76878 -204.67803) (xy 446.814441 -204.700761) (xy 446.83553 -204.71511)
			(xy 446.842055 -204.719412) (xy 446.85693 -204.724188) (xy 446.86474 -204.724508) (xy 447.380868 -204.724508)
			(xy 447.3862 -204.72485) (xy 447.393744 -204.732385) (xy 447.394076 -204.737716) (xy 447.394076 -205.232254)
			(xy 447.394051 -205.232508) (xy 453.43826 -205.232508) (xy 453.43826 -205.232) (xy 453.43826 -204.737716)
			(xy 453.438802 -204.732463) (xy 453.446217 -204.725021) (xy 453.451468 -204.724508) (xy 453.967596 -204.724508)
			(xy 453.975406 -204.724191) (xy 453.990277 -204.719407) (xy 453.996806 -204.71511) (xy 454.017895 -204.700761)
			(xy 454.063556 -204.67803) (xy 454.112162 -204.662571) (xy 454.162565 -204.654748) (xy 454.213571 -204.654748)
			(xy 454.263974 -204.662571) (xy 454.31258 -204.67803) (xy 454.358241 -204.700761) (xy 454.37933 -204.71511)
			(xy 454.385855 -204.719412) (xy 454.40073 -204.724188) (xy 454.40854 -204.724508) (xy 454.924668 -204.724508)
			(xy 454.93 -204.72485) (xy 454.937544 -204.732385) (xy 454.937876 -204.737716) (xy 454.937876 -205.232254)
			(xy 454.937348 -205.237549) (xy 454.92995 -205.245122) (xy 454.924668 -205.245716) (xy 454.408794 -205.245716)
			(xy 454.400983 -205.246024) (xy 454.386112 -205.250814) (xy 454.379584 -205.255114) (xy 454.358461 -205.269462)
			(xy 454.312738 -205.29219) (xy 454.264065 -205.307621) (xy 454.213599 -205.315387) (xy 454.188068 -205.31582)
			(xy 454.162537 -205.315408) (xy 454.112072 -205.307626) (xy 454.063399 -205.29219) (xy 454.017673 -205.269465)
			(xy 453.996552 -205.255114) (xy 453.99003 -205.250807) (xy 453.975153 -205.246033) (xy 453.967342 -205.245716)
			(xy 453.451468 -205.245716) (xy 453.446203 -205.245227) (xy 453.438763 -205.237774) (xy 453.43826 -205.232508)
			(xy 447.394051 -205.232508) (xy 447.393548 -205.237549) (xy 447.38615 -205.245122) (xy 447.380868 -205.245716)
			(xy 446.864994 -205.245716) (xy 446.857183 -205.246024) (xy 446.842312 -205.250814) (xy 446.835784 -205.255114)
			(xy 446.814661 -205.269462) (xy 446.768938 -205.29219) (xy 446.720265 -205.307621) (xy 446.669799 -205.315387)
			(xy 446.644268 -205.31582) (xy 446.618737 -205.315408) (xy 446.568272 -205.307626) (xy 446.519599 -205.29219)
			(xy 446.473873 -205.269465) (xy 446.452752 -205.255114) (xy 446.44623 -205.250807) (xy 446.431353 -205.246033)
			(xy 446.423542 -205.245716) (xy 445.907668 -205.245716) (xy 445.902403 -205.245227) (xy 445.894963 -205.237774)
			(xy 445.89446 -205.232508) (xy 439.850258 -205.232508) (xy 439.849891 -205.237679) (xy 439.842238 -205.245367)
			(xy 439.836814 -205.245716) (xy 439.32094 -205.245716) (xy 439.313131 -205.246044) (xy 439.29826 -205.25082)
			(xy 439.29173 -205.255114) (xy 439.270622 -205.269485) (xy 439.224894 -205.292208) (xy 439.176216 -205.307632)
			(xy 439.125746 -205.315391) (xy 439.100214 -205.31582) (xy 439.074684 -205.315384) (xy 439.024219 -205.30761)
			(xy 438.975547 -205.29218) (xy 438.929819 -205.269462) (xy 438.908698 -205.255114) (xy 438.902165 -205.250824)
			(xy 438.887296 -205.24604) (xy 438.879488 -205.245716) (xy 438.363614 -205.245716) (xy 438.35817 -205.245407)
			(xy 438.35048 -205.237699) (xy 438.350152 -205.232254) (xy 432.305968 -205.232254) (xy 432.305447 -205.237551)
			(xy 432.298045 -205.245124) (xy 432.29276 -205.245716) (xy 431.776886 -205.245716) (xy 431.769075 -205.246021)
			(xy 431.754204 -205.250813) (xy 431.747676 -205.255114) (xy 431.726556 -205.269465) (xy 431.680832 -205.292193)
			(xy 431.632158 -205.307622) (xy 431.581691 -205.315388) (xy 431.55616 -205.31582) (xy 431.530629 -205.315412)
			(xy 431.480163 -205.307628) (xy 431.431491 -205.292191) (xy 431.385765 -205.269466) (xy 431.364644 -205.255114)
			(xy 431.358123 -205.250804) (xy 431.343245 -205.246032) (xy 431.335434 -205.245716) (xy 430.81956 -205.245716)
			(xy 430.814294 -205.245233) (xy 430.806854 -205.237775) (xy 430.806352 -205.232508) (xy 424.76215 -205.232508)
			(xy 424.761791 -205.237681) (xy 424.754132 -205.24537) (xy 424.748706 -205.245716) (xy 424.232832 -205.245716)
			(xy 424.225023 -205.24604) (xy 424.210151 -205.250819) (xy 424.203622 -205.255114) (xy 424.182489 -205.269445)
			(xy 424.13677 -205.292177) (xy 424.0881 -205.307613) (xy 424.037636 -205.315384) (xy 424.012106 -205.31582)
			(xy 423.986575 -205.315388) (xy 423.936111 -205.307612) (xy 423.887438 -205.292182) (xy 423.841711 -205.269463)
			(xy 423.82059 -205.255114) (xy 423.814059 -205.250821) (xy 423.799189 -205.246039) (xy 423.79138 -205.245716)
			(xy 423.275506 -205.245716) (xy 423.270061 -205.245412) (xy 423.262372 -205.2377) (xy 423.262044 -205.232254)
			(xy 417.21786 -205.232254) (xy 417.217346 -205.237553) (xy 417.209939 -205.245127) (xy 417.204652 -205.245716)
			(xy 415.731452 -205.245716) (xy 415.726185 -205.245238) (xy 415.718746 -205.237776) (xy 415.718244 -205.232508)
			(xy 308.118239 -205.232508) (xy 308.117889 -205.237684) (xy 308.110223 -205.245373) (xy 308.104794 -205.245716)
			(xy 306.631594 -205.245716) (xy 306.626147 -205.24542) (xy 306.618459 -205.237702) (xy 306.618132 -205.232254)
			(xy 300.573948 -205.232254) (xy 300.573445 -205.237556) (xy 300.56603 -205.24513) (xy 300.56074 -205.245716)
			(xy 300.044866 -205.245716) (xy 300.037058 -205.246055) (xy 300.022187 -205.250824) (xy 300.015656 -205.255114)
			(xy 299.994541 -205.269474) (xy 299.948815 -205.292199) (xy 299.90014 -205.307627) (xy 299.849672 -205.315389)
			(xy 299.82414 -205.31582) (xy 299.79861 -205.315371) (xy 299.748146 -205.307601) (xy 299.699474 -205.292175)
			(xy 299.653746 -205.269461) (xy 299.632624 -205.255114) (xy 299.626086 -205.250834) (xy 299.611221 -205.246044)
			(xy 299.603414 -205.245716) (xy 299.08754 -205.245716) (xy 299.082215 -205.245347) (xy 299.074672 -205.237832)
			(xy 299.074332 -205.232508) (xy 293.030131 -205.232508) (xy 293.029789 -205.237686) (xy 293.022117 -205.245376)
			(xy 293.016686 -205.245716) (xy 292.500812 -205.245716) (xy 292.493002 -205.246032) (xy 292.478131 -205.250816)
			(xy 292.471602 -205.255114) (xy 292.450474 -205.269454) (xy 292.404753 -205.292184) (xy 292.356082 -205.307617)
			(xy 292.305617 -205.315386) (xy 292.280086 -205.31582) (xy 292.254555 -205.315398) (xy 292.20409 -205.307619)
			(xy 292.155418 -205.292186) (xy 292.109691 -205.269464) (xy 292.08857 -205.255114) (xy 292.082044 -205.250814)
			(xy 292.06717 -205.246036) (xy 292.05936 -205.245716) (xy 291.543486 -205.245716) (xy 291.538038 -205.245425)
			(xy 291.53035 -205.237703) (xy 291.530024 -205.232254) (xy 285.48584 -205.232254) (xy 285.485344 -205.237557)
			(xy 285.477924 -205.245132) (xy 285.472632 -205.245716) (xy 284.956758 -205.245716) (xy 284.94895 -205.246052)
			(xy 284.934078 -205.250822) (xy 284.927548 -205.255114) (xy 284.906435 -205.269477) (xy 284.860709 -205.292202)
			(xy 284.812033 -205.307628) (xy 284.761564 -205.31539) (xy 284.736032 -205.31582) (xy 284.710502 -205.315375)
			(xy 284.660038 -205.307603) (xy 284.611365 -205.292177) (xy 284.565638 -205.269461) (xy 284.544516 -205.255114)
			(xy 284.537979 -205.250831) (xy 284.523113 -205.246043) (xy 284.515306 -205.245716) (xy 283.999432 -205.245716)
			(xy 283.994106 -205.245352) (xy 283.986564 -205.237833) (xy 283.986224 -205.232508) (xy 277.942016 -205.232508)
			(xy 277.941544 -205.237557) (xy 277.934124 -205.245132) (xy 277.928832 -205.245716) (xy 277.412958 -205.245716)
			(xy 277.40515 -205.246052) (xy 277.390278 -205.250822) (xy 277.383748 -205.255114) (xy 277.362635 -205.269477)
			(xy 277.316909 -205.292202) (xy 277.268233 -205.307628) (xy 277.217764 -205.31539) (xy 277.192232 -205.31582)
			(xy 277.166702 -205.315375) (xy 277.116238 -205.307603) (xy 277.067565 -205.292177) (xy 277.021838 -205.269461)
			(xy 277.000716 -205.255114) (xy 276.994179 -205.250831) (xy 276.979313 -205.246043) (xy 276.971506 -205.245716)
			(xy 276.455632 -205.245716) (xy 276.450306 -205.245352) (xy 276.442764 -205.237833) (xy 276.442424 -205.232508)
			(xy 270.398224 -205.232508) (xy 270.397888 -205.237688) (xy 270.390211 -205.245378) (xy 270.384778 -205.245716)
			(xy 269.868904 -205.245716) (xy 269.861094 -205.246029) (xy 269.846222 -205.250815) (xy 269.839694 -205.255114)
			(xy 269.818569 -205.269458) (xy 269.772847 -205.292187) (xy 269.724174 -205.307619) (xy 269.673709 -205.315386)
			(xy 269.648178 -205.31582) (xy 269.622647 -205.315403) (xy 269.572182 -205.307622) (xy 269.523509 -205.292188)
			(xy 269.477783 -205.269465) (xy 269.456662 -205.255114) (xy 269.450137 -205.250811) (xy 269.435262 -205.246035)
			(xy 269.427452 -205.245716) (xy 268.911578 -205.245716) (xy 268.906129 -205.245431) (xy 268.898442 -205.237705)
			(xy 268.898116 -205.232254) (xy 256.30886 -205.232254) (xy 256.30886 -205.439772) (xy 256.308374 -205.467041)
			(xy 256.300612 -205.521025) (xy 256.285247 -205.573355) (xy 256.26259 -205.622965) (xy 256.233104 -205.668846)
			(xy 256.197389 -205.710063) (xy 256.156172 -205.745778) (xy 256.110291 -205.775264) (xy 256.060681 -205.797921)
			(xy 256.008351 -205.813286) (xy 255.954367 -205.821048) (xy 255.899829 -205.821048) (xy 255.845845 -205.813286)
			(xy 255.793515 -205.797921) (xy 255.743905 -205.775264) (xy 255.698024 -205.745778) (xy 255.656807 -205.710063)
			(xy 255.621092 -205.668846) (xy 255.591606 -205.622965) (xy 255.568949 -205.573355) (xy 255.553584 -205.521025)
			(xy 255.545822 -205.467041) (xy 255.545336 -205.439772) (xy 2.509012 -205.439772) (xy 2.509012 -206.082392)
			(xy 16.85798 -206.082392) (xy 16.85798 -205.587854) (xy 16.858424 -205.582474) (xy 16.866059 -205.574889)
			(xy 16.871442 -205.574392) (xy 17.38757 -205.574392) (xy 17.395379 -205.574067) (xy 17.410251 -205.569289)
			(xy 17.41678 -205.564994) (xy 17.437869 -205.550645) (xy 17.48353 -205.527914) (xy 17.532136 -205.512455)
			(xy 17.582539 -205.504632) (xy 17.633545 -205.504632) (xy 17.683948 -205.512455) (xy 17.732554 -205.527914)
			(xy 17.778215 -205.550645) (xy 17.799304 -205.564994) (xy 17.805836 -205.569285) (xy 17.820706 -205.574068)
			(xy 17.828514 -205.574392) (xy 18.344642 -205.574392) (xy 18.35 -205.574918) (xy 18.357581 -205.582496)
			(xy 18.358104 -205.587854) (xy 18.358104 -206.082392) (xy 24.402288 -206.082392) (xy 24.402288 -205.587854)
			(xy 24.402765 -205.582545) (xy 24.410197 -205.574968) (xy 24.415496 -205.574392) (xy 24.931624 -205.574392)
			(xy 24.939435 -205.57409) (xy 24.954306 -205.569296) (xy 24.960834 -205.564994) (xy 24.981923 -205.550645)
			(xy 25.027584 -205.527914) (xy 25.07619 -205.512455) (xy 25.126593 -205.504632) (xy 25.177599 -205.504632)
			(xy 25.228002 -205.512455) (xy 25.276608 -205.527914) (xy 25.322269 -205.550645) (xy 25.343358 -205.564994)
			(xy 25.349878 -205.569306) (xy 25.364757 -205.574076) (xy 25.372568 -205.574392) (xy 25.888696 -205.574392)
			(xy 25.894028 -205.57473) (xy 25.901569 -205.582268) (xy 25.901904 -205.5876) (xy 25.901904 -205.588108)
			(xy 25.901904 -206.082392) (xy 31.946088 -206.082392) (xy 31.946088 -205.587854) (xy 31.946565 -205.582545)
			(xy 31.953997 -205.574968) (xy 31.959296 -205.574392) (xy 32.475424 -205.574392) (xy 32.483235 -205.57409)
			(xy 32.498106 -205.569296) (xy 32.504634 -205.564994) (xy 32.525723 -205.550645) (xy 32.571384 -205.527914)
			(xy 32.61999 -205.512455) (xy 32.670393 -205.504632) (xy 32.721399 -205.504632) (xy 32.771802 -205.512455)
			(xy 32.820408 -205.527914) (xy 32.866069 -205.550645) (xy 32.887158 -205.564994) (xy 32.893678 -205.569306)
			(xy 32.908557 -205.574076) (xy 32.916368 -205.574392) (xy 33.432496 -205.574392) (xy 33.437828 -205.57473)
			(xy 33.445369 -205.582268) (xy 33.445704 -205.5876) (xy 33.445704 -205.588108) (xy 33.445704 -206.082392)
			(xy 39.489888 -206.082392) (xy 39.489888 -205.587854) (xy 39.490415 -205.582497) (xy 39.497993 -205.574916)
			(xy 39.50335 -205.574392) (xy 40.019478 -205.574392) (xy 40.027287 -205.57407) (xy 40.042159 -205.56929)
			(xy 40.048688 -205.564994) (xy 40.069777 -205.550645) (xy 40.115438 -205.527914) (xy 40.164044 -205.512455)
			(xy 40.214447 -205.504632) (xy 40.265453 -205.504632) (xy 40.315856 -205.512455) (xy 40.364462 -205.527914)
			(xy 40.410123 -205.550645) (xy 40.431212 -205.564994) (xy 40.437742 -205.569288) (xy 40.452613 -205.574069)
			(xy 40.460422 -205.574392) (xy 40.97655 -205.574392) (xy 40.981909 -205.574913) (xy 40.989489 -205.582495)
			(xy 40.990012 -205.587854) (xy 40.990012 -206.082392) (xy 47.034196 -206.082392) (xy 47.034196 -205.587854)
			(xy 47.034754 -205.582566) (xy 47.042131 -205.574995) (xy 47.047404 -205.574392) (xy 47.563532 -205.574392)
			(xy 47.57134 -205.574051) (xy 47.586211 -205.569284) (xy 47.592742 -205.564994) (xy 47.613831 -205.550645)
			(xy 47.659492 -205.527914) (xy 47.708098 -205.512455) (xy 47.758501 -205.504632) (xy 47.809507 -205.504632)
			(xy 47.85991 -205.512455) (xy 47.908516 -205.527914) (xy 47.954177 -205.550645) (xy 47.975266 -205.564994)
			(xy 47.981806 -205.56927) (xy 47.99667 -205.574063) (xy 48.004476 -205.574392) (xy 48.520604 -205.574392)
			(xy 48.525867 -205.574892) (xy 48.53331 -205.582337) (xy 48.533812 -205.5876) (xy 48.533812 -205.588108)
			(xy 48.533812 -206.082392) (xy 54.577996 -206.082392) (xy 54.577996 -205.587854) (xy 54.578516 -205.582495)
			(xy 54.586098 -205.574914) (xy 54.591458 -205.574392) (xy 56.064658 -205.574392) (xy 56.070006 -205.574974)
			(xy 56.077591 -205.58251) (xy 56.07812 -205.587854) (xy 56.07812 -206.082392) (xy 163.678108 -206.082392)
			(xy 163.678108 -205.587854) (xy 163.678656 -205.582564) (xy 163.686039 -205.574991) (xy 163.691316 -205.574392)
			(xy 165.164516 -205.574392) (xy 165.169781 -205.574884) (xy 165.177222 -205.582335) (xy 165.177724 -205.5876)
			(xy 165.177724 -205.588108) (xy 165.177724 -206.082392) (xy 171.221908 -206.082392) (xy 171.221908 -205.587854)
			(xy 171.222417 -205.582492) (xy 171.230007 -205.57491) (xy 171.23537 -205.574392) (xy 171.751498 -205.574392)
			(xy 171.759308 -205.574079) (xy 171.77418 -205.569293) (xy 171.780708 -205.564994) (xy 171.801797 -205.550645)
			(xy 171.847458 -205.527914) (xy 171.896064 -205.512455) (xy 171.946467 -205.504632) (xy 171.997473 -205.504632)
			(xy 172.047876 -205.512455) (xy 172.096482 -205.527914) (xy 172.142143 -205.550645) (xy 172.163232 -205.564994)
			(xy 172.169757 -205.569296) (xy 172.184632 -205.574072) (xy 172.192442 -205.574392) (xy 172.70857 -205.574392)
			(xy 172.713919 -205.574966) (xy 172.721504 -205.582508) (xy 172.722032 -205.587854) (xy 172.722032 -206.082392)
			(xy 178.766216 -206.082392) (xy 178.766216 -205.587854) (xy 178.766756 -205.582562) (xy 178.774145 -205.574989)
			(xy 178.779424 -205.574392) (xy 179.295552 -205.574392) (xy 179.30336 -205.574059) (xy 179.318232 -205.569287)
			(xy 179.324762 -205.564994) (xy 179.345851 -205.550645) (xy 179.391512 -205.527914) (xy 179.440118 -205.512455)
			(xy 179.490521 -205.504632) (xy 179.541527 -205.504632) (xy 179.59193 -205.512455) (xy 179.640536 -205.527914)
			(xy 179.686197 -205.550645) (xy 179.707286 -205.564994) (xy 179.713822 -205.569278) (xy 179.728688 -205.574066)
			(xy 179.736496 -205.574392) (xy 180.252624 -205.574392) (xy 180.25789 -205.574879) (xy 180.265331 -205.582334)
			(xy 180.265832 -205.5876) (xy 180.265832 -205.588108) (xy 180.265832 -206.082392) (xy 186.310016 -206.082392)
			(xy 186.310016 -205.587854) (xy 186.310518 -205.58249) (xy 186.318113 -205.574908) (xy 186.323478 -205.574392)
			(xy 186.839606 -205.574392) (xy 186.847416 -205.574082) (xy 186.862288 -205.569294) (xy 186.868816 -205.564994)
			(xy 186.889905 -205.550645) (xy 186.935566 -205.527914) (xy 186.984172 -205.512455) (xy 187.034575 -205.504632)
			(xy 187.085581 -205.504632) (xy 187.135984 -205.512455) (xy 187.18459 -205.527914) (xy 187.230251 -205.550645)
			(xy 187.25134 -205.564994) (xy 187.257864 -205.569299) (xy 187.27274 -205.574074) (xy 187.28055 -205.574392)
			(xy 187.796678 -205.574392) (xy 187.802028 -205.574961) (xy 187.809612 -205.582506) (xy 187.81014 -205.587854)
			(xy 187.81014 -206.082392) (xy 193.854324 -206.082392) (xy 193.854324 -205.587854) (xy 193.854857 -205.58256)
			(xy 193.862251 -205.574987) (xy 193.867532 -205.574392) (xy 194.38366 -205.574392) (xy 194.391469 -205.574063)
			(xy 194.40634 -205.569288) (xy 194.41287 -205.564994) (xy 194.433959 -205.550645) (xy 194.47962 -205.527914)
			(xy 194.528226 -205.512455) (xy 194.578629 -205.504632) (xy 194.629635 -205.504632) (xy 194.680038 -205.512455)
			(xy 194.728644 -205.527914) (xy 194.774305 -205.550645) (xy 194.795394 -205.564994) (xy 194.801928 -205.569281)
			(xy 194.816796 -205.574067) (xy 194.824604 -205.574392) (xy 195.340732 -205.574392) (xy 195.345999 -205.574873)
			(xy 195.353439 -205.582332) (xy 195.35394 -205.5876) (xy 195.35394 -205.588108) (xy 195.35394 -206.082392)
			(xy 201.398124 -206.082392) (xy 201.398124 -205.587854) (xy 201.398657 -205.58256) (xy 201.406051 -205.574987)
			(xy 201.411332 -205.574392) (xy 201.92746 -205.574392) (xy 201.935269 -205.574063) (xy 201.95014 -205.569288)
			(xy 201.95667 -205.564994) (xy 201.977759 -205.550645) (xy 202.02342 -205.527914) (xy 202.072026 -205.512455)
			(xy 202.122429 -205.504632) (xy 202.173435 -205.504632) (xy 202.223838 -205.512455) (xy 202.272444 -205.527914)
			(xy 202.318105 -205.550645) (xy 202.339194 -205.564994) (xy 202.345728 -205.569281) (xy 202.360596 -205.574067)
			(xy 202.368404 -205.574392) (xy 202.884532 -205.574392) (xy 202.889799 -205.574873) (xy 202.897239 -205.582332)
			(xy 202.89774 -205.5876) (xy 202.89774 -205.588108) (xy 202.89774 -206.082138) (xy 264.798048 -206.082138)
			(xy 264.798048 -205.5876) (xy 264.79859 -205.582348) (xy 264.806006 -205.574908) (xy 264.811256 -205.574392)
			(xy 264.811764 -205.574392) (xy 265.327638 -205.574392) (xy 265.335446 -205.574053) (xy 265.350317 -205.569284)
			(xy 265.356848 -205.564994) (xy 265.377937 -205.550645) (xy 265.423598 -205.527914) (xy 265.472204 -205.512455)
			(xy 265.522607 -205.504632) (xy 265.573613 -205.504632) (xy 265.624016 -205.512455) (xy 265.672622 -205.527914)
			(xy 265.718283 -205.550645) (xy 265.739372 -205.564994) (xy 265.745911 -205.569273) (xy 265.760775 -205.574064)
			(xy 265.768582 -205.574392) (xy 266.28471 -205.574392) (xy 266.290004 -205.574911) (xy 266.297572 -205.582318)
			(xy 266.298172 -205.5876) (xy 266.298172 -206.082138) (xy 266.298149 -206.082392) (xy 272.342356 -206.082392)
			(xy 272.342356 -206.081884) (xy 272.342356 -205.5876) (xy 272.342891 -205.582346) (xy 272.350311 -205.574906)
			(xy 272.355564 -205.574392) (xy 272.871692 -205.574392) (xy 272.879502 -205.574076) (xy 272.894373 -205.569292)
			(xy 272.900902 -205.564994) (xy 272.921991 -205.550645) (xy 272.967652 -205.527914) (xy 273.016258 -205.512455)
			(xy 273.066661 -205.504632) (xy 273.117667 -205.504632) (xy 273.16807 -205.512455) (xy 273.216676 -205.527914)
			(xy 273.262337 -205.550645) (xy 273.283426 -205.564994) (xy 273.289953 -205.569293) (xy 273.304826 -205.574072)
			(xy 273.312636 -205.574392) (xy 273.828764 -205.574392) (xy 273.834092 -205.574751) (xy 273.841635 -205.582273)
			(xy 273.841972 -205.5876) (xy 273.841972 -206.082138) (xy 273.84195 -206.082392) (xy 279.886156 -206.082392)
			(xy 279.886156 -206.081884) (xy 279.886156 -205.5876) (xy 279.886691 -205.582346) (xy 279.894111 -205.574906)
			(xy 279.899364 -205.574392) (xy 280.415492 -205.574392) (xy 280.423302 -205.574076) (xy 280.438173 -205.569292)
			(xy 280.444702 -205.564994) (xy 280.465791 -205.550645) (xy 280.511452 -205.527914) (xy 280.560058 -205.512455)
			(xy 280.610461 -205.504632) (xy 280.661467 -205.504632) (xy 280.71187 -205.512455) (xy 280.760476 -205.527914)
			(xy 280.806137 -205.550645) (xy 280.827226 -205.564994) (xy 280.833753 -205.569293) (xy 280.848626 -205.574072)
			(xy 280.856436 -205.574392) (xy 281.372564 -205.574392) (xy 281.377892 -205.574751) (xy 281.385435 -205.582273)
			(xy 281.385772 -205.5876) (xy 281.385772 -206.082138) (xy 287.429956 -206.082138) (xy 287.429956 -205.5876)
			(xy 287.430491 -205.582346) (xy 287.437911 -205.574906) (xy 287.443164 -205.574392) (xy 287.443672 -205.574392)
			(xy 287.959546 -205.574392) (xy 287.967354 -205.574057) (xy 287.982226 -205.569286) (xy 287.988756 -205.564994)
			(xy 288.009845 -205.550645) (xy 288.055506 -205.527914) (xy 288.104112 -205.512455) (xy 288.154515 -205.504632)
			(xy 288.205521 -205.504632) (xy 288.255924 -205.512455) (xy 288.30453 -205.527914) (xy 288.350191 -205.550645)
			(xy 288.37128 -205.564994) (xy 288.377817 -205.569276) (xy 288.392683 -205.574065) (xy 288.40049 -205.574392)
			(xy 288.916618 -205.574392) (xy 288.921913 -205.574905) (xy 288.929481 -205.582316) (xy 288.93008 -205.5876)
			(xy 288.93008 -206.082138) (xy 288.930056 -206.082392) (xy 294.974264 -206.082392) (xy 294.974264 -206.081884)
			(xy 294.974264 -205.5876) (xy 294.974792 -205.582344) (xy 294.982217 -205.574903) (xy 294.987472 -205.574392)
			(xy 295.5036 -205.574392) (xy 295.51141 -205.57408) (xy 295.526282 -205.569293) (xy 295.53281 -205.564994)
			(xy 295.553899 -205.550645) (xy 295.59956 -205.527914) (xy 295.648166 -205.512455) (xy 295.698569 -205.504632)
			(xy 295.749575 -205.504632) (xy 295.799978 -205.512455) (xy 295.848584 -205.527914) (xy 295.894245 -205.550645)
			(xy 295.915334 -205.564994) (xy 295.921859 -205.569297) (xy 295.936734 -205.574073) (xy 295.944544 -205.574392)
			(xy 296.460672 -205.574392) (xy 296.466001 -205.574745) (xy 296.473543 -205.582272) (xy 296.47388 -205.5876)
			(xy 296.47388 -206.082138) (xy 302.518064 -206.082138) (xy 302.518064 -205.5876) (xy 302.518592 -205.582344)
			(xy 302.526017 -205.574903) (xy 302.531272 -205.574392) (xy 304.004726 -205.574392) (xy 304.010022 -205.5749)
			(xy 304.017589 -205.582315) (xy 304.018188 -205.5876) (xy 304.018188 -206.082138) (xy 304.018164 -206.082392)
			(xy 411.618176 -206.082392) (xy 411.618176 -206.081884) (xy 411.618176 -205.5876) (xy 411.618693 -205.582341)
			(xy 411.626126 -205.5749) (xy 411.631384 -205.574392) (xy 413.104584 -205.574392) (xy 413.109914 -205.574738)
			(xy 413.117456 -205.58227) (xy 413.117792 -205.5876) (xy 413.117792 -206.082138) (xy 419.161976 -206.082138)
			(xy 419.161976 -205.5876) (xy 419.162493 -205.582341) (xy 419.169926 -205.5749) (xy 419.175184 -205.574392)
			(xy 419.175692 -205.574392) (xy 419.691566 -205.574392) (xy 419.699375 -205.574065) (xy 419.714246 -205.569288)
			(xy 419.720776 -205.564994) (xy 419.741865 -205.550645) (xy 419.787526 -205.527914) (xy 419.836132 -205.512455)
			(xy 419.886535 -205.504632) (xy 419.937541 -205.504632) (xy 419.987944 -205.512455) (xy 420.03655 -205.527914)
			(xy 420.082211 -205.550645) (xy 420.1033 -205.564994) (xy 420.109833 -205.569284) (xy 420.124702 -205.574068)
			(xy 420.13251 -205.574392) (xy 420.648638 -205.574392) (xy 420.653936 -205.574892) (xy 420.661502 -205.582313)
			(xy 420.6621 -205.5876) (xy 420.6621 -206.082138) (xy 420.662075 -206.082392) (xy 426.706284 -206.082392)
			(xy 426.706284 -206.081884) (xy 426.706284 -205.5876) (xy 426.706794 -205.582339) (xy 426.714232 -205.574897)
			(xy 426.719492 -205.574392) (xy 427.23562 -205.574392) (xy 427.243431 -205.574088) (xy 427.258302 -205.569295)
			(xy 427.26483 -205.564994) (xy 427.285919 -205.550645) (xy 427.33158 -205.527914) (xy 427.380186 -205.512455)
			(xy 427.430589 -205.504632) (xy 427.481595 -205.504632) (xy 427.531998 -205.512455) (xy 427.580604 -205.527914)
			(xy 427.626265 -205.550645) (xy 427.647354 -205.564994) (xy 427.653875 -205.569304) (xy 427.668753 -205.574076)
			(xy 427.676564 -205.574392) (xy 428.192692 -205.574392) (xy 428.198023 -205.574732) (xy 428.205565 -205.582269)
			(xy 428.2059 -205.5876) (xy 428.2059 -206.082138) (xy 434.250084 -206.082138) (xy 434.250084 -205.5876)
			(xy 434.250594 -205.582339) (xy 434.258032 -205.574897) (xy 434.263292 -205.574392) (xy 434.2638 -205.574392)
			(xy 434.779674 -205.574392) (xy 434.787483 -205.574069) (xy 434.802355 -205.56929) (xy 434.808884 -205.564994)
			(xy 434.829973 -205.550645) (xy 434.875634 -205.527914) (xy 434.92424 -205.512455) (xy 434.974643 -205.504632)
			(xy 435.025649 -205.504632) (xy 435.076052 -205.512455) (xy 435.124658 -205.527914) (xy 435.170319 -205.550645)
			(xy 435.191408 -205.564994) (xy 435.197939 -205.569287) (xy 435.212809 -205.574069) (xy 435.220618 -205.574392)
			(xy 435.736746 -205.574392) (xy 435.742033 -205.574954) (xy 435.749604 -205.582328) (xy 435.750208 -205.5876)
			(xy 435.750208 -206.082138) (xy 435.750183 -206.082392) (xy 441.794392 -206.082392) (xy 441.794392 -206.081884)
			(xy 441.794392 -205.5876) (xy 441.794895 -205.582337) (xy 441.802337 -205.574895) (xy 441.8076 -205.574392)
			(xy 442.323728 -205.574392) (xy 442.331539 -205.574092) (xy 442.346411 -205.569297) (xy 442.352938 -205.564994)
			(xy 442.374027 -205.550645) (xy 442.419688 -205.527914) (xy 442.468294 -205.512455) (xy 442.518697 -205.504632)
			(xy 442.569703 -205.504632) (xy 442.620106 -205.512455) (xy 442.668712 -205.527914) (xy 442.714373 -205.550645)
			(xy 442.735462 -205.564994) (xy 442.742003 -205.569269) (xy 442.756866 -205.574062) (xy 442.764672 -205.574392)
			(xy 443.2808 -205.574392) (xy 443.286063 -205.574895) (xy 443.293505 -205.582337) (xy 443.294008 -205.5876)
			(xy 443.294008 -206.082138) (xy 443.293984 -206.082392) (xy 449.338192 -206.082392) (xy 449.338192 -206.081884)
			(xy 449.338192 -205.5876) (xy 449.338695 -205.582337) (xy 449.346137 -205.574895) (xy 449.3514 -205.574392)
			(xy 449.867528 -205.574392) (xy 449.875339 -205.574092) (xy 449.890211 -205.569297) (xy 449.896738 -205.564994)
			(xy 449.917827 -205.550645) (xy 449.963488 -205.527914) (xy 450.012094 -205.512455) (xy 450.062497 -205.504632)
			(xy 450.113503 -205.504632) (xy 450.163906 -205.512455) (xy 450.212512 -205.527914) (xy 450.258173 -205.550645)
			(xy 450.279262 -205.564994) (xy 450.285803 -205.569269) (xy 450.300666 -205.574062) (xy 450.308472 -205.574392)
			(xy 450.8246 -205.574392) (xy 450.829863 -205.574895) (xy 450.837305 -205.582337) (xy 450.837808 -205.5876)
			(xy 450.837808 -206.082138) (xy 450.837308 -206.087436) (xy 450.829887 -206.095002) (xy 450.8246 -206.0956)
			(xy 450.308726 -206.0956) (xy 450.300917 -206.095925) (xy 450.286045 -206.100703) (xy 450.279516 -206.104998)
			(xy 450.258383 -206.11933) (xy 450.212664 -206.142062) (xy 450.163994 -206.157497) (xy 450.11353 -206.165269)
			(xy 450.088 -206.165704) (xy 450.06247 -206.16526) (xy 450.012007 -206.157485) (xy 449.963335 -206.142058)
			(xy 449.917607 -206.119344) (xy 449.896484 -206.104998) (xy 449.889955 -206.100702) (xy 449.875083 -206.095922)
			(xy 449.867274 -206.0956) (xy 449.3514 -206.0956) (xy 449.346066 -206.095273) (xy 449.338524 -206.087726)
			(xy 449.338192 -206.082392) (xy 443.293984 -206.082392) (xy 443.293508 -206.087436) (xy 443.286087 -206.095002)
			(xy 443.2808 -206.0956) (xy 442.764926 -206.0956) (xy 442.757117 -206.095925) (xy 442.742245 -206.100703)
			(xy 442.735716 -206.104998) (xy 442.714583 -206.11933) (xy 442.668864 -206.142062) (xy 442.620194 -206.157497)
			(xy 442.56973 -206.165269) (xy 442.5442 -206.165704) (xy 442.51867 -206.16526) (xy 442.468207 -206.157485)
			(xy 442.419535 -206.142058) (xy 442.373807 -206.119344) (xy 442.352684 -206.104998) (xy 442.346155 -206.100702)
			(xy 442.331283 -206.095922) (xy 442.323474 -206.0956) (xy 441.8076 -206.0956) (xy 441.802266 -206.095273)
			(xy 441.794724 -206.087726) (xy 441.794392 -206.082392) (xy 435.750183 -206.082392) (xy 435.749679 -206.087495)
			(xy 435.742103 -206.095076) (xy 435.736746 -206.0956) (xy 435.220872 -206.0956) (xy 435.213061 -206.095902)
			(xy 435.19819 -206.100696) (xy 435.191662 -206.104998) (xy 435.170544 -206.119354) (xy 435.12482 -206.14208)
			(xy 435.076145 -206.157509) (xy 435.025677 -206.165273) (xy 435.000146 -206.165704) (xy 434.974617 -206.165237)
			(xy 434.924155 -206.157469) (xy 434.875482 -206.142049) (xy 434.829753 -206.119341) (xy 434.80863 -206.104998)
			(xy 434.802091 -206.100719) (xy 434.787227 -206.095929) (xy 434.77942 -206.0956) (xy 434.263546 -206.0956)
			(xy 434.258126 -206.095194) (xy 434.25044 -206.087555) (xy 434.250084 -206.082138) (xy 428.2059 -206.082138)
			(xy 428.205407 -206.087438) (xy 428.197981 -206.095004) (xy 428.192692 -206.0956) (xy 427.676818 -206.0956)
			(xy 427.669009 -206.095921) (xy 427.654137 -206.100702) (xy 427.647608 -206.104998) (xy 427.626477 -206.119334)
			(xy 427.580757 -206.142065) (xy 427.532087 -206.157499) (xy 427.481622 -206.165269) (xy 427.456092 -206.165704)
			(xy 427.430562 -206.165264) (xy 427.380099 -206.157488) (xy 427.331426 -206.14206) (xy 427.285698 -206.119345)
			(xy 427.264576 -206.104998) (xy 427.258049 -206.100699) (xy 427.243176 -206.095921) (xy 427.235366 -206.0956)
			(xy 426.719492 -206.0956) (xy 426.714226 -206.09511) (xy 426.706784 -206.087658) (xy 426.706284 -206.082392)
			(xy 420.662075 -206.082392) (xy 420.661579 -206.087497) (xy 420.653997 -206.095079) (xy 420.648638 -206.0956)
			(xy 420.132764 -206.0956) (xy 420.124956 -206.095941) (xy 420.110085 -206.100708) (xy 420.103554 -206.104998)
			(xy 420.082439 -206.119357) (xy 420.036713 -206.142083) (xy 419.988038 -206.157511) (xy 419.93757 -206.165273)
			(xy 419.912038 -206.165704) (xy 419.886509 -206.165241) (xy 419.836046 -206.157472) (xy 419.787374 -206.14205)
			(xy 419.741645 -206.119342) (xy 419.720522 -206.104998) (xy 419.713985 -206.100716) (xy 419.699119 -206.095927)
			(xy 419.691312 -206.0956) (xy 419.175438 -206.0956) (xy 419.170088 -206.095028) (xy 419.162502 -206.087485)
			(xy 419.161976 -206.082138) (xy 413.117792 -206.082138) (xy 413.117306 -206.087439) (xy 413.109875 -206.095006)
			(xy 413.104584 -206.0956) (xy 411.631384 -206.0956) (xy 411.626117 -206.095115) (xy 411.618675 -206.08766)
			(xy 411.618176 -206.082392) (xy 304.018164 -206.082392) (xy 304.017677 -206.0875) (xy 304.010089 -206.095082)
			(xy 304.004726 -206.0956) (xy 302.531526 -206.0956) (xy 302.526174 -206.095036) (xy 302.518589 -206.087487)
			(xy 302.518064 -206.082138) (xy 296.47388 -206.082138) (xy 296.473404 -206.087442) (xy 296.465967 -206.09501)
			(xy 296.460672 -206.0956) (xy 295.944798 -206.0956) (xy 295.936988 -206.095913) (xy 295.922116 -206.100699)
			(xy 295.915588 -206.104998) (xy 295.894463 -206.119342) (xy 295.848741 -206.142072) (xy 295.800069 -206.157503)
			(xy 295.749603 -206.165271) (xy 295.724072 -206.165704) (xy 295.698542 -206.165274) (xy 295.648078 -206.157495)
			(xy 295.599406 -206.142064) (xy 295.553678 -206.119346) (xy 295.532556 -206.104998) (xy 295.526034 -206.100691)
			(xy 295.511157 -206.095918) (xy 295.503346 -206.0956) (xy 294.987472 -206.0956) (xy 294.982204 -206.095123)
			(xy 294.974762 -206.087661) (xy 294.974264 -206.082392) (xy 288.930056 -206.082392) (xy 288.929576 -206.087502)
			(xy 288.921983 -206.095084) (xy 288.916618 -206.0956) (xy 288.400744 -206.0956) (xy 288.392936 -206.095932)
			(xy 288.378064 -206.100705) (xy 288.371534 -206.104998) (xy 288.350424 -206.119366) (xy 288.304697 -206.14209)
			(xy 288.25602 -206.157515) (xy 288.20555 -206.165275) (xy 288.180018 -206.165704) (xy 288.154488 -206.165251)
			(xy 288.104026 -206.157479) (xy 288.055353 -206.142055) (xy 288.009625 -206.119343) (xy 287.988502 -206.104998)
			(xy 287.981969 -206.100709) (xy 287.9671 -206.095924) (xy 287.959292 -206.0956) (xy 287.443418 -206.0956)
			(xy 287.438065 -206.095042) (xy 287.430481 -206.087489) (xy 287.429956 -206.082138) (xy 281.385772 -206.082138)
			(xy 281.385303 -206.087444) (xy 281.377861 -206.095012) (xy 281.372564 -206.0956) (xy 280.85669 -206.0956)
			(xy 280.84888 -206.095909) (xy 280.834008 -206.100698) (xy 280.82748 -206.104998) (xy 280.806357 -206.119346)
			(xy 280.760634 -206.142074) (xy 280.711961 -206.157505) (xy 280.661495 -206.165271) (xy 280.635964 -206.165704)
			(xy 280.610433 -206.165278) (xy 280.559969 -206.157498) (xy 280.511297 -206.142065) (xy 280.46557 -206.119346)
			(xy 280.444448 -206.104998) (xy 280.437927 -206.100688) (xy 280.423049 -206.095917) (xy 280.415238 -206.0956)
			(xy 279.899364 -206.0956) (xy 279.894095 -206.095128) (xy 279.886654 -206.087663) (xy 279.886156 -206.082392)
			(xy 273.84195 -206.082392) (xy 273.841503 -206.087444) (xy 273.834061 -206.095012) (xy 273.828764 -206.0956)
			(xy 273.31289 -206.0956) (xy 273.30508 -206.095909) (xy 273.290208 -206.100698) (xy 273.28368 -206.104998)
			(xy 273.262557 -206.119346) (xy 273.216834 -206.142074) (xy 273.168161 -206.157505) (xy 273.117695 -206.165271)
			(xy 273.092164 -206.165704) (xy 273.066633 -206.165278) (xy 273.016169 -206.157498) (xy 272.967497 -206.142065)
			(xy 272.92177 -206.119346) (xy 272.900648 -206.104998) (xy 272.894127 -206.100688) (xy 272.879249 -206.095917)
			(xy 272.871438 -206.0956) (xy 272.355564 -206.0956) (xy 272.350295 -206.095128) (xy 272.342854 -206.087663)
			(xy 272.342356 -206.082392) (xy 266.298149 -206.082392) (xy 266.297676 -206.087504) (xy 266.290077 -206.095087)
			(xy 266.28471 -206.0956) (xy 265.768836 -206.0956) (xy 265.761027 -206.095929) (xy 265.746156 -206.100704)
			(xy 265.739626 -206.104998) (xy 265.71849 -206.119326) (xy 265.672772 -206.142059) (xy 265.624103 -206.157495)
			(xy 265.57364 -206.165268) (xy 265.54811 -206.165704) (xy 265.52258 -206.165255) (xy 265.472117 -206.157482)
			(xy 265.423445 -206.142056) (xy 265.377717 -206.119343) (xy 265.356594 -206.104998) (xy 265.350063 -206.100705)
			(xy 265.335193 -206.095923) (xy 265.327384 -206.0956) (xy 264.81151 -206.0956) (xy 264.806156 -206.095047)
			(xy 264.798572 -206.08749) (xy 264.798048 -206.082138) (xy 202.89774 -206.082138) (xy 202.89774 -206.082392)
			(xy 202.897203 -206.087646) (xy 202.889785 -206.095087) (xy 202.884532 -206.0956) (xy 202.368658 -206.0956)
			(xy 202.360783 -206.095886) (xy 202.34578 -206.100672) (xy 202.339194 -206.104998) (xy 202.318105 -206.119371)
			(xy 202.272465 -206.142205) (xy 202.223862 -206.157768) (xy 202.173448 -206.165692) (xy 202.147932 -206.166212)
			(xy 202.122412 -206.165721) (xy 202.071985 -206.157827) (xy 202.023374 -206.142267) (xy 201.977735 -206.119413)
			(xy 201.95667 -206.104998) (xy 201.950087 -206.100668) (xy 201.93508 -206.095891) (xy 201.927206 -206.0956)
			(xy 201.411332 -206.0956) (xy 201.406002 -206.095251) (xy 201.398459 -206.087721) (xy 201.398124 -206.082392)
			(xy 195.35394 -206.082392) (xy 195.353403 -206.087646) (xy 195.345985 -206.095087) (xy 195.340732 -206.0956)
			(xy 194.824858 -206.0956) (xy 194.816983 -206.095886) (xy 194.80198 -206.100672) (xy 194.795394 -206.104998)
			(xy 194.774305 -206.119371) (xy 194.728665 -206.142205) (xy 194.680062 -206.157768) (xy 194.629648 -206.165692)
			(xy 194.604132 -206.166212) (xy 194.578612 -206.165721) (xy 194.528185 -206.157827) (xy 194.479574 -206.142267)
			(xy 194.433935 -206.119413) (xy 194.41287 -206.104998) (xy 194.406287 -206.100668) (xy 194.39128 -206.095891)
			(xy 194.383406 -206.0956) (xy 193.867532 -206.0956) (xy 193.862202 -206.095251) (xy 193.854659 -206.087721)
			(xy 193.854324 -206.082392) (xy 187.81014 -206.082392) (xy 187.809603 -206.087646) (xy 187.802185 -206.095087)
			(xy 187.796932 -206.0956) (xy 187.796424 -206.0956) (xy 187.280804 -206.0956) (xy 187.272931 -206.095905)
			(xy 187.257927 -206.100678) (xy 187.25134 -206.104998) (xy 187.230266 -206.119394) (xy 187.18462 -206.142223)
			(xy 187.136013 -206.15778) (xy 187.085595 -206.165697) (xy 187.060078 -206.166212) (xy 187.034559 -206.165698)
			(xy 186.984133 -206.157811) (xy 186.935521 -206.142258) (xy 186.889882 -206.11941) (xy 186.868816 -206.104998)
			(xy 186.862223 -206.100686) (xy 186.847224 -206.095897) (xy 186.839352 -206.0956) (xy 186.323478 -206.0956)
			(xy 186.318181 -206.095096) (xy 186.310613 -206.087679) (xy 186.310016 -206.082392) (xy 180.265832 -206.082392)
			(xy 180.265303 -206.087648) (xy 180.257879 -206.09509) (xy 180.252624 -206.0956) (xy 179.73675 -206.0956)
			(xy 179.728875 -206.095882) (xy 179.713872 -206.100671) (xy 179.707286 -206.104998) (xy 179.686199 -206.119375)
			(xy 179.640558 -206.142208) (xy 179.591955 -206.15777) (xy 179.54154 -206.165693) (xy 179.516024 -206.166212)
			(xy 179.490504 -206.165725) (xy 179.440077 -206.157829) (xy 179.391465 -206.142269) (xy 179.345827 -206.119413)
			(xy 179.324762 -206.104998) (xy 179.318181 -206.100665) (xy 179.303173 -206.095889) (xy 179.295298 -206.0956)
			(xy 178.779424 -206.0956) (xy 178.774093 -206.095256) (xy 178.76655 -206.087723) (xy 178.766216 -206.082392)
			(xy 172.722032 -206.082392) (xy 172.721503 -206.087648) (xy 172.714079 -206.09509) (xy 172.708824 -206.0956)
			(xy 172.708316 -206.0956) (xy 172.192696 -206.0956) (xy 172.184823 -206.095902) (xy 172.169819 -206.100677)
			(xy 172.163232 -206.104998) (xy 172.14216 -206.119398) (xy 172.096514 -206.142226) (xy 172.047906 -206.157782)
			(xy 171.997487 -206.165697) (xy 171.97197 -206.166212) (xy 171.946451 -206.165702) (xy 171.896025 -206.157813)
			(xy 171.847413 -206.142259) (xy 171.801774 -206.11941) (xy 171.780708 -206.104998) (xy 171.774117 -206.100683)
			(xy 171.759116 -206.095896) (xy 171.751244 -206.0956) (xy 171.23537 -206.0956) (xy 171.230071 -206.095102)
			(xy 171.222504 -206.08768) (xy 171.221908 -206.082392) (xy 165.177724 -206.082392) (xy 165.177202 -206.08765)
			(xy 165.169773 -206.095092) (xy 165.164516 -206.0956) (xy 163.691316 -206.0956) (xy 163.685984 -206.095262)
			(xy 163.678442 -206.087724) (xy 163.678108 -206.082392) (xy 56.07812 -206.082392) (xy 56.077601 -206.087651)
			(xy 56.07017 -206.095093) (xy 56.064912 -206.0956) (xy 54.591458 -206.0956) (xy 54.586158 -206.09511)
			(xy 54.578592 -206.087682) (xy 54.577996 -206.082392) (xy 48.533812 -206.082392) (xy 48.533468 -206.087722)
			(xy 48.525934 -206.095263) (xy 48.520604 -206.0956) (xy 48.00473 -206.0956) (xy 47.996854 -206.095874)
			(xy 47.981851 -206.100668) (xy 47.975266 -206.104998) (xy 47.954184 -206.119383) (xy 47.908542 -206.142215)
			(xy 47.859937 -206.157774) (xy 47.80952 -206.165695) (xy 47.784004 -206.166212) (xy 47.758483 -206.165735)
			(xy 47.708056 -206.157836) (xy 47.659444 -206.142273) (xy 47.613807 -206.119415) (xy 47.592742 -206.104998)
			(xy 47.586165 -206.100657) (xy 47.571154 -206.095887) (xy 47.563278 -206.0956) (xy 47.047404 -206.0956)
			(xy 47.04207 -206.09527) (xy 47.034529 -206.087726) (xy 47.034196 -206.082392) (xy 40.990012 -206.082392)
			(xy 40.989668 -206.087722) (xy 40.982134 -206.095263) (xy 40.976804 -206.0956) (xy 40.976296 -206.0956)
			(xy 40.460676 -206.0956) (xy 40.452802 -206.095893) (xy 40.437798 -206.100674) (xy 40.431212 -206.104998)
			(xy 40.410146 -206.119407) (xy 40.364497 -206.142232) (xy 40.315888 -206.157786) (xy 40.265468 -206.165699)
			(xy 40.23995 -206.166212) (xy 40.21443 -206.165712) (xy 40.164004 -206.15782) (xy 40.115392 -206.142263)
			(xy 40.069753 -206.119412) (xy 40.048688 -206.104998) (xy 40.042101 -206.100675) (xy 40.027097 -206.095893)
			(xy 40.019224 -206.0956) (xy 39.50335 -206.0956) (xy 39.498061 -206.095048) (xy 39.49049 -206.087667)
			(xy 39.489888 -206.082392) (xy 33.445704 -206.082392) (xy 33.445368 -206.087724) (xy 33.437828 -206.095266)
			(xy 33.432496 -206.0956) (xy 32.916622 -206.0956) (xy 32.90875 -206.095913) (xy 32.893746 -206.10068)
			(xy 32.887158 -206.104998) (xy 32.866079 -206.119387) (xy 32.820435 -206.142217) (xy 32.771829 -206.157776)
			(xy 32.721413 -206.165695) (xy 32.695896 -206.166212) (xy 32.670375 -206.165739) (xy 32.619948 -206.157839)
			(xy 32.571336 -206.142274) (xy 32.525698 -206.119415) (xy 32.504634 -206.104998) (xy 32.498037 -206.100693)
			(xy 32.483041 -206.0959) (xy 32.47517 -206.0956) (xy 31.959296 -206.0956) (xy 31.953961 -206.095275)
			(xy 31.94642 -206.087727) (xy 31.946088 -206.082392) (xy 25.901904 -206.082392) (xy 25.901568 -206.087724)
			(xy 25.894028 -206.095266) (xy 25.888696 -206.0956) (xy 25.372822 -206.0956) (xy 25.36495 -206.095913)
			(xy 25.349946 -206.10068) (xy 25.343358 -206.104998) (xy 25.322279 -206.119387) (xy 25.276635 -206.142217)
			(xy 25.228029 -206.157776) (xy 25.177613 -206.165695) (xy 25.152096 -206.166212) (xy 25.126575 -206.165739)
			(xy 25.076148 -206.157839) (xy 25.027536 -206.142274) (xy 24.981898 -206.119415) (xy 24.960834 -206.104998)
			(xy 24.954237 -206.100693) (xy 24.939241 -206.0959) (xy 24.93137 -206.0956) (xy 24.415496 -206.0956)
			(xy 24.410161 -206.095275) (xy 24.40262 -206.087727) (xy 24.402288 -206.082392) (xy 18.358104 -206.082392)
			(xy 18.357768 -206.087724) (xy 18.350228 -206.095266) (xy 18.344896 -206.0956) (xy 18.344388 -206.0956)
			(xy 17.828768 -206.0956) (xy 17.820894 -206.09589) (xy 17.80589 -206.100673) (xy 17.799304 -206.104998)
			(xy 17.778212 -206.119367) (xy 17.732573 -206.142202) (xy 17.683971 -206.157766) (xy 17.633557 -206.165692)
			(xy 17.608042 -206.166212) (xy 17.582522 -206.165716) (xy 17.532096 -206.157823) (xy 17.483484 -206.142265)
			(xy 17.437845 -206.119412) (xy 17.41678 -206.104998) (xy 17.410195 -206.100672) (xy 17.39519 -206.095892)
			(xy 17.387316 -206.0956) (xy 16.871442 -206.0956) (xy 16.866152 -206.095053) (xy 16.858581 -206.087668)
			(xy 16.85798 -206.082392) (xy 2.509012 -206.082392) (xy 2.509012 -206.93253) (xy 20.958048 -206.93253)
			(xy 20.958048 -206.437992) (xy 20.958585 -206.432739) (xy 20.966004 -206.425299) (xy 20.971256 -206.424784)
			(xy 20.971764 -206.424784) (xy 21.487638 -206.424784) (xy 21.495446 -206.424446) (xy 21.510318 -206.419677)
			(xy 21.516848 -206.415386) (xy 21.537937 -206.401037) (xy 21.583598 -206.378306) (xy 21.632204 -206.362847)
			(xy 21.682607 -206.355024) (xy 21.733613 -206.355024) (xy 21.784016 -206.362847) (xy 21.832622 -206.378306)
			(xy 21.878283 -206.401037) (xy 21.899372 -206.415386) (xy 21.905911 -206.419664) (xy 21.920775 -206.424456)
			(xy 21.928582 -206.424784) (xy 22.44471 -206.424784) (xy 22.450026 -206.425222) (xy 22.457599 -206.432684)
			(xy 22.458172 -206.437992) (xy 22.458172 -206.93253) (xy 22.458148 -206.932784) (xy 28.502356 -206.932784)
			(xy 28.502356 -206.932276) (xy 28.502356 -206.437992) (xy 28.502886 -206.432737) (xy 28.51031 -206.425297)
			(xy 28.515564 -206.424784) (xy 29.031692 -206.424784) (xy 29.039502 -206.42447) (xy 29.054374 -206.419684)
			(xy 29.060902 -206.415386) (xy 29.081991 -206.401037) (xy 29.127652 -206.378306) (xy 29.176258 -206.362847)
			(xy 29.226661 -206.355024) (xy 29.277667 -206.355024) (xy 29.32807 -206.362847) (xy 29.376676 -206.378306)
			(xy 29.422337 -206.401037) (xy 29.443426 -206.415386) (xy 29.449953 -206.419685) (xy 29.464827 -206.424463)
			(xy 29.472636 -206.424784) (xy 29.988764 -206.424784) (xy 29.99409 -206.42515) (xy 30.001632 -206.432668)
			(xy 30.001972 -206.437992) (xy 30.001972 -206.93253) (xy 30.001949 -206.932784) (xy 36.046156 -206.932784)
			(xy 36.046156 -206.932276) (xy 36.046156 -206.437992) (xy 36.046686 -206.432737) (xy 36.05411 -206.425297)
			(xy 36.059364 -206.424784) (xy 36.575492 -206.424784) (xy 36.583302 -206.42447) (xy 36.598174 -206.419684)
			(xy 36.604702 -206.415386) (xy 36.625791 -206.401037) (xy 36.671452 -206.378306) (xy 36.720058 -206.362847)
			(xy 36.770461 -206.355024) (xy 36.821467 -206.355024) (xy 36.87187 -206.362847) (xy 36.920476 -206.378306)
			(xy 36.966137 -206.401037) (xy 36.987226 -206.415386) (xy 36.993753 -206.419685) (xy 37.008627 -206.424463)
			(xy 37.016436 -206.424784) (xy 37.532564 -206.424784) (xy 37.53789 -206.42515) (xy 37.545432 -206.432668)
			(xy 37.545772 -206.437992) (xy 37.545772 -206.93253) (xy 43.589956 -206.93253) (xy 43.589956 -206.437992)
			(xy 43.590486 -206.432737) (xy 43.59791 -206.425297) (xy 43.603164 -206.424784) (xy 43.603672 -206.424784)
			(xy 44.119546 -206.424784) (xy 44.127354 -206.42445) (xy 44.142226 -206.419678) (xy 44.148756 -206.415386)
			(xy 44.169845 -206.401037) (xy 44.215506 -206.378306) (xy 44.264112 -206.362847) (xy 44.314515 -206.355024)
			(xy 44.365521 -206.355024) (xy 44.415924 -206.362847) (xy 44.46453 -206.378306) (xy 44.510191 -206.401037)
			(xy 44.53128 -206.415386) (xy 44.537817 -206.419667) (xy 44.552683 -206.424457) (xy 44.56049 -206.424784)
			(xy 45.076618 -206.424784) (xy 45.081935 -206.425216) (xy 45.089507 -206.432683) (xy 45.09008 -206.437992)
			(xy 45.09008 -206.93253) (xy 45.090056 -206.932784) (xy 51.134264 -206.932784) (xy 51.134264 -206.932276)
			(xy 51.134264 -206.437992) (xy 51.134787 -206.432735) (xy 51.142216 -206.425295) (xy 51.147472 -206.424784)
			(xy 51.6636 -206.424784) (xy 51.67141 -206.424473) (xy 51.686282 -206.419685) (xy 51.69281 -206.415386)
			(xy 51.713899 -206.401037) (xy 51.75956 -206.378306) (xy 51.808166 -206.362847) (xy 51.858569 -206.355024)
			(xy 51.909575 -206.355024) (xy 51.959978 -206.362847) (xy 52.008584 -206.378306) (xy 52.054245 -206.401037)
			(xy 52.075334 -206.415386) (xy 52.081859 -206.419688) (xy 52.096734 -206.424465) (xy 52.104544 -206.424784)
			(xy 52.620672 -206.424784) (xy 52.625999 -206.425145) (xy 52.633541 -206.432666) (xy 52.63388 -206.437992)
			(xy 52.63388 -206.93253) (xy 58.678064 -206.93253) (xy 58.678064 -206.437992) (xy 58.678587 -206.432735)
			(xy 58.686016 -206.425295) (xy 58.691272 -206.424784) (xy 58.69178 -206.424784) (xy 60.164726 -206.424784)
			(xy 60.170044 -206.425211) (xy 60.177616 -206.432682) (xy 60.178188 -206.437992) (xy 60.178188 -206.93253)
			(xy 60.177672 -206.937891) (xy 60.170087 -206.945474) (xy 60.164726 -206.945992) (xy 58.691526 -206.945992)
			(xy 58.686172 -206.945435) (xy 58.678587 -206.937881) (xy 58.678064 -206.93253) (xy 52.63388 -206.93253)
			(xy 52.633399 -206.937833) (xy 52.625965 -206.945402) (xy 52.620672 -206.945992) (xy 52.104798 -206.945992)
			(xy 52.096988 -206.946306) (xy 52.082117 -206.951092) (xy 52.075588 -206.95539) (xy 52.05447 -206.969745)
			(xy 52.008745 -206.992469) (xy 51.96007 -207.007898) (xy 51.909603 -207.015663) (xy 51.884072 -207.016096)
			(xy 51.858541 -207.015668) (xy 51.808078 -207.007888) (xy 51.759405 -206.992457) (xy 51.713678 -206.969738)
			(xy 51.692556 -206.95539) (xy 51.686034 -206.951082) (xy 51.671157 -206.94631) (xy 51.663346 -206.945992)
			(xy 51.147472 -206.945992) (xy 51.142202 -206.945522) (xy 51.13476 -206.938056) (xy 51.134264 -206.932784)
			(xy 45.090056 -206.932784) (xy 45.089571 -206.937893) (xy 45.081982 -206.945476) (xy 45.076618 -206.945992)
			(xy 44.560744 -206.945992) (xy 44.552936 -206.946326) (xy 44.538064 -206.951098) (xy 44.531534 -206.95539)
			(xy 44.510431 -206.969768) (xy 44.4647 -206.992487) (xy 44.416021 -207.007909) (xy 44.365551 -207.015667)
			(xy 44.340018 -207.016096) (xy 44.314488 -207.015645) (xy 44.264025 -207.007872) (xy 44.215353 -206.992447)
			(xy 44.169625 -206.969735) (xy 44.148502 -206.95539) (xy 44.14197 -206.9511) (xy 44.1271 -206.946316)
			(xy 44.119292 -206.945992) (xy 43.603418 -206.945992) (xy 43.598063 -206.945441) (xy 43.590478 -206.937883)
			(xy 43.589956 -206.93253) (xy 37.545772 -206.93253) (xy 37.545298 -206.937835) (xy 37.53786 -206.945404)
			(xy 37.532564 -206.945992) (xy 37.01669 -206.945992) (xy 37.00888 -206.946303) (xy 36.994008 -206.951091)
			(xy 36.98748 -206.95539) (xy 36.966364 -206.969749) (xy 36.920638 -206.992472) (xy 36.871963 -207.007899)
			(xy 36.821495 -207.015664) (xy 36.795964 -207.016096) (xy 36.770433 -207.015672) (xy 36.719969 -207.007891)
			(xy 36.671297 -206.992458) (xy 36.62557 -206.969739) (xy 36.604448 -206.95539) (xy 36.597928 -206.951079)
			(xy 36.583049 -206.946309) (xy 36.575238 -206.945992) (xy 36.059364 -206.945992) (xy 36.054093 -206.945527)
			(xy 36.046652 -206.938057) (xy 36.046156 -206.932784) (xy 30.001949 -206.932784) (xy 30.001498 -206.937835)
			(xy 29.99406 -206.945404) (xy 29.988764 -206.945992) (xy 29.47289 -206.945992) (xy 29.46508 -206.946303)
			(xy 29.450208 -206.951091) (xy 29.44368 -206.95539) (xy 29.422564 -206.969749) (xy 29.376838 -206.992472)
			(xy 29.328163 -207.007899) (xy 29.277695 -207.015664) (xy 29.252164 -207.016096) (xy 29.226633 -207.015672)
			(xy 29.176169 -207.007891) (xy 29.127497 -206.992458) (xy 29.08177 -206.969739) (xy 29.060648 -206.95539)
			(xy 29.054128 -206.951079) (xy 29.039249 -206.946309) (xy 29.031438 -206.945992) (xy 28.515564 -206.945992)
			(xy 28.510293 -206.945527) (xy 28.502852 -206.938057) (xy 28.502356 -206.932784) (xy 22.458148 -206.932784)
			(xy 22.457671 -206.937895) (xy 22.450076 -206.945479) (xy 22.44471 -206.945992) (xy 21.928836 -206.945992)
			(xy 21.921027 -206.946322) (xy 21.906156 -206.951097) (xy 21.899626 -206.95539) (xy 21.878498 -206.969729)
			(xy 21.832776 -206.992457) (xy 21.784105 -207.007889) (xy 21.73364 -207.01566) (xy 21.70811 -207.016096)
			(xy 21.68258 -207.015649) (xy 21.632117 -207.007875) (xy 21.583445 -206.992449) (xy 21.537717 -206.969736)
			(xy 21.516594 -206.95539) (xy 21.510064 -206.951097) (xy 21.495193 -206.946315) (xy 21.487384 -206.945992)
			(xy 20.97151 -206.945992) (xy 20.966155 -206.945446) (xy 20.95857 -206.937884) (xy 20.958048 -206.93253)
			(xy 2.509012 -206.93253) (xy 2.509012 -207.782414) (xy 16.85798 -207.782414) (xy 16.85798 -207.287876)
			(xy 16.858478 -207.282613) (xy 16.865925 -207.275173) (xy 16.871188 -207.274668) (xy 16.871696 -207.274668)
			(xy 17.38757 -207.274668) (xy 17.395379 -207.274347) (xy 17.410251 -207.269566) (xy 17.41678 -207.26527)
			(xy 17.437869 -207.250921) (xy 17.48353 -207.22819) (xy 17.532136 -207.212731) (xy 17.582539 -207.204908)
			(xy 17.633545 -207.204908) (xy 17.683948 -207.212731) (xy 17.732554 -207.22819) (xy 17.778215 -207.250921)
			(xy 17.799304 -207.26527) (xy 17.805837 -207.269558) (xy 17.820706 -207.274344) (xy 17.828514 -207.274668)
			(xy 18.344642 -207.274668) (xy 18.349958 -207.275098) (xy 18.357528 -207.282567) (xy 18.358104 -207.287876)
			(xy 18.358104 -207.782414) (xy 18.358078 -207.782668) (xy 24.402288 -207.782668) (xy 24.402288 -207.78216)
			(xy 24.402288 -207.287876) (xy 24.402779 -207.282611) (xy 24.410231 -207.275171) (xy 24.415496 -207.274668)
			(xy 24.931624 -207.274668) (xy 24.939436 -207.27437) (xy 24.954307 -207.269574) (xy 24.960834 -207.26527)
			(xy 24.981923 -207.250921) (xy 25.027584 -207.22819) (xy 25.07619 -207.212731) (xy 25.126593 -207.204908)
			(xy 25.177599 -207.204908) (xy 25.228002 -207.212731) (xy 25.276608 -207.22819) (xy 25.322269 -207.250921)
			(xy 25.343358 -207.26527) (xy 25.349879 -207.269579) (xy 25.364757 -207.274351) (xy 25.372568 -207.274668)
			(xy 25.888696 -207.274668) (xy 25.893952 -207.275195) (xy 25.901394 -207.282621) (xy 25.901904 -207.287876)
			(xy 25.901904 -207.782414) (xy 25.901879 -207.782668) (xy 31.946088 -207.782668) (xy 31.946088 -207.78216)
			(xy 31.946088 -207.287876) (xy 31.946579 -207.282611) (xy 31.954031 -207.275171) (xy 31.959296 -207.274668)
			(xy 32.475424 -207.274668) (xy 32.483236 -207.27437) (xy 32.498107 -207.269574) (xy 32.504634 -207.26527)
			(xy 32.525723 -207.250921) (xy 32.571384 -207.22819) (xy 32.61999 -207.212731) (xy 32.670393 -207.204908)
			(xy 32.721399 -207.204908) (xy 32.771802 -207.212731) (xy 32.820408 -207.22819) (xy 32.866069 -207.250921)
			(xy 32.887158 -207.26527) (xy 32.893679 -207.269579) (xy 32.908557 -207.274351) (xy 32.916368 -207.274668)
			(xy 33.432496 -207.274668) (xy 33.437752 -207.275195) (xy 33.445194 -207.282621) (xy 33.445704 -207.287876)
			(xy 33.445704 -207.782414) (xy 39.489888 -207.782414) (xy 39.489888 -207.287876) (xy 39.490379 -207.282611)
			(xy 39.497831 -207.275171) (xy 39.503096 -207.274668) (xy 39.503604 -207.274668) (xy 40.019478 -207.274668)
			(xy 40.027288 -207.274351) (xy 40.04216 -207.269568) (xy 40.048688 -207.26527) (xy 40.069777 -207.250921)
			(xy 40.115438 -207.22819) (xy 40.164044 -207.212731) (xy 40.214447 -207.204908) (xy 40.265453 -207.204908)
			(xy 40.315856 -207.212731) (xy 40.364462 -207.22819) (xy 40.410123 -207.250921) (xy 40.431212 -207.26527)
			(xy 40.437743 -207.269561) (xy 40.452613 -207.274345) (xy 40.460422 -207.274668) (xy 40.97655 -207.274668)
			(xy 40.981855 -207.27516) (xy 40.98943 -207.282582) (xy 40.990012 -207.287876) (xy 40.990012 -207.782414)
			(xy 40.989986 -207.782668) (xy 47.034196 -207.782668) (xy 47.034196 -207.78216) (xy 47.034196 -207.287876)
			(xy 47.034679 -207.282609) (xy 47.042136 -207.275168) (xy 47.047404 -207.274668) (xy 47.563532 -207.274668)
			(xy 47.57134 -207.274331) (xy 47.586212 -207.269561) (xy 47.592742 -207.26527) (xy 47.613831 -207.250921)
			(xy 47.659492 -207.22819) (xy 47.708098 -207.212731) (xy 47.758501 -207.204908) (xy 47.809507 -207.204908)
			(xy 47.85991 -207.212731) (xy 47.908516 -207.22819) (xy 47.954177 -207.250921) (xy 47.975266 -207.26527)
			(xy 47.981808 -207.269544) (xy 47.99667 -207.274338) (xy 48.004476 -207.274668) (xy 48.520604 -207.274668)
			(xy 48.525862 -207.275189) (xy 48.533303 -207.282619) (xy 48.533812 -207.287876) (xy 48.533812 -207.782414)
			(xy 54.577996 -207.782414) (xy 54.577996 -207.287876) (xy 54.578479 -207.282609) (xy 54.585936 -207.275168)
			(xy 54.591204 -207.274668) (xy 56.064658 -207.274668) (xy 56.069964 -207.275154) (xy 56.077539 -207.282581)
			(xy 56.07812 -207.287876) (xy 56.07812 -207.499458) (xy 97.408492 -207.499458) (xy 97.408492 -206.635858)
			(xy 97.408978 -206.608589) (xy 97.41674 -206.554605) (xy 97.432105 -206.502275) (xy 97.454762 -206.452665)
			(xy 97.484248 -206.406784) (xy 97.519963 -206.365567) (xy 97.56118 -206.329852) (xy 97.607061 -206.300366)
			(xy 97.656671 -206.277709) (xy 97.709001 -206.262344) (xy 97.762985 -206.254582) (xy 97.817523 -206.254582)
			(xy 97.871507 -206.262344) (xy 97.923837 -206.277709) (xy 97.973447 -206.300366) (xy 98.019328 -206.329852)
			(xy 98.060545 -206.365567) (xy 98.09626 -206.406784) (xy 98.125746 -206.452665) (xy 98.148403 -206.502275)
			(xy 98.163768 -206.554605) (xy 98.17153 -206.608589) (xy 98.172016 -206.635858) (xy 98.172016 -206.932784)
			(xy 167.778176 -206.932784) (xy 167.778176 -206.437992) (xy 167.778688 -206.432732) (xy 167.786124 -206.425291)
			(xy 167.791384 -206.424784) (xy 169.264584 -206.424784) (xy 169.269912 -206.425137) (xy 169.277454 -206.432664)
			(xy 169.277792 -206.437992) (xy 169.277792 -206.93253) (xy 175.321976 -206.93253) (xy 175.321976 -206.437992)
			(xy 175.322488 -206.432732) (xy 175.329924 -206.425291) (xy 175.335184 -206.424784) (xy 175.335692 -206.424784)
			(xy 175.851566 -206.424784) (xy 175.859375 -206.424459) (xy 175.874247 -206.419681) (xy 175.880776 -206.415386)
			(xy 175.901865 -206.401037) (xy 175.947526 -206.378306) (xy 175.996132 -206.362847) (xy 176.046535 -206.355024)
			(xy 176.097541 -206.355024) (xy 176.147944 -206.362847) (xy 176.19655 -206.378306) (xy 176.242211 -206.401037)
			(xy 176.2633 -206.415386) (xy 176.269833 -206.419675) (xy 176.284702 -206.42446) (xy 176.29251 -206.424784)
			(xy 176.808638 -206.424784) (xy 176.813957 -206.425203) (xy 176.821528 -206.43268) (xy 176.8221 -206.437992)
			(xy 176.8221 -206.93253) (xy 176.822075 -206.932784) (xy 182.866284 -206.932784) (xy 182.866284 -206.932276)
			(xy 182.866284 -206.437992) (xy 182.866789 -206.43273) (xy 182.87423 -206.425289) (xy 182.879492 -206.424784)
			(xy 183.39562 -206.424784) (xy 183.403431 -206.424482) (xy 183.418303 -206.419688) (xy 183.42483 -206.415386)
			(xy 183.445919 -206.401037) (xy 183.49158 -206.378306) (xy 183.540186 -206.362847) (xy 183.590589 -206.355024)
			(xy 183.641595 -206.355024) (xy 183.691998 -206.362847) (xy 183.740604 -206.378306) (xy 183.786265 -206.401037)
			(xy 183.807354 -206.415386) (xy 183.813875 -206.419695) (xy 183.828753 -206.424468) (xy 183.836564 -206.424784)
			(xy 184.352692 -206.424784) (xy 184.357952 -206.425299) (xy 184.365395 -206.432733) (xy 184.3659 -206.437992)
			(xy 184.3659 -206.93253) (xy 190.410084 -206.93253) (xy 190.410084 -206.437992) (xy 190.410589 -206.43273)
			(xy 190.41803 -206.425289) (xy 190.423292 -206.424784) (xy 190.4238 -206.424784) (xy 190.939674 -206.424784)
			(xy 190.947483 -206.424462) (xy 190.962355 -206.419682) (xy 190.968884 -206.415386) (xy 190.989973 -206.401037)
			(xy 191.035634 -206.378306) (xy 191.08424 -206.362847) (xy 191.134643 -206.355024) (xy 191.185649 -206.355024)
			(xy 191.236052 -206.362847) (xy 191.284658 -206.378306) (xy 191.330319 -206.401037) (xy 191.351408 -206.415386)
			(xy 191.357939 -206.419678) (xy 191.372809 -206.424461) (xy 191.380618 -206.424784) (xy 191.896746 -206.424784)
			(xy 191.902054 -206.425264) (xy 191.909631 -206.432694) (xy 191.910208 -206.437992) (xy 191.910208 -206.93253)
			(xy 191.910183 -206.932784) (xy 197.954392 -206.932784) (xy 197.954392 -206.932276) (xy 197.954392 -206.437992)
			(xy 197.954889 -206.432728) (xy 197.962336 -206.425286) (xy 197.9676 -206.424784) (xy 198.483728 -206.424784)
			(xy 198.491539 -206.424485) (xy 198.506411 -206.419689) (xy 198.512938 -206.415386) (xy 198.534027 -206.401037)
			(xy 198.579688 -206.378306) (xy 198.628294 -206.362847) (xy 198.678697 -206.355024) (xy 198.729703 -206.355024)
			(xy 198.780106 -206.362847) (xy 198.828712 -206.378306) (xy 198.874373 -206.401037) (xy 198.895462 -206.415386)
			(xy 198.902003 -206.41966) (xy 198.916866 -206.424454) (xy 198.924672 -206.424784) (xy 199.4408 -206.424784)
			(xy 199.446061 -206.425294) (xy 199.453503 -206.432732) (xy 199.454008 -206.437992) (xy 199.454008 -206.93253)
			(xy 199.453984 -206.932784) (xy 205.498192 -206.932784) (xy 205.498192 -206.932276) (xy 205.498192 -206.437992)
			(xy 205.498689 -206.432728) (xy 205.506136 -206.425286) (xy 205.5114 -206.424784) (xy 206.027528 -206.424784)
			(xy 206.035339 -206.424485) (xy 206.050211 -206.419689) (xy 206.056738 -206.415386) (xy 206.077827 -206.401037)
			(xy 206.123488 -206.378306) (xy 206.172094 -206.362847) (xy 206.222497 -206.355024) (xy 206.273503 -206.355024)
			(xy 206.323906 -206.362847) (xy 206.372512 -206.378306) (xy 206.418173 -206.401037) (xy 206.439262 -206.415386)
			(xy 206.445803 -206.41966) (xy 206.460666 -206.424454) (xy 206.468472 -206.424784) (xy 206.9846 -206.424784)
			(xy 206.989861 -206.425294) (xy 206.997303 -206.432732) (xy 206.997808 -206.437992) (xy 206.997808 -206.932276)
			(xy 268.898116 -206.932276) (xy 268.898116 -206.437738) (xy 268.898502 -206.432313) (xy 268.906155 -206.424627)
			(xy 268.911578 -206.424276) (xy 269.427706 -206.424276) (xy 269.435517 -206.423969) (xy 269.450388 -206.419179)
			(xy 269.456916 -206.414878) (xy 269.478005 -206.400529) (xy 269.523666 -206.377798) (xy 269.572272 -206.362339)
			(xy 269.622675 -206.354516) (xy 269.673681 -206.354516) (xy 269.724084 -206.362339) (xy 269.77269 -206.377798)
			(xy 269.818351 -206.400529) (xy 269.83944 -206.414878) (xy 269.845965 -206.419181) (xy 269.86084 -206.423957)
			(xy 269.86865 -206.424276) (xy 270.384778 -206.424276) (xy 270.390219 -206.424598) (xy 270.397909 -206.432297)
			(xy 270.39824 -206.437738) (xy 270.39824 -206.932276) (xy 276.442424 -206.932276) (xy 276.442424 -206.437738)
			(xy 276.442947 -206.432442) (xy 276.450348 -206.42487) (xy 276.455632 -206.424276) (xy 276.97176 -206.424276)
			(xy 276.979569 -206.423949) (xy 276.99444 -206.419172) (xy 277.00097 -206.414878) (xy 277.022059 -206.400529)
			(xy 277.06772 -206.377798) (xy 277.116326 -206.362339) (xy 277.166729 -206.354516) (xy 277.217735 -206.354516)
			(xy 277.268138 -206.362339) (xy 277.316744 -206.377798) (xy 277.362405 -206.400529) (xy 277.383494 -206.414878)
			(xy 277.390029 -206.419163) (xy 277.404896 -206.42395) (xy 277.412704 -206.424276) (xy 277.928832 -206.424276)
			(xy 277.934095 -206.424772) (xy 277.941535 -206.432221) (xy 277.94204 -206.437484) (xy 277.94204 -206.437992)
			(xy 277.94204 -206.932276) (xy 283.986224 -206.932276) (xy 283.986224 -206.437738) (xy 283.986747 -206.432442)
			(xy 283.994148 -206.42487) (xy 283.999432 -206.424276) (xy 284.51556 -206.424276) (xy 284.523369 -206.423949)
			(xy 284.53824 -206.419172) (xy 284.54477 -206.414878) (xy 284.565859 -206.400529) (xy 284.61152 -206.377798)
			(xy 284.660126 -206.362339) (xy 284.710529 -206.354516) (xy 284.761535 -206.354516) (xy 284.811938 -206.362339)
			(xy 284.860544 -206.377798) (xy 284.906205 -206.400529) (xy 284.927294 -206.414878) (xy 284.933829 -206.419163)
			(xy 284.948696 -206.42395) (xy 284.956504 -206.424276) (xy 285.472632 -206.424276) (xy 285.477895 -206.424772)
			(xy 285.485335 -206.432221) (xy 285.48584 -206.437484) (xy 285.48584 -206.437992) (xy 285.48584 -206.932276)
			(xy 291.530024 -206.932276) (xy 291.530024 -206.437738) (xy 291.530403 -206.432312) (xy 291.538061 -206.424624)
			(xy 291.543486 -206.424276) (xy 292.059614 -206.424276) (xy 292.067425 -206.423972) (xy 292.082297 -206.41918)
			(xy 292.088824 -206.414878) (xy 292.109913 -206.400529) (xy 292.155574 -206.377798) (xy 292.20418 -206.362339)
			(xy 292.254583 -206.354516) (xy 292.305589 -206.354516) (xy 292.355992 -206.362339) (xy 292.404598 -206.377798)
			(xy 292.450259 -206.400529) (xy 292.471348 -206.414878) (xy 292.477871 -206.419184) (xy 292.492748 -206.423958)
			(xy 292.500558 -206.424276) (xy 293.016686 -206.424276) (xy 293.022128 -206.424592) (xy 293.029817 -206.432295)
			(xy 293.030148 -206.437738) (xy 293.030148 -206.932276) (xy 299.074332 -206.932276) (xy 299.074332 -206.437738)
			(xy 299.074848 -206.43244) (xy 299.082254 -206.424868) (xy 299.08754 -206.424276) (xy 299.603668 -206.424276)
			(xy 299.611477 -206.423953) (xy 299.626349 -206.419174) (xy 299.632878 -206.414878) (xy 299.653967 -206.400529)
			(xy 299.699628 -206.377798) (xy 299.748234 -206.362339) (xy 299.798637 -206.354516) (xy 299.849643 -206.354516)
			(xy 299.900046 -206.362339) (xy 299.948652 -206.377798) (xy 299.994313 -206.400529) (xy 300.015402 -206.414878)
			(xy 300.021935 -206.419166) (xy 300.036804 -206.423951) (xy 300.044612 -206.424276) (xy 300.56074 -206.424276)
			(xy 300.566004 -206.424766) (xy 300.573443 -206.432219) (xy 300.573948 -206.437484) (xy 300.573948 -206.437992)
			(xy 300.573948 -206.932276) (xy 306.618132 -206.932276) (xy 306.618132 -206.437738) (xy 306.618504 -206.43231)
			(xy 306.626167 -206.424622) (xy 306.631594 -206.424276) (xy 308.104794 -206.424276) (xy 308.110237 -206.424587)
			(xy 308.117926 -206.432294) (xy 308.118256 -206.437738) (xy 308.118256 -206.932276) (xy 415.718244 -206.932276)
			(xy 415.718244 -206.437738) (xy 415.718749 -206.432437) (xy 415.726163 -206.424864) (xy 415.731452 -206.424276)
			(xy 417.204652 -206.424276) (xy 417.209974 -206.424658) (xy 417.217517 -206.432164) (xy 417.21786 -206.437484)
			(xy 417.21786 -206.932276) (xy 423.262044 -206.932276) (xy 423.262044 -206.437738) (xy 423.262405 -206.432307)
			(xy 423.270076 -206.424618) (xy 423.275506 -206.424276) (xy 423.791634 -206.424276) (xy 423.799442 -206.423938)
			(xy 423.814314 -206.419169) (xy 423.820844 -206.414878) (xy 423.841933 -206.400529) (xy 423.887594 -206.377798)
			(xy 423.9362 -206.362339) (xy 423.986603 -206.354516) (xy 424.037609 -206.354516) (xy 424.088012 -206.362339)
			(xy 424.136618 -206.377798) (xy 424.182279 -206.400529) (xy 424.203368 -206.414878) (xy 424.209909 -206.419153)
			(xy 424.224772 -206.423946) (xy 424.232578 -206.424276) (xy 424.748706 -206.424276) (xy 424.754151 -206.424579)
			(xy 424.761839 -206.432292) (xy 424.762168 -206.437738) (xy 424.762168 -206.932276) (xy 430.806352 -206.932276)
			(xy 430.806352 -206.437738) (xy 430.80685 -206.432436) (xy 430.814269 -206.424862) (xy 430.81956 -206.424276)
			(xy 431.335688 -206.424276) (xy 431.343498 -206.423961) (xy 431.35837 -206.419177) (xy 431.364898 -206.414878)
			(xy 431.385987 -206.400529) (xy 431.431648 -206.377798) (xy 431.480254 -206.362339) (xy 431.530657 -206.354516)
			(xy 431.581663 -206.354516) (xy 431.632066 -206.362339) (xy 431.680672 -206.377798) (xy 431.726333 -206.400529)
			(xy 431.747422 -206.414878) (xy 431.753951 -206.419174) (xy 431.768823 -206.423954) (xy 431.776632 -206.424276)
			(xy 432.29276 -206.424276) (xy 432.298083 -206.424652) (xy 432.305625 -206.432163) (xy 432.305968 -206.437484)
			(xy 432.305968 -206.437992) (xy 432.305968 -206.932276) (xy 438.350152 -206.932276) (xy 438.350152 -206.437738)
			(xy 438.350506 -206.432305) (xy 438.358181 -206.424616) (xy 438.363614 -206.424276) (xy 438.879742 -206.424276)
			(xy 438.88755 -206.423941) (xy 438.902422 -206.41917) (xy 438.908952 -206.414878) (xy 438.930041 -206.400529)
			(xy 438.975702 -206.377798) (xy 439.024308 -206.362339) (xy 439.074711 -206.354516) (xy 439.125717 -206.354516)
			(xy 439.17612 -206.362339) (xy 439.224726 -206.377798) (xy 439.270387 -206.400529) (xy 439.291476 -206.414878)
			(xy 439.298015 -206.419156) (xy 439.312879 -206.423948) (xy 439.320686 -206.424276) (xy 439.836814 -206.424276)
			(xy 439.84226 -206.424574) (xy 439.849947 -206.432291) (xy 439.850276 -206.437738) (xy 439.850276 -206.932276)
			(xy 445.89446 -206.932276) (xy 445.89446 -206.437738) (xy 445.894951 -206.432434) (xy 445.902374 -206.424859)
			(xy 445.907668 -206.424276) (xy 446.423796 -206.424276) (xy 446.431606 -206.423965) (xy 446.446478 -206.419178)
			(xy 446.453006 -206.414878) (xy 446.474095 -206.400529) (xy 446.519756 -206.377798) (xy 446.568362 -206.362339)
			(xy 446.618765 -206.354516) (xy 446.669771 -206.354516) (xy 446.720174 -206.362339) (xy 446.76878 -206.377798)
			(xy 446.814441 -206.400529) (xy 446.83553 -206.414878) (xy 446.842057 -206.419177) (xy 446.85693 -206.423955)
			(xy 446.86474 -206.424276) (xy 447.380868 -206.424276) (xy 447.386192 -206.424647) (xy 447.393734 -206.432161)
			(xy 447.394076 -206.437484) (xy 447.394076 -206.437992) (xy 447.394076 -206.932276) (xy 453.43826 -206.932276)
			(xy 453.43826 -206.437738) (xy 453.438751 -206.432434) (xy 453.446174 -206.424859) (xy 453.451468 -206.424276)
			(xy 453.967596 -206.424276) (xy 453.975406 -206.423965) (xy 453.990278 -206.419178) (xy 453.996806 -206.414878)
			(xy 454.017895 -206.400529) (xy 454.063556 -206.377798) (xy 454.112162 -206.362339) (xy 454.162565 -206.354516)
			(xy 454.213571 -206.354516) (xy 454.263974 -206.362339) (xy 454.31258 -206.377798) (xy 454.358241 -206.400529)
			(xy 454.37933 -206.414878) (xy 454.385857 -206.419177) (xy 454.40073 -206.423955) (xy 454.40854 -206.424276)
			(xy 454.924668 -206.424276) (xy 454.929992 -206.424647) (xy 454.937534 -206.432161) (xy 454.937876 -206.437484)
			(xy 454.937876 -206.437992) (xy 454.937876 -206.932276) (xy 454.937554 -206.937613) (xy 454.930005 -206.945157)
			(xy 454.924668 -206.945484) (xy 454.408794 -206.945484) (xy 454.400919 -206.945771) (xy 454.385915 -206.950554)
			(xy 454.37933 -206.954882) (xy 454.358265 -206.969293) (xy 454.312615 -206.992116) (xy 454.264006 -207.007668)
			(xy 454.213586 -207.015582) (xy 454.188068 -207.016096) (xy 454.162548 -207.01559) (xy 454.112122 -207.007701)
			(xy 454.06351 -206.992145) (xy 454.017871 -206.969295) (xy 453.996806 -206.954882) (xy 453.990216 -206.950565)
			(xy 453.975215 -206.94578) (xy 453.967342 -206.945484) (xy 453.451468 -206.945484) (xy 453.446196 -206.945024)
			(xy 453.438753 -206.93755) (xy 453.43826 -206.932276) (xy 447.394076 -206.932276) (xy 447.393754 -206.937613)
			(xy 447.386205 -206.945157) (xy 447.380868 -206.945484) (xy 446.864994 -206.945484) (xy 446.857119 -206.945771)
			(xy 446.842115 -206.950554) (xy 446.83553 -206.954882) (xy 446.814465 -206.969293) (xy 446.768815 -206.992116)
			(xy 446.720206 -207.007668) (xy 446.669786 -207.015582) (xy 446.644268 -207.016096) (xy 446.618748 -207.01559)
			(xy 446.568322 -207.007701) (xy 446.51971 -206.992145) (xy 446.474071 -206.969295) (xy 446.453006 -206.954882)
			(xy 446.446416 -206.950565) (xy 446.431415 -206.94578) (xy 446.423542 -206.945484) (xy 445.907668 -206.945484)
			(xy 445.902396 -206.945024) (xy 445.894953 -206.93755) (xy 445.89446 -206.932276) (xy 439.850276 -206.932276)
			(xy 439.849954 -206.937613) (xy 439.842405 -206.945157) (xy 439.837068 -206.945484) (xy 439.83656 -206.945484)
			(xy 439.32094 -206.945484) (xy 439.313063 -206.945748) (xy 439.298059 -206.950547) (xy 439.291476 -206.954882)
			(xy 439.270398 -206.969273) (xy 439.224753 -206.992101) (xy 439.176147 -207.007658) (xy 439.125731 -207.015578)
			(xy 439.100214 -207.016096) (xy 439.074693 -207.015617) (xy 439.024266 -207.007719) (xy 438.975654 -206.992156)
			(xy 438.930016 -206.969299) (xy 438.908952 -206.954882) (xy 438.902374 -206.950544) (xy 438.887363 -206.945772)
			(xy 438.879488 -206.945484) (xy 438.363614 -206.945484) (xy 438.358317 -206.94497) (xy 438.350747 -206.937561)
			(xy 438.350152 -206.932276) (xy 432.305968 -206.932276) (xy 432.305653 -206.937615) (xy 432.298099 -206.945159)
			(xy 432.29276 -206.945484) (xy 431.776886 -206.945484) (xy 431.769011 -206.945768) (xy 431.754007 -206.950553)
			(xy 431.747422 -206.954882) (xy 431.726359 -206.969296) (xy 431.680709 -206.992118) (xy 431.632098 -207.00767)
			(xy 431.581678 -207.015582) (xy 431.55616 -207.016096) (xy 431.53064 -207.015594) (xy 431.480214 -207.007703)
			(xy 431.431602 -206.992147) (xy 431.385963 -206.969296) (xy 431.364898 -206.954882) (xy 431.35831 -206.950562)
			(xy 431.343307 -206.945779) (xy 431.335434 -206.945484) (xy 430.81956 -206.945484) (xy 430.814287 -206.94503)
			(xy 430.806845 -206.937552) (xy 430.806352 -206.932276) (xy 424.762168 -206.932276) (xy 424.761853 -206.937615)
			(xy 424.754299 -206.945159) (xy 424.74896 -206.945484) (xy 424.748452 -206.945484) (xy 424.232832 -206.945484)
			(xy 424.224955 -206.945744) (xy 424.209951 -206.950546) (xy 424.203368 -206.954882) (xy 424.182293 -206.969276)
			(xy 424.136647 -206.992103) (xy 424.08804 -207.00766) (xy 424.037623 -207.015579) (xy 424.012106 -207.016096)
			(xy 423.986585 -207.015621) (xy 423.936158 -207.007722) (xy 423.887546 -206.992158) (xy 423.841908 -206.969299)
			(xy 423.820844 -206.954882) (xy 423.814268 -206.950541) (xy 423.799256 -206.945771) (xy 423.79138 -206.945484)
			(xy 423.275506 -206.945484) (xy 423.270208 -206.944976) (xy 423.262638 -206.937563) (xy 423.262044 -206.932276)
			(xy 417.21786 -206.932276) (xy 417.217552 -206.937617) (xy 417.209993 -206.945162) (xy 417.204652 -206.945484)
			(xy 415.731452 -206.945484) (xy 415.726178 -206.945035) (xy 415.718737 -206.937553) (xy 415.718244 -206.932276)
			(xy 308.118256 -206.932276) (xy 308.117694 -206.937524) (xy 308.110293 -206.944965) (xy 308.105048 -206.945484)
			(xy 308.10454 -206.945484) (xy 306.631594 -206.945484) (xy 306.626295 -206.944984) (xy 306.618725 -206.937565)
			(xy 306.618132 -206.932276) (xy 300.573948 -206.932276) (xy 300.573393 -206.937526) (xy 300.565988 -206.944968)
			(xy 300.56074 -206.945484) (xy 300.044866 -206.945484) (xy 300.03699 -206.945759) (xy 300.021986 -206.950551)
			(xy 300.015402 -206.954882) (xy 299.994317 -206.969262) (xy 299.948675 -206.992092) (xy 299.900071 -207.007653)
			(xy 299.849656 -207.015576) (xy 299.82414 -207.016096) (xy 299.79862 -207.015604) (xy 299.748193 -207.00771)
			(xy 299.699581 -206.992151) (xy 299.653943 -206.969297) (xy 299.632878 -206.954882) (xy 299.626294 -206.950554)
			(xy 299.611288 -206.945776) (xy 299.603414 -206.945484) (xy 299.08754 -206.945484) (xy 299.082207 -206.945144)
			(xy 299.074663 -206.937608) (xy 299.074332 -206.932276) (xy 293.030148 -206.932276) (xy 293.029593 -206.937526)
			(xy 293.022188 -206.944968) (xy 293.01694 -206.945484) (xy 293.016432 -206.945484) (xy 292.500812 -206.945484)
			(xy 292.492938 -206.945779) (xy 292.477934 -206.950557) (xy 292.471348 -206.954882) (xy 292.450278 -206.969285)
			(xy 292.40463 -206.99211) (xy 292.356022 -207.007664) (xy 292.305603 -207.01558) (xy 292.280086 -207.016096)
			(xy 292.254567 -207.015581) (xy 292.204141 -207.007694) (xy 292.155529 -206.992142) (xy 292.10989 -206.969294)
			(xy 292.088824 -206.954882) (xy 292.08223 -206.950572) (xy 292.067232 -206.945782) (xy 292.05936 -206.945484)
			(xy 291.543486 -206.945484) (xy 291.538186 -206.944989) (xy 291.530617 -206.937566) (xy 291.530024 -206.932276)
			(xy 285.48584 -206.932276) (xy 285.485292 -206.937528) (xy 285.477882 -206.94497) (xy 285.472632 -206.945484)
			(xy 284.956758 -206.945484) (xy 284.948882 -206.945756) (xy 284.933878 -206.95055) (xy 284.927294 -206.954882)
			(xy 284.906211 -206.969265) (xy 284.860568 -206.992095) (xy 284.811964 -207.007654) (xy 284.761548 -207.015577)
			(xy 284.736032 -207.016096) (xy 284.710512 -207.015608) (xy 284.660085 -207.007713) (xy 284.611473 -206.992153)
			(xy 284.565835 -206.969297) (xy 284.54477 -206.954882) (xy 284.538188 -206.950551) (xy 284.523181 -206.945774)
			(xy 284.515306 -206.945484) (xy 283.999432 -206.945484) (xy 283.994098 -206.945149) (xy 283.986554 -206.93761)
			(xy 283.986224 -206.932276) (xy 277.94204 -206.932276) (xy 277.941492 -206.937528) (xy 277.934082 -206.94497)
			(xy 277.928832 -206.945484) (xy 277.412958 -206.945484) (xy 277.405082 -206.945756) (xy 277.390078 -206.95055)
			(xy 277.383494 -206.954882) (xy 277.362411 -206.969265) (xy 277.316768 -206.992095) (xy 277.268164 -207.007654)
			(xy 277.217748 -207.015577) (xy 277.192232 -207.016096) (xy 277.166712 -207.015608) (xy 277.116285 -207.007713)
			(xy 277.067673 -206.992153) (xy 277.022035 -206.969297) (xy 277.00097 -206.954882) (xy 276.994388 -206.950551)
			(xy 276.979381 -206.945774) (xy 276.971506 -206.945484) (xy 276.455632 -206.945484) (xy 276.450298 -206.945149)
			(xy 276.442754 -206.93761) (xy 276.442424 -206.932276) (xy 270.39824 -206.932276) (xy 270.397692 -206.937528)
			(xy 270.390282 -206.94497) (xy 270.385032 -206.945484) (xy 270.384524 -206.945484) (xy 269.868904 -206.945484)
			(xy 269.86103 -206.945775) (xy 269.846025 -206.950556) (xy 269.83944 -206.954882) (xy 269.818372 -206.969288)
			(xy 269.772724 -206.992112) (xy 269.724115 -207.007666) (xy 269.673695 -207.015581) (xy 269.648178 -207.016096)
			(xy 269.622659 -207.015585) (xy 269.572233 -207.007697) (xy 269.523621 -206.992143) (xy 269.477982 -206.969294)
			(xy 269.456916 -206.954882) (xy 269.450324 -206.950569) (xy 269.435324 -206.945781) (xy 269.427452 -206.945484)
			(xy 268.911578 -206.945484) (xy 268.906277 -206.944994) (xy 268.898708 -206.937567) (xy 268.898116 -206.932276)
			(xy 206.997808 -206.932276) (xy 206.997808 -206.93253) (xy 206.997303 -206.937827) (xy 206.989886 -206.945393)
			(xy 206.9846 -206.945992) (xy 206.468726 -206.945992) (xy 206.460917 -206.946318) (xy 206.446046 -206.951096)
			(xy 206.439516 -206.95539) (xy 206.41839 -206.969733) (xy 206.372668 -206.99246) (xy 206.323996 -207.007892)
			(xy 206.273531 -207.015661) (xy 206.248 -207.016096) (xy 206.22247 -207.015654) (xy 206.172007 -207.007879)
			(xy 206.123334 -206.992451) (xy 206.077606 -206.969736) (xy 206.056484 -206.95539) (xy 206.049956 -206.951093)
			(xy 206.035083 -206.946314) (xy 206.027274 -206.945992) (xy 205.5114 -206.945992) (xy 205.506064 -206.945672)
			(xy 205.498522 -206.938121) (xy 205.498192 -206.932784) (xy 199.453984 -206.932784) (xy 199.453503 -206.937827)
			(xy 199.446086 -206.945393) (xy 199.4408 -206.945992) (xy 198.924926 -206.945992) (xy 198.917117 -206.946318)
			(xy 198.902246 -206.951096) (xy 198.895716 -206.95539) (xy 198.87459 -206.969733) (xy 198.828868 -206.99246)
			(xy 198.780196 -207.007892) (xy 198.729731 -207.015661) (xy 198.7042 -207.016096) (xy 198.67867 -207.015654)
			(xy 198.628207 -207.007879) (xy 198.579534 -206.992451) (xy 198.533806 -206.969736) (xy 198.512684 -206.95539)
			(xy 198.506156 -206.951093) (xy 198.491283 -206.946314) (xy 198.483474 -206.945992) (xy 197.9676 -206.945992)
			(xy 197.962264 -206.945672) (xy 197.954722 -206.938121) (xy 197.954392 -206.932784) (xy 191.910183 -206.932784)
			(xy 191.909674 -206.937887) (xy 191.902102 -206.945468) (xy 191.896746 -206.945992) (xy 191.380872 -206.945992)
			(xy 191.373061 -206.946295) (xy 191.35819 -206.951089) (xy 191.351662 -206.95539) (xy 191.330552 -206.969756)
			(xy 191.284823 -206.992478) (xy 191.236147 -207.007903) (xy 191.185678 -207.015665) (xy 191.160146 -207.016096)
			(xy 191.134617 -207.015631) (xy 191.084154 -207.007863) (xy 191.035482 -206.992442) (xy 190.989753 -206.969733)
			(xy 190.96863 -206.95539) (xy 190.962092 -206.951111) (xy 190.947227 -206.94632) (xy 190.93942 -206.945992)
			(xy 190.423546 -206.945992) (xy 190.418124 -206.945593) (xy 190.410438 -206.937949) (xy 190.410084 -206.93253)
			(xy 184.3659 -206.93253) (xy 184.365402 -206.937829) (xy 184.35798 -206.945396) (xy 184.352692 -206.945992)
			(xy 183.836818 -206.945992) (xy 183.829009 -206.946315) (xy 183.814137 -206.951095) (xy 183.807608 -206.95539)
			(xy 183.786485 -206.969736) (xy 183.740761 -206.992463) (xy 183.692088 -207.007893) (xy 183.641623 -207.015662)
			(xy 183.616092 -207.016096) (xy 183.590562 -207.015658) (xy 183.540098 -207.007881) (xy 183.491426 -206.992453)
			(xy 183.445698 -206.969737) (xy 183.424576 -206.95539) (xy 183.41805 -206.95109) (xy 183.403176 -206.946313)
			(xy 183.395366 -206.945992) (xy 182.879492 -206.945992) (xy 182.874155 -206.945677) (xy 182.866613 -206.938122)
			(xy 182.866284 -206.932784) (xy 176.822075 -206.932784) (xy 176.821574 -206.937888) (xy 176.813996 -206.94547)
			(xy 176.808638 -206.945992) (xy 176.292764 -206.945992) (xy 176.284957 -206.946334) (xy 176.270085 -206.951101)
			(xy 176.263554 -206.95539) (xy 176.242446 -206.96976) (xy 176.196717 -206.992481) (xy 176.148039 -207.007905)
			(xy 176.09757 -207.015666) (xy 176.072038 -207.016096) (xy 176.046509 -207.015635) (xy 175.996046 -207.007865)
			(xy 175.947374 -206.992443) (xy 175.901645 -206.969734) (xy 175.880522 -206.95539) (xy 175.873985 -206.951107)
			(xy 175.859119 -206.946319) (xy 175.851312 -206.945992) (xy 175.335438 -206.945992) (xy 175.330015 -206.945598)
			(xy 175.322329 -206.937951) (xy 175.321976 -206.93253) (xy 169.277792 -206.93253) (xy 169.277301 -206.93783)
			(xy 169.269874 -206.945398) (xy 169.264584 -206.945992) (xy 167.791384 -206.945992) (xy 167.786115 -206.945515)
			(xy 167.778673 -206.938054) (xy 167.778176 -206.932784) (xy 98.172016 -206.932784) (xy 98.172016 -207.499458)
			(xy 98.17153 -207.526727) (xy 98.163768 -207.580711) (xy 98.148403 -207.633041) (xy 98.125746 -207.682651)
			(xy 98.09626 -207.728532) (xy 98.060545 -207.769749) (xy 98.045636 -207.782668) (xy 163.678108 -207.782668)
			(xy 163.678108 -207.78216) (xy 163.678108 -207.287876) (xy 163.678581 -207.282607) (xy 163.686045 -207.275165)
			(xy 163.691316 -207.274668) (xy 165.164516 -207.274668) (xy 165.169775 -207.275181) (xy 165.177215 -207.282617)
			(xy 165.177724 -207.287876) (xy 165.177724 -207.782414) (xy 171.221908 -207.782414) (xy 171.221908 -207.287876)
			(xy 171.222381 -207.282607) (xy 171.229845 -207.275165) (xy 171.235116 -207.274668) (xy 171.235624 -207.274668)
			(xy 171.751498 -207.274668) (xy 171.759309 -207.274359) (xy 171.77418 -207.26957) (xy 171.780708 -207.26527)
			(xy 171.801797 -207.250921) (xy 171.847458 -207.22819) (xy 171.896064 -207.212731) (xy 171.946467 -207.204908)
			(xy 171.997473 -207.204908) (xy 172.047876 -207.212731) (xy 172.096482 -207.22819) (xy 172.142143 -207.250921)
			(xy 172.163232 -207.26527) (xy 172.169759 -207.269569) (xy 172.184632 -207.274348) (xy 172.192442 -207.274668)
			(xy 172.70857 -207.274668) (xy 172.713877 -207.275146) (xy 172.721452 -207.282579) (xy 172.722032 -207.287876)
			(xy 172.722032 -207.782414) (xy 172.722018 -207.782668) (xy 178.766216 -207.782668) (xy 178.766216 -207.78216)
			(xy 178.766216 -207.287876) (xy 178.766681 -207.282605) (xy 178.774151 -207.275162) (xy 178.779424 -207.274668)
			(xy 179.295552 -207.274668) (xy 179.303361 -207.274339) (xy 179.318232 -207.269564) (xy 179.324762 -207.26527)
			(xy 179.345851 -207.250921) (xy 179.391512 -207.22819) (xy 179.440118 -207.212731) (xy 179.490521 -207.204908)
			(xy 179.541527 -207.204908) (xy 179.59193 -207.212731) (xy 179.640536 -207.22819) (xy 179.686197 -207.250921)
			(xy 179.707286 -207.26527) (xy 179.713823 -207.269552) (xy 179.728689 -207.274341) (xy 179.736496 -207.274668)
			(xy 180.252624 -207.274668) (xy 180.257884 -207.275176) (xy 180.265324 -207.282616) (xy 180.265832 -207.287876)
			(xy 180.265832 -207.782414) (xy 186.310016 -207.782414) (xy 186.310016 -207.287876) (xy 186.310481 -207.282605)
			(xy 186.317951 -207.275162) (xy 186.323224 -207.274668) (xy 186.323732 -207.274668) (xy 186.839606 -207.274668)
			(xy 186.847417 -207.274362) (xy 186.862289 -207.269571) (xy 186.868816 -207.26527) (xy 186.889905 -207.250921)
			(xy 186.935566 -207.22819) (xy 186.984172 -207.212731) (xy 187.034575 -207.204908) (xy 187.085581 -207.204908)
			(xy 187.135984 -207.212731) (xy 187.18459 -207.22819) (xy 187.230251 -207.250921) (xy 187.25134 -207.26527)
			(xy 187.257865 -207.269572) (xy 187.27274 -207.274349) (xy 187.28055 -207.274668) (xy 187.796678 -207.274668)
			(xy 187.801986 -207.275141) (xy 187.80956 -207.282578) (xy 187.81014 -207.287876) (xy 187.81014 -207.782414)
			(xy 187.810125 -207.782668) (xy 193.854324 -207.782668) (xy 193.854324 -207.78216) (xy 193.854324 -207.287876)
			(xy 193.854614 -207.282533) (xy 193.862187 -207.274991) (xy 193.867532 -207.274668) (xy 194.38366 -207.274668)
			(xy 194.391469 -207.274342) (xy 194.406341 -207.269565) (xy 194.41287 -207.26527) (xy 194.433959 -207.250921)
			(xy 194.47962 -207.22819) (xy 194.528226 -207.212731) (xy 194.578629 -207.204908) (xy 194.629635 -207.204908)
			(xy 194.680038 -207.212731) (xy 194.728644 -207.22819) (xy 194.774305 -207.250921) (xy 194.795394 -207.26527)
			(xy 194.801929 -207.269555) (xy 194.816796 -207.274342) (xy 194.824604 -207.274668) (xy 195.340732 -207.274668)
			(xy 195.345993 -207.275171) (xy 195.353432 -207.282615) (xy 195.35394 -207.287876) (xy 195.35394 -207.782414)
			(xy 195.353918 -207.782668) (xy 201.398124 -207.782668) (xy 201.398124 -207.78216) (xy 201.398124 -207.287876)
			(xy 201.398414 -207.282533) (xy 201.405987 -207.274991) (xy 201.411332 -207.274668) (xy 201.92746 -207.274668)
			(xy 201.935269 -207.274342) (xy 201.950141 -207.269565) (xy 201.95667 -207.26527) (xy 201.977759 -207.250921)
			(xy 202.02342 -207.22819) (xy 202.072026 -207.212731) (xy 202.122429 -207.204908) (xy 202.173435 -207.204908)
			(xy 202.223838 -207.212731) (xy 202.272444 -207.22819) (xy 202.318105 -207.250921) (xy 202.339194 -207.26527)
			(xy 202.345729 -207.269555) (xy 202.360596 -207.274342) (xy 202.368404 -207.274668) (xy 202.884532 -207.274668)
			(xy 202.889793 -207.275171) (xy 202.897232 -207.282615) (xy 202.89774 -207.287876) (xy 202.89774 -207.782414)
			(xy 202.897284 -207.787724) (xy 202.889834 -207.795296) (xy 202.884532 -207.795876) (xy 202.368658 -207.795876)
			(xy 202.360849 -207.796202) (xy 202.345977 -207.800978) (xy 202.339448 -207.805274) (xy 202.31834 -207.819645)
			(xy 202.272611 -207.842366) (xy 202.223934 -207.85779) (xy 202.173464 -207.86555) (xy 202.147932 -207.86598)
			(xy 202.122403 -207.865525) (xy 202.07194 -207.857754) (xy 202.023267 -207.84233) (xy 201.977539 -207.819619)
			(xy 201.956416 -207.805274) (xy 201.949876 -207.800997) (xy 201.935013 -207.796204) (xy 201.927206 -207.795876)
			(xy 201.411332 -207.795876) (xy 201.405996 -207.795548) (xy 201.398452 -207.788004) (xy 201.398124 -207.782668)
			(xy 195.353918 -207.782668) (xy 195.353484 -207.787724) (xy 195.346034 -207.795296) (xy 195.340732 -207.795876)
			(xy 194.824858 -207.795876) (xy 194.817049 -207.796202) (xy 194.802177 -207.800978) (xy 194.795648 -207.805274)
			(xy 194.77454 -207.819645) (xy 194.728811 -207.842366) (xy 194.680134 -207.85779) (xy 194.629664 -207.86555)
			(xy 194.604132 -207.86598) (xy 194.578603 -207.865525) (xy 194.52814 -207.857754) (xy 194.479467 -207.84233)
			(xy 194.433739 -207.819619) (xy 194.412616 -207.805274) (xy 194.406076 -207.800997) (xy 194.391213 -207.796204)
			(xy 194.383406 -207.795876) (xy 193.867532 -207.795876) (xy 193.862196 -207.795548) (xy 193.854652 -207.788004)
			(xy 193.854324 -207.782668) (xy 187.810125 -207.782668) (xy 187.809828 -207.787856) (xy 187.802121 -207.795542)
			(xy 187.796678 -207.795876) (xy 187.280804 -207.795876) (xy 187.272993 -207.796179) (xy 187.258121 -207.800971)
			(xy 187.251594 -207.805274) (xy 187.230473 -207.819625) (xy 187.184749 -207.84235) (xy 187.136075 -207.85778)
			(xy 187.085609 -207.865547) (xy 187.060078 -207.86598) (xy 187.034547 -207.865552) (xy 186.984083 -207.857773)
			(xy 186.935411 -207.842341) (xy 186.889684 -207.819622) (xy 186.868562 -207.805274) (xy 186.862034 -207.800977)
			(xy 186.847161 -207.796196) (xy 186.839352 -207.795876) (xy 186.323478 -207.795876) (xy 186.318115 -207.795366)
			(xy 186.310531 -207.787777) (xy 186.310016 -207.782414) (xy 180.265832 -207.782414) (xy 180.265383 -207.787726)
			(xy 180.257928 -207.795298) (xy 180.252624 -207.795876) (xy 179.73675 -207.795876) (xy 179.72894 -207.796198)
			(xy 179.714068 -207.800977) (xy 179.70754 -207.805274) (xy 179.686434 -207.819648) (xy 179.640705 -207.842368)
			(xy 179.592026 -207.857791) (xy 179.541556 -207.865551) (xy 179.516024 -207.86598) (xy 179.490494 -207.865529)
			(xy 179.440031 -207.857757) (xy 179.391359 -207.842332) (xy 179.345631 -207.819619) (xy 179.324508 -207.805274)
			(xy 179.31797 -207.800994) (xy 179.303105 -207.796203) (xy 179.295298 -207.795876) (xy 178.779424 -207.795876)
			(xy 178.774087 -207.795554) (xy 178.766543 -207.788005) (xy 178.766216 -207.782668) (xy 172.722018 -207.782668)
			(xy 172.721727 -207.787858) (xy 172.714015 -207.795545) (xy 172.70857 -207.795876) (xy 172.192696 -207.795876)
			(xy 172.184884 -207.796175) (xy 172.170013 -207.80097) (xy 172.163486 -207.805274) (xy 172.142368 -207.819628)
			(xy 172.096642 -207.842353) (xy 172.047968 -207.857782) (xy 171.997501 -207.865547) (xy 171.97197 -207.86598)
			(xy 171.946439 -207.865556) (xy 171.895975 -207.857776) (xy 171.847303 -207.842343) (xy 171.801576 -207.819623)
			(xy 171.780454 -207.805274) (xy 171.773928 -207.800973) (xy 171.759054 -207.796195) (xy 171.751244 -207.795876)
			(xy 171.23537 -207.795876) (xy 171.230006 -207.795371) (xy 171.222423 -207.787779) (xy 171.221908 -207.782414)
			(xy 165.177724 -207.782414) (xy 165.177282 -207.787728) (xy 165.169822 -207.795301) (xy 165.164516 -207.795876)
			(xy 163.691316 -207.795876) (xy 163.685978 -207.795559) (xy 163.678434 -207.788006) (xy 163.678108 -207.782668)
			(xy 98.045636 -207.782668) (xy 98.019328 -207.805464) (xy 97.973447 -207.83495) (xy 97.923837 -207.857607)
			(xy 97.871507 -207.872972) (xy 97.817523 -207.880734) (xy 97.762985 -207.880734) (xy 97.709001 -207.872972)
			(xy 97.656671 -207.857607) (xy 97.607061 -207.83495) (xy 97.56118 -207.805464) (xy 97.519963 -207.769749)
			(xy 97.484248 -207.728532) (xy 97.454762 -207.682651) (xy 97.432105 -207.633041) (xy 97.41674 -207.580711)
			(xy 97.408978 -207.526727) (xy 97.408492 -207.499458) (xy 56.07812 -207.499458) (xy 56.07812 -207.782414)
			(xy 56.077826 -207.787861) (xy 56.070106 -207.795548) (xy 56.064658 -207.795876) (xy 54.591458 -207.795876)
			(xy 54.586092 -207.795379) (xy 54.57851 -207.787781) (xy 54.577996 -207.782414) (xy 48.533812 -207.782414)
			(xy 48.53338 -207.787731) (xy 48.525913 -207.795304) (xy 48.520604 -207.795876) (xy 48.00473 -207.795876)
			(xy 47.99692 -207.79619) (xy 47.982048 -207.800974) (xy 47.97552 -207.805274) (xy 47.954392 -207.819613)
			(xy 47.90867 -207.842342) (xy 47.859999 -207.857774) (xy 47.809534 -207.865545) (xy 47.784004 -207.86598)
			(xy 47.758474 -207.865539) (xy 47.70801 -207.857764) (xy 47.659338 -207.842336) (xy 47.61361 -207.819621)
			(xy 47.592488 -207.805274) (xy 47.585954 -207.800986) (xy 47.571086 -207.7962) (xy 47.563278 -207.795876)
			(xy 47.047404 -207.795876) (xy 47.042065 -207.795567) (xy 47.034522 -207.788008) (xy 47.034196 -207.782668)
			(xy 40.989986 -207.782668) (xy 40.989464 -207.787768) (xy 40.981902 -207.795349) (xy 40.97655 -207.795876)
			(xy 40.460676 -207.795876) (xy 40.452864 -207.796167) (xy 40.437992 -207.800967) (xy 40.431466 -207.805274)
			(xy 40.410353 -207.819637) (xy 40.364626 -207.84236) (xy 40.31595 -207.857786) (xy 40.265482 -207.865549)
			(xy 40.23995 -207.86598) (xy 40.214421 -207.865516) (xy 40.163958 -207.857748) (xy 40.115286 -207.842327)
			(xy 40.069557 -207.819618) (xy 40.048434 -207.805274) (xy 40.04189 -207.801004) (xy 40.02703 -207.796206)
			(xy 40.019224 -207.795876) (xy 39.50335 -207.795876) (xy 39.497983 -207.795384) (xy 39.490402 -207.787782)
			(xy 39.489888 -207.782414) (xy 33.445704 -207.782414) (xy 33.445192 -207.78771) (xy 33.43778 -207.795278)
			(xy 33.432496 -207.795876) (xy 32.916622 -207.795876) (xy 32.908811 -207.796186) (xy 32.893939 -207.800973)
			(xy 32.887412 -207.805274) (xy 32.866286 -207.819617) (xy 32.820564 -207.842344) (xy 32.771892 -207.857776)
			(xy 32.721427 -207.865545) (xy 32.695896 -207.86598) (xy 32.670366 -207.865543) (xy 32.619902 -207.857767)
			(xy 32.57123 -207.842338) (xy 32.525502 -207.819621) (xy 32.50438 -207.805274) (xy 32.497848 -207.800983)
			(xy 32.482979 -207.796199) (xy 32.47517 -207.795876) (xy 31.959296 -207.795876) (xy 31.953955 -207.795573)
			(xy 31.946413 -207.788009) (xy 31.946088 -207.782668) (xy 25.901879 -207.782668) (xy 25.901392 -207.78771)
			(xy 25.89398 -207.795278) (xy 25.888696 -207.795876) (xy 25.372822 -207.795876) (xy 25.365011 -207.796186)
			(xy 25.350139 -207.800973) (xy 25.343612 -207.805274) (xy 25.322486 -207.819617) (xy 25.276764 -207.842344)
			(xy 25.228092 -207.857776) (xy 25.177627 -207.865545) (xy 25.152096 -207.86598) (xy 25.126566 -207.865543)
			(xy 25.076102 -207.857767) (xy 25.02743 -207.842338) (xy 24.981702 -207.819621) (xy 24.96058 -207.805274)
			(xy 24.954048 -207.800983) (xy 24.939179 -207.796199) (xy 24.93137 -207.795876) (xy 24.415496 -207.795876)
			(xy 24.410155 -207.795573) (xy 24.402613 -207.788009) (xy 24.402288 -207.782668) (xy 18.358078 -207.782668)
			(xy 18.357563 -207.787769) (xy 18.349996 -207.795352) (xy 18.344642 -207.795876) (xy 17.828768 -207.795876)
			(xy 17.820959 -207.796206) (xy 17.806087 -207.800979) (xy 17.799558 -207.805274) (xy 17.778447 -207.81964)
			(xy 17.732719 -207.842362) (xy 17.684043 -207.857788) (xy 17.633574 -207.865549) (xy 17.608042 -207.86598)
			(xy 17.582513 -207.86552) (xy 17.53205 -207.85775) (xy 17.483378 -207.842328) (xy 17.437649 -207.819618)
			(xy 17.416526 -207.805274) (xy 17.409984 -207.801001) (xy 17.395122 -207.796205) (xy 17.387316 -207.795876)
			(xy 16.871442 -207.795876) (xy 16.866016 -207.795494) (xy 16.858329 -207.787838) (xy 16.85798 -207.782414)
			(xy 2.509012 -207.782414) (xy 2.509012 -208.632552) (xy 20.958048 -208.632552) (xy 20.958048 -208.138014)
			(xy 20.95839 -208.132579) (xy 20.966075 -208.124891) (xy 20.97151 -208.124552) (xy 21.487638 -208.124552)
			(xy 21.495447 -208.12422) (xy 21.510318 -208.119447) (xy 21.516848 -208.115154) (xy 21.537937 -208.100805)
			(xy 21.583598 -208.078074) (xy 21.632204 -208.062615) (xy 21.682607 -208.054792) (xy 21.733613 -208.054792)
			(xy 21.784016 -208.062615) (xy 21.832622 -208.078074) (xy 21.878283 -208.100805) (xy 21.899372 -208.115154)
			(xy 21.905913 -208.119429) (xy 21.920776 -208.124223) (xy 21.928582 -208.124552) (xy 22.44471 -208.124552)
			(xy 22.45015 -208.124874) (xy 22.457836 -208.132574) (xy 22.458172 -208.138014) (xy 22.458172 -208.632552)
			(xy 28.502356 -208.632552) (xy 28.502356 -208.138014) (xy 28.502834 -208.132708) (xy 28.510268 -208.125135)
			(xy 28.515564 -208.124552) (xy 29.031692 -208.124552) (xy 29.039503 -208.124243) (xy 29.054374 -208.119454)
			(xy 29.060902 -208.115154) (xy 29.081991 -208.100805) (xy 29.127652 -208.078074) (xy 29.176258 -208.062615)
			(xy 29.226661 -208.054792) (xy 29.277667 -208.054792) (xy 29.32807 -208.062615) (xy 29.376676 -208.078074)
			(xy 29.422337 -208.100805) (xy 29.443426 -208.115154) (xy 29.449955 -208.119449) (xy 29.464827 -208.124231)
			(xy 29.472636 -208.124552) (xy 29.988764 -208.124552) (xy 29.994013 -208.125115) (xy 30.001455 -208.132514)
			(xy 30.001972 -208.13776) (xy 30.001972 -208.138268) (xy 30.001972 -208.632552) (xy 36.046156 -208.632552)
			(xy 36.046156 -208.138014) (xy 36.046634 -208.132708) (xy 36.054068 -208.125135) (xy 36.059364 -208.124552)
			(xy 36.575492 -208.124552) (xy 36.583303 -208.124243) (xy 36.598174 -208.119454) (xy 36.604702 -208.115154)
			(xy 36.625791 -208.100805) (xy 36.671452 -208.078074) (xy 36.720058 -208.062615) (xy 36.770461 -208.054792)
			(xy 36.821467 -208.054792) (xy 36.87187 -208.062615) (xy 36.920476 -208.078074) (xy 36.966137 -208.100805)
			(xy 36.987226 -208.115154) (xy 36.993755 -208.119449) (xy 37.008627 -208.124231) (xy 37.016436 -208.124552)
			(xy 37.532564 -208.124552) (xy 37.537813 -208.125115) (xy 37.545255 -208.132514) (xy 37.545772 -208.13776)
			(xy 37.545772 -208.138268) (xy 37.545772 -208.632552) (xy 43.589956 -208.632552) (xy 43.589956 -208.138014)
			(xy 43.59029 -208.132577) (xy 43.597981 -208.124889) (xy 43.603418 -208.124552) (xy 44.119546 -208.124552)
			(xy 44.127355 -208.124223) (xy 44.142227 -208.119448) (xy 44.148756 -208.115154) (xy 44.169845 -208.100805)
			(xy 44.215506 -208.078074) (xy 44.264112 -208.062615) (xy 44.314515 -208.054792) (xy 44.365521 -208.054792)
			(xy 44.415924 -208.062615) (xy 44.46453 -208.078074) (xy 44.510191 -208.100805) (xy 44.53128 -208.115154)
			(xy 44.537819 -208.119432) (xy 44.552683 -208.124224) (xy 44.56049 -208.124552) (xy 45.076618 -208.124552)
			(xy 45.081988 -208.12504) (xy 45.089573 -208.132643) (xy 45.09008 -208.138014) (xy 45.09008 -208.632552)
			(xy 51.134264 -208.632552) (xy 51.134264 -208.138014) (xy 51.134735 -208.132706) (xy 51.142174 -208.125133)
			(xy 51.147472 -208.124552) (xy 51.6636 -208.124552) (xy 51.671411 -208.124247) (xy 51.686283 -208.119456)
			(xy 51.69281 -208.115154) (xy 51.713899 -208.100805) (xy 51.75956 -208.078074) (xy 51.808166 -208.062615)
			(xy 51.858569 -208.054792) (xy 51.909575 -208.054792) (xy 51.959978 -208.062615) (xy 52.008584 -208.078074)
			(xy 52.054245 -208.100805) (xy 52.075334 -208.115154) (xy 52.081861 -208.119452) (xy 52.096734 -208.124232)
			(xy 52.104544 -208.124552) (xy 52.620672 -208.124552) (xy 52.625922 -208.125109) (xy 52.633364 -208.132513)
			(xy 52.63388 -208.13776) (xy 52.63388 -208.138268) (xy 52.63388 -208.632552) (xy 58.678064 -208.632552)
			(xy 58.678064 -208.138014) (xy 58.678391 -208.132575) (xy 58.686086 -208.124886) (xy 58.691526 -208.124552)
			(xy 60.164726 -208.124552) (xy 60.170096 -208.125035) (xy 60.177681 -208.132642) (xy 60.178188 -208.138014)
			(xy 60.178188 -208.632552) (xy 60.177839 -208.637883) (xy 60.17031 -208.645427) (xy 60.16498 -208.64576)
			(xy 60.164472 -208.64576) (xy 58.691526 -208.64576) (xy 58.686225 -208.645259) (xy 58.678652 -208.637842)
			(xy 58.678064 -208.632552) (xy 52.63388 -208.632552) (xy 52.633538 -208.637885) (xy 52.626004 -208.64543)
			(xy 52.620672 -208.64576) (xy 52.104798 -208.64576) (xy 52.096924 -208.646053) (xy 52.08192 -208.650833)
			(xy 52.075334 -208.655158) (xy 52.054266 -208.669564) (xy 52.008618 -208.692389) (xy 51.960009 -208.707943)
			(xy 51.90959 -208.715857) (xy 51.884072 -208.716372) (xy 51.858552 -208.715868) (xy 51.808126 -208.707979)
			(xy 51.759514 -208.692423) (xy 51.713875 -208.669572) (xy 51.69281 -208.655158) (xy 51.686215 -208.65085)
			(xy 51.671218 -208.646058) (xy 51.663346 -208.64576) (xy 51.147472 -208.64576) (xy 51.142124 -208.645487)
			(xy 51.134582 -208.637902) (xy 51.134264 -208.632552) (xy 45.09008 -208.632552) (xy 45.089738 -208.637885)
			(xy 45.082204 -208.64543) (xy 45.076872 -208.64576) (xy 45.076364 -208.64576) (xy 44.560744 -208.64576)
			(xy 44.552868 -208.64603) (xy 44.537864 -208.650826) (xy 44.53128 -208.655158) (xy 44.510199 -208.669544)
			(xy 44.464556 -208.692374) (xy 44.415951 -208.707933) (xy 44.365534 -208.715854) (xy 44.340018 -208.716372)
			(xy 44.314497 -208.715895) (xy 44.26407 -208.707998) (xy 44.215458 -208.692434) (xy 44.16982 -208.669575)
			(xy 44.148756 -208.655158) (xy 44.142173 -208.650829) (xy 44.127166 -208.64605) (xy 44.119292 -208.64576)
			(xy 43.603418 -208.64576) (xy 43.598116 -208.645265) (xy 43.590544 -208.637843) (xy 43.589956 -208.632552)
			(xy 37.545772 -208.632552) (xy 37.545437 -208.637887) (xy 37.537898 -208.645432) (xy 37.532564 -208.64576)
			(xy 37.01669 -208.64576) (xy 37.008816 -208.646049) (xy 36.993812 -208.650832) (xy 36.987226 -208.655158)
			(xy 36.96616 -208.669568) (xy 36.920511 -208.692392) (xy 36.871902 -208.707944) (xy 36.821482 -208.715858)
			(xy 36.795964 -208.716372) (xy 36.770444 -208.715872) (xy 36.720017 -208.707982) (xy 36.671406 -208.692425)
			(xy 36.625767 -208.669572) (xy 36.604702 -208.655158) (xy 36.598108 -208.650847) (xy 36.58311 -208.646057)
			(xy 36.575238 -208.64576) (xy 36.059364 -208.64576) (xy 36.054015 -208.645493) (xy 36.046473 -208.637903)
			(xy 36.046156 -208.632552) (xy 30.001972 -208.632552) (xy 30.001637 -208.637887) (xy 29.994098 -208.645432)
			(xy 29.988764 -208.64576) (xy 29.47289 -208.64576) (xy 29.465016 -208.646049) (xy 29.450012 -208.650832)
			(xy 29.443426 -208.655158) (xy 29.42236 -208.669568) (xy 29.376711 -208.692392) (xy 29.328102 -208.707944)
			(xy 29.277682 -208.715858) (xy 29.252164 -208.716372) (xy 29.226644 -208.715872) (xy 29.176217 -208.707982)
			(xy 29.127606 -208.692425) (xy 29.081967 -208.669572) (xy 29.060902 -208.655158) (xy 29.054308 -208.650847)
			(xy 29.03931 -208.646057) (xy 29.031438 -208.64576) (xy 28.515564 -208.64576) (xy 28.510215 -208.645493)
			(xy 28.502673 -208.637903) (xy 28.502356 -208.632552) (xy 22.458172 -208.632552) (xy 22.457837 -208.637887)
			(xy 22.450298 -208.645432) (xy 22.444964 -208.64576) (xy 22.444456 -208.64576) (xy 21.928836 -208.64576)
			(xy 21.920959 -208.646026) (xy 21.905955 -208.650824) (xy 21.899372 -208.655158) (xy 21.878294 -208.669548)
			(xy 21.832649 -208.692376) (xy 21.784043 -208.707935) (xy 21.733627 -208.715854) (xy 21.70811 -208.716372)
			(xy 21.682589 -208.7159) (xy 21.632161 -208.708001) (xy 21.58355 -208.692436) (xy 21.537912 -208.669576)
			(xy 21.516848 -208.655158) (xy 21.510266 -208.650826) (xy 21.495259 -208.646049) (xy 21.487384 -208.64576)
			(xy 20.97151 -208.64576) (xy 20.966207 -208.64527) (xy 20.958635 -208.637845) (xy 20.958048 -208.632552)
			(xy 2.509012 -208.632552) (xy 2.509012 -209.482436) (xy 16.85798 -209.482436) (xy 16.85798 -208.987898)
			(xy 16.858282 -208.982453) (xy 16.865996 -208.974764) (xy 16.871442 -208.974436) (xy 17.38757 -208.974436)
			(xy 17.39538 -208.97412) (xy 17.410252 -208.969337) (xy 17.41678 -208.965038) (xy 17.437869 -208.950689)
			(xy 17.48353 -208.927958) (xy 17.532136 -208.912499) (xy 17.582539 -208.904676) (xy 17.633545 -208.904676)
			(xy 17.683948 -208.912499) (xy 17.732554 -208.927958) (xy 17.778215 -208.950689) (xy 17.799304 -208.965038)
			(xy 17.805839 -208.969324) (xy 17.820706 -208.974111) (xy 17.828514 -208.974436) (xy 18.344642 -208.974436)
			(xy 18.350011 -208.974922) (xy 18.357594 -208.982528) (xy 18.358104 -208.987898) (xy 18.358104 -209.482436)
			(xy 24.402288 -209.482436) (xy 24.402288 -208.987898) (xy 24.402728 -208.982582) (xy 24.410188 -208.975009)
			(xy 24.415496 -208.974436) (xy 24.931624 -208.974436) (xy 24.939436 -208.974144) (xy 24.954308 -208.969344)
			(xy 24.960834 -208.965038) (xy 24.981923 -208.950689) (xy 25.027584 -208.927958) (xy 25.07619 -208.912499)
			(xy 25.126593 -208.904676) (xy 25.177599 -208.904676) (xy 25.228002 -208.912499) (xy 25.276608 -208.927958)
			(xy 25.322269 -208.950689) (xy 25.343358 -208.965038) (xy 25.349881 -208.969344) (xy 25.364757 -208.974119)
			(xy 25.372568 -208.974436) (xy 25.888696 -208.974436) (xy 25.894038 -208.974734) (xy 25.901582 -208.982301)
			(xy 25.901904 -208.987644) (xy 25.901904 -208.988152) (xy 25.901904 -209.482436) (xy 31.946088 -209.482436)
			(xy 31.946088 -208.987898) (xy 31.946528 -208.982582) (xy 31.953988 -208.975009) (xy 31.959296 -208.974436)
			(xy 32.475424 -208.974436) (xy 32.483236 -208.974144) (xy 32.498108 -208.969344) (xy 32.504634 -208.965038)
			(xy 32.525723 -208.950689) (xy 32.571384 -208.927958) (xy 32.61999 -208.912499) (xy 32.670393 -208.904676)
			(xy 32.721399 -208.904676) (xy 32.771802 -208.912499) (xy 32.820408 -208.927958) (xy 32.866069 -208.950689)
			(xy 32.887158 -208.965038) (xy 32.893681 -208.969344) (xy 32.908557 -208.974119) (xy 32.916368 -208.974436)
			(xy 33.432496 -208.974436) (xy 33.437838 -208.974734) (xy 33.445382 -208.982301) (xy 33.445704 -208.987644)
			(xy 33.445704 -208.988152) (xy 33.445704 -209.482436) (xy 39.489888 -209.482436) (xy 39.489888 -208.987898)
			(xy 39.490444 -208.982546) (xy 39.498 -208.974963) (xy 39.50335 -208.974436) (xy 40.019478 -208.974436)
			(xy 40.027288 -208.974124) (xy 40.04216 -208.969338) (xy 40.048688 -208.965038) (xy 40.069777 -208.950689)
			(xy 40.115438 -208.927958) (xy 40.164044 -208.912499) (xy 40.214447 -208.904676) (xy 40.265453 -208.904676)
			(xy 40.315856 -208.912499) (xy 40.364462 -208.927958) (xy 40.410123 -208.950689) (xy 40.431212 -208.965038)
			(xy 40.437745 -208.969327) (xy 40.452614 -208.974112) (xy 40.460422 -208.974436) (xy 40.97655 -208.974436)
			(xy 40.981919 -208.974917) (xy 40.989502 -208.982527) (xy 40.990012 -208.987898) (xy 40.990012 -209.482436)
			(xy 47.034196 -209.482436) (xy 47.034196 -208.987898) (xy 47.034716 -208.982604) (xy 47.042122 -208.975035)
			(xy 47.047404 -208.974436) (xy 47.563532 -208.974436) (xy 47.571341 -208.974104) (xy 47.586213 -208.969332)
			(xy 47.592742 -208.965038) (xy 47.613831 -208.950689) (xy 47.659492 -208.927958) (xy 47.708098 -208.912499)
			(xy 47.758501 -208.904676) (xy 47.809507 -208.904676) (xy 47.85991 -208.912499) (xy 47.908516 -208.927958)
			(xy 47.954177 -208.950689) (xy 47.975266 -208.965038) (xy 47.981809 -208.969309) (xy 47.99667 -208.974106)
			(xy 48.004476 -208.974436) (xy 48.520604 -208.974436) (xy 48.525948 -208.974729) (xy 48.533491 -208.982299)
			(xy 48.533812 -208.987644) (xy 48.533812 -208.988152) (xy 48.533812 -209.482436) (xy 54.577996 -209.482436)
			(xy 54.577996 -208.987898) (xy 54.578545 -208.982544) (xy 54.586106 -208.974961) (xy 54.591458 -208.974436)
			(xy 56.064658 -208.974436) (xy 56.070087 -208.974807) (xy 56.077775 -208.98247) (xy 56.07812 -208.987898)
			(xy 56.07812 -209.023458) (xy 94.105984 -209.023458) (xy 94.105984 -208.159858) (xy 94.10647 -208.132589)
			(xy 94.114232 -208.078605) (xy 94.129597 -208.026275) (xy 94.152254 -207.976665) (xy 94.18174 -207.930784)
			(xy 94.217455 -207.889567) (xy 94.258672 -207.853852) (xy 94.304553 -207.824366) (xy 94.354163 -207.801709)
			(xy 94.406493 -207.786344) (xy 94.460477 -207.778582) (xy 94.515015 -207.778582) (xy 94.568999 -207.786344)
			(xy 94.621329 -207.801709) (xy 94.670939 -207.824366) (xy 94.71682 -207.853852) (xy 94.758037 -207.889567)
			(xy 94.793752 -207.930784) (xy 94.823238 -207.976665) (xy 94.845895 -208.026275) (xy 94.86126 -208.078605)
			(xy 94.869022 -208.132589) (xy 94.869508 -208.159858) (xy 94.869508 -208.632552) (xy 167.778176 -208.632552)
			(xy 167.778176 -208.138014) (xy 167.778637 -208.132703) (xy 167.786082 -208.125129) (xy 167.791384 -208.124552)
			(xy 169.264584 -208.124552) (xy 169.269835 -208.125101) (xy 169.277276 -208.132511) (xy 169.277792 -208.13776)
			(xy 169.277792 -208.632552) (xy 175.321976 -208.632552) (xy 175.321976 -208.138014) (xy 175.322292 -208.132572)
			(xy 175.329995 -208.124883) (xy 175.335438 -208.124552) (xy 175.851566 -208.124552) (xy 175.859376 -208.124232)
			(xy 175.874247 -208.119451) (xy 175.880776 -208.115154) (xy 175.901865 -208.100805) (xy 175.947526 -208.078074)
			(xy 175.996132 -208.062615) (xy 176.046535 -208.054792) (xy 176.097541 -208.054792) (xy 176.147944 -208.062615)
			(xy 176.19655 -208.078074) (xy 176.242211 -208.100805) (xy 176.2633 -208.115154) (xy 176.269835 -208.119439)
			(xy 176.284702 -208.124227) (xy 176.29251 -208.124552) (xy 176.808638 -208.124552) (xy 176.81401 -208.125027)
			(xy 176.821594 -208.13264) (xy 176.8221 -208.138014) (xy 176.8221 -208.632552) (xy 182.866284 -208.632552)
			(xy 182.866284 -208.138014) (xy 182.866738 -208.132701) (xy 182.874188 -208.125127) (xy 182.879492 -208.124552)
			(xy 183.39562 -208.124552) (xy 183.403432 -208.124255) (xy 183.418303 -208.119459) (xy 183.42483 -208.115154)
			(xy 183.445919 -208.100805) (xy 183.49158 -208.078074) (xy 183.540186 -208.062615) (xy 183.590589 -208.054792)
			(xy 183.641595 -208.054792) (xy 183.691998 -208.062615) (xy 183.740604 -208.078074) (xy 183.786265 -208.100805)
			(xy 183.807354 -208.115154) (xy 183.813877 -208.11946) (xy 183.828753 -208.124235) (xy 183.836564 -208.124552)
			(xy 184.352692 -208.124552) (xy 184.357944 -208.125096) (xy 184.365385 -208.13251) (xy 184.3659 -208.13776)
			(xy 184.3659 -208.138268) (xy 184.3659 -208.632552) (xy 190.410084 -208.632552) (xy 190.410084 -208.138014)
			(xy 190.410393 -208.13257) (xy 190.418101 -208.12488) (xy 190.423546 -208.124552) (xy 190.939674 -208.124552)
			(xy 190.947484 -208.124235) (xy 190.962356 -208.119452) (xy 190.968884 -208.115154) (xy 190.989973 -208.100805)
			(xy 191.035634 -208.078074) (xy 191.08424 -208.062615) (xy 191.134643 -208.054792) (xy 191.185649 -208.054792)
			(xy 191.236052 -208.062615) (xy 191.284658 -208.078074) (xy 191.330319 -208.100805) (xy 191.351408 -208.115154)
			(xy 191.357941 -208.119443) (xy 191.37281 -208.124228) (xy 191.380618 -208.124552) (xy 191.896746 -208.124552)
			(xy 191.902119 -208.125021) (xy 191.909703 -208.132639) (xy 191.910208 -208.138014) (xy 191.910208 -208.632552)
			(xy 197.954392 -208.632552) (xy 197.954392 -208.138014) (xy 197.954927 -208.132723) (xy 197.962321 -208.125154)
			(xy 197.9676 -208.124552) (xy 198.483728 -208.124552) (xy 198.49154 -208.124258) (xy 198.506412 -208.11946)
			(xy 198.512938 -208.115154) (xy 198.534027 -208.100805) (xy 198.579688 -208.078074) (xy 198.628294 -208.062615)
			(xy 198.678697 -208.054792) (xy 198.729703 -208.054792) (xy 198.780106 -208.062615) (xy 198.828712 -208.078074)
			(xy 198.874373 -208.100805) (xy 198.895462 -208.115154) (xy 198.902005 -208.119425) (xy 198.916866 -208.124221)
			(xy 198.924672 -208.124552) (xy 199.4408 -208.124552) (xy 199.446053 -208.125091) (xy 199.453493 -208.132508)
			(xy 199.454008 -208.13776) (xy 199.454008 -208.138268) (xy 199.454008 -208.632552) (xy 205.498192 -208.632552)
			(xy 205.498192 -208.138014) (xy 205.498727 -208.132723) (xy 205.506121 -208.125154) (xy 205.5114 -208.124552)
			(xy 206.027528 -208.124552) (xy 206.03534 -208.124258) (xy 206.050212 -208.11946) (xy 206.056738 -208.115154)
			(xy 206.077827 -208.100805) (xy 206.123488 -208.078074) (xy 206.172094 -208.062615) (xy 206.222497 -208.054792)
			(xy 206.273503 -208.054792) (xy 206.323906 -208.062615) (xy 206.372512 -208.078074) (xy 206.418173 -208.100805)
			(xy 206.439262 -208.115154) (xy 206.445805 -208.119425) (xy 206.460666 -208.124221) (xy 206.468472 -208.124552)
			(xy 206.9846 -208.124552) (xy 206.989853 -208.125091) (xy 206.997293 -208.132508) (xy 206.997808 -208.13776)
			(xy 206.997808 -208.138268) (xy 206.997808 -208.217008) (xy 255.545336 -208.217008) (xy 255.545336 -207.353408)
			(xy 255.545822 -207.326139) (xy 255.553584 -207.272155) (xy 255.568949 -207.219825) (xy 255.591606 -207.170215)
			(xy 255.621092 -207.124334) (xy 255.656807 -207.083117) (xy 255.698024 -207.047402) (xy 255.743905 -207.017916)
			(xy 255.793515 -206.995259) (xy 255.845845 -206.979894) (xy 255.899829 -206.972132) (xy 255.954367 -206.972132)
			(xy 256.008351 -206.979894) (xy 256.060681 -206.995259) (xy 256.110291 -207.017916) (xy 256.156172 -207.047402)
			(xy 256.197389 -207.083117) (xy 256.233104 -207.124334) (xy 256.26259 -207.170215) (xy 256.285247 -207.219825)
			(xy 256.300612 -207.272155) (xy 256.308374 -207.326139) (xy 256.30886 -207.353408) (xy 256.30886 -207.78216)
			(xy 264.798048 -207.78216) (xy 264.798048 -207.287622) (xy 264.798395 -207.282188) (xy 264.806076 -207.2745)
			(xy 264.81151 -207.27416) (xy 265.327638 -207.27416) (xy 265.335446 -207.273827) (xy 265.350318 -207.269055)
			(xy 265.356848 -207.264762) (xy 265.377937 -207.250413) (xy 265.423598 -207.227682) (xy 265.472204 -207.212223)
			(xy 265.522607 -207.2044) (xy 265.573613 -207.2044) (xy 265.624016 -207.212223) (xy 265.672622 -207.227682)
			(xy 265.718283 -207.250413) (xy 265.739372 -207.264762) (xy 265.745913 -207.269037) (xy 265.760776 -207.273831)
			(xy 265.768582 -207.27416) (xy 266.28471 -207.27416) (xy 266.290152 -207.274475) (xy 266.297838 -207.28218)
			(xy 266.298172 -207.287622) (xy 266.298172 -207.78216) (xy 272.342356 -207.78216) (xy 272.342356 -207.287622)
			(xy 272.342839 -207.282317) (xy 272.350269 -207.274743) (xy 272.355564 -207.27416) (xy 272.871692 -207.27416)
			(xy 272.879503 -207.27385) (xy 272.894374 -207.269062) (xy 272.900902 -207.264762) (xy 272.921991 -207.250413)
			(xy 272.967652 -207.227682) (xy 273.016258 -207.212223) (xy 273.066661 -207.2044) (xy 273.117667 -207.2044)
			(xy 273.16807 -207.212223) (xy 273.216676 -207.227682) (xy 273.262337 -207.250413) (xy 273.283426 -207.264762)
			(xy 273.289955 -207.269058) (xy 273.304827 -207.273839) (xy 273.312636 -207.27416) (xy 273.828764 -207.27416)
			(xy 273.834084 -207.274548) (xy 273.841625 -207.28205) (xy 273.841972 -207.287368) (xy 273.841972 -207.287876)
			(xy 273.841972 -207.78216) (xy 279.886156 -207.78216) (xy 279.886156 -207.287622) (xy 279.886639 -207.282317)
			(xy 279.894069 -207.274743) (xy 279.899364 -207.27416) (xy 280.415492 -207.27416) (xy 280.423303 -207.27385)
			(xy 280.438174 -207.269062) (xy 280.444702 -207.264762) (xy 280.465791 -207.250413) (xy 280.511452 -207.227682)
			(xy 280.560058 -207.212223) (xy 280.610461 -207.2044) (xy 280.661467 -207.2044) (xy 280.71187 -207.212223)
			(xy 280.760476 -207.227682) (xy 280.806137 -207.250413) (xy 280.827226 -207.264762) (xy 280.833755 -207.269058)
			(xy 280.848627 -207.273839) (xy 280.856436 -207.27416) (xy 281.372564 -207.27416) (xy 281.377884 -207.274548)
			(xy 281.385425 -207.28205) (xy 281.385772 -207.287368) (xy 281.385772 -207.287876) (xy 281.385772 -207.78216)
			(xy 287.429956 -207.78216) (xy 287.429956 -207.287622) (xy 287.430296 -207.282186) (xy 287.437982 -207.274498)
			(xy 287.443418 -207.27416) (xy 287.959546 -207.27416) (xy 287.967355 -207.27383) (xy 287.982226 -207.269056)
			(xy 287.988756 -207.264762) (xy 288.009845 -207.250413) (xy 288.055506 -207.227682) (xy 288.104112 -207.212223)
			(xy 288.154515 -207.2044) (xy 288.205521 -207.2044) (xy 288.255924 -207.212223) (xy 288.30453 -207.227682)
			(xy 288.350191 -207.250413) (xy 288.37128 -207.264762) (xy 288.377819 -207.269041) (xy 288.392683 -207.273832)
			(xy 288.40049 -207.27416) (xy 288.916618 -207.27416) (xy 288.922061 -207.274469) (xy 288.929747 -207.282178)
			(xy 288.93008 -207.287622) (xy 288.93008 -207.78216) (xy 294.974264 -207.78216) (xy 294.974264 -207.287622)
			(xy 294.974741 -207.282315) (xy 294.982175 -207.274741) (xy 294.987472 -207.27416) (xy 295.5036 -207.27416)
			(xy 295.511411 -207.273853) (xy 295.526283 -207.269063) (xy 295.53281 -207.264762) (xy 295.553899 -207.250413)
			(xy 295.59956 -207.227682) (xy 295.648166 -207.212223) (xy 295.698569 -207.2044) (xy 295.749575 -207.2044)
			(xy 295.799978 -207.212223) (xy 295.848584 -207.227682) (xy 295.894245 -207.250413) (xy 295.915334 -207.264762)
			(xy 295.921861 -207.269061) (xy 295.936734 -207.27384) (xy 295.944544 -207.27416) (xy 296.460672 -207.27416)
			(xy 296.465924 -207.27471) (xy 296.473366 -207.282119) (xy 296.47388 -207.287368) (xy 296.47388 -207.287876)
			(xy 296.47388 -207.78216) (xy 302.518064 -207.78216) (xy 302.518064 -207.287622) (xy 302.518397 -207.282184)
			(xy 302.526088 -207.274495) (xy 302.531526 -207.27416) (xy 304.004726 -207.27416) (xy 304.010098 -207.274635)
			(xy 304.017684 -207.282248) (xy 304.018188 -207.287622) (xy 304.018188 -207.78216) (xy 411.618176 -207.78216)
			(xy 411.618176 -207.287622) (xy 411.618642 -207.282312) (xy 411.626084 -207.274738) (xy 411.631384 -207.27416)
			(xy 413.104584 -207.27416) (xy 413.109837 -207.274702) (xy 413.117279 -207.282117) (xy 413.117792 -207.287368)
			(xy 413.117792 -207.287876) (xy 413.117792 -207.78216) (xy 419.161976 -207.78216) (xy 419.161976 -207.287622)
			(xy 419.162298 -207.282181) (xy 419.169997 -207.274491) (xy 419.175438 -207.27416) (xy 419.691566 -207.27416)
			(xy 419.699375 -207.273838) (xy 419.714247 -207.269058) (xy 419.720776 -207.264762) (xy 419.741865 -207.250413)
			(xy 419.787526 -207.227682) (xy 419.836132 -207.212223) (xy 419.886535 -207.2044) (xy 419.937541 -207.2044)
			(xy 419.987944 -207.212223) (xy 420.03655 -207.227682) (xy 420.082211 -207.250413) (xy 420.1033 -207.264762)
			(xy 420.109835 -207.269048) (xy 420.124702 -207.273835) (xy 420.13251 -207.27416) (xy 420.648638 -207.27416)
			(xy 420.654012 -207.274628) (xy 420.661596 -207.282246) (xy 420.6621 -207.287622) (xy 420.6621 -207.78216)
			(xy 426.706284 -207.78216) (xy 426.706284 -207.287622) (xy 426.706743 -207.28231) (xy 426.714189 -207.274735)
			(xy 426.719492 -207.27416) (xy 427.23562 -207.27416) (xy 427.243432 -207.273862) (xy 427.258303 -207.269066)
			(xy 427.26483 -207.264762) (xy 427.285919 -207.250413) (xy 427.33158 -207.227682) (xy 427.380186 -207.212223)
			(xy 427.430589 -207.2044) (xy 427.481595 -207.2044) (xy 427.531998 -207.212223) (xy 427.580604 -207.227682)
			(xy 427.626265 -207.250413) (xy 427.647354 -207.264762) (xy 427.653877 -207.269069) (xy 427.668753 -207.273843)
			(xy 427.676564 -207.27416) (xy 428.192692 -207.27416) (xy 428.197946 -207.274697) (xy 428.205387 -207.282115)
			(xy 428.2059 -207.287368) (xy 428.2059 -207.287876) (xy 428.2059 -207.78216) (xy 434.250084 -207.78216)
			(xy 434.250084 -207.287622) (xy 434.250399 -207.282179) (xy 434.258102 -207.274489) (xy 434.263546 -207.27416)
			(xy 434.779674 -207.27416) (xy 434.787484 -207.273842) (xy 434.802355 -207.269059) (xy 434.808884 -207.264762)
			(xy 434.829973 -207.250413) (xy 434.875634 -207.227682) (xy 434.92424 -207.212223) (xy 434.974643 -207.2044)
			(xy 435.025649 -207.2044) (xy 435.076052 -207.212223) (xy 435.124658 -207.227682) (xy 435.170319 -207.250413)
			(xy 435.191408 -207.264762) (xy 435.197941 -207.269051) (xy 435.21281 -207.273836) (xy 435.220618 -207.27416)
			(xy 435.736746 -207.27416) (xy 435.742121 -207.274622) (xy 435.749705 -207.282245) (xy 435.750208 -207.287622)
			(xy 435.750208 -207.78216) (xy 441.794392 -207.78216) (xy 441.794392 -207.287622) (xy 441.794932 -207.282332)
			(xy 441.802323 -207.274762) (xy 441.8076 -207.27416) (xy 442.323728 -207.27416) (xy 442.33154 -207.273865)
			(xy 442.346411 -207.269067) (xy 442.352938 -207.264762) (xy 442.374027 -207.250413) (xy 442.419688 -207.227682)
			(xy 442.468294 -207.212223) (xy 442.518697 -207.2044) (xy 442.569703 -207.2044) (xy 442.620106 -207.212223)
			(xy 442.668712 -207.227682) (xy 442.714373 -207.250413) (xy 442.735462 -207.264762) (xy 442.742005 -207.269034)
			(xy 442.756866 -207.273829) (xy 442.764672 -207.27416) (xy 443.2808 -207.27416) (xy 443.286055 -207.274692)
			(xy 443.293496 -207.282114) (xy 443.294008 -207.287368) (xy 443.294008 -207.287876) (xy 443.294008 -207.78216)
			(xy 449.338192 -207.78216) (xy 449.338192 -207.287622) (xy 449.338732 -207.282332) (xy 449.346123 -207.274762)
			(xy 449.3514 -207.27416) (xy 449.867528 -207.27416) (xy 449.87534 -207.273865) (xy 449.890211 -207.269067)
			(xy 449.896738 -207.264762) (xy 449.917827 -207.250413) (xy 449.963488 -207.227682) (xy 450.012094 -207.212223)
			(xy 450.062497 -207.2044) (xy 450.113503 -207.2044) (xy 450.163906 -207.212223) (xy 450.212512 -207.227682)
			(xy 450.258173 -207.250413) (xy 450.279262 -207.264762) (xy 450.285805 -207.269034) (xy 450.300666 -207.273829)
			(xy 450.308472 -207.27416) (xy 450.8246 -207.27416) (xy 450.829855 -207.274692) (xy 450.837296 -207.282114)
			(xy 450.837808 -207.287368) (xy 450.837808 -207.287876) (xy 450.837808 -207.78216) (xy 450.837446 -207.787487)
			(xy 450.829926 -207.79503) (xy 450.8246 -207.795368) (xy 450.308726 -207.795368) (xy 450.300849 -207.795628)
			(xy 450.285845 -207.80043) (xy 450.279262 -207.804766) (xy 450.258187 -207.819161) (xy 450.212541 -207.841988)
			(xy 450.163934 -207.857545) (xy 450.113517 -207.865463) (xy 450.088 -207.86598) (xy 450.062479 -207.865511)
			(xy 450.012051 -207.857611) (xy 449.963439 -207.842045) (xy 449.917802 -207.819184) (xy 449.896738 -207.804766)
			(xy 449.890136 -207.800469) (xy 449.875144 -207.79567) (xy 449.867274 -207.795368) (xy 449.3514 -207.795368)
			(xy 449.346058 -207.795069) (xy 449.338515 -207.787503) (xy 449.338192 -207.78216) (xy 443.294008 -207.78216)
			(xy 443.293646 -207.787487) (xy 443.286126 -207.79503) (xy 443.2808 -207.795368) (xy 442.764926 -207.795368)
			(xy 442.757049 -207.795628) (xy 442.742045 -207.80043) (xy 442.735462 -207.804766) (xy 442.714387 -207.819161)
			(xy 442.668741 -207.841988) (xy 442.620134 -207.857545) (xy 442.569717 -207.865463) (xy 442.5442 -207.86598)
			(xy 442.518679 -207.865511) (xy 442.468251 -207.857611) (xy 442.419639 -207.842045) (xy 442.374002 -207.819184)
			(xy 442.352938 -207.804766) (xy 442.346336 -207.800469) (xy 442.331344 -207.79567) (xy 442.323474 -207.795368)
			(xy 441.8076 -207.795368) (xy 441.802258 -207.795069) (xy 441.794715 -207.787503) (xy 441.794392 -207.78216)
			(xy 435.750208 -207.78216) (xy 435.749846 -207.787487) (xy 435.742326 -207.79503) (xy 435.737 -207.795368)
			(xy 435.736492 -207.795368) (xy 435.220872 -207.795368) (xy 435.212997 -207.795648) (xy 435.197993 -207.800437)
			(xy 435.191408 -207.804766) (xy 435.170348 -207.819184) (xy 435.124697 -207.842006) (xy 435.076085 -207.857556)
			(xy 435.025664 -207.865467) (xy 435.000146 -207.86598) (xy 434.974626 -207.865488) (xy 434.924199 -207.857595)
			(xy 434.875587 -207.842036) (xy 434.829949 -207.819181) (xy 434.808884 -207.804766) (xy 434.802294 -207.800448)
			(xy 434.787293 -207.795662) (xy 434.77942 -207.795368) (xy 434.263546 -207.795368) (xy 434.258249 -207.794847)
			(xy 434.250676 -207.787445) (xy 434.250084 -207.78216) (xy 428.2059 -207.78216) (xy 428.205545 -207.787489)
			(xy 428.19802 -207.795032) (xy 428.192692 -207.795368) (xy 427.676818 -207.795368) (xy 427.668944 -207.795668)
			(xy 427.65394 -207.800443) (xy 427.647354 -207.804766) (xy 427.626281 -207.819165) (xy 427.580634 -207.841991)
			(xy 427.532027 -207.857547) (xy 427.481609 -207.865464) (xy 427.456092 -207.86598) (xy 427.430573 -207.865465)
			(xy 427.380147 -207.857579) (xy 427.331535 -207.842026) (xy 427.285896 -207.819178) (xy 427.26483 -207.804766)
			(xy 427.25823 -207.800466) (xy 427.243237 -207.795669) (xy 427.235366 -207.795368) (xy 426.719492 -207.795368)
			(xy 426.714149 -207.795075) (xy 426.706606 -207.787504) (xy 426.706284 -207.78216) (xy 420.6621 -207.78216)
			(xy 420.661745 -207.787489) (xy 420.65422 -207.795032) (xy 420.648892 -207.795368) (xy 420.648384 -207.795368)
			(xy 420.132764 -207.795368) (xy 420.124888 -207.795645) (xy 420.109884 -207.800436) (xy 420.1033 -207.804766)
			(xy 420.082214 -207.819145) (xy 420.036572 -207.841976) (xy 419.987969 -207.857537) (xy 419.937554 -207.86546)
			(xy 419.912038 -207.86598) (xy 419.886518 -207.865492) (xy 419.836091 -207.857598) (xy 419.787479 -207.842037)
			(xy 419.741841 -207.819182) (xy 419.720776 -207.804766) (xy 419.714188 -207.800445) (xy 419.699185 -207.795661)
			(xy 419.691312 -207.795368) (xy 419.175438 -207.795368) (xy 419.17014 -207.794852) (xy 419.162568 -207.787446)
			(xy 419.161976 -207.78216) (xy 413.117792 -207.78216) (xy 413.117445 -207.787491) (xy 413.109914 -207.795035)
			(xy 413.104584 -207.795368) (xy 411.631384 -207.795368) (xy 411.62604 -207.79508) (xy 411.618497 -207.787506)
			(xy 411.618176 -207.78216) (xy 304.018188 -207.78216) (xy 304.017844 -207.787492) (xy 304.010311 -207.795036)
			(xy 304.00498 -207.795368) (xy 302.531526 -207.795368) (xy 302.526227 -207.79486) (xy 302.518655 -207.787448)
			(xy 302.518064 -207.78216) (xy 296.47388 -207.78216) (xy 296.473543 -207.787494) (xy 296.466005 -207.795039)
			(xy 296.460672 -207.795368) (xy 295.944798 -207.795368) (xy 295.936924 -207.795659) (xy 295.92192 -207.80044)
			(xy 295.915334 -207.804766) (xy 295.894267 -207.819173) (xy 295.848618 -207.841997) (xy 295.800009 -207.857551)
			(xy 295.74959 -207.865465) (xy 295.724072 -207.86598) (xy 295.698552 -207.865475) (xy 295.648126 -207.857586)
			(xy 295.599514 -207.84203) (xy 295.553875 -207.819179) (xy 295.53281 -207.804766) (xy 295.526214 -207.800458)
			(xy 295.511218 -207.795666) (xy 295.503346 -207.795368) (xy 294.987472 -207.795368) (xy 294.982126 -207.795088)
			(xy 294.974584 -207.787508) (xy 294.974264 -207.78216) (xy 288.93008 -207.78216) (xy 288.929743 -207.787494)
			(xy 288.922205 -207.795039) (xy 288.916872 -207.795368) (xy 288.916364 -207.795368) (xy 288.400744 -207.795368)
			(xy 288.392868 -207.795636) (xy 288.377864 -207.800433) (xy 288.37128 -207.804766) (xy 288.3502 -207.819153)
			(xy 288.304556 -207.841982) (xy 288.255951 -207.857541) (xy 288.205534 -207.865462) (xy 288.180018 -207.86598)
			(xy 288.154497 -207.865502) (xy 288.10407 -207.857605) (xy 288.055458 -207.842041) (xy 288.00982 -207.819183)
			(xy 287.988756 -207.804766) (xy 287.982172 -207.800437) (xy 287.967166 -207.795658) (xy 287.959292 -207.795368)
			(xy 287.443418 -207.795368) (xy 287.438118 -207.794866) (xy 287.430546 -207.787449) (xy 287.429956 -207.78216)
			(xy 281.385772 -207.78216) (xy 281.385443 -207.787496) (xy 281.377899 -207.795041) (xy 281.372564 -207.795368)
			(xy 280.85669 -207.795368) (xy 280.848815 -207.795656) (xy 280.833811 -207.800439) (xy 280.827226 -207.804766)
			(xy 280.806161 -207.819177) (xy 280.760511 -207.842) (xy 280.711902 -207.857553) (xy 280.661482 -207.865466)
			(xy 280.635964 -207.86598) (xy 280.610444 -207.865479) (xy 280.560018 -207.857588) (xy 280.511406 -207.842032)
			(xy 280.465767 -207.81918) (xy 280.444702 -207.804766) (xy 280.438108 -207.800455) (xy 280.42311 -207.795665)
			(xy 280.415238 -207.795368) (xy 279.899364 -207.795368) (xy 279.894017 -207.795093) (xy 279.886476 -207.787509)
			(xy 279.886156 -207.78216) (xy 273.841972 -207.78216) (xy 273.841643 -207.787496) (xy 273.834099 -207.795041)
			(xy 273.828764 -207.795368) (xy 273.31289 -207.795368) (xy 273.305015 -207.795656) (xy 273.290011 -207.800439)
			(xy 273.283426 -207.804766) (xy 273.262361 -207.819177) (xy 273.216711 -207.842) (xy 273.168102 -207.857553)
			(xy 273.117682 -207.865466) (xy 273.092164 -207.86598) (xy 273.066644 -207.865479) (xy 273.016218 -207.857588)
			(xy 272.967606 -207.842032) (xy 272.921967 -207.81918) (xy 272.900902 -207.804766) (xy 272.894308 -207.800455)
			(xy 272.87931 -207.795665) (xy 272.871438 -207.795368) (xy 272.355564 -207.795368) (xy 272.350217 -207.795093)
			(xy 272.342676 -207.787509) (xy 272.342356 -207.78216) (xy 266.298172 -207.78216) (xy 266.297843 -207.787496)
			(xy 266.290299 -207.795041) (xy 266.284964 -207.795368) (xy 266.284456 -207.795368) (xy 265.768836 -207.795368)
			(xy 265.760959 -207.795633) (xy 265.745955 -207.800432) (xy 265.739372 -207.804766) (xy 265.718294 -207.819157)
			(xy 265.672649 -207.841985) (xy 265.624043 -207.857543) (xy 265.573627 -207.865462) (xy 265.54811 -207.86598)
			(xy 265.522589 -207.865506) (xy 265.472161 -207.857607) (xy 265.42355 -207.842043) (xy 265.377912 -207.819183)
			(xy 265.356848 -207.804766) (xy 265.350266 -207.800434) (xy 265.335259 -207.795657) (xy 265.327384 -207.795368)
			(xy 264.81151 -207.795368) (xy 264.806209 -207.794871) (xy 264.798637 -207.78745) (xy 264.798048 -207.78216)
			(xy 256.30886 -207.78216) (xy 256.30886 -208.217008) (xy 256.308374 -208.244277) (xy 256.300612 -208.298261)
			(xy 256.285247 -208.350591) (xy 256.26259 -208.400201) (xy 256.233104 -208.446082) (xy 256.197389 -208.487299)
			(xy 256.156172 -208.523014) (xy 256.110291 -208.5525) (xy 256.060681 -208.575157) (xy 256.008351 -208.590522)
			(xy 255.954367 -208.598284) (xy 255.899829 -208.598284) (xy 255.845845 -208.590522) (xy 255.793515 -208.575157)
			(xy 255.743905 -208.5525) (xy 255.698024 -208.523014) (xy 255.656807 -208.487299) (xy 255.621092 -208.446082)
			(xy 255.591606 -208.400201) (xy 255.568949 -208.350591) (xy 255.553584 -208.298261) (xy 255.545822 -208.244277)
			(xy 255.545336 -208.217008) (xy 206.997808 -208.217008) (xy 206.997808 -208.632298) (xy 268.898116 -208.632298)
			(xy 268.898116 -208.13776) (xy 268.89857 -208.132487) (xy 268.906048 -208.125045) (xy 268.911324 -208.124552)
			(xy 268.911832 -208.124552) (xy 269.427706 -208.124552) (xy 269.435517 -208.124249) (xy 269.450389 -208.119457)
			(xy 269.456916 -208.115154) (xy 269.478005 -208.100805) (xy 269.523666 -208.078074) (xy 269.572272 -208.062615)
			(xy 269.622675 -208.054792) (xy 269.673681 -208.054792) (xy 269.724084 -208.062615) (xy 269.77269 -208.078074)
			(xy 269.818351 -208.100805) (xy 269.83944 -208.115154) (xy 269.845966 -208.119455) (xy 269.86084 -208.124233)
			(xy 269.86865 -208.124552) (xy 270.384778 -208.124552) (xy 270.390082 -208.125039) (xy 270.397656 -208.132466)
			(xy 270.39824 -208.13776) (xy 270.39824 -208.632298) (xy 270.398225 -208.632552) (xy 276.442424 -208.632552)
			(xy 276.442424 -208.632044) (xy 276.442424 -208.13776) (xy 276.442871 -208.132485) (xy 276.450354 -208.125042)
			(xy 276.455632 -208.124552) (xy 276.97176 -208.124552) (xy 276.979569 -208.124229) (xy 276.994441 -208.11945)
			(xy 277.00097 -208.115154) (xy 277.022059 -208.100805) (xy 277.06772 -208.078074) (xy 277.116326 -208.062615)
			(xy 277.166729 -208.054792) (xy 277.217735 -208.054792) (xy 277.268138 -208.062615) (xy 277.316744 -208.078074)
			(xy 277.362405 -208.100805) (xy 277.383494 -208.115154) (xy 277.39003 -208.119437) (xy 277.404897 -208.124226)
			(xy 277.412704 -208.124552) (xy 277.928832 -208.124552) (xy 277.934089 -208.125069) (xy 277.941527 -208.132503)
			(xy 277.94204 -208.13776) (xy 277.94204 -208.632298) (xy 277.942018 -208.632552) (xy 283.986224 -208.632552)
			(xy 283.986224 -208.632044) (xy 283.986224 -208.13776) (xy 283.986671 -208.132485) (xy 283.994154 -208.125042)
			(xy 283.999432 -208.124552) (xy 284.51556 -208.124552) (xy 284.523369 -208.124229) (xy 284.538241 -208.11945)
			(xy 284.54477 -208.115154) (xy 284.565859 -208.100805) (xy 284.61152 -208.078074) (xy 284.660126 -208.062615)
			(xy 284.710529 -208.054792) (xy 284.761535 -208.054792) (xy 284.811938 -208.062615) (xy 284.860544 -208.078074)
			(xy 284.906205 -208.100805) (xy 284.927294 -208.115154) (xy 284.93383 -208.119437) (xy 284.948697 -208.124226)
			(xy 284.956504 -208.124552) (xy 285.472632 -208.124552) (xy 285.477889 -208.125069) (xy 285.485327 -208.132503)
			(xy 285.48584 -208.13776) (xy 285.48584 -208.632298) (xy 291.530024 -208.632298) (xy 291.530024 -208.13776)
			(xy 291.530471 -208.132485) (xy 291.537954 -208.125042) (xy 291.543232 -208.124552) (xy 291.54374 -208.124552)
			(xy 292.059614 -208.124552) (xy 292.067426 -208.124253) (xy 292.082297 -208.119458) (xy 292.088824 -208.115154)
			(xy 292.109913 -208.100805) (xy 292.155574 -208.078074) (xy 292.20418 -208.062615) (xy 292.254583 -208.054792)
			(xy 292.305589 -208.054792) (xy 292.355992 -208.062615) (xy 292.404598 -208.078074) (xy 292.450259 -208.100805)
			(xy 292.471348 -208.115154) (xy 292.477872 -208.119458) (xy 292.492748 -208.124234) (xy 292.500558 -208.124552)
			(xy 293.016686 -208.124552) (xy 293.021991 -208.125034) (xy 293.029564 -208.132465) (xy 293.030148 -208.13776)
			(xy 293.030148 -208.632298) (xy 293.030133 -208.632552) (xy 299.074332 -208.632552) (xy 299.074332 -208.632044)
			(xy 299.074332 -208.13776) (xy 299.074772 -208.132483) (xy 299.08226 -208.12504) (xy 299.08754 -208.124552)
			(xy 299.603668 -208.124552) (xy 299.611478 -208.124233) (xy 299.626349 -208.119451) (xy 299.632878 -208.115154)
			(xy 299.653967 -208.100805) (xy 299.699628 -208.078074) (xy 299.748234 -208.062615) (xy 299.798637 -208.054792)
			(xy 299.849643 -208.054792) (xy 299.900046 -208.062615) (xy 299.948652 -208.078074) (xy 299.994313 -208.100805)
			(xy 300.015402 -208.115154) (xy 300.021937 -208.11944) (xy 300.036804 -208.124227) (xy 300.044612 -208.124552)
			(xy 300.56074 -208.124552) (xy 300.565998 -208.125064) (xy 300.573436 -208.132502) (xy 300.573948 -208.13776)
			(xy 300.573948 -208.632298) (xy 306.618132 -208.632298) (xy 306.618132 -208.13776) (xy 306.618572 -208.132483)
			(xy 306.62606 -208.12504) (xy 306.63134 -208.124552) (xy 306.631848 -208.124552) (xy 308.104794 -208.124552)
			(xy 308.1101 -208.125028) (xy 308.117672 -208.132463) (xy 308.118256 -208.13776) (xy 308.118256 -208.632298)
			(xy 308.11824 -208.632552) (xy 415.718244 -208.632552) (xy 415.718244 -208.13776) (xy 415.718763 -208.132504)
			(xy 415.726196 -208.125066) (xy 415.731452 -208.124552) (xy 417.204652 -208.124552) (xy 417.209968 -208.124955)
			(xy 417.217509 -208.132446) (xy 417.21786 -208.13776) (xy 417.21786 -208.632298) (xy 423.262044 -208.632298)
			(xy 423.262044 -208.13776) (xy 423.262563 -208.132504) (xy 423.269996 -208.125066) (xy 423.275252 -208.124552)
			(xy 423.27576 -208.124552) (xy 423.791634 -208.124552) (xy 423.799442 -208.124218) (xy 423.814314 -208.119447)
			(xy 423.820844 -208.115154) (xy 423.841933 -208.100805) (xy 423.887594 -208.078074) (xy 423.9362 -208.062615)
			(xy 423.986603 -208.054792) (xy 424.037609 -208.054792) (xy 424.088012 -208.062615) (xy 424.136618 -208.078074)
			(xy 424.182279 -208.100805) (xy 424.203368 -208.115154) (xy 424.20991 -208.119427) (xy 424.224772 -208.124222)
			(xy 424.232578 -208.124552) (xy 424.748706 -208.124552) (xy 424.754014 -208.12502) (xy 424.761585 -208.132462)
			(xy 424.762168 -208.13776) (xy 424.762168 -208.632298) (xy 424.762143 -208.632552) (xy 430.806352 -208.632552)
			(xy 430.806352 -208.632044) (xy 430.806352 -208.13776) (xy 430.806864 -208.132502) (xy 430.814302 -208.125064)
			(xy 430.81956 -208.124552) (xy 431.335688 -208.124552) (xy 431.343498 -208.124241) (xy 431.35837 -208.119454)
			(xy 431.364898 -208.115154) (xy 431.385987 -208.100805) (xy 431.431648 -208.078074) (xy 431.480254 -208.062615)
			(xy 431.530657 -208.054792) (xy 431.581663 -208.054792) (xy 431.632066 -208.062615) (xy 431.680672 -208.078074)
			(xy 431.726333 -208.100805) (xy 431.747422 -208.115154) (xy 431.753952 -208.119448) (xy 431.768823 -208.12423)
			(xy 431.776632 -208.124552) (xy 432.29276 -208.124552) (xy 432.298008 -208.125117) (xy 432.305451 -208.132515)
			(xy 432.305968 -208.13776) (xy 432.305968 -208.632298) (xy 438.350152 -208.632298) (xy 438.350152 -208.13776)
			(xy 438.350664 -208.132502) (xy 438.358102 -208.125064) (xy 438.36336 -208.124552) (xy 438.363868 -208.124552)
			(xy 438.879742 -208.124552) (xy 438.887551 -208.124222) (xy 438.902423 -208.119448) (xy 438.908952 -208.115154)
			(xy 438.930041 -208.100805) (xy 438.975702 -208.078074) (xy 439.024308 -208.062615) (xy 439.074711 -208.054792)
			(xy 439.125717 -208.054792) (xy 439.17612 -208.062615) (xy 439.224726 -208.078074) (xy 439.270387 -208.100805)
			(xy 439.291476 -208.115154) (xy 439.298016 -208.11943) (xy 439.312879 -208.124223) (xy 439.320686 -208.124552)
			(xy 439.836814 -208.124552) (xy 439.842123 -208.125015) (xy 439.849693 -208.13246) (xy 439.850276 -208.13776)
			(xy 439.850276 -208.632298) (xy 439.850251 -208.632552) (xy 445.89446 -208.632552) (xy 445.89446 -208.632044)
			(xy 445.89446 -208.13776) (xy 445.894965 -208.1325) (xy 445.902408 -208.125062) (xy 445.907668 -208.124552)
			(xy 446.423796 -208.124552) (xy 446.431607 -208.124244) (xy 446.446478 -208.119455) (xy 446.453006 -208.115154)
			(xy 446.474095 -208.100805) (xy 446.519756 -208.078074) (xy 446.568362 -208.062615) (xy 446.618765 -208.054792)
			(xy 446.669771 -208.054792) (xy 446.720174 -208.062615) (xy 446.76878 -208.078074) (xy 446.814441 -208.100805)
			(xy 446.83553 -208.115154) (xy 446.842058 -208.119451) (xy 446.856931 -208.124231) (xy 446.86474 -208.124552)
			(xy 447.380868 -208.124552) (xy 447.386117 -208.125112) (xy 447.39356 -208.132513) (xy 447.394076 -208.13776)
			(xy 447.394076 -208.632298) (xy 447.394052 -208.632552) (xy 453.43826 -208.632552) (xy 453.43826 -208.632044)
			(xy 453.43826 -208.13776) (xy 453.438765 -208.1325) (xy 453.446208 -208.125062) (xy 453.451468 -208.124552)
			(xy 453.967596 -208.124552) (xy 453.975407 -208.124244) (xy 453.990278 -208.119455) (xy 453.996806 -208.115154)
			(xy 454.017895 -208.100805) (xy 454.063556 -208.078074) (xy 454.112162 -208.062615) (xy 454.162565 -208.054792)
			(xy 454.213571 -208.054792) (xy 454.263974 -208.062615) (xy 454.31258 -208.078074) (xy 454.358241 -208.100805)
			(xy 454.37933 -208.115154) (xy 454.385858 -208.119451) (xy 454.400731 -208.124231) (xy 454.40854 -208.124552)
			(xy 454.924668 -208.124552) (xy 454.929917 -208.125112) (xy 454.93736 -208.132513) (xy 454.937876 -208.13776)
			(xy 454.937876 -208.632298) (xy 454.937377 -208.637598) (xy 454.929957 -208.645168) (xy 454.924668 -208.64576)
			(xy 454.408794 -208.64576) (xy 454.400983 -208.646061) (xy 454.386111 -208.650855) (xy 454.379584 -208.655158)
			(xy 454.358465 -208.669511) (xy 454.31274 -208.692237) (xy 454.264066 -208.707666) (xy 454.213599 -208.715431)
			(xy 454.188068 -208.715864) (xy 454.162537 -208.715444) (xy 454.112073 -208.707663) (xy 454.0634 -208.692229)
			(xy 454.017673 -208.669508) (xy 453.996552 -208.655158) (xy 453.990027 -208.650855) (xy 453.975152 -208.646078)
			(xy 453.967342 -208.64576) (xy 453.451468 -208.64576) (xy 453.44612 -208.64549) (xy 453.438578 -208.637902)
			(xy 453.43826 -208.632552) (xy 447.394052 -208.632552) (xy 447.393577 -208.637598) (xy 447.386157 -208.645168)
			(xy 447.380868 -208.64576) (xy 446.864994 -208.64576) (xy 446.857183 -208.646061) (xy 446.842311 -208.650855)
			(xy 446.835784 -208.655158) (xy 446.814665 -208.669511) (xy 446.76894 -208.692237) (xy 446.720266 -208.707666)
			(xy 446.669799 -208.715431) (xy 446.644268 -208.715864) (xy 446.618737 -208.715444) (xy 446.568273 -208.707663)
			(xy 446.5196 -208.692229) (xy 446.473873 -208.669508) (xy 446.452752 -208.655158) (xy 446.446227 -208.650855)
			(xy 446.431352 -208.646078) (xy 446.423542 -208.64576) (xy 445.907668 -208.64576) (xy 445.90232 -208.64549)
			(xy 445.894778 -208.637902) (xy 445.89446 -208.632552) (xy 439.850251 -208.632552) (xy 439.84975 -208.637658)
			(xy 439.842174 -208.645243) (xy 439.836814 -208.64576) (xy 439.32094 -208.64576) (xy 439.31313 -208.646081)
			(xy 439.298259 -208.650861) (xy 439.29173 -208.655158) (xy 439.270626 -208.669534) (xy 439.224896 -208.692255)
			(xy 439.176217 -208.707677) (xy 439.125746 -208.715435) (xy 439.100214 -208.715864) (xy 439.074684 -208.715421)
			(xy 439.02422 -208.707647) (xy 438.975548 -208.69222) (xy 438.92982 -208.669505) (xy 438.908698 -208.655158)
			(xy 438.902163 -208.650873) (xy 438.887296 -208.646085) (xy 438.879488 -208.64576) (xy 438.363614 -208.64576)
			(xy 438.358181 -208.645411) (xy 438.350494 -208.637731) (xy 438.350152 -208.632298) (xy 432.305968 -208.632298)
			(xy 432.305476 -208.6376) (xy 432.298052 -208.645171) (xy 432.29276 -208.64576) (xy 431.776886 -208.64576)
			(xy 431.769074 -208.646057) (xy 431.754202 -208.650853) (xy 431.747676 -208.655158) (xy 431.726559 -208.669515)
			(xy 431.680834 -208.692239) (xy 431.632159 -208.707667) (xy 431.581691 -208.715432) (xy 431.55616 -208.715864)
			(xy 431.530629 -208.715448) (xy 431.480164 -208.707666) (xy 431.431492 -208.692231) (xy 431.385765 -208.669508)
			(xy 431.364644 -208.655158) (xy 431.358121 -208.650852) (xy 431.343245 -208.646077) (xy 431.335434 -208.64576)
			(xy 430.81956 -208.64576) (xy 430.81421 -208.645495) (xy 430.806669 -208.637903) (xy 430.806352 -208.632552)
			(xy 424.762143 -208.632552) (xy 424.761649 -208.63766) (xy 424.754068 -208.645246) (xy 424.748706 -208.64576)
			(xy 424.232832 -208.64576) (xy 424.225022 -208.646077) (xy 424.21015 -208.65086) (xy 424.203622 -208.655158)
			(xy 424.182492 -208.669495) (xy 424.136771 -208.692224) (xy 424.088101 -208.707658) (xy 424.037636 -208.715428)
			(xy 424.012106 -208.715864) (xy 423.986576 -208.715425) (xy 423.936112 -208.70765) (xy 423.88744 -208.692221)
			(xy 423.841712 -208.669505) (xy 423.82059 -208.655158) (xy 423.814057 -208.65087) (xy 423.799188 -208.646084)
			(xy 423.79138 -208.64576) (xy 423.275506 -208.64576) (xy 423.270072 -208.645417) (xy 423.262385 -208.637732)
			(xy 423.262044 -208.632298) (xy 417.21786 -208.632298) (xy 417.217375 -208.637602) (xy 417.209946 -208.645173)
			(xy 417.204652 -208.64576) (xy 415.731452 -208.64576) (xy 415.726172 -208.645332) (xy 415.718729 -208.637836)
			(xy 415.718244 -208.632552) (xy 308.11824 -208.632552) (xy 308.117919 -208.637734) (xy 308.11023 -208.64542)
			(xy 308.104794 -208.64576) (xy 306.631594 -208.64576) (xy 306.626229 -208.645254) (xy 306.618643 -208.637663)
			(xy 306.618132 -208.632298) (xy 300.573948 -208.632298) (xy 300.573474 -208.637605) (xy 300.566037 -208.645177)
			(xy 300.56074 -208.64576) (xy 300.044866 -208.64576) (xy 300.037057 -208.646092) (xy 300.022185 -208.650864)
			(xy 300.015656 -208.655158) (xy 299.994545 -208.669523) (xy 299.948817 -208.692246) (xy 299.900141 -208.707672)
			(xy 299.849672 -208.715433) (xy 299.82414 -208.715864) (xy 299.798611 -208.715407) (xy 299.748147 -208.707638)
			(xy 299.699475 -208.692214) (xy 299.653747 -208.669503) (xy 299.632624 -208.655158) (xy 299.626083 -208.650883)
			(xy 299.61122 -208.646089) (xy 299.603414 -208.64576) (xy 299.08754 -208.64576) (xy 299.082201 -208.645441)
			(xy 299.074655 -208.637891) (xy 299.074332 -208.632552) (xy 293.030133 -208.632552) (xy 293.029818 -208.637736)
			(xy 293.022124 -208.645423) (xy 293.016686 -208.64576) (xy 292.500812 -208.64576) (xy 292.493001 -208.646069)
			(xy 292.47813 -208.650857) (xy 292.471602 -208.655158) (xy 292.450478 -208.669503) (xy 292.404755 -208.692231)
			(xy 292.356082 -208.707662) (xy 292.305617 -208.71543) (xy 292.280086 -208.715864) (xy 292.254555 -208.715435)
			(xy 292.204091 -208.707657) (xy 292.155419 -208.692225) (xy 292.109692 -208.669507) (xy 292.08857 -208.655158)
			(xy 292.082041 -208.650862) (xy 292.067169 -208.646081) (xy 292.05936 -208.64576) (xy 291.543486 -208.64576)
			(xy 291.53812 -208.645259) (xy 291.530535 -208.637665) (xy 291.530024 -208.632298) (xy 285.48584 -208.632298)
			(xy 285.485373 -208.637607) (xy 285.477931 -208.645179) (xy 285.472632 -208.64576) (xy 284.956758 -208.64576)
			(xy 284.948949 -208.646088) (xy 284.934077 -208.650863) (xy 284.927548 -208.655158) (xy 284.906439 -208.669527)
			(xy 284.860711 -208.692249) (xy 284.812033 -208.707673) (xy 284.761564 -208.715434) (xy 284.736032 -208.715864)
			(xy 284.710502 -208.715411) (xy 284.660039 -208.70764) (xy 284.611367 -208.692216) (xy 284.565638 -208.669504)
			(xy 284.544516 -208.655158) (xy 284.537977 -208.65088) (xy 284.523113 -208.646088) (xy 284.515306 -208.64576)
			(xy 283.999432 -208.64576) (xy 283.994092 -208.645447) (xy 283.986547 -208.637892) (xy 283.986224 -208.632552)
			(xy 277.942018 -208.632552) (xy 277.941573 -208.637607) (xy 277.934131 -208.645179) (xy 277.928832 -208.64576)
			(xy 277.412958 -208.64576) (xy 277.405149 -208.646088) (xy 277.390277 -208.650863) (xy 277.383748 -208.655158)
			(xy 277.362639 -208.669527) (xy 277.316911 -208.692249) (xy 277.268233 -208.707673) (xy 277.217764 -208.715434)
			(xy 277.192232 -208.715864) (xy 277.166702 -208.715411) (xy 277.116239 -208.70764) (xy 277.067567 -208.692216)
			(xy 277.021838 -208.669504) (xy 277.000716 -208.655158) (xy 276.994177 -208.65088) (xy 276.979313 -208.646088)
			(xy 276.971506 -208.64576) (xy 276.455632 -208.64576) (xy 276.450292 -208.645447) (xy 276.442747 -208.637892)
			(xy 276.442424 -208.632552) (xy 270.398225 -208.632552) (xy 270.397917 -208.637738) (xy 270.390218 -208.645425)
			(xy 270.384778 -208.64576) (xy 269.868904 -208.64576) (xy 269.861093 -208.646065) (xy 269.846221 -208.650856)
			(xy 269.839694 -208.655158) (xy 269.818572 -208.669507) (xy 269.772848 -208.692233) (xy 269.724175 -208.707664)
			(xy 269.673709 -208.715431) (xy 269.648178 -208.715864) (xy 269.622647 -208.715439) (xy 269.572183 -208.707659)
			(xy 269.523511 -208.692227) (xy 269.477784 -208.669507) (xy 269.456662 -208.655158) (xy 269.450135 -208.650859)
			(xy 269.435262 -208.64608) (xy 269.427452 -208.64576) (xy 268.911578 -208.64576) (xy 268.906211 -208.645264)
			(xy 268.898626 -208.637666) (xy 268.898116 -208.632298) (xy 206.997808 -208.632298) (xy 206.997808 -208.632552)
			(xy 206.997441 -208.637878) (xy 206.989924 -208.645421) (xy 206.9846 -208.64576) (xy 206.468726 -208.64576)
			(xy 206.460849 -208.646022) (xy 206.445845 -208.650823) (xy 206.439262 -208.655158) (xy 206.418186 -208.669552)
			(xy 206.372541 -208.69238) (xy 206.323934 -208.707937) (xy 206.273517 -208.715855) (xy 206.248 -208.716372)
			(xy 206.222479 -208.715905) (xy 206.172051 -208.708004) (xy 206.123439 -208.692438) (xy 206.077802 -208.669576)
			(xy 206.056738 -208.655158) (xy 206.050136 -208.65086) (xy 206.035144 -208.646062) (xy 206.027274 -208.64576)
			(xy 205.5114 -208.64576) (xy 205.506056 -208.645469) (xy 205.498512 -208.637897) (xy 205.498192 -208.632552)
			(xy 199.454008 -208.632552) (xy 199.453641 -208.637878) (xy 199.446124 -208.645421) (xy 199.4408 -208.64576)
			(xy 198.924926 -208.64576) (xy 198.917049 -208.646022) (xy 198.902045 -208.650823) (xy 198.895462 -208.655158)
			(xy 198.874386 -208.669552) (xy 198.828741 -208.69238) (xy 198.780134 -208.707937) (xy 198.729717 -208.715855)
			(xy 198.7042 -208.716372) (xy 198.678679 -208.715905) (xy 198.628251 -208.708004) (xy 198.579639 -208.692438)
			(xy 198.534002 -208.669576) (xy 198.512938 -208.655158) (xy 198.506336 -208.65086) (xy 198.491344 -208.646062)
			(xy 198.483474 -208.64576) (xy 197.9676 -208.64576) (xy 197.962256 -208.645469) (xy 197.954712 -208.637897)
			(xy 197.954392 -208.632552) (xy 191.910208 -208.632552) (xy 191.909841 -208.637878) (xy 191.902324 -208.645421)
			(xy 191.897 -208.64576) (xy 191.896492 -208.64576) (xy 191.380872 -208.64576) (xy 191.372997 -208.646042)
			(xy 191.357993 -208.650829) (xy 191.351408 -208.655158) (xy 191.330347 -208.669575) (xy 191.284696 -208.692398)
			(xy 191.236085 -208.707948) (xy 191.185664 -208.715859) (xy 191.160146 -208.716372) (xy 191.134626 -208.715881)
			(xy 191.084199 -208.707988) (xy 191.035587 -208.692428) (xy 190.989949 -208.669573) (xy 190.968884 -208.655158)
			(xy 190.962294 -208.65084) (xy 190.947293 -208.646054) (xy 190.93942 -208.64576) (xy 190.423546 -208.64576)
			(xy 190.418247 -208.645246) (xy 190.410673 -208.637839) (xy 190.410084 -208.632552) (xy 184.3659 -208.632552)
			(xy 184.36554 -208.63788) (xy 184.358019 -208.645424) (xy 184.352692 -208.64576) (xy 183.836818 -208.64576)
			(xy 183.828945 -208.646061) (xy 183.81394 -208.650835) (xy 183.807354 -208.655158) (xy 183.786281 -208.669556)
			(xy 183.740634 -208.692382) (xy 183.692027 -208.707938) (xy 183.641609 -208.715856) (xy 183.616092 -208.716372)
			(xy 183.590573 -208.715858) (xy 183.540147 -208.707972) (xy 183.491535 -208.692419) (xy 183.445896 -208.66957)
			(xy 183.42483 -208.655158) (xy 183.41823 -208.650857) (xy 183.403237 -208.646061) (xy 183.395366 -208.64576)
			(xy 182.879492 -208.64576) (xy 182.874147 -208.645474) (xy 182.866603 -208.637899) (xy 182.866284 -208.632552)
			(xy 176.8221 -208.632552) (xy 176.82174 -208.63788) (xy 176.814219 -208.645424) (xy 176.808892 -208.64576)
			(xy 176.808384 -208.64576) (xy 176.292764 -208.64576) (xy 176.284889 -208.646038) (xy 176.269885 -208.650828)
			(xy 176.2633 -208.655158) (xy 176.242214 -208.669536) (xy 176.196572 -208.692367) (xy 176.147969 -208.707929)
			(xy 176.097554 -208.715852) (xy 176.072038 -208.716372) (xy 176.046518 -208.715885) (xy 175.99609 -208.707991)
			(xy 175.947479 -208.69243) (xy 175.901841 -208.669574) (xy 175.880776 -208.655158) (xy 175.874188 -208.650836)
			(xy 175.859185 -208.646053) (xy 175.851312 -208.64576) (xy 175.335438 -208.64576) (xy 175.330138 -208.645251)
			(xy 175.322565 -208.63784) (xy 175.321976 -208.632552) (xy 169.277792 -208.632552) (xy 169.277439 -208.637882)
			(xy 169.269913 -208.645426) (xy 169.264584 -208.64576) (xy 167.791384 -208.64576) (xy 167.786038 -208.645479)
			(xy 167.778495 -208.6379) (xy 167.778176 -208.632552) (xy 94.869508 -208.632552) (xy 94.869508 -209.023458)
			(xy 94.869022 -209.050727) (xy 94.86126 -209.104711) (xy 94.845895 -209.157041) (xy 94.823238 -209.206651)
			(xy 94.793752 -209.252532) (xy 94.758037 -209.293749) (xy 94.71682 -209.329464) (xy 94.670939 -209.35895)
			(xy 94.621329 -209.381607) (xy 94.568999 -209.396972) (xy 94.515015 -209.404734) (xy 94.460477 -209.404734)
			(xy 94.406493 -209.396972) (xy 94.354163 -209.381607) (xy 94.304553 -209.35895) (xy 94.258672 -209.329464)
			(xy 94.217455 -209.293749) (xy 94.18174 -209.252532) (xy 94.152254 -209.206651) (xy 94.129597 -209.157041)
			(xy 94.114232 -209.104711) (xy 94.10647 -209.050727) (xy 94.105984 -209.023458) (xy 56.07812 -209.023458)
			(xy 56.07812 -209.482436) (xy 163.678108 -209.482436) (xy 163.678108 -208.987898) (xy 163.678618 -208.982601)
			(xy 163.68603 -208.975032) (xy 163.691316 -208.974436) (xy 165.164516 -208.974436) (xy 165.169861 -208.97472)
			(xy 165.177404 -208.982297) (xy 165.177724 -208.987644) (xy 165.177724 -208.988152) (xy 165.177724 -209.482436)
			(xy 171.221908 -209.482436) (xy 171.221908 -208.987898) (xy 171.222446 -208.982541) (xy 171.230014 -208.974957)
			(xy 171.23537 -208.974436) (xy 171.751498 -208.974436) (xy 171.759309 -208.974132) (xy 171.774181 -208.96934)
			(xy 171.780708 -208.965038) (xy 171.801797 -208.950689) (xy 171.847458 -208.927958) (xy 171.896064 -208.912499)
			(xy 171.946467 -208.904676) (xy 171.997473 -208.904676) (xy 172.047876 -208.912499) (xy 172.096482 -208.927958)
			(xy 172.142143 -208.950689) (xy 172.163232 -208.965038) (xy 172.169761 -208.969334) (xy 172.184633 -208.974115)
			(xy 172.192442 -208.974436) (xy 172.70857 -208.974436) (xy 172.714 -208.974799) (xy 172.721688 -208.982469)
			(xy 172.722032 -208.987898) (xy 172.722032 -209.482436) (xy 178.766216 -209.482436) (xy 178.766216 -208.987898)
			(xy 178.766719 -208.982599) (xy 178.774136 -208.97503) (xy 178.779424 -208.974436) (xy 179.295552 -208.974436)
			(xy 179.303361 -208.974113) (xy 179.318233 -208.969334) (xy 179.324762 -208.965038) (xy 179.345851 -208.950689)
			(xy 179.391512 -208.927958) (xy 179.440118 -208.912499) (xy 179.490521 -208.904676) (xy 179.541527 -208.904676)
			(xy 179.59193 -208.912499) (xy 179.640536 -208.927958) (xy 179.686197 -208.950689) (xy 179.707286 -208.965038)
			(xy 179.713825 -208.969317) (xy 179.728689 -208.974109) (xy 179.736496 -208.974436) (xy 180.252624 -208.974436)
			(xy 180.25797 -208.974715) (xy 180.265512 -208.982296) (xy 180.265832 -208.987644) (xy 180.265832 -208.988152)
			(xy 180.265832 -209.482436) (xy 186.310016 -209.482436) (xy 186.310016 -208.987898) (xy 186.310547 -208.982539)
			(xy 186.31812 -208.974955) (xy 186.323478 -208.974436) (xy 186.839606 -208.974436) (xy 186.847417 -208.974135)
			(xy 186.862289 -208.969341) (xy 186.868816 -208.965038) (xy 186.889905 -208.950689) (xy 186.935566 -208.927958)
			(xy 186.984172 -208.912499) (xy 187.034575 -208.904676) (xy 187.085581 -208.904676) (xy 187.135984 -208.912499)
			(xy 187.18459 -208.927958) (xy 187.230251 -208.950689) (xy 187.25134 -208.965038) (xy 187.257867 -208.969337)
			(xy 187.27274 -208.974116) (xy 187.28055 -208.974436) (xy 187.796678 -208.974436) (xy 187.802109 -208.974794)
			(xy 187.809796 -208.982467) (xy 187.81014 -208.987898) (xy 187.81014 -209.482436) (xy 193.854324 -209.482436)
			(xy 193.854324 -208.987898) (xy 193.85482 -208.982597) (xy 193.862242 -208.975027) (xy 193.867532 -208.974436)
			(xy 194.38366 -208.974436) (xy 194.39147 -208.974116) (xy 194.406342 -208.969335) (xy 194.41287 -208.965038)
			(xy 194.433959 -208.950689) (xy 194.47962 -208.927958) (xy 194.528226 -208.912499) (xy 194.578629 -208.904676)
			(xy 194.629635 -208.904676) (xy 194.680038 -208.912499) (xy 194.728644 -208.927958) (xy 194.774305 -208.950689)
			(xy 194.795394 -208.965038) (xy 194.801931 -208.96932) (xy 194.816797 -208.97411) (xy 194.824604 -208.974436)
			(xy 195.340732 -208.974436) (xy 195.346079 -208.97471) (xy 195.353621 -208.982295) (xy 195.35394 -208.987644)
			(xy 195.35394 -208.988152) (xy 195.35394 -209.482436) (xy 201.398124 -209.482436) (xy 201.398124 -208.987898)
			(xy 201.39862 -208.982597) (xy 201.406042 -208.975027) (xy 201.411332 -208.974436) (xy 201.92746 -208.974436)
			(xy 201.93527 -208.974116) (xy 201.950142 -208.969335) (xy 201.95667 -208.965038) (xy 201.977759 -208.950689)
			(xy 202.02342 -208.927958) (xy 202.072026 -208.912499) (xy 202.122429 -208.904676) (xy 202.173435 -208.904676)
			(xy 202.223838 -208.912499) (xy 202.272444 -208.927958) (xy 202.318105 -208.950689) (xy 202.339194 -208.965038)
			(xy 202.345731 -208.96932) (xy 202.360597 -208.97411) (xy 202.368404 -208.974436) (xy 202.884532 -208.974436)
			(xy 202.889879 -208.97471) (xy 202.897421 -208.982295) (xy 202.89774 -208.987644) (xy 202.89774 -208.988152)
			(xy 202.89774 -209.482182) (xy 264.798048 -209.482182) (xy 264.798048 -208.987644) (xy 264.798619 -208.982397)
			(xy 264.806012 -208.974954) (xy 264.811256 -208.974436) (xy 264.811764 -208.974436) (xy 265.327638 -208.974436)
			(xy 265.335447 -208.974107) (xy 265.350319 -208.969333) (xy 265.356848 -208.965038) (xy 265.377937 -208.950689)
			(xy 265.423598 -208.927958) (xy 265.472204 -208.912499) (xy 265.522607 -208.904676) (xy 265.573613 -208.904676)
			(xy 265.624016 -208.912499) (xy 265.672622 -208.927958) (xy 265.718283 -208.950689) (xy 265.739372 -208.965038)
			(xy 265.745914 -208.969311) (xy 265.760776 -208.974107) (xy 265.768582 -208.974436) (xy 266.28471 -208.974436)
			(xy 266.290014 -208.974916) (xy 266.297585 -208.982349) (xy 266.298172 -208.987644) (xy 266.298172 -209.482182)
			(xy 266.298155 -209.482436) (xy 272.342356 -209.482436) (xy 272.342356 -209.481928) (xy 272.342356 -208.987644)
			(xy 272.342753 -208.982326) (xy 272.350249 -208.974785) (xy 272.355564 -208.974436) (xy 272.871692 -208.974436)
			(xy 272.879503 -208.97413) (xy 272.894375 -208.96934) (xy 272.900902 -208.965038) (xy 272.921991 -208.950689)
			(xy 272.967652 -208.927958) (xy 273.016258 -208.912499) (xy 273.066661 -208.904676) (xy 273.117667 -208.904676)
			(xy 273.16807 -208.912499) (xy 273.216676 -208.927958) (xy 273.262337 -208.950689) (xy 273.283426 -208.965038)
			(xy 273.289956 -208.969332) (xy 273.304827 -208.974114) (xy 273.312636 -208.974436) (xy 273.828764 -208.974436)
			(xy 273.834102 -208.974755) (xy 273.841648 -208.982306) (xy 273.841972 -208.987644) (xy 273.841972 -209.482182)
			(xy 273.841948 -209.482436) (xy 279.886156 -209.482436) (xy 279.886156 -209.481928) (xy 279.886156 -208.987644)
			(xy 279.886553 -208.982326) (xy 279.894049 -208.974785) (xy 279.899364 -208.974436) (xy 280.415492 -208.974436)
			(xy 280.423303 -208.97413) (xy 280.438175 -208.96934) (xy 280.444702 -208.965038) (xy 280.465791 -208.950689)
			(xy 280.511452 -208.927958) (xy 280.560058 -208.912499) (xy 280.610461 -208.904676) (xy 280.661467 -208.904676)
			(xy 280.71187 -208.912499) (xy 280.760476 -208.927958) (xy 280.806137 -208.950689) (xy 280.827226 -208.965038)
			(xy 280.833756 -208.969332) (xy 280.848627 -208.974114) (xy 280.856436 -208.974436) (xy 281.372564 -208.974436)
			(xy 281.377902 -208.974755) (xy 281.385448 -208.982306) (xy 281.385772 -208.987644) (xy 281.385772 -209.482182)
			(xy 287.429956 -209.482182) (xy 287.429956 -208.987644) (xy 287.430353 -208.982326) (xy 287.437849 -208.974785)
			(xy 287.443164 -208.974436) (xy 287.443672 -208.974436) (xy 287.959546 -208.974436) (xy 287.967355 -208.97411)
			(xy 287.982227 -208.969334) (xy 287.988756 -208.965038) (xy 288.009845 -208.950689) (xy 288.055506 -208.927958)
			(xy 288.104112 -208.912499) (xy 288.154515 -208.904676) (xy 288.205521 -208.904676) (xy 288.255924 -208.912499)
			(xy 288.30453 -208.927958) (xy 288.350191 -208.950689) (xy 288.37128 -208.965038) (xy 288.37782 -208.969314)
			(xy 288.392683 -208.974108) (xy 288.40049 -208.974436) (xy 288.916618 -208.974436) (xy 288.921923 -208.974911)
			(xy 288.929493 -208.982348) (xy 288.93008 -208.987644) (xy 288.93008 -209.482182) (xy 288.930054 -209.482436)
			(xy 294.974264 -209.482436) (xy 294.974264 -209.481928) (xy 294.974264 -208.987644) (xy 294.974654 -208.982324)
			(xy 294.982154 -208.974783) (xy 294.987472 -208.974436) (xy 295.5036 -208.974436) (xy 295.511411 -208.974133)
			(xy 295.526283 -208.969341) (xy 295.53281 -208.965038) (xy 295.553899 -208.950689) (xy 295.59956 -208.927958)
			(xy 295.648166 -208.912499) (xy 295.698569 -208.904676) (xy 295.749575 -208.904676) (xy 295.799978 -208.912499)
			(xy 295.848584 -208.927958) (xy 295.894245 -208.950689) (xy 295.915334 -208.965038) (xy 295.921862 -208.969335)
			(xy 295.936735 -208.974116) (xy 295.944544 -208.974436) (xy 296.460672 -208.974436) (xy 296.466011 -208.97475)
			(xy 296.473557 -208.982304) (xy 296.47388 -208.987644) (xy 296.47388 -209.482182) (xy 302.518064 -209.482182)
			(xy 302.518064 -208.987644) (xy 302.518454 -208.982324) (xy 302.525954 -208.974783) (xy 302.531272 -208.974436)
			(xy 304.004726 -208.974436) (xy 304.010032 -208.974906) (xy 304.017602 -208.982347) (xy 304.018188 -208.987644)
			(xy 304.018188 -209.482182) (xy 304.018162 -209.482436) (xy 411.618176 -209.482436) (xy 411.618176 -209.481928)
			(xy 411.618176 -208.987644) (xy 411.618555 -208.982321) (xy 411.626063 -208.974779) (xy 411.631384 -208.974436)
			(xy 413.104584 -208.974436) (xy 413.109925 -208.974742) (xy 413.117469 -208.982302) (xy 413.117792 -208.987644)
			(xy 413.117792 -209.482182) (xy 419.161976 -209.482182) (xy 419.161976 -208.987644) (xy 419.162355 -208.982321)
			(xy 419.169863 -208.974779) (xy 419.175184 -208.974436) (xy 419.175692 -208.974436) (xy 419.691566 -208.974436)
			(xy 419.699376 -208.974119) (xy 419.714248 -208.969336) (xy 419.720776 -208.965038) (xy 419.741865 -208.950689)
			(xy 419.787526 -208.927958) (xy 419.836132 -208.912499) (xy 419.886535 -208.904676) (xy 419.937541 -208.904676)
			(xy 419.987944 -208.912499) (xy 420.03655 -208.927958) (xy 420.082211 -208.950689) (xy 420.1033 -208.965038)
			(xy 420.109836 -208.969322) (xy 420.124702 -208.974111) (xy 420.13251 -208.974436) (xy 420.648638 -208.974436)
			(xy 420.653946 -208.974898) (xy 420.661514 -208.982345) (xy 420.6621 -208.987644) (xy 420.6621 -209.482182)
			(xy 420.662074 -209.482436) (xy 426.706284 -209.482436) (xy 426.706284 -209.481928) (xy 426.706284 -208.987644)
			(xy 426.706656 -208.982319) (xy 426.714169 -208.974776) (xy 426.719492 -208.974436) (xy 427.23562 -208.974436)
			(xy 427.243432 -208.974142) (xy 427.258304 -208.969344) (xy 427.26483 -208.965038) (xy 427.285919 -208.950689)
			(xy 427.33158 -208.927958) (xy 427.380186 -208.912499) (xy 427.430589 -208.904676) (xy 427.481595 -208.904676)
			(xy 427.531998 -208.912499) (xy 427.580604 -208.927958) (xy 427.626265 -208.950689) (xy 427.647354 -208.965038)
			(xy 427.653878 -208.969343) (xy 427.668754 -208.974119) (xy 427.676564 -208.974436) (xy 428.192692 -208.974436)
			(xy 428.198034 -208.974736) (xy 428.205578 -208.982301) (xy 428.2059 -208.987644) (xy 428.2059 -209.482182)
			(xy 434.250084 -209.482182) (xy 434.250084 -208.987644) (xy 434.250456 -208.982319) (xy 434.257969 -208.974776)
			(xy 434.263292 -208.974436) (xy 434.2638 -208.974436) (xy 434.779674 -208.974436) (xy 434.787484 -208.974122)
			(xy 434.802356 -208.969337) (xy 434.808884 -208.965038) (xy 434.829973 -208.950689) (xy 434.875634 -208.927958)
			(xy 434.92424 -208.912499) (xy 434.974643 -208.904676) (xy 435.025649 -208.904676) (xy 435.076052 -208.912499)
			(xy 435.124658 -208.927958) (xy 435.170319 -208.950689) (xy 435.191408 -208.965038) (xy 435.197942 -208.969325)
			(xy 435.21281 -208.974112) (xy 435.220618 -208.974436) (xy 435.736746 -208.974436) (xy 435.742043 -208.974959)
			(xy 435.749617 -208.98236) (xy 435.750208 -208.987644) (xy 435.750208 -209.482182) (xy 435.750181 -209.482436)
			(xy 441.794392 -209.482436) (xy 441.794392 -209.481928) (xy 441.794392 -208.987644) (xy 441.794756 -208.982318)
			(xy 441.802275 -208.974774) (xy 441.8076 -208.974436) (xy 442.323728 -208.974436) (xy 442.33154 -208.974145)
			(xy 442.346412 -208.969345) (xy 442.352938 -208.965038) (xy 442.374027 -208.950689) (xy 442.419688 -208.927958)
			(xy 442.468294 -208.912499) (xy 442.518697 -208.904676) (xy 442.569703 -208.904676) (xy 442.620106 -208.912499)
			(xy 442.668712 -208.927958) (xy 442.714373 -208.950689) (xy 442.735462 -208.965038) (xy 442.742006 -208.969307)
			(xy 442.756866 -208.974105) (xy 442.764672 -208.974436) (xy 443.2808 -208.974436) (xy 443.286143 -208.974731)
			(xy 443.293687 -208.9823) (xy 443.294008 -208.987644) (xy 443.294008 -209.482182) (xy 443.293982 -209.482436)
			(xy 449.338192 -209.482436) (xy 449.338192 -209.481928) (xy 449.338192 -208.987644) (xy 449.338556 -208.982318)
			(xy 449.346075 -208.974774) (xy 449.3514 -208.974436) (xy 449.867528 -208.974436) (xy 449.87534 -208.974145)
			(xy 449.890212 -208.969345) (xy 449.896738 -208.965038) (xy 449.917827 -208.950689) (xy 449.963488 -208.927958)
			(xy 450.012094 -208.912499) (xy 450.062497 -208.904676) (xy 450.113503 -208.904676) (xy 450.163906 -208.912499)
			(xy 450.212512 -208.927958) (xy 450.258173 -208.950689) (xy 450.279262 -208.965038) (xy 450.285806 -208.969307)
			(xy 450.300666 -208.974105) (xy 450.308472 -208.974436) (xy 450.8246 -208.974436) (xy 450.829943 -208.974731)
			(xy 450.837487 -208.9823) (xy 450.837808 -208.987644) (xy 450.837808 -209.482182) (xy 450.837271 -209.487473)
			(xy 450.829878 -209.495042) (xy 450.8246 -209.495644) (xy 450.308726 -209.495644) (xy 450.300916 -209.495962)
			(xy 450.286044 -209.500744) (xy 450.279516 -209.505042) (xy 450.258387 -209.519379) (xy 450.212666 -209.542109)
			(xy 450.163995 -209.557542) (xy 450.11353 -209.565313) (xy 450.088 -209.565748) (xy 450.06247 -209.565314)
			(xy 450.012006 -209.557538) (xy 449.963333 -209.542108) (xy 449.917606 -209.51939) (xy 449.896484 -209.505042)
			(xy 449.889953 -209.50075) (xy 449.875083 -209.495967) (xy 449.867274 -209.495644) (xy 449.3514 -209.495644)
			(xy 449.346146 -209.495109) (xy 449.338706 -209.487689) (xy 449.338192 -209.482436) (xy 443.293982 -209.482436)
			(xy 443.293471 -209.487473) (xy 443.286078 -209.495042) (xy 443.2808 -209.495644) (xy 442.764926 -209.495644)
			(xy 442.757116 -209.495962) (xy 442.742244 -209.500744) (xy 442.735716 -209.505042) (xy 442.714587 -209.519379)
			(xy 442.668866 -209.542109) (xy 442.620195 -209.557542) (xy 442.56973 -209.565313) (xy 442.5442 -209.565748)
			(xy 442.51867 -209.565314) (xy 442.468206 -209.557538) (xy 442.419533 -209.542108) (xy 442.373806 -209.51939)
			(xy 442.352684 -209.505042) (xy 442.346153 -209.50075) (xy 442.331283 -209.495967) (xy 442.323474 -209.495644)
			(xy 441.8076 -209.495644) (xy 441.802346 -209.495109) (xy 441.794906 -209.487689) (xy 441.794392 -209.482436)
			(xy 435.750181 -209.482436) (xy 435.749642 -209.487533) (xy 435.742094 -209.495117) (xy 435.736746 -209.495644)
			(xy 435.220872 -209.495644) (xy 435.21306 -209.495938) (xy 435.198188 -209.500737) (xy 435.191662 -209.505042)
			(xy 435.170548 -209.519403) (xy 435.124821 -209.542127) (xy 435.076146 -209.557554) (xy 435.025678 -209.565317)
			(xy 435.000146 -209.565748) (xy 434.974616 -209.565291) (xy 434.924153 -209.557522) (xy 434.875481 -209.542099)
			(xy 434.829752 -209.519387) (xy 434.80863 -209.505042) (xy 434.802089 -209.500768) (xy 434.787226 -209.495974)
			(xy 434.77942 -209.495644) (xy 434.263546 -209.495644) (xy 434.258113 -209.495288) (xy 434.250423 -209.487614)
			(xy 434.250084 -209.482182) (xy 428.2059 -209.482182) (xy 428.20537 -209.487475) (xy 428.197972 -209.495045)
			(xy 428.192692 -209.495644) (xy 427.676818 -209.495644) (xy 427.669008 -209.495958) (xy 427.654136 -209.500743)
			(xy 427.647608 -209.505042) (xy 427.626481 -209.519383) (xy 427.580759 -209.542112) (xy 427.532088 -209.557544)
			(xy 427.481623 -209.565313) (xy 427.456092 -209.565748) (xy 427.430561 -209.565318) (xy 427.380097 -209.557541)
			(xy 427.331425 -209.54211) (xy 427.285698 -209.519391) (xy 427.264576 -209.505042) (xy 427.258047 -209.500747)
			(xy 427.243175 -209.495966) (xy 427.235366 -209.495644) (xy 426.719492 -209.495644) (xy 426.714237 -209.495114)
			(xy 426.706797 -209.48769) (xy 426.706284 -209.482436) (xy 420.662074 -209.482436) (xy 420.661542 -209.487535)
			(xy 420.653989 -209.495119) (xy 420.648638 -209.495644) (xy 420.132764 -209.495644) (xy 420.124956 -209.495978)
			(xy 420.110084 -209.500749) (xy 420.103554 -209.505042) (xy 420.082442 -209.519406) (xy 420.036715 -209.54213)
			(xy 419.988039 -209.557556) (xy 419.93757 -209.565318) (xy 419.912038 -209.565748) (xy 419.886508 -209.565295)
			(xy 419.836045 -209.557525) (xy 419.787372 -209.5421) (xy 419.741644 -209.519388) (xy 419.720522 -209.505042)
			(xy 419.713982 -209.500765) (xy 419.699119 -209.495972) (xy 419.691312 -209.495644) (xy 419.175438 -209.495644)
			(xy 419.170004 -209.495294) (xy 419.162314 -209.487616) (xy 419.161976 -209.482182) (xy 413.117792 -209.482182)
			(xy 413.117269 -209.487477) (xy 413.109866 -209.495047) (xy 413.104584 -209.495644) (xy 411.631384 -209.495644)
			(xy 411.626128 -209.49512) (xy 411.618688 -209.487691) (xy 411.618176 -209.482436) (xy 304.018162 -209.482436)
			(xy 304.01764 -209.487538) (xy 304.01008 -209.495123) (xy 304.004726 -209.495644) (xy 302.531526 -209.495644)
			(xy 302.52609 -209.495302) (xy 302.518402 -209.487618) (xy 302.518064 -209.482182) (xy 296.47388 -209.482182)
			(xy 296.473367 -209.487479) (xy 296.465958 -209.49505) (xy 296.460672 -209.495644) (xy 295.944798 -209.495644)
			(xy 295.936987 -209.495949) (xy 295.922115 -209.50074) (xy 295.915588 -209.505042) (xy 295.894466 -209.519391)
			(xy 295.848743 -209.542118) (xy 295.800069 -209.557548) (xy 295.749603 -209.565315) (xy 295.724072 -209.565748)
			(xy 295.698541 -209.565328) (xy 295.648076 -209.557548) (xy 295.599404 -209.542114) (xy 295.553677 -209.519392)
			(xy 295.532556 -209.505042) (xy 295.526031 -209.500739) (xy 295.511156 -209.495963) (xy 295.503346 -209.495644)
			(xy 294.987472 -209.495644) (xy 294.982215 -209.495128) (xy 294.974775 -209.487693) (xy 294.974264 -209.482436)
			(xy 288.930054 -209.482436) (xy 288.92954 -209.48754) (xy 288.921974 -209.495125) (xy 288.916618 -209.495644)
			(xy 288.400744 -209.495644) (xy 288.392935 -209.495969) (xy 288.378063 -209.500747) (xy 288.371534 -209.505042)
			(xy 288.350428 -209.519415) (xy 288.304698 -209.542136) (xy 288.25602 -209.55756) (xy 288.20555 -209.565319)
			(xy 288.180018 -209.565748) (xy 288.154488 -209.565305) (xy 288.104024 -209.557532) (xy 288.055352 -209.542105)
			(xy 288.009624 -209.519389) (xy 287.988502 -209.505042) (xy 287.981967 -209.500757) (xy 287.9671 -209.495969)
			(xy 287.959292 -209.495644) (xy 287.443418 -209.495644) (xy 287.437981 -209.495307) (xy 287.430293 -209.487619)
			(xy 287.429956 -209.482182) (xy 281.385772 -209.482182) (xy 281.385266 -209.487481) (xy 281.377852 -209.495053)
			(xy 281.372564 -209.495644) (xy 280.85669 -209.495644) (xy 280.848879 -209.495946) (xy 280.834007 -209.500739)
			(xy 280.82748 -209.505042) (xy 280.806361 -209.519395) (xy 280.760636 -209.542121) (xy 280.711962 -209.55755)
			(xy 280.661495 -209.565316) (xy 280.635964 -209.565748) (xy 280.610433 -209.565332) (xy 280.559968 -209.557551)
			(xy 280.511296 -209.542115) (xy 280.465569 -209.519393) (xy 280.444448 -209.505042) (xy 280.437925 -209.500736)
			(xy 280.423048 -209.495962) (xy 280.415238 -209.495644) (xy 279.899364 -209.495644) (xy 279.894106 -209.495133)
			(xy 279.886667 -209.487694) (xy 279.886156 -209.482436) (xy 273.841948 -209.482436) (xy 273.841466 -209.487481)
			(xy 273.834052 -209.495053) (xy 273.828764 -209.495644) (xy 273.31289 -209.495644) (xy 273.305079 -209.495946)
			(xy 273.290207 -209.500739) (xy 273.28368 -209.505042) (xy 273.262561 -209.519395) (xy 273.216836 -209.542121)
			(xy 273.168162 -209.55755) (xy 273.117695 -209.565316) (xy 273.092164 -209.565748) (xy 273.066633 -209.565332)
			(xy 273.016168 -209.557551) (xy 272.967496 -209.542115) (xy 272.921769 -209.519393) (xy 272.900648 -209.505042)
			(xy 272.894125 -209.500736) (xy 272.879248 -209.495962) (xy 272.871438 -209.495644) (xy 272.355564 -209.495644)
			(xy 272.350306 -209.495133) (xy 272.342867 -209.487694) (xy 272.342356 -209.482436) (xy 266.298155 -209.482436)
			(xy 266.29781 -209.487612) (xy 266.290139 -209.495299) (xy 266.28471 -209.495644) (xy 265.768836 -209.495644)
			(xy 265.761027 -209.495966) (xy 265.746155 -209.500746) (xy 265.739626 -209.505042) (xy 265.718494 -209.519375)
			(xy 265.672774 -209.542106) (xy 265.624104 -209.55754) (xy 265.57364 -209.565312) (xy 265.54811 -209.565748)
			(xy 265.52258 -209.565309) (xy 265.472116 -209.557535) (xy 265.423443 -209.542106) (xy 265.377716 -209.51939)
			(xy 265.356594 -209.505042) (xy 265.350061 -209.500754) (xy 265.335192 -209.495968) (xy 265.327384 -209.495644)
			(xy 264.81151 -209.495644) (xy 264.806072 -209.495312) (xy 264.798384 -209.48762) (xy 264.798048 -209.482182)
			(xy 202.89774 -209.482182) (xy 202.89774 -209.482436) (xy 202.897232 -209.487695) (xy 202.889791 -209.495134)
			(xy 202.884532 -209.495644) (xy 202.368658 -209.495644) (xy 202.360783 -209.495922) (xy 202.345779 -209.500712)
			(xy 202.339194 -209.505042) (xy 202.318108 -209.51942) (xy 202.272466 -209.542252) (xy 202.223863 -209.557813)
			(xy 202.173448 -209.565737) (xy 202.147932 -209.566256) (xy 202.122411 -209.565775) (xy 202.071984 -209.557879)
			(xy 202.023372 -209.542317) (xy 201.977734 -209.519459) (xy 201.95667 -209.505042) (xy 201.950084 -209.500717)
			(xy 201.93508 -209.495936) (xy 201.927206 -209.495644) (xy 201.411332 -209.495644) (xy 201.406082 -209.495088)
			(xy 201.398639 -209.487684) (xy 201.398124 -209.482436) (xy 195.35394 -209.482436) (xy 195.353432 -209.487695)
			(xy 195.345991 -209.495134) (xy 195.340732 -209.495644) (xy 194.824858 -209.495644) (xy 194.816983 -209.495922)
			(xy 194.801979 -209.500712) (xy 194.795394 -209.505042) (xy 194.774308 -209.51942) (xy 194.728666 -209.542252)
			(xy 194.680063 -209.557813) (xy 194.629648 -209.565737) (xy 194.604132 -209.566256) (xy 194.578611 -209.565775)
			(xy 194.528184 -209.557879) (xy 194.479572 -209.542317) (xy 194.433934 -209.519459) (xy 194.41287 -209.505042)
			(xy 194.406284 -209.500717) (xy 194.39128 -209.495936) (xy 194.383406 -209.495644) (xy 193.867532 -209.495644)
			(xy 193.862282 -209.495088) (xy 193.854839 -209.487684) (xy 193.854324 -209.482436) (xy 187.81014 -209.482436)
			(xy 187.809632 -209.487695) (xy 187.802191 -209.495134) (xy 187.796932 -209.495644) (xy 187.796424 -209.495644)
			(xy 187.280804 -209.495644) (xy 187.27293 -209.495942) (xy 187.257926 -209.500719) (xy 187.25134 -209.505042)
			(xy 187.230269 -209.519444) (xy 187.184622 -209.54227) (xy 187.136014 -209.557825) (xy 187.085595 -209.565741)
			(xy 187.060078 -209.566256) (xy 187.034558 -209.565752) (xy 186.984132 -209.557863) (xy 186.93552 -209.542308)
			(xy 186.889881 -209.519456) (xy 186.868816 -209.505042) (xy 186.86222 -209.500735) (xy 186.847224 -209.495942)
			(xy 186.839352 -209.495644) (xy 186.323478 -209.495644) (xy 186.318167 -209.49519) (xy 186.310597 -209.487738)
			(xy 186.310016 -209.482436) (xy 180.265832 -209.482436) (xy 180.265331 -209.487697) (xy 180.257886 -209.495136)
			(xy 180.252624 -209.495644) (xy 179.73675 -209.495644) (xy 179.728874 -209.495919) (xy 179.71387 -209.500711)
			(xy 179.707286 -209.505042) (xy 179.686202 -209.519424) (xy 179.64056 -209.542255) (xy 179.591956 -209.557815)
			(xy 179.54154 -209.565737) (xy 179.516024 -209.566256) (xy 179.490503 -209.565779) (xy 179.440075 -209.557882)
			(xy 179.391464 -209.542319) (xy 179.345826 -209.51946) (xy 179.324762 -209.505042) (xy 179.318178 -209.500714)
			(xy 179.303172 -209.495934) (xy 179.295298 -209.495644) (xy 178.779424 -209.495644) (xy 178.774173 -209.495093)
			(xy 178.766731 -209.487685) (xy 178.766216 -209.482436) (xy 172.722032 -209.482436) (xy 172.721531 -209.487697)
			(xy 172.714086 -209.495136) (xy 172.708824 -209.495644) (xy 172.708316 -209.495644) (xy 172.192696 -209.495644)
			(xy 172.184822 -209.495939) (xy 172.169818 -209.500718) (xy 172.163232 -209.505042) (xy 172.142163 -209.519447)
			(xy 172.096515 -209.542273) (xy 172.047907 -209.557827) (xy 171.997487 -209.565741) (xy 171.97197 -209.566256)
			(xy 171.94645 -209.565756) (xy 171.896023 -209.557866) (xy 171.847411 -209.542309) (xy 171.801773 -209.519457)
			(xy 171.780708 -209.505042) (xy 171.774114 -209.500731) (xy 171.759116 -209.495941) (xy 171.751244 -209.495644)
			(xy 171.23537 -209.495644) (xy 171.230058 -209.495195) (xy 171.222488 -209.487739) (xy 171.221908 -209.482436)
			(xy 165.177724 -209.482436) (xy 165.177231 -209.487699) (xy 165.16978 -209.495139) (xy 165.164516 -209.495644)
			(xy 163.691316 -209.495644) (xy 163.686064 -209.495098) (xy 163.678622 -209.487686) (xy 163.678108 -209.482436)
			(xy 56.07812 -209.482436) (xy 56.07763 -209.4877) (xy 56.070177 -209.49514) (xy 56.064912 -209.495644)
			(xy 54.591458 -209.495644) (xy 54.586145 -209.495203) (xy 54.578575 -209.487741) (xy 54.577996 -209.482436)
			(xy 48.533812 -209.482436) (xy 48.533329 -209.487702) (xy 48.525871 -209.495142) (xy 48.520604 -209.495644)
			(xy 48.00473 -209.495644) (xy 47.996854 -209.49591) (xy 47.98185 -209.500709) (xy 47.975266 -209.505042)
			(xy 47.954188 -209.519433) (xy 47.908543 -209.542261) (xy 47.859938 -209.557819) (xy 47.809521 -209.565739)
			(xy 47.784004 -209.566256) (xy 47.758483 -209.565789) (xy 47.708055 -209.557889) (xy 47.659443 -209.542323)
			(xy 47.613806 -209.519461) (xy 47.592742 -209.505042) (xy 47.586163 -209.500706) (xy 47.571153 -209.495931)
			(xy 47.563278 -209.495644) (xy 47.047404 -209.495644) (xy 47.04215 -209.495106) (xy 47.03471 -209.487688)
			(xy 47.034196 -209.482436) (xy 40.990012 -209.482436) (xy 40.989529 -209.487702) (xy 40.982071 -209.495142)
			(xy 40.976804 -209.495644) (xy 40.976296 -209.495644) (xy 40.460676 -209.495644) (xy 40.452801 -209.49593)
			(xy 40.437797 -209.500715) (xy 40.431212 -209.505042) (xy 40.410149 -209.519456) (xy 40.364499 -209.542279)
			(xy 40.315889 -209.557831) (xy 40.265468 -209.565743) (xy 40.23995 -209.566256) (xy 40.21443 -209.565766)
			(xy 40.164002 -209.557873) (xy 40.115391 -209.542313) (xy 40.069753 -209.519458) (xy 40.048688 -209.505042)
			(xy 40.042098 -209.500724) (xy 40.027097 -209.495938) (xy 40.019224 -209.495644) (xy 39.50335 -209.495644)
			(xy 39.498048 -209.495142) (xy 39.490473 -209.487727) (xy 39.489888 -209.482436) (xy 33.445704 -209.482436)
			(xy 33.445229 -209.487704) (xy 33.437765 -209.495145) (xy 33.432496 -209.495644) (xy 32.916622 -209.495644)
			(xy 32.908749 -209.49595) (xy 32.893745 -209.500721) (xy 32.887158 -209.505042) (xy 32.866082 -209.519436)
			(xy 32.820437 -209.542264) (xy 32.77183 -209.557821) (xy 32.721413 -209.565739) (xy 32.695896 -209.566256)
			(xy 32.670375 -209.565793) (xy 32.619946 -209.557892) (xy 32.571335 -209.542324) (xy 32.525698 -209.519461)
			(xy 32.504634 -209.505042) (xy 32.498034 -209.500741) (xy 32.483041 -209.495945) (xy 32.47517 -209.495644)
			(xy 31.959296 -209.495644) (xy 31.954041 -209.495112) (xy 31.946601 -209.487689) (xy 31.946088 -209.482436)
			(xy 25.901904 -209.482436) (xy 25.901429 -209.487704) (xy 25.893965 -209.495145) (xy 25.888696 -209.495644)
			(xy 25.372822 -209.495644) (xy 25.364949 -209.49595) (xy 25.349945 -209.500721) (xy 25.343358 -209.505042)
			(xy 25.322282 -209.519436) (xy 25.276637 -209.542264) (xy 25.22803 -209.557821) (xy 25.177613 -209.565739)
			(xy 25.152096 -209.566256) (xy 25.126575 -209.565793) (xy 25.076146 -209.557892) (xy 25.027535 -209.542324)
			(xy 24.981898 -209.519461) (xy 24.960834 -209.505042) (xy 24.954234 -209.500741) (xy 24.939241 -209.495945)
			(xy 24.93137 -209.495644) (xy 24.415496 -209.495644) (xy 24.410241 -209.495112) (xy 24.402801 -209.487689)
			(xy 24.402288 -209.482436) (xy 18.358104 -209.482436) (xy 18.357629 -209.487704) (xy 18.350165 -209.495145)
			(xy 18.344896 -209.495644) (xy 18.344388 -209.495644) (xy 17.828768 -209.495644) (xy 17.820893 -209.495927)
			(xy 17.805889 -209.500714) (xy 17.799304 -209.505042) (xy 17.778215 -209.519416) (xy 17.732575 -209.542249)
			(xy 17.683972 -209.557811) (xy 17.633558 -209.565736) (xy 17.608042 -209.566256) (xy 17.582522 -209.56577)
			(xy 17.532094 -209.557876) (xy 17.483482 -209.542315) (xy 17.437844 -209.519458) (xy 17.41678 -209.505042)
			(xy 17.410192 -209.500721) (xy 17.395189 -209.495937) (xy 17.387316 -209.495644) (xy 16.871442 -209.495644)
			(xy 16.866139 -209.495147) (xy 16.858565 -209.487728) (xy 16.85798 -209.482436) (xy 2.509012 -209.482436)
			(xy 2.509012 -210.332574) (xy 20.958048 -210.332574) (xy 20.958048 -209.838036) (xy 20.958614 -209.832788)
			(xy 20.966011 -209.825346) (xy 20.971256 -209.824828) (xy 20.971764 -209.824828) (xy 21.487638 -209.824828)
			(xy 21.495447 -209.8245) (xy 21.510319 -209.819725) (xy 21.516848 -209.81543) (xy 21.537937 -209.801081)
			(xy 21.583598 -209.77835) (xy 21.632204 -209.762891) (xy 21.682607 -209.755068) (xy 21.733613 -209.755068)
			(xy 21.784016 -209.762891) (xy 21.832622 -209.77835) (xy 21.878283 -209.801081) (xy 21.899372 -209.81543)
			(xy 21.905915 -209.819703) (xy 21.920776 -209.824498) (xy 21.928582 -209.824828) (xy 22.44471 -209.824828)
			(xy 22.450013 -209.825315) (xy 22.457582 -209.832744) (xy 22.458172 -209.838036) (xy 22.458172 -210.332574)
			(xy 22.458155 -210.332828) (xy 28.502356 -210.332828) (xy 28.502356 -210.33232) (xy 28.502356 -209.838036)
			(xy 28.502915 -209.832786) (xy 28.510317 -209.825344) (xy 28.515564 -209.824828) (xy 29.031692 -209.824828)
			(xy 29.039503 -209.824523) (xy 29.054375 -209.819732) (xy 29.060902 -209.81543) (xy 29.081991 -209.801081)
			(xy 29.127652 -209.77835) (xy 29.176258 -209.762891) (xy 29.226661 -209.755068) (xy 29.277667 -209.755068)
			(xy 29.32807 -209.762891) (xy 29.376676 -209.77835) (xy 29.422337 -209.801081) (xy 29.443426 -209.81543)
			(xy 29.449957 -209.819723) (xy 29.464827 -209.824506) (xy 29.472636 -209.824828) (xy 29.988764 -209.824828)
			(xy 29.9941 -209.825154) (xy 30.001646 -209.8327) (xy 30.001972 -209.838036) (xy 30.001972 -210.332574)
			(xy 30.001948 -210.332828) (xy 36.046156 -210.332828) (xy 36.046156 -210.33232) (xy 36.046156 -209.838036)
			(xy 36.046715 -209.832786) (xy 36.054117 -209.825344) (xy 36.059364 -209.824828) (xy 36.575492 -209.824828)
			(xy 36.583303 -209.824523) (xy 36.598175 -209.819732) (xy 36.604702 -209.81543) (xy 36.625791 -209.801081)
			(xy 36.671452 -209.77835) (xy 36.720058 -209.762891) (xy 36.770461 -209.755068) (xy 36.821467 -209.755068)
			(xy 36.87187 -209.762891) (xy 36.920476 -209.77835) (xy 36.966137 -209.801081) (xy 36.987226 -209.81543)
			(xy 36.993757 -209.819723) (xy 37.008627 -209.824506) (xy 37.016436 -209.824828) (xy 37.532564 -209.824828)
			(xy 37.5379 -209.825154) (xy 37.545446 -209.8327) (xy 37.545772 -209.838036) (xy 37.545772 -210.332574)
			(xy 43.589956 -210.332574) (xy 43.589956 -209.838036) (xy 43.590515 -209.832786) (xy 43.597917 -209.825344)
			(xy 43.603164 -209.824828) (xy 43.603672 -209.824828) (xy 44.119546 -209.824828) (xy 44.127355 -209.824503)
			(xy 44.142227 -209.819726) (xy 44.148756 -209.81543) (xy 44.169845 -209.801081) (xy 44.215506 -209.77835)
			(xy 44.264112 -209.762891) (xy 44.314515 -209.755068) (xy 44.365521 -209.755068) (xy 44.415924 -209.762891)
			(xy 44.46453 -209.77835) (xy 44.510191 -209.801081) (xy 44.53128 -209.81543) (xy 44.537821 -209.819706)
			(xy 44.552683 -209.8245) (xy 44.56049 -209.824828) (xy 45.076618 -209.824828) (xy 45.081922 -209.82531)
			(xy 45.089491 -209.832742) (xy 45.09008 -209.838036) (xy 45.09008 -210.332574) (xy 45.090062 -210.332828)
			(xy 51.134264 -210.332828) (xy 51.134264 -210.33232) (xy 51.134264 -209.838036) (xy 51.134648 -209.832715)
			(xy 51.142153 -209.825174) (xy 51.147472 -209.824828) (xy 51.6636 -209.824828) (xy 51.671411 -209.824526)
			(xy 51.686283 -209.819733) (xy 51.69281 -209.81543) (xy 51.713899 -209.801081) (xy 51.75956 -209.77835)
			(xy 51.808166 -209.762891) (xy 51.858569 -209.755068) (xy 51.909575 -209.755068) (xy 51.959978 -209.762891)
			(xy 52.008584 -209.77835) (xy 52.054245 -209.801081) (xy 52.075334 -209.81543) (xy 52.081863 -209.819726)
			(xy 52.096735 -209.824507) (xy 52.104544 -209.824828) (xy 52.620672 -209.824828) (xy 52.626009 -209.825149)
			(xy 52.633554 -209.832698) (xy 52.63388 -209.838036) (xy 52.63388 -210.332574) (xy 58.678064 -210.332574)
			(xy 58.678064 -209.838036) (xy 58.678448 -209.832715) (xy 58.685953 -209.825174) (xy 58.691272 -209.824828)
			(xy 58.69178 -209.824828) (xy 60.164726 -209.824828) (xy 60.17003 -209.825305) (xy 60.177599 -209.832741)
			(xy 60.178188 -209.838036) (xy 60.178188 -210.332574) (xy 60.178162 -210.332828) (xy 167.778176 -210.332828)
			(xy 167.778176 -209.838036) (xy 167.778549 -209.832712) (xy 167.786062 -209.82517) (xy 167.791384 -209.824828)
			(xy 169.264584 -209.824828) (xy 169.269923 -209.825141) (xy 169.277467 -209.832697) (xy 169.277792 -209.838036)
			(xy 169.277792 -210.332574) (xy 175.321976 -210.332574) (xy 175.321976 -209.838036) (xy 175.322349 -209.832712)
			(xy 175.329862 -209.82517) (xy 175.335184 -209.824828) (xy 175.335692 -209.824828) (xy 175.851566 -209.824828)
			(xy 175.859376 -209.824512) (xy 175.874248 -209.819729) (xy 175.880776 -209.81543) (xy 175.901865 -209.801081)
			(xy 175.947526 -209.77835) (xy 175.996132 -209.762891) (xy 176.046535 -209.755068) (xy 176.097541 -209.755068)
			(xy 176.147944 -209.762891) (xy 176.19655 -209.77835) (xy 176.242211 -209.801081) (xy 176.2633 -209.81543)
			(xy 176.269836 -209.819713) (xy 176.284702 -209.824503) (xy 176.29251 -209.824828) (xy 176.808638 -209.824828)
			(xy 176.813944 -209.825297) (xy 176.821512 -209.832739) (xy 176.8221 -209.838036) (xy 176.8221 -210.332574)
			(xy 176.822073 -210.332828) (xy 182.866284 -210.332828) (xy 182.866284 -210.33232) (xy 182.866284 -209.838036)
			(xy 182.86665 -209.83271) (xy 182.874168 -209.825168) (xy 182.879492 -209.824828) (xy 183.39562 -209.824828)
			(xy 183.403432 -209.824535) (xy 183.418304 -209.819736) (xy 183.42483 -209.81543) (xy 183.445919 -209.801081)
			(xy 183.49158 -209.77835) (xy 183.540186 -209.762891) (xy 183.590589 -209.755068) (xy 183.641595 -209.755068)
			(xy 183.691998 -209.762891) (xy 183.740604 -209.77835) (xy 183.786265 -209.801081) (xy 183.807354 -209.81543)
			(xy 183.813878 -209.819734) (xy 183.828754 -209.82451) (xy 183.836564 -209.824828) (xy 184.352692 -209.824828)
			(xy 184.358032 -209.825136) (xy 184.365576 -209.832695) (xy 184.3659 -209.838036) (xy 184.3659 -210.332574)
			(xy 190.410084 -210.332574) (xy 190.410084 -209.838036) (xy 190.41045 -209.83271) (xy 190.417968 -209.825168)
			(xy 190.423292 -209.824828) (xy 190.4238 -209.824828) (xy 190.939674 -209.824828) (xy 190.947484 -209.824515)
			(xy 190.962356 -209.81973) (xy 190.968884 -209.81543) (xy 190.989973 -209.801081) (xy 191.035634 -209.77835)
			(xy 191.08424 -209.762891) (xy 191.134643 -209.755068) (xy 191.185649 -209.755068) (xy 191.236052 -209.762891)
			(xy 191.284658 -209.77835) (xy 191.330319 -209.801081) (xy 191.351408 -209.81543) (xy 191.357943 -209.819716)
			(xy 191.37281 -209.824504) (xy 191.380618 -209.824828) (xy 191.896746 -209.824828) (xy 191.902041 -209.825358)
			(xy 191.909614 -209.832754) (xy 191.910208 -209.838036) (xy 191.910208 -210.332574) (xy 191.910181 -210.332828)
			(xy 197.954392 -210.332828) (xy 197.954392 -210.33232) (xy 197.954392 -209.838036) (xy 197.954751 -209.832708)
			(xy 197.962273 -209.825165) (xy 197.9676 -209.824828) (xy 198.483728 -209.824828) (xy 198.49154 -209.824538)
			(xy 198.506412 -209.819737) (xy 198.512938 -209.81543) (xy 198.534027 -209.801081) (xy 198.579688 -209.77835)
			(xy 198.628294 -209.762891) (xy 198.678697 -209.755068) (xy 198.729703 -209.755068) (xy 198.780106 -209.762891)
			(xy 198.828712 -209.77835) (xy 198.874373 -209.801081) (xy 198.895462 -209.81543) (xy 198.902007 -209.819699)
			(xy 198.916866 -209.824497) (xy 198.924672 -209.824828) (xy 199.4408 -209.824828) (xy 199.446141 -209.82513)
			(xy 199.453684 -209.832694) (xy 199.454008 -209.838036) (xy 199.454008 -210.332574) (xy 199.453982 -210.332828)
			(xy 205.498192 -210.332828) (xy 205.498192 -210.33232) (xy 205.498192 -209.838036) (xy 205.498551 -209.832708)
			(xy 205.506073 -209.825165) (xy 205.5114 -209.824828) (xy 206.027528 -209.824828) (xy 206.03534 -209.824538)
			(xy 206.050212 -209.819737) (xy 206.056738 -209.81543) (xy 206.077827 -209.801081) (xy 206.123488 -209.77835)
			(xy 206.172094 -209.762891) (xy 206.222497 -209.755068) (xy 206.273503 -209.755068) (xy 206.323906 -209.762891)
			(xy 206.372512 -209.77835) (xy 206.418173 -209.801081) (xy 206.439262 -209.81543) (xy 206.445807 -209.819699)
			(xy 206.460666 -209.824497) (xy 206.468472 -209.824828) (xy 206.9846 -209.824828) (xy 206.989941 -209.82513)
			(xy 206.997484 -209.832694) (xy 206.997808 -209.838036) (xy 206.997808 -210.332574) (xy 206.997265 -210.337864)
			(xy 206.989877 -210.345434) (xy 206.9846 -210.346036) (xy 206.468726 -210.346036) (xy 206.460916 -210.346355)
			(xy 206.446045 -210.351137) (xy 206.439516 -210.355434) (xy 206.418386 -210.36977) (xy 206.372665 -210.392501)
			(xy 206.323995 -210.407934) (xy 206.27353 -210.415705) (xy 206.248 -210.41614) (xy 206.22247 -210.415708)
			(xy 206.172005 -210.407931) (xy 206.123333 -210.392501) (xy 206.077606 -210.369783) (xy 206.056484 -210.355434)
			(xy 206.049953 -210.351141) (xy 206.035083 -210.346359) (xy 206.027274 -210.346036) (xy 205.5114 -210.346036)
			(xy 205.506144 -210.345508) (xy 205.498703 -210.338083) (xy 205.498192 -210.332828) (xy 199.453982 -210.332828)
			(xy 199.453465 -210.337864) (xy 199.446077 -210.345434) (xy 199.4408 -210.346036) (xy 198.924926 -210.346036)
			(xy 198.917116 -210.346355) (xy 198.902245 -210.351137) (xy 198.895716 -210.355434) (xy 198.874586 -210.36977)
			(xy 198.828865 -210.392501) (xy 198.780195 -210.407934) (xy 198.72973 -210.415705) (xy 198.7042 -210.41614)
			(xy 198.67867 -210.415708) (xy 198.628205 -210.407931) (xy 198.579533 -210.392501) (xy 198.533806 -210.369783)
			(xy 198.512684 -210.355434) (xy 198.506153 -210.351141) (xy 198.491283 -210.346359) (xy 198.483474 -210.346036)
			(xy 197.9676 -210.346036) (xy 197.962344 -210.345508) (xy 197.954903 -210.338083) (xy 197.954392 -210.332828)
			(xy 191.910181 -210.332828) (xy 191.909637 -210.337924) (xy 191.902093 -210.345508) (xy 191.896746 -210.346036)
			(xy 191.380872 -210.346036) (xy 191.37306 -210.346332) (xy 191.358189 -210.351129) (xy 191.351662 -210.355434)
			(xy 191.330547 -210.369794) (xy 191.284821 -210.392519) (xy 191.236146 -210.407946) (xy 191.185678 -210.415709)
			(xy 191.160146 -210.41614) (xy 191.134616 -210.415685) (xy 191.084153 -210.407915) (xy 191.035481 -210.392492)
			(xy 190.989752 -210.36978) (xy 190.96863 -210.355434) (xy 190.962089 -210.351159) (xy 190.947226 -210.346365)
			(xy 190.93942 -210.346036) (xy 190.423546 -210.346036) (xy 190.418111 -210.345687) (xy 190.410421 -210.338009)
			(xy 190.410084 -210.332574) (xy 184.3659 -210.332574) (xy 184.365364 -210.337866) (xy 184.357971 -210.345436)
			(xy 184.352692 -210.346036) (xy 183.836818 -210.346036) (xy 183.829008 -210.346351) (xy 183.814136 -210.351135)
			(xy 183.807608 -210.355434) (xy 183.78648 -210.369774) (xy 183.740759 -210.392503) (xy 183.692087 -210.407936)
			(xy 183.641622 -210.415705) (xy 183.616092 -210.41614) (xy 183.590561 -210.415712) (xy 183.540097 -210.407934)
			(xy 183.491424 -210.392503) (xy 183.445697 -210.369783) (xy 183.424576 -210.355434) (xy 183.418047 -210.351138)
			(xy 183.403175 -210.346358) (xy 183.395366 -210.346036) (xy 182.879492 -210.346036) (xy 182.874235 -210.345513)
			(xy 182.866795 -210.338084) (xy 182.866284 -210.332828) (xy 176.822073 -210.332828) (xy 176.821536 -210.337926)
			(xy 176.813987 -210.345511) (xy 176.808638 -210.346036) (xy 176.292764 -210.346036) (xy 176.284956 -210.346371)
			(xy 176.270084 -210.351142) (xy 176.263554 -210.355434) (xy 176.242441 -210.369797) (xy 176.196714 -210.392521)
			(xy 176.148038 -210.407948) (xy 176.09757 -210.41571) (xy 176.072038 -210.41614) (xy 176.046508 -210.415689)
			(xy 175.996045 -210.407918) (xy 175.947372 -210.392493) (xy 175.901644 -210.36978) (xy 175.880522 -210.355434)
			(xy 175.873983 -210.351156) (xy 175.859119 -210.346364) (xy 175.851312 -210.346036) (xy 175.335438 -210.346036)
			(xy 175.330002 -210.345693) (xy 175.322312 -210.33801) (xy 175.321976 -210.332574) (xy 169.277792 -210.332574)
			(xy 169.277263 -210.337868) (xy 169.269865 -210.345438) (xy 169.264584 -210.346036) (xy 167.791384 -210.346036)
			(xy 167.786126 -210.345519) (xy 167.778686 -210.338086) (xy 167.778176 -210.332828) (xy 60.178162 -210.332828)
			(xy 60.177635 -210.337929) (xy 60.170079 -210.345514) (xy 60.164726 -210.346036) (xy 58.691526 -210.346036)
			(xy 58.686088 -210.345701) (xy 58.678399 -210.338012) (xy 58.678064 -210.332574) (xy 52.63388 -210.332574)
			(xy 52.633362 -210.33787) (xy 52.625956 -210.345442) (xy 52.620672 -210.346036) (xy 52.104798 -210.346036)
			(xy 52.096987 -210.346343) (xy 52.082116 -210.351133) (xy 52.075588 -210.355434) (xy 52.054466 -210.369783)
			(xy 52.008742 -210.39251) (xy 51.960069 -210.40794) (xy 51.909603 -210.415707) (xy 51.884072 -210.41614)
			(xy 51.858541 -210.415722) (xy 51.808076 -210.407941) (xy 51.759404 -210.392507) (xy 51.713677 -210.369784)
			(xy 51.692556 -210.355434) (xy 51.686031 -210.351131) (xy 51.671156 -210.346355) (xy 51.663346 -210.346036)
			(xy 51.147472 -210.346036) (xy 51.142213 -210.345527) (xy 51.134773 -210.338087) (xy 51.134264 -210.332828)
			(xy 45.090062 -210.332828) (xy 45.089705 -210.338001) (xy 45.082044 -210.345687) (xy 45.076618 -210.346036)
			(xy 44.560744 -210.346036) (xy 44.552935 -210.346363) (xy 44.538063 -210.351139) (xy 44.531534 -210.355434)
			(xy 44.510427 -210.369806) (xy 44.464698 -210.392528) (xy 44.41602 -210.407952) (xy 44.36555 -210.415711)
			(xy 44.340018 -210.41614) (xy 44.314488 -210.415699) (xy 44.264024 -210.407925) (xy 44.215351 -210.392497)
			(xy 44.169624 -210.369781) (xy 44.148502 -210.355434) (xy 44.141967 -210.351148) (xy 44.1271 -210.346361)
			(xy 44.119292 -210.346036) (xy 43.603418 -210.346036) (xy 43.597979 -210.345706) (xy 43.590291 -210.338013)
			(xy 43.589956 -210.332574) (xy 37.545772 -210.332574) (xy 37.545261 -210.337872) (xy 37.537851 -210.345444)
			(xy 37.532564 -210.346036) (xy 37.01669 -210.346036) (xy 37.008879 -210.346339) (xy 36.994007 -210.351132)
			(xy 36.98748 -210.355434) (xy 36.96636 -210.369786) (xy 36.920636 -210.392513) (xy 36.871962 -210.407942)
			(xy 36.821495 -210.415708) (xy 36.795964 -210.41614) (xy 36.770433 -210.415726) (xy 36.719968 -210.407944)
			(xy 36.671295 -210.392508) (xy 36.625569 -210.369785) (xy 36.604448 -210.355434) (xy 36.597925 -210.351128)
			(xy 36.583049 -210.346353) (xy 36.575238 -210.346036) (xy 36.059364 -210.346036) (xy 36.054104 -210.345532)
			(xy 36.046665 -210.338089) (xy 36.046156 -210.332828) (xy 30.001948 -210.332828) (xy 30.001461 -210.337872)
			(xy 29.994051 -210.345444) (xy 29.988764 -210.346036) (xy 29.47289 -210.346036) (xy 29.465079 -210.346339)
			(xy 29.450207 -210.351132) (xy 29.44368 -210.355434) (xy 29.42256 -210.369786) (xy 29.376836 -210.392513)
			(xy 29.328162 -210.407942) (xy 29.277695 -210.415708) (xy 29.252164 -210.41614) (xy 29.226633 -210.415726)
			(xy 29.176168 -210.407944) (xy 29.127495 -210.392508) (xy 29.081769 -210.369785) (xy 29.060648 -210.355434)
			(xy 29.054125 -210.351128) (xy 29.039249 -210.346353) (xy 29.031438 -210.346036) (xy 28.515564 -210.346036)
			(xy 28.510304 -210.345532) (xy 28.502865 -210.338089) (xy 28.502356 -210.332828) (xy 22.458155 -210.332828)
			(xy 22.457804 -210.338003) (xy 22.450138 -210.34569) (xy 22.44471 -210.346036) (xy 21.928836 -210.346036)
			(xy 21.921027 -210.346359) (xy 21.906155 -210.351138) (xy 21.899626 -210.355434) (xy 21.878493 -210.369766)
			(xy 21.832774 -210.392497) (xy 21.784104 -210.407932) (xy 21.73364 -210.415704) (xy 21.70811 -210.41614)
			(xy 21.68258 -210.415703) (xy 21.632116 -210.407928) (xy 21.583443 -210.392499) (xy 21.537716 -210.369782)
			(xy 21.516594 -210.355434) (xy 21.510061 -210.351145) (xy 21.495192 -210.34636) (xy 21.487384 -210.346036)
			(xy 20.97151 -210.346036) (xy 20.96607 -210.345712) (xy 20.958382 -210.338014) (xy 20.958048 -210.332574)
			(xy 2.509012 -210.332574) (xy 2.509012 -211.182458) (xy 16.85798 -211.182458) (xy 16.85798 -210.68792)
			(xy 16.858339 -210.682593) (xy 16.865862 -210.675052) (xy 16.871188 -210.674712) (xy 16.871696 -210.674712)
			(xy 17.38757 -210.674712) (xy 17.395381 -210.6744) (xy 17.410253 -210.669615) (xy 17.41678 -210.665314)
			(xy 17.437869 -210.650965) (xy 17.48353 -210.628234) (xy 17.532136 -210.612775) (xy 17.582539 -210.604952)
			(xy 17.633545 -210.604952) (xy 17.683948 -210.612775) (xy 17.732554 -210.628234) (xy 17.778215 -210.650965)
			(xy 17.799304 -210.665314) (xy 17.80584 -210.669597) (xy 17.820706 -210.674387) (xy 17.828514 -210.674712)
			(xy 18.344642 -210.674712) (xy 18.349945 -210.675192) (xy 18.357512 -210.682627) (xy 18.358104 -210.68792)
			(xy 18.358104 -211.182458) (xy 20.958048 -211.182458) (xy 20.958048 -210.68792) (xy 20.958603 -210.68267)
			(xy 20.966009 -210.675229) (xy 20.971256 -210.674712) (xy 20.971764 -210.674712) (xy 21.487638 -210.674712)
			(xy 21.495447 -210.674387) (xy 21.510319 -210.66961) (xy 21.516848 -210.665314) (xy 21.537937 -210.650965)
			(xy 21.583598 -210.628234) (xy 21.632204 -210.612775) (xy 21.682607 -210.604952) (xy 21.733613 -210.604952)
			(xy 21.784016 -210.612775) (xy 21.832622 -210.628234) (xy 21.878283 -210.650965) (xy 21.899372 -210.665314)
			(xy 21.905916 -210.669585) (xy 21.920776 -210.674382) (xy 21.928582 -210.674712) (xy 22.44471 -210.674712)
			(xy 22.450009 -210.675213) (xy 22.457578 -210.682632) (xy 22.458172 -210.68792) (xy 22.458172 -211.182458)
			(xy 22.458154 -211.182712) (xy 24.402288 -211.182712) (xy 24.402288 -211.182204) (xy 24.402288 -210.68792)
			(xy 24.40264 -210.682591) (xy 24.410168 -210.675049) (xy 24.415496 -210.674712) (xy 24.931624 -210.674712)
			(xy 24.939437 -210.674423) (xy 24.954308 -210.669622) (xy 24.960834 -210.665314) (xy 24.981923 -210.650965)
			(xy 25.027584 -210.628234) (xy 25.07619 -210.612775) (xy 25.126593 -210.604952) (xy 25.177599 -210.604952)
			(xy 25.228002 -210.612775) (xy 25.276608 -210.628234) (xy 25.322269 -210.650965) (xy 25.343358 -210.665314)
			(xy 25.349882 -210.669618) (xy 25.364758 -210.674395) (xy 25.372568 -210.674712) (xy 25.888696 -210.674712)
			(xy 25.894033 -210.675032) (xy 25.901575 -210.682583) (xy 25.901904 -210.68792) (xy 25.901904 -211.182458)
			(xy 25.901878 -211.182712) (xy 28.502356 -211.182712) (xy 28.502356 -211.182204) (xy 28.502356 -210.68792)
			(xy 28.502904 -210.682668) (xy 28.510314 -210.675226) (xy 28.515564 -210.674712) (xy 29.031692 -210.674712)
			(xy 29.039503 -210.67441) (xy 29.054375 -210.669617) (xy 29.060902 -210.665314) (xy 29.081991 -210.650965)
			(xy 29.127652 -210.628234) (xy 29.176258 -210.612775) (xy 29.226661 -210.604952) (xy 29.277667 -210.604952)
			(xy 29.32807 -210.612775) (xy 29.376676 -210.628234) (xy 29.422337 -210.650965) (xy 29.443426 -210.665314)
			(xy 29.449957 -210.669606) (xy 29.464827 -210.67439) (xy 29.472636 -210.674712) (xy 29.988764 -210.674712)
			(xy 29.994096 -210.675053) (xy 30.001641 -210.682588) (xy 30.001972 -210.68792) (xy 30.001972 -211.182458)
			(xy 30.001947 -211.182712) (xy 31.946088 -211.182712) (xy 31.946088 -211.182204) (xy 31.946088 -210.68792)
			(xy 31.94644 -210.682591) (xy 31.953968 -210.675049) (xy 31.959296 -210.674712) (xy 32.475424 -210.674712)
			(xy 32.483237 -210.674423) (xy 32.498108 -210.669622) (xy 32.504634 -210.665314) (xy 32.525723 -210.650965)
			(xy 32.571384 -210.628234) (xy 32.61999 -210.612775) (xy 32.670393 -210.604952) (xy 32.721399 -210.604952)
			(xy 32.771802 -210.612775) (xy 32.820408 -210.628234) (xy 32.866069 -210.650965) (xy 32.887158 -210.665314)
			(xy 32.893682 -210.669618) (xy 32.908558 -210.674395) (xy 32.916368 -210.674712) (xy 33.432496 -210.674712)
			(xy 33.437833 -210.675032) (xy 33.445375 -210.682583) (xy 33.445704 -210.68792) (xy 33.445704 -211.182458)
			(xy 33.445678 -211.182712) (xy 36.046156 -211.182712) (xy 36.046156 -211.182204) (xy 36.046156 -210.68792)
			(xy 36.046704 -210.682668) (xy 36.054114 -210.675226) (xy 36.059364 -210.674712) (xy 36.575492 -210.674712)
			(xy 36.583303 -210.67441) (xy 36.598175 -210.669617) (xy 36.604702 -210.665314) (xy 36.625791 -210.650965)
			(xy 36.671452 -210.628234) (xy 36.720058 -210.612775) (xy 36.770461 -210.604952) (xy 36.821467 -210.604952)
			(xy 36.87187 -210.612775) (xy 36.920476 -210.628234) (xy 36.966137 -210.650965) (xy 36.987226 -210.665314)
			(xy 36.993757 -210.669606) (xy 37.008627 -210.67439) (xy 37.016436 -210.674712) (xy 37.532564 -210.674712)
			(xy 37.537896 -210.675053) (xy 37.545441 -210.682588) (xy 37.545772 -210.68792) (xy 37.545772 -211.182458)
			(xy 39.489888 -211.182458) (xy 39.489888 -210.68792) (xy 39.49024 -210.682591) (xy 39.497768 -210.675049)
			(xy 39.503096 -210.674712) (xy 39.503604 -210.674712) (xy 40.019478 -210.674712) (xy 40.027289 -210.674404)
			(xy 40.042161 -210.669616) (xy 40.048688 -210.665314) (xy 40.069777 -210.650965) (xy 40.115438 -210.628234)
			(xy 40.164044 -210.612775) (xy 40.214447 -210.604952) (xy 40.265453 -210.604952) (xy 40.315856 -210.612775)
			(xy 40.364462 -210.628234) (xy 40.410123 -210.650965) (xy 40.431212 -210.665314) (xy 40.437747 -210.6696)
			(xy 40.452614 -210.674388) (xy 40.460422 -210.674712) (xy 40.97655 -210.674712) (xy 40.981842 -210.675253)
			(xy 40.989414 -210.682642) (xy 40.990012 -210.68792) (xy 40.990012 -211.182458) (xy 43.589956 -211.182458)
			(xy 43.589956 -210.68792) (xy 43.590504 -210.682668) (xy 43.597914 -210.675226) (xy 43.603164 -210.674712)
			(xy 43.603672 -210.674712) (xy 44.119546 -210.674712) (xy 44.127356 -210.67439) (xy 44.142228 -210.669611)
			(xy 44.148756 -210.665314) (xy 44.169845 -210.650965) (xy 44.215506 -210.628234) (xy 44.264112 -210.612775)
			(xy 44.314515 -210.604952) (xy 44.365521 -210.604952) (xy 44.415924 -210.612775) (xy 44.46453 -210.628234)
			(xy 44.510191 -210.650965) (xy 44.53128 -210.665314) (xy 44.537822 -210.669588) (xy 44.552684 -210.674383)
			(xy 44.56049 -210.674712) (xy 45.076618 -210.674712) (xy 45.081918 -210.675208) (xy 45.089486 -210.682631)
			(xy 45.09008 -210.68792) (xy 45.09008 -211.182458) (xy 45.090062 -211.182712) (xy 47.034196 -211.182712)
			(xy 47.034196 -211.182204) (xy 47.034196 -210.68792) (xy 47.03454 -210.682589) (xy 47.042074 -210.675047)
			(xy 47.047404 -210.674712) (xy 47.563532 -210.674712) (xy 47.571341 -210.674384) (xy 47.586213 -210.66961)
			(xy 47.592742 -210.665314) (xy 47.613831 -210.650965) (xy 47.659492 -210.628234) (xy 47.708098 -210.612775)
			(xy 47.758501 -210.604952) (xy 47.809507 -210.604952) (xy 47.85991 -210.612775) (xy 47.908516 -210.628234)
			(xy 47.954177 -210.650965) (xy 47.975266 -210.665314) (xy 47.981811 -210.669583) (xy 47.99667 -210.674381)
			(xy 48.004476 -210.674712) (xy 48.520604 -210.674712) (xy 48.525942 -210.675026) (xy 48.533483 -210.682582)
			(xy 48.533812 -210.68792) (xy 48.533812 -211.182458) (xy 48.53379 -211.182712) (xy 51.134264 -211.182712)
			(xy 51.134264 -211.182204) (xy 51.134264 -210.68792) (xy 51.134805 -210.682666) (xy 51.14222 -210.675224)
			(xy 51.147472 -210.674712) (xy 51.6636 -210.674712) (xy 51.671412 -210.674413) (xy 51.686284 -210.669618)
			(xy 51.69281 -210.665314) (xy 51.713899 -210.650965) (xy 51.75956 -210.628234) (xy 51.808166 -210.612775)
			(xy 51.858569 -210.604952) (xy 51.909575 -210.604952) (xy 51.959978 -210.612775) (xy 52.008584 -210.628234)
			(xy 52.054245 -210.650965) (xy 52.075334 -210.665314) (xy 52.081864 -210.669609) (xy 52.096735 -210.674391)
			(xy 52.104544 -210.674712) (xy 52.620672 -210.674712) (xy 52.626005 -210.675047) (xy 52.633549 -210.682587)
			(xy 52.63388 -210.68792) (xy 52.63388 -211.182458) (xy 54.577996 -211.182458) (xy 54.577996 -210.68792)
			(xy 54.57834 -210.682589) (xy 54.585874 -210.675047) (xy 54.591204 -210.674712) (xy 56.064658 -210.674712)
			(xy 56.069951 -210.675248) (xy 56.077522 -210.68264) (xy 56.07812 -210.68792) (xy 56.07812 -211.182458)
			(xy 58.678064 -211.182458) (xy 58.678064 -210.68792) (xy 58.678605 -210.682666) (xy 58.68602 -210.675224)
			(xy 58.691272 -210.674712) (xy 58.69178 -210.674712) (xy 60.164726 -210.674712) (xy 60.170027 -210.675203)
			(xy 60.177595 -210.68263) (xy 60.178188 -210.68792) (xy 60.178188 -211.182458) (xy 60.177795 -211.187881)
			(xy 60.170147 -211.195568) (xy 60.164726 -211.19592) (xy 58.691526 -211.19592) (xy 58.686084 -211.195599)
			(xy 58.678394 -211.1879) (xy 58.678064 -211.182458) (xy 56.07812 -211.182458) (xy 56.077788 -211.187897)
			(xy 56.070097 -211.195588) (xy 56.064658 -211.19592) (xy 54.591458 -211.19592) (xy 54.586079 -211.195473)
			(xy 54.578493 -211.18784) (xy 54.577996 -211.182458) (xy 52.63388 -211.182458) (xy 52.633351 -211.187753)
			(xy 52.625954 -211.195325) (xy 52.620672 -211.19592) (xy 52.104798 -211.19592) (xy 52.096987 -211.196229)
			(xy 52.082116 -211.201018) (xy 52.075588 -211.205318) (xy 52.054465 -211.219665) (xy 52.008742 -211.242393)
			(xy 51.960069 -211.257824) (xy 51.909603 -211.265591) (xy 51.884072 -211.266024) (xy 51.858541 -211.265609)
			(xy 51.808076 -211.257828) (xy 51.759403 -211.242392) (xy 51.713677 -211.219669) (xy 51.692556 -211.205318)
			(xy 51.686032 -211.201013) (xy 51.671156 -211.196238) (xy 51.663346 -211.19592) (xy 51.147472 -211.19592)
			(xy 51.142209 -211.195425) (xy 51.134768 -211.187976) (xy 51.134264 -211.182712) (xy 48.53379 -211.182712)
			(xy 48.533343 -211.187768) (xy 48.525905 -211.195345) (xy 48.520604 -211.19592) (xy 48.00473 -211.19592)
			(xy 47.996921 -211.196243) (xy 47.982049 -211.201022) (xy 47.97552 -211.205318) (xy 47.954388 -211.219651)
			(xy 47.908668 -211.242382) (xy 47.859998 -211.257817) (xy 47.809534 -211.265589) (xy 47.784004 -211.266024)
			(xy 47.758473 -211.265593) (xy 47.708009 -211.257816) (xy 47.659336 -211.242386) (xy 47.613609 -211.219667)
			(xy 47.592488 -211.205318) (xy 47.585957 -211.201025) (xy 47.571087 -211.196243) (xy 47.563278 -211.19592)
			(xy 47.047404 -211.19592) (xy 47.042145 -211.195404) (xy 47.034702 -211.187971) (xy 47.034196 -211.182712)
			(xy 45.090062 -211.182712) (xy 45.089694 -211.187883) (xy 45.082041 -211.19557) (xy 45.076618 -211.19592)
			(xy 44.560744 -211.19592) (xy 44.552935 -211.196249) (xy 44.538064 -211.201024) (xy 44.531534 -211.205318)
			(xy 44.510426 -211.219688) (xy 44.464697 -211.242411) (xy 44.41602 -211.257835) (xy 44.36555 -211.265595)
			(xy 44.340018 -211.266024) (xy 44.314488 -211.265586) (xy 44.264024 -211.257812) (xy 44.215351 -211.242383)
			(xy 44.169624 -211.219666) (xy 44.148502 -211.205318) (xy 44.141968 -211.201031) (xy 44.1271 -211.196245)
			(xy 44.119292 -211.19592) (xy 43.603418 -211.19592) (xy 43.597975 -211.195605) (xy 43.590286 -211.187901)
			(xy 43.589956 -211.182458) (xy 40.990012 -211.182458) (xy 40.989427 -211.187805) (xy 40.981893 -211.19539)
			(xy 40.97655 -211.19592) (xy 40.460676 -211.19592) (xy 40.452865 -211.19622) (xy 40.437993 -211.201015)
			(xy 40.431466 -211.205318) (xy 40.410349 -211.219674) (xy 40.364624 -211.2424) (xy 40.315949 -211.257829)
			(xy 40.265481 -211.265593) (xy 40.23995 -211.266024) (xy 40.21442 -211.26557) (xy 40.163957 -211.2578)
			(xy 40.115284 -211.242377) (xy 40.069556 -211.219664) (xy 40.048434 -211.205318) (xy 40.041893 -211.201043)
			(xy 40.02703 -211.19625) (xy 40.019224 -211.19592) (xy 39.50335 -211.19592) (xy 39.49797 -211.195478)
			(xy 39.490385 -211.187841) (xy 39.489888 -211.182458) (xy 37.545772 -211.182458) (xy 37.54525 -211.187754)
			(xy 37.537848 -211.195327) (xy 37.532564 -211.19592) (xy 37.01669 -211.19592) (xy 37.008879 -211.196226)
			(xy 36.994008 -211.201017) (xy 36.98748 -211.205318) (xy 36.966359 -211.219668) (xy 36.920635 -211.242396)
			(xy 36.871962 -211.257826) (xy 36.821495 -211.265592) (xy 36.795964 -211.266024) (xy 36.770433 -211.265613)
			(xy 36.719967 -211.25783) (xy 36.671295 -211.242394) (xy 36.625569 -211.21967) (xy 36.604448 -211.205318)
			(xy 36.597926 -211.20101) (xy 36.583049 -211.196237) (xy 36.575238 -211.19592) (xy 36.059364 -211.19592)
			(xy 36.0541 -211.19543) (xy 36.04666 -211.187977) (xy 36.046156 -211.182712) (xy 33.445678 -211.182712)
			(xy 33.445154 -211.187747) (xy 33.437771 -211.195318) (xy 33.432496 -211.19592) (xy 32.916622 -211.19592)
			(xy 32.908812 -211.196239) (xy 32.893941 -211.201021) (xy 32.887412 -211.205318) (xy 32.866282 -211.219654)
			(xy 32.820561 -211.242385) (xy 32.771891 -211.257819) (xy 32.721426 -211.265589) (xy 32.695896 -211.266024)
			(xy 32.670365 -211.265597) (xy 32.619901 -211.257819) (xy 32.571228 -211.242388) (xy 32.525501 -211.219667)
			(xy 32.50438 -211.205318) (xy 32.497851 -211.201022) (xy 32.482979 -211.196242) (xy 32.47517 -211.19592)
			(xy 31.959296 -211.19592) (xy 31.954036 -211.195409) (xy 31.946594 -211.187972) (xy 31.946088 -211.182712)
			(xy 30.001947 -211.182712) (xy 30.00145 -211.187754) (xy 29.994048 -211.195327) (xy 29.988764 -211.19592)
			(xy 29.47289 -211.19592) (xy 29.465079 -211.196226) (xy 29.450208 -211.201017) (xy 29.44368 -211.205318)
			(xy 29.422559 -211.219668) (xy 29.376835 -211.242396) (xy 29.328162 -211.257826) (xy 29.277695 -211.265592)
			(xy 29.252164 -211.266024) (xy 29.226633 -211.265613) (xy 29.176167 -211.25783) (xy 29.127495 -211.242394)
			(xy 29.081769 -211.21967) (xy 29.060648 -211.205318) (xy 29.054126 -211.20101) (xy 29.039249 -211.196237)
			(xy 29.031438 -211.19592) (xy 28.515564 -211.19592) (xy 28.5103 -211.19543) (xy 28.50286 -211.187977)
			(xy 28.502356 -211.182712) (xy 25.901878 -211.182712) (xy 25.901354 -211.187747) (xy 25.893971 -211.195318)
			(xy 25.888696 -211.19592) (xy 25.372822 -211.19592) (xy 25.365012 -211.196239) (xy 25.350141 -211.201021)
			(xy 25.343612 -211.205318) (xy 25.322482 -211.219654) (xy 25.276761 -211.242385) (xy 25.228091 -211.257819)
			(xy 25.177626 -211.265589) (xy 25.152096 -211.266024) (xy 25.126565 -211.265597) (xy 25.076101 -211.257819)
			(xy 25.027428 -211.242388) (xy 24.981701 -211.219667) (xy 24.96058 -211.205318) (xy 24.954051 -211.201022)
			(xy 24.939179 -211.196242) (xy 24.93137 -211.19592) (xy 24.415496 -211.19592) (xy 24.410236 -211.195409)
			(xy 24.402794 -211.187972) (xy 24.402288 -211.182712) (xy 22.458154 -211.182712) (xy 22.457793 -211.187885)
			(xy 22.450135 -211.195573) (xy 22.44471 -211.19592) (xy 21.928836 -211.19592) (xy 21.921027 -211.196245)
			(xy 21.906155 -211.201023) (xy 21.899626 -211.205318) (xy 21.878492 -211.219648) (xy 21.832773 -211.24238)
			(xy 21.784103 -211.257816) (xy 21.73364 -211.265588) (xy 21.70811 -211.266024) (xy 21.68258 -211.26559)
			(xy 21.632115 -211.257814) (xy 21.583443 -211.242385) (xy 21.537715 -211.219667) (xy 21.516594 -211.205318)
			(xy 21.510062 -211.201028) (xy 21.495192 -211.196244) (xy 21.487384 -211.19592) (xy 20.97151 -211.19592)
			(xy 20.966066 -211.19561) (xy 20.958377 -211.187903) (xy 20.958048 -211.182458) (xy 18.358104 -211.182458)
			(xy 18.357526 -211.187807) (xy 18.349988 -211.195393) (xy 18.344642 -211.19592) (xy 17.828768 -211.19592)
			(xy 17.82096 -211.196259) (xy 17.806089 -211.201027) (xy 17.799558 -211.205318) (xy 17.778443 -211.219678)
			(xy 17.732717 -211.242403) (xy 17.684042 -211.25783) (xy 17.633574 -211.265593) (xy 17.608042 -211.266024)
			(xy 17.582512 -211.265574) (xy 17.532049 -211.257803) (xy 17.483376 -211.242378) (xy 17.437648 -211.219664)
			(xy 17.416526 -211.205318) (xy 17.409987 -211.20104) (xy 17.395123 -211.196249) (xy 17.387316 -211.19592)
			(xy 16.871442 -211.19592) (xy 16.866003 -211.195588) (xy 16.858312 -211.187897) (xy 16.85798 -211.182458)
			(xy 2.509012 -211.182458) (xy 2.509012 -212.032342) (xy 16.85798 -212.032342) (xy 16.85798 -211.537804)
			(xy 16.858496 -211.532545) (xy 16.865929 -211.525102) (xy 16.871188 -211.524596) (xy 16.871696 -211.524596)
			(xy 17.38757 -211.524596) (xy 17.395379 -211.52427) (xy 17.410251 -211.519493) (xy 17.41678 -211.515198)
			(xy 17.437869 -211.500849) (xy 17.48353 -211.478118) (xy 17.532136 -211.462659) (xy 17.582539 -211.454836)
			(xy 17.633545 -211.454836) (xy 17.683948 -211.462659) (xy 17.732554 -211.478118) (xy 17.778215 -211.500849)
			(xy 17.799304 -211.515198) (xy 17.805835 -211.519489) (xy 17.820706 -211.524272) (xy 17.828514 -211.524596)
			(xy 18.344642 -211.524596) (xy 18.349941 -211.52509) (xy 18.357507 -211.532515) (xy 18.358104 -211.537804)
			(xy 18.358104 -212.032342) (xy 18.358079 -212.032596) (xy 24.402288 -212.032596) (xy 24.402288 -212.032088)
			(xy 24.402288 -211.537804) (xy 24.402797 -211.532543) (xy 24.410235 -211.5251) (xy 24.415496 -211.524596)
			(xy 24.931624 -211.524596) (xy 24.939435 -211.524293) (xy 24.954306 -211.5195) (xy 24.960834 -211.515198)
			(xy 24.981923 -211.500849) (xy 25.027584 -211.478118) (xy 25.07619 -211.462659) (xy 25.126593 -211.454836)
			(xy 25.177599 -211.454836) (xy 25.228002 -211.462659) (xy 25.276608 -211.478118) (xy 25.322269 -211.500849)
			(xy 25.343358 -211.515198) (xy 25.349877 -211.51951) (xy 25.364757 -211.52428) (xy 25.372568 -211.524596)
			(xy 25.888696 -211.524596) (xy 25.894029 -211.52493) (xy 25.90157 -211.532471) (xy 25.901904 -211.537804)
			(xy 25.901904 -212.032342) (xy 25.90188 -212.032596) (xy 31.946088 -212.032596) (xy 31.946088 -212.032088)
			(xy 31.946088 -211.537804) (xy 31.946597 -211.532543) (xy 31.954035 -211.5251) (xy 31.959296 -211.524596)
			(xy 32.475424 -211.524596) (xy 32.483235 -211.524293) (xy 32.498106 -211.5195) (xy 32.504634 -211.515198)
			(xy 32.525723 -211.500849) (xy 32.571384 -211.478118) (xy 32.61999 -211.462659) (xy 32.670393 -211.454836)
			(xy 32.721399 -211.454836) (xy 32.771802 -211.462659) (xy 32.820408 -211.478118) (xy 32.866069 -211.500849)
			(xy 32.887158 -211.515198) (xy 32.893677 -211.51951) (xy 32.908557 -211.52428) (xy 32.916368 -211.524596)
			(xy 33.432496 -211.524596) (xy 33.437829 -211.52493) (xy 33.44537 -211.532471) (xy 33.445704 -211.537804)
			(xy 33.445704 -212.032342) (xy 39.489888 -212.032342) (xy 39.489888 -211.537804) (xy 39.490397 -211.532543)
			(xy 39.497835 -211.5251) (xy 39.503096 -211.524596) (xy 39.503604 -211.524596) (xy 40.019478 -211.524596)
			(xy 40.027287 -211.524274) (xy 40.042159 -211.519494) (xy 40.048688 -211.515198) (xy 40.069777 -211.500849)
			(xy 40.115438 -211.478118) (xy 40.164044 -211.462659) (xy 40.214447 -211.454836) (xy 40.265453 -211.454836)
			(xy 40.315856 -211.462659) (xy 40.364462 -211.478118) (xy 40.410123 -211.500849) (xy 40.431212 -211.515198)
			(xy 40.437742 -211.519492) (xy 40.452613 -211.524274) (xy 40.460422 -211.524596) (xy 40.97655 -211.524596)
			(xy 40.981838 -211.525152) (xy 40.989409 -211.53253) (xy 40.990012 -211.537804) (xy 40.990012 -212.032342)
			(xy 40.989987 -212.032596) (xy 47.034196 -212.032596) (xy 47.034196 -212.032088) (xy 47.034196 -211.537804)
			(xy 47.03453 -211.532471) (xy 47.042071 -211.52493) (xy 47.047404 -211.524596) (xy 47.563532 -211.524596)
			(xy 47.571339 -211.524254) (xy 47.586211 -211.519487) (xy 47.592742 -211.515198) (xy 47.613831 -211.500849)
			(xy 47.659492 -211.478118) (xy 47.708098 -211.462659) (xy 47.758501 -211.454836) (xy 47.809507 -211.454836)
			(xy 47.85991 -211.462659) (xy 47.908516 -211.478118) (xy 47.954177 -211.500849) (xy 47.975266 -211.515198)
			(xy 47.981806 -211.519475) (xy 47.996669 -211.524267) (xy 48.004476 -211.524596) (xy 48.520604 -211.524596)
			(xy 48.525868 -211.525092) (xy 48.533311 -211.532539) (xy 48.533812 -211.537804) (xy 48.533812 -212.032342)
			(xy 54.577996 -212.032342) (xy 54.577996 -211.537804) (xy 54.57833 -211.532471) (xy 54.585871 -211.52493)
			(xy 54.591204 -211.524596) (xy 56.064658 -211.524596) (xy 56.069947 -211.525146) (xy 56.077518 -211.532529)
			(xy 56.07812 -211.537804) (xy 56.07812 -212.032342) (xy 56.077673 -212.037721) (xy 56.07004 -212.045307)
			(xy 56.064658 -212.045804) (xy 54.591458 -212.045804) (xy 54.586099 -212.045282) (xy 54.578518 -212.037701)
			(xy 54.577996 -212.032342) (xy 48.533812 -212.032342) (xy 48.533399 -212.037663) (xy 48.525918 -212.045234)
			(xy 48.520604 -212.045804) (xy 48.00473 -212.045804) (xy 47.996921 -212.04613) (xy 47.982049 -212.050907)
			(xy 47.97552 -212.055202) (xy 47.954386 -212.069533) (xy 47.908667 -212.092265) (xy 47.859998 -212.107701)
			(xy 47.809534 -212.115472) (xy 47.784004 -212.115908) (xy 47.758474 -212.115462) (xy 47.708011 -212.107687)
			(xy 47.659339 -212.092261) (xy 47.613611 -212.069548) (xy 47.592488 -212.055202) (xy 47.585958 -212.050908)
			(xy 47.571087 -212.046126) (xy 47.563278 -212.045804) (xy 47.047404 -212.045804) (xy 47.042071 -212.04547)
			(xy 47.03453 -212.037929) (xy 47.034196 -212.032596) (xy 40.989987 -212.032596) (xy 40.989483 -212.037699)
			(xy 40.981907 -212.04528) (xy 40.97655 -212.045804) (xy 40.460676 -212.045804) (xy 40.452865 -212.046107)
			(xy 40.437994 -212.0509) (xy 40.431466 -212.055202) (xy 40.410347 -212.069556) (xy 40.364623 -212.092283)
			(xy 40.315949 -212.107712) (xy 40.265481 -212.115477) (xy 40.23995 -212.115908) (xy 40.214421 -212.115439)
			(xy 40.163959 -212.107671) (xy 40.115287 -212.092252) (xy 40.069557 -212.069545) (xy 40.048434 -212.055202)
			(xy 40.041894 -212.050925) (xy 40.027031 -212.046133) (xy 40.019224 -212.045804) (xy 39.50335 -212.045804)
			(xy 39.49799 -212.045287) (xy 39.49041 -212.037702) (xy 39.489888 -212.032342) (xy 33.445704 -212.032342)
			(xy 33.44521 -212.037641) (xy 33.437785 -212.045207) (xy 33.432496 -212.045804) (xy 32.916622 -212.045804)
			(xy 32.908813 -212.046126) (xy 32.893941 -212.050906) (xy 32.887412 -212.055202) (xy 32.866281 -212.069536)
			(xy 32.820561 -212.092268) (xy 32.77189 -212.107702) (xy 32.721426 -212.115473) (xy 32.695896 -212.115908)
			(xy 32.670366 -212.115466) (xy 32.619903 -212.10769) (xy 32.571231 -212.092263) (xy 32.525503 -212.069548)
			(xy 32.50438 -212.055202) (xy 32.497852 -212.050904) (xy 32.482979 -212.046125) (xy 32.47517 -212.045804)
			(xy 31.959296 -212.045804) (xy 31.954032 -212.045308) (xy 31.946589 -212.037861) (xy 31.946088 -212.032596)
			(xy 25.90188 -212.032596) (xy 25.90141 -212.037641) (xy 25.893985 -212.045207) (xy 25.888696 -212.045804)
			(xy 25.372822 -212.045804) (xy 25.365013 -212.046126) (xy 25.350141 -212.050906) (xy 25.343612 -212.055202)
			(xy 25.322481 -212.069536) (xy 25.276761 -212.092268) (xy 25.22809 -212.107702) (xy 25.177626 -212.115473)
			(xy 25.152096 -212.115908) (xy 25.126566 -212.115466) (xy 25.076103 -212.10769) (xy 25.027431 -212.092263)
			(xy 24.981703 -212.069548) (xy 24.96058 -212.055202) (xy 24.954052 -212.050904) (xy 24.939179 -212.046125)
			(xy 24.93137 -212.045804) (xy 24.415496 -212.045804) (xy 24.410232 -212.045308) (xy 24.402789 -212.037861)
			(xy 24.402288 -212.032596) (xy 18.358079 -212.032596) (xy 18.357582 -212.037701) (xy 18.350001 -212.045282)
			(xy 18.344642 -212.045804) (xy 17.828768 -212.045804) (xy 17.820961 -212.046146) (xy 17.806089 -212.050913)
			(xy 17.799558 -212.055202) (xy 17.778442 -212.06956) (xy 17.732716 -212.092286) (xy 17.684041 -212.107714)
			(xy 17.633574 -212.115477) (xy 17.608042 -212.115908) (xy 17.582513 -212.115443) (xy 17.532051 -212.107674)
			(xy 17.483378 -212.092253) (xy 17.437649 -212.069545) (xy 17.416526 -212.055202) (xy 17.409988 -212.050922)
			(xy 17.395123 -212.046132) (xy 17.387316 -212.045804) (xy 16.871442 -212.045804) (xy 16.866093 -212.045226)
			(xy 16.858507 -212.037688) (xy 16.85798 -212.032342) (xy 2.509012 -212.032342) (xy 2.509012 -212.88248)
			(xy 20.958048 -212.88248) (xy 20.958048 -212.387942) (xy 20.958409 -212.38251) (xy 20.966079 -212.374821)
			(xy 20.97151 -212.37448) (xy 21.487638 -212.37448) (xy 21.495446 -212.374143) (xy 21.510318 -212.369373)
			(xy 21.516848 -212.365082) (xy 21.537937 -212.350733) (xy 21.583598 -212.328002) (xy 21.632204 -212.312543)
			(xy 21.682607 -212.30472) (xy 21.733613 -212.30472) (xy 21.784016 -212.312543) (xy 21.832622 -212.328002)
			(xy 21.878283 -212.350733) (xy 21.899372 -212.365082) (xy 21.905912 -212.369359) (xy 21.920775 -212.374151)
			(xy 21.928582 -212.37448) (xy 22.44471 -212.37448) (xy 22.450156 -212.374777) (xy 22.457844 -212.382494)
			(xy 22.458172 -212.387942) (xy 22.458172 -212.88248) (xy 28.502356 -212.88248) (xy 28.502356 -212.387942)
			(xy 28.502853 -212.382639) (xy 28.510272 -212.375065) (xy 28.515564 -212.37448) (xy 29.031692 -212.37448)
			(xy 29.039502 -212.374166) (xy 29.054374 -212.369381) (xy 29.060902 -212.365082) (xy 29.081991 -212.350733)
			(xy 29.127652 -212.328002) (xy 29.176258 -212.312543) (xy 29.226661 -212.30472) (xy 29.277667 -212.30472)
			(xy 29.32807 -212.312543) (xy 29.376676 -212.328002) (xy 29.422337 -212.350733) (xy 29.443426 -212.365082)
			(xy 29.449954 -212.36938) (xy 29.464827 -212.374159) (xy 29.472636 -212.37448) (xy 29.988764 -212.37448)
			(xy 29.994089 -212.37485) (xy 30.001631 -212.382365) (xy 30.001972 -212.387688) (xy 30.001972 -212.388196)
			(xy 30.001972 -212.88248) (xy 36.046156 -212.88248) (xy 36.046156 -212.387942) (xy 36.046653 -212.382639)
			(xy 36.054072 -212.375065) (xy 36.059364 -212.37448) (xy 36.575492 -212.37448) (xy 36.583302 -212.374166)
			(xy 36.598174 -212.369381) (xy 36.604702 -212.365082) (xy 36.625791 -212.350733) (xy 36.671452 -212.328002)
			(xy 36.720058 -212.312543) (xy 36.770461 -212.30472) (xy 36.821467 -212.30472) (xy 36.87187 -212.312543)
			(xy 36.920476 -212.328002) (xy 36.966137 -212.350733) (xy 36.987226 -212.365082) (xy 36.993754 -212.36938)
			(xy 37.008627 -212.374159) (xy 37.016436 -212.37448) (xy 37.532564 -212.37448) (xy 37.537889 -212.37485)
			(xy 37.545431 -212.382365) (xy 37.545772 -212.387688) (xy 37.545772 -212.388196) (xy 37.545772 -212.88248)
			(xy 43.589956 -212.88248) (xy 43.589956 -212.387942) (xy 43.590309 -212.382508) (xy 43.597985 -212.374819)
			(xy 43.603418 -212.37448) (xy 44.119546 -212.37448) (xy 44.127354 -212.374147) (xy 44.142226 -212.369374)
			(xy 44.148756 -212.365082) (xy 44.169845 -212.350733) (xy 44.215506 -212.328002) (xy 44.264112 -212.312543)
			(xy 44.314515 -212.30472) (xy 44.365521 -212.30472) (xy 44.415924 -212.312543) (xy 44.46453 -212.328002)
			(xy 44.510191 -212.350733) (xy 44.53128 -212.365082) (xy 44.537818 -212.369362) (xy 44.552683 -212.374152)
			(xy 44.56049 -212.37448) (xy 45.076618 -212.37448) (xy 45.082066 -212.374771) (xy 45.089753 -212.382493)
			(xy 45.09008 -212.387942) (xy 45.09008 -212.88248) (xy 51.134264 -212.88248) (xy 51.134264 -212.387942)
			(xy 51.134754 -212.382637) (xy 51.142178 -212.375062) (xy 51.147472 -212.37448) (xy 51.6636 -212.37448)
			(xy 51.67141 -212.37417) (xy 51.686282 -212.369382) (xy 51.69281 -212.365082) (xy 51.713899 -212.350733)
			(xy 51.75956 -212.328002) (xy 51.808166 -212.312543) (xy 51.858569 -212.30472) (xy 51.909575 -212.30472)
			(xy 51.959978 -212.312543) (xy 52.008584 -212.328002) (xy 52.054245 -212.350733) (xy 52.075334 -212.365082)
			(xy 52.08186 -212.369383) (xy 52.096734 -212.37416) (xy 52.104544 -212.37448) (xy 52.620672 -212.37448)
			(xy 52.625998 -212.374844) (xy 52.63354 -212.382363) (xy 52.63388 -212.387688) (xy 52.63388 -212.388196)
			(xy 52.63388 -212.88248) (xy 58.678064 -212.88248) (xy 58.678064 -212.387942) (xy 58.67841 -212.382506)
			(xy 58.686091 -212.374817) (xy 58.691526 -212.37448) (xy 60.164726 -212.37448) (xy 60.170175 -212.374766)
			(xy 60.177862 -212.382492) (xy 60.178188 -212.387942) (xy 60.178188 -212.88248) (xy 60.177858 -212.887815)
			(xy 60.170315 -212.895358) (xy 60.16498 -212.895688) (xy 60.164472 -212.895688) (xy 58.691526 -212.895688)
			(xy 58.686231 -212.895163) (xy 58.678661 -212.887762) (xy 58.678064 -212.88248) (xy 52.63388 -212.88248)
			(xy 52.633557 -212.887816) (xy 52.626009 -212.89536) (xy 52.620672 -212.895688) (xy 52.104798 -212.895688)
			(xy 52.096923 -212.895976) (xy 52.081919 -212.900759) (xy 52.075334 -212.905086) (xy 52.054268 -212.919496)
			(xy 52.008619 -212.942319) (xy 51.960009 -212.957871) (xy 51.90959 -212.965785) (xy 51.884072 -212.9663)
			(xy 51.858553 -212.965791) (xy 51.808126 -212.957903) (xy 51.759515 -212.942348) (xy 51.713876 -212.919499)
			(xy 51.69281 -212.905086) (xy 51.686219 -212.900771) (xy 51.671218 -212.895984) (xy 51.663346 -212.895688)
			(xy 51.147472 -212.895688) (xy 51.142201 -212.895222) (xy 51.134759 -212.887753) (xy 51.134264 -212.88248)
			(xy 45.09008 -212.88248) (xy 45.089757 -212.887816) (xy 45.082209 -212.89536) (xy 45.076872 -212.895688)
			(xy 45.076364 -212.895688) (xy 44.560744 -212.895688) (xy 44.552867 -212.895953) (xy 44.537863 -212.900752)
			(xy 44.53128 -212.905086) (xy 44.510202 -212.919476) (xy 44.464557 -212.942303) (xy 44.415951 -212.957861)
			(xy 44.365535 -212.965782) (xy 44.340018 -212.9663) (xy 44.314497 -212.965818) (xy 44.26407 -212.957921)
			(xy 44.215459 -212.942359) (xy 44.169821 -212.919502) (xy 44.148756 -212.905086) (xy 44.142177 -212.90075)
			(xy 44.127167 -212.895976) (xy 44.119292 -212.895688) (xy 43.603418 -212.895688) (xy 43.598122 -212.895168)
			(xy 43.590552 -212.887764) (xy 43.589956 -212.88248) (xy 37.545772 -212.88248) (xy 37.545456 -212.887818)
			(xy 37.537903 -212.895363) (xy 37.532564 -212.895688) (xy 37.01669 -212.895688) (xy 37.008815 -212.895973)
			(xy 36.993811 -212.900758) (xy 36.987226 -212.905086) (xy 36.966163 -212.919499) (xy 36.920512 -212.942321)
			(xy 36.871902 -212.957873) (xy 36.821482 -212.965786) (xy 36.795964 -212.9663) (xy 36.770444 -212.965795)
			(xy 36.720018 -212.957905) (xy 36.671406 -212.94235) (xy 36.625767 -212.919499) (xy 36.604702 -212.905086)
			(xy 36.598113 -212.900768) (xy 36.583111 -212.895983) (xy 36.575238 -212.895688) (xy 36.059364 -212.895688)
			(xy 36.054092 -212.895227) (xy 36.046651 -212.887754) (xy 36.046156 -212.88248) (xy 30.001972 -212.88248)
			(xy 30.001656 -212.887818) (xy 29.994103 -212.895363) (xy 29.988764 -212.895688) (xy 29.47289 -212.895688)
			(xy 29.465015 -212.895973) (xy 29.450011 -212.900758) (xy 29.443426 -212.905086) (xy 29.422363 -212.919499)
			(xy 29.376712 -212.942321) (xy 29.328102 -212.957873) (xy 29.277682 -212.965786) (xy 29.252164 -212.9663)
			(xy 29.226644 -212.965795) (xy 29.176218 -212.957905) (xy 29.127606 -212.94235) (xy 29.081967 -212.919499)
			(xy 29.060902 -212.905086) (xy 29.054313 -212.900768) (xy 29.039311 -212.895983) (xy 29.031438 -212.895688)
			(xy 28.515564 -212.895688) (xy 28.510292 -212.895227) (xy 28.502851 -212.887754) (xy 28.502356 -212.88248)
			(xy 22.458172 -212.88248) (xy 22.457856 -212.887818) (xy 22.450303 -212.895363) (xy 22.444964 -212.895688)
			(xy 22.444456 -212.895688) (xy 21.928836 -212.895688) (xy 21.920959 -212.895949) (xy 21.905955 -212.90075)
			(xy 21.899372 -212.905086) (xy 21.878296 -212.919479) (xy 21.83265 -212.942306) (xy 21.784044 -212.957863)
			(xy 21.733627 -212.965782) (xy 21.70811 -212.9663) (xy 21.682589 -212.965822) (xy 21.632162 -212.957924)
			(xy 21.58355 -212.942361) (xy 21.537912 -212.919503) (xy 21.516848 -212.905086) (xy 21.510271 -212.900747)
			(xy 21.49526 -212.895975) (xy 21.487384 -212.895688) (xy 20.97151 -212.895688) (xy 20.966213 -212.895174)
			(xy 20.958643 -212.887765) (xy 20.958048 -212.88248) (xy 2.509012 -212.88248) (xy 2.509012 -212.98027)
			(xy 78.81214 -212.98027) (xy 78.81617 -212.837935) (xy 78.828245 -212.696055) (xy 78.848328 -212.555087)
			(xy 78.876355 -212.41548) (xy 78.912235 -212.277682) (xy 78.955853 -212.142135) (xy 79.00707 -212.009273)
			(xy 79.065721 -211.879521) (xy 79.131619 -211.753295) (xy 79.204553 -211.630999) (xy 79.28429 -211.513026)
			(xy 79.370572 -211.399753) (xy 79.463125 -211.291542) (xy 79.561652 -211.188741) (xy 79.665837 -211.091679)
			(xy 79.775346 -211.000667) (xy 79.889829 -210.915995) (xy 80.008919 -210.837937) (xy 80.132234 -210.766741)
			(xy 80.25938 -210.702635) (xy 80.389949 -210.645826) (xy 80.523523 -210.596494) (xy 80.659674 -210.554798)
			(xy 80.797965 -210.520872) (xy 80.937955 -210.494824) (xy 81.079194 -210.476738) (xy 81.22123 -210.466671)
			(xy 81.363608 -210.464656) (xy 81.505872 -210.470699) (xy 81.647566 -210.484781) (xy 81.788236 -210.506857)
			(xy 81.927433 -210.536857) (xy 82.064709 -210.574683) (xy 82.199625 -210.620215) (xy 82.331749 -210.673306)
			(xy 82.460658 -210.733788) (xy 82.585939 -210.801466) (xy 82.70719 -210.876123) (xy 82.824023 -210.957521)
			(xy 82.936064 -211.045398) (xy 83.042954 -211.139473) (xy 83.144351 -211.239445) (xy 83.239929 -211.344993)
			(xy 83.329383 -211.455779) (xy 83.412425 -211.571448) (xy 83.488791 -211.691631) (xy 83.558235 -211.815941)
			(xy 83.620535 -211.943982) (xy 83.675491 -212.075341) (xy 83.69835 -212.140038) (xy 94.106492 -212.140038)
			(xy 94.106492 -211.276438) (xy 94.106978 -211.249187) (xy 94.114734 -211.195239) (xy 94.130089 -211.142944)
			(xy 94.152731 -211.093367) (xy 94.182197 -211.047517) (xy 94.217888 -211.006326) (xy 94.259079 -210.970635)
			(xy 94.304929 -210.941169) (xy 94.354506 -210.918527) (xy 94.406801 -210.903172) (xy 94.460749 -210.895416)
			(xy 94.515251 -210.895416) (xy 94.569199 -210.903172) (xy 94.621494 -210.918527) (xy 94.671071 -210.941169)
			(xy 94.716921 -210.970635) (xy 94.758112 -211.006326) (xy 94.793803 -211.047517) (xy 94.823269 -211.093367)
			(xy 94.845911 -211.142944) (xy 94.861266 -211.195239) (xy 94.869022 -211.249187) (xy 94.869508 -211.276438)
			(xy 94.869508 -212.140038) (xy 94.869022 -212.167289) (xy 94.861266 -212.221237) (xy 94.845911 -212.273532)
			(xy 94.823269 -212.323109) (xy 94.793803 -212.368959) (xy 94.758112 -212.41015) (xy 94.716921 -212.445841)
			(xy 94.671071 -212.475307) (xy 94.621494 -212.497949) (xy 94.569199 -212.513304) (xy 94.515251 -212.52106)
			(xy 94.460749 -212.52106) (xy 94.406801 -212.513304) (xy 94.354506 -212.497949) (xy 94.304929 -212.475307)
			(xy 94.259079 -212.445841) (xy 94.217888 -212.41015) (xy 94.182197 -212.368959) (xy 94.152731 -212.323109)
			(xy 94.130089 -212.273532) (xy 94.114734 -212.221237) (xy 94.106978 -212.167289) (xy 94.106492 -212.140038)
			(xy 83.69835 -212.140038) (xy 83.722928 -212.2096) (xy 83.762692 -212.346327) (xy 83.794658 -212.485085)
			(xy 83.818723 -212.625429) (xy 83.834809 -212.76691) (xy 83.842864 -212.909074) (xy 83.843368 -212.98027)
			(xy 140.011408 -212.98027) (xy 140.015438 -212.837906) (xy 140.027516 -212.695998) (xy 140.047604 -212.555001)
			(xy 140.075636 -212.415366) (xy 140.111523 -212.27754) (xy 140.15515 -212.141966) (xy 140.206377 -212.009077)
			(xy 140.26504 -211.879298) (xy 140.330952 -211.753047) (xy 140.403901 -211.630727) (xy 140.483653 -211.51273)
			(xy 140.569953 -211.399434) (xy 140.662525 -211.291201) (xy 140.761071 -211.188379) (xy 140.865277 -211.091298)
			(xy 140.974809 -211.000267) (xy 141.089315 -210.915579) (xy 141.208429 -210.837504) (xy 141.331769 -210.766294)
			(xy 141.45894 -210.702175) (xy 141.589536 -210.645354) (xy 141.723136 -210.596013) (xy 141.859315 -210.554308)
			(xy 141.997634 -210.520375) (xy 142.137652 -210.494322) (xy 142.278919 -210.476232) (xy 142.420984 -210.466163)
			(xy 142.563391 -210.464148) (xy 142.705684 -210.470192) (xy 142.847406 -210.484278) (xy 142.988105 -210.506358)
			(xy 143.12733 -210.536363) (xy 143.264634 -210.574197) (xy 143.399577 -210.619738) (xy 143.531728 -210.672841)
			(xy 143.660663 -210.733335) (xy 143.785969 -210.801026) (xy 143.907245 -210.875699) (xy 144.024101 -210.957113)
			(xy 144.136165 -211.045007) (xy 144.243077 -211.139101) (xy 144.28731 -211.182712) (xy 163.678108 -211.182712)
			(xy 163.678108 -211.182204) (xy 163.678108 -210.68792) (xy 163.678442 -210.682586) (xy 163.685983 -210.675043)
			(xy 163.691316 -210.674712) (xy 165.164516 -210.674712) (xy 165.169855 -210.675018) (xy 165.177397 -210.68258)
			(xy 165.177724 -210.68792) (xy 165.177724 -211.182458) (xy 165.177701 -211.182712) (xy 167.778176 -211.182712)
			(xy 167.778176 -210.68792) (xy 167.778538 -210.682594) (xy 167.786059 -210.675053) (xy 167.791384 -210.674712)
			(xy 169.264584 -210.674712) (xy 169.269919 -210.67504) (xy 169.277462 -210.682585) (xy 169.277792 -210.68792)
			(xy 169.277792 -211.182458) (xy 171.221908 -211.182458) (xy 171.221908 -210.68792) (xy 171.222242 -210.682586)
			(xy 171.229783 -210.675043) (xy 171.235116 -210.674712) (xy 171.235624 -210.674712) (xy 171.751498 -210.674712)
			(xy 171.75931 -210.674412) (xy 171.774182 -210.669618) (xy 171.780708 -210.665314) (xy 171.801797 -210.650965)
			(xy 171.847458 -210.628234) (xy 171.896064 -210.612775) (xy 171.946467 -210.604952) (xy 171.997473 -210.604952)
			(xy 172.047876 -210.612775) (xy 172.096482 -210.628234) (xy 172.142143 -210.650965) (xy 172.163232 -210.665314)
			(xy 172.169762 -210.669608) (xy 172.184633 -210.674391) (xy 172.192442 -210.674712) (xy 172.70857 -210.674712)
			(xy 172.713864 -210.67524) (xy 172.721435 -210.682638) (xy 172.722032 -210.68792) (xy 172.722032 -211.182458)
			(xy 175.321976 -211.182458) (xy 175.321976 -210.68792) (xy 175.322338 -210.682594) (xy 175.329859 -210.675053)
			(xy 175.335184 -210.674712) (xy 175.335692 -210.674712) (xy 175.851566 -210.674712) (xy 175.859376 -210.674399)
			(xy 175.874248 -210.669614) (xy 175.880776 -210.665314) (xy 175.901865 -210.650965) (xy 175.947526 -210.628234)
			(xy 175.996132 -210.612775) (xy 176.046535 -210.604952) (xy 176.097541 -210.604952) (xy 176.147944 -210.612775)
			(xy 176.19655 -210.628234) (xy 176.242211 -210.650965) (xy 176.2633 -210.665314) (xy 176.269837 -210.669596)
			(xy 176.284703 -210.674386) (xy 176.29251 -210.674712) (xy 176.808638 -210.674712) (xy 176.81394 -210.675195)
			(xy 176.821507 -210.682628) (xy 176.8221 -210.68792) (xy 176.8221 -211.182458) (xy 176.822081 -211.182712)
			(xy 178.766216 -211.182712) (xy 178.766216 -211.182204) (xy 178.766216 -210.68792) (xy 178.766542 -210.682584)
			(xy 178.774088 -210.675041) (xy 178.779424 -210.674712) (xy 179.295552 -210.674712) (xy 179.303362 -210.674393)
			(xy 179.318234 -210.669612) (xy 179.324762 -210.665314) (xy 179.345851 -210.650965) (xy 179.391512 -210.628234)
			(xy 179.440118 -210.612775) (xy 179.490521 -210.604952) (xy 179.541527 -210.604952) (xy 179.59193 -210.612775)
			(xy 179.640536 -210.628234) (xy 179.686197 -210.650965) (xy 179.707286 -210.665314) (xy 179.713826 -210.66959)
			(xy 179.728689 -210.674384) (xy 179.736496 -210.674712) (xy 180.252624 -210.674712) (xy 180.257894 -210.675181)
			(xy 180.265337 -210.682648) (xy 180.265832 -210.68792) (xy 180.265832 -211.182458) (xy 180.265809 -211.182712)
			(xy 182.866284 -211.182712) (xy 182.866284 -211.182204) (xy 182.866284 -210.68792) (xy 182.866639 -210.682592)
			(xy 182.874165 -210.675051) (xy 182.879492 -210.674712) (xy 183.39562 -210.674712) (xy 183.403432 -210.674421)
			(xy 183.418304 -210.669621) (xy 183.42483 -210.665314) (xy 183.445919 -210.650965) (xy 183.49158 -210.628234)
			(xy 183.540186 -210.612775) (xy 183.590589 -210.604952) (xy 183.641595 -210.604952) (xy 183.691998 -210.612775)
			(xy 183.740604 -210.628234) (xy 183.786265 -210.650965) (xy 183.807354 -210.665314) (xy 183.813879 -210.669617)
			(xy 183.828754 -210.674394) (xy 183.836564 -210.674712) (xy 184.352692 -210.674712) (xy 184.358028 -210.675034)
			(xy 184.365571 -210.682584) (xy 184.3659 -210.68792) (xy 184.3659 -211.182458) (xy 186.310016 -211.182458)
			(xy 186.310016 -210.68792) (xy 186.310342 -210.682584) (xy 186.317888 -210.675041) (xy 186.323224 -210.674712)
			(xy 186.323732 -210.674712) (xy 186.839606 -210.674712) (xy 186.847418 -210.674416) (xy 186.86229 -210.669619)
			(xy 186.868816 -210.665314) (xy 186.889905 -210.650965) (xy 186.935566 -210.628234) (xy 186.984172 -210.612775)
			(xy 187.034575 -210.604952) (xy 187.085581 -210.604952) (xy 187.135984 -210.612775) (xy 187.18459 -210.628234)
			(xy 187.230251 -210.650965) (xy 187.25134 -210.665314) (xy 187.257868 -210.669611) (xy 187.272741 -210.674392)
			(xy 187.28055 -210.674712) (xy 187.796678 -210.674712) (xy 187.801973 -210.675234) (xy 187.809544 -210.682637)
			(xy 187.81014 -210.68792) (xy 187.81014 -211.182458) (xy 190.410084 -211.182458) (xy 190.410084 -210.68792)
			(xy 190.410439 -210.682592) (xy 190.417965 -210.675051) (xy 190.423292 -210.674712) (xy 190.4238 -210.674712)
			(xy 190.939674 -210.674712) (xy 190.947485 -210.674402) (xy 190.962357 -210.669615) (xy 190.968884 -210.665314)
			(xy 190.989973 -210.650965) (xy 191.035634 -210.628234) (xy 191.08424 -210.612775) (xy 191.134643 -210.604952)
			(xy 191.185649 -210.604952) (xy 191.236052 -210.612775) (xy 191.284658 -210.628234) (xy 191.330319 -210.650965)
			(xy 191.351408 -210.665314) (xy 191.357943 -210.669599) (xy 191.37281 -210.674388) (xy 191.380618 -210.674712)
			(xy 191.896746 -210.674712) (xy 191.902037 -210.675256) (xy 191.90961 -210.682642) (xy 191.910208 -210.68792)
			(xy 191.910208 -211.182458) (xy 191.91018 -211.182712) (xy 193.854324 -211.182712) (xy 193.854324 -211.182204)
			(xy 193.854324 -210.68792) (xy 193.854643 -210.682583) (xy 193.862194 -210.675038) (xy 193.867532 -210.674712)
			(xy 194.38366 -210.674712) (xy 194.39147 -210.674396) (xy 194.406342 -210.669613) (xy 194.41287 -210.665314)
			(xy 194.433959 -210.650965) (xy 194.47962 -210.628234) (xy 194.528226 -210.612775) (xy 194.578629 -210.604952)
			(xy 194.629635 -210.604952) (xy 194.680038 -210.612775) (xy 194.728644 -210.628234) (xy 194.774305 -210.650965)
			(xy 194.795394 -210.665314) (xy 194.801933 -210.669594) (xy 194.816797 -210.674385) (xy 194.824604 -210.674712)
			(xy 195.340732 -210.674712) (xy 195.346003 -210.675175) (xy 195.353445 -210.682647) (xy 195.35394 -210.68792)
			(xy 195.35394 -211.182458) (xy 195.353916 -211.182712) (xy 197.954392 -211.182712) (xy 197.954392 -211.182204)
			(xy 197.954392 -210.68792) (xy 197.95474 -210.68259) (xy 197.962271 -210.675048) (xy 197.9676 -210.674712)
			(xy 198.483728 -210.674712) (xy 198.491541 -210.674425) (xy 198.506413 -210.669622) (xy 198.512938 -210.665314)
			(xy 198.534027 -210.650965) (xy 198.579688 -210.628234) (xy 198.628294 -210.612775) (xy 198.678697 -210.604952)
			(xy 198.729703 -210.604952) (xy 198.780106 -210.612775) (xy 198.828712 -210.628234) (xy 198.874373 -210.650965)
			(xy 198.895462 -210.665314) (xy 198.902008 -210.669581) (xy 198.916867 -210.674381) (xy 198.924672 -210.674712)
			(xy 199.4408 -210.674712) (xy 199.446137 -210.675029) (xy 199.453679 -210.682582) (xy 199.454008 -210.68792)
			(xy 199.454008 -211.182458) (xy 199.453981 -211.182712) (xy 201.398124 -211.182712) (xy 201.398124 -211.182204)
			(xy 201.398124 -210.68792) (xy 201.398443 -210.682583) (xy 201.405994 -210.675038) (xy 201.411332 -210.674712)
			(xy 201.92746 -210.674712) (xy 201.93527 -210.674396) (xy 201.950142 -210.669613) (xy 201.95667 -210.665314)
			(xy 201.977759 -210.650965) (xy 202.02342 -210.628234) (xy 202.072026 -210.612775) (xy 202.122429 -210.604952)
			(xy 202.173435 -210.604952) (xy 202.223838 -210.612775) (xy 202.272444 -210.628234) (xy 202.318105 -210.650965)
			(xy 202.339194 -210.665314) (xy 202.345733 -210.669594) (xy 202.360597 -210.674385) (xy 202.368404 -210.674712)
			(xy 202.884532 -210.674712) (xy 202.889803 -210.675175) (xy 202.897245 -210.682647) (xy 202.89774 -210.68792)
			(xy 202.89774 -211.182458) (xy 202.897716 -211.182712) (xy 205.498192 -211.182712) (xy 205.498192 -211.182204)
			(xy 205.498192 -210.68792) (xy 205.49854 -210.68259) (xy 205.506071 -210.675048) (xy 205.5114 -210.674712)
			(xy 206.027528 -210.674712) (xy 206.035341 -210.674425) (xy 206.050213 -210.669622) (xy 206.056738 -210.665314)
			(xy 206.077827 -210.650965) (xy 206.123488 -210.628234) (xy 206.172094 -210.612775) (xy 206.222497 -210.604952)
			(xy 206.273503 -210.604952) (xy 206.323906 -210.612775) (xy 206.372512 -210.628234) (xy 206.418173 -210.650965)
			(xy 206.439262 -210.665314) (xy 206.445808 -210.669581) (xy 206.460667 -210.674381) (xy 206.468472 -210.674712)
			(xy 206.9846 -210.674712) (xy 206.989937 -210.675029) (xy 206.997479 -210.682582) (xy 206.997808 -210.68792)
			(xy 206.997808 -211.011516) (xy 255.545336 -211.011516) (xy 255.545336 -210.147916) (xy 255.545822 -210.120647)
			(xy 255.553584 -210.066663) (xy 255.568949 -210.014333) (xy 255.591606 -209.964723) (xy 255.621092 -209.918842)
			(xy 255.656807 -209.877625) (xy 255.698024 -209.84191) (xy 255.743905 -209.812424) (xy 255.793515 -209.789767)
			(xy 255.845845 -209.774402) (xy 255.899829 -209.76664) (xy 255.954367 -209.76664) (xy 256.008351 -209.774402)
			(xy 256.060681 -209.789767) (xy 256.110291 -209.812424) (xy 256.156172 -209.84191) (xy 256.197389 -209.877625)
			(xy 256.233104 -209.918842) (xy 256.26259 -209.964723) (xy 256.285247 -210.014333) (xy 256.300612 -210.066663)
			(xy 256.308374 -210.120647) (xy 256.30886 -210.147916) (xy 256.30886 -210.33232) (xy 268.898116 -210.33232)
			(xy 268.898116 -209.837782) (xy 268.898636 -209.832421) (xy 268.906217 -209.824838) (xy 268.911578 -209.82432)
			(xy 269.427706 -209.82432) (xy 269.435518 -209.824022) (xy 269.45039 -209.819227) (xy 269.456916 -209.814922)
			(xy 269.478005 -209.800573) (xy 269.523666 -209.777842) (xy 269.572272 -209.762383) (xy 269.622675 -209.75456)
			(xy 269.673681 -209.75456) (xy 269.724084 -209.762383) (xy 269.77269 -209.777842) (xy 269.818351 -209.800573)
			(xy 269.83944 -209.814922) (xy 269.845968 -209.81922) (xy 269.86084 -209.824) (xy 269.86865 -209.82432)
			(xy 270.384778 -209.82432) (xy 270.390205 -209.824692) (xy 270.397892 -209.832356) (xy 270.39824 -209.837782)
			(xy 270.39824 -210.33232) (xy 276.442424 -210.33232) (xy 276.442424 -209.837782) (xy 276.442909 -209.832479)
			(xy 276.450339 -209.82491) (xy 276.455632 -209.82432) (xy 276.97176 -209.82432) (xy 276.97957 -209.824003)
			(xy 276.994442 -209.819221) (xy 277.00097 -209.814922) (xy 277.022059 -209.800573) (xy 277.06772 -209.777842)
			(xy 277.116326 -209.762383) (xy 277.166729 -209.75456) (xy 277.217735 -209.75456) (xy 277.268138 -209.762383)
			(xy 277.316744 -209.777842) (xy 277.362405 -209.800573) (xy 277.383494 -209.814922) (xy 277.390032 -209.819202)
			(xy 277.404897 -209.823994) (xy 277.412704 -209.82432) (xy 277.928832 -209.82432) (xy 277.934105 -209.824776)
			(xy 277.941548 -209.832252) (xy 277.94204 -209.837528) (xy 277.94204 -209.838036) (xy 277.94204 -210.33232)
			(xy 283.986224 -210.33232) (xy 283.986224 -209.837782) (xy 283.986709 -209.832479) (xy 283.994139 -209.82491)
			(xy 283.999432 -209.82432) (xy 284.51556 -209.82432) (xy 284.52337 -209.824003) (xy 284.538242 -209.819221)
			(xy 284.54477 -209.814922) (xy 284.565859 -209.800573) (xy 284.61152 -209.777842) (xy 284.660126 -209.762383)
			(xy 284.710529 -209.75456) (xy 284.761535 -209.75456) (xy 284.811938 -209.762383) (xy 284.860544 -209.777842)
			(xy 284.906205 -209.800573) (xy 284.927294 -209.814922) (xy 284.933832 -209.819202) (xy 284.948697 -209.823994)
			(xy 284.956504 -209.82432) (xy 285.472632 -209.82432) (xy 285.477905 -209.824776) (xy 285.485348 -209.832252)
			(xy 285.48584 -209.837528) (xy 285.48584 -209.838036) (xy 285.48584 -210.33232) (xy 291.530024 -210.33232)
			(xy 291.530024 -209.837782) (xy 291.530537 -209.832419) (xy 291.538123 -209.824835) (xy 291.543486 -209.82432)
			(xy 292.059614 -209.82432) (xy 292.067426 -209.824026) (xy 292.082298 -209.819228) (xy 292.088824 -209.814922)
			(xy 292.109913 -209.800573) (xy 292.155574 -209.777842) (xy 292.20418 -209.762383) (xy 292.254583 -209.75456)
			(xy 292.305589 -209.75456) (xy 292.355992 -209.762383) (xy 292.404598 -209.777842) (xy 292.450259 -209.800573)
			(xy 292.471348 -209.814922) (xy 292.477874 -209.819223) (xy 292.492748 -209.824001) (xy 292.500558 -209.82432)
			(xy 293.016686 -209.82432) (xy 293.022044 -209.824858) (xy 293.029629 -209.832425) (xy 293.030148 -209.837782)
			(xy 293.030148 -210.33232) (xy 299.074332 -210.33232) (xy 299.074332 -209.837782) (xy 299.07481 -209.832477)
			(xy 299.082245 -209.824908) (xy 299.08754 -209.82432) (xy 299.603668 -209.82432) (xy 299.611478 -209.824006)
			(xy 299.62635 -209.819222) (xy 299.632878 -209.814922) (xy 299.653967 -209.800573) (xy 299.699628 -209.777842)
			(xy 299.748234 -209.762383) (xy 299.798637 -209.75456) (xy 299.849643 -209.75456) (xy 299.900046 -209.762383)
			(xy 299.948652 -209.777842) (xy 299.994313 -209.800573) (xy 300.015402 -209.814922) (xy 300.021938 -209.819205)
			(xy 300.036804 -209.823995) (xy 300.044612 -209.82432) (xy 300.56074 -209.82432) (xy 300.566014 -209.824771)
			(xy 300.573456 -209.832251) (xy 300.573948 -209.837528) (xy 300.573948 -209.838036) (xy 300.573948 -210.33232)
			(xy 306.618132 -210.33232) (xy 306.618132 -209.837782) (xy 306.618638 -209.832417) (xy 306.626229 -209.824833)
			(xy 306.631594 -209.82432) (xy 308.104794 -209.82432) (xy 308.110153 -209.824852) (xy 308.117738 -209.832424)
			(xy 308.118256 -209.837782) (xy 308.118256 -210.33232) (xy 415.718244 -210.33232) (xy 415.718244 -209.837782)
			(xy 415.718712 -209.832475) (xy 415.726154 -209.824904) (xy 415.731452 -209.82432) (xy 417.204652 -209.82432)
			(xy 417.209985 -209.824662) (xy 417.21753 -209.832196) (xy 417.21786 -209.837528) (xy 417.21786 -210.33232)
			(xy 423.262044 -210.33232) (xy 423.262044 -209.837782) (xy 423.262539 -209.832414) (xy 423.270138 -209.824829)
			(xy 423.275506 -209.82432) (xy 423.791634 -209.82432) (xy 423.799443 -209.823992) (xy 423.814315 -209.819217)
			(xy 423.820844 -209.814922) (xy 423.841933 -209.800573) (xy 423.887594 -209.777842) (xy 423.9362 -209.762383)
			(xy 423.986603 -209.75456) (xy 424.037609 -209.75456) (xy 424.088012 -209.762383) (xy 424.136618 -209.777842)
			(xy 424.182279 -209.800573) (xy 424.203368 -209.814922) (xy 424.209912 -209.819192) (xy 424.224772 -209.82399)
			(xy 424.232578 -209.82432) (xy 424.748706 -209.82432) (xy 424.754066 -209.824844) (xy 424.761651 -209.832422)
			(xy 424.762168 -209.837782) (xy 424.762168 -210.33232) (xy 430.806352 -210.33232) (xy 430.806352 -209.837782)
			(xy 430.806812 -209.832473) (xy 430.81426 -209.824902) (xy 430.81956 -209.82432) (xy 431.335688 -209.82432)
			(xy 431.343499 -209.824015) (xy 431.358371 -209.819224) (xy 431.364898 -209.814922) (xy 431.385987 -209.800573)
			(xy 431.431648 -209.777842) (xy 431.480254 -209.762383) (xy 431.530657 -209.75456) (xy 431.581663 -209.75456)
			(xy 431.632066 -209.762383) (xy 431.680672 -209.777842) (xy 431.726333 -209.800573) (xy 431.747422 -209.814922)
			(xy 431.753954 -209.819213) (xy 431.768823 -209.823998) (xy 431.776632 -209.82432) (xy 432.29276 -209.82432)
			(xy 432.298094 -209.824657) (xy 432.305639 -209.832195) (xy 432.305968 -209.837528) (xy 432.305968 -209.838036)
			(xy 432.305968 -210.33232) (xy 438.350152 -210.33232) (xy 438.350152 -209.837782) (xy 438.35064 -209.832412)
			(xy 438.358243 -209.824827) (xy 438.363614 -209.82432) (xy 438.879742 -209.82432) (xy 438.887551 -209.823995)
			(xy 438.902423 -209.819218) (xy 438.908952 -209.814922) (xy 438.930041 -209.800573) (xy 438.975702 -209.777842)
			(xy 439.024308 -209.762383) (xy 439.074711 -209.75456) (xy 439.125717 -209.75456) (xy 439.17612 -209.762383)
			(xy 439.224726 -209.777842) (xy 439.270387 -209.800573) (xy 439.291476 -209.814922) (xy 439.298018 -209.819195)
			(xy 439.31288 -209.823991) (xy 439.320686 -209.82432) (xy 439.836814 -209.82432) (xy 439.842175 -209.824839)
			(xy 439.849759 -209.832421) (xy 439.850276 -209.837782) (xy 439.850276 -210.33232) (xy 445.89446 -210.33232)
			(xy 445.89446 -209.837782) (xy 445.894913 -209.832471) (xy 445.902365 -209.8249) (xy 445.907668 -209.82432)
			(xy 446.423796 -209.82432) (xy 446.431607 -209.824018) (xy 446.446479 -209.819225) (xy 446.453006 -209.814922)
			(xy 446.474095 -209.800573) (xy 446.519756 -209.777842) (xy 446.568362 -209.762383) (xy 446.618765 -209.75456)
			(xy 446.669771 -209.75456) (xy 446.720174 -209.762383) (xy 446.76878 -209.777842) (xy 446.814441 -209.800573)
			(xy 446.83553 -209.814922) (xy 446.84206 -209.819216) (xy 446.856931 -209.823999) (xy 446.86474 -209.82432)
			(xy 447.380868 -209.82432) (xy 447.386203 -209.824651) (xy 447.393747 -209.832193) (xy 447.394076 -209.837528)
			(xy 447.394076 -209.838036) (xy 447.394076 -210.33232) (xy 453.43826 -210.33232) (xy 453.43826 -209.837782)
			(xy 453.438713 -209.832471) (xy 453.446165 -209.8249) (xy 453.451468 -209.82432) (xy 453.967596 -209.82432)
			(xy 453.975407 -209.824018) (xy 453.990279 -209.819225) (xy 453.996806 -209.814922) (xy 454.017895 -209.800573)
			(xy 454.063556 -209.777842) (xy 454.112162 -209.762383) (xy 454.162565 -209.75456) (xy 454.213571 -209.75456)
			(xy 454.263974 -209.762383) (xy 454.31258 -209.777842) (xy 454.358241 -209.800573) (xy 454.37933 -209.814922)
			(xy 454.38586 -209.819216) (xy 454.400731 -209.823999) (xy 454.40854 -209.82432) (xy 454.924668 -209.82432)
			(xy 454.930003 -209.824651) (xy 454.937547 -209.832193) (xy 454.937876 -209.837528) (xy 454.937876 -209.838036)
			(xy 454.937876 -210.33232) (xy 454.937583 -210.337663) (xy 454.930012 -210.345204) (xy 454.924668 -210.345528)
			(xy 454.408794 -210.345528) (xy 454.40092 -210.345825) (xy 454.385917 -210.350603) (xy 454.37933 -210.354926)
			(xy 454.358261 -210.36933) (xy 454.312613 -210.392156) (xy 454.264005 -210.407711) (xy 454.213585 -210.415625)
			(xy 454.188068 -210.41614) (xy 454.162549 -210.415626) (xy 454.112123 -210.407738) (xy 454.063512 -210.392185)
			(xy 454.017872 -210.369337) (xy 453.996806 -210.354926) (xy 453.990213 -210.350613) (xy 453.975214 -210.345825)
			(xy 453.967342 -210.345528) (xy 453.451468 -210.345528) (xy 453.446206 -210.345029) (xy 453.438767 -210.337582)
			(xy 453.43826 -210.33232) (xy 447.394076 -210.33232) (xy 447.393783 -210.337663) (xy 447.386212 -210.345204)
			(xy 447.380868 -210.345528) (xy 446.864994 -210.345528) (xy 446.85712 -210.345825) (xy 446.842117 -210.350603)
			(xy 446.83553 -210.354926) (xy 446.814461 -210.36933) (xy 446.768813 -210.392156) (xy 446.720205 -210.407711)
			(xy 446.669785 -210.415625) (xy 446.644268 -210.41614) (xy 446.618749 -210.415626) (xy 446.568323 -210.407738)
			(xy 446.519712 -210.392185) (xy 446.474072 -210.369337) (xy 446.453006 -210.354926) (xy 446.446413 -210.350613)
			(xy 446.431414 -210.345825) (xy 446.423542 -210.345528) (xy 445.907668 -210.345528) (xy 445.902406 -210.345029)
			(xy 445.894967 -210.337582) (xy 445.89446 -210.33232) (xy 439.850276 -210.33232) (xy 439.849983 -210.337663)
			(xy 439.842412 -210.345204) (xy 439.837068 -210.345528) (xy 439.83656 -210.345528) (xy 439.32094 -210.345528)
			(xy 439.313064 -210.345801) (xy 439.29806 -210.350595) (xy 439.291476 -210.354926) (xy 439.270394 -210.36931)
			(xy 439.224751 -210.392141) (xy 439.176146 -210.407701) (xy 439.12573 -210.415622) (xy 439.100214 -210.41614)
			(xy 439.074694 -210.415653) (xy 439.024267 -210.407757) (xy 438.975656 -210.392196) (xy 438.930017 -210.369341)
			(xy 438.908952 -210.354926) (xy 438.902371 -210.350592) (xy 438.887363 -210.345817) (xy 438.879488 -210.345528)
			(xy 438.363614 -210.345528) (xy 438.358304 -210.345064) (xy 438.35073 -210.337621) (xy 438.350152 -210.33232)
			(xy 432.305968 -210.33232) (xy 432.305683 -210.337665) (xy 432.298106 -210.345207) (xy 432.29276 -210.345528)
			(xy 431.776886 -210.345528) (xy 431.769012 -210.345821) (xy 431.754008 -210.350602) (xy 431.747422 -210.354926)
			(xy 431.726355 -210.369334) (xy 431.680707 -210.392159) (xy 431.632097 -210.407712) (xy 431.581678 -210.415626)
			(xy 431.55616 -210.41614) (xy 431.530641 -210.41563) (xy 431.480215 -210.40774) (xy 431.431603 -210.392186)
			(xy 431.385964 -210.369338) (xy 431.364898 -210.354926) (xy 431.358307 -210.35061) (xy 431.343307 -210.345824)
			(xy 431.335434 -210.345528) (xy 430.81956 -210.345528) (xy 430.814297 -210.345034) (xy 430.806858 -210.337584)
			(xy 430.806352 -210.33232) (xy 424.762168 -210.33232) (xy 424.761883 -210.337665) (xy 424.754306 -210.345207)
			(xy 424.74896 -210.345528) (xy 424.748452 -210.345528) (xy 424.232832 -210.345528) (xy 424.224956 -210.345798)
			(xy 424.209952 -210.350594) (xy 424.203368 -210.354926) (xy 424.182288 -210.369314) (xy 424.136644 -210.392144)
			(xy 424.088039 -210.407703) (xy 424.037623 -210.415622) (xy 424.012106 -210.41614) (xy 423.986586 -210.415657)
			(xy 423.936159 -210.407759) (xy 423.887547 -210.392197) (xy 423.841909 -210.369341) (xy 423.820844 -210.354926)
			(xy 423.814265 -210.350589) (xy 423.799255 -210.345816) (xy 423.79138 -210.345528) (xy 423.275506 -210.345528)
			(xy 423.270195 -210.345069) (xy 423.262622 -210.337622) (xy 423.262044 -210.33232) (xy 417.21786 -210.33232)
			(xy 417.217582 -210.337667) (xy 417.21 -210.345209) (xy 417.204652 -210.345528) (xy 415.731452 -210.345528)
			(xy 415.726188 -210.345039) (xy 415.71875 -210.337585) (xy 415.718244 -210.33232) (xy 308.118256 -210.33232)
			(xy 308.117723 -210.337574) (xy 308.110301 -210.345012) (xy 308.105048 -210.345528) (xy 308.10454 -210.345528)
			(xy 306.631594 -210.345528) (xy 306.626282 -210.345077) (xy 306.618709 -210.337624) (xy 306.618132 -210.33232)
			(xy 300.573948 -210.33232) (xy 300.573423 -210.337576) (xy 300.565995 -210.345015) (xy 300.56074 -210.345528)
			(xy 300.044866 -210.345528) (xy 300.036991 -210.345812) (xy 300.021987 -210.350599) (xy 300.015402 -210.354926)
			(xy 299.994313 -210.369299) (xy 299.948672 -210.392132) (xy 299.90007 -210.407695) (xy 299.849656 -210.41562)
			(xy 299.82414 -210.41614) (xy 299.79862 -210.41564) (xy 299.748194 -210.407747) (xy 299.699583 -210.39219)
			(xy 299.653944 -210.369339) (xy 299.632878 -210.354926) (xy 299.626292 -210.350602) (xy 299.611288 -210.345821)
			(xy 299.603414 -210.345528) (xy 299.08754 -210.345528) (xy 299.082218 -210.345148) (xy 299.074676 -210.33764)
			(xy 299.074332 -210.33232) (xy 293.030148 -210.33232) (xy 293.029623 -210.337576) (xy 293.022195 -210.345015)
			(xy 293.01694 -210.345528) (xy 293.016432 -210.345528) (xy 292.500812 -210.345528) (xy 292.492939 -210.345832)
			(xy 292.477935 -210.350605) (xy 292.471348 -210.354926) (xy 292.450274 -210.369322) (xy 292.404628 -210.39215)
			(xy 292.356021 -210.407707) (xy 292.305603 -210.415624) (xy 292.280086 -210.41614) (xy 292.254567 -210.415617)
			(xy 292.204142 -210.407731) (xy 292.15553 -210.392181) (xy 292.10989 -210.369336) (xy 292.088824 -210.354926)
			(xy 292.082227 -210.35062) (xy 292.067231 -210.345827) (xy 292.05936 -210.345528) (xy 291.543486 -210.345528)
			(xy 291.538173 -210.345082) (xy 291.530601 -210.337625) (xy 291.530024 -210.33232) (xy 285.48584 -210.33232)
			(xy 285.485322 -210.337577) (xy 285.477889 -210.345017) (xy 285.472632 -210.345528) (xy 284.956758 -210.345528)
			(xy 284.948883 -210.345809) (xy 284.933879 -210.350597) (xy 284.927294 -210.354926) (xy 284.906207 -210.369303)
			(xy 284.860566 -210.392135) (xy 284.811963 -210.407697) (xy 284.761548 -210.415621) (xy 284.736032 -210.41614)
			(xy 284.710512 -210.415644) (xy 284.660086 -210.40775) (xy 284.611474 -210.392192) (xy 284.565836 -210.36934)
			(xy 284.54477 -210.354926) (xy 284.538185 -210.350599) (xy 284.52318 -210.345819) (xy 284.515306 -210.345528)
			(xy 283.999432 -210.345528) (xy 283.994109 -210.345154) (xy 283.986567 -210.337642) (xy 283.986224 -210.33232)
			(xy 277.94204 -210.33232) (xy 277.941522 -210.337577) (xy 277.934089 -210.345017) (xy 277.928832 -210.345528)
			(xy 277.412958 -210.345528) (xy 277.405083 -210.345809) (xy 277.390079 -210.350597) (xy 277.383494 -210.354926)
			(xy 277.362407 -210.369303) (xy 277.316766 -210.392135) (xy 277.268163 -210.407697) (xy 277.217748 -210.415621)
			(xy 277.192232 -210.41614) (xy 277.166712 -210.415644) (xy 277.116286 -210.40775) (xy 277.067674 -210.392192)
			(xy 277.022036 -210.36934) (xy 277.00097 -210.354926) (xy 276.994385 -210.350599) (xy 276.97938 -210.345819)
			(xy 276.971506 -210.345528) (xy 276.455632 -210.345528) (xy 276.450309 -210.345154) (xy 276.442767 -210.337642)
			(xy 276.442424 -210.33232) (xy 270.39824 -210.33232) (xy 270.397722 -210.337577) (xy 270.390289 -210.345017)
			(xy 270.385032 -210.345528) (xy 270.384524 -210.345528) (xy 269.868904 -210.345528) (xy 269.861031 -210.345829)
			(xy 269.846027 -210.350604) (xy 269.83944 -210.354926) (xy 269.818368 -210.369326) (xy 269.772721 -210.392153)
			(xy 269.724114 -210.407709) (xy 269.673695 -210.415625) (xy 269.648178 -210.41614) (xy 269.622659 -210.415621)
			(xy 269.572234 -210.407734) (xy 269.523622 -210.392183) (xy 269.477982 -210.369337) (xy 269.456916 -210.354926)
			(xy 269.450321 -210.350617) (xy 269.435324 -210.345826) (xy 269.427452 -210.345528) (xy 268.911578 -210.345528)
			(xy 268.906264 -210.345088) (xy 268.898692 -210.337626) (xy 268.898116 -210.33232) (xy 256.30886 -210.33232)
			(xy 256.30886 -211.011516) (xy 256.308374 -211.038785) (xy 256.300612 -211.092769) (xy 256.285247 -211.145099)
			(xy 256.268301 -211.182204) (xy 264.798048 -211.182204) (xy 264.798048 -210.687666) (xy 264.798529 -210.682296)
			(xy 264.806138 -210.674711) (xy 264.81151 -210.674204) (xy 265.327638 -210.674204) (xy 265.335446 -210.673863)
			(xy 265.350317 -210.669096) (xy 265.356848 -210.664806) (xy 265.377937 -210.650457) (xy 265.423598 -210.627726)
			(xy 265.472204 -210.612267) (xy 265.522607 -210.604444) (xy 265.573613 -210.604444) (xy 265.624016 -210.612267)
			(xy 265.672622 -210.627726) (xy 265.718283 -210.650457) (xy 265.739372 -210.664806) (xy 265.74591 -210.669086)
			(xy 265.760775 -210.673876) (xy 265.768582 -210.674204) (xy 266.28471 -210.674204) (xy 266.290067 -210.67474)
			(xy 266.29765 -210.68231) (xy 266.298172 -210.687666) (xy 266.298172 -211.182204) (xy 268.898116 -211.182204)
			(xy 268.898116 -210.687666) (xy 268.898626 -210.682303) (xy 268.906215 -210.674721) (xy 268.911578 -210.674204)
			(xy 269.427706 -210.674204) (xy 269.435516 -210.673892) (xy 269.450388 -210.669105) (xy 269.456916 -210.664806)
			(xy 269.478005 -210.650457) (xy 269.523666 -210.627726) (xy 269.572272 -210.612267) (xy 269.622675 -210.604444)
			(xy 269.673681 -210.604444) (xy 269.724084 -210.612267) (xy 269.77269 -210.627726) (xy 269.818351 -210.650457)
			(xy 269.83944 -210.664806) (xy 269.845963 -210.669112) (xy 269.86084 -210.673886) (xy 269.86865 -210.674204)
			(xy 270.384778 -210.674204) (xy 270.390131 -210.674762) (xy 270.397716 -210.682315) (xy 270.39824 -210.687666)
			(xy 270.39824 -211.182204) (xy 272.342356 -211.182204) (xy 272.342356 -210.687666) (xy 272.342802 -210.682354)
			(xy 272.35026 -210.674784) (xy 272.355564 -210.674204) (xy 272.871692 -210.674204) (xy 272.879502 -210.673886)
			(xy 272.894373 -210.669103) (xy 272.900902 -210.664806) (xy 272.921991 -210.650457) (xy 272.967652 -210.627726)
			(xy 273.016258 -210.612267) (xy 273.066661 -210.604444) (xy 273.117667 -210.604444) (xy 273.16807 -210.612267)
			(xy 273.216676 -210.627726) (xy 273.262337 -210.650457) (xy 273.283426 -210.664806) (xy 273.289952 -210.669107)
			(xy 273.304826 -210.673884) (xy 273.312636 -210.674204) (xy 273.828764 -210.674204) (xy 273.834094 -210.674552)
			(xy 273.841638 -210.682082) (xy 273.841972 -210.687412) (xy 273.841972 -210.68792) (xy 273.841972 -211.182204)
			(xy 276.442424 -211.182204) (xy 276.442424 -210.687666) (xy 276.442899 -210.682361) (xy 276.450337 -210.674793)
			(xy 276.455632 -210.674204) (xy 276.97176 -210.674204) (xy 276.979568 -210.673873) (xy 276.99444 -210.669099)
			(xy 277.00097 -210.664806) (xy 277.022059 -210.650457) (xy 277.06772 -210.627726) (xy 277.116326 -210.612267)
			(xy 277.166729 -210.604444) (xy 277.217735 -210.604444) (xy 277.268138 -210.612267) (xy 277.316744 -210.627726)
			(xy 277.362405 -210.650457) (xy 277.383494 -210.664806) (xy 277.390027 -210.669094) (xy 277.404896 -210.673879)
			(xy 277.412704 -210.674204) (xy 277.928832 -210.674204) (xy 277.934102 -210.674675) (xy 277.941543 -210.682141)
			(xy 277.94204 -210.687412) (xy 277.94204 -210.68792) (xy 277.94204 -211.182204) (xy 279.886156 -211.182204)
			(xy 279.886156 -210.687666) (xy 279.886602 -210.682354) (xy 279.89406 -210.674784) (xy 279.899364 -210.674204)
			(xy 280.415492 -210.674204) (xy 280.423302 -210.673886) (xy 280.438173 -210.669103) (xy 280.444702 -210.664806)
			(xy 280.465791 -210.650457) (xy 280.511452 -210.627726) (xy 280.560058 -210.612267) (xy 280.610461 -210.604444)
			(xy 280.661467 -210.604444) (xy 280.71187 -210.612267) (xy 280.760476 -210.627726) (xy 280.806137 -210.650457)
			(xy 280.827226 -210.664806) (xy 280.833752 -210.669107) (xy 280.848626 -210.673884) (xy 280.856436 -210.674204)
			(xy 281.372564 -210.674204) (xy 281.377894 -210.674552) (xy 281.385438 -210.682082) (xy 281.385772 -210.687412)
			(xy 281.385772 -210.68792) (xy 281.385772 -211.182204) (xy 283.986224 -211.182204) (xy 283.986224 -210.687666)
			(xy 283.986699 -210.682361) (xy 283.994137 -210.674793) (xy 283.999432 -210.674204) (xy 284.51556 -210.674204)
			(xy 284.523368 -210.673873) (xy 284.53824 -210.669099) (xy 284.54477 -210.664806) (xy 284.565859 -210.650457)
			(xy 284.61152 -210.627726) (xy 284.660126 -210.612267) (xy 284.710529 -210.604444) (xy 284.761535 -210.604444)
			(xy 284.811938 -210.612267) (xy 284.860544 -210.627726) (xy 284.906205 -210.650457) (xy 284.927294 -210.664806)
			(xy 284.933827 -210.669094) (xy 284.948696 -210.673879) (xy 284.956504 -210.674204) (xy 285.472632 -210.674204)
			(xy 285.477902 -210.674675) (xy 285.485343 -210.682141) (xy 285.48584 -210.687412) (xy 285.48584 -210.68792)
			(xy 285.48584 -211.182204) (xy 287.429956 -211.182204) (xy 287.429956 -210.687666) (xy 287.43043 -210.682294)
			(xy 287.438044 -210.674709) (xy 287.443418 -210.674204) (xy 287.959546 -210.674204) (xy 287.967354 -210.673867)
			(xy 287.982225 -210.669097) (xy 287.988756 -210.664806) (xy 288.009845 -210.650457) (xy 288.055506 -210.627726)
			(xy 288.104112 -210.612267) (xy 288.154515 -210.604444) (xy 288.205521 -210.604444) (xy 288.255924 -210.612267)
			(xy 288.30453 -210.627726) (xy 288.350191 -210.650457) (xy 288.37128 -210.664806) (xy 288.377816 -210.669089)
			(xy 288.392683 -210.673877) (xy 288.40049 -210.674204) (xy 288.916618 -210.674204) (xy 288.921976 -210.674735)
			(xy 288.929559 -210.682309) (xy 288.93008 -210.687666) (xy 288.93008 -211.182204) (xy 291.530024 -211.182204)
			(xy 291.530024 -210.687666) (xy 291.530526 -210.682301) (xy 291.538121 -210.674718) (xy 291.543486 -210.674204)
			(xy 292.059614 -210.674204) (xy 292.067425 -210.673896) (xy 292.082296 -210.669106) (xy 292.088824 -210.664806)
			(xy 292.109913 -210.650457) (xy 292.155574 -210.627726) (xy 292.20418 -210.612267) (xy 292.254583 -210.604444)
			(xy 292.305589 -210.604444) (xy 292.355992 -210.612267) (xy 292.404598 -210.627726) (xy 292.450259 -210.650457)
			(xy 292.471348 -210.664806) (xy 292.477869 -210.669115) (xy 292.492747 -210.673887) (xy 292.500558 -210.674204)
			(xy 293.016686 -210.674204) (xy 293.02204 -210.674756) (xy 293.029625 -210.682314) (xy 293.030148 -210.687666)
			(xy 293.030148 -211.182204) (xy 294.974264 -211.182204) (xy 294.974264 -210.687666) (xy 294.974703 -210.682352)
			(xy 294.982166 -210.674782) (xy 294.987472 -210.674204) (xy 295.5036 -210.674204) (xy 295.51141 -210.67389)
			(xy 295.526281 -210.669104) (xy 295.53281 -210.664806) (xy 295.553899 -210.650457) (xy 295.59956 -210.627726)
			(xy 295.648166 -210.612267) (xy 295.698569 -210.604444) (xy 295.749575 -210.604444) (xy 295.799978 -210.612267)
			(xy 295.848584 -210.627726) (xy 295.894245 -210.650457) (xy 295.915334 -210.664806) (xy 295.921858 -210.66911)
			(xy 295.936734 -210.673885) (xy 295.944544 -210.674204) (xy 296.460672 -210.674204) (xy 296.466003 -210.674547)
			(xy 296.473547 -210.682081) (xy 296.47388 -210.687412) (xy 296.47388 -210.68792) (xy 296.47388 -211.182204)
			(xy 299.074332 -211.182204) (xy 299.074332 -210.687666) (xy 299.0748 -210.68236) (xy 299.082243 -210.674791)
			(xy 299.08754 -210.674204) (xy 299.603668 -210.674204) (xy 299.611477 -210.673876) (xy 299.626348 -210.6691)
			(xy 299.632878 -210.664806) (xy 299.653967 -210.650457) (xy 299.699628 -210.627726) (xy 299.748234 -210.612267)
			(xy 299.798637 -210.604444) (xy 299.849643 -210.604444) (xy 299.900046 -210.612267) (xy 299.948652 -210.627726)
			(xy 299.994313 -210.650457) (xy 300.015402 -210.664806) (xy 300.021933 -210.669097) (xy 300.036804 -210.67388)
			(xy 300.044612 -210.674204) (xy 300.56074 -210.674204) (xy 300.566011 -210.674669) (xy 300.573452 -210.68214)
			(xy 300.573948 -210.687412) (xy 300.573948 -210.68792) (xy 300.573948 -211.182204) (xy 302.518064 -211.182204)
			(xy 302.518064 -210.687666) (xy 302.51853 -210.682292) (xy 302.52615 -210.674706) (xy 302.531526 -210.674204)
			(xy 304.004726 -210.674204) (xy 304.010085 -210.67473) (xy 304.017667 -210.682307) (xy 304.018188 -210.687666)
			(xy 304.018188 -211.182204) (xy 306.618132 -211.182204) (xy 306.618132 -210.687666) (xy 306.618627 -210.682299)
			(xy 306.626226 -210.674716) (xy 306.631594 -210.674204) (xy 308.104794 -210.674204) (xy 308.110149 -210.674751)
			(xy 308.117733 -210.682312) (xy 308.118256 -210.687666) (xy 308.118256 -211.182204) (xy 308.117713 -211.187456)
			(xy 308.110298 -211.194895) (xy 308.105048 -211.195412) (xy 308.10454 -211.195412) (xy 306.631594 -211.195412)
			(xy 306.626278 -211.194975) (xy 306.618704 -211.187512) (xy 306.618132 -211.182204) (xy 304.018188 -211.182204)
			(xy 304.017874 -211.187542) (xy 304.010318 -211.195083) (xy 304.00498 -211.195412) (xy 302.531526 -211.195412)
			(xy 302.526214 -211.194954) (xy 302.518638 -211.187507) (xy 302.518064 -211.182204) (xy 300.573948 -211.182204)
			(xy 300.573412 -211.187458) (xy 300.565992 -211.194898) (xy 300.56074 -211.195412) (xy 300.044866 -211.195412)
			(xy 300.036992 -211.195699) (xy 300.021988 -211.200484) (xy 300.015402 -211.20481) (xy 299.994311 -211.219181)
			(xy 299.948672 -211.242015) (xy 299.90007 -211.257579) (xy 299.849656 -211.265504) (xy 299.82414 -211.266024)
			(xy 299.79862 -211.265527) (xy 299.748194 -211.257634) (xy 299.699582 -211.242076) (xy 299.653943 -211.219224)
			(xy 299.632878 -211.20481) (xy 299.626293 -211.200485) (xy 299.611288 -211.195704) (xy 299.603414 -211.195412)
			(xy 299.08754 -211.195412) (xy 299.082214 -211.195047) (xy 299.074671 -211.187529) (xy 299.074332 -211.182204)
			(xy 296.47388 -211.182204) (xy 296.473573 -211.187544) (xy 296.466012 -211.195086) (xy 296.460672 -211.195412)
			(xy 295.944798 -211.195412) (xy 295.936925 -211.195713) (xy 295.921921 -211.200488) (xy 295.915334 -211.20481)
			(xy 295.894262 -211.219211) (xy 295.848616 -211.242038) (xy 295.800008 -211.257593) (xy 295.749589 -211.265509)
			(xy 295.724072 -211.266024) (xy 295.698553 -211.265511) (xy 295.648127 -211.257623) (xy 295.599515 -211.24207)
			(xy 295.553876 -211.219222) (xy 295.53281 -211.20481) (xy 295.526217 -211.200497) (xy 295.511218 -211.195709)
			(xy 295.503346 -211.195412) (xy 294.987472 -211.195412) (xy 294.982207 -211.194924) (xy 294.974766 -211.18747)
			(xy 294.974264 -211.182204) (xy 293.030148 -211.182204) (xy 293.029612 -211.187458) (xy 293.022192 -211.194898)
			(xy 293.01694 -211.195412) (xy 293.016432 -211.195412) (xy 292.500812 -211.195412) (xy 292.492939 -211.195719)
			(xy 292.477936 -211.20049) (xy 292.471348 -211.20481) (xy 292.450272 -211.219204) (xy 292.404627 -211.242033)
			(xy 292.356021 -211.257591) (xy 292.305603 -211.265508) (xy 292.280086 -211.266024) (xy 292.254567 -211.265504)
			(xy 292.204142 -211.257618) (xy 292.15553 -211.242067) (xy 292.10989 -211.219221) (xy 292.088824 -211.20481)
			(xy 292.082228 -211.200502) (xy 292.067232 -211.195711) (xy 292.05936 -211.195412) (xy 291.543486 -211.195412)
			(xy 291.538169 -211.19498) (xy 291.530596 -211.187513) (xy 291.530024 -211.182204) (xy 288.93008 -211.182204)
			(xy 288.929773 -211.187544) (xy 288.922212 -211.195086) (xy 288.916872 -211.195412) (xy 288.916364 -211.195412)
			(xy 288.400744 -211.195412) (xy 288.392869 -211.19569) (xy 288.377865 -211.200481) (xy 288.37128 -211.20481)
			(xy 288.350195 -211.219191) (xy 288.304554 -211.242023) (xy 288.25595 -211.257584) (xy 288.205534 -211.265506)
			(xy 288.180018 -211.266024) (xy 288.154498 -211.265538) (xy 288.104071 -211.257642) (xy 288.055459 -211.24208)
			(xy 288.009821 -211.219225) (xy 287.988756 -211.20481) (xy 287.982176 -211.200476) (xy 287.967167 -211.195701)
			(xy 287.959292 -211.195412) (xy 287.443418 -211.195412) (xy 287.438105 -211.194959) (xy 287.43053 -211.187509)
			(xy 287.429956 -211.182204) (xy 285.48584 -211.182204) (xy 285.485311 -211.18746) (xy 285.477887 -211.1949)
			(xy 285.472632 -211.195412) (xy 284.956758 -211.195412) (xy 284.948883 -211.195696) (xy 284.93388 -211.200483)
			(xy 284.927294 -211.20481) (xy 284.906206 -211.219185) (xy 284.860565 -211.242018) (xy 284.811962 -211.257581)
			(xy 284.761548 -211.265505) (xy 284.736032 -211.266024) (xy 284.710512 -211.265531) (xy 284.660085 -211.257637)
			(xy 284.611474 -211.242078) (xy 284.565835 -211.219224) (xy 284.54477 -211.20481) (xy 284.538186 -211.200481)
			(xy 284.52318 -211.195703) (xy 284.515306 -211.195412) (xy 283.999432 -211.195412) (xy 283.994105 -211.195052)
			(xy 283.986563 -211.18753) (xy 283.986224 -211.182204) (xy 281.385772 -211.182204) (xy 281.385472 -211.187546)
			(xy 281.377907 -211.195088) (xy 281.372564 -211.195412) (xy 280.85669 -211.195412) (xy 280.848816 -211.195709)
			(xy 280.833813 -211.200487) (xy 280.827226 -211.20481) (xy 280.806157 -211.219214) (xy 280.760509 -211.242041)
			(xy 280.711901 -211.257595) (xy 280.661481 -211.26551) (xy 280.635964 -211.266024) (xy 280.610445 -211.265515)
			(xy 280.560019 -211.257626) (xy 280.511407 -211.242071) (xy 280.465768 -211.219222) (xy 280.444702 -211.20481)
			(xy 280.438111 -211.200494) (xy 280.423111 -211.195708) (xy 280.415238 -211.195412) (xy 279.899364 -211.195412)
			(xy 279.894098 -211.194929) (xy 279.886658 -211.187471) (xy 279.886156 -211.182204) (xy 277.94204 -211.182204)
			(xy 277.941511 -211.18746) (xy 277.934087 -211.1949) (xy 277.928832 -211.195412) (xy 277.412958 -211.195412)
			(xy 277.405083 -211.195696) (xy 277.39008 -211.200483) (xy 277.383494 -211.20481) (xy 277.362406 -211.219185)
			(xy 277.316765 -211.242018) (xy 277.268162 -211.257581) (xy 277.217748 -211.265505) (xy 277.192232 -211.266024)
			(xy 277.166712 -211.265531) (xy 277.116285 -211.257637) (xy 277.067674 -211.242078) (xy 277.022035 -211.219224)
			(xy 277.00097 -211.20481) (xy 276.994386 -211.200481) (xy 276.97938 -211.195703) (xy 276.971506 -211.195412)
			(xy 276.455632 -211.195412) (xy 276.450305 -211.195052) (xy 276.442763 -211.18753) (xy 276.442424 -211.182204)
			(xy 273.841972 -211.182204) (xy 273.841672 -211.187546) (xy 273.834107 -211.195088) (xy 273.828764 -211.195412)
			(xy 273.31289 -211.195412) (xy 273.305016 -211.195709) (xy 273.290013 -211.200487) (xy 273.283426 -211.20481)
			(xy 273.262357 -211.219214) (xy 273.216709 -211.242041) (xy 273.168101 -211.257595) (xy 273.117681 -211.26551)
			(xy 273.092164 -211.266024) (xy 273.066645 -211.265515) (xy 273.016219 -211.257626) (xy 272.967607 -211.242071)
			(xy 272.921968 -211.219222) (xy 272.900902 -211.20481) (xy 272.894311 -211.200494) (xy 272.879311 -211.195708)
			(xy 272.871438 -211.195412) (xy 272.355564 -211.195412) (xy 272.350298 -211.194929) (xy 272.342858 -211.187471)
			(xy 272.342356 -211.182204) (xy 270.39824 -211.182204) (xy 270.397711 -211.18746) (xy 270.390287 -211.1949)
			(xy 270.385032 -211.195412) (xy 270.384524 -211.195412) (xy 269.868904 -211.195412) (xy 269.861031 -211.195715)
			(xy 269.846027 -211.200489) (xy 269.83944 -211.20481) (xy 269.818367 -211.219208) (xy 269.772721 -211.242036)
			(xy 269.724113 -211.257592) (xy 269.673695 -211.265509) (xy 269.648178 -211.266024) (xy 269.622659 -211.265508)
			(xy 269.572233 -211.257621) (xy 269.523622 -211.242068) (xy 269.477982 -211.219221) (xy 269.456916 -211.20481)
			(xy 269.450322 -211.200499) (xy 269.435324 -211.19571) (xy 269.427452 -211.195412) (xy 268.911578 -211.195412)
			(xy 268.90626 -211.194986) (xy 268.898687 -211.187515) (xy 268.898116 -211.182204) (xy 266.298172 -211.182204)
			(xy 266.297872 -211.187546) (xy 266.290307 -211.195088) (xy 266.284964 -211.195412) (xy 266.284456 -211.195412)
			(xy 265.768836 -211.195412) (xy 265.76096 -211.195686) (xy 265.745957 -211.20048) (xy 265.739372 -211.20481)
			(xy 265.71829 -211.219194) (xy 265.672647 -211.242025) (xy 265.624042 -211.257585) (xy 265.573626 -211.265506)
			(xy 265.54811 -211.266024) (xy 265.52259 -211.265542) (xy 265.472163 -211.257644) (xy 265.423551 -211.242082)
			(xy 265.377913 -211.219226) (xy 265.356848 -211.20481) (xy 265.350269 -211.200473) (xy 265.335259 -211.1957)
			(xy 265.327384 -211.195412) (xy 264.81151 -211.195412) (xy 264.806196 -211.194964) (xy 264.798622 -211.18751)
			(xy 264.798048 -211.182204) (xy 256.268301 -211.182204) (xy 256.26259 -211.194709) (xy 256.233104 -211.24059)
			(xy 256.197389 -211.281807) (xy 256.156172 -211.317522) (xy 256.110291 -211.347008) (xy 256.060681 -211.369665)
			(xy 256.008351 -211.38503) (xy 255.954367 -211.392792) (xy 255.899829 -211.392792) (xy 255.845845 -211.38503)
			(xy 255.793515 -211.369665) (xy 255.743905 -211.347008) (xy 255.698024 -211.317522) (xy 255.656807 -211.281807)
			(xy 255.621092 -211.24059) (xy 255.591606 -211.194709) (xy 255.568949 -211.145099) (xy 255.553584 -211.092769)
			(xy 255.545822 -211.038785) (xy 255.545336 -211.011516) (xy 206.997808 -211.011516) (xy 206.997808 -211.182458)
			(xy 206.997254 -211.187746) (xy 206.989874 -211.195317) (xy 206.9846 -211.19592) (xy 206.468726 -211.19592)
			(xy 206.460917 -211.196241) (xy 206.446045 -211.201022) (xy 206.439516 -211.205318) (xy 206.418385 -211.219653)
			(xy 206.372665 -211.242384) (xy 206.323994 -211.257818) (xy 206.27353 -211.265589) (xy 206.248 -211.266024)
			(xy 206.222469 -211.265595) (xy 206.172005 -211.257818) (xy 206.123332 -211.242387) (xy 206.077605 -211.219667)
			(xy 206.056484 -211.205318) (xy 206.049954 -211.201024) (xy 206.035083 -211.196243) (xy 206.027274 -211.19592)
			(xy 205.5114 -211.19592) (xy 205.50614 -211.195406) (xy 205.498698 -211.187971) (xy 205.498192 -211.182712)
			(xy 202.897716 -211.182712) (xy 202.897247 -211.187762) (xy 202.889825 -211.195336) (xy 202.884532 -211.19592)
			(xy 202.368658 -211.19592) (xy 202.36085 -211.196255) (xy 202.345978 -211.201026) (xy 202.339448 -211.205318)
			(xy 202.318336 -211.219682) (xy 202.272609 -211.242406) (xy 202.223933 -211.257832) (xy 202.173464 -211.265594)
			(xy 202.147932 -211.266024) (xy 202.122402 -211.265579) (xy 202.071938 -211.257807) (xy 202.023266 -211.24238)
			(xy 201.977538 -211.219665) (xy 201.956416 -211.205318) (xy 201.949879 -211.201036) (xy 201.935013 -211.196247)
			(xy 201.927206 -211.19592) (xy 201.411332 -211.19592) (xy 201.406007 -211.195553) (xy 201.398465 -211.188036)
			(xy 201.398124 -211.182712) (xy 199.453981 -211.182712) (xy 199.453454 -211.187746) (xy 199.446074 -211.195317)
			(xy 199.4408 -211.19592) (xy 198.924926 -211.19592) (xy 198.917117 -211.196241) (xy 198.902245 -211.201022)
			(xy 198.895716 -211.205318) (xy 198.874585 -211.219653) (xy 198.828865 -211.242384) (xy 198.780194 -211.257818)
			(xy 198.72973 -211.265589) (xy 198.7042 -211.266024) (xy 198.678669 -211.265595) (xy 198.628205 -211.257818)
			(xy 198.579532 -211.242387) (xy 198.533805 -211.219667) (xy 198.512684 -211.205318) (xy 198.506154 -211.201024)
			(xy 198.491283 -211.196243) (xy 198.483474 -211.19592) (xy 197.9676 -211.19592) (xy 197.96234 -211.195406)
			(xy 197.954898 -211.187971) (xy 197.954392 -211.182712) (xy 195.353916 -211.182712) (xy 195.353447 -211.187762)
			(xy 195.346025 -211.195336) (xy 195.340732 -211.19592) (xy 194.824858 -211.19592) (xy 194.81705 -211.196255)
			(xy 194.802178 -211.201026) (xy 194.795648 -211.205318) (xy 194.774536 -211.219682) (xy 194.728809 -211.242406)
			(xy 194.680133 -211.257832) (xy 194.629664 -211.265594) (xy 194.604132 -211.266024) (xy 194.578602 -211.265579)
			(xy 194.528138 -211.257807) (xy 194.479466 -211.24238) (xy 194.433738 -211.219665) (xy 194.412616 -211.205318)
			(xy 194.406079 -211.201036) (xy 194.391213 -211.196247) (xy 194.383406 -211.19592) (xy 193.867532 -211.19592)
			(xy 193.862207 -211.195553) (xy 193.854665 -211.188036) (xy 193.854324 -211.182712) (xy 191.91018 -211.182712)
			(xy 191.909626 -211.187806) (xy 191.90209 -211.195391) (xy 191.896746 -211.19592) (xy 191.380872 -211.19592)
			(xy 191.37306 -211.196218) (xy 191.358189 -211.201015) (xy 191.351662 -211.205318) (xy 191.330546 -211.219676)
			(xy 191.28482 -211.242402) (xy 191.236145 -211.257829) (xy 191.185678 -211.265593) (xy 191.160146 -211.266024)
			(xy 191.134616 -211.265572) (xy 191.084153 -211.257802) (xy 191.03548 -211.242377) (xy 190.989752 -211.219664)
			(xy 190.96863 -211.205318) (xy 190.96209 -211.201042) (xy 190.947227 -211.196249) (xy 190.93942 -211.19592)
			(xy 190.423546 -211.19592) (xy 190.418107 -211.195586) (xy 190.410416 -211.187897) (xy 190.410084 -211.182458)
			(xy 187.81014 -211.182458) (xy 187.80979 -211.187893) (xy 187.802112 -211.195582) (xy 187.796678 -211.19592)
			(xy 187.280804 -211.19592) (xy 187.272994 -211.196232) (xy 187.258122 -211.201019) (xy 187.251594 -211.205318)
			(xy 187.230469 -211.219662) (xy 187.184747 -211.242391) (xy 187.136074 -211.257823) (xy 187.085609 -211.26559)
			(xy 187.060078 -211.266024) (xy 187.034547 -211.265606) (xy 186.984082 -211.257826) (xy 186.935409 -211.242391)
			(xy 186.889683 -211.219669) (xy 186.868562 -211.205318) (xy 186.862037 -211.201015) (xy 186.847162 -211.196239)
			(xy 186.839352 -211.19592) (xy 186.323478 -211.19592) (xy 186.31803 -211.195631) (xy 186.310343 -211.187908)
			(xy 186.310016 -211.182458) (xy 184.3659 -211.182458) (xy 184.365353 -211.187748) (xy 184.357968 -211.195319)
			(xy 184.352692 -211.19592) (xy 183.836818 -211.19592) (xy 183.829008 -211.196238) (xy 183.814137 -211.201021)
			(xy 183.807608 -211.205318) (xy 183.786479 -211.219656) (xy 183.740758 -211.242386) (xy 183.692087 -211.25782)
			(xy 183.641622 -211.265589) (xy 183.616092 -211.266024) (xy 183.590561 -211.265599) (xy 183.540097 -211.257821)
			(xy 183.491424 -211.242388) (xy 183.445697 -211.219668) (xy 183.424576 -211.205318) (xy 183.418048 -211.201021)
			(xy 183.403175 -211.196241) (xy 183.395366 -211.19592) (xy 182.879492 -211.19592) (xy 182.874231 -211.195412)
			(xy 182.86679 -211.187973) (xy 182.866284 -211.182712) (xy 180.265809 -211.182712) (xy 180.265346 -211.187764)
			(xy 180.257919 -211.195339) (xy 180.252624 -211.19592) (xy 179.73675 -211.19592) (xy 179.728942 -211.196252)
			(xy 179.71407 -211.201025) (xy 179.70754 -211.205318) (xy 179.68643 -211.219685) (xy 179.640702 -211.242409)
			(xy 179.592025 -211.257834) (xy 179.541556 -211.265595) (xy 179.516024 -211.266024) (xy 179.490494 -211.265583)
			(xy 179.44003 -211.257809) (xy 179.391357 -211.242382) (xy 179.34563 -211.219666) (xy 179.324508 -211.205318)
			(xy 179.317973 -211.201033) (xy 179.303106 -211.196246) (xy 179.295298 -211.19592) (xy 178.779424 -211.19592)
			(xy 178.774098 -211.195558) (xy 178.766556 -211.188037) (xy 178.766216 -211.182712) (xy 176.822081 -211.182712)
			(xy 176.821696 -211.187878) (xy 176.814056 -211.195564) (xy 176.808638 -211.19592) (xy 176.292764 -211.19592)
			(xy 176.284956 -211.196258) (xy 176.270084 -211.201027) (xy 176.263554 -211.205318) (xy 176.24244 -211.219679)
			(xy 176.196714 -211.242404) (xy 176.148038 -211.257831) (xy 176.09757 -211.265593) (xy 176.072038 -211.266024)
			(xy 176.046508 -211.265576) (xy 175.996044 -211.257805) (xy 175.947372 -211.242379) (xy 175.901644 -211.219665)
			(xy 175.880522 -211.205318) (xy 175.873984 -211.201038) (xy 175.859119 -211.196248) (xy 175.851312 -211.19592)
			(xy 175.335438 -211.19592) (xy 175.329998 -211.195591) (xy 175.322307 -211.187898) (xy 175.321976 -211.182458)
			(xy 172.722032 -211.182458) (xy 172.72169 -211.187894) (xy 172.714006 -211.195585) (xy 172.70857 -211.19592)
			(xy 172.192696 -211.19592) (xy 172.184885 -211.196229) (xy 172.170014 -211.201018) (xy 172.163486 -211.205318)
			(xy 172.142363 -211.219666) (xy 172.09664 -211.242394) (xy 172.047967 -211.257824) (xy 171.997501 -211.265591)
			(xy 171.97197 -211.266024) (xy 171.946439 -211.26561) (xy 171.895974 -211.257828) (xy 171.847301 -211.242393)
			(xy 171.801575 -211.219669) (xy 171.780454 -211.205318) (xy 171.773931 -211.201012) (xy 171.759054 -211.196238)
			(xy 171.751244 -211.19592) (xy 171.23537 -211.19592) (xy 171.229921 -211.195637) (xy 171.222234 -211.187909)
			(xy 171.221908 -211.182458) (xy 169.277792 -211.182458) (xy 169.277253 -211.18775) (xy 169.269863 -211.195321)
			(xy 169.264584 -211.19592) (xy 167.791384 -211.19592) (xy 167.786122 -211.195417) (xy 167.778681 -211.187974)
			(xy 167.778176 -211.182712) (xy 165.177701 -211.182712) (xy 165.177245 -211.187766) (xy 165.169813 -211.195341)
			(xy 165.164516 -211.19592) (xy 163.691316 -211.19592) (xy 163.685989 -211.195564) (xy 163.678448 -211.188038)
			(xy 163.678108 -211.182712) (xy 144.28731 -211.182712) (xy 144.344494 -211.239093) (xy 144.440091 -211.344662)
			(xy 144.529563 -211.455471) (xy 144.612622 -211.571164) (xy 144.689003 -211.691371) (xy 144.758461 -211.815706)
			(xy 144.820774 -211.943772) (xy 144.857934 -212.032596) (xy 163.678108 -212.032596) (xy 163.678108 -212.032088)
			(xy 163.678108 -211.537804) (xy 163.678431 -211.532468) (xy 163.68598 -211.524926) (xy 163.691316 -211.524596)
			(xy 165.164516 -211.524596) (xy 165.169782 -211.525084) (xy 165.177224 -211.532538) (xy 165.177724 -211.537804)
			(xy 165.177724 -212.032342) (xy 171.221908 -212.032342) (xy 171.221908 -211.537804) (xy 171.222231 -211.532468)
			(xy 171.22978 -211.524926) (xy 171.235116 -211.524596) (xy 171.235624 -211.524596) (xy 171.751498 -211.524596)
			(xy 171.759308 -211.524282) (xy 171.774179 -211.519496) (xy 171.780708 -211.515198) (xy 171.801797 -211.500849)
			(xy 171.847458 -211.478118) (xy 171.896064 -211.462659) (xy 171.946467 -211.454836) (xy 171.997473 -211.454836)
			(xy 172.047876 -211.462659) (xy 172.096482 -211.478118) (xy 172.142143 -211.500849) (xy 172.163232 -211.515198)
			(xy 172.169757 -211.5195) (xy 172.184632 -211.524276) (xy 172.192442 -211.524596) (xy 172.70857 -211.524596)
			(xy 172.71386 -211.525138) (xy 172.721431 -211.532527) (xy 172.722032 -211.537804) (xy 172.722032 -212.032342)
			(xy 172.72201 -212.032596) (xy 178.766216 -212.032596) (xy 178.766216 -212.032088) (xy 178.766216 -211.537804)
			(xy 178.766532 -211.532466) (xy 178.774086 -211.524924) (xy 178.779424 -211.524596) (xy 179.295552 -211.524596)
			(xy 179.30336 -211.524263) (xy 179.318232 -211.51949) (xy 179.324762 -211.515198) (xy 179.345851 -211.500849)
			(xy 179.391512 -211.478118) (xy 179.440118 -211.462659) (xy 179.490521 -211.454836) (xy 179.541527 -211.454836)
			(xy 179.59193 -211.462659) (xy 179.640536 -211.478118) (xy 179.686197 -211.500849) (xy 179.707286 -211.515198)
			(xy 179.713821 -211.519483) (xy 179.728688 -211.52427) (xy 179.736496 -211.524596) (xy 180.252624 -211.524596)
			(xy 180.257891 -211.525079) (xy 180.265332 -211.532536) (xy 180.265832 -211.537804) (xy 180.265832 -212.032342)
			(xy 186.310016 -212.032342) (xy 186.310016 -211.537804) (xy 186.310332 -211.532466) (xy 186.317886 -211.524924)
			(xy 186.323224 -211.524596) (xy 186.323732 -211.524596) (xy 186.839606 -211.524596) (xy 186.847416 -211.524286)
			(xy 186.862288 -211.519497) (xy 186.868816 -211.515198) (xy 186.889905 -211.500849) (xy 186.935566 -211.478118)
			(xy 186.984172 -211.462659) (xy 187.034575 -211.454836) (xy 187.085581 -211.454836) (xy 187.135984 -211.462659)
			(xy 187.18459 -211.478118) (xy 187.230251 -211.500849) (xy 187.25134 -211.515198) (xy 187.257863 -211.519503)
			(xy 187.27274 -211.524278) (xy 187.28055 -211.524596) (xy 187.796678 -211.524596) (xy 187.801969 -211.525132)
			(xy 187.809539 -211.532525) (xy 187.81014 -211.537804) (xy 187.81014 -212.032342) (xy 187.810118 -212.032596)
			(xy 193.854324 -212.032596) (xy 193.854324 -212.032088) (xy 193.854324 -211.537804) (xy 193.854633 -211.532465)
			(xy 193.862192 -211.524922) (xy 193.867532 -211.524596) (xy 194.38366 -211.524596) (xy 194.391469 -211.524266)
			(xy 194.40634 -211.519491) (xy 194.41287 -211.515198) (xy 194.433959 -211.500849) (xy 194.47962 -211.478118)
			(xy 194.528226 -211.462659) (xy 194.578629 -211.454836) (xy 194.629635 -211.454836) (xy 194.680038 -211.462659)
			(xy 194.728644 -211.478118) (xy 194.774305 -211.500849) (xy 194.795394 -211.515198) (xy 194.801928 -211.519486)
			(xy 194.816796 -211.524271) (xy 194.824604 -211.524596) (xy 195.340732 -211.524596) (xy 195.346 -211.525074)
			(xy 195.353441 -211.532535) (xy 195.35394 -211.537804) (xy 195.35394 -212.032342) (xy 195.353919 -212.032596)
			(xy 201.398124 -212.032596) (xy 201.398124 -212.032088) (xy 201.398124 -211.537804) (xy 201.398433 -211.532465)
			(xy 201.405992 -211.524922) (xy 201.411332 -211.524596) (xy 201.92746 -211.524596) (xy 201.935269 -211.524266)
			(xy 201.95014 -211.519491) (xy 201.95667 -211.515198) (xy 201.977759 -211.500849) (xy 202.02342 -211.478118)
			(xy 202.072026 -211.462659) (xy 202.122429 -211.454836) (xy 202.173435 -211.454836) (xy 202.223838 -211.462659)
			(xy 202.272444 -211.478118) (xy 202.318105 -211.500849) (xy 202.339194 -211.515198) (xy 202.345728 -211.519486)
			(xy 202.360596 -211.524271) (xy 202.368404 -211.524596) (xy 202.884532 -211.524596) (xy 202.8898 -211.525074)
			(xy 202.897241 -211.532535) (xy 202.89774 -211.537804) (xy 202.89774 -212.032088) (xy 264.798048 -212.032088)
			(xy 264.798048 -211.53755) (xy 264.798518 -211.532178) (xy 264.806136 -211.524594) (xy 264.81151 -211.524088)
			(xy 265.327638 -211.524088) (xy 265.335446 -211.52375) (xy 265.350317 -211.518981) (xy 265.356848 -211.51469)
			(xy 265.377937 -211.500341) (xy 265.423598 -211.47761) (xy 265.472204 -211.462151) (xy 265.522607 -211.454328)
			(xy 265.573613 -211.454328) (xy 265.624016 -211.462151) (xy 265.672622 -211.47761) (xy 265.718283 -211.500341)
			(xy 265.739372 -211.51469) (xy 265.745911 -211.518968) (xy 265.760775 -211.52376) (xy 265.768582 -211.524088)
			(xy 266.28471 -211.524088) (xy 266.290063 -211.524639) (xy 266.297645 -211.532198) (xy 266.298172 -211.53755)
			(xy 266.298172 -212.032088) (xy 272.342356 -212.032088) (xy 272.342356 -211.53755) (xy 272.342858 -211.532248)
			(xy 272.350273 -211.524673) (xy 272.355564 -211.524088) (xy 272.871692 -211.524088) (xy 272.879502 -211.523773)
			(xy 272.894373 -211.518988) (xy 272.900902 -211.51469) (xy 272.921991 -211.500341) (xy 272.967652 -211.47761)
			(xy 273.016258 -211.462151) (xy 273.066661 -211.454328) (xy 273.117667 -211.454328) (xy 273.16807 -211.462151)
			(xy 273.216676 -211.47761) (xy 273.262337 -211.500341) (xy 273.283426 -211.51469) (xy 273.289953 -211.518989)
			(xy 273.304826 -211.523767) (xy 273.312636 -211.524088) (xy 273.828764 -211.524088) (xy 273.834091 -211.524451)
			(xy 273.841633 -211.531971) (xy 273.841972 -211.537296) (xy 273.841972 -211.537804) (xy 273.841972 -212.032088)
			(xy 279.886156 -212.032088) (xy 279.886156 -211.53755) (xy 279.886658 -211.532248) (xy 279.894073 -211.524673)
			(xy 279.899364 -211.524088) (xy 280.415492 -211.524088) (xy 280.423302 -211.523773) (xy 280.438173 -211.518988)
			(xy 280.444702 -211.51469) (xy 280.465791 -211.500341) (xy 280.511452 -211.47761) (xy 280.560058 -211.462151)
			(xy 280.610461 -211.454328) (xy 280.661467 -211.454328) (xy 280.71187 -211.462151) (xy 280.760476 -211.47761)
			(xy 280.806137 -211.500341) (xy 280.827226 -211.51469) (xy 280.833753 -211.518989) (xy 280.848626 -211.523767)
			(xy 280.856436 -211.524088) (xy 281.372564 -211.524088) (xy 281.377891 -211.524451) (xy 281.385433 -211.531971)
			(xy 281.385772 -211.537296) (xy 281.385772 -211.537804) (xy 281.385772 -212.032088) (xy 287.429956 -212.032088)
			(xy 287.429956 -211.53755) (xy 287.430419 -211.532176) (xy 287.438041 -211.524592) (xy 287.443418 -211.524088)
			(xy 287.959546 -211.524088) (xy 287.967354 -211.523754) (xy 287.982226 -211.518982) (xy 287.988756 -211.51469)
			(xy 288.009845 -211.500341) (xy 288.055506 -211.47761) (xy 288.104112 -211.462151) (xy 288.154515 -211.454328)
			(xy 288.205521 -211.454328) (xy 288.255924 -211.462151) (xy 288.30453 -211.47761) (xy 288.350191 -211.500341)
			(xy 288.37128 -211.51469) (xy 288.377817 -211.518971) (xy 288.392683 -211.523761) (xy 288.40049 -211.524088)
			(xy 288.916618 -211.524088) (xy 288.921972 -211.524633) (xy 288.929554 -211.532197) (xy 288.93008 -211.53755)
			(xy 288.93008 -212.032088) (xy 294.974264 -212.032088) (xy 294.974264 -211.53755) (xy 294.974759 -211.532246)
			(xy 294.982179 -211.524671) (xy 294.987472 -211.524088) (xy 295.5036 -211.524088) (xy 295.51141 -211.523776)
			(xy 295.526282 -211.518989) (xy 295.53281 -211.51469) (xy 295.553899 -211.500341) (xy 295.59956 -211.47761)
			(xy 295.648166 -211.462151) (xy 295.698569 -211.454328) (xy 295.749575 -211.454328) (xy 295.799978 -211.462151)
			(xy 295.848584 -211.47761) (xy 295.894245 -211.500341) (xy 295.915334 -211.51469) (xy 295.921859 -211.518992)
			(xy 295.936734 -211.523769) (xy 295.944544 -211.524088) (xy 296.460672 -211.524088) (xy 296.466 -211.524445)
			(xy 296.473542 -211.531969) (xy 296.47388 -211.537296) (xy 296.47388 -211.537804) (xy 296.47388 -212.032088)
			(xy 302.518064 -212.032088) (xy 302.518064 -211.53755) (xy 302.51852 -211.532174) (xy 302.526147 -211.52459)
			(xy 302.531526 -211.524088) (xy 304.004726 -211.524088) (xy 304.010081 -211.524628) (xy 304.017662 -211.532196)
			(xy 304.018188 -211.53755) (xy 304.018188 -212.032088) (xy 304.017863 -212.037423) (xy 304.010316 -212.044966)
			(xy 304.00498 -212.045296) (xy 302.531526 -212.045296) (xy 302.526233 -212.044764) (xy 302.518663 -212.037368)
			(xy 302.518064 -212.032088) (xy 296.47388 -212.032088) (xy 296.473562 -212.037425) (xy 296.46601 -212.044969)
			(xy 296.460672 -212.045296) (xy 295.944798 -212.045296) (xy 295.936923 -212.045583) (xy 295.921919 -212.050366)
			(xy 295.915334 -212.054694) (xy 295.894269 -212.069104) (xy 295.848619 -212.091927) (xy 295.800009 -212.107479)
			(xy 295.74959 -212.115393) (xy 295.724072 -212.115908) (xy 295.698553 -212.115398) (xy 295.648127 -212.107509)
			(xy 295.599515 -212.091955) (xy 295.553876 -212.069106) (xy 295.53281 -212.054694) (xy 295.526218 -212.050379)
			(xy 295.511218 -212.045593) (xy 295.503346 -212.045296) (xy 294.987472 -212.045296) (xy 294.982203 -212.044823)
			(xy 294.974761 -212.037359) (xy 294.974264 -212.032088) (xy 288.93008 -212.032088) (xy 288.929762 -212.037425)
			(xy 288.92221 -212.044969) (xy 288.916872 -212.045296) (xy 288.916364 -212.045296) (xy 288.400744 -212.045296)
			(xy 288.392867 -212.04556) (xy 288.377863 -212.050359) (xy 288.37128 -212.054694) (xy 288.350202 -212.069085)
			(xy 288.304557 -212.091912) (xy 288.255951 -212.10747) (xy 288.205535 -212.11539) (xy 288.180018 -212.115908)
			(xy 288.154498 -212.115425) (xy 288.10407 -212.107528) (xy 288.055459 -212.091966) (xy 288.009821 -212.06911)
			(xy 287.988756 -212.054694) (xy 287.982176 -212.050359) (xy 287.967167 -212.045585) (xy 287.959292 -212.045296)
			(xy 287.443418 -212.045296) (xy 287.438124 -212.044769) (xy 287.430554 -212.037369) (xy 287.429956 -212.032088)
			(xy 281.385772 -212.032088) (xy 281.385461 -212.037427) (xy 281.377904 -212.044971) (xy 281.372564 -212.045296)
			(xy 280.85669 -212.045296) (xy 280.848815 -212.045579) (xy 280.833811 -212.050365) (xy 280.827226 -212.054694)
			(xy 280.806163 -212.069108) (xy 280.760513 -212.09193) (xy 280.711902 -212.107481) (xy 280.661482 -212.115394)
			(xy 280.635964 -212.115908) (xy 280.610445 -212.115402) (xy 280.560018 -212.107512) (xy 280.511407 -212.091957)
			(xy 280.465768 -212.069107) (xy 280.444702 -212.054694) (xy 280.438112 -212.050376) (xy 280.423111 -212.045591)
			(xy 280.415238 -212.045296) (xy 279.899364 -212.045296) (xy 279.894094 -212.044828) (xy 279.886653 -212.03736)
			(xy 279.886156 -212.032088) (xy 273.841972 -212.032088) (xy 273.841661 -212.037427) (xy 273.834104 -212.044971)
			(xy 273.828764 -212.045296) (xy 273.31289 -212.045296) (xy 273.305015 -212.045579) (xy 273.290011 -212.050365)
			(xy 273.283426 -212.054694) (xy 273.262363 -212.069108) (xy 273.216713 -212.09193) (xy 273.168102 -212.107481)
			(xy 273.117682 -212.115394) (xy 273.092164 -212.115908) (xy 273.066645 -212.115402) (xy 273.016218 -212.107512)
			(xy 272.967607 -212.091957) (xy 272.921968 -212.069107) (xy 272.900902 -212.054694) (xy 272.894312 -212.050376)
			(xy 272.879311 -212.045591) (xy 272.871438 -212.045296) (xy 272.355564 -212.045296) (xy 272.350294 -212.044828)
			(xy 272.342853 -212.03736) (xy 272.342356 -212.032088) (xy 266.298172 -212.032088) (xy 266.297861 -212.037427)
			(xy 266.290304 -212.044971) (xy 266.284964 -212.045296) (xy 266.284456 -212.045296) (xy 265.768836 -212.045296)
			(xy 265.760959 -212.045556) (xy 265.745955 -212.050358) (xy 265.739372 -212.054694) (xy 265.718296 -212.069088)
			(xy 265.67265 -212.091915) (xy 265.624044 -212.107471) (xy 265.573627 -212.11539) (xy 265.54811 -212.115908)
			(xy 265.522589 -212.115429) (xy 265.472162 -212.107531) (xy 265.423551 -212.091968) (xy 265.377913 -212.06911)
			(xy 265.356848 -212.054694) (xy 265.35027 -212.050355) (xy 265.33526 -212.045583) (xy 265.327384 -212.045296)
			(xy 264.81151 -212.045296) (xy 264.806215 -212.044775) (xy 264.798646 -212.037371) (xy 264.798048 -212.032088)
			(xy 202.89774 -212.032088) (xy 202.89774 -212.032342) (xy 202.897303 -212.037656) (xy 202.889838 -212.045226)
			(xy 202.884532 -212.045804) (xy 202.368658 -212.045804) (xy 202.36085 -212.046141) (xy 202.345978 -212.050911)
			(xy 202.339448 -212.055202) (xy 202.318335 -212.069564) (xy 202.272608 -212.092289) (xy 202.223932 -212.107716)
			(xy 202.173464 -212.115478) (xy 202.147932 -212.115908) (xy 202.122403 -212.115448) (xy 202.07194 -212.107678)
			(xy 202.023268 -212.092255) (xy 201.977539 -212.069546) (xy 201.956416 -212.055202) (xy 201.94988 -212.050918)
			(xy 201.935013 -212.046131) (xy 201.927206 -212.045804) (xy 201.411332 -212.045804) (xy 201.406003 -212.045451)
			(xy 201.39846 -212.037924) (xy 201.398124 -212.032596) (xy 195.353919 -212.032596) (xy 195.353503 -212.037656)
			(xy 195.346038 -212.045226) (xy 195.340732 -212.045804) (xy 194.824858 -212.045804) (xy 194.81705 -212.046141)
			(xy 194.802178 -212.050911) (xy 194.795648 -212.055202) (xy 194.774535 -212.069564) (xy 194.728808 -212.092289)
			(xy 194.680132 -212.107716) (xy 194.629664 -212.115478) (xy 194.604132 -212.115908) (xy 194.578603 -212.115448)
			(xy 194.52814 -212.107678) (xy 194.479468 -212.092255) (xy 194.433739 -212.069546) (xy 194.412616 -212.055202)
			(xy 194.40608 -212.050918) (xy 194.391213 -212.046131) (xy 194.383406 -212.045804) (xy 193.867532 -212.045804)
			(xy 193.862203 -212.045451) (xy 193.85466 -212.037924) (xy 193.854324 -212.032596) (xy 187.810118 -212.032596)
			(xy 187.809675 -212.037716) (xy 187.802055 -212.045301) (xy 187.796678 -212.045804) (xy 187.280804 -212.045804)
			(xy 187.272994 -212.046119) (xy 187.258123 -212.050904) (xy 187.251594 -212.055202) (xy 187.230468 -212.069544)
			(xy 187.184746 -212.092274) (xy 187.136074 -212.107706) (xy 187.085609 -212.115474) (xy 187.060078 -212.115908)
			(xy 187.034548 -212.115475) (xy 186.984084 -212.107696) (xy 186.935412 -212.092266) (xy 186.889684 -212.069549)
			(xy 186.868562 -212.055202) (xy 186.862038 -212.050898) (xy 186.847162 -212.046123) (xy 186.839352 -212.045804)
			(xy 186.323478 -212.045804) (xy 186.318122 -212.045268) (xy 186.31054 -212.037698) (xy 186.310016 -212.032342)
			(xy 180.265832 -212.032342) (xy 180.265402 -212.037658) (xy 180.257933 -212.045228) (xy 180.252624 -212.045804)
			(xy 179.73675 -212.045804) (xy 179.728942 -212.046138) (xy 179.71407 -212.05091) (xy 179.70754 -212.055202)
			(xy 179.686429 -212.069568) (xy 179.640702 -212.092292) (xy 179.592025 -212.107718) (xy 179.541556 -212.115479)
			(xy 179.516024 -212.115908) (xy 179.490495 -212.115452) (xy 179.440032 -212.10768) (xy 179.39136 -212.092257)
			(xy 179.345631 -212.069546) (xy 179.324508 -212.055202) (xy 179.317974 -212.050915) (xy 179.303106 -212.046129)
			(xy 179.295298 -212.045804) (xy 178.779424 -212.045804) (xy 178.774094 -212.045457) (xy 178.766551 -212.037925)
			(xy 178.766216 -212.032596) (xy 172.72201 -212.032596) (xy 172.721575 -212.037718) (xy 172.713949 -212.045303)
			(xy 172.70857 -212.045804) (xy 172.192696 -212.045804) (xy 172.184886 -212.046115) (xy 172.170014 -212.050903)
			(xy 172.163486 -212.055202) (xy 172.142362 -212.069548) (xy 172.096639 -212.092277) (xy 172.047967 -212.107708)
			(xy 171.997501 -212.115475) (xy 171.97197 -212.115908) (xy 171.94644 -212.115479) (xy 171.895976 -212.107699)
			(xy 171.847304 -212.092268) (xy 171.801576 -212.06955) (xy 171.780454 -212.055202) (xy 171.773932 -212.050894)
			(xy 171.759055 -212.046122) (xy 171.751244 -212.045804) (xy 171.23537 -212.045804) (xy 171.230013 -212.045274)
			(xy 171.222431 -212.037699) (xy 171.221908 -212.032342) (xy 165.177724 -212.032342) (xy 165.177301 -212.03766)
			(xy 165.169827 -212.045231) (xy 165.164516 -212.045804) (xy 163.691316 -212.045804) (xy 163.685985 -212.045462)
			(xy 163.678443 -212.037927) (xy 163.678108 -212.032596) (xy 144.857934 -212.032596) (xy 144.875741 -212.075159)
			(xy 144.923187 -212.209444) (xy 144.96296 -212.346199) (xy 144.994932 -212.484985) (xy 145.019002 -212.625357)
			(xy 145.035091 -212.766867) (xy 145.041642 -212.88248) (xy 167.778176 -212.88248) (xy 167.778176 -212.387942)
			(xy 167.778655 -212.382634) (xy 167.786087 -212.375059) (xy 167.791384 -212.37448) (xy 169.264584 -212.37448)
			(xy 169.269911 -212.374836) (xy 169.277452 -212.382362) (xy 169.277792 -212.387688) (xy 169.277792 -212.88248)
			(xy 175.321976 -212.88248) (xy 175.321976 -212.387942) (xy 175.322311 -212.382504) (xy 175.33 -212.374813)
			(xy 175.335438 -212.37448) (xy 175.851566 -212.37448) (xy 175.859375 -212.374155) (xy 175.874247 -212.369377)
			(xy 175.880776 -212.365082) (xy 175.901865 -212.350733) (xy 175.947526 -212.328002) (xy 175.996132 -212.312543)
			(xy 176.046535 -212.30472) (xy 176.097541 -212.30472) (xy 176.147944 -212.312543) (xy 176.19655 -212.328002)
			(xy 176.242211 -212.350733) (xy 176.2633 -212.365082) (xy 176.269833 -212.36937) (xy 176.284702 -212.374155)
			(xy 176.29251 -212.37448) (xy 176.808638 -212.37448) (xy 176.814088 -212.374758) (xy 176.821774 -212.38249)
			(xy 176.8221 -212.387942) (xy 176.8221 -212.88248) (xy 182.866284 -212.88248) (xy 182.866284 -212.387942)
			(xy 182.866756 -212.382633) (xy 182.874192 -212.375056) (xy 182.879492 -212.37448) (xy 183.39562 -212.37448)
			(xy 183.403431 -212.374178) (xy 183.418303 -212.369384) (xy 183.42483 -212.365082) (xy 183.445919 -212.350733)
			(xy 183.49158 -212.328002) (xy 183.540186 -212.312543) (xy 183.590589 -212.30472) (xy 183.641595 -212.30472)
			(xy 183.691998 -212.312543) (xy 183.740604 -212.328002) (xy 183.786265 -212.350733) (xy 183.807354 -212.365082)
			(xy 183.813875 -212.369391) (xy 183.828753 -212.374163) (xy 183.836564 -212.37448) (xy 184.352692 -212.37448)
			(xy 184.357951 -212.374999) (xy 184.365393 -212.38243) (xy 184.3659 -212.387688) (xy 184.3659 -212.388196)
			(xy 184.3659 -212.88248) (xy 190.410084 -212.88248) (xy 190.410084 -212.387942) (xy 190.410412 -212.382502)
			(xy 190.418106 -212.37481) (xy 190.423546 -212.37448) (xy 190.939674 -212.37448) (xy 190.947483 -212.374159)
			(xy 190.962355 -212.369378) (xy 190.968884 -212.365082) (xy 190.989973 -212.350733) (xy 191.035634 -212.328002)
			(xy 191.08424 -212.312543) (xy 191.134643 -212.30472) (xy 191.185649 -212.30472) (xy 191.236052 -212.312543)
			(xy 191.284658 -212.328002) (xy 191.330319 -212.350733) (xy 191.351408 -212.365082) (xy 191.35794 -212.369373)
			(xy 191.37281 -212.374156) (xy 191.380618 -212.37448) (xy 191.896746 -212.37448) (xy 191.902126 -212.374924)
			(xy 191.909711 -212.382559) (xy 191.910208 -212.387942) (xy 191.910208 -212.88248) (xy 197.954392 -212.88248)
			(xy 197.954392 -212.387942) (xy 197.954946 -212.382654) (xy 197.962326 -212.375083) (xy 197.9676 -212.37448)
			(xy 198.483728 -212.37448) (xy 198.49154 -212.374182) (xy 198.506411 -212.369385) (xy 198.512938 -212.365082)
			(xy 198.534027 -212.350733) (xy 198.579688 -212.328002) (xy 198.628294 -212.312543) (xy 198.678697 -212.30472)
			(xy 198.729703 -212.30472) (xy 198.780106 -212.312543) (xy 198.828712 -212.328002) (xy 198.874373 -212.350733)
			(xy 198.895462 -212.365082) (xy 198.902004 -212.369355) (xy 198.916866 -212.37415) (xy 198.924672 -212.37448)
			(xy 199.4408 -212.37448) (xy 199.44606 -212.374994) (xy 199.453502 -212.382429) (xy 199.454008 -212.387688)
			(xy 199.454008 -212.388196) (xy 199.454008 -212.88248) (xy 205.498192 -212.88248) (xy 205.498192 -212.387942)
			(xy 205.498746 -212.382654) (xy 205.506126 -212.375083) (xy 205.5114 -212.37448) (xy 206.027528 -212.37448)
			(xy 206.03534 -212.374182) (xy 206.050211 -212.369385) (xy 206.056738 -212.365082) (xy 206.077827 -212.350733)
			(xy 206.123488 -212.328002) (xy 206.172094 -212.312543) (xy 206.222497 -212.30472) (xy 206.273503 -212.30472)
			(xy 206.323906 -212.312543) (xy 206.372512 -212.328002) (xy 206.418173 -212.350733) (xy 206.439262 -212.365082)
			(xy 206.445804 -212.369355) (xy 206.460666 -212.37415) (xy 206.468472 -212.37448) (xy 206.9846 -212.37448)
			(xy 206.98986 -212.374994) (xy 206.997302 -212.382429) (xy 206.997808 -212.387688) (xy 206.997808 -212.388196)
			(xy 206.997808 -212.88248) (xy 206.99746 -212.88781) (xy 206.989929 -212.895352) (xy 206.9846 -212.895688)
			(xy 206.468726 -212.895688) (xy 206.460849 -212.895945) (xy 206.445845 -212.900749) (xy 206.439262 -212.905086)
			(xy 206.418189 -212.919483) (xy 206.372542 -212.942309) (xy 206.323935 -212.957865) (xy 206.273517 -212.965783)
			(xy 206.248 -212.9663) (xy 206.222479 -212.965827) (xy 206.172052 -212.957928) (xy 206.12344 -212.942363)
			(xy 206.077802 -212.919503) (xy 206.056738 -212.905086) (xy 206.050141 -212.900782) (xy 206.035145 -212.895989)
			(xy 206.027274 -212.895688) (xy 205.5114 -212.895688) (xy 205.506063 -212.895371) (xy 205.498521 -212.887818)
			(xy 205.498192 -212.88248) (xy 199.454008 -212.88248) (xy 199.45366 -212.88781) (xy 199.446129 -212.895352)
			(xy 199.4408 -212.895688) (xy 198.924926 -212.895688) (xy 198.917049 -212.895945) (xy 198.902045 -212.900749)
			(xy 198.895462 -212.905086) (xy 198.874389 -212.919483) (xy 198.828742 -212.942309) (xy 198.780135 -212.957865)
			(xy 198.729717 -212.965783) (xy 198.7042 -212.9663) (xy 198.678679 -212.965827) (xy 198.628252 -212.957928)
			(xy 198.57964 -212.942363) (xy 198.534002 -212.919503) (xy 198.512938 -212.905086) (xy 198.506341 -212.900782)
			(xy 198.491345 -212.895989) (xy 198.483474 -212.895688) (xy 197.9676 -212.895688) (xy 197.962263 -212.895371)
			(xy 197.954721 -212.887818) (xy 197.954392 -212.88248) (xy 191.910208 -212.88248) (xy 191.90986 -212.88781)
			(xy 191.902329 -212.895352) (xy 191.897 -212.895688) (xy 191.896492 -212.895688) (xy 191.380872 -212.895688)
			(xy 191.372996 -212.895965) (xy 191.357992 -212.900755) (xy 191.351408 -212.905086) (xy 191.33035 -212.919507)
			(xy 191.284698 -212.942327) (xy 191.236086 -212.957877) (xy 191.185664 -212.965787) (xy 191.160146 -212.9663)
			(xy 191.134626 -212.965804) (xy 191.084199 -212.957912) (xy 191.035588 -212.942353) (xy 190.989949 -212.9195)
			(xy 190.968884 -212.905086) (xy 190.962299 -212.900761) (xy 190.947294 -212.895981) (xy 190.93942 -212.895688)
			(xy 190.423546 -212.895688) (xy 190.418254 -212.89515) (xy 190.410682 -212.887759) (xy 190.410084 -212.88248)
			(xy 184.3659 -212.88248) (xy 184.365559 -212.887812) (xy 184.358023 -212.895354) (xy 184.352692 -212.895688)
			(xy 183.836818 -212.895688) (xy 183.828944 -212.895984) (xy 183.81394 -212.900761) (xy 183.807354 -212.905086)
			(xy 183.786283 -212.919487) (xy 183.740635 -212.942312) (xy 183.692027 -212.957867) (xy 183.641609 -212.965784)
			(xy 183.616092 -212.9663) (xy 183.590573 -212.965781) (xy 183.540147 -212.957896) (xy 183.491536 -212.942344)
			(xy 183.445896 -212.919497) (xy 183.42483 -212.905086) (xy 183.418234 -212.900778) (xy 183.403237 -212.895987)
			(xy 183.395366 -212.895688) (xy 182.879492 -212.895688) (xy 182.874154 -212.895377) (xy 182.866612 -212.887819)
			(xy 182.866284 -212.88248) (xy 176.8221 -212.88248) (xy 176.821759 -212.887812) (xy 176.814223 -212.895354)
			(xy 176.808892 -212.895688) (xy 176.808384 -212.895688) (xy 176.292764 -212.895688) (xy 176.284888 -212.895961)
			(xy 176.269884 -212.900754) (xy 176.2633 -212.905086) (xy 176.242216 -212.919467) (xy 176.196573 -212.942297)
			(xy 176.147969 -212.957857) (xy 176.097554 -212.96578) (xy 176.072038 -212.9663) (xy 176.046518 -212.965808)
			(xy 175.996091 -212.957914) (xy 175.947479 -212.942355) (xy 175.901841 -212.919501) (xy 175.880776 -212.905086)
			(xy 175.874192 -212.900758) (xy 175.859186 -212.895979) (xy 175.851312 -212.895688) (xy 175.335438 -212.895688)
			(xy 175.330145 -212.895155) (xy 175.322573 -212.88776) (xy 175.321976 -212.88248) (xy 169.277792 -212.88248)
			(xy 169.277458 -212.887814) (xy 169.269917 -212.895357) (xy 169.264584 -212.895688) (xy 167.791384 -212.895688)
			(xy 167.786045 -212.895382) (xy 167.778503 -212.88782) (xy 167.778176 -212.88248) (xy 145.041642 -212.88248)
			(xy 145.043148 -212.909059) (xy 145.043652 -212.98027) (xy 145.043148 -213.051481) (xy 145.035091 -213.193673)
			(xy 145.019002 -213.335183) (xy 144.994932 -213.475555) (xy 144.96296 -213.614341) (xy 144.928635 -213.732364)
			(xy 163.678108 -213.732364) (xy 163.678108 -213.237826) (xy 163.678637 -213.232532) (xy 163.686035 -213.224962)
			(xy 163.691316 -213.224364) (xy 165.164516 -213.224364) (xy 165.169774 -213.224881) (xy 165.177214 -213.232314)
			(xy 165.177724 -213.237572) (xy 165.177724 -213.23808) (xy 165.177724 -213.732364) (xy 171.221908 -213.732364)
			(xy 171.221908 -213.237826) (xy 171.222465 -213.232472) (xy 171.230019 -213.224887) (xy 171.23537 -213.224364)
			(xy 171.751498 -213.224364) (xy 171.759309 -213.224056) (xy 171.77418 -213.219267) (xy 171.780708 -213.214966)
			(xy 171.801797 -213.200617) (xy 171.847458 -213.177886) (xy 171.896064 -213.162427) (xy 171.946467 -213.154604)
			(xy 171.997473 -213.154604) (xy 172.047876 -213.162427) (xy 172.096482 -213.177886) (xy 172.142143 -213.200617)
			(xy 172.163232 -213.214966) (xy 172.169759 -213.219265) (xy 172.184632 -213.224044) (xy 172.192442 -213.224364)
			(xy 172.70857 -213.224364) (xy 172.714007 -213.224702) (xy 172.721696 -213.232389) (xy 172.722032 -213.237826)
			(xy 172.722032 -213.732364) (xy 178.766216 -213.732364) (xy 178.766216 -213.237826) (xy 178.766738 -213.232531)
			(xy 178.774141 -213.224959) (xy 178.779424 -213.224364) (xy 179.295552 -213.224364) (xy 179.303361 -213.224036)
			(xy 179.318233 -213.21926) (xy 179.324762 -213.214966) (xy 179.345851 -213.200617) (xy 179.391512 -213.177886)
			(xy 179.440118 -213.162427) (xy 179.490521 -213.154604) (xy 179.541527 -213.154604) (xy 179.59193 -213.162427)
			(xy 179.640536 -213.177886) (xy 179.686197 -213.200617) (xy 179.707286 -213.214966) (xy 179.713823 -213.219247)
			(xy 179.728689 -213.224037) (xy 179.736496 -213.224364) (xy 180.252624 -213.224364) (xy 180.257883 -213.224876)
			(xy 180.265322 -213.232313) (xy 180.265832 -213.237572) (xy 180.265832 -213.23808) (xy 180.265832 -213.732364)
			(xy 186.310016 -213.732364) (xy 186.310016 -213.237826) (xy 186.310394 -213.2324) (xy 186.318053 -213.224714)
			(xy 186.323478 -213.224364) (xy 186.839606 -213.224364) (xy 186.847417 -213.224059) (xy 186.862289 -213.219268)
			(xy 186.868816 -213.214966) (xy 186.889905 -213.200617) (xy 186.935566 -213.177886) (xy 186.984172 -213.162427)
			(xy 187.034575 -213.154604) (xy 187.085581 -213.154604) (xy 187.135984 -213.162427) (xy 187.18459 -213.177886)
			(xy 187.230251 -213.200617) (xy 187.25134 -213.214966) (xy 187.257865 -213.219268) (xy 187.27274 -213.224045)
			(xy 187.28055 -213.224364) (xy 187.796678 -213.224364) (xy 187.802116 -213.224697) (xy 187.809805 -213.232388)
			(xy 187.81014 -213.237826) (xy 187.81014 -213.732364) (xy 193.854324 -213.732364) (xy 193.854324 -213.237826)
			(xy 193.854839 -213.232529) (xy 193.862246 -213.224957) (xy 193.867532 -213.224364) (xy 194.38366 -213.224364)
			(xy 194.391469 -213.224039) (xy 194.406341 -213.219261) (xy 194.41287 -213.214966) (xy 194.433959 -213.200617)
			(xy 194.47962 -213.177886) (xy 194.528226 -213.162427) (xy 194.578629 -213.154604) (xy 194.629635 -213.154604)
			(xy 194.680038 -213.162427) (xy 194.728644 -213.177886) (xy 194.774305 -213.200617) (xy 194.795394 -213.214966)
			(xy 194.80193 -213.21925) (xy 194.816796 -213.224038) (xy 194.824604 -213.224364) (xy 195.340732 -213.224364)
			(xy 195.345992 -213.224871) (xy 195.353431 -213.232312) (xy 195.35394 -213.237572) (xy 195.35394 -213.23808)
			(xy 195.35394 -213.732364) (xy 201.398124 -213.732364) (xy 201.398124 -213.237826) (xy 201.398639 -213.232529)
			(xy 201.406046 -213.224957) (xy 201.411332 -213.224364) (xy 201.92746 -213.224364) (xy 201.935269 -213.224039)
			(xy 201.950141 -213.219261) (xy 201.95667 -213.214966) (xy 201.977759 -213.200617) (xy 202.02342 -213.177886)
			(xy 202.072026 -213.162427) (xy 202.122429 -213.154604) (xy 202.173435 -213.154604) (xy 202.223838 -213.162427)
			(xy 202.272444 -213.177886) (xy 202.318105 -213.200617) (xy 202.339194 -213.214966) (xy 202.34573 -213.21925)
			(xy 202.360596 -213.224038) (xy 202.368404 -213.224364) (xy 202.884532 -213.224364) (xy 202.889792 -213.224871)
			(xy 202.897231 -213.232312) (xy 202.89774 -213.237572) (xy 202.89774 -213.23808) (xy 202.89774 -213.732364)
			(xy 202.897352 -213.737684) (xy 202.88985 -213.745225) (xy 202.884532 -213.745572) (xy 202.368658 -213.745572)
			(xy 202.360782 -213.745846) (xy 202.345778 -213.750639) (xy 202.339194 -213.75497) (xy 202.31811 -213.769352)
			(xy 202.272467 -213.792182) (xy 202.229229 -213.806024) (xy 255.545336 -213.806024) (xy 255.545336 -212.942424)
			(xy 255.545822 -212.915155) (xy 255.553584 -212.861171) (xy 255.568949 -212.808841) (xy 255.591606 -212.759231)
			(xy 255.621092 -212.71335) (xy 255.656807 -212.672133) (xy 255.698024 -212.636418) (xy 255.743905 -212.606932)
			(xy 255.793515 -212.584275) (xy 255.845845 -212.56891) (xy 255.899829 -212.561148) (xy 255.954367 -212.561148)
			(xy 256.008351 -212.56891) (xy 256.060681 -212.584275) (xy 256.110291 -212.606932) (xy 256.156172 -212.636418)
			(xy 256.197389 -212.672133) (xy 256.233104 -212.71335) (xy 256.26259 -212.759231) (xy 256.285247 -212.808841)
			(xy 256.300612 -212.861171) (xy 256.303639 -212.882226) (xy 268.898116 -212.882226) (xy 268.898116 -212.387688)
			(xy 268.898421 -212.382348) (xy 268.905983 -212.374807) (xy 268.911324 -212.37448) (xy 268.911832 -212.37448)
			(xy 269.427706 -212.37448) (xy 269.435517 -212.374172) (xy 269.450388 -212.369383) (xy 269.456916 -212.365082)
			(xy 269.478005 -212.350733) (xy 269.523666 -212.328002) (xy 269.572272 -212.312543) (xy 269.622675 -212.30472)
			(xy 269.673681 -212.30472) (xy 269.724084 -212.312543) (xy 269.77269 -212.328002) (xy 269.818351 -212.350733)
			(xy 269.83944 -212.365082) (xy 269.845965 -212.369385) (xy 269.86084 -212.374161) (xy 269.86865 -212.37448)
			(xy 270.384778 -212.37448) (xy 270.390089 -212.374943) (xy 270.397663 -212.382386) (xy 270.39824 -212.387688)
			(xy 270.39824 -212.882226) (xy 270.398218 -212.88248) (xy 276.442424 -212.88248) (xy 276.442424 -212.881972)
			(xy 276.442424 -212.387688) (xy 276.442722 -212.382346) (xy 276.450289 -212.374804) (xy 276.455632 -212.37448)
			(xy 276.97176 -212.37448) (xy 276.979569 -212.374153) (xy 276.994441 -212.369377) (xy 277.00097 -212.365082)
			(xy 277.022059 -212.350733) (xy 277.06772 -212.328002) (xy 277.116326 -212.312543) (xy 277.166729 -212.30472)
			(xy 277.217735 -212.30472) (xy 277.268138 -212.312543) (xy 277.316744 -212.328002) (xy 277.362405 -212.350733)
			(xy 277.383494 -212.365082) (xy 277.390029 -212.369368) (xy 277.404896 -212.374154) (xy 277.412704 -212.37448)
			(xy 277.928832 -212.37448) (xy 277.934096 -212.374972) (xy 277.941536 -212.382424) (xy 277.94204 -212.387688)
			(xy 277.94204 -212.882226) (xy 277.942019 -212.88248) (xy 283.986224 -212.88248) (xy 283.986224 -212.881972)
			(xy 283.986224 -212.387688) (xy 283.986522 -212.382346) (xy 283.994089 -212.374804) (xy 283.999432 -212.37448)
			(xy 284.51556 -212.37448) (xy 284.523369 -212.374153) (xy 284.538241 -212.369377) (xy 284.54477 -212.365082)
			(xy 284.565859 -212.350733) (xy 284.61152 -212.328002) (xy 284.660126 -212.312543) (xy 284.710529 -212.30472)
			(xy 284.761535 -212.30472) (xy 284.811938 -212.312543) (xy 284.860544 -212.328002) (xy 284.906205 -212.350733)
			(xy 284.927294 -212.365082) (xy 284.933829 -212.369368) (xy 284.948696 -212.374154) (xy 284.956504 -212.37448)
			(xy 285.472632 -212.37448) (xy 285.477896 -212.374972) (xy 285.485336 -212.382424) (xy 285.48584 -212.387688)
			(xy 285.48584 -212.882226) (xy 291.530024 -212.882226) (xy 291.530024 -212.387688) (xy 291.530322 -212.382346)
			(xy 291.537889 -212.374804) (xy 291.543232 -212.37448) (xy 291.54374 -212.37448) (xy 292.059614 -212.37448)
			(xy 292.067425 -212.374176) (xy 292.082296 -212.369384) (xy 292.088824 -212.365082) (xy 292.109913 -212.350733)
			(xy 292.155574 -212.328002) (xy 292.20418 -212.312543) (xy 292.254583 -212.30472) (xy 292.305589 -212.30472)
			(xy 292.355992 -212.312543) (xy 292.404598 -212.328002) (xy 292.450259 -212.350733) (xy 292.471348 -212.365082)
			(xy 292.477871 -212.369388) (xy 292.492747 -212.374162) (xy 292.500558 -212.37448) (xy 293.016686 -212.37448)
			(xy 293.021998 -212.374937) (xy 293.029572 -212.382385) (xy 293.030148 -212.387688) (xy 293.030148 -212.882226)
			(xy 293.030125 -212.88248) (xy 299.074332 -212.88248) (xy 299.074332 -212.881972) (xy 299.074332 -212.387688)
			(xy 299.074623 -212.382344) (xy 299.082195 -212.374802) (xy 299.08754 -212.37448) (xy 299.603668 -212.37448)
			(xy 299.611477 -212.374156) (xy 299.626349 -212.369378) (xy 299.632878 -212.365082) (xy 299.653967 -212.350733)
			(xy 299.699628 -212.328002) (xy 299.748234 -212.312543) (xy 299.798637 -212.30472) (xy 299.849643 -212.30472)
			(xy 299.900046 -212.312543) (xy 299.948652 -212.328002) (xy 299.994313 -212.350733) (xy 300.015402 -212.365082)
			(xy 300.021935 -212.369371) (xy 300.036804 -212.374155) (xy 300.044612 -212.37448) (xy 300.56074 -212.37448)
			(xy 300.566005 -212.374967) (xy 300.573444 -212.382422) (xy 300.573948 -212.387688) (xy 300.573948 -212.882226)
			(xy 306.618132 -212.882226) (xy 306.618132 -212.387688) (xy 306.618423 -212.382344) (xy 306.625995 -212.374802)
			(xy 306.63134 -212.37448) (xy 306.631848 -212.37448) (xy 308.104794 -212.37448) (xy 308.110107 -212.374932)
			(xy 308.117681 -212.382384) (xy 308.118256 -212.387688) (xy 308.118256 -212.882226) (xy 308.117766 -212.887594)
			(xy 308.110164 -212.895179) (xy 308.104794 -212.895688) (xy 306.631594 -212.895688) (xy 306.626236 -212.895156)
			(xy 306.618652 -212.887584) (xy 306.618132 -212.882226) (xy 300.573948 -212.882226) (xy 300.573493 -212.887536)
			(xy 300.566041 -212.895106) (xy 300.56074 -212.895688) (xy 300.044866 -212.895688) (xy 300.037057 -212.896015)
			(xy 300.022185 -212.90079) (xy 300.015656 -212.905086) (xy 299.994547 -212.919454) (xy 299.948818 -212.942176)
			(xy 299.900141 -212.9576) (xy 299.849672 -212.965362) (xy 299.82414 -212.965792) (xy 299.798611 -212.96533)
			(xy 299.748148 -212.957561) (xy 299.699476 -212.942139) (xy 299.653747 -212.91943) (xy 299.632624 -212.905086)
			(xy 299.626081 -212.900813) (xy 299.61122 -212.896017) (xy 299.603414 -212.895688) (xy 299.08754 -212.895688)
			(xy 299.082208 -212.895344) (xy 299.074664 -212.887811) (xy 299.074332 -212.88248) (xy 293.030125 -212.88248)
			(xy 293.029665 -212.887596) (xy 293.022058 -212.895181) (xy 293.016686 -212.895688) (xy 292.500812 -212.895688)
			(xy 292.493001 -212.895992) (xy 292.478129 -212.900783) (xy 292.471602 -212.905086) (xy 292.45048 -212.919435)
			(xy 292.404756 -212.94216) (xy 292.356083 -212.95759) (xy 292.305617 -212.965358) (xy 292.280086 -212.965792)
			(xy 292.254556 -212.965358) (xy 292.204092 -212.95758) (xy 292.15542 -212.94215) (xy 292.109692 -212.919433)
			(xy 292.08857 -212.905086) (xy 292.082039 -212.900793) (xy 292.067169 -212.896009) (xy 292.05936 -212.895688)
			(xy 291.543486 -212.895688) (xy 291.538127 -212.895161) (xy 291.530543 -212.887585) (xy 291.530024 -212.882226)
			(xy 285.48584 -212.882226) (xy 285.485392 -212.887538) (xy 285.477936 -212.895109) (xy 285.472632 -212.895688)
			(xy 284.956758 -212.895688) (xy 284.948949 -212.896011) (xy 284.934076 -212.900789) (xy 284.927548 -212.905086)
			(xy 284.906441 -212.919458) (xy 284.860712 -212.942179) (xy 284.812034 -212.957602) (xy 284.761564 -212.965362)
			(xy 284.736032 -212.965792) (xy 284.710503 -212.965334) (xy 284.66004 -212.957564) (xy 284.611367 -212.942141)
			(xy 284.565639 -212.91943) (xy 284.544516 -212.905086) (xy 284.537975 -212.90081) (xy 284.523113 -212.896016)
			(xy 284.515306 -212.895688) (xy 283.999432 -212.895688) (xy 283.994099 -212.89535) (xy 283.986555 -212.887812)
			(xy 283.986224 -212.88248) (xy 277.942019 -212.88248) (xy 277.941592 -212.887538) (xy 277.934136 -212.895109)
			(xy 277.928832 -212.895688) (xy 277.412958 -212.895688) (xy 277.405149 -212.896011) (xy 277.390276 -212.900789)
			(xy 277.383748 -212.905086) (xy 277.362641 -212.919458) (xy 277.316912 -212.942179) (xy 277.268234 -212.957602)
			(xy 277.217764 -212.965362) (xy 277.192232 -212.965792) (xy 277.166703 -212.965334) (xy 277.11624 -212.957564)
			(xy 277.067567 -212.942141) (xy 277.021839 -212.91943) (xy 277.000716 -212.905086) (xy 276.994175 -212.90081)
			(xy 276.979313 -212.896016) (xy 276.971506 -212.895688) (xy 276.455632 -212.895688) (xy 276.450299 -212.89535)
			(xy 276.442755 -212.887812) (xy 276.442424 -212.88248) (xy 270.398218 -212.88248) (xy 270.397765 -212.887598)
			(xy 270.390152 -212.895184) (xy 270.384778 -212.895688) (xy 269.868904 -212.895688) (xy 269.861092 -212.895989)
			(xy 269.846221 -212.900782) (xy 269.839694 -212.905086) (xy 269.818574 -212.919438) (xy 269.772849 -212.942163)
			(xy 269.724176 -212.957592) (xy 269.673709 -212.965359) (xy 269.648178 -212.965792) (xy 269.622648 -212.965362)
			(xy 269.572184 -212.957583) (xy 269.523511 -212.942152) (xy 269.477784 -212.919434) (xy 269.456662 -212.905086)
			(xy 269.450133 -212.90079) (xy 269.435261 -212.896008) (xy 269.427452 -212.895688) (xy 268.911578 -212.895688)
			(xy 268.906218 -212.895167) (xy 268.898635 -212.887586) (xy 268.898116 -212.882226) (xy 256.303639 -212.882226)
			(xy 256.308374 -212.915155) (xy 256.30886 -212.942424) (xy 256.30886 -212.980016) (xy 326.752208 -212.980016)
			(xy 326.756238 -212.837681) (xy 326.768313 -212.695801) (xy 326.788396 -212.554833) (xy 326.816423 -212.415226)
			(xy 326.852303 -212.277428) (xy 326.895921 -212.141881) (xy 326.947138 -212.009019) (xy 327.005789 -211.879267)
			(xy 327.071687 -211.753041) (xy 327.144621 -211.630745) (xy 327.224358 -211.512772) (xy 327.31064 -211.399499)
			(xy 327.403193 -211.291288) (xy 327.50172 -211.188487) (xy 327.605905 -211.091425) (xy 327.715414 -211.000413)
			(xy 327.829897 -210.915741) (xy 327.948987 -210.837683) (xy 328.072302 -210.766487) (xy 328.199448 -210.702381)
			(xy 328.330017 -210.645572) (xy 328.463591 -210.59624) (xy 328.599742 -210.554544) (xy 328.738033 -210.520618)
			(xy 328.878023 -210.49457) (xy 329.019262 -210.476484) (xy 329.161298 -210.466417) (xy 329.303676 -210.464402)
			(xy 329.44594 -210.470445) (xy 329.587634 -210.484527) (xy 329.728304 -210.506603) (xy 329.867501 -210.536603)
			(xy 330.004777 -210.574429) (xy 330.139693 -210.619961) (xy 330.271817 -210.673052) (xy 330.400726 -210.733534)
			(xy 330.526007 -210.801212) (xy 330.647258 -210.875869) (xy 330.764091 -210.957267) (xy 330.876132 -211.045144)
			(xy 330.983022 -211.139219) (xy 331.084419 -211.239191) (xy 331.179997 -211.344739) (xy 331.269451 -211.455525)
			(xy 331.352493 -211.571194) (xy 331.428859 -211.691377) (xy 331.498303 -211.815687) (xy 331.560603 -211.943728)
			(xy 331.615559 -212.075087) (xy 331.662996 -212.209346) (xy 331.70276 -212.346073) (xy 331.734726 -212.484831)
			(xy 331.758791 -212.625175) (xy 331.774877 -212.766656) (xy 331.782932 -212.90882) (xy 331.783436 -212.980016)
			(xy 387.951476 -212.980016) (xy 387.955506 -212.837652) (xy 387.967584 -212.695744) (xy 387.987672 -212.554747)
			(xy 388.015704 -212.415112) (xy 388.051591 -212.277286) (xy 388.095218 -212.141712) (xy 388.146445 -212.008823)
			(xy 388.205108 -211.879044) (xy 388.27102 -211.752793) (xy 388.343969 -211.630473) (xy 388.423721 -211.512476)
			(xy 388.510021 -211.39918) (xy 388.602593 -211.290947) (xy 388.701139 -211.188125) (xy 388.805345 -211.091044)
			(xy 388.914877 -211.000013) (xy 389.029383 -210.915325) (xy 389.148497 -210.83725) (xy 389.271837 -210.76604)
			(xy 389.399008 -210.701921) (xy 389.529604 -210.6451) (xy 389.663204 -210.595759) (xy 389.799383 -210.554054)
			(xy 389.937702 -210.520121) (xy 390.07772 -210.494068) (xy 390.218987 -210.475978) (xy 390.361052 -210.465909)
			(xy 390.503459 -210.463894) (xy 390.645752 -210.469938) (xy 390.787474 -210.484024) (xy 390.928173 -210.506104)
			(xy 391.067398 -210.536109) (xy 391.204702 -210.573943) (xy 391.339645 -210.619484) (xy 391.471796 -210.672587)
			(xy 391.600731 -210.733081) (xy 391.726037 -210.800772) (xy 391.847313 -210.875445) (xy 391.964169 -210.956859)
			(xy 392.076233 -211.044753) (xy 392.183145 -211.138847) (xy 392.22712 -211.182204) (xy 411.618176 -211.182204)
			(xy 411.618176 -210.687666) (xy 411.618605 -210.682349) (xy 411.626075 -210.674778) (xy 411.631384 -210.674204)
			(xy 413.104584 -210.674204) (xy 413.109917 -210.674539) (xy 413.11746 -210.682079) (xy 413.117792 -210.687412)
			(xy 413.117792 -210.68792) (xy 413.117792 -211.182204) (xy 415.718244 -211.182204) (xy 415.718244 -210.687666)
			(xy 415.718701 -210.682357) (xy 415.726151 -210.674787) (xy 415.731452 -210.674204) (xy 417.204652 -210.674204)
			(xy 417.209981 -210.674561) (xy 417.217525 -210.682084) (xy 417.21786 -210.687412) (xy 417.21786 -211.182204)
			(xy 419.161976 -211.182204) (xy 419.161976 -210.687666) (xy 419.16226 -210.682217) (xy 419.169988 -210.674531)
			(xy 419.175438 -210.674204) (xy 419.691566 -210.674204) (xy 419.699375 -210.673875) (xy 419.714246 -210.6691)
			(xy 419.720776 -210.664806) (xy 419.741865 -210.650457) (xy 419.787526 -210.627726) (xy 419.836132 -210.612267)
			(xy 419.886535 -210.604444) (xy 419.937541 -210.604444) (xy 419.987944 -210.612267) (xy 420.03655 -210.627726)
			(xy 420.082211 -210.650457) (xy 420.1033 -210.664806) (xy 420.109832 -210.669097) (xy 420.124702 -210.67388)
			(xy 420.13251 -210.674204) (xy 420.648638 -210.674204) (xy 420.653998 -210.674722) (xy 420.66158 -210.682306)
			(xy 420.6621 -210.687666) (xy 420.6621 -211.182204) (xy 423.262044 -211.182204) (xy 423.262044 -210.687666)
			(xy 423.262528 -210.682296) (xy 423.270135 -210.674712) (xy 423.275506 -210.674204) (xy 423.791634 -210.674204)
			(xy 423.799441 -210.673862) (xy 423.814313 -210.669095) (xy 423.820844 -210.664806) (xy 423.841933 -210.650457)
			(xy 423.887594 -210.627726) (xy 423.9362 -210.612267) (xy 423.986603 -210.604444) (xy 424.037609 -210.604444)
			(xy 424.088012 -210.612267) (xy 424.136618 -210.627726) (xy 424.182279 -210.650457) (xy 424.203368 -210.664806)
			(xy 424.209907 -210.669084) (xy 424.224771 -210.673875) (xy 424.232578 -210.674204) (xy 424.748706 -210.674204)
			(xy 424.754063 -210.674743) (xy 424.761646 -210.682311) (xy 424.762168 -210.687666) (xy 424.762168 -211.182204)
			(xy 426.706284 -211.182204) (xy 426.706284 -210.687666) (xy 426.706706 -210.682347) (xy 426.71418 -210.674776)
			(xy 426.719492 -210.674204) (xy 427.23562 -210.674204) (xy 427.243431 -210.673898) (xy 427.258302 -210.669107)
			(xy 427.26483 -210.664806) (xy 427.285919 -210.650457) (xy 427.33158 -210.627726) (xy 427.380186 -210.612267)
			(xy 427.430589 -210.604444) (xy 427.481595 -210.604444) (xy 427.531998 -210.612267) (xy 427.580604 -210.627726)
			(xy 427.626265 -210.650457) (xy 427.647354 -210.664806) (xy 427.653874 -210.669117) (xy 427.668753 -210.673888)
			(xy 427.676564 -210.674204) (xy 428.192692 -210.674204) (xy 428.198026 -210.674533) (xy 428.205568 -210.682078)
			(xy 428.2059 -210.687412) (xy 428.2059 -210.68792) (xy 428.2059 -211.182204) (xy 430.806352 -211.182204)
			(xy 430.806352 -210.687666) (xy 430.806802 -210.682355) (xy 430.814257 -210.674785) (xy 430.81956 -210.674204)
			(xy 431.335688 -210.674204) (xy 431.343498 -210.673885) (xy 431.358369 -210.669102) (xy 431.364898 -210.664806)
			(xy 431.385987 -210.650457) (xy 431.431648 -210.627726) (xy 431.480254 -210.612267) (xy 431.530657 -210.604444)
			(xy 431.581663 -210.604444) (xy 431.632066 -210.612267) (xy 431.680672 -210.627726) (xy 431.726333 -210.650457)
			(xy 431.747422 -210.664806) (xy 431.753949 -210.669105) (xy 431.768823 -210.673883) (xy 431.776632 -210.674204)
			(xy 432.29276 -210.674204) (xy 432.29809 -210.674555) (xy 432.305634 -210.682083) (xy 432.305968 -210.687412)
			(xy 432.305968 -210.68792) (xy 432.305968 -211.182204) (xy 434.250084 -211.182204) (xy 434.250084 -210.687666)
			(xy 434.250361 -210.682215) (xy 434.258094 -210.674529) (xy 434.263546 -210.674204) (xy 434.779674 -210.674204)
			(xy 434.787483 -210.673879) (xy 434.802354 -210.669101) (xy 434.808884 -210.664806) (xy 434.829973 -210.650457)
			(xy 434.875634 -210.627726) (xy 434.92424 -210.612267) (xy 434.974643 -210.604444) (xy 435.025649 -210.604444)
			(xy 435.076052 -210.612267) (xy 435.124658 -210.627726) (xy 435.170319 -210.650457) (xy 435.191408 -210.664806)
			(xy 435.197938 -210.6691) (xy 435.212809 -210.673881) (xy 435.220618 -210.674204) (xy 435.736746 -210.674204)
			(xy 435.742107 -210.674716) (xy 435.749688 -210.682304) (xy 435.750208 -210.687666) (xy 435.750208 -211.182204)
			(xy 438.350152 -211.182204) (xy 438.350152 -210.687666) (xy 438.350629 -210.682295) (xy 438.358241 -210.67471)
			(xy 438.363614 -210.674204) (xy 438.879742 -210.674204) (xy 438.88755 -210.673865) (xy 438.902421 -210.669096)
			(xy 438.908952 -210.664806) (xy 438.930041 -210.650457) (xy 438.975702 -210.627726) (xy 439.024308 -210.612267)
			(xy 439.074711 -210.604444) (xy 439.125717 -210.604444) (xy 439.17612 -210.612267) (xy 439.224726 -210.627726)
			(xy 439.270387 -210.650457) (xy 439.291476 -210.664806) (xy 439.298013 -210.669087) (xy 439.312879 -210.673876)
			(xy 439.320686 -210.674204) (xy 439.836814 -210.674204) (xy 439.842171 -210.674738) (xy 439.849754 -210.682309)
			(xy 439.850276 -210.687666) (xy 439.850276 -211.182204) (xy 441.794392 -211.182204) (xy 441.794392 -210.687666)
			(xy 441.794895 -210.682369) (xy 441.802314 -210.674803) (xy 441.8076 -210.674204) (xy 442.323728 -210.674204)
			(xy 442.331539 -210.673901) (xy 442.34641 -210.669108) (xy 442.352938 -210.664806) (xy 442.374027 -210.650457)
			(xy 442.419688 -210.627726) (xy 442.468294 -210.612267) (xy 442.518697 -210.604444) (xy 442.569703 -210.604444)
			(xy 442.620106 -210.612267) (xy 442.668712 -210.627726) (xy 442.714373 -210.650457) (xy 442.735462 -210.664806)
			(xy 442.742002 -210.669082) (xy 442.756866 -210.673874) (xy 442.764672 -210.674204) (xy 443.2808 -210.674204)
			(xy 443.286135 -210.674528) (xy 443.293677 -210.682076) (xy 443.294008 -210.687412) (xy 443.294008 -210.68792)
			(xy 443.294008 -211.182204) (xy 445.89446 -211.182204) (xy 445.89446 -210.687666) (xy 445.894903 -210.682353)
			(xy 445.902363 -210.674783) (xy 445.907668 -210.674204) (xy 446.423796 -210.674204) (xy 446.431606 -210.673888)
			(xy 446.446477 -210.669103) (xy 446.453006 -210.664806) (xy 446.474095 -210.650457) (xy 446.519756 -210.627726)
			(xy 446.568362 -210.612267) (xy 446.618765 -210.604444) (xy 446.669771 -210.604444) (xy 446.720174 -210.612267)
			(xy 446.76878 -210.627726) (xy 446.814441 -210.650457) (xy 446.83553 -210.664806) (xy 446.842055 -210.669108)
			(xy 446.85693 -210.673884) (xy 446.86474 -210.674204) (xy 447.380868 -210.674204) (xy 447.386199 -210.67455)
			(xy 447.393742 -210.682082) (xy 447.394076 -210.687412) (xy 447.394076 -210.68792) (xy 447.394076 -211.182204)
			(xy 449.338192 -211.182204) (xy 449.338192 -210.687666) (xy 449.338695 -210.682369) (xy 449.346114 -210.674803)
			(xy 449.3514 -210.674204) (xy 449.867528 -210.674204) (xy 449.875339 -210.673901) (xy 449.89021 -210.669108)
			(xy 449.896738 -210.664806) (xy 449.917827 -210.650457) (xy 449.963488 -210.627726) (xy 450.012094 -210.612267)
			(xy 450.062497 -210.604444) (xy 450.113503 -210.604444) (xy 450.163906 -210.612267) (xy 450.212512 -210.627726)
			(xy 450.258173 -210.650457) (xy 450.279262 -210.664806) (xy 450.285802 -210.669082) (xy 450.300666 -210.673874)
			(xy 450.308472 -210.674204) (xy 450.8246 -210.674204) (xy 450.829935 -210.674528) (xy 450.837477 -210.682076)
			(xy 450.837808 -210.687412) (xy 450.837808 -210.68792) (xy 450.837808 -211.182204) (xy 453.43826 -211.182204)
			(xy 453.43826 -210.687666) (xy 453.438703 -210.682353) (xy 453.446163 -210.674783) (xy 453.451468 -210.674204)
			(xy 453.967596 -210.674204) (xy 453.975406 -210.673888) (xy 453.990277 -210.669103) (xy 453.996806 -210.664806)
			(xy 454.017895 -210.650457) (xy 454.063556 -210.627726) (xy 454.112162 -210.612267) (xy 454.162565 -210.604444)
			(xy 454.213571 -210.604444) (xy 454.263974 -210.612267) (xy 454.31258 -210.627726) (xy 454.358241 -210.650457)
			(xy 454.37933 -210.664806) (xy 454.385855 -210.669108) (xy 454.40073 -210.673884) (xy 454.40854 -210.674204)
			(xy 454.924668 -210.674204) (xy 454.929999 -210.67455) (xy 454.937542 -210.682082) (xy 454.937876 -210.687412)
			(xy 454.937876 -210.68792) (xy 454.937876 -211.182204) (xy 454.937573 -211.187545) (xy 454.930009 -211.195087)
			(xy 454.924668 -211.195412) (xy 454.408794 -211.195412) (xy 454.400921 -211.195711) (xy 454.385917 -211.200487)
			(xy 454.37933 -211.20481) (xy 454.358259 -211.219212) (xy 454.312612 -211.242039) (xy 454.264004 -211.257594)
			(xy 454.213585 -211.265509) (xy 454.188068 -211.266024) (xy 454.162549 -211.265513) (xy 454.112123 -211.257624)
			(xy 454.063511 -211.24207) (xy 454.017872 -211.219222) (xy 453.996806 -211.20481) (xy 453.990214 -211.200495)
			(xy 453.975214 -211.195708) (xy 453.967342 -211.195412) (xy 453.451468 -211.195412) (xy 453.446202 -211.194927)
			(xy 453.438762 -211.187471) (xy 453.43826 -211.182204) (xy 450.837808 -211.182204) (xy 450.837308 -211.187467)
			(xy 450.829863 -211.19491) (xy 450.8246 -211.195412) (xy 450.308726 -211.195412) (xy 450.30085 -211.195682)
			(xy 450.285846 -211.200478) (xy 450.279262 -211.20481) (xy 450.258182 -211.219198) (xy 450.212539 -211.242029)
			(xy 450.163933 -211.257588) (xy 450.113517 -211.265507) (xy 450.088 -211.266024) (xy 450.062479 -211.265547)
			(xy 450.012052 -211.257648) (xy 449.963441 -211.242084) (xy 449.917803 -211.219226) (xy 449.896738 -211.20481)
			(xy 449.890139 -211.200508) (xy 449.875145 -211.195713) (xy 449.867274 -211.195412) (xy 449.3514 -211.195412)
			(xy 449.346138 -211.194906) (xy 449.338696 -211.187466) (xy 449.338192 -211.182204) (xy 447.394076 -211.182204)
			(xy 447.393773 -211.187545) (xy 447.386209 -211.195087) (xy 447.380868 -211.195412) (xy 446.864994 -211.195412)
			(xy 446.857121 -211.195711) (xy 446.842117 -211.200487) (xy 446.83553 -211.20481) (xy 446.814459 -211.219212)
			(xy 446.768812 -211.242039) (xy 446.720204 -211.257594) (xy 446.669785 -211.265509) (xy 446.644268 -211.266024)
			(xy 446.618749 -211.265513) (xy 446.568323 -211.257624) (xy 446.519711 -211.24207) (xy 446.474072 -211.219222)
			(xy 446.453006 -211.20481) (xy 446.446414 -211.200495) (xy 446.431414 -211.195708) (xy 446.423542 -211.195412)
			(xy 445.907668 -211.195412) (xy 445.902402 -211.194927) (xy 445.894962 -211.187471) (xy 445.89446 -211.182204)
			(xy 443.294008 -211.182204) (xy 443.293508 -211.187467) (xy 443.286063 -211.19491) (xy 443.2808 -211.195412)
			(xy 442.764926 -211.195412) (xy 442.75705 -211.195682) (xy 442.742046 -211.200478) (xy 442.735462 -211.20481)
			(xy 442.714382 -211.219198) (xy 442.668739 -211.242029) (xy 442.620133 -211.257588) (xy 442.569717 -211.265507)
			(xy 442.5442 -211.266024) (xy 442.518679 -211.265547) (xy 442.468252 -211.257648) (xy 442.419641 -211.242084)
			(xy 442.374003 -211.219226) (xy 442.352938 -211.20481) (xy 442.346339 -211.200508) (xy 442.331345 -211.195713)
			(xy 442.323474 -211.195412) (xy 441.8076 -211.195412) (xy 441.802338 -211.194906) (xy 441.794896 -211.187466)
			(xy 441.794392 -211.182204) (xy 439.850276 -211.182204) (xy 439.849973 -211.187545) (xy 439.842409 -211.195087)
			(xy 439.837068 -211.195412) (xy 439.83656 -211.195412) (xy 439.32094 -211.195412) (xy 439.313065 -211.195688)
			(xy 439.298061 -211.20048) (xy 439.291476 -211.20481) (xy 439.270393 -211.219192) (xy 439.22475 -211.242024)
			(xy 439.176146 -211.257585) (xy 439.12573 -211.265506) (xy 439.100214 -211.266024) (xy 439.074694 -211.26554)
			(xy 439.024267 -211.257643) (xy 438.975655 -211.242081) (xy 438.930017 -211.219225) (xy 438.908952 -211.20481)
			(xy 438.902372 -211.200474) (xy 438.887363 -211.1957) (xy 438.879488 -211.195412) (xy 438.363614 -211.195412)
			(xy 438.3583 -211.194962) (xy 438.350726 -211.187509) (xy 438.350152 -211.182204) (xy 435.750208 -211.182204)
			(xy 435.749708 -211.187467) (xy 435.742263 -211.19491) (xy 435.737 -211.195412) (xy 435.736492 -211.195412)
			(xy 435.220872 -211.195412) (xy 435.212998 -211.195701) (xy 435.197994 -211.200485) (xy 435.191408 -211.20481)
			(xy 435.170344 -211.219222) (xy 435.124694 -211.242047) (xy 435.076084 -211.257599) (xy 435.025664 -211.265511)
			(xy 435.000146 -211.266024) (xy 434.974626 -211.265524) (xy 434.9242 -211.257632) (xy 434.875588 -211.242075)
			(xy 434.82995 -211.219223) (xy 434.808884 -211.20481) (xy 434.802297 -211.200487) (xy 434.787294 -211.195705)
			(xy 434.77942 -211.195412) (xy 434.263546 -211.195412) (xy 434.258236 -211.19494) (xy 434.25066 -211.187504)
			(xy 434.250084 -211.182204) (xy 432.305968 -211.182204) (xy 432.305672 -211.187547) (xy 432.298104 -211.19509)
			(xy 432.29276 -211.195412) (xy 431.776886 -211.195412) (xy 431.769012 -211.195707) (xy 431.754008 -211.200486)
			(xy 431.747422 -211.20481) (xy 431.726354 -211.219216) (xy 431.680706 -211.242042) (xy 431.632097 -211.257596)
			(xy 431.581678 -211.26551) (xy 431.55616 -211.266024) (xy 431.530641 -211.265517) (xy 431.480215 -211.257627)
			(xy 431.431603 -211.242072) (xy 431.385964 -211.219222) (xy 431.364898 -211.20481) (xy 431.358308 -211.200492)
			(xy 431.343307 -211.195707) (xy 431.335434 -211.195412) (xy 430.81956 -211.195412) (xy 430.814293 -211.194932)
			(xy 430.806853 -211.187472) (xy 430.806352 -211.182204) (xy 428.2059 -211.182204) (xy 428.205575 -211.187539)
			(xy 428.198027 -211.19508) (xy 428.192692 -211.195412) (xy 427.676818 -211.195412) (xy 427.668945 -211.195722)
			(xy 427.653942 -211.200491) (xy 427.647354 -211.20481) (xy 427.626277 -211.219202) (xy 427.580632 -211.242031)
			(xy 427.532026 -211.257589) (xy 427.481609 -211.265508) (xy 427.456092 -211.266024) (xy 427.430573 -211.265501)
			(xy 427.380148 -211.257616) (xy 427.331536 -211.242065) (xy 427.285896 -211.21922) (xy 427.26483 -211.20481)
			(xy 427.258233 -211.200505) (xy 427.243237 -211.195712) (xy 427.235366 -211.195412) (xy 426.719492 -211.195412)
			(xy 426.714229 -211.194911) (xy 426.706787 -211.187467) (xy 426.706284 -211.182204) (xy 424.762168 -211.182204)
			(xy 424.761872 -211.187547) (xy 424.754304 -211.19509) (xy 424.74896 -211.195412) (xy 424.748452 -211.195412)
			(xy 424.232832 -211.195412) (xy 424.224956 -211.195684) (xy 424.209953 -211.200479) (xy 424.203368 -211.20481)
			(xy 424.182287 -211.219196) (xy 424.136644 -211.242027) (xy 424.088039 -211.257586) (xy 424.037622 -211.265506)
			(xy 424.012106 -211.266024) (xy 423.986585 -211.265544) (xy 423.936158 -211.257646) (xy 423.887547 -211.242083)
			(xy 423.841909 -211.219226) (xy 423.820844 -211.20481) (xy 423.814266 -211.200471) (xy 423.799256 -211.195699)
			(xy 423.79138 -211.195412) (xy 423.275506 -211.195412) (xy 423.270191 -211.194967) (xy 423.262617 -211.18751)
			(xy 423.262044 -211.182204) (xy 420.6621 -211.182204) (xy 420.661775 -211.187539) (xy 420.654227 -211.19508)
			(xy 420.648892 -211.195412) (xy 420.648384 -211.195412) (xy 420.132764 -211.195412) (xy 420.124889 -211.195698)
			(xy 420.109886 -211.200483) (xy 420.1033 -211.20481) (xy 420.08221 -211.219182) (xy 420.03657 -211.242016)
			(xy 419.987968 -211.257579) (xy 419.937554 -211.265504) (xy 419.912038 -211.266024) (xy 419.886518 -211.265528)
			(xy 419.836092 -211.257635) (xy 419.78748 -211.242076) (xy 419.741841 -211.219224) (xy 419.720776 -211.20481)
			(xy 419.714191 -211.200484) (xy 419.699186 -211.195704) (xy 419.691312 -211.195412) (xy 419.175438 -211.195412)
			(xy 419.170127 -211.194946) (xy 419.162551 -211.187505) (xy 419.161976 -211.182204) (xy 417.21786 -211.182204)
			(xy 417.217571 -211.187549) (xy 417.209998 -211.195092) (xy 417.204652 -211.195412) (xy 415.731452 -211.195412)
			(xy 415.726184 -211.194937) (xy 415.718745 -211.187473) (xy 415.718244 -211.182204) (xy 413.117792 -211.182204)
			(xy 413.117474 -211.187541) (xy 413.109921 -211.195082) (xy 413.104584 -211.195412) (xy 411.631384 -211.195412)
			(xy 411.62612 -211.194917) (xy 411.618679 -211.187468) (xy 411.618176 -211.182204) (xy 392.22712 -211.182204)
			(xy 392.284562 -211.238839) (xy 392.380159 -211.344408) (xy 392.469631 -211.455217) (xy 392.55269 -211.57091)
			(xy 392.629071 -211.691117) (xy 392.698529 -211.815452) (xy 392.760842 -211.943518) (xy 392.797896 -212.032088)
			(xy 411.618176 -212.032088) (xy 411.618176 -211.53755) (xy 411.618661 -211.532243) (xy 411.626088 -211.524667)
			(xy 411.631384 -211.524088) (xy 413.104584 -211.524088) (xy 413.109913 -211.524437) (xy 413.117455 -211.531967)
			(xy 413.117792 -211.537296) (xy 413.117792 -211.537804) (xy 413.117792 -212.032088) (xy 419.161976 -212.032088)
			(xy 419.161976 -211.53755) (xy 419.162421 -211.532171) (xy 419.170056 -211.524586) (xy 419.175438 -211.524088)
			(xy 419.691566 -211.524088) (xy 419.699375 -211.523762) (xy 419.714247 -211.518985) (xy 419.720776 -211.51469)
			(xy 419.741865 -211.500341) (xy 419.787526 -211.47761) (xy 419.836132 -211.462151) (xy 419.886535 -211.454328)
			(xy 419.937541 -211.454328) (xy 419.987944 -211.462151) (xy 420.03655 -211.47761) (xy 420.082211 -211.500341)
			(xy 420.1033 -211.51469) (xy 420.109833 -211.518979) (xy 420.124702 -211.523764) (xy 420.13251 -211.524088)
			(xy 420.648638 -211.524088) (xy 420.653994 -211.52462) (xy 420.661575 -211.532194) (xy 420.6621 -211.53755)
			(xy 420.6621 -212.032088) (xy 426.706284 -212.032088) (xy 426.706284 -211.53755) (xy 426.706762 -211.532242)
			(xy 426.714194 -211.524665) (xy 426.719492 -211.524088) (xy 427.23562 -211.524088) (xy 427.243431 -211.523785)
			(xy 427.258302 -211.518992) (xy 427.26483 -211.51469) (xy 427.285919 -211.500341) (xy 427.33158 -211.47761)
			(xy 427.380186 -211.462151) (xy 427.430589 -211.454328) (xy 427.481595 -211.454328) (xy 427.531998 -211.462151)
			(xy 427.580604 -211.47761) (xy 427.626265 -211.500341) (xy 427.647354 -211.51469) (xy 427.653875 -211.519)
			(xy 427.668753 -211.523772) (xy 427.676564 -211.524088) (xy 428.192692 -211.524088) (xy 428.198022 -211.524432)
			(xy 428.205563 -211.531966) (xy 428.2059 -211.537296) (xy 428.2059 -211.537804) (xy 428.2059 -212.032088)
			(xy 434.250084 -212.032088) (xy 434.250084 -211.53755) (xy 434.250522 -211.532169) (xy 434.258162 -211.524584)
			(xy 434.263546 -211.524088) (xy 434.779674 -211.524088) (xy 434.787483 -211.523765) (xy 434.802355 -211.518986)
			(xy 434.808884 -211.51469) (xy 434.829973 -211.500341) (xy 434.875634 -211.47761) (xy 434.92424 -211.462151)
			(xy 434.974643 -211.454328) (xy 435.025649 -211.454328) (xy 435.076052 -211.462151) (xy 435.124658 -211.47761)
			(xy 435.170319 -211.500341) (xy 435.191408 -211.51469) (xy 435.197939 -211.518982) (xy 435.212809 -211.523765)
			(xy 435.220618 -211.524088) (xy 435.736746 -211.524088) (xy 435.742103 -211.524615) (xy 435.749684 -211.532193)
			(xy 435.750208 -211.53755) (xy 435.750208 -212.032088) (xy 441.794392 -212.032088) (xy 441.794392 -211.53755)
			(xy 441.794951 -211.532263) (xy 441.802327 -211.524692) (xy 441.8076 -211.524088) (xy 442.323728 -211.524088)
			(xy 442.331539 -211.523788) (xy 442.346411 -211.518993) (xy 442.352938 -211.51469) (xy 442.374027 -211.500341)
			(xy 442.419688 -211.47761) (xy 442.468294 -211.462151) (xy 442.518697 -211.454328) (xy 442.569703 -211.454328)
			(xy 442.620106 -211.462151) (xy 442.668712 -211.47761) (xy 442.714373 -211.500341) (xy 442.735462 -211.51469)
			(xy 442.742003 -211.518965) (xy 442.756866 -211.523758) (xy 442.764672 -211.524088) (xy 443.2808 -211.524088)
			(xy 443.286062 -211.524594) (xy 443.293504 -211.532034) (xy 443.294008 -211.537296) (xy 443.294008 -211.537804)
			(xy 443.294008 -212.032088) (xy 449.338192 -212.032088) (xy 449.338192 -211.53755) (xy 449.338751 -211.532263)
			(xy 449.346127 -211.524692) (xy 449.3514 -211.524088) (xy 449.867528 -211.524088) (xy 449.875339 -211.523788)
			(xy 449.890211 -211.518993) (xy 449.896738 -211.51469) (xy 449.917827 -211.500341) (xy 449.963488 -211.47761)
			(xy 450.012094 -211.462151) (xy 450.062497 -211.454328) (xy 450.113503 -211.454328) (xy 450.163906 -211.462151)
			(xy 450.212512 -211.47761) (xy 450.258173 -211.500341) (xy 450.279262 -211.51469) (xy 450.285803 -211.518965)
			(xy 450.300666 -211.523758) (xy 450.308472 -211.524088) (xy 450.8246 -211.524088) (xy 450.829862 -211.524594)
			(xy 450.837304 -211.532034) (xy 450.837808 -211.537296) (xy 450.837808 -211.537804) (xy 450.837808 -212.032088)
			(xy 450.837465 -212.037419) (xy 450.82993 -212.04496) (xy 450.8246 -212.045296) (xy 450.308726 -212.045296)
			(xy 450.300849 -212.045552) (xy 450.285844 -212.050357) (xy 450.279262 -212.054694) (xy 450.258189 -212.069092)
			(xy 450.212542 -212.091918) (xy 450.163935 -212.107473) (xy 450.113517 -212.115391) (xy 450.088 -212.115908)
			(xy 450.062479 -212.115434) (xy 450.012052 -212.107534) (xy 449.96344 -212.09197) (xy 449.917802 -212.069111)
			(xy 449.896738 -212.054694) (xy 449.89014 -212.05039) (xy 449.875145 -212.045597) (xy 449.867274 -212.045296)
			(xy 449.3514 -212.045296) (xy 449.346065 -212.044972) (xy 449.338523 -212.037424) (xy 449.338192 -212.032088)
			(xy 443.294008 -212.032088) (xy 443.293665 -212.037419) (xy 443.28613 -212.04496) (xy 443.2808 -212.045296)
			(xy 442.764926 -212.045296) (xy 442.757049 -212.045552) (xy 442.742044 -212.050357) (xy 442.735462 -212.054694)
			(xy 442.714389 -212.069092) (xy 442.668742 -212.091918) (xy 442.620135 -212.107473) (xy 442.569717 -212.115391)
			(xy 442.5442 -212.115908) (xy 442.518679 -212.115434) (xy 442.468252 -212.107534) (xy 442.41964 -212.09197)
			(xy 442.374002 -212.069111) (xy 442.352938 -212.054694) (xy 442.34634 -212.05039) (xy 442.331345 -212.045597)
			(xy 442.323474 -212.045296) (xy 441.8076 -212.045296) (xy 441.802265 -212.044972) (xy 441.794723 -212.037424)
			(xy 441.794392 -212.032088) (xy 435.750208 -212.032088) (xy 435.749865 -212.037419) (xy 435.74233 -212.04496)
			(xy 435.737 -212.045296) (xy 435.736492 -212.045296) (xy 435.220872 -212.045296) (xy 435.212996 -212.045571)
			(xy 435.197992 -212.050363) (xy 435.191408 -212.054694) (xy 435.17035 -212.069116) (xy 435.124698 -212.091936)
			(xy 435.076086 -212.107485) (xy 435.025664 -212.115395) (xy 435.000146 -212.115908) (xy 434.974626 -212.115411)
			(xy 434.9242 -212.107518) (xy 434.875588 -212.091961) (xy 434.829949 -212.069108) (xy 434.808884 -212.054694)
			(xy 434.802298 -212.050369) (xy 434.787294 -212.045589) (xy 434.77942 -212.045296) (xy 434.263546 -212.045296)
			(xy 434.258256 -212.04475) (xy 434.250684 -212.037365) (xy 434.250084 -212.032088) (xy 428.2059 -212.032088)
			(xy 428.205564 -212.037421) (xy 428.198024 -212.044963) (xy 428.192692 -212.045296) (xy 427.676818 -212.045296)
			(xy 427.668944 -212.045591) (xy 427.65394 -212.050369) (xy 427.647354 -212.054694) (xy 427.626283 -212.069096)
			(xy 427.580636 -212.091921) (xy 427.532028 -212.107475) (xy 427.481609 -212.115392) (xy 427.456092 -212.115908)
			(xy 427.430573 -212.115388) (xy 427.380147 -212.107502) (xy 427.331536 -212.091951) (xy 427.285896 -212.069105)
			(xy 427.26483 -212.054694) (xy 427.258234 -212.050387) (xy 427.243237 -212.045595) (xy 427.235366 -212.045296)
			(xy 426.719492 -212.045296) (xy 426.714156 -212.044978) (xy 426.706614 -212.037425) (xy 426.706284 -212.032088)
			(xy 420.6621 -212.032088) (xy 420.661764 -212.037421) (xy 420.654224 -212.044963) (xy 420.648892 -212.045296)
			(xy 420.648384 -212.045296) (xy 420.132764 -212.045296) (xy 420.124888 -212.045568) (xy 420.109884 -212.050362)
			(xy 420.1033 -212.054694) (xy 420.082217 -212.069076) (xy 420.036573 -212.091905) (xy 419.987969 -212.107465)
			(xy 419.937554 -212.115388) (xy 419.912038 -212.115908) (xy 419.886518 -212.115415) (xy 419.836091 -212.107521)
			(xy 419.78748 -212.091962) (xy 419.741841 -212.069109) (xy 419.720776 -212.054694) (xy 419.714192 -212.050366)
			(xy 419.699186 -212.045588) (xy 419.691312 -212.045296) (xy 419.175438 -212.045296) (xy 419.170147 -212.044756)
			(xy 419.162576 -212.037366) (xy 419.161976 -212.032088) (xy 413.117792 -212.032088) (xy 413.117463 -212.037422)
			(xy 413.109919 -212.044965) (xy 413.104584 -212.045296) (xy 411.631384 -212.045296) (xy 411.626116 -212.044815)
			(xy 411.618674 -212.037357) (xy 411.618176 -212.032088) (xy 392.797896 -212.032088) (xy 392.815809 -212.074905)
			(xy 392.863255 -212.20919) (xy 392.903028 -212.345945) (xy 392.935 -212.484731) (xy 392.95907 -212.625103)
			(xy 392.975159 -212.766613) (xy 392.981724 -212.88248) (xy 415.718244 -212.88248) (xy 415.718244 -212.387688)
			(xy 415.718782 -212.382435) (xy 415.726201 -212.374996) (xy 415.731452 -212.37448) (xy 417.204652 -212.37448)
			(xy 417.209975 -212.374858) (xy 417.217518 -212.382367) (xy 417.21786 -212.387688) (xy 417.21786 -212.882226)
			(xy 423.262044 -212.882226) (xy 423.262044 -212.387688) (xy 423.262582 -212.382435) (xy 423.270001 -212.374996)
			(xy 423.275252 -212.37448) (xy 423.27576 -212.37448) (xy 423.791634 -212.37448) (xy 423.799442 -212.374141)
			(xy 423.814313 -212.369373) (xy 423.820844 -212.365082) (xy 423.841933 -212.350733) (xy 423.887594 -212.328002)
			(xy 423.9362 -212.312543) (xy 423.986603 -212.30472) (xy 424.037609 -212.30472) (xy 424.088012 -212.312543)
			(xy 424.136618 -212.328002) (xy 424.182279 -212.350733) (xy 424.203368 -212.365082) (xy 424.209909 -212.369358)
			(xy 424.224772 -212.37415) (xy 424.232578 -212.37448) (xy 424.748706 -212.37448) (xy 424.75402 -212.374924)
			(xy 424.761593 -212.382382) (xy 424.762168 -212.387688) (xy 424.762168 -212.882226) (xy 424.762144 -212.88248)
			(xy 430.806352 -212.88248) (xy 430.806352 -212.881972) (xy 430.806352 -212.387688) (xy 430.806883 -212.382434)
			(xy 430.814307 -212.374994) (xy 430.81956 -212.37448) (xy 431.335688 -212.37448) (xy 431.343498 -212.374165)
			(xy 431.35837 -212.36938) (xy 431.364898 -212.365082) (xy 431.385987 -212.350733) (xy 431.431648 -212.328002)
			(xy 431.480254 -212.312543) (xy 431.530657 -212.30472) (xy 431.581663 -212.30472) (xy 431.632066 -212.312543)
			(xy 431.680672 -212.328002) (xy 431.726333 -212.350733) (xy 431.747422 -212.365082) (xy 431.753951 -212.369378)
			(xy 431.768823 -212.374158) (xy 431.776632 -212.37448) (xy 432.29276 -212.37448) (xy 432.298084 -212.374853)
			(xy 432.305626 -212.382365) (xy 432.305968 -212.387688) (xy 432.305968 -212.882226) (xy 438.350152 -212.882226)
			(xy 438.350152 -212.387688) (xy 438.350683 -212.382434) (xy 438.358107 -212.374994) (xy 438.36336 -212.37448)
			(xy 438.363868 -212.37448) (xy 438.879742 -212.37448) (xy 438.88755 -212.374145) (xy 438.902422 -212.369374)
			(xy 438.908952 -212.365082) (xy 438.930041 -212.350733) (xy 438.975702 -212.328002) (xy 439.024308 -212.312543)
			(xy 439.074711 -212.30472) (xy 439.125717 -212.30472) (xy 439.17612 -212.312543) (xy 439.224726 -212.328002)
			(xy 439.270387 -212.350733) (xy 439.291476 -212.365082) (xy 439.298015 -212.369361) (xy 439.312879 -212.374152)
			(xy 439.320686 -212.37448) (xy 439.836814 -212.37448) (xy 439.842129 -212.374919) (xy 439.849702 -212.382381)
			(xy 439.850276 -212.387688) (xy 439.850276 -212.882226) (xy 439.850252 -212.88248) (xy 445.89446 -212.88248)
			(xy 445.89446 -212.881972) (xy 445.89446 -212.387688) (xy 445.894984 -212.382432) (xy 445.902412 -212.374992)
			(xy 445.907668 -212.37448) (xy 446.423796 -212.37448) (xy 446.431606 -212.374168) (xy 446.446478 -212.369381)
			(xy 446.453006 -212.365082) (xy 446.474095 -212.350733) (xy 446.519756 -212.328002) (xy 446.568362 -212.312543)
			(xy 446.618765 -212.30472) (xy 446.669771 -212.30472) (xy 446.720174 -212.312543) (xy 446.76878 -212.328002)
			(xy 446.814441 -212.350733) (xy 446.83553 -212.365082) (xy 446.842057 -212.369381) (xy 446.85693 -212.374159)
			(xy 446.86474 -212.37448) (xy 447.380868 -212.37448) (xy 447.386193 -212.374847) (xy 447.393735 -212.382364)
			(xy 447.394076 -212.387688) (xy 447.394076 -212.882226) (xy 447.394053 -212.88248) (xy 453.43826 -212.88248)
			(xy 453.43826 -212.881972) (xy 453.43826 -212.387688) (xy 453.438784 -212.382432) (xy 453.446212 -212.374992)
			(xy 453.451468 -212.37448) (xy 453.967596 -212.37448) (xy 453.975406 -212.374168) (xy 453.990278 -212.369381)
			(xy 453.996806 -212.365082) (xy 454.017895 -212.350733) (xy 454.063556 -212.328002) (xy 454.112162 -212.312543)
			(xy 454.162565 -212.30472) (xy 454.213571 -212.30472) (xy 454.263974 -212.312543) (xy 454.31258 -212.328002)
			(xy 454.358241 -212.350733) (xy 454.37933 -212.365082) (xy 454.385857 -212.369381) (xy 454.40073 -212.374159)
			(xy 454.40854 -212.37448) (xy 454.924668 -212.37448) (xy 454.929993 -212.374847) (xy 454.937535 -212.382364)
			(xy 454.937876 -212.387688) (xy 454.937876 -212.882226) (xy 454.937396 -212.88753) (xy 454.929962 -212.895098)
			(xy 454.924668 -212.895688) (xy 454.408794 -212.895688) (xy 454.400982 -212.895984) (xy 454.38611 -212.900781)
			(xy 454.379584 -212.905086) (xy 454.358467 -212.919442) (xy 454.312741 -212.942166) (xy 454.264067 -212.957594)
			(xy 454.213599 -212.965359) (xy 454.188068 -212.965792) (xy 454.162537 -212.965367) (xy 454.112073 -212.957586)
			(xy 454.063401 -212.942154) (xy 454.017674 -212.919435) (xy 453.996552 -212.905086) (xy 453.990025 -212.900786)
			(xy 453.975152 -212.896007) (xy 453.967342 -212.895688) (xy 453.451468 -212.895688) (xy 453.446197 -212.895225)
			(xy 453.438755 -212.887753) (xy 453.43826 -212.88248) (xy 447.394053 -212.88248) (xy 447.393596 -212.88753)
			(xy 447.386162 -212.895098) (xy 447.380868 -212.895688) (xy 446.864994 -212.895688) (xy 446.857182 -212.895984)
			(xy 446.84231 -212.900781) (xy 446.835784 -212.905086) (xy 446.814667 -212.919442) (xy 446.768941 -212.942166)
			(xy 446.720267 -212.957594) (xy 446.669799 -212.965359) (xy 446.644268 -212.965792) (xy 446.618737 -212.965367)
			(xy 446.568273 -212.957586) (xy 446.519601 -212.942154) (xy 446.473874 -212.919435) (xy 446.452752 -212.905086)
			(xy 446.446225 -212.900786) (xy 446.431352 -212.896007) (xy 446.423542 -212.895688) (xy 445.907668 -212.895688)
			(xy 445.902397 -212.895225) (xy 445.894955 -212.887753) (xy 445.89446 -212.88248) (xy 439.850252 -212.88248)
			(xy 439.849768 -212.88759) (xy 439.842178 -212.895173) (xy 439.836814 -212.895688) (xy 439.32094 -212.895688)
			(xy 439.31313 -212.896004) (xy 439.298258 -212.900787) (xy 439.29173 -212.905086) (xy 439.270628 -212.919466)
			(xy 439.224897 -212.942185) (xy 439.176218 -212.957606) (xy 439.125747 -212.965363) (xy 439.100214 -212.965792)
			(xy 439.074684 -212.965343) (xy 439.024221 -212.95757) (xy 438.975549 -212.942145) (xy 438.929821 -212.919432)
			(xy 438.908698 -212.905086) (xy 438.902161 -212.900803) (xy 438.887295 -212.896013) (xy 438.879488 -212.895688)
			(xy 438.363614 -212.895688) (xy 438.358258 -212.895143) (xy 438.350673 -212.88758) (xy 438.350152 -212.882226)
			(xy 432.305968 -212.882226) (xy 432.305495 -212.887531) (xy 432.298056 -212.8951) (xy 432.29276 -212.895688)
			(xy 431.776886 -212.895688) (xy 431.769074 -212.895981) (xy 431.754202 -212.90078) (xy 431.747676 -212.905086)
			(xy 431.726561 -212.919446) (xy 431.680835 -212.942169) (xy 431.632159 -212.957596) (xy 431.581691 -212.96536)
			(xy 431.55616 -212.965792) (xy 431.530629 -212.965371) (xy 431.480165 -212.957589) (xy 431.431493 -212.942156)
			(xy 431.385766 -212.919435) (xy 431.364644 -212.905086) (xy 431.358119 -212.900783) (xy 431.343244 -212.896005)
			(xy 431.335434 -212.895688) (xy 430.81956 -212.895688) (xy 430.814287 -212.89523) (xy 430.806846 -212.887755)
			(xy 430.806352 -212.88248) (xy 424.762144 -212.88248) (xy 424.761667 -212.887592) (xy 424.754072 -212.895175)
			(xy 424.748706 -212.895688) (xy 424.232832 -212.895688) (xy 424.225022 -212.896) (xy 424.21015 -212.900786)
			(xy 424.203622 -212.905086) (xy 424.182494 -212.919426) (xy 424.136772 -212.942154) (xy 424.088101 -212.957586)
			(xy 424.037636 -212.965357) (xy 424.012106 -212.965792) (xy 423.986576 -212.965347) (xy 423.936113 -212.957573)
			(xy 423.88744 -212.942146) (xy 423.841712 -212.919432) (xy 423.82059 -212.905086) (xy 423.814055 -212.9008)
			(xy 423.799188 -212.896012) (xy 423.79138 -212.895688) (xy 423.275506 -212.895688) (xy 423.270149 -212.895148)
			(xy 423.262564 -212.887582) (xy 423.262044 -212.882226) (xy 417.21786 -212.882226) (xy 417.217394 -212.887533)
			(xy 417.20995 -212.895103) (xy 417.204652 -212.895688) (xy 415.731452 -212.895688) (xy 415.726179 -212.895235)
			(xy 415.718738 -212.887756) (xy 415.718244 -212.88248) (xy 392.981724 -212.88248) (xy 392.983216 -212.908805)
			(xy 392.98372 -212.980016) (xy 392.983216 -213.051227) (xy 392.975159 -213.193419) (xy 392.95907 -213.334929)
			(xy 392.935 -213.475301) (xy 392.903028 -213.614087) (xy 392.868629 -213.732364) (xy 411.618176 -213.732364)
			(xy 411.618176 -213.731856) (xy 411.618176 -213.237572) (xy 411.618674 -213.23231) (xy 411.626121 -213.22487)
			(xy 411.631384 -213.224364) (xy 413.104584 -213.224364) (xy 413.109838 -213.224902) (xy 413.11728 -213.23232)
			(xy 413.117792 -213.237572) (xy 413.117792 -213.73211) (xy 419.161976 -213.73211) (xy 419.161976 -213.237572)
			(xy 419.162474 -213.23231) (xy 419.169921 -213.22487) (xy 419.175184 -213.224364) (xy 419.175692 -213.224364)
			(xy 419.691566 -213.224364) (xy 419.699375 -213.224042) (xy 419.714247 -213.219262) (xy 419.720776 -213.214966)
			(xy 419.741865 -213.200617) (xy 419.787526 -213.177886) (xy 419.836132 -213.162427) (xy 419.886535 -213.154604)
			(xy 419.937541 -213.154604) (xy 419.987944 -213.162427) (xy 420.03655 -213.177886) (xy 420.082211 -213.200617)
			(xy 420.1033 -213.214966) (xy 420.109834 -213.219253) (xy 420.124702 -213.224039) (xy 420.13251 -213.224364)
			(xy 420.648638 -213.224364) (xy 420.653952 -213.224801) (xy 420.661523 -213.232265) (xy 420.6621 -213.237572)
			(xy 420.6621 -213.73211) (xy 420.662074 -213.732364) (xy 426.706284 -213.732364) (xy 426.706284 -213.731856)
			(xy 426.706284 -213.237572) (xy 426.706775 -213.232308) (xy 426.714227 -213.224867) (xy 426.719492 -213.224364)
			(xy 427.23562 -213.224364) (xy 427.243432 -213.224065) (xy 427.258303 -213.21927) (xy 427.26483 -213.214966)
			(xy 427.285919 -213.200617) (xy 427.33158 -213.177886) (xy 427.380186 -213.162427) (xy 427.430589 -213.154604)
			(xy 427.481595 -213.154604) (xy 427.531998 -213.162427) (xy 427.580604 -213.177886) (xy 427.626265 -213.200617)
			(xy 427.647354 -213.214966) (xy 427.653876 -213.219273) (xy 427.668753 -213.224047) (xy 427.676564 -213.224364)
			(xy 428.192692 -213.224364) (xy 428.197947 -213.224897) (xy 428.205389 -213.232318) (xy 428.2059 -213.237572)
			(xy 428.2059 -213.73211) (xy 434.250084 -213.73211) (xy 434.250084 -213.237572) (xy 434.250575 -213.232308)
			(xy 434.258027 -213.224867) (xy 434.263292 -213.224364) (xy 434.2638 -213.224364) (xy 434.779674 -213.224364)
			(xy 434.787484 -213.224045) (xy 434.802355 -213.219263) (xy 434.808884 -213.214966) (xy 434.829973 -213.200617)
			(xy 434.875634 -213.177886) (xy 434.92424 -213.162427) (xy 434.974643 -213.154604) (xy 435.025649 -213.154604)
			(xy 435.076052 -213.162427) (xy 435.124658 -213.177886) (xy 435.170319 -213.200617) (xy 435.191408 -213.214966)
			(xy 435.197941 -213.219256) (xy 435.21281 -213.22404) (xy 435.220618 -213.224364) (xy 435.736746 -213.224364)
			(xy 435.742049 -213.224862) (xy 435.749625 -213.23228) (xy 435.750208 -213.237572) (xy 435.750208 -213.73211)
			(xy 435.750182 -213.732364) (xy 441.794392 -213.732364) (xy 441.794392 -213.731856) (xy 441.794392 -213.237572)
			(xy 441.794876 -213.232306) (xy 441.802333 -213.224865) (xy 441.8076 -213.224364) (xy 442.323728 -213.224364)
			(xy 442.33154 -213.224068) (xy 442.346411 -213.219271) (xy 442.352938 -213.214966) (xy 442.374027 -213.200617)
			(xy 442.419688 -213.177886) (xy 442.468294 -213.162427) (xy 442.518697 -213.154604) (xy 442.569703 -213.154604)
			(xy 442.620106 -213.162427) (xy 442.668712 -213.177886) (xy 442.714373 -213.200617) (xy 442.735462 -213.214966)
			(xy 442.742005 -213.219238) (xy 442.756866 -213.224033) (xy 442.764672 -213.224364) (xy 443.2808 -213.224364)
			(xy 443.286056 -213.224892) (xy 443.293497 -213.232317) (xy 443.294008 -213.237572) (xy 443.294008 -213.73211)
			(xy 443.293983 -213.732364) (xy 449.338192 -213.732364) (xy 449.338192 -213.731856) (xy 449.338192 -213.237572)
			(xy 449.338676 -213.232306) (xy 449.346133 -213.224865) (xy 449.3514 -213.224364) (xy 449.867528 -213.224364)
			(xy 449.87534 -213.224068) (xy 449.890211 -213.219271) (xy 449.896738 -213.214966) (xy 449.917827 -213.200617)
			(xy 449.963488 -213.177886) (xy 450.012094 -213.162427) (xy 450.062497 -213.154604) (xy 450.113503 -213.154604)
			(xy 450.163906 -213.162427) (xy 450.212512 -213.177886) (xy 450.258173 -213.200617) (xy 450.279262 -213.214966)
			(xy 450.285805 -213.219238) (xy 450.300666 -213.224033) (xy 450.308472 -213.224364) (xy 450.8246 -213.224364)
			(xy 450.829856 -213.224892) (xy 450.837297 -213.232317) (xy 450.837808 -213.237572) (xy 450.837808 -213.73211)
			(xy 450.837289 -213.737404) (xy 450.829882 -213.744972) (xy 450.8246 -213.745572) (xy 450.308726 -213.745572)
			(xy 450.300916 -213.745885) (xy 450.286044 -213.75067) (xy 450.279516 -213.75497) (xy 450.258389 -213.769311)
			(xy 450.212667 -213.792039) (xy 450.163995 -213.807471) (xy 450.11353 -213.815241) (xy 450.088 -213.815676)
			(xy 450.06247 -213.815237) (xy 450.012006 -213.807462) (xy 449.963334 -213.792033) (xy 449.917606 -213.769317)
			(xy 449.896484 -213.75497) (xy 449.889951 -213.750681) (xy 449.875082 -213.745895) (xy 449.867274 -213.745572)
			(xy 449.3514 -213.745572) (xy 449.346059 -213.74527) (xy 449.338516 -213.737706) (xy 449.338192 -213.732364)
			(xy 443.293983 -213.732364) (xy 443.293489 -213.737404) (xy 443.286082 -213.744972) (xy 443.2808 -213.745572)
			(xy 442.764926 -213.745572) (xy 442.757116 -213.745885) (xy 442.742244 -213.75067) (xy 442.735716 -213.75497)
			(xy 442.714589 -213.769311) (xy 442.668867 -213.792039) (xy 442.620195 -213.807471) (xy 442.56973 -213.815241)
			(xy 442.5442 -213.815676) (xy 442.51867 -213.815237) (xy 442.468206 -213.807462) (xy 442.419534 -213.792033)
			(xy 442.373806 -213.769317) (xy 442.352684 -213.75497) (xy 442.346151 -213.750681) (xy 442.331282 -213.745895)
			(xy 442.323474 -213.745572) (xy 441.8076 -213.745572) (xy 441.802259 -213.74527) (xy 441.794716 -213.737706)
			(xy 441.794392 -213.732364) (xy 435.750182 -213.732364) (xy 435.749661 -213.737464) (xy 435.742099 -213.745047)
			(xy 435.736746 -213.745572) (xy 435.220872 -213.745572) (xy 435.21306 -213.745862) (xy 435.198188 -213.750663)
			(xy 435.191662 -213.75497) (xy 435.17055 -213.769334) (xy 435.124822 -213.792057) (xy 435.076146 -213.807483)
			(xy 435.025678 -213.815245) (xy 435.000146 -213.815676) (xy 434.974617 -213.815214) (xy 434.924154 -213.807446)
			(xy 434.875482 -213.792024) (xy 434.829753 -213.769314) (xy 434.80863 -213.75497) (xy 434.802087 -213.750698)
			(xy 434.787226 -213.745902) (xy 434.77942 -213.745572) (xy 434.263546 -213.745572) (xy 434.25812 -213.745191)
			(xy 434.250432 -213.737535) (xy 434.250084 -213.73211) (xy 428.2059 -213.73211) (xy 428.205388 -213.737406)
			(xy 428.197977 -213.744974) (xy 428.192692 -213.745572) (xy 427.676818 -213.745572) (xy 427.669007 -213.745881)
			(xy 427.654135 -213.750669) (xy 427.647608 -213.75497) (xy 427.626483 -213.769314) (xy 427.58076 -213.792041)
			(xy 427.532088 -213.807473) (xy 427.481623 -213.815242) (xy 427.456092 -213.815676) (xy 427.430562 -213.815241)
			(xy 427.380098 -213.807465) (xy 427.331426 -213.792035) (xy 427.285698 -213.769318) (xy 427.264576 -213.75497)
			(xy 427.258045 -213.750678) (xy 427.243175 -213.745894) (xy 427.235366 -213.745572) (xy 426.719492 -213.745572)
			(xy 426.71415 -213.745275) (xy 426.706607 -213.737707) (xy 426.706284 -213.732364) (xy 420.662074 -213.732364)
			(xy 420.66156 -213.737466) (xy 420.653993 -213.745049) (xy 420.648638 -213.745572) (xy 420.132764 -213.745572)
			(xy 420.124955 -213.745901) (xy 420.110083 -213.750675) (xy 420.103554 -213.75497) (xy 420.082444 -213.769337)
			(xy 420.036716 -213.79206) (xy 419.988039 -213.807484) (xy 419.93757 -213.815246) (xy 419.912038 -213.815676)
			(xy 419.886509 -213.815218) (xy 419.836046 -213.807449) (xy 419.787373 -213.792025) (xy 419.741645 -213.769315)
			(xy 419.720522 -213.75497) (xy 419.713981 -213.750695) (xy 419.699118 -213.745901) (xy 419.691312 -213.745572)
			(xy 419.175438 -213.745572) (xy 419.170011 -213.745196) (xy 419.162323 -213.737536) (xy 419.161976 -213.73211)
			(xy 413.117792 -213.73211) (xy 413.117287 -213.737408) (xy 413.109871 -213.744977) (xy 413.104584 -213.745572)
			(xy 411.631384 -213.745572) (xy 411.626041 -213.745281) (xy 411.618498 -213.737709) (xy 411.618176 -213.732364)
			(xy 392.868629 -213.732364) (xy 392.863255 -213.750842) (xy 392.815809 -213.885127) (xy 392.760842 -214.016514)
			(xy 392.698529 -214.14458) (xy 392.629071 -214.268915) (xy 392.55269 -214.389122) (xy 392.469631 -214.504815)
			(xy 392.407108 -214.582248) (xy 415.718244 -214.582248) (xy 415.718244 -214.08771) (xy 415.71873 -214.082406)
			(xy 415.726158 -214.074834) (xy 415.731452 -214.074248) (xy 417.204652 -214.074248) (xy 417.209967 -214.074655)
			(xy 417.217508 -214.082143) (xy 417.21786 -214.087456) (xy 417.21786 -214.582248) (xy 423.262044 -214.582248)
			(xy 423.262044 -214.08771) (xy 423.262386 -214.082275) (xy 423.270071 -214.074588) (xy 423.275506 -214.074248)
			(xy 423.791634 -214.074248) (xy 423.799442 -214.073915) (xy 423.814314 -214.069143) (xy 423.820844 -214.06485)
			(xy 423.841933 -214.050501) (xy 423.887594 -214.02777) (xy 423.9362 -214.012311) (xy 423.986603 -214.004488)
			(xy 424.037609 -214.004488) (xy 424.088012 -214.012311) (xy 424.136618 -214.02777) (xy 424.182279 -214.050501)
			(xy 424.203368 -214.06485) (xy 424.20991 -214.069123) (xy 424.224772 -214.073918) (xy 424.232578 -214.074248)
			(xy 424.748706 -214.074248) (xy 424.754144 -214.074576) (xy 424.76183 -214.082272) (xy 424.762168 -214.08771)
			(xy 424.762168 -214.582248) (xy 430.806352 -214.582248) (xy 430.806352 -214.08771) (xy 430.806831 -214.082404)
			(xy 430.814264 -214.074832) (xy 430.81956 -214.074248) (xy 431.335688 -214.074248) (xy 431.343499 -214.073938)
			(xy 431.35837 -214.06915) (xy 431.364898 -214.06485) (xy 431.385987 -214.050501) (xy 431.431648 -214.02777)
			(xy 431.480254 -214.012311) (xy 431.530657 -214.004488) (xy 431.581663 -214.004488) (xy 431.632066 -214.012311)
			(xy 431.680672 -214.02777) (xy 431.726333 -214.050501) (xy 431.747422 -214.06485) (xy 431.753952 -214.069144)
			(xy 431.768823 -214.073926) (xy 431.776632 -214.074248) (xy 432.29276 -214.074248) (xy 432.298008 -214.074817)
			(xy 432.30545 -214.082212) (xy 432.305968 -214.087456) (xy 432.305968 -214.087964) (xy 432.305968 -214.582248)
			(xy 438.350152 -214.582248) (xy 438.350152 -214.08771) (xy 438.350487 -214.082273) (xy 438.358177 -214.074586)
			(xy 438.363614 -214.074248) (xy 438.879742 -214.074248) (xy 438.887551 -214.073918) (xy 438.902423 -214.069144)
			(xy 438.908952 -214.06485) (xy 438.930041 -214.050501) (xy 438.975702 -214.02777) (xy 439.024308 -214.012311)
			(xy 439.074711 -214.004488) (xy 439.125717 -214.004488) (xy 439.17612 -214.012311) (xy 439.224726 -214.02777)
			(xy 439.270387 -214.050501) (xy 439.291476 -214.06485) (xy 439.298017 -214.069126) (xy 439.31288 -214.073919)
			(xy 439.320686 -214.074248) (xy 439.836814 -214.074248) (xy 439.842182 -214.074742) (xy 439.849767 -214.082341)
			(xy 439.850276 -214.08771) (xy 439.850276 -214.582248) (xy 445.89446 -214.582248) (xy 445.89446 -214.08771)
			(xy 445.894932 -214.082402) (xy 445.90237 -214.074829) (xy 445.907668 -214.074248) (xy 446.423796 -214.074248)
			(xy 446.431607 -214.073941) (xy 446.446478 -214.069151) (xy 446.453006 -214.06485) (xy 446.474095 -214.050501)
			(xy 446.519756 -214.02777) (xy 446.568362 -214.012311) (xy 446.618765 -214.004488) (xy 446.669771 -214.004488)
			(xy 446.720174 -214.012311) (xy 446.76878 -214.02777) (xy 446.814441 -214.050501) (xy 446.83553 -214.06485)
			(xy 446.842059 -214.069147) (xy 446.856931 -214.073927) (xy 446.86474 -214.074248) (xy 447.380868 -214.074248)
			(xy 447.386117 -214.074811) (xy 447.393558 -214.082211) (xy 447.394076 -214.087456) (xy 447.394076 -214.087964)
			(xy 447.394076 -214.582248) (xy 453.43826 -214.582248) (xy 453.43826 -214.08771) (xy 453.438732 -214.082402)
			(xy 453.44617 -214.074829) (xy 453.451468 -214.074248) (xy 453.967596 -214.074248) (xy 453.975407 -214.073941)
			(xy 453.990278 -214.069151) (xy 453.996806 -214.06485) (xy 454.017895 -214.050501) (xy 454.063556 -214.02777)
			(xy 454.112162 -214.012311) (xy 454.162565 -214.004488) (xy 454.213571 -214.004488) (xy 454.263974 -214.012311)
			(xy 454.31258 -214.02777) (xy 454.358241 -214.050501) (xy 454.37933 -214.06485) (xy 454.385859 -214.069147)
			(xy 454.400731 -214.073927) (xy 454.40854 -214.074248) (xy 454.924668 -214.074248) (xy 454.929917 -214.074811)
			(xy 454.937358 -214.082211) (xy 454.937876 -214.087456) (xy 454.937876 -214.087964) (xy 454.937876 -214.582248)
			(xy 454.937434 -214.587524) (xy 454.929947 -214.594966) (xy 454.924668 -214.595456) (xy 454.408794 -214.595456)
			(xy 454.40092 -214.595748) (xy 454.385916 -214.600529) (xy 454.37933 -214.604854) (xy 454.358263 -214.619261)
			(xy 454.312614 -214.642086) (xy 454.264005 -214.657639) (xy 454.213586 -214.665553) (xy 454.188068 -214.666068)
			(xy 454.162548 -214.665567) (xy 454.112121 -214.657677) (xy 454.06351 -214.64212) (xy 454.017871 -214.619268)
			(xy 453.996806 -214.604854) (xy 453.990212 -214.600544) (xy 453.975214 -214.595753) (xy 453.967342 -214.595456)
			(xy 453.451468 -214.595456) (xy 453.446213 -214.594931) (xy 453.438775 -214.587502) (xy 453.43826 -214.582248)
			(xy 447.394076 -214.582248) (xy 447.393634 -214.587524) (xy 447.386147 -214.594966) (xy 447.380868 -214.595456)
			(xy 446.864994 -214.595456) (xy 446.85712 -214.595748) (xy 446.842116 -214.600529) (xy 446.83553 -214.604854)
			(xy 446.814463 -214.619261) (xy 446.768814 -214.642086) (xy 446.720205 -214.657639) (xy 446.669786 -214.665553)
			(xy 446.644268 -214.666068) (xy 446.618748 -214.665567) (xy 446.568321 -214.657677) (xy 446.51971 -214.64212)
			(xy 446.474071 -214.619268) (xy 446.453006 -214.604854) (xy 446.446412 -214.600544) (xy 446.431414 -214.595753)
			(xy 446.423542 -214.595456) (xy 445.907668 -214.595456) (xy 445.902413 -214.594931) (xy 445.894975 -214.587502)
			(xy 445.89446 -214.582248) (xy 439.850276 -214.582248) (xy 439.849834 -214.587524) (xy 439.842347 -214.594966)
			(xy 439.837068 -214.595456) (xy 439.83656 -214.595456) (xy 439.32094 -214.595456) (xy 439.313064 -214.595724)
			(xy 439.29806 -214.600521) (xy 439.291476 -214.604854) (xy 439.270396 -214.619242) (xy 439.224752 -214.642071)
			(xy 439.176147 -214.65763) (xy 439.12573 -214.66555) (xy 439.100214 -214.666068) (xy 439.074693 -214.665594)
			(xy 439.024265 -214.657696) (xy 438.975654 -214.642131) (xy 438.930016 -214.619272) (xy 438.908952 -214.604854)
			(xy 438.90237 -214.600523) (xy 438.887363 -214.595745) (xy 438.879488 -214.595456) (xy 438.363614 -214.595456)
			(xy 438.358311 -214.594967) (xy 438.350739 -214.587541) (xy 438.350152 -214.582248) (xy 432.305968 -214.582248)
			(xy 432.305533 -214.587526) (xy 432.298041 -214.594968) (xy 432.29276 -214.595456) (xy 431.776886 -214.595456)
			(xy 431.769012 -214.595744) (xy 431.754008 -214.600527) (xy 431.747422 -214.604854) (xy 431.726357 -214.619265)
			(xy 431.680708 -214.642089) (xy 431.632098 -214.657641) (xy 431.581678 -214.665554) (xy 431.55616 -214.666068)
			(xy 431.53064 -214.665571) (xy 431.480213 -214.65768) (xy 431.431601 -214.642122) (xy 431.385963 -214.619269)
			(xy 431.364898 -214.604854) (xy 431.358305 -214.600541) (xy 431.343306 -214.595752) (xy 431.335434 -214.595456)
			(xy 430.81956 -214.595456) (xy 430.814304 -214.594937) (xy 430.806866 -214.587504) (xy 430.806352 -214.582248)
			(xy 424.762168 -214.582248) (xy 424.761733 -214.587526) (xy 424.754241 -214.594968) (xy 424.74896 -214.595456)
			(xy 424.748452 -214.595456) (xy 424.232832 -214.595456) (xy 424.224955 -214.595721) (xy 424.209951 -214.60052)
			(xy 424.203368 -214.604854) (xy 424.18229 -214.619245) (xy 424.136645 -214.642073) (xy 424.08804 -214.657631)
			(xy 424.037623 -214.665551) (xy 424.012106 -214.666068) (xy 423.986585 -214.665598) (xy 423.936157 -214.657699)
			(xy 423.887545 -214.642133) (xy 423.841908 -214.619272) (xy 423.820844 -214.604854) (xy 423.814264 -214.60052)
			(xy 423.799255 -214.595744) (xy 423.79138 -214.595456) (xy 423.275506 -214.595456) (xy 423.270202 -214.594972)
			(xy 423.26263 -214.587542) (xy 423.262044 -214.582248) (xy 417.21786 -214.582248) (xy 417.217432 -214.587528)
			(xy 417.209936 -214.594971) (xy 417.204652 -214.595456) (xy 415.731452 -214.595456) (xy 415.726195 -214.594942)
			(xy 415.718758 -214.587505) (xy 415.718244 -214.582248) (xy 392.407108 -214.582248) (xy 392.380159 -214.615624)
			(xy 392.284562 -214.721193) (xy 392.183145 -214.821185) (xy 392.076233 -214.915279) (xy 391.964169 -215.003173)
			(xy 391.847313 -215.084587) (xy 391.726037 -215.15926) (xy 391.600731 -215.226951) (xy 391.471796 -215.287445)
			(xy 391.339645 -215.340548) (xy 391.204702 -215.386089) (xy 391.067398 -215.423923) (xy 391.029308 -215.432132)
			(xy 411.618176 -215.432132) (xy 411.618176 -214.937594) (xy 411.618623 -214.932281) (xy 411.626079 -214.924708)
			(xy 411.631384 -214.924132) (xy 413.104584 -214.924132) (xy 413.109924 -214.924441) (xy 413.117468 -214.932)
			(xy 413.117792 -214.93734) (xy 413.117792 -214.937848) (xy 413.117792 -215.432132) (xy 419.161976 -215.432132)
			(xy 419.161976 -214.937594) (xy 419.162279 -214.932149) (xy 419.169992 -214.924461) (xy 419.175438 -214.924132)
			(xy 419.691566 -214.924132) (xy 419.699376 -214.923815) (xy 419.714248 -214.919033) (xy 419.720776 -214.914734)
			(xy 419.741865 -214.900385) (xy 419.787526 -214.877654) (xy 419.836132 -214.862195) (xy 419.886535 -214.854372)
			(xy 419.937541 -214.854372) (xy 419.987944 -214.862195) (xy 420.03655 -214.877654) (xy 420.082211 -214.900385)
			(xy 420.1033 -214.914734) (xy 420.109836 -214.919018) (xy 420.124702 -214.923807) (xy 420.13251 -214.924132)
			(xy 420.648638 -214.924132) (xy 420.654005 -214.924625) (xy 420.661588 -214.932226) (xy 420.6621 -214.937594)
			(xy 420.6621 -215.432132) (xy 426.706284 -215.432132) (xy 426.706284 -214.937594) (xy 426.706724 -214.932279)
			(xy 426.714185 -214.924705) (xy 426.719492 -214.924132) (xy 427.23562 -214.924132) (xy 427.243432 -214.923838)
			(xy 427.258304 -214.91904) (xy 427.26483 -214.914734) (xy 427.285919 -214.900385) (xy 427.33158 -214.877654)
			(xy 427.380186 -214.862195) (xy 427.430589 -214.854372) (xy 427.481595 -214.854372) (xy 427.531998 -214.862195)
			(xy 427.580604 -214.877654) (xy 427.626265 -214.900385) (xy 427.647354 -214.914734) (xy 427.653878 -214.919038)
			(xy 427.668754 -214.923814) (xy 427.676564 -214.924132) (xy 428.192692 -214.924132) (xy 428.198033 -214.924436)
			(xy 428.205577 -214.931998) (xy 428.2059 -214.93734) (xy 428.2059 -214.937848) (xy 428.2059 -215.432132)
			(xy 434.250084 -215.432132) (xy 434.250084 -214.937594) (xy 434.25038 -214.932147) (xy 434.258098 -214.924459)
			(xy 434.263546 -214.924132) (xy 434.779674 -214.924132) (xy 434.787484 -214.923819) (xy 434.802356 -214.919034)
			(xy 434.808884 -214.914734) (xy 434.829973 -214.900385) (xy 434.875634 -214.877654) (xy 434.92424 -214.862195)
			(xy 434.974643 -214.854372) (xy 435.025649 -214.854372) (xy 435.076052 -214.862195) (xy 435.124658 -214.877654)
			(xy 435.170319 -214.900385) (xy 435.191408 -214.914734) (xy 435.197942 -214.919021) (xy 435.21281 -214.923808)
			(xy 435.220618 -214.924132) (xy 435.736746 -214.924132) (xy 435.742114 -214.924619) (xy 435.749697 -214.932225)
			(xy 435.750208 -214.937594) (xy 435.750208 -215.432132) (xy 441.794392 -215.432132) (xy 441.794392 -214.937594)
			(xy 441.794913 -214.9323) (xy 441.802318 -214.924732) (xy 441.8076 -214.924132) (xy 442.323728 -214.924132)
			(xy 442.33154 -214.923842) (xy 442.346412 -214.919041) (xy 442.352938 -214.914734) (xy 442.374027 -214.900385)
			(xy 442.419688 -214.877654) (xy 442.468294 -214.862195) (xy 442.518697 -214.854372) (xy 442.569703 -214.854372)
			(xy 442.620106 -214.862195) (xy 442.668712 -214.877654) (xy 442.714373 -214.900385) (xy 442.735462 -214.914734)
			(xy 442.742007 -214.919003) (xy 442.756866 -214.923801) (xy 442.764672 -214.924132) (xy 443.2808 -214.924132)
			(xy 443.286142 -214.924431) (xy 443.293685 -214.931997) (xy 443.294008 -214.93734) (xy 443.294008 -214.937848)
			(xy 443.294008 -215.432132) (xy 449.338192 -215.432132) (xy 449.338192 -214.937594) (xy 449.338713 -214.9323)
			(xy 449.346118 -214.924732) (xy 449.3514 -214.924132) (xy 449.867528 -214.924132) (xy 449.87534 -214.923842)
			(xy 449.890212 -214.919041) (xy 449.896738 -214.914734) (xy 449.917827 -214.900385) (xy 449.963488 -214.877654)
			(xy 450.012094 -214.862195) (xy 450.062497 -214.854372) (xy 450.113503 -214.854372) (xy 450.163906 -214.862195)
			(xy 450.212512 -214.877654) (xy 450.258173 -214.900385) (xy 450.279262 -214.914734) (xy 450.285807 -214.919003)
			(xy 450.300666 -214.923801) (xy 450.308472 -214.924132) (xy 450.8246 -214.924132) (xy 450.829942 -214.924431)
			(xy 450.837485 -214.931997) (xy 450.837808 -214.93734) (xy 450.837808 -214.937848) (xy 450.837808 -215.432132)
			(xy 450.837327 -215.437399) (xy 450.829868 -215.444839) (xy 450.8246 -215.44534) (xy 450.308726 -215.44534)
			(xy 450.300849 -215.445605) (xy 450.285846 -215.450404) (xy 450.279262 -215.454738) (xy 450.258185 -215.46913)
			(xy 450.21254 -215.491958) (xy 450.163934 -215.507516) (xy 450.113517 -215.515435) (xy 450.088 -215.515952)
			(xy 450.06248 -215.51547) (xy 450.012053 -215.507572) (xy 449.963441 -215.492009) (xy 449.917803 -215.469153)
			(xy 449.896738 -215.454738) (xy 449.890137 -215.450439) (xy 449.875144 -215.445642) (xy 449.867274 -215.44534)
			(xy 449.3514 -215.44534) (xy 449.346145 -215.444808) (xy 449.338704 -215.437386) (xy 449.338192 -215.432132)
			(xy 443.294008 -215.432132) (xy 443.293527 -215.437399) (xy 443.286068 -215.444839) (xy 443.2808 -215.44534)
			(xy 442.764926 -215.44534) (xy 442.757049 -215.445605) (xy 442.742046 -215.450404) (xy 442.735462 -215.454738)
			(xy 442.714385 -215.46913) (xy 442.66874 -215.491958) (xy 442.620134 -215.507516) (xy 442.569717 -215.515435)
			(xy 442.5442 -215.515952) (xy 442.51868 -215.51547) (xy 442.468253 -215.507572) (xy 442.419641 -215.492009)
			(xy 442.374003 -215.469153) (xy 442.352938 -215.454738) (xy 442.346337 -215.450439) (xy 442.331344 -215.445642)
			(xy 442.323474 -215.44534) (xy 441.8076 -215.44534) (xy 441.802345 -215.444808) (xy 441.794904 -215.437386)
			(xy 441.794392 -215.432132) (xy 435.750208 -215.432132) (xy 435.749727 -215.437399) (xy 435.742268 -215.444839)
			(xy 435.737 -215.44534) (xy 435.736492 -215.44534) (xy 435.220872 -215.44534) (xy 435.212997 -215.445625)
			(xy 435.197993 -215.450411) (xy 435.191408 -215.454738) (xy 435.170346 -215.469153) (xy 435.124696 -215.491976)
			(xy 435.076085 -215.507528) (xy 435.025664 -215.515439) (xy 435.000146 -215.515952) (xy 434.974627 -215.515447)
			(xy 434.924201 -215.507555) (xy 434.875589 -215.492) (xy 434.82995 -215.46915) (xy 434.808884 -215.454738)
			(xy 434.802296 -215.450418) (xy 434.787293 -215.445634) (xy 434.77942 -215.44534) (xy 434.263546 -215.44534)
			(xy 434.258243 -215.444844) (xy 434.250668 -215.437424) (xy 434.250084 -215.432132) (xy 428.2059 -215.432132)
			(xy 428.205426 -215.437401) (xy 428.197962 -215.444842) (xy 428.192692 -215.44534) (xy 427.676818 -215.44534)
			(xy 427.668945 -215.445645) (xy 427.653941 -215.450417) (xy 427.647354 -215.454738) (xy 427.626279 -215.469133)
			(xy 427.580633 -215.491961) (xy 427.532027 -215.507518) (xy 427.481609 -215.515436) (xy 427.456092 -215.515952)
			(xy 427.430573 -215.515424) (xy 427.380149 -215.507539) (xy 427.331537 -215.49199) (xy 427.285897 -215.469147)
			(xy 427.26483 -215.454738) (xy 427.258231 -215.450436) (xy 427.243237 -215.44564) (xy 427.235366 -215.44534)
			(xy 426.719492 -215.44534) (xy 426.714236 -215.444814) (xy 426.706796 -215.437387) (xy 426.706284 -215.432132)
			(xy 420.6621 -215.432132) (xy 420.661626 -215.437401) (xy 420.654162 -215.444842) (xy 420.648892 -215.44534)
			(xy 420.648384 -215.44534) (xy 420.132764 -215.44534) (xy 420.124889 -215.445621) (xy 420.109885 -215.450409)
			(xy 420.1033 -215.454738) (xy 420.082212 -215.469113) (xy 420.036571 -215.491946) (xy 419.987968 -215.507508)
			(xy 419.937554 -215.515432) (xy 419.912038 -215.515952) (xy 419.886518 -215.515451) (xy 419.836092 -215.507558)
			(xy 419.787481 -215.492001) (xy 419.741842 -215.469151) (xy 419.720776 -215.454738) (xy 419.714189 -215.450415)
			(xy 419.699186 -215.445632) (xy 419.691312 -215.44534) (xy 419.175438 -215.44534) (xy 419.170134 -215.444849)
			(xy 419.162559 -215.437426) (xy 419.161976 -215.432132) (xy 413.117792 -215.432132) (xy 413.117325 -215.437402)
			(xy 413.109856 -215.444844) (xy 413.104584 -215.44534) (xy 411.631384 -215.44534) (xy 411.626127 -215.444819)
			(xy 411.618687 -215.437388) (xy 411.618176 -215.432132) (xy 391.029308 -215.432132) (xy 390.928173 -215.453928)
			(xy 390.787474 -215.476008) (xy 390.645752 -215.490094) (xy 390.503459 -215.496138) (xy 390.361052 -215.494123)
			(xy 390.218987 -215.484054) (xy 390.07772 -215.465964) (xy 389.937702 -215.439911) (xy 389.799383 -215.405978)
			(xy 389.663204 -215.364273) (xy 389.529604 -215.314932) (xy 389.399008 -215.258111) (xy 389.271837 -215.193992)
			(xy 389.148497 -215.122782) (xy 389.029383 -215.044707) (xy 388.914877 -214.960019) (xy 388.805345 -214.868988)
			(xy 388.701139 -214.771907) (xy 388.602593 -214.669085) (xy 388.510021 -214.560852) (xy 388.423721 -214.447556)
			(xy 388.343969 -214.329559) (xy 388.27102 -214.207239) (xy 388.205108 -214.080988) (xy 388.146445 -213.951209)
			(xy 388.095218 -213.81832) (xy 388.051591 -213.682746) (xy 388.015704 -213.54492) (xy 387.987672 -213.405285)
			(xy 387.967584 -213.264288) (xy 387.955506 -213.12238) (xy 387.951476 -212.980016) (xy 331.783436 -212.980016)
			(xy 331.782932 -213.051212) (xy 331.774877 -213.193376) (xy 331.758791 -213.334857) (xy 331.734726 -213.475201)
			(xy 331.70276 -213.613959) (xy 331.662996 -213.750686) (xy 331.615559 -213.884945) (xy 331.560603 -214.016304)
			(xy 331.498303 -214.144345) (xy 331.428859 -214.268655) (xy 331.352493 -214.388838) (xy 331.269451 -214.504507)
			(xy 331.179997 -214.615293) (xy 331.084419 -214.720841) (xy 330.983022 -214.820813) (xy 330.876132 -214.914888)
			(xy 330.764091 -215.002765) (xy 330.647258 -215.084163) (xy 330.526007 -215.15882) (xy 330.400726 -215.226498)
			(xy 330.271817 -215.28698) (xy 330.139693 -215.340071) (xy 330.004777 -215.385603) (xy 329.867501 -215.423429)
			(xy 329.728304 -215.453429) (xy 329.587634 -215.475505) (xy 329.44594 -215.489587) (xy 329.303676 -215.49563)
			(xy 329.161298 -215.493615) (xy 329.019262 -215.483548) (xy 328.878023 -215.465462) (xy 328.738033 -215.439414)
			(xy 328.599742 -215.405488) (xy 328.463591 -215.363792) (xy 328.330017 -215.31446) (xy 328.199448 -215.257651)
			(xy 328.072302 -215.193545) (xy 327.948987 -215.122349) (xy 327.829897 -215.044291) (xy 327.715414 -214.959619)
			(xy 327.605905 -214.868607) (xy 327.50172 -214.771545) (xy 327.403193 -214.668744) (xy 327.31064 -214.560533)
			(xy 327.224358 -214.44726) (xy 327.144621 -214.329287) (xy 327.071687 -214.206991) (xy 327.005789 -214.080765)
			(xy 326.947138 -213.951013) (xy 326.895921 -213.818151) (xy 326.852303 -213.682604) (xy 326.816423 -213.544806)
			(xy 326.788396 -213.405199) (xy 326.768313 -213.264231) (xy 326.756238 -213.122351) (xy 326.752208 -212.980016)
			(xy 256.30886 -212.980016) (xy 256.30886 -213.73211) (xy 264.798048 -213.73211) (xy 264.798048 -213.237572)
			(xy 264.798571 -213.232316) (xy 264.806001 -213.224878) (xy 264.811256 -213.224364) (xy 264.811764 -213.224364)
			(xy 265.327638 -213.224364) (xy 265.335446 -213.22403) (xy 265.350318 -213.219258) (xy 265.356848 -213.214966)
			(xy 265.377937 -213.200617) (xy 265.423598 -213.177886) (xy 265.472204 -213.162427) (xy 265.522607 -213.154604)
			(xy 265.573613 -213.154604) (xy 265.624016 -213.162427) (xy 265.672622 -213.177886) (xy 265.718283 -213.200617)
			(xy 265.739372 -213.214966) (xy 265.745913 -213.219242) (xy 265.760776 -213.224035) (xy 265.768582 -213.224364)
			(xy 266.28471 -213.224364) (xy 266.290021 -213.224819) (xy 266.297593 -213.23227) (xy 266.298172 -213.237572)
			(xy 266.298172 -213.73211) (xy 266.298148 -213.732364) (xy 272.342356 -213.732364) (xy 272.342356 -213.731856)
			(xy 272.342356 -213.237572) (xy 272.342872 -213.232315) (xy 272.350307 -213.224875) (xy 272.355564 -213.224364)
			(xy 272.871692 -213.224364) (xy 272.879502 -213.224053) (xy 272.894374 -213.219266) (xy 272.900902 -213.214966)
			(xy 272.921991 -213.200617) (xy 272.967652 -213.177886) (xy 273.016258 -213.162427) (xy 273.066661 -213.154604)
			(xy 273.117667 -213.154604) (xy 273.16807 -213.162427) (xy 273.216676 -213.177886) (xy 273.262337 -213.200617)
			(xy 273.283426 -213.214966) (xy 273.289955 -213.219263) (xy 273.304827 -213.224043) (xy 273.312636 -213.224364)
			(xy 273.828764 -213.224364) (xy 273.834085 -213.224748) (xy 273.841626 -213.232253) (xy 273.841972 -213.237572)
			(xy 273.841972 -213.73211) (xy 273.841949 -213.732364) (xy 279.886156 -213.732364) (xy 279.886156 -213.731856)
			(xy 279.886156 -213.237572) (xy 279.886672 -213.232315) (xy 279.894107 -213.224875) (xy 279.899364 -213.224364)
			(xy 280.415492 -213.224364) (xy 280.423302 -213.224053) (xy 280.438174 -213.219266) (xy 280.444702 -213.214966)
			(xy 280.465791 -213.200617) (xy 280.511452 -213.177886) (xy 280.560058 -213.162427) (xy 280.610461 -213.154604)
			(xy 280.661467 -213.154604) (xy 280.71187 -213.162427) (xy 280.760476 -213.177886) (xy 280.806137 -213.200617)
			(xy 280.827226 -213.214966) (xy 280.833755 -213.219263) (xy 280.848627 -213.224043) (xy 280.856436 -213.224364)
			(xy 281.372564 -213.224364) (xy 281.377885 -213.224748) (xy 281.385426 -213.232253) (xy 281.385772 -213.237572)
			(xy 281.385772 -213.73211) (xy 287.429956 -213.73211) (xy 287.429956 -213.237572) (xy 287.430472 -213.232315)
			(xy 287.437907 -213.224875) (xy 287.443164 -213.224364) (xy 287.443672 -213.224364) (xy 287.959546 -213.224364)
			(xy 287.967355 -213.224033) (xy 287.982226 -213.21926) (xy 287.988756 -213.214966) (xy 288.009845 -213.200617)
			(xy 288.055506 -213.177886) (xy 288.104112 -213.162427) (xy 288.154515 -213.154604) (xy 288.205521 -213.154604)
			(xy 288.255924 -213.162427) (xy 288.30453 -213.177886) (xy 288.350191 -213.200617) (xy 288.37128 -213.214966)
			(xy 288.377819 -213.219245) (xy 288.392683 -213.224036) (xy 288.40049 -213.224364) (xy 288.916618 -213.224364)
			(xy 288.92193 -213.224814) (xy 288.929502 -213.232268) (xy 288.93008 -213.237572) (xy 288.93008 -213.73211)
			(xy 288.930055 -213.732364) (xy 294.974264 -213.732364) (xy 294.974264 -213.731856) (xy 294.974264 -213.237572)
			(xy 294.974773 -213.232313) (xy 294.982213 -213.224873) (xy 294.987472 -213.224364) (xy 295.5036 -213.224364)
			(xy 295.511411 -213.224057) (xy 295.526282 -213.219267) (xy 295.53281 -213.214966) (xy 295.553899 -213.200617)
			(xy 295.59956 -213.177886) (xy 295.648166 -213.162427) (xy 295.698569 -213.154604) (xy 295.749575 -213.154604)
			(xy 295.799978 -213.162427) (xy 295.848584 -213.177886) (xy 295.894245 -213.200617) (xy 295.915334 -213.214966)
			(xy 295.921861 -213.219266) (xy 295.936734 -213.224044) (xy 295.944544 -213.224364) (xy 296.460672 -213.224364)
			(xy 296.465925 -213.22491) (xy 296.473367 -213.232322) (xy 296.47388 -213.237572) (xy 296.47388 -213.73211)
			(xy 302.518064 -213.73211) (xy 302.518064 -213.237572) (xy 302.518573 -213.232313) (xy 302.526013 -213.224873)
			(xy 302.531272 -213.224364) (xy 304.004726 -213.224364) (xy 304.010039 -213.224809) (xy 304.01761 -213.232267)
			(xy 304.018188 -213.237572) (xy 304.018188 -213.73211) (xy 304.017659 -213.737469) (xy 304.010084 -213.745052)
			(xy 304.004726 -213.745572) (xy 302.531526 -213.745572) (xy 302.526097 -213.745204) (xy 302.51841 -213.737538)
			(xy 302.518064 -213.73211) (xy 296.47388 -213.73211) (xy 296.473386 -213.737411) (xy 296.465962 -213.74498)
			(xy 296.460672 -213.745572) (xy 295.944798 -213.745572) (xy 295.936987 -213.745873) (xy 295.922115 -213.750666)
			(xy 295.915588 -213.75497) (xy 295.894469 -213.769323) (xy 295.848744 -213.792048) (xy 295.80007 -213.807477)
			(xy 295.749603 -213.815243) (xy 295.724072 -213.815676) (xy 295.698541 -213.815251) (xy 295.648077 -213.807472)
			(xy 295.599405 -213.792039) (xy 295.553678 -213.769319) (xy 295.532556 -213.75497) (xy 295.526029 -213.75067)
			(xy 295.511156 -213.745891) (xy 295.503346 -213.745572) (xy 294.987472 -213.745572) (xy 294.982127 -213.745288)
			(xy 294.974586 -213.73771) (xy 294.974264 -213.732364) (xy 288.930055 -213.732364) (xy 288.929558 -213.737471)
			(xy 288.921978 -213.745055) (xy 288.916618 -213.745572) (xy 288.400744 -213.745572) (xy 288.392934 -213.745892)
			(xy 288.378062 -213.750672) (xy 288.371534 -213.75497) (xy 288.35043 -213.769346) (xy 288.304699 -213.792066)
			(xy 288.256021 -213.807489) (xy 288.20555 -213.815247) (xy 288.180018 -213.815676) (xy 288.154488 -213.815228)
			(xy 288.104025 -213.807455) (xy 288.055352 -213.79203) (xy 288.009624 -213.769316) (xy 287.988502 -213.75497)
			(xy 287.981965 -213.750687) (xy 287.967099 -213.745898) (xy 287.959292 -213.745572) (xy 287.443418 -213.745572)
			(xy 287.437988 -213.74521) (xy 287.430301 -213.737539) (xy 287.429956 -213.73211) (xy 281.385772 -213.73211)
			(xy 281.385285 -213.737413) (xy 281.377856 -213.744982) (xy 281.372564 -213.745572) (xy 280.85669 -213.745572)
			(xy 280.848878 -213.745869) (xy 280.834007 -213.750665) (xy 280.82748 -213.75497) (xy 280.806363 -213.769326)
			(xy 280.760637 -213.792051) (xy 280.711963 -213.807479) (xy 280.661495 -213.815244) (xy 280.635964 -213.815676)
			(xy 280.610433 -213.815255) (xy 280.559969 -213.807474) (xy 280.511296 -213.79204) (xy 280.465569 -213.769319)
			(xy 280.444448 -213.75497) (xy 280.437923 -213.750667) (xy 280.423048 -213.74589) (xy 280.415238 -213.745572)
			(xy 279.899364 -213.745572) (xy 279.894088 -213.745125) (xy 279.886646 -213.737642) (xy 279.886156 -213.732364)
			(xy 273.841949 -213.732364) (xy 273.841485 -213.737413) (xy 273.834056 -213.744982) (xy 273.828764 -213.745572)
			(xy 273.31289 -213.745572) (xy 273.305078 -213.745869) (xy 273.290207 -213.750665) (xy 273.28368 -213.75497)
			(xy 273.262563 -213.769326) (xy 273.216837 -213.792051) (xy 273.168163 -213.807479) (xy 273.117695 -213.815244)
			(xy 273.092164 -213.815676) (xy 273.066633 -213.815255) (xy 273.016169 -213.807474) (xy 272.967496 -213.79204)
			(xy 272.921769 -213.769319) (xy 272.900648 -213.75497) (xy 272.894123 -213.750667) (xy 272.879248 -213.74589)
			(xy 272.871438 -213.745572) (xy 272.355564 -213.745572) (xy 272.350288 -213.745125) (xy 272.342846 -213.737642)
			(xy 272.342356 -213.732364) (xy 266.298148 -213.732364) (xy 266.297657 -213.737473) (xy 266.290073 -213.745057)
			(xy 266.28471 -213.745572) (xy 265.768836 -213.745572) (xy 265.761026 -213.745889) (xy 265.746154 -213.750671)
			(xy 265.739626 -213.75497) (xy 265.718496 -213.769306) (xy 265.672775 -213.792035) (xy 265.624104 -213.807469)
			(xy 265.57364 -213.81524) (xy 265.54811 -213.815676) (xy 265.52258 -213.815232) (xy 265.472117 -213.807458)
			(xy 265.423444 -213.792031) (xy 265.377716 -213.769316) (xy 265.356594 -213.75497) (xy 265.350059 -213.750684)
			(xy 265.335192 -213.745897) (xy 265.327384 -213.745572) (xy 264.81151 -213.745572) (xy 264.80615 -213.745044)
			(xy 264.798564 -213.737469) (xy 264.798048 -213.73211) (xy 256.30886 -213.73211) (xy 256.30886 -213.806024)
			(xy 256.308374 -213.833293) (xy 256.300612 -213.887277) (xy 256.285247 -213.939607) (xy 256.26259 -213.989217)
			(xy 256.233104 -214.035098) (xy 256.197389 -214.076315) (xy 256.156172 -214.11203) (xy 256.110291 -214.141516)
			(xy 256.060681 -214.164173) (xy 256.008351 -214.179538) (xy 255.954367 -214.1873) (xy 255.899829 -214.1873)
			(xy 255.845845 -214.179538) (xy 255.793515 -214.164173) (xy 255.743905 -214.141516) (xy 255.698024 -214.11203)
			(xy 255.656807 -214.076315) (xy 255.621092 -214.035098) (xy 255.591606 -213.989217) (xy 255.568949 -213.939607)
			(xy 255.553584 -213.887277) (xy 255.545822 -213.833293) (xy 255.545336 -213.806024) (xy 202.229229 -213.806024)
			(xy 202.223863 -213.807742) (xy 202.173448 -213.815665) (xy 202.147932 -213.816184) (xy 202.122412 -213.815698)
			(xy 202.071984 -213.807803) (xy 202.023373 -213.792242) (xy 201.977735 -213.769386) (xy 201.95667 -213.75497)
			(xy 201.950083 -213.750647) (xy 201.93508 -213.745864) (xy 201.927206 -213.745572) (xy 201.411332 -213.745572)
			(xy 201.405995 -213.745248) (xy 201.39845 -213.737701) (xy 201.398124 -213.732364) (xy 195.35394 -213.732364)
			(xy 195.353552 -213.737684) (xy 195.34605 -213.745225) (xy 195.340732 -213.745572) (xy 194.824858 -213.745572)
			(xy 194.816982 -213.745846) (xy 194.801978 -213.750639) (xy 194.795394 -213.75497) (xy 194.77431 -213.769352)
			(xy 194.728667 -213.792182) (xy 194.680063 -213.807742) (xy 194.629648 -213.815665) (xy 194.604132 -213.816184)
			(xy 194.578612 -213.815698) (xy 194.528184 -213.807803) (xy 194.479573 -213.792242) (xy 194.433935 -213.769386)
			(xy 194.41287 -213.75497) (xy 194.406283 -213.750647) (xy 194.39128 -213.745864) (xy 194.383406 -213.745572)
			(xy 193.867532 -213.745572) (xy 193.862195 -213.745248) (xy 193.85465 -213.737701) (xy 193.854324 -213.732364)
			(xy 187.81014 -213.732364) (xy 187.809752 -213.737684) (xy 187.80225 -213.745225) (xy 187.796932 -213.745572)
			(xy 187.796424 -213.745572) (xy 187.280804 -213.745572) (xy 187.27293 -213.745865) (xy 187.257926 -213.750645)
			(xy 187.25134 -213.75497) (xy 187.230271 -213.769375) (xy 187.184623 -213.7922) (xy 187.136014 -213.807754)
			(xy 187.085595 -213.815669) (xy 187.060078 -213.816184) (xy 187.034559 -213.815675) (xy 186.984132 -213.807787)
			(xy 186.935521 -213.792233) (xy 186.889881 -213.769383) (xy 186.868816 -213.75497) (xy 186.862219 -213.750665)
			(xy 186.847223 -213.745871) (xy 186.839352 -213.745572) (xy 186.323478 -213.745572) (xy 186.318174 -213.745093)
			(xy 186.310605 -213.737658) (xy 186.310016 -213.732364) (xy 180.265832 -213.732364) (xy 180.265451 -213.737686)
			(xy 180.257944 -213.745227) (xy 180.252624 -213.745572) (xy 179.73675 -213.745572) (xy 179.728874 -213.745842)
			(xy 179.71387 -213.750638) (xy 179.707286 -213.75497) (xy 179.686205 -213.769355) (xy 179.640561 -213.792184)
			(xy 179.591956 -213.807744) (xy 179.54154 -213.815665) (xy 179.516024 -213.816184) (xy 179.490503 -213.815702)
			(xy 179.440076 -213.807806) (xy 179.391464 -213.792244) (xy 179.345826 -213.769386) (xy 179.324762 -213.75497)
			(xy 179.318177 -213.750644) (xy 179.303172 -213.745863) (xy 179.295298 -213.745572) (xy 178.779424 -213.745572)
			(xy 178.774086 -213.745253) (xy 178.766542 -213.737702) (xy 178.766216 -213.732364) (xy 172.722032 -213.732364)
			(xy 172.721651 -213.737686) (xy 172.714144 -213.745227) (xy 172.708824 -213.745572) (xy 172.708316 -213.745572)
			(xy 172.192696 -213.745572) (xy 172.184822 -213.745862) (xy 172.169817 -213.750644) (xy 172.163232 -213.75497)
			(xy 172.142166 -213.769378) (xy 172.096517 -213.792202) (xy 172.047907 -213.807755) (xy 171.997488 -213.815669)
			(xy 171.97197 -213.816184) (xy 171.94645 -213.815679) (xy 171.896024 -213.80779) (xy 171.847412 -213.792234)
			(xy 171.801773 -213.769383) (xy 171.780708 -213.75497) (xy 171.774112 -213.750662) (xy 171.759116 -213.74587)
			(xy 171.751244 -213.745572) (xy 171.23537 -213.745572) (xy 171.230065 -213.745098) (xy 171.222496 -213.73766)
			(xy 171.221908 -213.732364) (xy 165.177724 -213.732364) (xy 165.177351 -213.737688) (xy 165.169838 -213.74523)
			(xy 165.164516 -213.745572) (xy 163.691316 -213.745572) (xy 163.685977 -213.745259) (xy 163.678433 -213.737703)
			(xy 163.678108 -213.732364) (xy 144.928635 -213.732364) (xy 144.923187 -213.751096) (xy 144.875741 -213.885381)
			(xy 144.820774 -214.016768) (xy 144.758461 -214.144834) (xy 144.689003 -214.269169) (xy 144.612622 -214.389376)
			(xy 144.529563 -214.505069) (xy 144.466835 -214.582756) (xy 167.778176 -214.582756) (xy 167.778176 -214.087964)
			(xy 167.778669 -214.082701) (xy 167.78612 -214.075261) (xy 167.791384 -214.074756) (xy 169.264584 -214.074756)
			(xy 169.269836 -214.075302) (xy 169.277278 -214.082714) (xy 169.277792 -214.087964) (xy 169.277792 -214.582502)
			(xy 175.321976 -214.582502) (xy 175.321976 -214.087964) (xy 175.322469 -214.082701) (xy 175.32992 -214.075261)
			(xy 175.335184 -214.074756) (xy 175.335692 -214.074756) (xy 175.851566 -214.074756) (xy 175.859376 -214.074435)
			(xy 175.874247 -214.069655) (xy 175.880776 -214.065358) (xy 175.901865 -214.051009) (xy 175.947526 -214.028278)
			(xy 175.996132 -214.012819) (xy 176.046535 -214.004996) (xy 176.097541 -214.004996) (xy 176.147944 -214.012819)
			(xy 176.19655 -214.028278) (xy 176.242211 -214.051009) (xy 176.2633 -214.065358) (xy 176.269835 -214.069644)
			(xy 176.284702 -214.074431) (xy 176.29251 -214.074756) (xy 176.808638 -214.074756) (xy 176.813951 -214.0752)
			(xy 176.82152 -214.08266) (xy 176.8221 -214.087964) (xy 176.8221 -214.582502) (xy 176.822074 -214.582756)
			(xy 182.866284 -214.582756) (xy 182.866284 -214.582248) (xy 182.866284 -214.087964) (xy 182.86677 -214.082699)
			(xy 182.874226 -214.075259) (xy 182.879492 -214.074756) (xy 183.39562 -214.074756) (xy 183.403432 -214.074458)
			(xy 183.418303 -214.069662) (xy 183.42483 -214.065358) (xy 183.445919 -214.051009) (xy 183.49158 -214.028278)
			(xy 183.540186 -214.012819) (xy 183.590589 -214.004996) (xy 183.641595 -214.004996) (xy 183.691998 -214.012819)
			(xy 183.740604 -214.028278) (xy 183.786265 -214.051009) (xy 183.807354 -214.065358) (xy 183.813877 -214.069665)
			(xy 183.828753 -214.074439) (xy 183.836564 -214.074756) (xy 184.352692 -214.074756) (xy 184.357945 -214.075296)
			(xy 184.365386 -214.082713) (xy 184.3659 -214.087964) (xy 184.3659 -214.582502) (xy 190.410084 -214.582502)
			(xy 190.410084 -214.087964) (xy 190.41057 -214.082699) (xy 190.418026 -214.075259) (xy 190.423292 -214.074756)
			(xy 190.4238 -214.074756) (xy 190.939674 -214.074756) (xy 190.947484 -214.074438) (xy 190.962356 -214.069656)
			(xy 190.968884 -214.065358) (xy 190.989973 -214.051009) (xy 191.035634 -214.028278) (xy 191.08424 -214.012819)
			(xy 191.134643 -214.004996) (xy 191.185649 -214.004996) (xy 191.236052 -214.012819) (xy 191.284658 -214.028278)
			(xy 191.330319 -214.051009) (xy 191.351408 -214.065358) (xy 191.357941 -214.069647) (xy 191.37281 -214.074432)
			(xy 191.380618 -214.074756) (xy 191.896746 -214.074756) (xy 191.902047 -214.075261) (xy 191.909623 -214.082674)
			(xy 191.910208 -214.087964) (xy 191.910208 -214.582502) (xy 191.910182 -214.582756) (xy 197.954392 -214.582756)
			(xy 197.954392 -214.582248) (xy 197.954392 -214.087964) (xy 197.954871 -214.082697) (xy 197.962332 -214.075257)
			(xy 197.9676 -214.074756) (xy 198.483728 -214.074756) (xy 198.49154 -214.074462) (xy 198.506412 -214.069663)
			(xy 198.512938 -214.065358) (xy 198.534027 -214.051009) (xy 198.579688 -214.028278) (xy 198.628294 -214.012819)
			(xy 198.678697 -214.004996) (xy 198.729703 -214.004996) (xy 198.780106 -214.012819) (xy 198.828712 -214.028278)
			(xy 198.874373 -214.051009) (xy 198.895462 -214.065358) (xy 198.902005 -214.069629) (xy 198.916866 -214.074425)
			(xy 198.924672 -214.074756) (xy 199.4408 -214.074756) (xy 199.446054 -214.075291) (xy 199.453494 -214.082711)
			(xy 199.454008 -214.087964) (xy 199.454008 -214.582502) (xy 199.453983 -214.582756) (xy 205.498192 -214.582756)
			(xy 205.498192 -214.582248) (xy 205.498192 -214.087964) (xy 205.498671 -214.082697) (xy 205.506132 -214.075257)
			(xy 205.5114 -214.074756) (xy 206.027528 -214.074756) (xy 206.03534 -214.074462) (xy 206.050212 -214.069663)
			(xy 206.056738 -214.065358) (xy 206.077827 -214.051009) (xy 206.123488 -214.028278) (xy 206.172094 -214.012819)
			(xy 206.222497 -214.004996) (xy 206.273503 -214.004996) (xy 206.323906 -214.012819) (xy 206.372512 -214.028278)
			(xy 206.418173 -214.051009) (xy 206.439262 -214.065358) (xy 206.445805 -214.069629) (xy 206.460666 -214.074425)
			(xy 206.468472 -214.074756) (xy 206.9846 -214.074756) (xy 206.989854 -214.075291) (xy 206.997294 -214.082711)
			(xy 206.997808 -214.087964) (xy 206.997808 -214.582248) (xy 268.898116 -214.582248) (xy 268.898116 -214.08771)
			(xy 268.898655 -214.082353) (xy 268.906222 -214.074768) (xy 268.911578 -214.074248) (xy 269.427706 -214.074248)
			(xy 269.435517 -214.073946) (xy 269.450389 -214.069153) (xy 269.456916 -214.06485) (xy 269.478005 -214.050501)
			(xy 269.523666 -214.02777) (xy 269.572272 -214.012311) (xy 269.622675 -214.004488) (xy 269.673681 -214.004488)
			(xy 269.724084 -214.012311) (xy 269.77269 -214.02777) (xy 269.818351 -214.050501) (xy 269.83944 -214.06485)
			(xy 269.845966 -214.06915) (xy 269.86084 -214.073929) (xy 269.86865 -214.074248) (xy 270.384778 -214.074248)
			(xy 270.390212 -214.074595) (xy 270.3979 -214.082276) (xy 270.39824 -214.08771) (xy 270.39824 -214.582248)
			(xy 276.442424 -214.582248) (xy 276.442424 -214.08771) (xy 276.442928 -214.082411) (xy 276.450344 -214.07484)
			(xy 276.455632 -214.074248) (xy 276.97176 -214.074248) (xy 276.979569 -214.073926) (xy 276.994441 -214.069147)
			(xy 277.00097 -214.06485) (xy 277.022059 -214.050501) (xy 277.06772 -214.02777) (xy 277.116326 -214.012311)
			(xy 277.166729 -214.004488) (xy 277.217735 -214.004488) (xy 277.268138 -214.012311) (xy 277.316744 -214.02777)
			(xy 277.362405 -214.050501) (xy 277.383494 -214.06485) (xy 277.390031 -214.069133) (xy 277.404897 -214.073922)
			(xy 277.412704 -214.074248) (xy 277.928832 -214.074248) (xy 277.934088 -214.074769) (xy 277.941526 -214.0822)
			(xy 277.94204 -214.087456) (xy 277.94204 -214.087964) (xy 277.94204 -214.582248) (xy 283.986224 -214.582248)
			(xy 283.986224 -214.08771) (xy 283.986728 -214.082411) (xy 283.994144 -214.07484) (xy 283.999432 -214.074248)
			(xy 284.51556 -214.074248) (xy 284.523369 -214.073926) (xy 284.538241 -214.069147) (xy 284.54477 -214.06485)
			(xy 284.565859 -214.050501) (xy 284.61152 -214.02777) (xy 284.660126 -214.012311) (xy 284.710529 -214.004488)
			(xy 284.761535 -214.004488) (xy 284.811938 -214.012311) (xy 284.860544 -214.02777) (xy 284.906205 -214.050501)
			(xy 284.927294 -214.06485) (xy 284.933831 -214.069133) (xy 284.948697 -214.073922) (xy 284.956504 -214.074248)
			(xy 285.472632 -214.074248) (xy 285.477888 -214.074769) (xy 285.485326 -214.0822) (xy 285.48584 -214.087456)
			(xy 285.48584 -214.087964) (xy 285.48584 -214.582248) (xy 291.530024 -214.582248) (xy 291.530024 -214.08771)
			(xy 291.530556 -214.082351) (xy 291.538128 -214.074765) (xy 291.543486 -214.074248) (xy 292.059614 -214.074248)
			(xy 292.067426 -214.073949) (xy 292.082297 -214.069154) (xy 292.088824 -214.06485) (xy 292.109913 -214.050501)
			(xy 292.155574 -214.02777) (xy 292.20418 -214.012311) (xy 292.254583 -214.004488) (xy 292.305589 -214.004488)
			(xy 292.355992 -214.012311) (xy 292.404598 -214.02777) (xy 292.450259 -214.050501) (xy 292.471348 -214.06485)
			(xy 292.477873 -214.069153) (xy 292.492748 -214.07393) (xy 292.500558 -214.074248) (xy 293.016686 -214.074248)
			(xy 293.022121 -214.07459) (xy 293.029809 -214.082275) (xy 293.030148 -214.08771) (xy 293.030148 -214.582248)
			(xy 299.074332 -214.582248) (xy 299.074332 -214.08771) (xy 299.074829 -214.082409) (xy 299.08225 -214.074837)
			(xy 299.08754 -214.074248) (xy 299.603668 -214.074248) (xy 299.611478 -214.073929) (xy 299.62635 -214.069148)
			(xy 299.632878 -214.06485) (xy 299.653967 -214.050501) (xy 299.699628 -214.02777) (xy 299.748234 -214.012311)
			(xy 299.798637 -214.004488) (xy 299.849643 -214.004488) (xy 299.900046 -214.012311) (xy 299.948652 -214.02777)
			(xy 299.994313 -214.050501) (xy 300.015402 -214.06485) (xy 300.021937 -214.069136) (xy 300.036804 -214.073923)
			(xy 300.044612 -214.074248) (xy 300.56074 -214.074248) (xy 300.565997 -214.074764) (xy 300.573435 -214.082199)
			(xy 300.573948 -214.087456) (xy 300.573948 -214.087964) (xy 300.573948 -214.582248) (xy 306.618132 -214.582248)
			(xy 306.618132 -214.08771) (xy 306.618485 -214.082278) (xy 306.626162 -214.074592) (xy 306.631594 -214.074248)
			(xy 308.104794 -214.074248) (xy 308.11023 -214.074584) (xy 308.117917 -214.082273) (xy 308.118256 -214.08771)
			(xy 308.118256 -214.582248) (xy 308.117742 -214.587505) (xy 308.110305 -214.594942) (xy 308.105048 -214.595456)
			(xy 308.10454 -214.595456) (xy 306.631594 -214.595456) (xy 306.626288 -214.59498) (xy 306.618717 -214.587544)
			(xy 306.618132 -214.582248) (xy 300.573948 -214.582248) (xy 300.573441 -214.587507) (xy 300.565999 -214.594944)
			(xy 300.56074 -214.595456) (xy 300.044866 -214.595456) (xy 300.036991 -214.595736) (xy 300.021987 -214.600525)
			(xy 300.015402 -214.604854) (xy 299.994315 -214.61923) (xy 299.948673 -214.642062) (xy 299.90007 -214.657624)
			(xy 299.849656 -214.665548) (xy 299.82414 -214.666068) (xy 299.79862 -214.665581) (xy 299.748192 -214.657687)
			(xy 299.699581 -214.642126) (xy 299.653943 -214.61927) (xy 299.632878 -214.604854) (xy 299.62629 -214.600533)
			(xy 299.611287 -214.595749) (xy 299.603414 -214.595456) (xy 299.08754 -214.595456) (xy 299.082293 -214.594884)
			(xy 299.074851 -214.587491) (xy 299.074332 -214.582248) (xy 293.030148 -214.582248) (xy 293.029641 -214.587507)
			(xy 293.022199 -214.594944) (xy 293.01694 -214.595456) (xy 293.016432 -214.595456) (xy 292.500812 -214.595456)
			(xy 292.492938 -214.595755) (xy 292.477934 -214.600531) (xy 292.471348 -214.604854) (xy 292.450276 -214.619254)
			(xy 292.404629 -214.64208) (xy 292.356021 -214.657636) (xy 292.305603 -214.665552) (xy 292.280086 -214.666068)
			(xy 292.254567 -214.665558) (xy 292.20414 -214.657671) (xy 292.155528 -214.642117) (xy 292.109889 -214.619267)
			(xy 292.088824 -214.604854) (xy 292.082226 -214.600551) (xy 292.067231 -214.595756) (xy 292.05936 -214.595456)
			(xy 291.543486 -214.595456) (xy 291.538179 -214.594985) (xy 291.530609 -214.587545) (xy 291.530024 -214.582248)
			(xy 285.48584 -214.582248) (xy 285.48534 -214.587509) (xy 285.477893 -214.594947) (xy 285.472632 -214.595456)
			(xy 284.956758 -214.595456) (xy 284.948882 -214.595732) (xy 284.933879 -214.600524) (xy 284.927294 -214.604854)
			(xy 284.906209 -214.619234) (xy 284.860567 -214.642065) (xy 284.811963 -214.657626) (xy 284.761548 -214.665549)
			(xy 284.736032 -214.666068) (xy 284.710511 -214.665585) (xy 284.660084 -214.65769) (xy 284.611472 -214.642128)
			(xy 284.565834 -214.619271) (xy 284.54477 -214.604854) (xy 284.538184 -214.60053) (xy 284.52318 -214.595748)
			(xy 284.515306 -214.595456) (xy 283.999432 -214.595456) (xy 283.994184 -214.594889) (xy 283.986743 -214.587492)
			(xy 283.986224 -214.582248) (xy 277.94204 -214.582248) (xy 277.94154 -214.587509) (xy 277.934093 -214.594947)
			(xy 277.928832 -214.595456) (xy 277.412958 -214.595456) (xy 277.405082 -214.595732) (xy 277.390079 -214.600524)
			(xy 277.383494 -214.604854) (xy 277.362409 -214.619234) (xy 277.316767 -214.642065) (xy 277.268163 -214.657626)
			(xy 277.217748 -214.665549) (xy 277.192232 -214.666068) (xy 277.166711 -214.665585) (xy 277.116284 -214.65769)
			(xy 277.067672 -214.642128) (xy 277.022034 -214.619271) (xy 277.00097 -214.604854) (xy 276.994384 -214.60053)
			(xy 276.97938 -214.595748) (xy 276.971506 -214.595456) (xy 276.455632 -214.595456) (xy 276.450384 -214.594889)
			(xy 276.442943 -214.587492) (xy 276.442424 -214.582248) (xy 270.39824 -214.582248) (xy 270.39774 -214.587509)
			(xy 270.390293 -214.594947) (xy 270.385032 -214.595456) (xy 270.384524 -214.595456) (xy 269.868904 -214.595456)
			(xy 269.86103 -214.595752) (xy 269.846026 -214.60053) (xy 269.83944 -214.604854) (xy 269.81837 -214.619257)
			(xy 269.772722 -214.642083) (xy 269.724114 -214.657637) (xy 269.673695 -214.665553) (xy 269.648178 -214.666068)
			(xy 269.622658 -214.665562) (xy 269.572232 -214.657673) (xy 269.52362 -214.642118) (xy 269.477981 -214.619268)
			(xy 269.456916 -214.604854) (xy 269.450319 -214.600548) (xy 269.435323 -214.595755) (xy 269.427452 -214.595456)
			(xy 268.911578 -214.595456) (xy 268.90627 -214.594991) (xy 268.8987 -214.587547) (xy 268.898116 -214.582248)
			(xy 206.997808 -214.582248) (xy 206.997808 -214.582502) (xy 206.997284 -214.587795) (xy 206.989881 -214.595364)
			(xy 206.9846 -214.595964) (xy 206.468726 -214.595964) (xy 206.460916 -214.596278) (xy 206.446044 -214.601063)
			(xy 206.439516 -214.605362) (xy 206.418388 -214.619702) (xy 206.372667 -214.64243) (xy 206.323995 -214.657863)
			(xy 206.27353 -214.665633) (xy 206.248 -214.666068) (xy 206.22247 -214.665631) (xy 206.172006 -214.657855)
			(xy 206.123334 -214.642426) (xy 206.077606 -214.619709) (xy 206.056484 -214.605362) (xy 206.049952 -214.601072)
			(xy 206.035082 -214.596287) (xy 206.027274 -214.595964) (xy 205.5114 -214.595964) (xy 205.506057 -214.595669)
			(xy 205.498513 -214.5881) (xy 205.498192 -214.582756) (xy 199.453983 -214.582756) (xy 199.453484 -214.587795)
			(xy 199.446081 -214.595364) (xy 199.4408 -214.595964) (xy 198.924926 -214.595964) (xy 198.917116 -214.596278)
			(xy 198.902244 -214.601063) (xy 198.895716 -214.605362) (xy 198.874588 -214.619702) (xy 198.828867 -214.64243)
			(xy 198.780195 -214.657863) (xy 198.72973 -214.665633) (xy 198.7042 -214.666068) (xy 198.67867 -214.665631)
			(xy 198.628206 -214.657855) (xy 198.579534 -214.642426) (xy 198.533806 -214.619709) (xy 198.512684 -214.605362)
			(xy 198.506152 -214.601072) (xy 198.491282 -214.596287) (xy 198.483474 -214.595964) (xy 197.9676 -214.595964)
			(xy 197.962257 -214.595669) (xy 197.954713 -214.5881) (xy 197.954392 -214.582756) (xy 191.910182 -214.582756)
			(xy 191.909655 -214.587855) (xy 191.902097 -214.595438) (xy 191.896746 -214.595964) (xy 191.380872 -214.595964)
			(xy 191.37306 -214.596255) (xy 191.358188 -214.601055) (xy 191.351662 -214.605362) (xy 191.330549 -214.619725)
			(xy 191.284822 -214.642448) (xy 191.236146 -214.657874) (xy 191.185678 -214.665637) (xy 191.160146 -214.666068)
			(xy 191.134617 -214.665608) (xy 191.084154 -214.657839) (xy 191.035481 -214.642417) (xy 190.989753 -214.619706)
			(xy 190.96863 -214.605362) (xy 190.962087 -214.601089) (xy 190.947226 -214.596294) (xy 190.93942 -214.595964)
			(xy 190.423546 -214.595964) (xy 190.418118 -214.59559) (xy 190.410429 -214.587929) (xy 190.410084 -214.582502)
			(xy 184.3659 -214.582502) (xy 184.365383 -214.587797) (xy 184.357976 -214.595366) (xy 184.352692 -214.595964)
			(xy 183.836818 -214.595964) (xy 183.829007 -214.596275) (xy 183.814136 -214.601062) (xy 183.807608 -214.605362)
			(xy 183.786482 -214.619705) (xy 183.74076 -214.642433) (xy 183.692088 -214.657865) (xy 183.641623 -214.665634)
			(xy 183.616092 -214.666068) (xy 183.590562 -214.665635) (xy 183.540098 -214.657858) (xy 183.491425 -214.642428)
			(xy 183.445698 -214.61971) (xy 183.424576 -214.605362) (xy 183.418045 -214.601069) (xy 183.403175 -214.596286)
			(xy 183.395366 -214.595964) (xy 182.879492 -214.595964) (xy 182.874148 -214.595674) (xy 182.866605 -214.588101)
			(xy 182.866284 -214.582756) (xy 176.822074 -214.582756) (xy 176.821555 -214.587857) (xy 176.813992 -214.59544)
			(xy 176.808638 -214.595964) (xy 176.292764 -214.595964) (xy 176.284955 -214.596294) (xy 176.270083 -214.601068)
			(xy 176.263554 -214.605362) (xy 176.242444 -214.619729) (xy 176.196716 -214.642451) (xy 176.148039 -214.657876)
			(xy 176.09757 -214.665638) (xy 176.072038 -214.666068) (xy 176.046509 -214.665612) (xy 175.996045 -214.657842)
			(xy 175.947373 -214.642418) (xy 175.901645 -214.619707) (xy 175.880522 -214.605362) (xy 175.873981 -214.601086)
			(xy 175.859118 -214.596293) (xy 175.851312 -214.595964) (xy 175.335438 -214.595964) (xy 175.330009 -214.595596)
			(xy 175.32232 -214.58793) (xy 175.321976 -214.582502) (xy 169.277792 -214.582502) (xy 169.277282 -214.587799)
			(xy 169.26987 -214.595368) (xy 169.264584 -214.595964) (xy 167.791384 -214.595964) (xy 167.786039 -214.59568)
			(xy 167.778496 -214.588103) (xy 167.778176 -214.582756) (xy 144.466835 -214.582756) (xy 144.440091 -214.615878)
			(xy 144.344494 -214.721447) (xy 144.243077 -214.821439) (xy 144.136165 -214.915533) (xy 144.024101 -215.003427)
			(xy 143.907245 -215.084841) (xy 143.785969 -215.159514) (xy 143.660663 -215.227205) (xy 143.531728 -215.287699)
			(xy 143.399577 -215.340802) (xy 143.264634 -215.386343) (xy 143.12733 -215.424177) (xy 143.088061 -215.43264)
			(xy 163.678108 -215.43264) (xy 163.678108 -215.432132) (xy 163.678108 -214.937848) (xy 163.678461 -214.932518)
			(xy 163.685987 -214.924974) (xy 163.691316 -214.92464) (xy 165.164516 -214.92464) (xy 165.169862 -214.924921)
			(xy 165.177405 -214.9325) (xy 165.177724 -214.937848) (xy 165.177724 -215.432386) (xy 171.221908 -215.432386)
			(xy 171.221908 -214.937848) (xy 171.222261 -214.932518) (xy 171.229787 -214.924974) (xy 171.235116 -214.92464)
			(xy 171.235624 -214.92464) (xy 171.751498 -214.92464) (xy 171.759309 -214.924335) (xy 171.774181 -214.919544)
			(xy 171.780708 -214.915242) (xy 171.801797 -214.900893) (xy 171.847458 -214.878162) (xy 171.896064 -214.862703)
			(xy 171.946467 -214.85488) (xy 171.997473 -214.85488) (xy 172.047876 -214.862703) (xy 172.096482 -214.878162)
			(xy 172.142143 -214.900893) (xy 172.163232 -214.915242) (xy 172.169761 -214.919539) (xy 172.184633 -214.924319)
			(xy 172.192442 -214.92464) (xy 172.70857 -214.92464) (xy 172.713871 -214.925143) (xy 172.721443 -214.932559)
			(xy 172.722032 -214.937848) (xy 172.722032 -215.432386) (xy 172.722017 -215.43264) (xy 178.766216 -215.43264)
			(xy 178.766216 -215.432132) (xy 178.766216 -214.937848) (xy 178.766562 -214.932516) (xy 178.774093 -214.924971)
			(xy 178.779424 -214.92464) (xy 179.295552 -214.92464) (xy 179.303361 -214.924316) (xy 179.318233 -214.919538)
			(xy 179.324762 -214.915242) (xy 179.345851 -214.900893) (xy 179.391512 -214.878162) (xy 179.440118 -214.862703)
			(xy 179.490521 -214.85488) (xy 179.541527 -214.85488) (xy 179.59193 -214.862703) (xy 179.640536 -214.878162)
			(xy 179.686197 -214.900893) (xy 179.707286 -214.915242) (xy 179.713825 -214.919521) (xy 179.728689 -214.924313)
			(xy 179.736496 -214.92464) (xy 180.252624 -214.92464) (xy 180.257971 -214.924916) (xy 180.265513 -214.932499)
			(xy 180.265832 -214.937848) (xy 180.265832 -215.432386) (xy 186.310016 -215.432386) (xy 186.310016 -214.937848)
			(xy 186.310362 -214.932516) (xy 186.317893 -214.924971) (xy 186.323224 -214.92464) (xy 186.323732 -214.92464)
			(xy 186.839606 -214.92464) (xy 186.847417 -214.924339) (xy 186.862289 -214.919545) (xy 186.868816 -214.915242)
			(xy 186.889905 -214.900893) (xy 186.935566 -214.878162) (xy 186.984172 -214.862703) (xy 187.034575 -214.85488)
			(xy 187.085581 -214.85488) (xy 187.135984 -214.862703) (xy 187.18459 -214.878162) (xy 187.230251 -214.900893)
			(xy 187.25134 -214.915242) (xy 187.257867 -214.919542) (xy 187.27274 -214.924321) (xy 187.28055 -214.92464)
			(xy 187.796678 -214.92464) (xy 187.80198 -214.925138) (xy 187.809552 -214.932557) (xy 187.81014 -214.937848)
			(xy 187.81014 -215.432386) (xy 187.810125 -215.43264) (xy 193.854324 -215.43264) (xy 193.854324 -215.432132)
			(xy 193.854324 -214.937848) (xy 193.854662 -214.932514) (xy 193.862199 -214.924969) (xy 193.867532 -214.92464)
			(xy 194.38366 -214.92464) (xy 194.39147 -214.924319) (xy 194.406341 -214.919539) (xy 194.41287 -214.915242)
			(xy 194.433959 -214.900893) (xy 194.47962 -214.878162) (xy 194.528226 -214.862703) (xy 194.578629 -214.85488)
			(xy 194.629635 -214.85488) (xy 194.680038 -214.862703) (xy 194.728644 -214.878162) (xy 194.774305 -214.900893)
			(xy 194.795394 -214.915242) (xy 194.801931 -214.919524) (xy 194.816797 -214.924314) (xy 194.824604 -214.92464)
			(xy 195.340732 -214.92464) (xy 195.34608 -214.92491) (xy 195.353622 -214.932498) (xy 195.35394 -214.937848)
			(xy 195.35394 -215.432386) (xy 195.353917 -215.43264) (xy 201.398124 -215.43264) (xy 201.398124 -215.432132)
			(xy 201.398124 -214.937848) (xy 201.398462 -214.932514) (xy 201.405999 -214.924969) (xy 201.411332 -214.92464)
			(xy 201.92746 -214.92464) (xy 201.93527 -214.924319) (xy 201.950141 -214.919539) (xy 201.95667 -214.915242)
			(xy 201.977759 -214.900893) (xy 202.02342 -214.878162) (xy 202.072026 -214.862703) (xy 202.122429 -214.85488)
			(xy 202.173435 -214.85488) (xy 202.223838 -214.862703) (xy 202.272444 -214.878162) (xy 202.318105 -214.900893)
			(xy 202.339194 -214.915242) (xy 202.345731 -214.919524) (xy 202.360597 -214.924314) (xy 202.368404 -214.92464)
			(xy 202.884532 -214.92464) (xy 202.88988 -214.92491) (xy 202.897422 -214.932498) (xy 202.89774 -214.937848)
			(xy 202.89774 -215.432132) (xy 264.798048 -215.432132) (xy 264.798048 -214.937594) (xy 264.798376 -214.932156)
			(xy 264.806072 -214.92447) (xy 264.81151 -214.924132) (xy 265.327638 -214.924132) (xy 265.335447 -214.923803)
			(xy 265.350319 -214.919029) (xy 265.356848 -214.914734) (xy 265.377937 -214.900385) (xy 265.423598 -214.877654)
			(xy 265.472204 -214.862195) (xy 265.522607 -214.854372) (xy 265.573613 -214.854372) (xy 265.624016 -214.862195)
			(xy 265.672622 -214.877654) (xy 265.718283 -214.900385) (xy 265.739372 -214.914734) (xy 265.745914 -214.919007)
			(xy 265.760776 -214.923802) (xy 265.768582 -214.924132) (xy 266.28471 -214.924132) (xy 266.290074 -214.924643)
			(xy 266.297658 -214.93223) (xy 266.298172 -214.937594) (xy 266.298172 -215.432132) (xy 272.342356 -215.432132)
			(xy 272.342356 -214.937594) (xy 272.342821 -214.932285) (xy 272.350264 -214.924714) (xy 272.355564 -214.924132)
			(xy 272.871692 -214.924132) (xy 272.879503 -214.923826) (xy 272.894375 -214.919036) (xy 272.900902 -214.914734)
			(xy 272.921991 -214.900385) (xy 272.967652 -214.877654) (xy 273.016258 -214.862195) (xy 273.066661 -214.854372)
			(xy 273.117667 -214.854372) (xy 273.16807 -214.862195) (xy 273.216676 -214.877654) (xy 273.262337 -214.900385)
			(xy 273.283426 -214.914734) (xy 273.289956 -214.919028) (xy 273.304827 -214.92381) (xy 273.312636 -214.924132)
			(xy 273.828764 -214.924132) (xy 273.834101 -214.924455) (xy 273.841647 -214.932003) (xy 273.841972 -214.93734)
			(xy 273.841972 -214.937848) (xy 273.841972 -215.432132) (xy 279.886156 -215.432132) (xy 279.886156 -214.937594)
			(xy 279.886621 -214.932285) (xy 279.894064 -214.924714) (xy 279.899364 -214.924132) (xy 280.415492 -214.924132)
			(xy 280.423303 -214.923826) (xy 280.438175 -214.919036) (xy 280.444702 -214.914734) (xy 280.465791 -214.900385)
			(xy 280.511452 -214.877654) (xy 280.560058 -214.862195) (xy 280.610461 -214.854372) (xy 280.661467 -214.854372)
			(xy 280.71187 -214.862195) (xy 280.760476 -214.877654) (xy 280.806137 -214.900385) (xy 280.827226 -214.914734)
			(xy 280.833756 -214.919028) (xy 280.848627 -214.92381) (xy 280.856436 -214.924132) (xy 281.372564 -214.924132)
			(xy 281.377901 -214.924455) (xy 281.385447 -214.932003) (xy 281.385772 -214.93734) (xy 281.385772 -214.937848)
			(xy 281.385772 -215.432132) (xy 287.429956 -215.432132) (xy 287.429956 -214.937594) (xy 287.430277 -214.932154)
			(xy 287.437977 -214.924467) (xy 287.443418 -214.924132) (xy 287.959546 -214.924132) (xy 287.967355 -214.923807)
			(xy 287.982227 -214.91903) (xy 287.988756 -214.914734) (xy 288.009845 -214.900385) (xy 288.055506 -214.877654)
			(xy 288.104112 -214.862195) (xy 288.154515 -214.854372) (xy 288.205521 -214.854372) (xy 288.255924 -214.862195)
			(xy 288.30453 -214.877654) (xy 288.350191 -214.900385) (xy 288.37128 -214.914734) (xy 288.377821 -214.91901)
			(xy 288.392683 -214.923804) (xy 288.40049 -214.924132) (xy 288.916618 -214.924132) (xy 288.921983 -214.924638)
			(xy 288.929567 -214.932229) (xy 288.93008 -214.937594) (xy 288.93008 -215.432132) (xy 294.974264 -215.432132)
			(xy 294.974264 -214.937594) (xy 294.974722 -214.932283) (xy 294.98217 -214.924711) (xy 294.987472 -214.924132)
			(xy 295.5036 -214.924132) (xy 295.511411 -214.92383) (xy 295.526283 -214.919037) (xy 295.53281 -214.914734)
			(xy 295.553899 -214.900385) (xy 295.59956 -214.877654) (xy 295.648166 -214.862195) (xy 295.698569 -214.854372)
			(xy 295.749575 -214.854372) (xy 295.799978 -214.862195) (xy 295.848584 -214.877654) (xy 295.894245 -214.900385)
			(xy 295.915334 -214.914734) (xy 295.921863 -214.919031) (xy 295.936735 -214.923812) (xy 295.944544 -214.924132)
			(xy 296.460672 -214.924132) (xy 296.46601 -214.924449) (xy 296.473555 -214.932001) (xy 296.47388 -214.93734)
			(xy 296.47388 -214.937848) (xy 296.47388 -215.432132) (xy 302.518064 -215.432132) (xy 302.518064 -214.937594)
			(xy 302.518378 -214.932152) (xy 302.526083 -214.924465) (xy 302.531526 -214.924132) (xy 304.004726 -214.924132)
			(xy 304.010092 -214.924633) (xy 304.017675 -214.932228) (xy 304.018188 -214.937594) (xy 304.018188 -215.432132)
			(xy 304.017725 -215.437403) (xy 304.010253 -215.444845) (xy 304.00498 -215.44534) (xy 302.531526 -215.44534)
			(xy 302.52622 -215.444857) (xy 302.518647 -215.437427) (xy 302.518064 -215.432132) (xy 296.47388 -215.432132)
			(xy 296.473424 -215.437405) (xy 296.465948 -215.444848) (xy 296.460672 -215.44534) (xy 295.944798 -215.44534)
			(xy 295.936924 -215.445636) (xy 295.92192 -215.450414) (xy 295.915334 -215.454738) (xy 295.894265 -215.469142)
			(xy 295.848617 -215.491968) (xy 295.800008 -215.507522) (xy 295.749589 -215.515437) (xy 295.724072 -215.515952)
			(xy 295.698553 -215.515434) (xy 295.648128 -215.507546) (xy 295.599516 -215.491994) (xy 295.553876 -215.469149)
			(xy 295.53281 -215.454738) (xy 295.526216 -215.450428) (xy 295.511218 -215.445637) (xy 295.503346 -215.44534)
			(xy 294.987472 -215.44534) (xy 294.982214 -215.444827) (xy 294.974774 -215.43739) (xy 294.974264 -215.432132)
			(xy 288.93008 -215.432132) (xy 288.929624 -215.437405) (xy 288.922148 -215.444848) (xy 288.916872 -215.44534)
			(xy 288.916364 -215.44534) (xy 288.400744 -215.44534) (xy 288.392868 -215.445613) (xy 288.377864 -215.450407)
			(xy 288.37128 -215.454738) (xy 288.350198 -215.469122) (xy 288.304555 -215.491952) (xy 288.25595 -215.507512)
			(xy 288.205534 -215.515434) (xy 288.180018 -215.515952) (xy 288.154498 -215.515461) (xy 288.104072 -215.507565)
			(xy 288.05546 -215.492005) (xy 288.009821 -215.469152) (xy 287.988756 -215.454738) (xy 287.982174 -215.450407)
			(xy 287.967167 -215.44563) (xy 287.959292 -215.44534) (xy 287.443418 -215.44534) (xy 287.438111 -215.444863)
			(xy 287.430538 -215.437429) (xy 287.429956 -215.432132) (xy 281.385772 -215.432132) (xy 281.385491 -215.437477)
			(xy 281.377911 -215.445018) (xy 281.372564 -215.44534) (xy 280.85669 -215.44534) (xy 280.848816 -215.445633)
			(xy 280.833812 -215.450413) (xy 280.827226 -215.454738) (xy 280.806159 -215.469145) (xy 280.76051 -215.49197)
			(xy 280.711901 -215.507524) (xy 280.661482 -215.515438) (xy 280.635964 -215.515952) (xy 280.610445 -215.515438)
			(xy 280.560019 -215.507549) (xy 280.511408 -215.491996) (xy 280.465768 -215.469149) (xy 280.444702 -215.454738)
			(xy 280.438109 -215.450425) (xy 280.42311 -215.445636) (xy 280.415238 -215.44534) (xy 279.899364 -215.44534)
			(xy 279.894105 -215.444832) (xy 279.886666 -215.437391) (xy 279.886156 -215.432132) (xy 273.841972 -215.432132)
			(xy 273.841691 -215.437477) (xy 273.834111 -215.445018) (xy 273.828764 -215.44534) (xy 273.31289 -215.44534)
			(xy 273.305016 -215.445633) (xy 273.290012 -215.450413) (xy 273.283426 -215.454738) (xy 273.262359 -215.469145)
			(xy 273.21671 -215.49197) (xy 273.168101 -215.507524) (xy 273.117682 -215.515438) (xy 273.092164 -215.515952)
			(xy 273.066645 -215.515438) (xy 273.016219 -215.507549) (xy 272.967608 -215.491996) (xy 272.921968 -215.469149)
			(xy 272.900902 -215.454738) (xy 272.894309 -215.450425) (xy 272.87931 -215.445636) (xy 272.871438 -215.44534)
			(xy 272.355564 -215.44534) (xy 272.350305 -215.444832) (xy 272.342866 -215.437391) (xy 272.342356 -215.432132)
			(xy 266.298172 -215.432132) (xy 266.297891 -215.437477) (xy 266.290311 -215.445018) (xy 266.284964 -215.44534)
			(xy 266.284456 -215.44534) (xy 265.768836 -215.44534) (xy 265.76096 -215.445609) (xy 265.745956 -215.450406)
			(xy 265.739372 -215.454738) (xy 265.718292 -215.469125) (xy 265.672648 -215.491955) (xy 265.624043 -215.507514)
			(xy 265.573626 -215.515434) (xy 265.54811 -215.515952) (xy 265.52259 -215.515465) (xy 265.472163 -215.507568)
			(xy 265.423552 -215.492007) (xy 265.377913 -215.469153) (xy 265.356848 -215.454738) (xy 265.350268 -215.450404)
			(xy 265.335259 -215.445628) (xy 265.327384 -215.44534) (xy 264.81151 -215.44534) (xy 264.806202 -215.444868)
			(xy 264.798629 -215.43743) (xy 264.798048 -215.432132) (xy 202.89774 -215.432132) (xy 202.89774 -215.432386)
			(xy 202.897265 -215.437693) (xy 202.889829 -215.445266) (xy 202.884532 -215.445848) (xy 202.368658 -215.445848)
			(xy 202.360849 -215.446178) (xy 202.345977 -215.450952) (xy 202.339448 -215.455246) (xy 202.318338 -215.469613)
			(xy 202.27261 -215.492336) (xy 202.223933 -215.507761) (xy 202.173464 -215.515522) (xy 202.147932 -215.515952)
			(xy 202.122402 -215.515502) (xy 202.071939 -215.50773) (xy 202.023266 -215.492305) (xy 201.977538 -215.469592)
			(xy 201.956416 -215.455246) (xy 201.949877 -215.450967) (xy 201.935013 -215.446176) (xy 201.927206 -215.445848)
			(xy 201.411332 -215.445848) (xy 201.406083 -215.445288) (xy 201.39864 -215.437887) (xy 201.398124 -215.43264)
			(xy 195.353917 -215.43264) (xy 195.353465 -215.437693) (xy 195.346029 -215.445266) (xy 195.340732 -215.445848)
			(xy 194.824858 -215.445848) (xy 194.817049 -215.446178) (xy 194.802177 -215.450952) (xy 194.795648 -215.455246)
			(xy 194.774538 -215.469613) (xy 194.72881 -215.492336) (xy 194.680133 -215.507761) (xy 194.629664 -215.515522)
			(xy 194.604132 -215.515952) (xy 194.578602 -215.515502) (xy 194.528139 -215.50773) (xy 194.479466 -215.492305)
			(xy 194.433738 -215.469592) (xy 194.412616 -215.455246) (xy 194.406077 -215.450967) (xy 194.391213 -215.446176)
			(xy 194.383406 -215.445848) (xy 193.867532 -215.445848) (xy 193.862283 -215.445288) (xy 193.85484 -215.437887)
			(xy 193.854324 -215.43264) (xy 187.810125 -215.43264) (xy 187.809809 -215.437824) (xy 187.802116 -215.445512)
			(xy 187.796678 -215.445848) (xy 187.280804 -215.445848) (xy 187.272993 -215.446156) (xy 187.258122 -215.450945)
			(xy 187.251594 -215.455246) (xy 187.230471 -215.469593) (xy 187.184748 -215.492321) (xy 187.136075 -215.507751)
			(xy 187.085609 -215.515519) (xy 187.060078 -215.515952) (xy 187.034547 -215.515529) (xy 186.984083 -215.507749)
			(xy 186.93541 -215.492316) (xy 186.889683 -215.469596) (xy 186.868562 -215.455246) (xy 186.862035 -215.450946)
			(xy 186.847162 -215.446168) (xy 186.839352 -215.445848) (xy 186.323478 -215.445848) (xy 186.318108 -215.445363)
			(xy 186.310523 -215.437757) (xy 186.310016 -215.432386) (xy 180.265832 -215.432386) (xy 180.265364 -215.437695)
			(xy 180.257924 -215.445268) (xy 180.252624 -215.445848) (xy 179.73675 -215.445848) (xy 179.728941 -215.446175)
			(xy 179.714069 -215.450951) (xy 179.70754 -215.455246) (xy 179.686432 -215.469617) (xy 179.640703 -215.492339)
			(xy 179.592026 -215.507763) (xy 179.541556 -215.515523) (xy 179.516024 -215.515952) (xy 179.490494 -215.515506)
			(xy 179.440031 -215.507733) (xy 179.391358 -215.492307) (xy 179.34563 -215.469593) (xy 179.324508 -215.455246)
			(xy 179.317971 -215.450964) (xy 179.303105 -215.446174) (xy 179.295298 -215.445848) (xy 178.779424 -215.445848)
			(xy 178.774174 -215.445293) (xy 178.766732 -215.437888) (xy 178.766216 -215.43264) (xy 172.722017 -215.43264)
			(xy 172.721708 -215.437826) (xy 172.714011 -215.445515) (xy 172.70857 -215.445848) (xy 172.192696 -215.445848)
			(xy 172.184885 -215.446152) (xy 172.170013 -215.450944) (xy 172.163486 -215.455246) (xy 172.142365 -215.469597)
			(xy 172.096641 -215.492323) (xy 172.047968 -215.507753) (xy 171.997501 -215.515519) (xy 171.97197 -215.515952)
			(xy 171.946439 -215.515533) (xy 171.895974 -215.507752) (xy 171.847302 -215.492318) (xy 171.801575 -215.469596)
			(xy 171.780454 -215.455246) (xy 171.773929 -215.450943) (xy 171.759054 -215.446166) (xy 171.751244 -215.445848)
			(xy 171.23537 -215.445848) (xy 171.229999 -215.445368) (xy 171.222414 -215.437759) (xy 171.221908 -215.432386)
			(xy 165.177724 -215.432386) (xy 165.177263 -215.437697) (xy 165.169818 -215.445271) (xy 165.164516 -215.445848)
			(xy 163.691316 -215.445848) (xy 163.686065 -215.445299) (xy 163.678624 -215.437889) (xy 163.678108 -215.43264)
			(xy 143.088061 -215.43264) (xy 142.988105 -215.454182) (xy 142.847406 -215.476262) (xy 142.705684 -215.490348)
			(xy 142.563391 -215.496392) (xy 142.420984 -215.494377) (xy 142.278919 -215.484308) (xy 142.137652 -215.466218)
			(xy 141.997634 -215.440165) (xy 141.859315 -215.406232) (xy 141.723136 -215.364527) (xy 141.589536 -215.315186)
			(xy 141.45894 -215.258365) (xy 141.331769 -215.194246) (xy 141.208429 -215.123036) (xy 141.089315 -215.044961)
			(xy 140.974809 -214.960273) (xy 140.865277 -214.869242) (xy 140.761071 -214.772161) (xy 140.662525 -214.669339)
			(xy 140.569953 -214.561106) (xy 140.483653 -214.44781) (xy 140.403901 -214.329813) (xy 140.330952 -214.207493)
			(xy 140.26504 -214.081242) (xy 140.206377 -213.951463) (xy 140.15515 -213.818574) (xy 140.111523 -213.683)
			(xy 140.075636 -213.545174) (xy 140.047604 -213.405539) (xy 140.027516 -213.264542) (xy 140.015438 -213.122634)
			(xy 140.011408 -212.98027) (xy 83.843368 -212.98027) (xy 83.842864 -213.051466) (xy 83.834809 -213.19363)
			(xy 83.818723 -213.335111) (xy 83.794658 -213.475455) (xy 83.762692 -213.614213) (xy 83.722928 -213.75094)
			(xy 83.675491 -213.885199) (xy 83.620535 -214.016558) (xy 83.558235 -214.144599) (xy 83.488791 -214.268909)
			(xy 83.412425 -214.389092) (xy 83.329383 -214.504761) (xy 83.239929 -214.615547) (xy 83.144351 -214.721095)
			(xy 83.042954 -214.821067) (xy 82.936064 -214.915142) (xy 82.837488 -214.992458) (xy 94.106492 -214.992458)
			(xy 94.106492 -214.128858) (xy 94.106978 -214.101607) (xy 94.114734 -214.047659) (xy 94.130089 -213.995364)
			(xy 94.152731 -213.945787) (xy 94.182197 -213.899937) (xy 94.217888 -213.858746) (xy 94.259079 -213.823055)
			(xy 94.304929 -213.793589) (xy 94.354506 -213.770947) (xy 94.406801 -213.755592) (xy 94.460749 -213.747836)
			(xy 94.515251 -213.747836) (xy 94.569199 -213.755592) (xy 94.621494 -213.770947) (xy 94.671071 -213.793589)
			(xy 94.716921 -213.823055) (xy 94.758112 -213.858746) (xy 94.793803 -213.899937) (xy 94.823269 -213.945787)
			(xy 94.845911 -213.995364) (xy 94.861266 -214.047659) (xy 94.869022 -214.101607) (xy 94.869508 -214.128858)
			(xy 94.869508 -214.992458) (xy 94.869022 -215.019709) (xy 94.861266 -215.073657) (xy 94.845911 -215.125952)
			(xy 94.823269 -215.175529) (xy 94.793803 -215.221379) (xy 94.758112 -215.26257) (xy 94.716921 -215.298261)
			(xy 94.671071 -215.327727) (xy 94.621494 -215.350369) (xy 94.569199 -215.365724) (xy 94.515251 -215.37348)
			(xy 94.460749 -215.37348) (xy 94.406801 -215.365724) (xy 94.354506 -215.350369) (xy 94.304929 -215.327727)
			(xy 94.259079 -215.298261) (xy 94.217888 -215.26257) (xy 94.182197 -215.221379) (xy 94.152731 -215.175529)
			(xy 94.130089 -215.125952) (xy 94.114734 -215.073657) (xy 94.106978 -215.019709) (xy 94.106492 -214.992458)
			(xy 82.837488 -214.992458) (xy 82.824023 -215.003019) (xy 82.70719 -215.084417) (xy 82.585939 -215.159074)
			(xy 82.460658 -215.226752) (xy 82.331749 -215.287234) (xy 82.199625 -215.340325) (xy 82.064709 -215.385857)
			(xy 81.927433 -215.423683) (xy 81.788236 -215.453683) (xy 81.647566 -215.475759) (xy 81.505872 -215.489841)
			(xy 81.363608 -215.495884) (xy 81.22123 -215.493869) (xy 81.079194 -215.483802) (xy 80.937955 -215.465716)
			(xy 80.797965 -215.439668) (xy 80.659674 -215.405742) (xy 80.523523 -215.364046) (xy 80.389949 -215.314714)
			(xy 80.25938 -215.257905) (xy 80.132234 -215.193799) (xy 80.008919 -215.122603) (xy 79.889829 -215.044545)
			(xy 79.775346 -214.959873) (xy 79.665837 -214.868861) (xy 79.561652 -214.771799) (xy 79.463125 -214.668998)
			(xy 79.370572 -214.560787) (xy 79.28429 -214.447514) (xy 79.204553 -214.329541) (xy 79.131619 -214.207245)
			(xy 79.065721 -214.081019) (xy 79.00707 -213.951267) (xy 78.955853 -213.818405) (xy 78.912235 -213.682858)
			(xy 78.876355 -213.54506) (xy 78.848328 -213.405453) (xy 78.828245 -213.264485) (xy 78.81617 -213.122605)
			(xy 78.81214 -212.98027) (xy 2.509012 -212.98027) (xy 2.509012 -213.732364) (xy 16.85798 -213.732364)
			(xy 16.85798 -213.237826) (xy 16.858301 -213.232384) (xy 16.866 -213.224694) (xy 16.871442 -213.224364)
			(xy 17.38757 -213.224364) (xy 17.39538 -213.224043) (xy 17.410251 -213.219263) (xy 17.41678 -213.214966)
			(xy 17.437869 -213.200617) (xy 17.48353 -213.177886) (xy 17.532136 -213.162427) (xy 17.582539 -213.154604)
			(xy 17.633545 -213.154604) (xy 17.683948 -213.162427) (xy 17.732554 -213.177886) (xy 17.778215 -213.200617)
			(xy 17.799304 -213.214966) (xy 17.805837 -213.219254) (xy 17.820706 -213.22404) (xy 17.828514 -213.224364)
			(xy 18.344642 -213.224364) (xy 18.350017 -213.224825) (xy 18.357602 -213.232448) (xy 18.358104 -213.237826)
			(xy 18.358104 -213.732364) (xy 24.402288 -213.732364) (xy 24.402288 -213.237826) (xy 24.402746 -213.232514)
			(xy 24.410193 -213.224938) (xy 24.415496 -213.224364) (xy 24.931624 -213.224364) (xy 24.939436 -213.224067)
			(xy 24.954307 -213.21927) (xy 24.960834 -213.214966) (xy 24.981923 -213.200617) (xy 25.027584 -213.177886)
			(xy 25.07619 -213.162427) (xy 25.126593 -213.154604) (xy 25.177599 -213.154604) (xy 25.228002 -213.162427)
			(xy 25.276608 -213.177886) (xy 25.322269 -213.200617) (xy 25.343358 -213.214966) (xy 25.349879 -213.219275)
			(xy 25.364757 -213.224047) (xy 25.372568 -213.224364) (xy 25.888696 -213.224364) (xy 25.893952 -213.224894)
			(xy 25.901393 -213.232318) (xy 25.901904 -213.237572) (xy 25.901904 -213.23808) (xy 25.901904 -213.732364)
			(xy 31.946088 -213.732364) (xy 31.946088 -213.237826) (xy 31.946546 -213.232514) (xy 31.953993 -213.224938)
			(xy 31.959296 -213.224364) (xy 32.475424 -213.224364) (xy 32.483236 -213.224067) (xy 32.498107 -213.21927)
			(xy 32.504634 -213.214966) (xy 32.525723 -213.200617) (xy 32.571384 -213.177886) (xy 32.61999 -213.162427)
			(xy 32.670393 -213.154604) (xy 32.721399 -213.154604) (xy 32.771802 -213.162427) (xy 32.820408 -213.177886)
			(xy 32.866069 -213.200617) (xy 32.887158 -213.214966) (xy 32.893679 -213.219275) (xy 32.908557 -213.224047)
			(xy 32.916368 -213.224364) (xy 33.432496 -213.224364) (xy 33.437752 -213.224894) (xy 33.445193 -213.232318)
			(xy 33.445704 -213.237572) (xy 33.445704 -213.23808) (xy 33.445704 -213.732364) (xy 39.489888 -213.732364)
			(xy 39.489888 -213.237826) (xy 39.490463 -213.232477) (xy 39.498004 -213.224893) (xy 39.50335 -213.224364)
			(xy 40.019478 -213.224364) (xy 40.027288 -213.224047) (xy 40.042159 -213.219264) (xy 40.048688 -213.214966)
			(xy 40.069777 -213.200617) (xy 40.115438 -213.177886) (xy 40.164044 -213.162427) (xy 40.214447 -213.154604)
			(xy 40.265453 -213.154604) (xy 40.315856 -213.162427) (xy 40.364462 -213.177886) (xy 40.410123 -213.200617)
			(xy 40.431212 -213.214966) (xy 40.437744 -213.219257) (xy 40.452613 -213.224041) (xy 40.460422 -213.224364)
			(xy 40.97655 -213.224364) (xy 40.981926 -213.22482) (xy 40.98951 -213.232447) (xy 40.990012 -213.237826)
			(xy 40.990012 -213.732364) (xy 47.034196 -213.732364) (xy 47.034196 -213.237826) (xy 47.034735 -213.232535)
			(xy 47.042126 -213.224965) (xy 47.047404 -213.224364) (xy 47.563532 -213.224364) (xy 47.57134 -213.224027)
			(xy 47.586212 -213.219258) (xy 47.592742 -213.214966) (xy 47.613831 -213.200617) (xy 47.659492 -213.177886)
			(xy 47.708098 -213.162427) (xy 47.758501 -213.154604) (xy 47.809507 -213.154604) (xy 47.85991 -213.162427)
			(xy 47.908516 -213.177886) (xy 47.954177 -213.200617) (xy 47.975266 -213.214966) (xy 47.981808 -213.21924)
			(xy 47.99667 -213.224034) (xy 48.004476 -213.224364) (xy 48.520604 -213.224364) (xy 48.525861 -213.224889)
			(xy 48.533301 -213.232316) (xy 48.533812 -213.237572) (xy 48.533812 -213.23808) (xy 48.533812 -213.732364)
			(xy 54.577996 -213.732364) (xy 54.577996 -213.237826) (xy 54.578563 -213.232475) (xy 54.58611 -213.224891)
			(xy 54.591458 -213.224364) (xy 56.064658 -213.224364) (xy 56.070094 -213.22471) (xy 56.077783 -213.232391)
			(xy 56.07812 -213.237826) (xy 56.07812 -213.732364) (xy 56.07775 -213.737689) (xy 56.070235 -213.745231)
			(xy 56.064912 -213.745572) (xy 54.591458 -213.745572) (xy 54.586151 -213.745106) (xy 54.578583 -213.737662)
			(xy 54.577996 -213.732364) (xy 48.533812 -213.732364) (xy 48.533449 -213.737691) (xy 48.525929 -213.745233)
			(xy 48.520604 -213.745572) (xy 48.00473 -213.745572) (xy 47.996853 -213.745834) (xy 47.981849 -213.750635)
			(xy 47.975266 -213.75497) (xy 47.95419 -213.769364) (xy 47.908544 -213.792191) (xy 47.859938 -213.807748)
			(xy 47.809521 -213.815667) (xy 47.784004 -213.816184) (xy 47.758483 -213.815712) (xy 47.708055 -213.807813)
			(xy 47.659444 -213.792248) (xy 47.613806 -213.769388) (xy 47.592742 -213.75497) (xy 47.586161 -213.750636)
			(xy 47.571153 -213.74586) (xy 47.563278 -213.745572) (xy 47.047404 -213.745572) (xy 47.042064 -213.745267)
			(xy 47.03452 -213.737705) (xy 47.034196 -213.732364) (xy 40.990012 -213.732364) (xy 40.989649 -213.737691)
			(xy 40.982129 -213.745233) (xy 40.976804 -213.745572) (xy 40.976296 -213.745572) (xy 40.460676 -213.745572)
			(xy 40.452801 -213.745853) (xy 40.437797 -213.750641) (xy 40.431212 -213.75497) (xy 40.410151 -213.769387)
			(xy 40.3645 -213.792209) (xy 40.315889 -213.80776) (xy 40.265468 -213.815671) (xy 40.23995 -213.816184)
			(xy 40.21443 -213.815689) (xy 40.164003 -213.807797) (xy 40.115391 -213.792238) (xy 40.069753 -213.769385)
			(xy 40.048688 -213.75497) (xy 40.042097 -213.750654) (xy 40.027097 -213.745867) (xy 40.019224 -213.745572)
			(xy 39.50335 -213.745572) (xy 39.498055 -213.745045) (xy 39.490482 -213.737647) (xy 39.489888 -213.732364)
			(xy 33.445704 -213.732364) (xy 33.445349 -213.737692) (xy 33.437824 -213.745236) (xy 33.432496 -213.745572)
			(xy 32.916622 -213.745572) (xy 32.908749 -213.745873) (xy 32.893744 -213.750647) (xy 32.887158 -213.75497)
			(xy 32.866084 -213.769367) (xy 32.820438 -213.792194) (xy 32.771831 -213.80775) (xy 32.721413 -213.815667)
			(xy 32.695896 -213.816184) (xy 32.670375 -213.815716) (xy 32.619947 -213.807816) (xy 32.571335 -213.792249)
			(xy 32.525698 -213.769388) (xy 32.504634 -213.75497) (xy 32.498033 -213.750672) (xy 32.48304 -213.745873)
			(xy 32.47517 -213.745572) (xy 31.959296 -213.745572) (xy 31.953954 -213.745272) (xy 31.946412 -213.737707)
			(xy 31.946088 -213.732364) (xy 25.901904 -213.732364) (xy 25.901549 -213.737692) (xy 25.894024 -213.745236)
			(xy 25.888696 -213.745572) (xy 25.372822 -213.745572) (xy 25.364949 -213.745873) (xy 25.349944 -213.750647)
			(xy 25.343358 -213.75497) (xy 25.322284 -213.769367) (xy 25.276638 -213.792194) (xy 25.228031 -213.80775)
			(xy 25.177613 -213.815667) (xy 25.152096 -213.816184) (xy 25.126575 -213.815716) (xy 25.076147 -213.807816)
			(xy 25.027535 -213.792249) (xy 24.981898 -213.769388) (xy 24.960834 -213.75497) (xy 24.954233 -213.750672)
			(xy 24.93924 -213.745873) (xy 24.93137 -213.745572) (xy 24.415496 -213.745572) (xy 24.410154 -213.745272)
			(xy 24.402612 -213.737707) (xy 24.402288 -213.732364) (xy 18.358104 -213.732364) (xy 18.357749 -213.737692)
			(xy 18.350224 -213.745236) (xy 18.344896 -213.745572) (xy 18.344388 -213.745572) (xy 17.828768 -213.745572)
			(xy 17.820893 -213.74585) (xy 17.805888 -213.75064) (xy 17.799304 -213.75497) (xy 17.778218 -213.769347)
			(xy 17.732576 -213.792178) (xy 17.683973 -213.80774) (xy 17.633558 -213.815664) (xy 17.608042 -213.816184)
			(xy 17.582522 -213.815693) (xy 17.532095 -213.8078) (xy 17.483483 -213.79224) (xy 17.437845 -213.769385)
			(xy 17.41678 -213.75497) (xy 17.410191 -213.750651) (xy 17.395189 -213.745865) (xy 17.387316 -213.745572)
			(xy 16.871442 -213.745572) (xy 16.866146 -213.74505) (xy 16.858573 -213.737648) (xy 16.85798 -213.732364)
			(xy 2.509012 -213.732364) (xy 2.509012 -214.582502) (xy 20.958048 -214.582502) (xy 20.958048 -214.087964)
			(xy 20.958566 -214.082708) (xy 20.966 -214.07527) (xy 20.971256 -214.074756) (xy 20.971764 -214.074756)
			(xy 21.487638 -214.074756) (xy 21.495446 -214.074423) (xy 21.510318 -214.069651) (xy 21.516848 -214.065358)
			(xy 21.537937 -214.051009) (xy 21.583598 -214.028278) (xy 21.632204 -214.012819) (xy 21.682607 -214.004996)
			(xy 21.733613 -214.004996) (xy 21.784016 -214.012819) (xy 21.832622 -214.028278) (xy 21.878283 -214.051009)
			(xy 21.899372 -214.065358) (xy 21.905913 -214.069633) (xy 21.920776 -214.074427) (xy 21.928582 -214.074756)
			(xy 22.44471 -214.074756) (xy 22.450019 -214.075218) (xy 22.457591 -214.082664) (xy 22.458172 -214.087964)
			(xy 22.458172 -214.582502) (xy 22.458147 -214.582756) (xy 28.502356 -214.582756) (xy 28.502356 -214.582248)
			(xy 28.502356 -214.087964) (xy 28.502867 -214.082706) (xy 28.510306 -214.075267) (xy 28.515564 -214.074756)
			(xy 29.031692 -214.074756) (xy 29.039503 -214.074447) (xy 29.054374 -214.069659) (xy 29.060902 -214.065358)
			(xy 29.081991 -214.051009) (xy 29.127652 -214.028278) (xy 29.176258 -214.012819) (xy 29.226661 -214.004996)
			(xy 29.277667 -214.004996) (xy 29.32807 -214.012819) (xy 29.376676 -214.028278) (xy 29.422337 -214.051009)
			(xy 29.443426 -214.065358) (xy 29.449955 -214.069654) (xy 29.464827 -214.074435) (xy 29.472636 -214.074756)
			(xy 29.988764 -214.074756) (xy 29.994014 -214.075315) (xy 30.001456 -214.082717) (xy 30.001972 -214.087964)
			(xy 30.001972 -214.582502) (xy 30.001948 -214.582756) (xy 36.046156 -214.582756) (xy 36.046156 -214.582248)
			(xy 36.046156 -214.087964) (xy 36.046667 -214.082706) (xy 36.054106 -214.075267) (xy 36.059364 -214.074756)
			(xy 36.575492 -214.074756) (xy 36.583303 -214.074447) (xy 36.598174 -214.069659) (xy 36.604702 -214.065358)
			(xy 36.625791 -214.051009) (xy 36.671452 -214.028278) (xy 36.720058 -214.012819) (xy 36.770461 -214.004996)
			(xy 36.821467 -214.004996) (xy 36.87187 -214.012819) (xy 36.920476 -214.028278) (xy 36.966137 -214.051009)
			(xy 36.987226 -214.065358) (xy 36.993755 -214.069654) (xy 37.008627 -214.074435) (xy 37.016436 -214.074756)
			(xy 37.532564 -214.074756) (xy 37.537814 -214.075315) (xy 37.545256 -214.082717) (xy 37.545772 -214.087964)
			(xy 37.545772 -214.582502) (xy 43.589956 -214.582502) (xy 43.589956 -214.087964) (xy 43.590467 -214.082706)
			(xy 43.597906 -214.075267) (xy 43.603164 -214.074756) (xy 43.603672 -214.074756) (xy 44.119546 -214.074756)
			(xy 44.127355 -214.074427) (xy 44.142227 -214.069652) (xy 44.148756 -214.065358) (xy 44.169845 -214.051009)
			(xy 44.215506 -214.028278) (xy 44.264112 -214.012819) (xy 44.314515 -214.004996) (xy 44.365521 -214.004996)
			(xy 44.415924 -214.012819) (xy 44.46453 -214.028278) (xy 44.510191 -214.051009) (xy 44.53128 -214.065358)
			(xy 44.537819 -214.069636) (xy 44.552683 -214.074428) (xy 44.56049 -214.074756) (xy 45.076618 -214.074756)
			(xy 45.081928 -214.075213) (xy 45.089499 -214.082663) (xy 45.09008 -214.087964) (xy 45.09008 -214.582502)
			(xy 45.090055 -214.582756) (xy 51.134264 -214.582756) (xy 51.134264 -214.582248) (xy 51.134264 -214.087964)
			(xy 51.134768 -214.082704) (xy 51.142211 -214.075265) (xy 51.147472 -214.074756) (xy 51.6636 -214.074756)
			(xy 51.671411 -214.07445) (xy 51.686283 -214.06966) (xy 51.69281 -214.065358) (xy 51.713899 -214.051009)
			(xy 51.75956 -214.028278) (xy 51.808166 -214.012819) (xy 51.858569 -214.004996) (xy 51.909575 -214.004996)
			(xy 51.959978 -214.012819) (xy 52.008584 -214.028278) (xy 52.054245 -214.051009) (xy 52.075334 -214.065358)
			(xy 52.081861 -214.069657) (xy 52.096734 -214.074436) (xy 52.104544 -214.074756) (xy 52.620672 -214.074756)
			(xy 52.625923 -214.07531) (xy 52.633365 -214.082716) (xy 52.63388 -214.087964) (xy 52.63388 -214.582502)
			(xy 58.678064 -214.582502) (xy 58.678064 -214.087964) (xy 58.678568 -214.082704) (xy 58.686011 -214.075265)
			(xy 58.691272 -214.074756) (xy 58.69178 -214.074756) (xy 60.164726 -214.074756) (xy 60.170037 -214.075208)
			(xy 60.177607 -214.082661) (xy 60.178188 -214.087964) (xy 60.178188 -214.582502) (xy 60.177653 -214.58786)
			(xy 60.170083 -214.595444) (xy 60.164726 -214.595964) (xy 58.691526 -214.595964) (xy 58.686095 -214.595604)
			(xy 58.678408 -214.587932) (xy 58.678064 -214.582502) (xy 52.63388 -214.582502) (xy 52.63338 -214.587802)
			(xy 52.625961 -214.595371) (xy 52.620672 -214.595964) (xy 52.104798 -214.595964) (xy 52.096987 -214.596266)
			(xy 52.082115 -214.601059) (xy 52.075588 -214.605362) (xy 52.054468 -214.619714) (xy 52.008744 -214.64244)
			(xy 51.96007 -214.657869) (xy 51.909603 -214.665635) (xy 51.884072 -214.666068) (xy 51.858541 -214.665645)
			(xy 51.808077 -214.657865) (xy 51.759405 -214.642432) (xy 51.713677 -214.619711) (xy 51.692556 -214.605362)
			(xy 51.68603 -214.601061) (xy 51.671156 -214.596283) (xy 51.663346 -214.595964) (xy 51.147472 -214.595964)
			(xy 51.142125 -214.595688) (xy 51.134583 -214.588105) (xy 51.134264 -214.582756) (xy 45.090055 -214.582756)
			(xy 45.089553 -214.587862) (xy 45.081977 -214.595446) (xy 45.076618 -214.595964) (xy 44.560744 -214.595964)
			(xy 44.552934 -214.596286) (xy 44.538063 -214.601065) (xy 44.531534 -214.605362) (xy 44.510429 -214.619737)
			(xy 44.464699 -214.642458) (xy 44.416021 -214.65788) (xy 44.36555 -214.665639) (xy 44.340018 -214.666068)
			(xy 44.314488 -214.665622) (xy 44.264025 -214.657849) (xy 44.215352 -214.642422) (xy 44.169624 -214.619708)
			(xy 44.148502 -214.605362) (xy 44.141966 -214.601079) (xy 44.1271 -214.59629) (xy 44.119292 -214.595964)
			(xy 43.603418 -214.595964) (xy 43.597986 -214.595609) (xy 43.590299 -214.587933) (xy 43.589956 -214.582502)
			(xy 37.545772 -214.582502) (xy 37.545279 -214.587804) (xy 37.537855 -214.595374) (xy 37.532564 -214.595964)
			(xy 37.01669 -214.595964) (xy 37.008878 -214.596263) (xy 36.994007 -214.601058) (xy 36.98748 -214.605362)
			(xy 36.966362 -214.619717) (xy 36.920637 -214.642442) (xy 36.871962 -214.657871) (xy 36.821495 -214.665636)
			(xy 36.795964 -214.666068) (xy 36.770433 -214.665649) (xy 36.719969 -214.657868) (xy 36.671296 -214.642433)
			(xy 36.625569 -214.619712) (xy 36.604448 -214.605362) (xy 36.597924 -214.601058) (xy 36.583048 -214.596282)
			(xy 36.575238 -214.595964) (xy 36.059364 -214.595964) (xy 36.054016 -214.595693) (xy 36.046475 -214.588106)
			(xy 36.046156 -214.582756) (xy 30.001948 -214.582756) (xy 30.001479 -214.587804) (xy 29.994055 -214.595374)
			(xy 29.988764 -214.595964) (xy 29.47289 -214.595964) (xy 29.465078 -214.596263) (xy 29.450207 -214.601058)
			(xy 29.44368 -214.605362) (xy 29.422562 -214.619717) (xy 29.376837 -214.642442) (xy 29.328162 -214.657871)
			(xy 29.277695 -214.665636) (xy 29.252164 -214.666068) (xy 29.226633 -214.665649) (xy 29.176169 -214.657868)
			(xy 29.127496 -214.642433) (xy 29.081769 -214.619712) (xy 29.060648 -214.605362) (xy 29.054124 -214.601058)
			(xy 29.039248 -214.596282) (xy 29.031438 -214.595964) (xy 28.515564 -214.595964) (xy 28.510216 -214.595693)
			(xy 28.502675 -214.588106) (xy 28.502356 -214.582756) (xy 22.458147 -214.582756) (xy 22.457652 -214.587864)
			(xy 22.450071 -214.595449) (xy 22.44471 -214.595964) (xy 21.928836 -214.595964) (xy 21.921026 -214.596282)
			(xy 21.906154 -214.601064) (xy 21.899626 -214.605362) (xy 21.878495 -214.619697) (xy 21.832775 -214.642427)
			(xy 21.784104 -214.657861) (xy 21.73364 -214.665632) (xy 21.70811 -214.666068) (xy 21.68258 -214.665626)
			(xy 21.632116 -214.657852) (xy 21.583444 -214.642424) (xy 21.537716 -214.619709) (xy 21.516594 -214.605362)
			(xy 21.510059 -214.601076) (xy 21.495192 -214.596289) (xy 21.487384 -214.595964) (xy 20.97151 -214.595964)
			(xy 20.966077 -214.595614) (xy 20.95839 -214.587935) (xy 20.958048 -214.582502) (xy 2.509012 -214.582502)
			(xy 2.509012 -215.432386) (xy 16.85798 -215.432386) (xy 16.85798 -214.937848) (xy 16.858358 -214.932525)
			(xy 16.865867 -214.924982) (xy 16.871188 -214.92464) (xy 16.871696 -214.92464) (xy 17.38757 -214.92464)
			(xy 17.39538 -214.924324) (xy 17.410252 -214.91954) (xy 17.41678 -214.915242) (xy 17.437869 -214.900893)
			(xy 17.48353 -214.878162) (xy 17.532136 -214.862703) (xy 17.582539 -214.85488) (xy 17.633545 -214.85488)
			(xy 17.683948 -214.862703) (xy 17.732554 -214.878162) (xy 17.778215 -214.900893) (xy 17.799304 -214.915242)
			(xy 17.805839 -214.919528) (xy 17.820706 -214.924315) (xy 17.828514 -214.92464) (xy 18.344642 -214.92464)
			(xy 18.349951 -214.925095) (xy 18.35752 -214.932547) (xy 18.358104 -214.937848) (xy 18.358104 -215.432386)
			(xy 18.358077 -215.43264) (xy 24.402288 -215.43264) (xy 24.402288 -215.432132) (xy 24.402288 -214.937848)
			(xy 24.402659 -214.932523) (xy 24.410173 -214.92498) (xy 24.415496 -214.92464) (xy 24.931624 -214.92464)
			(xy 24.939436 -214.924347) (xy 24.954308 -214.919548) (xy 24.960834 -214.915242) (xy 24.981923 -214.900893)
			(xy 25.027584 -214.878162) (xy 25.07619 -214.862703) (xy 25.126593 -214.85488) (xy 25.177599 -214.85488)
			(xy 25.228002 -214.862703) (xy 25.276608 -214.878162) (xy 25.322269 -214.900893) (xy 25.343358 -214.915242)
			(xy 25.349881 -214.919549) (xy 25.364757 -214.924323) (xy 25.372568 -214.92464) (xy 25.888696 -214.92464)
			(xy 25.894039 -214.924934) (xy 25.901583 -214.932504) (xy 25.901904 -214.937848) (xy 25.901904 -215.432386)
			(xy 25.901879 -215.43264) (xy 31.946088 -215.43264) (xy 31.946088 -215.432132) (xy 31.946088 -214.937848)
			(xy 31.946459 -214.932523) (xy 31.953973 -214.92498) (xy 31.959296 -214.92464) (xy 32.475424 -214.92464)
			(xy 32.483236 -214.924347) (xy 32.498108 -214.919548) (xy 32.504634 -214.915242) (xy 32.525723 -214.900893)
			(xy 32.571384 -214.878162) (xy 32.61999 -214.862703) (xy 32.670393 -214.85488) (xy 32.721399 -214.85488)
			(xy 32.771802 -214.862703) (xy 32.820408 -214.878162) (xy 32.866069 -214.900893) (xy 32.887158 -214.915242)
			(xy 32.893681 -214.919549) (xy 32.908557 -214.924323) (xy 32.916368 -214.92464) (xy 33.432496 -214.92464)
			(xy 33.437839 -214.924934) (xy 33.445383 -214.932504) (xy 33.445704 -214.937848) (xy 33.445704 -215.432386)
			(xy 39.489888 -215.432386) (xy 39.489888 -214.937848) (xy 39.490259 -214.932523) (xy 39.497773 -214.92498)
			(xy 39.503096 -214.92464) (xy 39.503604 -214.92464) (xy 40.019478 -214.92464) (xy 40.027288 -214.924327)
			(xy 40.04216 -214.919542) (xy 40.048688 -214.915242) (xy 40.069777 -214.900893) (xy 40.115438 -214.878162)
			(xy 40.164044 -214.862703) (xy 40.214447 -214.85488) (xy 40.265453 -214.85488) (xy 40.315856 -214.862703)
			(xy 40.364462 -214.878162) (xy 40.410123 -214.900893) (xy 40.431212 -214.915242) (xy 40.437745 -214.919531)
			(xy 40.452614 -214.924316) (xy 40.460422 -214.92464) (xy 40.97655 -214.92464) (xy 40.981848 -214.925157)
			(xy 40.989422 -214.932562) (xy 40.990012 -214.937848) (xy 40.990012 -215.432386) (xy 40.989985 -215.43264)
			(xy 47.034196 -215.43264) (xy 47.034196 -215.432132) (xy 47.034196 -214.937848) (xy 47.03456 -214.932521)
			(xy 47.042078 -214.924977) (xy 47.047404 -214.92464) (xy 47.563532 -214.92464) (xy 47.571341 -214.924307)
			(xy 47.586212 -214.919536) (xy 47.592742 -214.915242) (xy 47.613831 -214.900893) (xy 47.659492 -214.878162)
			(xy 47.708098 -214.862703) (xy 47.758501 -214.85488) (xy 47.809507 -214.85488) (xy 47.85991 -214.862703)
			(xy 47.908516 -214.878162) (xy 47.954177 -214.900893) (xy 47.975266 -214.915242) (xy 47.981809 -214.919513)
			(xy 47.99667 -214.92431) (xy 48.004476 -214.92464) (xy 48.520604 -214.92464) (xy 48.525949 -214.924929)
			(xy 48.533492 -214.932502) (xy 48.533812 -214.937848) (xy 48.533812 -215.432386) (xy 54.577996 -215.432386)
			(xy 54.577996 -214.937848) (xy 54.57836 -214.932521) (xy 54.585878 -214.924977) (xy 54.591204 -214.92464)
			(xy 56.064658 -214.92464) (xy 56.069957 -214.925151) (xy 56.077531 -214.932561) (xy 56.07812 -214.937848)
			(xy 56.07812 -215.432386) (xy 56.077807 -215.437829) (xy 56.070102 -215.445518) (xy 56.064658 -215.445848)
			(xy 54.591458 -215.445848) (xy 54.586086 -215.445376) (xy 54.578501 -215.43776) (xy 54.577996 -215.432386)
			(xy 48.533812 -215.432386) (xy 48.533362 -215.4377) (xy 48.525909 -215.445274) (xy 48.520604 -215.445848)
			(xy 48.00473 -215.445848) (xy 47.99692 -215.446167) (xy 47.982049 -215.450948) (xy 47.97552 -215.455246)
			(xy 47.95439 -215.469582) (xy 47.908669 -215.492312) (xy 47.859999 -215.507746) (xy 47.809534 -215.515517)
			(xy 47.784004 -215.515952) (xy 47.758474 -215.515516) (xy 47.70801 -215.50774) (xy 47.659337 -215.492311)
			(xy 47.61361 -215.469594) (xy 47.592488 -215.455246) (xy 47.585956 -215.450956) (xy 47.571086 -215.446171)
			(xy 47.563278 -215.445848) (xy 47.047404 -215.445848) (xy 47.042151 -215.445307) (xy 47.034711 -215.437891)
			(xy 47.034196 -215.43264) (xy 40.989985 -215.43264) (xy 40.989445 -215.437736) (xy 40.981898 -215.44532)
			(xy 40.97655 -215.445848) (xy 40.460676 -215.445848) (xy 40.452864 -215.446143) (xy 40.437992 -215.450941)
			(xy 40.431466 -215.455246) (xy 40.410351 -215.469605) (xy 40.364625 -215.49233) (xy 40.31595 -215.507757)
			(xy 40.265482 -215.515521) (xy 40.23995 -215.515952) (xy 40.214421 -215.515493) (xy 40.163958 -215.507724)
			(xy 40.115285 -215.492302) (xy 40.069557 -215.469591) (xy 40.048434 -215.455246) (xy 40.041891 -215.450974)
			(xy 40.02703 -215.446178) (xy 40.019224 -215.445848) (xy 39.50335 -215.445848) (xy 39.497977 -215.445381)
			(xy 39.490393 -215.437762) (xy 39.489888 -215.432386) (xy 33.445704 -215.432386) (xy 33.445173 -215.437678)
			(xy 33.437776 -215.445248) (xy 33.432496 -215.445848) (xy 32.916622 -215.445848) (xy 32.908812 -215.446163)
			(xy 32.89394 -215.450947) (xy 32.887412 -215.455246) (xy 32.866284 -215.469586) (xy 32.820563 -215.492315)
			(xy 32.771891 -215.507747) (xy 32.721426 -215.515517) (xy 32.695896 -215.515952) (xy 32.670366 -215.51552)
			(xy 32.619901 -215.507743) (xy 32.571229 -215.492313) (xy 32.525502 -215.469594) (xy 32.50438 -215.455246)
			(xy 32.497849 -215.450953) (xy 32.482979 -215.44617) (xy 32.47517 -215.445848) (xy 31.959296 -215.445848)
			(xy 31.954042 -215.445312) (xy 31.946602 -215.437892) (xy 31.946088 -215.43264) (xy 25.901879 -215.43264)
			(xy 25.901373 -215.437678) (xy 25.893976 -215.445248) (xy 25.888696 -215.445848) (xy 25.372822 -215.445848)
			(xy 25.365012 -215.446163) (xy 25.35014 -215.450947) (xy 25.343612 -215.455246) (xy 25.322484 -215.469586)
			(xy 25.276763 -215.492315) (xy 25.228091 -215.507747) (xy 25.177626 -215.515517) (xy 25.152096 -215.515952)
			(xy 25.126566 -215.51552) (xy 25.076101 -215.507743) (xy 25.027429 -215.492313) (xy 24.981702 -215.469594)
			(xy 24.96058 -215.455246) (xy 24.954049 -215.450953) (xy 24.939179 -215.44617) (xy 24.93137 -215.445848)
			(xy 24.415496 -215.445848) (xy 24.410242 -215.445312) (xy 24.402802 -215.437892) (xy 24.402288 -215.43264)
			(xy 18.358077 -215.43264) (xy 18.357545 -215.437738) (xy 18.349992 -215.445322) (xy 18.344642 -215.445848)
			(xy 17.828768 -215.445848) (xy 17.82096 -215.446183) (xy 17.806088 -215.450953) (xy 17.799558 -215.455246)
			(xy 17.778445 -215.469609) (xy 17.732718 -215.492333) (xy 17.684042 -215.507759) (xy 17.633574 -215.515521)
			(xy 17.608042 -215.515952) (xy 17.582512 -215.515497) (xy 17.532049 -215.507727) (xy 17.483377 -215.492303)
			(xy 17.437648 -215.469591) (xy 17.416526 -215.455246) (xy 17.409985 -215.450971) (xy 17.395122 -215.446177)
			(xy 17.387316 -215.445848) (xy 16.871442 -215.445848) (xy 16.866009 -215.445491) (xy 16.85832 -215.437818)
			(xy 16.85798 -215.432386) (xy 2.509012 -215.432386) (xy 2.509012 -216.282524) (xy 20.958048 -216.282524)
			(xy 20.958048 -215.787986) (xy 20.958542 -215.782618) (xy 20.966141 -215.775033) (xy 20.97151 -215.774524)
			(xy 21.487638 -215.774524) (xy 21.495447 -215.774197) (xy 21.510319 -215.769422) (xy 21.516848 -215.765126)
			(xy 21.537937 -215.750777) (xy 21.583598 -215.728046) (xy 21.632204 -215.712587) (xy 21.682607 -215.704764)
			(xy 21.733613 -215.704764) (xy 21.784016 -215.712587) (xy 21.832622 -215.728046) (xy 21.878283 -215.750777)
			(xy 21.899372 -215.765126) (xy 21.905915 -215.769398) (xy 21.920776 -215.774194) (xy 21.928582 -215.774524)
			(xy 22.44471 -215.774524) (xy 22.450072 -215.775042) (xy 22.457656 -215.782624) (xy 22.458172 -215.787986)
			(xy 22.458172 -216.282524) (xy 28.502356 -216.282524) (xy 28.502356 -215.787986) (xy 28.502816 -215.782676)
			(xy 28.510263 -215.775105) (xy 28.515564 -215.774524) (xy 29.031692 -215.774524) (xy 29.039503 -215.77422)
			(xy 29.054375 -215.769429) (xy 29.060902 -215.765126) (xy 29.081991 -215.750777) (xy 29.127652 -215.728046)
			(xy 29.176258 -215.712587) (xy 29.226661 -215.704764) (xy 29.277667 -215.704764) (xy 29.32807 -215.712587)
			(xy 29.376676 -215.728046) (xy 29.422337 -215.750777) (xy 29.443426 -215.765126) (xy 29.449957 -215.769419)
			(xy 29.464827 -215.774202) (xy 29.472636 -215.774524) (xy 29.988764 -215.774524) (xy 29.994099 -215.774854)
			(xy 30.001644 -215.782397) (xy 30.001972 -215.787732) (xy 30.001972 -215.78824) (xy 30.001972 -216.282524)
			(xy 36.046156 -216.282524) (xy 36.046156 -215.787986) (xy 36.046616 -215.782676) (xy 36.054063 -215.775105)
			(xy 36.059364 -215.774524) (xy 36.575492 -215.774524) (xy 36.583303 -215.77422) (xy 36.598175 -215.769429)
			(xy 36.604702 -215.765126) (xy 36.625791 -215.750777) (xy 36.671452 -215.728046) (xy 36.720058 -215.712587)
			(xy 36.770461 -215.704764) (xy 36.821467 -215.704764) (xy 36.87187 -215.712587) (xy 36.920476 -215.728046)
			(xy 36.966137 -215.750777) (xy 36.987226 -215.765126) (xy 36.993757 -215.769419) (xy 37.008627 -215.774202)
			(xy 37.016436 -215.774524) (xy 37.532564 -215.774524) (xy 37.537899 -215.774854) (xy 37.545444 -215.782397)
			(xy 37.545772 -215.787732) (xy 37.545772 -215.78824) (xy 37.545772 -216.282524) (xy 43.589956 -216.282524)
			(xy 43.589956 -215.787986) (xy 43.590272 -215.782545) (xy 43.597976 -215.774859) (xy 43.603418 -215.774524)
			(xy 44.119546 -215.774524) (xy 44.127355 -215.7742) (xy 44.142227 -215.769423) (xy 44.148756 -215.765126)
			(xy 44.169845 -215.750777) (xy 44.215506 -215.728046) (xy 44.264112 -215.712587) (xy 44.314515 -215.704764)
			(xy 44.365521 -215.704764) (xy 44.415924 -215.712587) (xy 44.46453 -215.728046) (xy 44.510191 -215.750777)
			(xy 44.53128 -215.765126) (xy 44.537821 -215.769401) (xy 44.552684 -215.774196) (xy 44.56049 -215.774524)
			(xy 45.076618 -215.774524) (xy 45.081981 -215.775037) (xy 45.089565 -215.782623) (xy 45.09008 -215.787986)
			(xy 45.09008 -216.282524) (xy 51.134264 -216.282524) (xy 51.134264 -215.787986) (xy 51.134717 -215.782675)
			(xy 51.142169 -215.775103) (xy 51.147472 -215.774524) (xy 51.6636 -215.774524) (xy 51.671411 -215.774223)
			(xy 51.686283 -215.76943) (xy 51.69281 -215.765126) (xy 51.713899 -215.750777) (xy 51.75956 -215.728046)
			(xy 51.808166 -215.712587) (xy 51.858569 -215.704764) (xy 51.909575 -215.704764) (xy 51.959978 -215.712587)
			(xy 52.008584 -215.728046) (xy 52.054245 -215.750777) (xy 52.075334 -215.765126) (xy 52.081863 -215.769422)
			(xy 52.096735 -215.774203) (xy 52.104544 -215.774524) (xy 52.620672 -215.774524) (xy 52.626008 -215.774849)
			(xy 52.633553 -215.782396) (xy 52.63388 -215.787732) (xy 52.63388 -215.78824) (xy 52.63388 -216.282524)
			(xy 58.678064 -216.282524) (xy 58.678064 -215.787986) (xy 58.678373 -215.782543) (xy 58.686082 -215.774856)
			(xy 58.691526 -215.774524) (xy 60.164726 -215.774524) (xy 60.17009 -215.775032) (xy 60.177673 -215.782622)
			(xy 60.178188 -215.787986) (xy 60.178188 -216.282524) (xy 167.778176 -216.282524) (xy 167.778176 -215.787986)
			(xy 167.778618 -215.782672) (xy 167.786078 -215.775099) (xy 167.791384 -215.774524) (xy 169.264584 -215.774524)
			(xy 169.269922 -215.774841) (xy 169.277466 -215.782394) (xy 169.277792 -215.787732) (xy 169.277792 -216.282524)
			(xy 175.321976 -216.282524) (xy 175.321976 -215.787986) (xy 175.322274 -215.78254) (xy 175.329991 -215.774853)
			(xy 175.335438 -215.774524) (xy 175.851566 -215.774524) (xy 175.859376 -215.774209) (xy 175.874248 -215.769425)
			(xy 175.880776 -215.765126) (xy 175.901865 -215.750777) (xy 175.947526 -215.728046) (xy 175.996132 -215.712587)
			(xy 176.046535 -215.704764) (xy 176.097541 -215.704764) (xy 176.147944 -215.712587) (xy 176.19655 -215.728046)
			(xy 176.242211 -215.750777) (xy 176.2633 -215.765126) (xy 176.269837 -215.769409) (xy 176.284703 -215.774198)
			(xy 176.29251 -215.774524) (xy 176.808638 -215.774524) (xy 176.814003 -215.775024) (xy 176.821586 -215.78262)
			(xy 176.8221 -215.787986) (xy 176.8221 -216.282524) (xy 182.866284 -216.282524) (xy 182.866284 -215.787986)
			(xy 182.866719 -215.78267) (xy 182.874184 -215.775097) (xy 182.879492 -215.774524) (xy 183.39562 -215.774524)
			(xy 183.403432 -215.774231) (xy 183.418304 -215.769432) (xy 183.42483 -215.765126) (xy 183.445919 -215.750777)
			(xy 183.49158 -215.728046) (xy 183.540186 -215.712587) (xy 183.590589 -215.704764) (xy 183.641595 -215.704764)
			(xy 183.691998 -215.712587) (xy 183.740604 -215.728046) (xy 183.786265 -215.750777) (xy 183.807354 -215.765126)
			(xy 183.813879 -215.76943) (xy 183.828754 -215.774206) (xy 183.836564 -215.774524) (xy 184.352692 -215.774524)
			(xy 184.358031 -215.774835) (xy 184.365574 -215.782392) (xy 184.3659 -215.787732) (xy 184.3659 -215.78824)
			(xy 184.3659 -216.282524) (xy 190.410084 -216.282524) (xy 190.410084 -215.787986) (xy 190.410375 -215.782538)
			(xy 190.418097 -215.77485) (xy 190.423546 -215.774524) (xy 190.939674 -215.774524) (xy 190.947484 -215.774212)
			(xy 190.962356 -215.769426) (xy 190.968884 -215.765126) (xy 190.989973 -215.750777) (xy 191.035634 -215.728046)
			(xy 191.08424 -215.712587) (xy 191.134643 -215.704764) (xy 191.185649 -215.704764) (xy 191.236052 -215.712587)
			(xy 191.284658 -215.728046) (xy 191.330319 -215.750777) (xy 191.351408 -215.765126) (xy 191.357943 -215.769412)
			(xy 191.37281 -215.7742) (xy 191.380618 -215.774524) (xy 191.896746 -215.774524) (xy 191.902112 -215.775019)
			(xy 191.909694 -215.782619) (xy 191.910208 -215.787986) (xy 191.910208 -216.282524) (xy 197.954392 -216.282524)
			(xy 197.954392 -215.787986) (xy 197.954908 -215.782691) (xy 197.962317 -215.775124) (xy 197.9676 -215.774524)
			(xy 198.483728 -215.774524) (xy 198.491541 -215.774235) (xy 198.506412 -215.769433) (xy 198.512938 -215.765126)
			(xy 198.534027 -215.750777) (xy 198.579688 -215.728046) (xy 198.628294 -215.712587) (xy 198.678697 -215.704764)
			(xy 198.729703 -215.704764) (xy 198.780106 -215.712587) (xy 198.828712 -215.728046) (xy 198.874373 -215.750777)
			(xy 198.895462 -215.765126) (xy 198.902007 -215.769394) (xy 198.916866 -215.774193) (xy 198.924672 -215.774524)
			(xy 199.4408 -215.774524) (xy 199.44614 -215.77483) (xy 199.453683 -215.782391) (xy 199.454008 -215.787732)
			(xy 199.454008 -215.78824) (xy 199.454008 -216.282524) (xy 205.498192 -216.282524) (xy 205.498192 -215.787986)
			(xy 205.498708 -215.782691) (xy 205.506117 -215.775124) (xy 205.5114 -215.774524) (xy 206.027528 -215.774524)
			(xy 206.035341 -215.774235) (xy 206.050212 -215.769433) (xy 206.056738 -215.765126) (xy 206.077827 -215.750777)
			(xy 206.123488 -215.728046) (xy 206.172094 -215.712587) (xy 206.222497 -215.704764) (xy 206.273503 -215.704764)
			(xy 206.323906 -215.712587) (xy 206.372512 -215.728046) (xy 206.418173 -215.750777) (xy 206.439262 -215.765126)
			(xy 206.445807 -215.769394) (xy 206.460666 -215.774193) (xy 206.468472 -215.774524) (xy 206.9846 -215.774524)
			(xy 206.98994 -215.77483) (xy 206.997483 -215.782391) (xy 206.997808 -215.787732) (xy 206.997808 -215.78824)
			(xy 206.997808 -216.28227) (xy 268.898116 -216.28227) (xy 268.898116 -215.787732) (xy 268.898451 -215.782398)
			(xy 268.90599 -215.774854) (xy 268.911324 -215.774524) (xy 268.911832 -215.774524) (xy 269.427706 -215.774524)
			(xy 269.435518 -215.774226) (xy 269.450389 -215.76943) (xy 269.456916 -215.765126) (xy 269.478005 -215.750777)
			(xy 269.523666 -215.728046) (xy 269.572272 -215.712587) (xy 269.622675 -215.704764) (xy 269.673681 -215.704764)
			(xy 269.724084 -215.712587) (xy 269.77269 -215.728046) (xy 269.818351 -215.750777) (xy 269.83944 -215.765126)
			(xy 269.845968 -215.769424) (xy 269.86084 -215.774204) (xy 269.86865 -215.774524) (xy 270.384778 -215.774524)
			(xy 270.390076 -215.775036) (xy 270.397647 -215.782446) (xy 270.39824 -215.787732) (xy 270.39824 -216.28227)
			(xy 270.398224 -216.282524) (xy 276.442424 -216.282524) (xy 276.442424 -216.282016) (xy 276.442424 -215.787732)
			(xy 276.442752 -215.782396) (xy 276.450296 -215.774852) (xy 276.455632 -215.774524) (xy 276.97176 -215.774524)
			(xy 276.97957 -215.774206) (xy 276.994442 -215.769424) (xy 277.00097 -215.765126) (xy 277.022059 -215.750777)
			(xy 277.06772 -215.728046) (xy 277.116326 -215.712587) (xy 277.166729 -215.704764) (xy 277.217735 -215.704764)
			(xy 277.268138 -215.712587) (xy 277.316744 -215.728046) (xy 277.362405 -215.750777) (xy 277.383494 -215.765126)
			(xy 277.390032 -215.769407) (xy 277.404897 -215.774198) (xy 277.412704 -215.774524) (xy 277.928832 -215.774524)
			(xy 277.934106 -215.774977) (xy 277.941549 -215.782455) (xy 277.94204 -215.787732) (xy 277.94204 -216.28227)
			(xy 277.942017 -216.282524) (xy 283.986224 -216.282524) (xy 283.986224 -216.282016) (xy 283.986224 -215.787732)
			(xy 283.986552 -215.782396) (xy 283.994096 -215.774852) (xy 283.999432 -215.774524) (xy 284.51556 -215.774524)
			(xy 284.52337 -215.774206) (xy 284.538242 -215.769424) (xy 284.54477 -215.765126) (xy 284.565859 -215.750777)
			(xy 284.61152 -215.728046) (xy 284.660126 -215.712587) (xy 284.710529 -215.704764) (xy 284.761535 -215.704764)
			(xy 284.811938 -215.712587) (xy 284.860544 -215.728046) (xy 284.906205 -215.750777) (xy 284.927294 -215.765126)
			(xy 284.933832 -215.769407) (xy 284.948697 -215.774198) (xy 284.956504 -215.774524) (xy 285.472632 -215.774524)
			(xy 285.477906 -215.774977) (xy 285.485349 -215.782455) (xy 285.48584 -215.787732) (xy 285.48584 -216.28227)
			(xy 291.530024 -216.28227) (xy 291.530024 -215.787732) (xy 291.530352 -215.782396) (xy 291.537896 -215.774852)
			(xy 291.543232 -215.774524) (xy 291.54374 -215.774524) (xy 292.059614 -215.774524) (xy 292.067426 -215.774229)
			(xy 292.082298 -215.769431) (xy 292.088824 -215.765126) (xy 292.109913 -215.750777) (xy 292.155574 -215.728046)
			(xy 292.20418 -215.712587) (xy 292.254583 -215.704764) (xy 292.305589 -215.704764) (xy 292.355992 -215.712587)
			(xy 292.404598 -215.728046) (xy 292.450259 -215.750777) (xy 292.471348 -215.765126) (xy 292.477874 -215.769427)
			(xy 292.492748 -215.774205) (xy 292.500558 -215.774524) (xy 293.016686 -215.774524) (xy 293.021985 -215.775031)
			(xy 293.029556 -215.782445) (xy 293.030148 -215.787732) (xy 293.030148 -216.28227) (xy 293.030132 -216.282524)
			(xy 299.074332 -216.282524) (xy 299.074332 -216.282016) (xy 299.074332 -215.787732) (xy 299.074652 -215.782394)
			(xy 299.082202 -215.774849) (xy 299.08754 -215.774524) (xy 299.603668 -215.774524) (xy 299.611478 -215.774209)
			(xy 299.62635 -215.769425) (xy 299.632878 -215.765126) (xy 299.653967 -215.750777) (xy 299.699628 -215.728046)
			(xy 299.748234 -215.712587) (xy 299.798637 -215.704764) (xy 299.849643 -215.704764) (xy 299.900046 -215.712587)
			(xy 299.948652 -215.728046) (xy 299.994313 -215.750777) (xy 300.015402 -215.765126) (xy 300.021938 -215.76941)
			(xy 300.036804 -215.774199) (xy 300.044612 -215.774524) (xy 300.56074 -215.774524) (xy 300.566015 -215.774971)
			(xy 300.573458 -215.782454) (xy 300.573948 -215.787732) (xy 300.573948 -216.28227) (xy 306.618132 -216.28227)
			(xy 306.618132 -215.787732) (xy 306.618452 -215.782394) (xy 306.626002 -215.774849) (xy 306.63134 -215.774524)
			(xy 306.631848 -215.774524) (xy 308.104794 -215.774524) (xy 308.110094 -215.775025) (xy 308.117664 -215.782443)
			(xy 308.118256 -215.787732) (xy 308.118256 -216.28227) (xy 308.118239 -216.282524) (xy 415.718244 -216.282524)
			(xy 415.718244 -215.787732) (xy 415.718811 -215.782484) (xy 415.726208 -215.775043) (xy 415.731452 -215.774524)
			(xy 417.204652 -215.774524) (xy 417.209986 -215.774862) (xy 417.217531 -215.782399) (xy 417.21786 -215.787732)
			(xy 417.21786 -216.28227) (xy 423.262044 -216.28227) (xy 423.262044 -215.787732) (xy 423.262611 -215.782484)
			(xy 423.270008 -215.775043) (xy 423.275252 -215.774524) (xy 423.27576 -215.774524) (xy 423.791634 -215.774524)
			(xy 423.799443 -215.774195) (xy 423.814315 -215.769421) (xy 423.820844 -215.765126) (xy 423.841933 -215.750777)
			(xy 423.887594 -215.728046) (xy 423.9362 -215.712587) (xy 423.986603 -215.704764) (xy 424.037609 -215.704764)
			(xy 424.088012 -215.712587) (xy 424.136618 -215.728046) (xy 424.182279 -215.750777) (xy 424.203368 -215.765126)
			(xy 424.209912 -215.769397) (xy 424.224772 -215.774194) (xy 424.232578 -215.774524) (xy 424.748706 -215.774524)
			(xy 424.754007 -215.775017) (xy 424.761577 -215.782441) (xy 424.762168 -215.787732) (xy 424.762168 -216.28227)
			(xy 424.762151 -216.282524) (xy 430.806352 -216.282524) (xy 430.806352 -216.282016) (xy 430.806352 -215.787732)
			(xy 430.806912 -215.782483) (xy 430.814313 -215.77504) (xy 430.81956 -215.774524) (xy 431.335688 -215.774524)
			(xy 431.343499 -215.774218) (xy 431.358371 -215.769428) (xy 431.364898 -215.765126) (xy 431.385987 -215.750777)
			(xy 431.431648 -215.728046) (xy 431.480254 -215.712587) (xy 431.530657 -215.704764) (xy 431.581663 -215.704764)
			(xy 431.632066 -215.712587) (xy 431.680672 -215.728046) (xy 431.726333 -215.750777) (xy 431.747422 -215.765126)
			(xy 431.753954 -215.769417) (xy 431.768823 -215.774202) (xy 431.776632 -215.774524) (xy 432.29276 -215.774524)
			(xy 432.298095 -215.774857) (xy 432.30564 -215.782398) (xy 432.305968 -215.787732) (xy 432.305968 -216.28227)
			(xy 438.350152 -216.28227) (xy 438.350152 -215.787732) (xy 438.350712 -215.782483) (xy 438.358113 -215.77504)
			(xy 438.36336 -215.774524) (xy 438.363868 -215.774524) (xy 438.879742 -215.774524) (xy 438.887551 -215.774198)
			(xy 438.902423 -215.769422) (xy 438.908952 -215.765126) (xy 438.930041 -215.750777) (xy 438.975702 -215.728046)
			(xy 439.024308 -215.712587) (xy 439.074711 -215.704764) (xy 439.125717 -215.704764) (xy 439.17612 -215.712587)
			(xy 439.224726 -215.728046) (xy 439.270387 -215.750777) (xy 439.291476 -215.765126) (xy 439.298018 -215.7694)
			(xy 439.31288 -215.774195) (xy 439.320686 -215.774524) (xy 439.836814 -215.774524) (xy 439.842116 -215.775012)
			(xy 439.849685 -215.78244) (xy 439.850276 -215.787732) (xy 439.850276 -216.28227) (xy 439.850258 -216.282524)
			(xy 445.89446 -216.282524) (xy 445.89446 -216.282016) (xy 445.89446 -215.787732) (xy 445.895013 -215.782481)
			(xy 445.902419 -215.775038) (xy 445.907668 -215.774524) (xy 446.423796 -215.774524) (xy 446.431607 -215.774221)
			(xy 446.446479 -215.769429) (xy 446.453006 -215.765126) (xy 446.474095 -215.750777) (xy 446.519756 -215.728046)
			(xy 446.568362 -215.712587) (xy 446.618765 -215.704764) (xy 446.669771 -215.704764) (xy 446.720174 -215.712587)
			(xy 446.76878 -215.728046) (xy 446.814441 -215.750777) (xy 446.83553 -215.765126) (xy 446.84206 -215.76942)
			(xy 446.856931 -215.774203) (xy 446.86474 -215.774524) (xy 447.380868 -215.774524) (xy 447.386204 -215.774852)
			(xy 447.393748 -215.782396) (xy 447.394076 -215.787732) (xy 447.394076 -216.28227) (xy 447.394051 -216.282524)
			(xy 453.43826 -216.282524) (xy 453.43826 -216.282016) (xy 453.43826 -215.787732) (xy 453.438813 -215.782481)
			(xy 453.446219 -215.775038) (xy 453.451468 -215.774524) (xy 453.967596 -215.774524) (xy 453.975407 -215.774221)
			(xy 453.990279 -215.769429) (xy 453.996806 -215.765126) (xy 454.017895 -215.750777) (xy 454.063556 -215.728046)
			(xy 454.112162 -215.712587) (xy 454.162565 -215.704764) (xy 454.213571 -215.704764) (xy 454.263974 -215.712587)
			(xy 454.31258 -215.728046) (xy 454.358241 -215.750777) (xy 454.37933 -215.765126) (xy 454.38586 -215.76942)
			(xy 454.400731 -215.774203) (xy 454.40854 -215.774524) (xy 454.924668 -215.774524) (xy 454.930004 -215.774852)
			(xy 454.937548 -215.782396) (xy 454.937876 -215.787732) (xy 454.937876 -216.28227) (xy 454.937359 -216.287567)
			(xy 454.929953 -216.295139) (xy 454.924668 -216.295732) (xy 454.408794 -216.295732) (xy 454.400983 -216.296038)
			(xy 454.386111 -216.300829) (xy 454.379584 -216.30513) (xy 454.358463 -216.31948) (xy 454.312739 -216.342207)
			(xy 454.264066 -216.357637) (xy 454.213599 -216.365403) (xy 454.188068 -216.365836) (xy 454.162537 -216.365421)
			(xy 454.112072 -216.357639) (xy 454.063399 -216.342204) (xy 454.017673 -216.319481) (xy 453.996552 -216.30513)
			(xy 453.990029 -216.300825) (xy 453.975152 -216.29605) (xy 453.967342 -216.295732) (xy 453.451468 -216.295732)
			(xy 453.446207 -216.295229) (xy 453.438768 -216.287785) (xy 453.43826 -216.282524) (xy 447.394051 -216.282524)
			(xy 447.393559 -216.287567) (xy 447.386153 -216.295139) (xy 447.380868 -216.295732) (xy 446.864994 -216.295732)
			(xy 446.857183 -216.296038) (xy 446.842311 -216.300829) (xy 446.835784 -216.30513) (xy 446.814663 -216.31948)
			(xy 446.768939 -216.342207) (xy 446.720266 -216.357637) (xy 446.669799 -216.365403) (xy 446.644268 -216.365836)
			(xy 446.618737 -216.365421) (xy 446.568272 -216.357639) (xy 446.519599 -216.342204) (xy 446.473873 -216.319481)
			(xy 446.452752 -216.30513) (xy 446.446229 -216.300825) (xy 446.431352 -216.29605) (xy 446.423542 -216.295732)
			(xy 445.907668 -216.295732) (xy 445.902407 -216.295229) (xy 445.894968 -216.287785) (xy 445.89446 -216.282524)
			(xy 439.850258 -216.282524) (xy 439.849902 -216.287697) (xy 439.84224 -216.295384) (xy 439.836814 -216.295732)
			(xy 439.32094 -216.295732) (xy 439.313131 -216.296058) (xy 439.298259 -216.300835) (xy 439.29173 -216.30513)
			(xy 439.270624 -216.319503) (xy 439.224895 -216.342225) (xy 439.176217 -216.357649) (xy 439.125746 -216.365407)
			(xy 439.100214 -216.365836) (xy 439.074684 -216.365398) (xy 439.02422 -216.357623) (xy 438.975547 -216.342195)
			(xy 438.92982 -216.319478) (xy 438.908698 -216.30513) (xy 438.902164 -216.300842) (xy 438.887296 -216.296057)
			(xy 438.879488 -216.295732) (xy 438.363614 -216.295732) (xy 438.358174 -216.295408) (xy 438.350485 -216.287711)
			(xy 438.350152 -216.28227) (xy 432.305968 -216.28227) (xy 432.305458 -216.287569) (xy 432.298047 -216.295141)
			(xy 432.29276 -216.295732) (xy 431.776886 -216.295732) (xy 431.769075 -216.296034) (xy 431.754203 -216.300827)
			(xy 431.747676 -216.30513) (xy 431.726557 -216.319483) (xy 431.680832 -216.34221) (xy 431.632158 -216.357639)
			(xy 431.581691 -216.365404) (xy 431.55616 -216.365836) (xy 431.530629 -216.365425) (xy 431.480164 -216.357642)
			(xy 431.431491 -216.342206) (xy 431.385765 -216.319481) (xy 431.364644 -216.30513) (xy 431.358122 -216.300822)
			(xy 431.343245 -216.296049) (xy 431.335434 -216.295732) (xy 430.81956 -216.295732) (xy 430.814298 -216.295234)
			(xy 430.806859 -216.287786) (xy 430.806352 -216.282524) (xy 424.762151 -216.282524) (xy 424.761801 -216.287699)
			(xy 424.754134 -216.295387) (xy 424.748706 -216.295732) (xy 424.232832 -216.295732) (xy 424.225023 -216.296054)
			(xy 424.210151 -216.300834) (xy 424.203622 -216.30513) (xy 424.18249 -216.319463) (xy 424.13677 -216.342194)
			(xy 424.0881 -216.357629) (xy 424.037636 -216.3654) (xy 424.012106 -216.365836) (xy 423.986576 -216.365402)
			(xy 423.936111 -216.357626) (xy 423.887439 -216.342196) (xy 423.841712 -216.319478) (xy 423.82059 -216.30513)
			(xy 423.814058 -216.300839) (xy 423.799188 -216.296056) (xy 423.79138 -216.295732) (xy 423.275506 -216.295732)
			(xy 423.270065 -216.295414) (xy 423.262377 -216.287712) (xy 423.262044 -216.28227) (xy 417.21786 -216.28227)
			(xy 417.217357 -216.287571) (xy 417.209941 -216.295143) (xy 417.204652 -216.295732) (xy 415.731452 -216.295732)
			(xy 415.726189 -216.295239) (xy 415.718751 -216.287788) (xy 415.718244 -216.282524) (xy 308.118239 -216.282524)
			(xy 308.1179 -216.287702) (xy 308.110226 -216.29539) (xy 308.104794 -216.295732) (xy 306.631594 -216.295732)
			(xy 306.626151 -216.295422) (xy 306.618464 -216.287714) (xy 306.618132 -216.28227) (xy 300.573948 -216.28227)
			(xy 300.573456 -216.287573) (xy 300.566033 -216.295147) (xy 300.56074 -216.295732) (xy 300.044866 -216.295732)
			(xy 300.037058 -216.296069) (xy 300.022186 -216.300838) (xy 300.015656 -216.30513) (xy 299.994542 -216.319492)
			(xy 299.948816 -216.342216) (xy 299.90014 -216.357643) (xy 299.849672 -216.365405) (xy 299.82414 -216.365836)
			(xy 299.79861 -216.365385) (xy 299.748147 -216.357614) (xy 299.699474 -216.342189) (xy 299.653746 -216.319476)
			(xy 299.632624 -216.30513) (xy 299.626085 -216.300852) (xy 299.611221 -216.296061) (xy 299.603414 -216.295732)
			(xy 299.08754 -216.295732) (xy 299.082219 -216.295349) (xy 299.074677 -216.287843) (xy 299.074332 -216.282524)
			(xy 293.030132 -216.282524) (xy 293.029799 -216.287704) (xy 293.02212 -216.295393) (xy 293.016686 -216.295732)
			(xy 292.500812 -216.295732) (xy 292.493002 -216.296045) (xy 292.47813 -216.300831) (xy 292.471602 -216.30513)
			(xy 292.450476 -216.319472) (xy 292.404754 -216.342201) (xy 292.356082 -216.357633) (xy 292.305617 -216.365402)
			(xy 292.280086 -216.365836) (xy 292.254555 -216.365412) (xy 292.204091 -216.357633) (xy 292.155418 -216.3422)
			(xy 292.109691 -216.31948) (xy 292.08857 -216.30513) (xy 292.082043 -216.300832) (xy 292.067169 -216.296053)
			(xy 292.05936 -216.295732) (xy 291.543486 -216.295732) (xy 291.538042 -216.295427) (xy 291.530355 -216.287715)
			(xy 291.530024 -216.28227) (xy 285.48584 -216.28227) (xy 285.485355 -216.287575) (xy 285.477927 -216.295149)
			(xy 285.472632 -216.295732) (xy 284.956758 -216.295732) (xy 284.94895 -216.296065) (xy 284.934078 -216.300837)
			(xy 284.927548 -216.30513) (xy 284.906437 -216.319495) (xy 284.860709 -216.342219) (xy 284.812033 -216.357645)
			(xy 284.761564 -216.365406) (xy 284.736032 -216.365836) (xy 284.710502 -216.365389) (xy 284.660038 -216.357617)
			(xy 284.611366 -216.342191) (xy 284.565638 -216.319477) (xy 284.544516 -216.30513) (xy 284.537978 -216.300849)
			(xy 284.523113 -216.296059) (xy 284.515306 -216.295732) (xy 283.999432 -216.295732) (xy 283.99411 -216.295354)
			(xy 283.986569 -216.287845) (xy 283.986224 -216.282524) (xy 277.942017 -216.282524) (xy 277.941555 -216.287575)
			(xy 277.934127 -216.295149) (xy 277.928832 -216.295732) (xy 277.412958 -216.295732) (xy 277.40515 -216.296065)
			(xy 277.390278 -216.300837) (xy 277.383748 -216.30513) (xy 277.362637 -216.319495) (xy 277.316909 -216.342219)
			(xy 277.268233 -216.357645) (xy 277.217764 -216.365406) (xy 277.192232 -216.365836) (xy 277.166702 -216.365389)
			(xy 277.116238 -216.357617) (xy 277.067566 -216.342191) (xy 277.021838 -216.319477) (xy 277.000716 -216.30513)
			(xy 276.994178 -216.300849) (xy 276.979313 -216.296059) (xy 276.971506 -216.295732) (xy 276.455632 -216.295732)
			(xy 276.45031 -216.295354) (xy 276.442769 -216.287845) (xy 276.442424 -216.282524) (xy 270.398224 -216.282524)
			(xy 270.397898 -216.287706) (xy 270.390214 -216.295395) (xy 270.384778 -216.295732) (xy 269.868904 -216.295732)
			(xy 269.861093 -216.296042) (xy 269.846222 -216.30083) (xy 269.839694 -216.30513) (xy 269.81857 -216.319475)
			(xy 269.772847 -216.342204) (xy 269.724175 -216.357635) (xy 269.673709 -216.365402) (xy 269.648178 -216.365836)
			(xy 269.622647 -216.365416) (xy 269.572182 -216.357636) (xy 269.52351 -216.342202) (xy 269.477783 -216.31948)
			(xy 269.456662 -216.30513) (xy 269.450136 -216.300829) (xy 269.435262 -216.296051) (xy 269.427452 -216.295732)
			(xy 268.911578 -216.295732) (xy 268.906133 -216.295432) (xy 268.898446 -216.287716) (xy 268.898116 -216.28227)
			(xy 206.997808 -216.28227) (xy 206.997808 -216.282524) (xy 206.997321 -216.28779) (xy 206.989866 -216.295231)
			(xy 206.9846 -216.295732) (xy 206.468726 -216.295732) (xy 206.46085 -216.295998) (xy 206.445846 -216.300797)
			(xy 206.439262 -216.30513) (xy 206.418184 -216.319521) (xy 206.37254 -216.34235) (xy 206.323934 -216.357908)
			(xy 206.273517 -216.365827) (xy 206.248 -216.366344) (xy 206.22248 -216.365863) (xy 206.172053 -216.357965)
			(xy 206.123441 -216.342402) (xy 206.077803 -216.319546) (xy 206.056738 -216.30513) (xy 206.050138 -216.30083)
			(xy 206.035145 -216.296034) (xy 206.027274 -216.295732) (xy 205.5114 -216.295732) (xy 205.506143 -216.295208)
			(xy 205.498702 -216.28778) (xy 205.498192 -216.282524) (xy 199.454008 -216.282524) (xy 199.453521 -216.28779)
			(xy 199.446066 -216.295231) (xy 199.4408 -216.295732) (xy 198.924926 -216.295732) (xy 198.91705 -216.295998)
			(xy 198.902046 -216.300797) (xy 198.895462 -216.30513) (xy 198.874384 -216.319521) (xy 198.82874 -216.34235)
			(xy 198.780134 -216.357908) (xy 198.729717 -216.365827) (xy 198.7042 -216.366344) (xy 198.67868 -216.365863)
			(xy 198.628253 -216.357965) (xy 198.579641 -216.342402) (xy 198.534003 -216.319546) (xy 198.512938 -216.30513)
			(xy 198.506338 -216.30083) (xy 198.491345 -216.296034) (xy 198.483474 -216.295732) (xy 197.9676 -216.295732)
			(xy 197.962343 -216.295208) (xy 197.954902 -216.28778) (xy 197.954392 -216.282524) (xy 191.910208 -216.282524)
			(xy 191.909721 -216.28779) (xy 191.902266 -216.295231) (xy 191.897 -216.295732) (xy 191.896492 -216.295732)
			(xy 191.380872 -216.295732) (xy 191.372997 -216.296018) (xy 191.357993 -216.300803) (xy 191.351408 -216.30513)
			(xy 191.330345 -216.319544) (xy 191.284695 -216.342368) (xy 191.236085 -216.35792) (xy 191.185664 -216.365831)
			(xy 191.160146 -216.366344) (xy 191.134626 -216.36584) (xy 191.0842 -216.357949) (xy 191.035589 -216.342393)
			(xy 190.98995 -216.319543) (xy 190.968884 -216.30513) (xy 190.962296 -216.300809) (xy 190.947293 -216.296026)
			(xy 190.93942 -216.295732) (xy 190.423546 -216.295732) (xy 190.418241 -216.295243) (xy 190.410666 -216.287818)
			(xy 190.410084 -216.282524) (xy 184.3659 -216.282524) (xy 184.36542 -216.287792) (xy 184.357961 -216.295233)
			(xy 184.352692 -216.295732) (xy 183.836818 -216.295732) (xy 183.828945 -216.296038) (xy 183.813941 -216.30081)
			(xy 183.807354 -216.30513) (xy 183.786278 -216.319524) (xy 183.740633 -216.342353) (xy 183.692026 -216.35791)
			(xy 183.641609 -216.365828) (xy 183.616092 -216.366344) (xy 183.590573 -216.365817) (xy 183.540148 -216.357933)
			(xy 183.491537 -216.342383) (xy 183.445897 -216.31954) (xy 183.42483 -216.30513) (xy 183.418232 -216.300827)
			(xy 183.403237 -216.296032) (xy 183.395366 -216.295732) (xy 182.879492 -216.295732) (xy 182.874234 -216.295213)
			(xy 182.866793 -216.287781) (xy 182.866284 -216.282524) (xy 176.8221 -216.282524) (xy 176.82162 -216.287792)
			(xy 176.814161 -216.295233) (xy 176.808892 -216.295732) (xy 176.808384 -216.295732) (xy 176.292764 -216.295732)
			(xy 176.284889 -216.296015) (xy 176.269885 -216.300802) (xy 176.2633 -216.30513) (xy 176.242211 -216.319504)
			(xy 176.196571 -216.342337) (xy 176.147968 -216.3579) (xy 176.097554 -216.365824) (xy 176.072038 -216.366344)
			(xy 176.046518 -216.365844) (xy 175.996092 -216.357951) (xy 175.947481 -216.342394) (xy 175.901842 -216.319543)
			(xy 175.880776 -216.30513) (xy 175.87419 -216.300806) (xy 175.859186 -216.296024) (xy 175.851312 -216.295732)
			(xy 175.335438 -216.295732) (xy 175.330132 -216.295248) (xy 175.322557 -216.28782) (xy 175.321976 -216.282524)
			(xy 169.277792 -216.282524) (xy 169.277319 -216.287793) (xy 169.269855 -216.295235) (xy 169.264584 -216.295732)
			(xy 167.791384 -216.295732) (xy 167.786125 -216.295219) (xy 167.778685 -216.287783) (xy 167.778176 -216.282524)
			(xy 60.178188 -216.282524) (xy 60.177719 -216.287794) (xy 60.170252 -216.295237) (xy 60.16498 -216.295732)
			(xy 60.164472 -216.295732) (xy 58.691526 -216.295732) (xy 58.686218 -216.295256) (xy 58.678644 -216.287822)
			(xy 58.678064 -216.282524) (xy 52.63388 -216.282524) (xy 52.633586 -216.287866) (xy 52.626016 -216.295407)
			(xy 52.620672 -216.295732) (xy 52.104798 -216.295732) (xy 52.096924 -216.29603) (xy 52.081921 -216.300807)
			(xy 52.075334 -216.30513) (xy 52.054264 -216.319533) (xy 52.008617 -216.342359) (xy 51.960008 -216.357914)
			(xy 51.909589 -216.365829) (xy 51.884072 -216.366344) (xy 51.858553 -216.365827) (xy 51.808128 -216.35794)
			(xy 51.759516 -216.342387) (xy 51.713876 -216.319541) (xy 51.69281 -216.30513) (xy 51.686216 -216.300819)
			(xy 51.671218 -216.296029) (xy 51.663346 -216.295732) (xy 51.147472 -216.295732) (xy 51.142212 -216.295226)
			(xy 51.134772 -216.287785) (xy 51.134264 -216.282524) (xy 45.09008 -216.282524) (xy 45.089786 -216.287866)
			(xy 45.082216 -216.295407) (xy 45.076872 -216.295732) (xy 45.076364 -216.295732) (xy 44.560744 -216.295732)
			(xy 44.552868 -216.296006) (xy 44.537864 -216.300799) (xy 44.53128 -216.30513) (xy 44.510197 -216.319513)
			(xy 44.464554 -216.342344) (xy 44.41595 -216.357904) (xy 44.365534 -216.365826) (xy 44.340018 -216.366344)
			(xy 44.314498 -216.365854) (xy 44.264071 -216.357958) (xy 44.21546 -216.342398) (xy 44.169821 -216.319544)
			(xy 44.148756 -216.30513) (xy 44.142174 -216.300798) (xy 44.127167 -216.296021) (xy 44.119292 -216.295732)
			(xy 43.603418 -216.295732) (xy 43.598109 -216.295262) (xy 43.590536 -216.287823) (xy 43.589956 -216.282524)
			(xy 37.545772 -216.282524) (xy 37.545486 -216.287868) (xy 37.53791 -216.29541) (xy 37.532564 -216.295732)
			(xy 37.01669 -216.295732) (xy 37.008816 -216.296026) (xy 36.993812 -216.300806) (xy 36.987226 -216.30513)
			(xy 36.966158 -216.319536) (xy 36.92051 -216.342362) (xy 36.871901 -216.357916) (xy 36.821482 -216.36583)
			(xy 36.795964 -216.366344) (xy 36.770445 -216.365831) (xy 36.720019 -216.357942) (xy 36.671408 -216.342389)
			(xy 36.625768 -216.319541) (xy 36.604702 -216.30513) (xy 36.59811 -216.300816) (xy 36.58311 -216.296028)
			(xy 36.575238 -216.295732) (xy 36.059364 -216.295732) (xy 36.054103 -216.295231) (xy 36.046664 -216.287786)
			(xy 36.046156 -216.282524) (xy 30.001972 -216.282524) (xy 30.001686 -216.287868) (xy 29.99411 -216.29541)
			(xy 29.988764 -216.295732) (xy 29.47289 -216.295732) (xy 29.465016 -216.296026) (xy 29.450012 -216.300806)
			(xy 29.443426 -216.30513) (xy 29.422358 -216.319536) (xy 29.37671 -216.342362) (xy 29.328101 -216.357916)
			(xy 29.277682 -216.36583) (xy 29.252164 -216.366344) (xy 29.226645 -216.365831) (xy 29.176219 -216.357942)
			(xy 29.127608 -216.342389) (xy 29.081968 -216.319541) (xy 29.060902 -216.30513) (xy 29.05431 -216.300816)
			(xy 29.03931 -216.296028) (xy 29.031438 -216.295732) (xy 28.515564 -216.295732) (xy 28.510303 -216.295231)
			(xy 28.502864 -216.287786) (xy 28.502356 -216.282524) (xy 22.458172 -216.282524) (xy 22.457886 -216.287868)
			(xy 22.45031 -216.29541) (xy 22.444964 -216.295732) (xy 22.444456 -216.295732) (xy 21.928836 -216.295732)
			(xy 21.92096 -216.296003) (xy 21.905956 -216.300798) (xy 21.899372 -216.30513) (xy 21.878291 -216.319517)
			(xy 21.832648 -216.342347) (xy 21.784043 -216.357906) (xy 21.733626 -216.365826) (xy 21.70811 -216.366344)
			(xy 21.68259 -216.365858) (xy 21.632163 -216.357961) (xy 21.583552 -216.3424) (xy 21.537913 -216.319545)
			(xy 21.516848 -216.30513) (xy 21.510268 -216.300795) (xy 21.495259 -216.29602) (xy 21.487384 -216.295732)
			(xy 20.97151 -216.295732) (xy 20.966201 -216.295267) (xy 20.958627 -216.287824) (xy 20.958048 -216.282524)
			(xy 2.509012 -216.282524) (xy 2.509012 -217.132408) (xy 16.85798 -217.132408) (xy 16.85798 -216.63787)
			(xy 16.858263 -216.632421) (xy 16.865991 -216.624734) (xy 16.871442 -216.624408) (xy 17.38757 -216.624408)
			(xy 17.395379 -216.62408) (xy 17.41025 -216.619304) (xy 17.41678 -216.61501) (xy 17.437869 -216.600661)
			(xy 17.48353 -216.57793) (xy 17.532136 -216.562471) (xy 17.582539 -216.554648) (xy 17.633545 -216.554648)
			(xy 17.683948 -216.562471) (xy 17.732554 -216.57793) (xy 17.778215 -216.600661) (xy 17.799304 -216.61501)
			(xy 17.805835 -216.619302) (xy 17.820705 -216.624084) (xy 17.828514 -216.624408) (xy 18.344642 -216.624408)
			(xy 18.350004 -216.624919) (xy 18.357585 -216.632508) (xy 18.358104 -216.63787) (xy 18.358104 -217.132408)
			(xy 24.402288 -217.132408) (xy 24.402288 -216.63787) (xy 24.402709 -216.632551) (xy 24.410184 -216.624979)
			(xy 24.415496 -216.624408) (xy 24.931624 -216.624408) (xy 24.939435 -216.624103) (xy 24.954306 -216.619311)
			(xy 24.960834 -216.61501) (xy 24.981923 -216.600661) (xy 25.027584 -216.57793) (xy 25.07619 -216.562471)
			(xy 25.126593 -216.554648) (xy 25.177599 -216.554648) (xy 25.228002 -216.562471) (xy 25.276608 -216.57793)
			(xy 25.322269 -216.600661) (xy 25.343358 -216.61501) (xy 25.349877 -216.619323) (xy 25.364757 -216.624092)
			(xy 25.372568 -216.624408) (xy 25.888696 -216.624408) (xy 25.894032 -216.624731) (xy 25.901574 -216.63228)
			(xy 25.901904 -216.637616) (xy 25.901904 -216.638124) (xy 25.901904 -217.132408) (xy 31.946088 -217.132408)
			(xy 31.946088 -216.63787) (xy 31.946509 -216.632551) (xy 31.953984 -216.624979) (xy 31.959296 -216.624408)
			(xy 32.475424 -216.624408) (xy 32.483235 -216.624103) (xy 32.498106 -216.619311) (xy 32.504634 -216.61501)
			(xy 32.525723 -216.600661) (xy 32.571384 -216.57793) (xy 32.61999 -216.562471) (xy 32.670393 -216.554648)
			(xy 32.721399 -216.554648) (xy 32.771802 -216.562471) (xy 32.820408 -216.57793) (xy 32.866069 -216.600661)
			(xy 32.887158 -216.61501) (xy 32.893677 -216.619323) (xy 32.908557 -216.624092) (xy 32.916368 -216.624408)
			(xy 33.432496 -216.624408) (xy 33.437832 -216.624731) (xy 33.445374 -216.63228) (xy 33.445704 -216.637616)
			(xy 33.445704 -216.638124) (xy 33.445704 -217.132408) (xy 39.489888 -217.132408) (xy 39.489888 -216.63787)
			(xy 39.490425 -216.632514) (xy 39.497995 -216.624933) (xy 39.50335 -216.624408) (xy 40.019478 -216.624408)
			(xy 40.027287 -216.624084) (xy 40.042158 -216.619305) (xy 40.048688 -216.61501) (xy 40.069777 -216.600661)
			(xy 40.115438 -216.57793) (xy 40.164044 -216.562471) (xy 40.214447 -216.554648) (xy 40.265453 -216.554648)
			(xy 40.315856 -216.562471) (xy 40.364462 -216.57793) (xy 40.410123 -216.600661) (xy 40.431212 -216.61501)
			(xy 40.437741 -216.619306) (xy 40.452613 -216.624086) (xy 40.460422 -216.624408) (xy 40.97655 -216.624408)
			(xy 40.981913 -216.624914) (xy 40.989494 -216.632507) (xy 40.990012 -216.63787) (xy 40.990012 -217.132408)
			(xy 47.034196 -217.132408) (xy 47.034196 -216.63787) (xy 47.034698 -216.632572) (xy 47.042117 -216.625005)
			(xy 47.047404 -216.624408) (xy 47.563532 -216.624408) (xy 47.571339 -216.624064) (xy 47.586211 -216.619299)
			(xy 47.592742 -216.61501) (xy 47.613831 -216.600661) (xy 47.659492 -216.57793) (xy 47.708098 -216.562471)
			(xy 47.758501 -216.554648) (xy 47.809507 -216.554648) (xy 47.85991 -216.562471) (xy 47.908516 -216.57793)
			(xy 47.954177 -216.600661) (xy 47.975266 -216.61501) (xy 47.981805 -216.619288) (xy 47.996669 -216.624079)
			(xy 48.004476 -216.624408) (xy 48.520604 -216.624408) (xy 48.525941 -216.624726) (xy 48.533482 -216.632279)
			(xy 48.533812 -216.637616) (xy 48.533812 -216.638124) (xy 48.533812 -217.132408) (xy 54.577996 -217.132408)
			(xy 54.577996 -216.63787) (xy 54.578526 -216.632513) (xy 54.586101 -216.624931) (xy 54.591458 -216.624408)
			(xy 56.064658 -216.624408) (xy 56.07008 -216.624805) (xy 56.077767 -216.63245) (xy 56.07812 -216.63787)
			(xy 56.07812 -217.132408) (xy 163.678108 -217.132408) (xy 163.678108 -216.63787) (xy 163.678599 -216.63257)
			(xy 163.686026 -216.625002) (xy 163.691316 -216.624408) (xy 165.164516 -216.624408) (xy 165.169785 -216.624885)
			(xy 165.177227 -216.632346) (xy 165.177724 -216.637616) (xy 165.177724 -216.638124) (xy 165.177724 -217.132408)
			(xy 171.221908 -217.132408) (xy 171.221908 -216.63787) (xy 171.222427 -216.63251) (xy 171.23001 -216.624927)
			(xy 171.23537 -216.624408) (xy 171.751498 -216.624408) (xy 171.759308 -216.624092) (xy 171.774179 -216.619307)
			(xy 171.780708 -216.61501) (xy 171.801797 -216.600661) (xy 171.847458 -216.57793) (xy 171.896064 -216.562471)
			(xy 171.946467 -216.554648) (xy 171.997473 -216.554648) (xy 172.047876 -216.562471) (xy 172.096482 -216.57793)
			(xy 172.142143 -216.600661) (xy 172.163232 -216.61501) (xy 172.169757 -216.619313) (xy 172.184632 -216.624089)
			(xy 172.192442 -216.624408) (xy 172.70857 -216.624408) (xy 172.713923 -216.624967) (xy 172.721509 -216.632519)
			(xy 172.722032 -216.63787) (xy 172.722032 -217.132408) (xy 178.766216 -217.132408) (xy 178.766216 -216.63787)
			(xy 178.7667 -216.632568) (xy 178.774132 -216.625) (xy 178.779424 -216.624408) (xy 179.295552 -216.624408)
			(xy 179.30336 -216.624073) (xy 179.318232 -216.619301) (xy 179.324762 -216.61501) (xy 179.345851 -216.600661)
			(xy 179.391512 -216.57793) (xy 179.440118 -216.562471) (xy 179.490521 -216.554648) (xy 179.541527 -216.554648)
			(xy 179.59193 -216.562471) (xy 179.640536 -216.57793) (xy 179.686197 -216.600661) (xy 179.707286 -216.61501)
			(xy 179.713821 -216.619296) (xy 179.728688 -216.624082) (xy 179.736496 -216.624408) (xy 180.252624 -216.624408)
			(xy 180.257893 -216.624881) (xy 180.265335 -216.632345) (xy 180.265832 -216.637616) (xy 180.265832 -216.638124)
			(xy 180.265832 -217.132408) (xy 186.310016 -217.132408) (xy 186.310016 -216.63787) (xy 186.310528 -216.632508)
			(xy 186.318115 -216.624925) (xy 186.323478 -216.624408) (xy 186.839606 -216.624408) (xy 186.847416 -216.624096)
			(xy 186.862287 -216.619308) (xy 186.868816 -216.61501) (xy 186.889905 -216.600661) (xy 186.935566 -216.57793)
			(xy 186.984172 -216.562471) (xy 187.034575 -216.554648) (xy 187.085581 -216.554648) (xy 187.135984 -216.562471)
			(xy 187.18459 -216.57793) (xy 187.230251 -216.600661) (xy 187.25134 -216.61501) (xy 187.257863 -216.619316)
			(xy 187.27274 -216.62409) (xy 187.28055 -216.624408) (xy 187.796678 -216.624408) (xy 187.802032 -216.624962)
			(xy 187.809617 -216.632518) (xy 187.81014 -216.63787) (xy 187.81014 -217.132408) (xy 193.854324 -217.132408)
			(xy 193.854324 -216.63787) (xy 193.854801 -216.632566) (xy 193.862237 -216.624997) (xy 193.867532 -216.624408)
			(xy 194.38366 -216.624408) (xy 194.391468 -216.624076) (xy 194.40634 -216.619302) (xy 194.41287 -216.61501)
			(xy 194.433959 -216.600661) (xy 194.47962 -216.57793) (xy 194.528226 -216.562471) (xy 194.578629 -216.554648)
			(xy 194.629635 -216.554648) (xy 194.680038 -216.562471) (xy 194.728644 -216.57793) (xy 194.774305 -216.600661)
			(xy 194.795394 -216.61501) (xy 194.801927 -216.619299) (xy 194.816796 -216.624083) (xy 194.824604 -216.624408)
			(xy 195.340732 -216.624408) (xy 195.346002 -216.624875) (xy 195.353444 -216.632344) (xy 195.35394 -216.637616)
			(xy 195.35394 -216.638124) (xy 195.35394 -217.132408) (xy 201.398124 -217.132408) (xy 201.398124 -216.63787)
			(xy 201.398601 -216.632566) (xy 201.406037 -216.624997) (xy 201.411332 -216.624408) (xy 201.92746 -216.624408)
			(xy 201.935268 -216.624076) (xy 201.95014 -216.619302) (xy 201.95667 -216.61501) (xy 201.977759 -216.600661)
			(xy 202.02342 -216.57793) (xy 202.072026 -216.562471) (xy 202.122429 -216.554648) (xy 202.173435 -216.554648)
			(xy 202.223838 -216.562471) (xy 202.272444 -216.57793) (xy 202.318105 -216.600661) (xy 202.339194 -216.61501)
			(xy 202.345727 -216.619299) (xy 202.360596 -216.624083) (xy 202.368404 -216.624408) (xy 202.884532 -216.624408)
			(xy 202.889802 -216.624875) (xy 202.897244 -216.632344) (xy 202.89774 -216.637616) (xy 202.89774 -216.638124)
			(xy 202.89774 -217.132154) (xy 264.798048 -217.132154) (xy 264.798048 -216.637616) (xy 264.798601 -216.632366)
			(xy 264.806008 -216.624925) (xy 264.811256 -216.624408) (xy 264.811764 -216.624408) (xy 265.327638 -216.624408)
			(xy 265.335446 -216.624067) (xy 265.350317 -216.6193) (xy 265.356848 -216.61501) (xy 265.377937 -216.600661)
			(xy 265.423598 -216.57793) (xy 265.472204 -216.562471) (xy 265.522607 -216.554648) (xy 265.573613 -216.554648)
			(xy 265.624016 -216.562471) (xy 265.672622 -216.57793) (xy 265.718283 -216.600661) (xy 265.739372 -216.61501)
			(xy 265.74591 -216.61929) (xy 265.760775 -216.62408) (xy 265.768582 -216.624408) (xy 266.28471 -216.624408)
			(xy 266.290008 -216.624913) (xy 266.297577 -216.632329) (xy 266.298172 -216.637616) (xy 266.298172 -217.132154)
			(xy 266.298154 -217.132408) (xy 272.342356 -217.132408) (xy 272.342356 -217.1319) (xy 272.342356 -216.637616)
			(xy 272.342902 -216.632364) (xy 272.350314 -216.624922) (xy 272.355564 -216.624408) (xy 272.871692 -216.624408)
			(xy 272.879502 -216.62409) (xy 272.894373 -216.619307) (xy 272.900902 -216.61501) (xy 272.921991 -216.600661)
			(xy 272.967652 -216.57793) (xy 273.016258 -216.562471) (xy 273.066661 -216.554648) (xy 273.117667 -216.554648)
			(xy 273.16807 -216.562471) (xy 273.216676 -216.57793) (xy 273.262337 -216.600661) (xy 273.283426 -216.61501)
			(xy 273.289952 -216.619311) (xy 273.304826 -216.624088) (xy 273.312636 -216.624408) (xy 273.828764 -216.624408)
			(xy 273.834095 -216.624753) (xy 273.841639 -216.632285) (xy 273.841972 -216.637616) (xy 273.841972 -217.132154)
			(xy 273.841947 -217.132408) (xy 279.886156 -217.132408) (xy 279.886156 -217.1319) (xy 279.886156 -216.637616)
			(xy 279.886702 -216.632364) (xy 279.894114 -216.624922) (xy 279.899364 -216.624408) (xy 280.415492 -216.624408)
			(xy 280.423302 -216.62409) (xy 280.438173 -216.619307) (xy 280.444702 -216.61501) (xy 280.465791 -216.600661)
			(xy 280.511452 -216.57793) (xy 280.560058 -216.562471) (xy 280.610461 -216.554648) (xy 280.661467 -216.554648)
			(xy 280.71187 -216.562471) (xy 280.760476 -216.57793) (xy 280.806137 -216.600661) (xy 280.827226 -216.61501)
			(xy 280.833752 -216.619311) (xy 280.848626 -216.624088) (xy 280.856436 -216.624408) (xy 281.372564 -216.624408)
			(xy 281.377895 -216.624753) (xy 281.385439 -216.632285) (xy 281.385772 -216.637616) (xy 281.385772 -217.132154)
			(xy 287.429956 -217.132154) (xy 287.429956 -216.637616) (xy 287.430502 -216.632364) (xy 287.437914 -216.624922)
			(xy 287.443164 -216.624408) (xy 287.443672 -216.624408) (xy 287.959546 -216.624408) (xy 287.967354 -216.62407)
			(xy 287.982225 -216.619301) (xy 287.988756 -216.61501) (xy 288.009845 -216.600661) (xy 288.055506 -216.57793)
			(xy 288.104112 -216.562471) (xy 288.154515 -216.554648) (xy 288.205521 -216.554648) (xy 288.255924 -216.562471)
			(xy 288.30453 -216.57793) (xy 288.350191 -216.600661) (xy 288.37128 -216.61501) (xy 288.377816 -216.619293)
			(xy 288.392683 -216.624081) (xy 288.40049 -216.624408) (xy 288.916618 -216.624408) (xy 288.921917 -216.624907)
			(xy 288.929485 -216.632328) (xy 288.93008 -216.637616) (xy 288.93008 -217.132154) (xy 288.930062 -217.132408)
			(xy 294.974264 -217.132408) (xy 294.974264 -217.1319) (xy 294.974264 -216.637616) (xy 294.974802 -216.632362)
			(xy 294.98222 -216.62492) (xy 294.987472 -216.624408) (xy 295.5036 -216.624408) (xy 295.51141 -216.624093)
			(xy 295.526281 -216.619308) (xy 295.53281 -216.61501) (xy 295.553899 -216.600661) (xy 295.59956 -216.57793)
			(xy 295.648166 -216.562471) (xy 295.698569 -216.554648) (xy 295.749575 -216.554648) (xy 295.799978 -216.562471)
			(xy 295.848584 -216.57793) (xy 295.894245 -216.600661) (xy 295.915334 -216.61501) (xy 295.921858 -216.619314)
			(xy 295.936734 -216.624089) (xy 295.944544 -216.624408) (xy 296.460672 -216.624408) (xy 296.466004 -216.624747)
			(xy 296.473548 -216.632284) (xy 296.47388 -216.637616) (xy 296.47388 -217.132154) (xy 302.518064 -217.132154)
			(xy 302.518064 -216.637616) (xy 302.518602 -216.632362) (xy 302.52602 -216.62492) (xy 302.531272 -216.624408)
			(xy 304.004726 -216.624408) (xy 304.010026 -216.624902) (xy 304.017593 -216.632327) (xy 304.018188 -216.637616)
			(xy 304.018188 -217.132154) (xy 304.018169 -217.132408) (xy 411.618176 -217.132408) (xy 411.618176 -217.1319)
			(xy 411.618176 -216.637616) (xy 411.618704 -216.632359) (xy 411.626128 -216.624916) (xy 411.631384 -216.624408)
			(xy 413.104584 -216.624408) (xy 413.109918 -216.624739) (xy 413.117461 -216.632282) (xy 413.117792 -216.637616)
			(xy 413.117792 -217.132154) (xy 419.161976 -217.132154) (xy 419.161976 -216.637616) (xy 419.162504 -216.632359)
			(xy 419.169928 -216.624916) (xy 419.175184 -216.624408) (xy 419.175692 -216.624408) (xy 419.691566 -216.624408)
			(xy 419.699375 -216.624079) (xy 419.714246 -216.619303) (xy 419.720776 -216.61501) (xy 419.741865 -216.600661)
			(xy 419.787526 -216.57793) (xy 419.836132 -216.562471) (xy 419.886535 -216.554648) (xy 419.937541 -216.554648)
			(xy 419.987944 -216.562471) (xy 420.03655 -216.57793) (xy 420.082211 -216.600661) (xy 420.1033 -216.61501)
			(xy 420.109832 -216.619301) (xy 420.124702 -216.624084) (xy 420.13251 -216.624408) (xy 420.648638 -216.624408)
			(xy 420.653939 -216.624894) (xy 420.661506 -216.632325) (xy 420.6621 -216.637616) (xy 420.6621 -217.132154)
			(xy 420.662081 -217.132408) (xy 426.706284 -217.132408) (xy 426.706284 -217.1319) (xy 426.706284 -216.637616)
			(xy 426.706637 -216.632288) (xy 426.714164 -216.624746) (xy 426.719492 -216.624408) (xy 427.23562 -216.624408)
			(xy 427.243431 -216.624101) (xy 427.258302 -216.61931) (xy 427.26483 -216.61501) (xy 427.285919 -216.600661)
			(xy 427.33158 -216.57793) (xy 427.380186 -216.562471) (xy 427.430589 -216.554648) (xy 427.481595 -216.554648)
			(xy 427.531998 -216.562471) (xy 427.580604 -216.57793) (xy 427.626265 -216.600661) (xy 427.647354 -216.61501)
			(xy 427.653874 -216.619322) (xy 427.668753 -216.624092) (xy 427.676564 -216.624408) (xy 428.192692 -216.624408)
			(xy 428.198027 -216.624734) (xy 428.20557 -216.632281) (xy 428.2059 -216.637616) (xy 428.2059 -217.132154)
			(xy 434.250084 -217.132154) (xy 434.250084 -216.637616) (xy 434.250437 -216.632288) (xy 434.257964 -216.624746)
			(xy 434.263292 -216.624408) (xy 434.2638 -216.624408) (xy 434.779674 -216.624408) (xy 434.787483 -216.624082)
			(xy 434.802354 -216.619304) (xy 434.808884 -216.61501) (xy 434.829973 -216.600661) (xy 434.875634 -216.57793)
			(xy 434.92424 -216.562471) (xy 434.974643 -216.554648) (xy 435.025649 -216.554648) (xy 435.076052 -216.562471)
			(xy 435.124658 -216.57793) (xy 435.170319 -216.600661) (xy 435.191408 -216.61501) (xy 435.197938 -216.619304)
			(xy 435.212809 -216.624085) (xy 435.220618 -216.624408) (xy 435.736746 -216.624408) (xy 435.742036 -216.624956)
			(xy 435.749609 -216.632339) (xy 435.750208 -216.637616) (xy 435.750208 -217.132154) (xy 435.75018 -217.132408)
			(xy 441.794392 -217.132408) (xy 441.794392 -217.1319) (xy 441.794392 -216.637616) (xy 441.794738 -216.632286)
			(xy 441.80227 -216.624744) (xy 441.8076 -216.624408) (xy 442.323728 -216.624408) (xy 442.331539 -216.624105)
			(xy 442.34641 -216.619311) (xy 442.352938 -216.61501) (xy 442.374027 -216.600661) (xy 442.419688 -216.57793)
			(xy 442.468294 -216.562471) (xy 442.518697 -216.554648) (xy 442.569703 -216.554648) (xy 442.620106 -216.562471)
			(xy 442.668712 -216.57793) (xy 442.714373 -216.600661) (xy 442.735462 -216.61501) (xy 442.742002 -216.619286)
			(xy 442.756866 -216.624078) (xy 442.764672 -216.624408) (xy 443.2808 -216.624408) (xy 443.286136 -216.624728)
			(xy 443.293678 -216.632279) (xy 443.294008 -216.637616) (xy 443.294008 -217.132154) (xy 443.293981 -217.132408)
			(xy 449.338192 -217.132408) (xy 449.338192 -217.1319) (xy 449.338192 -216.637616) (xy 449.338538 -216.632286)
			(xy 449.34607 -216.624744) (xy 449.3514 -216.624408) (xy 449.867528 -216.624408) (xy 449.875339 -216.624105)
			(xy 449.89021 -216.619311) (xy 449.896738 -216.61501) (xy 449.917827 -216.600661) (xy 449.963488 -216.57793)
			(xy 450.012094 -216.562471) (xy 450.062497 -216.554648) (xy 450.113503 -216.554648) (xy 450.163906 -216.562471)
			(xy 450.212512 -216.57793) (xy 450.258173 -216.600661) (xy 450.279262 -216.61501) (xy 450.285802 -216.619286)
			(xy 450.300666 -216.624078) (xy 450.308472 -216.624408) (xy 450.8246 -216.624408) (xy 450.829936 -216.624728)
			(xy 450.837478 -216.632279) (xy 450.837808 -216.637616) (xy 450.837808 -217.132154) (xy 450.837252 -217.137442)
			(xy 450.829874 -217.145013) (xy 450.8246 -217.145616) (xy 450.308726 -217.145616) (xy 450.300917 -217.145938)
			(xy 450.286045 -217.150718) (xy 450.279516 -217.155014) (xy 450.258384 -217.169348) (xy 450.212665 -217.192079)
			(xy 450.163994 -217.207514) (xy 450.11353 -217.215285) (xy 450.088 -217.21572) (xy 450.062469 -217.215291)
			(xy 450.012005 -217.207514) (xy 449.963332 -217.192083) (xy 449.917605 -217.169363) (xy 449.896484 -217.155014)
			(xy 449.889955 -217.150719) (xy 449.875083 -217.145938) (xy 449.867274 -217.145616) (xy 449.3514 -217.145616)
			(xy 449.346139 -217.145106) (xy 449.338697 -217.137668) (xy 449.338192 -217.132408) (xy 443.293981 -217.132408)
			(xy 443.293452 -217.137442) (xy 443.286074 -217.145013) (xy 443.2808 -217.145616) (xy 442.764926 -217.145616)
			(xy 442.757117 -217.145938) (xy 442.742245 -217.150718) (xy 442.735716 -217.155014) (xy 442.714584 -217.169348)
			(xy 442.668865 -217.192079) (xy 442.620194 -217.207514) (xy 442.56973 -217.215285) (xy 442.5442 -217.21572)
			(xy 442.518669 -217.215291) (xy 442.468205 -217.207514) (xy 442.419532 -217.192083) (xy 442.373805 -217.169363)
			(xy 442.352684 -217.155014) (xy 442.346155 -217.150719) (xy 442.331283 -217.145938) (xy 442.323474 -217.145616)
			(xy 441.8076 -217.145616) (xy 441.802339 -217.145106) (xy 441.794897 -217.137668) (xy 441.794392 -217.132408)
			(xy 435.75018 -217.132408) (xy 435.749623 -217.137501) (xy 435.74209 -217.145087) (xy 435.736746 -217.145616)
			(xy 435.220872 -217.145616) (xy 435.213061 -217.145915) (xy 435.198189 -217.150711) (xy 435.191662 -217.155014)
			(xy 435.170546 -217.169371) (xy 435.12482 -217.192097) (xy 435.076145 -217.207525) (xy 435.025677 -217.215289)
			(xy 435.000146 -217.21572) (xy 434.974616 -217.215268) (xy 434.924153 -217.207498) (xy 434.87548 -217.192074)
			(xy 434.829752 -217.16936) (xy 434.80863 -217.155014) (xy 434.80209 -217.150737) (xy 434.787227 -217.145945)
			(xy 434.77942 -217.145616) (xy 434.263546 -217.145616) (xy 434.258106 -217.145285) (xy 434.250415 -217.137594)
			(xy 434.250084 -217.132154) (xy 428.2059 -217.132154) (xy 428.205351 -217.137444) (xy 428.197968 -217.145015)
			(xy 428.192692 -217.145616) (xy 427.676818 -217.145616) (xy 427.669008 -217.145934) (xy 427.654137 -217.150717)
			(xy 427.647608 -217.155014) (xy 427.626479 -217.169352) (xy 427.580758 -217.192082) (xy 427.532087 -217.207516)
			(xy 427.481622 -217.215285) (xy 427.456092 -217.21572) (xy 427.430561 -217.215295) (xy 427.380097 -217.207517)
			(xy 427.331424 -217.192085) (xy 427.285697 -217.169364) (xy 427.264576 -217.155014) (xy 427.258048 -217.150716)
			(xy 427.243175 -217.145937) (xy 427.235366 -217.145616) (xy 426.719492 -217.145616) (xy 426.71423 -217.145111)
			(xy 426.706789 -217.13767) (xy 426.706284 -217.132408) (xy 420.662081 -217.132408) (xy 420.661694 -217.137574)
			(xy 420.654055 -217.14526) (xy 420.648638 -217.145616) (xy 420.132764 -217.145616) (xy 420.124956 -217.145954)
			(xy 420.110085 -217.150723) (xy 420.103554 -217.155014) (xy 420.08244 -217.169375) (xy 420.036714 -217.1921)
			(xy 419.988038 -217.207527) (xy 419.93757 -217.215289) (xy 419.912038 -217.21572) (xy 419.886508 -217.215272)
			(xy 419.836044 -217.207501) (xy 419.787372 -217.192075) (xy 419.741644 -217.169361) (xy 419.720522 -217.155014)
			(xy 419.713984 -217.150734) (xy 419.699119 -217.145944) (xy 419.691312 -217.145616) (xy 419.175438 -217.145616)
			(xy 419.169997 -217.145291) (xy 419.162306 -217.137595) (xy 419.161976 -217.132154) (xy 413.117792 -217.132154)
			(xy 413.11725 -217.137445) (xy 413.109862 -217.145017) (xy 413.104584 -217.145616) (xy 411.631384 -217.145616)
			(xy 411.626121 -217.145117) (xy 411.61868 -217.137671) (xy 411.618176 -217.132408) (xy 304.018169 -217.132408)
			(xy 304.017793 -217.137577) (xy 304.010146 -217.145264) (xy 304.004726 -217.145616) (xy 302.531526 -217.145616)
			(xy 302.526083 -217.145299) (xy 302.518393 -217.137597) (xy 302.518064 -217.132154) (xy 296.47388 -217.132154)
			(xy 296.473349 -217.137448) (xy 296.465953 -217.145021) (xy 296.460672 -217.145616) (xy 295.944798 -217.145616)
			(xy 295.936988 -217.145926) (xy 295.922116 -217.150714) (xy 295.915588 -217.155014) (xy 295.894464 -217.16936)
			(xy 295.848742 -217.192089) (xy 295.800069 -217.20752) (xy 295.749603 -217.215287) (xy 295.724072 -217.21572)
			(xy 295.698541 -217.215306) (xy 295.648076 -217.207524) (xy 295.599403 -217.192089) (xy 295.553677 -217.169365)
			(xy 295.532556 -217.155014) (xy 295.526033 -217.150708) (xy 295.511156 -217.145934) (xy 295.503346 -217.145616)
			(xy 294.987472 -217.145616) (xy 294.982208 -217.145125) (xy 294.974767 -217.137673) (xy 294.974264 -217.132408)
			(xy 288.930062 -217.132408) (xy 288.929692 -217.137578) (xy 288.922041 -217.145266) (xy 288.916618 -217.145616)
			(xy 288.400744 -217.145616) (xy 288.392935 -217.145945) (xy 288.378064 -217.15072) (xy 288.371534 -217.155014)
			(xy 288.350425 -217.169384) (xy 288.304697 -217.192107) (xy 288.25602 -217.207531) (xy 288.20555 -217.215291)
			(xy 288.180018 -217.21572) (xy 288.154488 -217.215282) (xy 288.104024 -217.207508) (xy 288.055351 -217.19208)
			(xy 288.009624 -217.169362) (xy 287.988502 -217.155014) (xy 287.981969 -217.150726) (xy 287.9671 -217.145941)
			(xy 287.959292 -217.145616) (xy 287.443418 -217.145616) (xy 287.437974 -217.145304) (xy 287.430284 -217.137598)
			(xy 287.429956 -217.132154) (xy 281.385772 -217.132154) (xy 281.385248 -217.13745) (xy 281.377848 -217.145023)
			(xy 281.372564 -217.145616) (xy 280.85669 -217.145616) (xy 280.848879 -217.145923) (xy 280.834008 -217.150713)
			(xy 280.82748 -217.155014) (xy 280.806359 -217.169364) (xy 280.760635 -217.192091) (xy 280.711962 -217.207522)
			(xy 280.661495 -217.215288) (xy 280.635964 -217.21572) (xy 280.610433 -217.21531) (xy 280.559967 -217.207527)
			(xy 280.511295 -217.19209) (xy 280.465569 -217.169366) (xy 280.444448 -217.155014) (xy 280.437927 -217.150705)
			(xy 280.423049 -217.145933) (xy 280.415238 -217.145616) (xy 279.899364 -217.145616) (xy 279.894099 -217.14513)
			(xy 279.886659 -217.137674) (xy 279.886156 -217.132408) (xy 273.841947 -217.132408) (xy 273.841448 -217.13745)
			(xy 273.834048 -217.145023) (xy 273.828764 -217.145616) (xy 273.31289 -217.145616) (xy 273.305079 -217.145923)
			(xy 273.290208 -217.150713) (xy 273.28368 -217.155014) (xy 273.262559 -217.169364) (xy 273.216835 -217.192091)
			(xy 273.168162 -217.207522) (xy 273.117695 -217.215288) (xy 273.092164 -217.21572) (xy 273.066633 -217.21531)
			(xy 273.016167 -217.207527) (xy 272.967495 -217.19209) (xy 272.921769 -217.169366) (xy 272.900648 -217.155014)
			(xy 272.894127 -217.150705) (xy 272.879249 -217.145933) (xy 272.871438 -217.145616) (xy 272.355564 -217.145616)
			(xy 272.350299 -217.14513) (xy 272.342859 -217.137674) (xy 272.342356 -217.132408) (xy 266.298154 -217.132408)
			(xy 266.297791 -217.13758) (xy 266.290135 -217.145268) (xy 266.28471 -217.145616) (xy 265.768836 -217.145616)
			(xy 265.761027 -217.145942) (xy 265.746155 -217.150719) (xy 265.739626 -217.155014) (xy 265.718492 -217.169344)
			(xy 265.672773 -217.192076) (xy 265.624103 -217.207512) (xy 265.57364 -217.215284) (xy 265.54811 -217.21572)
			(xy 265.52258 -217.215286) (xy 265.472115 -217.207511) (xy 265.423443 -217.192081) (xy 265.377715 -217.169363)
			(xy 265.356594 -217.155014) (xy 265.350062 -217.150723) (xy 265.335192 -217.145939) (xy 265.327384 -217.145616)
			(xy 264.81151 -217.145616) (xy 264.806065 -217.14531) (xy 264.798376 -217.1376) (xy 264.798048 -217.132154)
			(xy 202.89774 -217.132154) (xy 202.89774 -217.132408) (xy 202.897214 -217.137664) (xy 202.889787 -217.145104)
			(xy 202.884532 -217.145616) (xy 202.368658 -217.145616) (xy 202.360783 -217.145899) (xy 202.345779 -217.150686)
			(xy 202.339194 -217.155014) (xy 202.318106 -217.169389) (xy 202.272465 -217.192222) (xy 202.223862 -217.207785)
			(xy 202.173448 -217.215709) (xy 202.147932 -217.216228) (xy 202.122412 -217.215734) (xy 202.071985 -217.20784)
			(xy 202.023374 -217.192281) (xy 201.977735 -217.169428) (xy 201.95667 -217.155014) (xy 201.950086 -217.150686)
			(xy 201.93508 -217.145907) (xy 201.927206 -217.145616) (xy 201.411332 -217.145616) (xy 201.406006 -217.145252)
			(xy 201.398464 -217.137733) (xy 201.398124 -217.132408) (xy 195.35394 -217.132408) (xy 195.353414 -217.137664)
			(xy 195.345987 -217.145104) (xy 195.340732 -217.145616) (xy 194.824858 -217.145616) (xy 194.816983 -217.145899)
			(xy 194.801979 -217.150686) (xy 194.795394 -217.155014) (xy 194.774306 -217.169389) (xy 194.728665 -217.192222)
			(xy 194.680062 -217.207785) (xy 194.629648 -217.215709) (xy 194.604132 -217.216228) (xy 194.578612 -217.215734)
			(xy 194.528185 -217.20784) (xy 194.479574 -217.192281) (xy 194.433935 -217.169428) (xy 194.41287 -217.155014)
			(xy 194.406286 -217.150686) (xy 194.39128 -217.145907) (xy 194.383406 -217.145616) (xy 193.867532 -217.145616)
			(xy 193.862206 -217.145252) (xy 193.854664 -217.137733) (xy 193.854324 -217.132408) (xy 187.81014 -217.132408)
			(xy 187.809614 -217.137664) (xy 187.802187 -217.145104) (xy 187.796932 -217.145616) (xy 187.796424 -217.145616)
			(xy 187.280804 -217.145616) (xy 187.272931 -217.145919) (xy 187.257927 -217.150693) (xy 187.25134 -217.155014)
			(xy 187.230267 -217.169412) (xy 187.184621 -217.19224) (xy 187.136013 -217.207796) (xy 187.085595 -217.215713)
			(xy 187.060078 -217.216228) (xy 187.034559 -217.215711) (xy 186.984133 -217.207824) (xy 186.935522 -217.192272)
			(xy 186.889882 -217.169425) (xy 186.868816 -217.155014) (xy 186.862222 -217.150704) (xy 186.847224 -217.145914)
			(xy 186.839352 -217.145616) (xy 186.323478 -217.145616) (xy 186.318161 -217.145186) (xy 186.310588 -217.137718)
			(xy 186.310016 -217.132408) (xy 180.265832 -217.132408) (xy 180.265313 -217.137666) (xy 180.257881 -217.145107)
			(xy 180.252624 -217.145616) (xy 179.73675 -217.145616) (xy 179.728875 -217.145895) (xy 179.713871 -217.150685)
			(xy 179.707286 -217.155014) (xy 179.6862 -217.169393) (xy 179.640559 -217.192225) (xy 179.591955 -217.207786)
			(xy 179.54154 -217.215709) (xy 179.516024 -217.216228) (xy 179.490504 -217.215738) (xy 179.440077 -217.207843)
			(xy 179.391466 -217.192283) (xy 179.345827 -217.169429) (xy 179.324762 -217.155014) (xy 179.31818 -217.150683)
			(xy 179.303173 -217.145906) (xy 179.295298 -217.145616) (xy 178.779424 -217.145616) (xy 178.774097 -217.145258)
			(xy 178.766555 -217.137734) (xy 178.766216 -217.132408) (xy 172.722032 -217.132408) (xy 172.721513 -217.137666)
			(xy 172.714081 -217.145107) (xy 172.708824 -217.145616) (xy 172.708316 -217.145616) (xy 172.192696 -217.145616)
			(xy 172.184823 -217.145915) (xy 172.169819 -217.150691) (xy 172.163232 -217.155014) (xy 172.142161 -217.169416)
			(xy 172.096514 -217.192243) (xy 172.047906 -217.207798) (xy 171.997487 -217.215713) (xy 171.97197 -217.216228)
			(xy 171.946451 -217.215715) (xy 171.896025 -217.207827) (xy 171.847414 -217.192273) (xy 171.801774 -217.169426)
			(xy 171.780708 -217.155014) (xy 171.774116 -217.1507) (xy 171.759116 -217.145912) (xy 171.751244 -217.145616)
			(xy 171.23537 -217.145616) (xy 171.230052 -217.145192) (xy 171.22248 -217.137719) (xy 171.221908 -217.132408)
			(xy 165.177724 -217.132408) (xy 165.177212 -217.137668) (xy 165.169776 -217.145109) (xy 165.164516 -217.145616)
			(xy 163.691316 -217.145616) (xy 163.685988 -217.145263) (xy 163.678446 -217.137736) (xy 163.678108 -217.132408)
			(xy 56.07812 -217.132408) (xy 56.077612 -217.137669) (xy 56.070173 -217.14511) (xy 56.064912 -217.145616)
			(xy 54.591458 -217.145616) (xy 54.586138 -217.1452) (xy 54.578567 -217.137721) (xy 54.577996 -217.132408)
			(xy 48.533812 -217.132408) (xy 48.533311 -217.137671) (xy 48.525867 -217.145113) (xy 48.520604 -217.145616)
			(xy 48.00473 -217.145616) (xy 47.996854 -217.145887) (xy 47.98185 -217.150683) (xy 47.975266 -217.155014)
			(xy 47.954186 -217.169401) (xy 47.908542 -217.192232) (xy 47.859937 -217.207791) (xy 47.809521 -217.215711)
			(xy 47.784004 -217.216228) (xy 47.758483 -217.215748) (xy 47.708056 -217.20785) (xy 47.659445 -217.192287)
			(xy 47.613807 -217.16943) (xy 47.592742 -217.155014) (xy 47.586164 -217.150675) (xy 47.571154 -217.145903)
			(xy 47.563278 -217.145616) (xy 47.047404 -217.145616) (xy 47.042144 -217.145103) (xy 47.034701 -217.137668)
			(xy 47.034196 -217.132408) (xy 40.990012 -217.132408) (xy 40.989511 -217.137671) (xy 40.982067 -217.145113)
			(xy 40.976804 -217.145616) (xy 40.976296 -217.145616) (xy 40.460676 -217.145616) (xy 40.452802 -217.145907)
			(xy 40.437798 -217.150689) (xy 40.431212 -217.155014) (xy 40.410147 -217.169424) (xy 40.364498 -217.192249)
			(xy 40.315888 -217.207802) (xy 40.265468 -217.215715) (xy 40.23995 -217.216228) (xy 40.21443 -217.215725)
			(xy 40.164004 -217.207834) (xy 40.115393 -217.192278) (xy 40.069754 -217.169427) (xy 40.048688 -217.155014)
			(xy 40.0421 -217.150693) (xy 40.027097 -217.145909) (xy 40.019224 -217.145616) (xy 39.50335 -217.145616)
			(xy 39.498042 -217.145138) (xy 39.490465 -217.137706) (xy 39.489888 -217.132408) (xy 33.445704 -217.132408)
			(xy 33.44521 -217.137673) (xy 33.437761 -217.145115) (xy 33.432496 -217.145616) (xy 32.916622 -217.145616)
			(xy 32.90875 -217.145927) (xy 32.893746 -217.150695) (xy 32.887158 -217.155014) (xy 32.86608 -217.169405)
			(xy 32.820436 -217.192234) (xy 32.77183 -217.207792) (xy 32.721413 -217.215711) (xy 32.695896 -217.216228)
			(xy 32.670375 -217.215752) (xy 32.619948 -217.207853) (xy 32.571337 -217.192289) (xy 32.525699 -217.16943)
			(xy 32.504634 -217.155014) (xy 32.498036 -217.150711) (xy 32.483041 -217.145916) (xy 32.47517 -217.145616)
			(xy 31.959296 -217.145616) (xy 31.954035 -217.145109) (xy 31.946593 -217.137669) (xy 31.946088 -217.132408)
			(xy 25.901904 -217.132408) (xy 25.90141 -217.137673) (xy 25.893961 -217.145115) (xy 25.888696 -217.145616)
			(xy 25.372822 -217.145616) (xy 25.36495 -217.145927) (xy 25.349946 -217.150695) (xy 25.343358 -217.155014)
			(xy 25.32228 -217.169405) (xy 25.276636 -217.192234) (xy 25.22803 -217.207792) (xy 25.177613 -217.215711)
			(xy 25.152096 -217.216228) (xy 25.126575 -217.215752) (xy 25.076148 -217.207853) (xy 25.027537 -217.192289)
			(xy 24.981899 -217.16943) (xy 24.960834 -217.155014) (xy 24.954236 -217.150711) (xy 24.939241 -217.145916)
			(xy 24.93137 -217.145616) (xy 24.415496 -217.145616) (xy 24.410235 -217.145109) (xy 24.402793 -217.137669)
			(xy 24.402288 -217.132408) (xy 18.358104 -217.132408) (xy 18.35761 -217.137673) (xy 18.350161 -217.145115)
			(xy 18.344896 -217.145616) (xy 18.344388 -217.145616) (xy 17.828768 -217.145616) (xy 17.820894 -217.145903)
			(xy 17.80589 -217.150688) (xy 17.799304 -217.155014) (xy 17.778213 -217.169385) (xy 17.732573 -217.192219)
			(xy 17.683972 -217.207783) (xy 17.633558 -217.215708) (xy 17.608042 -217.216228) (xy 17.582522 -217.215729)
			(xy 17.532096 -217.207837) (xy 17.483484 -217.192279) (xy 17.437846 -217.169427) (xy 17.41678 -217.155014)
			(xy 17.410194 -217.15069) (xy 17.39519 -217.145908) (xy 17.387316 -217.145616) (xy 16.871442 -217.145616)
			(xy 16.866133 -217.145144) (xy 16.858556 -217.137708) (xy 16.85798 -217.132408) (xy 2.509012 -217.132408)
			(xy 2.509012 -217.982546) (xy 20.958048 -217.982546) (xy 20.958048 -217.488008) (xy 20.958595 -217.482757)
			(xy 20.966007 -217.475316) (xy 20.971256 -217.4748) (xy 20.971764 -217.4748) (xy 21.487638 -217.4748)
			(xy 21.495446 -217.47446) (xy 21.510317 -217.469692) (xy 21.516848 -217.465402) (xy 21.537937 -217.451053)
			(xy 21.583598 -217.428322) (xy 21.632204 -217.412863) (xy 21.682607 -217.40504) (xy 21.733613 -217.40504)
			(xy 21.784016 -217.412863) (xy 21.832622 -217.428322) (xy 21.878283 -217.451053) (xy 21.899372 -217.465402)
			(xy 21.90591 -217.469682) (xy 21.920775 -217.474472) (xy 21.928582 -217.4748) (xy 22.44471 -217.4748)
			(xy 22.450006 -217.475312) (xy 22.457574 -217.482723) (xy 22.458172 -217.488008) (xy 22.458172 -217.982546)
			(xy 22.458149 -217.9828) (xy 28.502356 -217.9828) (xy 28.502356 -217.982292) (xy 28.502356 -217.488008)
			(xy 28.502896 -217.482755) (xy 28.510313 -217.475314) (xy 28.515564 -217.4748) (xy 29.031692 -217.4748)
			(xy 29.039502 -217.474483) (xy 29.054373 -217.469699) (xy 29.060902 -217.465402) (xy 29.081991 -217.451053)
			(xy 29.127652 -217.428322) (xy 29.176258 -217.412863) (xy 29.226661 -217.40504) (xy 29.277667 -217.40504)
			(xy 29.32807 -217.412863) (xy 29.376676 -217.428322) (xy 29.422337 -217.451053) (xy 29.443426 -217.465402)
			(xy 29.449952 -217.469702) (xy 29.464826 -217.47448) (xy 29.472636 -217.4748) (xy 29.988764 -217.4748)
			(xy 29.994093 -217.475152) (xy 30.001637 -217.482679) (xy 30.001972 -217.488008) (xy 30.001972 -217.982546)
			(xy 30.001947 -217.9828) (xy 36.046156 -217.9828) (xy 36.046156 -217.982292) (xy 36.046156 -217.488008)
			(xy 36.046696 -217.482755) (xy 36.054113 -217.475314) (xy 36.059364 -217.4748) (xy 36.575492 -217.4748)
			(xy 36.583302 -217.474483) (xy 36.598173 -217.469699) (xy 36.604702 -217.465402) (xy 36.625791 -217.451053)
			(xy 36.671452 -217.428322) (xy 36.720058 -217.412863) (xy 36.770461 -217.40504) (xy 36.821467 -217.40504)
			(xy 36.87187 -217.412863) (xy 36.920476 -217.428322) (xy 36.966137 -217.451053) (xy 36.987226 -217.465402)
			(xy 36.993752 -217.469702) (xy 37.008626 -217.47448) (xy 37.016436 -217.4748) (xy 37.532564 -217.4748)
			(xy 37.537893 -217.475152) (xy 37.545437 -217.482679) (xy 37.545772 -217.488008) (xy 37.545772 -217.982546)
			(xy 43.589956 -217.982546) (xy 43.589956 -217.488008) (xy 43.590496 -217.482755) (xy 43.597913 -217.475314)
			(xy 43.603164 -217.4748) (xy 43.603672 -217.4748) (xy 44.119546 -217.4748) (xy 44.127354 -217.474464)
			(xy 44.142226 -217.469693) (xy 44.148756 -217.465402) (xy 44.169845 -217.451053) (xy 44.215506 -217.428322)
			(xy 44.264112 -217.412863) (xy 44.314515 -217.40504) (xy 44.365521 -217.40504) (xy 44.415924 -217.412863)
			(xy 44.46453 -217.428322) (xy 44.510191 -217.451053) (xy 44.53128 -217.465402) (xy 44.537817 -217.469685)
			(xy 44.552683 -217.474473) (xy 44.56049 -217.4748) (xy 45.076618 -217.4748) (xy 45.081915 -217.475306)
			(xy 45.089483 -217.482722) (xy 45.09008 -217.488008) (xy 45.09008 -217.982546) (xy 45.090056 -217.9828)
			(xy 51.134264 -217.9828) (xy 51.134264 -217.982292) (xy 51.134264 -217.488008) (xy 51.134797 -217.482753)
			(xy 51.142218 -217.475311) (xy 51.147472 -217.4748) (xy 51.6636 -217.4748) (xy 51.67141 -217.474486)
			(xy 51.686281 -217.4697) (xy 51.69281 -217.465402) (xy 51.713899 -217.451053) (xy 51.75956 -217.428322)
			(xy 51.808166 -217.412863) (xy 51.858569 -217.40504) (xy 51.909575 -217.40504) (xy 51.959978 -217.412863)
			(xy 52.008584 -217.428322) (xy 52.054245 -217.451053) (xy 52.075334 -217.465402) (xy 52.081859 -217.469705)
			(xy 52.096734 -217.474481) (xy 52.104544 -217.4748) (xy 52.620672 -217.4748) (xy 52.626003 -217.475146)
			(xy 52.633546 -217.482678) (xy 52.63388 -217.488008) (xy 52.63388 -217.982546) (xy 58.678064 -217.982546)
			(xy 58.678064 -217.488008) (xy 58.678597 -217.482753) (xy 58.686018 -217.475311) (xy 58.691272 -217.4748)
			(xy 58.69178 -217.4748) (xy 60.164726 -217.4748) (xy 60.170024 -217.475301) (xy 60.177592 -217.482721)
			(xy 60.178188 -217.488008) (xy 60.178188 -217.982546) (xy 60.178164 -217.9828) (xy 167.778176 -217.9828)
			(xy 167.778176 -217.488008) (xy 167.778698 -217.48275) (xy 167.786127 -217.475308) (xy 167.791384 -217.4748)
			(xy 169.264584 -217.4748) (xy 169.269916 -217.475138) (xy 169.277458 -217.482676) (xy 169.277792 -217.488008)
			(xy 169.277792 -217.982546) (xy 175.321976 -217.982546) (xy 175.321976 -217.488008) (xy 175.322498 -217.48275)
			(xy 175.329927 -217.475308) (xy 175.335184 -217.4748) (xy 175.335692 -217.4748) (xy 175.851566 -217.4748)
			(xy 175.859375 -217.474472) (xy 175.874246 -217.469696) (xy 175.880776 -217.465402) (xy 175.901865 -217.451053)
			(xy 175.947526 -217.428322) (xy 175.996132 -217.412863) (xy 176.046535 -217.40504) (xy 176.097541 -217.40504)
			(xy 176.147944 -217.412863) (xy 176.19655 -217.428322) (xy 176.242211 -217.451053) (xy 176.2633 -217.465402)
			(xy 176.269832 -217.469692) (xy 176.284702 -217.474476) (xy 176.29251 -217.4748) (xy 176.808638 -217.4748)
			(xy 176.813938 -217.475293) (xy 176.821504 -217.482719) (xy 176.8221 -217.488008) (xy 176.8221 -217.982546)
			(xy 176.822076 -217.9828) (xy 182.866284 -217.9828) (xy 182.866284 -217.982292) (xy 182.866284 -217.488008)
			(xy 182.866799 -217.482748) (xy 182.874233 -217.475305) (xy 182.879492 -217.4748) (xy 183.39562 -217.4748)
			(xy 183.403431 -217.474495) (xy 183.418302 -217.469703) (xy 183.42483 -217.465402) (xy 183.445919 -217.451053)
			(xy 183.49158 -217.428322) (xy 183.540186 -217.412863) (xy 183.590589 -217.40504) (xy 183.641595 -217.40504)
			(xy 183.691998 -217.412863) (xy 183.740604 -217.428322) (xy 183.786265 -217.451053) (xy 183.807354 -217.465402)
			(xy 183.813874 -217.469713) (xy 183.828753 -217.474484) (xy 183.836564 -217.4748) (xy 184.352692 -217.4748)
			(xy 184.358025 -217.475133) (xy 184.365567 -217.482675) (xy 184.3659 -217.488008) (xy 184.3659 -217.982546)
			(xy 190.410084 -217.982546) (xy 190.410084 -217.488008) (xy 190.410599 -217.482748) (xy 190.418033 -217.475305)
			(xy 190.423292 -217.4748) (xy 190.4238 -217.4748) (xy 190.939674 -217.4748) (xy 190.947483 -217.474475)
			(xy 190.962355 -217.469697) (xy 190.968884 -217.465402) (xy 190.989973 -217.451053) (xy 191.035634 -217.428322)
			(xy 191.08424 -217.412863) (xy 191.134643 -217.40504) (xy 191.185649 -217.40504) (xy 191.236052 -217.412863)
			(xy 191.284658 -217.428322) (xy 191.330319 -217.451053) (xy 191.351408 -217.465402) (xy 191.357938 -217.469695)
			(xy 191.372809 -217.474477) (xy 191.380618 -217.4748) (xy 191.896746 -217.4748) (xy 191.902035 -217.475355)
			(xy 191.909606 -217.482734) (xy 191.910208 -217.488008) (xy 191.910208 -217.982546) (xy 191.910183 -217.9828)
			(xy 197.954392 -217.9828) (xy 197.954392 -217.982292) (xy 197.954392 -217.488008) (xy 197.954732 -217.482677)
			(xy 197.962269 -217.475135) (xy 197.9676 -217.4748) (xy 198.483728 -217.4748) (xy 198.491539 -217.474498)
			(xy 198.50641 -217.469704) (xy 198.512938 -217.465402) (xy 198.534027 -217.451053) (xy 198.579688 -217.428322)
			(xy 198.628294 -217.412863) (xy 198.678697 -217.40504) (xy 198.729703 -217.40504) (xy 198.780106 -217.412863)
			(xy 198.828712 -217.428322) (xy 198.874373 -217.451053) (xy 198.895462 -217.465402) (xy 198.902003 -217.469678)
			(xy 198.916866 -217.47447) (xy 198.924672 -217.4748) (xy 199.4408 -217.4748) (xy 199.446134 -217.475127)
			(xy 199.453676 -217.482674) (xy 199.454008 -217.488008) (xy 199.454008 -217.982546) (xy 199.453981 -217.9828)
			(xy 205.498192 -217.9828) (xy 205.498192 -217.982292) (xy 205.498192 -217.488008) (xy 205.498532 -217.482677)
			(xy 205.506069 -217.475135) (xy 205.5114 -217.4748) (xy 206.027528 -217.4748) (xy 206.035339 -217.474498)
			(xy 206.05021 -217.469704) (xy 206.056738 -217.465402) (xy 206.077827 -217.451053) (xy 206.123488 -217.428322)
			(xy 206.172094 -217.412863) (xy 206.222497 -217.40504) (xy 206.273503 -217.40504) (xy 206.323906 -217.412863)
			(xy 206.372512 -217.428322) (xy 206.418173 -217.451053) (xy 206.439262 -217.465402) (xy 206.445803 -217.469678)
			(xy 206.460666 -217.47447) (xy 206.468472 -217.4748) (xy 206.9846 -217.4748) (xy 206.989934 -217.475127)
			(xy 206.997476 -217.482674) (xy 206.997808 -217.488008) (xy 206.997808 -217.982292) (xy 268.898116 -217.982292)
			(xy 268.898116 -217.487754) (xy 268.898618 -217.48239) (xy 268.906213 -217.474808) (xy 268.911578 -217.474292)
			(xy 269.427706 -217.474292) (xy 269.435516 -217.473982) (xy 269.450388 -217.469194) (xy 269.456916 -217.464894)
			(xy 269.478005 -217.450545) (xy 269.523666 -217.427814) (xy 269.572272 -217.412355) (xy 269.622675 -217.404532)
			(xy 269.673681 -217.404532) (xy 269.724084 -217.412355) (xy 269.77269 -217.427814) (xy 269.818351 -217.450545)
			(xy 269.83944 -217.464894) (xy 269.845964 -217.469199) (xy 269.86084 -217.473974) (xy 269.86865 -217.474292)
			(xy 270.384778 -217.474292) (xy 270.390128 -217.474861) (xy 270.397712 -217.482406) (xy 270.39824 -217.487754)
			(xy 270.39824 -217.982292) (xy 276.442424 -217.982292) (xy 276.442424 -217.487754) (xy 276.442957 -217.48246)
			(xy 276.450351 -217.474887) (xy 276.455632 -217.474292) (xy 276.97176 -217.474292) (xy 276.979569 -217.473963)
			(xy 276.99444 -217.469188) (xy 277.00097 -217.464894) (xy 277.022059 -217.450545) (xy 277.06772 -217.427814)
			(xy 277.116326 -217.412355) (xy 277.166729 -217.404532) (xy 277.217735 -217.404532) (xy 277.268138 -217.412355)
			(xy 277.316744 -217.427814) (xy 277.362405 -217.450545) (xy 277.383494 -217.464894) (xy 277.390028 -217.469181)
			(xy 277.404896 -217.473967) (xy 277.412704 -217.474292) (xy 277.928832 -217.474292) (xy 277.934099 -217.474773)
			(xy 277.941539 -217.482232) (xy 277.94204 -217.4875) (xy 277.94204 -217.488008) (xy 277.94204 -217.982292)
			(xy 283.986224 -217.982292) (xy 283.986224 -217.487754) (xy 283.986757 -217.48246) (xy 283.994151 -217.474887)
			(xy 283.999432 -217.474292) (xy 284.51556 -217.474292) (xy 284.523369 -217.473963) (xy 284.53824 -217.469188)
			(xy 284.54477 -217.464894) (xy 284.565859 -217.450545) (xy 284.61152 -217.427814) (xy 284.660126 -217.412355)
			(xy 284.710529 -217.404532) (xy 284.761535 -217.404532) (xy 284.811938 -217.412355) (xy 284.860544 -217.427814)
			(xy 284.906205 -217.450545) (xy 284.927294 -217.464894) (xy 284.933828 -217.469181) (xy 284.948696 -217.473967)
			(xy 284.956504 -217.474292) (xy 285.472632 -217.474292) (xy 285.477899 -217.474773) (xy 285.485339 -217.482232)
			(xy 285.48584 -217.4875) (xy 285.48584 -217.488008) (xy 285.48584 -217.982292) (xy 291.530024 -217.982292)
			(xy 291.530024 -217.487754) (xy 291.530519 -217.482388) (xy 291.538119 -217.474806) (xy 291.543486 -217.474292)
			(xy 292.059614 -217.474292) (xy 292.067425 -217.473986) (xy 292.082296 -217.469195) (xy 292.088824 -217.464894)
			(xy 292.109913 -217.450545) (xy 292.155574 -217.427814) (xy 292.20418 -217.412355) (xy 292.254583 -217.404532)
			(xy 292.305589 -217.404532) (xy 292.355992 -217.412355) (xy 292.404598 -217.427814) (xy 292.450259 -217.450545)
			(xy 292.471348 -217.464894) (xy 292.47787 -217.469202) (xy 292.492747 -217.473975) (xy 292.500558 -217.474292)
			(xy 293.016686 -217.474292) (xy 293.022037 -217.474855) (xy 293.029621 -217.482405) (xy 293.030148 -217.487754)
			(xy 293.030148 -217.982292) (xy 299.074332 -217.982292) (xy 299.074332 -217.487754) (xy 299.074858 -217.482458)
			(xy 299.082257 -217.474884) (xy 299.08754 -217.474292) (xy 299.603668 -217.474292) (xy 299.611477 -217.473966)
			(xy 299.626349 -217.469189) (xy 299.632878 -217.464894) (xy 299.653967 -217.450545) (xy 299.699628 -217.427814)
			(xy 299.748234 -217.412355) (xy 299.798637 -217.404532) (xy 299.849643 -217.404532) (xy 299.900046 -217.412355)
			(xy 299.948652 -217.427814) (xy 299.994313 -217.450545) (xy 300.015402 -217.464894) (xy 300.021934 -217.469184)
			(xy 300.036804 -217.473968) (xy 300.044612 -217.474292) (xy 300.56074 -217.474292) (xy 300.566008 -217.474768)
			(xy 300.573448 -217.482231) (xy 300.573948 -217.4875) (xy 300.573948 -217.488008) (xy 300.573948 -217.982292)
			(xy 306.618132 -217.982292) (xy 306.618132 -217.487754) (xy 306.618619 -217.482386) (xy 306.626225 -217.474803)
			(xy 306.631594 -217.474292) (xy 308.104794 -217.474292) (xy 308.110146 -217.47485) (xy 308.11773 -217.482404)
			(xy 308.118256 -217.487754) (xy 308.118256 -217.548574) (xy 338.152884 -217.548574) (xy 338.152884 -217.494026)
			(xy 338.160647 -217.440032) (xy 338.176017 -217.387693) (xy 338.198679 -217.338074) (xy 338.228172 -217.292186)
			(xy 338.263897 -217.250963) (xy 338.305125 -217.215244) (xy 338.351016 -217.185756) (xy 338.400638 -217.1631)
			(xy 338.452979 -217.147737) (xy 338.506973 -217.13998) (xy 338.534248 -217.13952) (xy 339.550248 -217.13952)
			(xy 339.577514 -217.140046) (xy 339.63149 -217.147813) (xy 339.683811 -217.163181) (xy 339.733413 -217.185839)
			(xy 339.779286 -217.215325) (xy 339.820495 -217.251039) (xy 339.856204 -217.292253) (xy 339.885684 -217.338129)
			(xy 339.908336 -217.387734) (xy 339.923698 -217.440057) (xy 339.931458 -217.494034) (xy 339.931458 -217.548566)
			(xy 339.923698 -217.602543) (xy 339.908336 -217.654866) (xy 339.885684 -217.704471) (xy 339.856204 -217.750347)
			(xy 339.820495 -217.791561) (xy 339.779286 -217.827275) (xy 339.733413 -217.856761) (xy 339.683811 -217.879419)
			(xy 339.63149 -217.894787) (xy 339.577514 -217.902554) (xy 339.550248 -217.903044) (xy 338.534248 -217.903044)
			(xy 338.506973 -217.90262) (xy 338.452979 -217.894863) (xy 338.400638 -217.8795) (xy 338.351016 -217.856844)
			(xy 338.305125 -217.827356) (xy 338.263897 -217.791637) (xy 338.228172 -217.750414) (xy 338.198679 -217.704526)
			(xy 338.176017 -217.654907) (xy 338.160647 -217.602568) (xy 338.152884 -217.548574) (xy 308.118256 -217.548574)
			(xy 308.118256 -217.982292) (xy 415.718244 -217.982292) (xy 415.718244 -217.487754) (xy 415.71876 -217.482455)
			(xy 415.726165 -217.474881) (xy 415.731452 -217.474292) (xy 417.204652 -217.474292) (xy 417.209978 -217.474659)
			(xy 417.217521 -217.482176) (xy 417.21786 -217.4875) (xy 417.21786 -217.982292) (xy 423.262044 -217.982292)
			(xy 423.262044 -217.487754) (xy 423.262521 -217.482383) (xy 423.270133 -217.4748) (xy 423.275506 -217.474292)
			(xy 423.791634 -217.474292) (xy 423.799442 -217.473951) (xy 423.814313 -217.469184) (xy 423.820844 -217.464894)
			(xy 423.841933 -217.450545) (xy 423.887594 -217.427814) (xy 423.9362 -217.412355) (xy 423.986603 -217.404532)
			(xy 424.037609 -217.404532) (xy 424.088012 -217.412355) (xy 424.136618 -217.427814) (xy 424.182279 -217.450545)
			(xy 424.203368 -217.464894) (xy 424.209908 -217.469171) (xy 424.224771 -217.473963) (xy 424.232578 -217.474292)
			(xy 424.748706 -217.474292) (xy 424.75406 -217.474842) (xy 424.761642 -217.482402) (xy 424.762168 -217.487754)
			(xy 424.762168 -217.982292) (xy 430.806352 -217.982292) (xy 430.806352 -217.487754) (xy 430.806861 -217.482453)
			(xy 430.814271 -217.474879) (xy 430.81956 -217.474292) (xy 431.335688 -217.474292) (xy 431.343498 -217.473975)
			(xy 431.358369 -217.469191) (xy 431.364898 -217.464894) (xy 431.385987 -217.450545) (xy 431.431648 -217.427814)
			(xy 431.480254 -217.412355) (xy 431.530657 -217.404532) (xy 431.581663 -217.404532) (xy 431.632066 -217.412355)
			(xy 431.680672 -217.427814) (xy 431.726333 -217.450545) (xy 431.747422 -217.464894) (xy 431.75395 -217.469192)
			(xy 431.768823 -217.473971) (xy 431.776632 -217.474292) (xy 432.29276 -217.474292) (xy 432.298087 -217.474654)
			(xy 432.30563 -217.482174) (xy 432.305968 -217.4875) (xy 432.305968 -217.488008) (xy 432.305968 -217.982292)
			(xy 438.350152 -217.982292) (xy 438.350152 -217.487754) (xy 438.350621 -217.482381) (xy 438.358239 -217.474797)
			(xy 438.363614 -217.474292) (xy 438.879742 -217.474292) (xy 438.88755 -217.473955) (xy 438.902422 -217.469185)
			(xy 438.908952 -217.464894) (xy 438.930041 -217.450545) (xy 438.975702 -217.427814) (xy 439.024308 -217.412355)
			(xy 439.074711 -217.404532) (xy 439.125717 -217.404532) (xy 439.17612 -217.412355) (xy 439.224726 -217.427814)
			(xy 439.270387 -217.450545) (xy 439.291476 -217.464894) (xy 439.298014 -217.469174) (xy 439.312879 -217.473964)
			(xy 439.320686 -217.474292) (xy 439.836814 -217.474292) (xy 439.842168 -217.474837) (xy 439.849751 -217.482401)
			(xy 439.850276 -217.487754) (xy 439.850276 -217.982292) (xy 445.89446 -217.982292) (xy 445.89446 -217.487754)
			(xy 445.894961 -217.482452) (xy 445.902377 -217.474876) (xy 445.907668 -217.474292) (xy 446.423796 -217.474292)
			(xy 446.431606 -217.473978) (xy 446.446478 -217.469192) (xy 446.453006 -217.464894) (xy 446.474095 -217.450545)
			(xy 446.519756 -217.427814) (xy 446.568362 -217.412355) (xy 446.618765 -217.404532) (xy 446.669771 -217.404532)
			(xy 446.720174 -217.412355) (xy 446.76878 -217.427814) (xy 446.814441 -217.450545) (xy 446.83553 -217.464894)
			(xy 446.842056 -217.469195) (xy 446.85693 -217.473972) (xy 446.86474 -217.474292) (xy 447.380868 -217.474292)
			(xy 447.386196 -217.474648) (xy 447.393739 -217.482173) (xy 447.394076 -217.4875) (xy 447.394076 -217.488008)
			(xy 447.394076 -217.982292) (xy 453.43826 -217.982292) (xy 453.43826 -217.487754) (xy 453.438761 -217.482452)
			(xy 453.446177 -217.474876) (xy 453.451468 -217.474292) (xy 453.967596 -217.474292) (xy 453.975406 -217.473978)
			(xy 453.990278 -217.469192) (xy 453.996806 -217.464894) (xy 454.017895 -217.450545) (xy 454.063556 -217.427814)
			(xy 454.112162 -217.412355) (xy 454.162565 -217.404532) (xy 454.213571 -217.404532) (xy 454.263974 -217.412355)
			(xy 454.31258 -217.427814) (xy 454.358241 -217.450545) (xy 454.37933 -217.464894) (xy 454.385856 -217.469195)
			(xy 454.40073 -217.473972) (xy 454.40854 -217.474292) (xy 454.924668 -217.474292) (xy 454.929996 -217.474648)
			(xy 454.937539 -217.482173) (xy 454.937876 -217.4875) (xy 454.937876 -217.488008) (xy 454.937876 -217.982292)
			(xy 454.937565 -217.987631) (xy 454.930008 -217.995174) (xy 454.924668 -217.9955) (xy 454.408794 -217.9955)
			(xy 454.400921 -217.995801) (xy 454.385917 -218.000576) (xy 454.37933 -218.004898) (xy 454.358258 -218.019299)
			(xy 454.312612 -218.042127) (xy 454.264004 -218.057682) (xy 454.213585 -218.065597) (xy 454.188068 -218.066112)
			(xy 454.162549 -218.065603) (xy 454.112123 -218.057714) (xy 454.063511 -218.04216) (xy 454.017872 -218.01931)
			(xy 453.996806 -218.004898) (xy 453.990215 -218.000582) (xy 453.975215 -217.995796) (xy 453.967342 -217.9955)
			(xy 453.451468 -217.9955) (xy 453.446199 -217.995026) (xy 453.438758 -217.987562) (xy 453.43826 -217.982292)
			(xy 447.394076 -217.982292) (xy 447.393765 -217.987631) (xy 447.386208 -217.995174) (xy 447.380868 -217.9955)
			(xy 446.864994 -217.9955) (xy 446.857121 -217.995801) (xy 446.842117 -218.000576) (xy 446.83553 -218.004898)
			(xy 446.814458 -218.019299) (xy 446.768812 -218.042127) (xy 446.720204 -218.057682) (xy 446.669785 -218.065597)
			(xy 446.644268 -218.066112) (xy 446.618749 -218.065603) (xy 446.568323 -218.057714) (xy 446.519711 -218.04216)
			(xy 446.474072 -218.01931) (xy 446.453006 -218.004898) (xy 446.446415 -218.000582) (xy 446.431415 -217.995796)
			(xy 446.423542 -217.9955) (xy 445.907668 -217.9955) (xy 445.902399 -217.995026) (xy 445.894958 -217.987562)
			(xy 445.89446 -217.982292) (xy 439.850276 -217.982292) (xy 439.849965 -217.987631) (xy 439.842408 -217.995174)
			(xy 439.837068 -217.9955) (xy 439.83656 -217.9955) (xy 439.32094 -217.9955) (xy 439.313065 -217.995778)
			(xy 439.298061 -218.000569) (xy 439.291476 -218.004898) (xy 439.270392 -218.019279) (xy 439.22475 -218.042111)
			(xy 439.176146 -218.057672) (xy 439.12573 -218.065594) (xy 439.100214 -218.066112) (xy 439.074694 -218.06563)
			(xy 439.024266 -218.057733) (xy 438.975655 -218.042171) (xy 438.930017 -218.019314) (xy 438.908952 -218.004898)
			(xy 438.902373 -218.000561) (xy 438.887363 -217.995788) (xy 438.879488 -217.9955) (xy 438.363614 -217.9955)
			(xy 438.358321 -217.994972) (xy 438.350751 -217.987573) (xy 438.350152 -217.982292) (xy 432.305968 -217.982292)
			(xy 432.305664 -217.987633) (xy 432.298102 -217.995177) (xy 432.29276 -217.9955) (xy 431.776886 -217.9955)
			(xy 431.769012 -217.995798) (xy 431.754009 -218.000575) (xy 431.747422 -218.004898) (xy 431.726353 -218.019302)
			(xy 431.680705 -218.042129) (xy 431.632097 -218.057684) (xy 431.581678 -218.065598) (xy 431.55616 -218.066112)
			(xy 431.53064 -218.065607) (xy 431.480214 -218.057717) (xy 431.431603 -218.042161) (xy 431.385964 -218.019311)
			(xy 431.364898 -218.004898) (xy 431.358309 -218.000579) (xy 431.343307 -217.995795) (xy 431.335434 -217.9955)
			(xy 430.81956 -217.9955) (xy 430.81429 -217.995031) (xy 430.80685 -217.987563) (xy 430.806352 -217.982292)
			(xy 424.762168 -217.982292) (xy 424.761864 -217.987633) (xy 424.754302 -217.995177) (xy 424.74896 -217.9955)
			(xy 424.748452 -217.9955) (xy 424.232832 -217.9955) (xy 424.224956 -217.995775) (xy 424.209953 -218.000568)
			(xy 424.203368 -218.004898) (xy 424.182286 -218.019282) (xy 424.136643 -218.042114) (xy 424.088039 -218.057674)
			(xy 424.037622 -218.065594) (xy 424.012106 -218.066112) (xy 423.986585 -218.065634) (xy 423.936158 -218.057736)
			(xy 423.887547 -218.042172) (xy 423.841909 -218.019314) (xy 423.820844 -218.004898) (xy 423.814267 -218.000558)
			(xy 423.799256 -217.995787) (xy 423.79138 -217.9955) (xy 423.275506 -217.9955) (xy 423.270212 -217.994978)
			(xy 423.262643 -217.987574) (xy 423.262044 -217.982292) (xy 417.21786 -217.982292) (xy 417.217563 -217.987635)
			(xy 417.209996 -217.995179) (xy 417.204652 -217.9955) (xy 415.731452 -217.9955) (xy 415.726182 -217.995036)
			(xy 415.718741 -217.987564) (xy 415.718244 -217.982292) (xy 308.118256 -217.982292) (xy 308.117705 -217.987542)
			(xy 308.110296 -217.994983) (xy 308.105048 -217.9955) (xy 308.10454 -217.9955) (xy 306.631594 -217.9955)
			(xy 306.626298 -217.994986) (xy 306.61873 -217.987576) (xy 306.618132 -217.982292) (xy 300.573948 -217.982292)
			(xy 300.573404 -217.987544) (xy 300.56599 -217.994985) (xy 300.56074 -217.9955) (xy 300.044866 -217.9955)
			(xy 300.036992 -217.995789) (xy 300.021988 -218.000573) (xy 300.015402 -218.004898) (xy 299.99431 -218.019268)
			(xy 299.948671 -218.042103) (xy 299.900069 -218.057667) (xy 299.849656 -218.065592) (xy 299.82414 -218.066112)
			(xy 299.79862 -218.065617) (xy 299.748193 -218.057724) (xy 299.699582 -218.042165) (xy 299.653943 -218.019312)
			(xy 299.632878 -218.004898) (xy 299.626293 -218.000571) (xy 299.611288 -217.995792) (xy 299.603414 -217.9955)
			(xy 299.08754 -217.9955) (xy 299.082211 -217.995145) (xy 299.074668 -217.98762) (xy 299.074332 -217.982292)
			(xy 293.030148 -217.982292) (xy 293.029604 -217.987544) (xy 293.02219 -217.994985) (xy 293.01694 -217.9955)
			(xy 293.016432 -217.9955) (xy 292.500812 -217.9955) (xy 292.492939 -217.995809) (xy 292.477936 -218.000579)
			(xy 292.471348 -218.004898) (xy 292.450271 -218.019291) (xy 292.404627 -218.042121) (xy 292.35602 -218.057678)
			(xy 292.305603 -218.065596) (xy 292.280086 -218.066112) (xy 292.254567 -218.065594) (xy 292.204141 -218.057708)
			(xy 292.15553 -218.042156) (xy 292.10989 -218.019309) (xy 292.088824 -218.004898) (xy 292.082229 -218.000589)
			(xy 292.067232 -217.995799) (xy 292.05936 -217.9955) (xy 291.543486 -217.9955) (xy 291.538189 -217.994991)
			(xy 291.530621 -217.987577) (xy 291.530024 -217.982292) (xy 285.48584 -217.982292) (xy 285.485303 -217.987546)
			(xy 285.477885 -217.994987) (xy 285.472632 -217.9955) (xy 284.956758 -217.9955) (xy 284.948883 -217.995786)
			(xy 284.93388 -218.000572) (xy 284.927294 -218.004898) (xy 284.906205 -218.019271) (xy 284.860565 -218.042105)
			(xy 284.811962 -218.057668) (xy 284.761548 -218.065592) (xy 284.736032 -218.066112) (xy 284.710512 -218.065621)
			(xy 284.660085 -218.057727) (xy 284.611474 -218.042167) (xy 284.565835 -218.019313) (xy 284.54477 -218.004898)
			(xy 284.538187 -218.000568) (xy 284.52318 -217.995791) (xy 284.515306 -217.9955) (xy 283.999432 -217.9955)
			(xy 283.994102 -217.995151) (xy 283.986559 -217.987621) (xy 283.986224 -217.982292) (xy 277.94204 -217.982292)
			(xy 277.941503 -217.987546) (xy 277.934085 -217.994987) (xy 277.928832 -217.9955) (xy 277.412958 -217.9955)
			(xy 277.405083 -217.995786) (xy 277.39008 -218.000572) (xy 277.383494 -218.004898) (xy 277.362405 -218.019271)
			(xy 277.316765 -218.042105) (xy 277.268162 -218.057668) (xy 277.217748 -218.065592) (xy 277.192232 -218.066112)
			(xy 277.166712 -218.065621) (xy 277.116285 -218.057727) (xy 277.067674 -218.042167) (xy 277.022035 -218.019313)
			(xy 277.00097 -218.004898) (xy 276.994387 -218.000568) (xy 276.97938 -217.995791) (xy 276.971506 -217.9955)
			(xy 276.455632 -217.9955) (xy 276.450302 -217.995151) (xy 276.442759 -217.987621) (xy 276.442424 -217.982292)
			(xy 270.39824 -217.982292) (xy 270.397703 -217.987546) (xy 270.390285 -217.994987) (xy 270.385032 -217.9955)
			(xy 270.384524 -217.9955) (xy 269.868904 -217.9955) (xy 269.861031 -217.995805) (xy 269.846027 -218.000578)
			(xy 269.83944 -218.004898) (xy 269.818366 -218.019294) (xy 269.77272 -218.042123) (xy 269.724113 -218.05768)
			(xy 269.673695 -218.065597) (xy 269.648178 -218.066112) (xy 269.622659 -218.065598) (xy 269.572233 -218.057711)
			(xy 269.523621 -218.042158) (xy 269.477982 -218.01931) (xy 269.456916 -218.004898) (xy 269.450323 -218.000586)
			(xy 269.435324 -217.995797) (xy 269.427452 -217.9955) (xy 268.911578 -217.9955) (xy 268.906281 -217.994996)
			(xy 268.898713 -217.987579) (xy 268.898116 -217.982292) (xy 206.997808 -217.982292) (xy 206.997808 -217.982546)
			(xy 206.997246 -217.987833) (xy 206.989872 -217.995404) (xy 206.9846 -217.996008) (xy 206.468726 -217.996008)
			(xy 206.460917 -217.996331) (xy 206.446045 -218.00111) (xy 206.439516 -218.005406) (xy 206.418384 -218.019739)
			(xy 206.372664 -218.042471) (xy 206.323994 -218.057906) (xy 206.27353 -218.065677) (xy 206.248 -218.066112)
			(xy 206.22247 -218.065667) (xy 206.172007 -218.057892) (xy 206.123335 -218.042465) (xy 206.077607 -218.019752)
			(xy 206.056484 -218.005406) (xy 206.049955 -218.00111) (xy 206.035083 -217.99633) (xy 206.027274 -217.996008)
			(xy 205.5114 -217.996008) (xy 205.506137 -217.995505) (xy 205.498695 -217.988063) (xy 205.498192 -217.9828)
			(xy 199.453981 -217.9828) (xy 199.453446 -217.987833) (xy 199.446072 -217.995404) (xy 199.4408 -217.996008)
			(xy 198.924926 -217.996008) (xy 198.917117 -217.996331) (xy 198.902245 -218.00111) (xy 198.895716 -218.005406)
			(xy 198.874584 -218.019739) (xy 198.828864 -218.042471) (xy 198.780194 -218.057906) (xy 198.72973 -218.065677)
			(xy 198.7042 -218.066112) (xy 198.67867 -218.065667) (xy 198.628207 -218.057892) (xy 198.579535 -218.042465)
			(xy 198.533807 -218.019752) (xy 198.512684 -218.005406) (xy 198.506155 -218.00111) (xy 198.491283 -217.99633)
			(xy 198.483474 -217.996008) (xy 197.9676 -217.996008) (xy 197.962337 -217.995505) (xy 197.954895 -217.988063)
			(xy 197.954392 -217.9828) (xy 191.910183 -217.9828) (xy 191.909685 -217.987904) (xy 191.902104 -217.995485)
			(xy 191.896746 -217.996008) (xy 191.380872 -217.996008) (xy 191.373061 -217.996308) (xy 191.358189 -218.001103)
			(xy 191.351662 -218.005406) (xy 191.330545 -218.019762) (xy 191.28482 -218.042489) (xy 191.236145 -218.057917)
			(xy 191.185677 -218.065681) (xy 191.160146 -218.066112) (xy 191.134617 -218.065644) (xy 191.084155 -218.057876)
			(xy 191.035483 -218.042456) (xy 190.989753 -218.019749) (xy 190.96863 -218.005406) (xy 190.962091 -218.001128)
			(xy 190.947227 -217.996337) (xy 190.93942 -217.996008) (xy 190.423546 -217.996008) (xy 190.418199 -217.995423)
			(xy 190.410613 -217.98789) (xy 190.410084 -217.982546) (xy 184.3659 -217.982546) (xy 184.365345 -217.987835)
			(xy 184.357966 -217.995406) (xy 184.352692 -217.996008) (xy 183.836818 -217.996008) (xy 183.829008 -217.996328)
			(xy 183.814137 -218.001109) (xy 183.807608 -218.005406) (xy 183.786478 -218.019743) (xy 183.740758 -218.042473)
			(xy 183.692087 -218.057907) (xy 183.641622 -218.065677) (xy 183.616092 -218.066112) (xy 183.590562 -218.065671)
			(xy 183.540099 -218.057895) (xy 183.491427 -218.042467) (xy 183.445699 -218.019752) (xy 183.424576 -218.005406)
			(xy 183.418049 -218.001107) (xy 183.403175 -217.996329) (xy 183.395366 -217.996008) (xy 182.879492 -217.996008)
			(xy 182.874228 -217.995511) (xy 182.866786 -217.988064) (xy 182.866284 -217.9828) (xy 176.822076 -217.9828)
			(xy 176.821584 -217.987906) (xy 176.813999 -217.995487) (xy 176.808638 -217.996008) (xy 176.292764 -217.996008)
			(xy 176.284956 -217.996348) (xy 176.270085 -218.001116) (xy 176.263554 -218.005406) (xy 176.242439 -218.019766)
			(xy 176.196713 -218.042492) (xy 176.148038 -218.057919) (xy 176.09757 -218.065681) (xy 176.072038 -218.066112)
			(xy 176.046509 -218.065648) (xy 175.996047 -218.057879) (xy 175.947374 -218.042458) (xy 175.901645 -218.019749)
			(xy 175.880522 -218.005406) (xy 175.873985 -218.001125) (xy 175.859119 -217.996335) (xy 175.851312 -217.996008)
			(xy 175.335438 -217.996008) (xy 175.33009 -217.995429) (xy 175.322504 -217.987891) (xy 175.321976 -217.982546)
			(xy 169.277792 -217.982546) (xy 169.277244 -217.987836) (xy 169.269861 -217.995409) (xy 169.264584 -217.996008)
			(xy 167.791384 -217.996008) (xy 167.786119 -217.995516) (xy 167.778678 -217.988065) (xy 167.778176 -217.9828)
			(xy 60.178164 -217.9828) (xy 60.177683 -217.987909) (xy 60.17009 -217.995491) (xy 60.164726 -217.996008)
			(xy 58.691526 -217.996008) (xy 58.686176 -217.995437) (xy 58.678592 -217.987893) (xy 58.678064 -217.982546)
			(xy 52.63388 -217.982546) (xy 52.633343 -217.987839) (xy 52.625952 -217.995412) (xy 52.620672 -217.996008)
			(xy 52.104798 -217.996008) (xy 52.096988 -217.996319) (xy 52.082116 -218.001107) (xy 52.075588 -218.005406)
			(xy 52.054464 -218.019751) (xy 52.008741 -218.04248) (xy 51.960069 -218.057912) (xy 51.909603 -218.065679)
			(xy 51.884072 -218.066112) (xy 51.858542 -218.065681) (xy 51.808078 -218.057902) (xy 51.759406 -218.042471)
			(xy 51.713678 -218.019754) (xy 51.692556 -218.005406) (xy 51.686033 -218.0011) (xy 51.671156 -217.996326)
			(xy 51.663346 -217.996008) (xy 51.147472 -217.996008) (xy 51.142206 -217.995524) (xy 51.134765 -217.988067)
			(xy 51.134264 -217.9828) (xy 45.090056 -217.9828) (xy 45.089582 -217.987911) (xy 45.081984 -217.995493)
			(xy 45.076618 -217.996008) (xy 44.560744 -217.996008) (xy 44.552935 -217.996339) (xy 44.538064 -218.001113)
			(xy 44.531534 -218.005406) (xy 44.510425 -218.019775) (xy 44.464697 -218.042498) (xy 44.41602 -218.057923)
			(xy 44.36555 -218.065683) (xy 44.340018 -218.066112) (xy 44.314489 -218.065658) (xy 44.264026 -218.057886)
			(xy 44.215354 -218.042462) (xy 44.169625 -218.019751) (xy 44.148502 -218.005406) (xy 44.141969 -218.001117)
			(xy 44.1271 -217.996333) (xy 44.119292 -217.996008) (xy 43.603418 -217.996008) (xy 43.598067 -217.995442)
			(xy 43.590483 -217.987894) (xy 43.589956 -217.982546) (xy 37.545772 -217.982546) (xy 37.545242 -217.987841)
			(xy 37.537846 -217.995414) (xy 37.532564 -217.996008) (xy 37.01669 -217.996008) (xy 37.008879 -217.996316)
			(xy 36.994008 -218.001106) (xy 36.98748 -218.005406) (xy 36.966358 -218.019755) (xy 36.920635 -218.042483)
			(xy 36.871962 -218.057913) (xy 36.821495 -218.065679) (xy 36.795964 -218.066112) (xy 36.770433 -218.065685)
			(xy 36.71997 -218.057905) (xy 36.671297 -218.042473) (xy 36.62557 -218.019754) (xy 36.604448 -218.005406)
			(xy 36.597927 -218.001097) (xy 36.583049 -217.996325) (xy 36.575238 -217.996008) (xy 36.059364 -217.996008)
			(xy 36.054097 -217.995529) (xy 36.046657 -217.988068) (xy 36.046156 -217.9828) (xy 30.001947 -217.9828)
			(xy 30.001442 -217.987841) (xy 29.994046 -217.995414) (xy 29.988764 -217.996008) (xy 29.47289 -217.996008)
			(xy 29.465079 -217.996316) (xy 29.450208 -218.001106) (xy 29.44368 -218.005406) (xy 29.422558 -218.019755)
			(xy 29.376835 -218.042483) (xy 29.328162 -218.057913) (xy 29.277695 -218.065679) (xy 29.252164 -218.066112)
			(xy 29.226633 -218.065685) (xy 29.17617 -218.057905) (xy 29.127497 -218.042473) (xy 29.08177 -218.019754)
			(xy 29.060648 -218.005406) (xy 29.054127 -218.001097) (xy 29.039249 -217.996325) (xy 29.031438 -217.996008)
			(xy 28.515564 -217.996008) (xy 28.510297 -217.995529) (xy 28.502857 -217.988068) (xy 28.502356 -217.9828)
			(xy 22.458149 -217.9828) (xy 22.457681 -217.987913) (xy 22.450078 -217.995496) (xy 22.44471 -217.996008)
			(xy 21.928836 -217.996008) (xy 21.921027 -217.996335) (xy 21.906156 -218.001112) (xy 21.899626 -218.005406)
			(xy 21.878491 -218.019735) (xy 21.832772 -218.042467) (xy 21.784103 -218.057903) (xy 21.73364 -218.065676)
			(xy 21.70811 -218.066112) (xy 21.68258 -218.065662) (xy 21.632117 -218.057889) (xy 21.583445 -218.042463)
			(xy 21.537717 -218.019751) (xy 21.516594 -218.005406) (xy 21.510063 -218.001114) (xy 21.495193 -217.996331)
			(xy 21.487384 -217.996008) (xy 20.97151 -217.996008) (xy 20.966158 -217.995447) (xy 20.958575 -217.987895)
			(xy 20.958048 -217.982546) (xy 2.509012 -217.982546) (xy 2.509012 -218.83243) (xy 16.85798 -218.83243)
			(xy 16.85798 -218.337892) (xy 16.858488 -218.332631) (xy 16.865927 -218.32519) (xy 16.871188 -218.324684)
			(xy 16.871696 -218.324684) (xy 17.38757 -218.324684) (xy 17.395379 -218.32436) (xy 17.410251 -218.319582)
			(xy 17.41678 -218.315286) (xy 17.437869 -218.300937) (xy 17.48353 -218.278206) (xy 17.532136 -218.262747)
			(xy 17.582539 -218.254924) (xy 17.633545 -218.254924) (xy 17.683948 -218.262747) (xy 17.732554 -218.278206)
			(xy 17.778215 -218.300937) (xy 17.799304 -218.315286) (xy 17.805836 -218.319576) (xy 17.820706 -218.32436)
			(xy 17.828514 -218.324684) (xy 18.344642 -218.324684) (xy 18.349962 -218.3251) (xy 18.357533 -218.332579)
			(xy 18.358104 -218.337892) (xy 18.358104 -218.83243) (xy 18.358079 -218.832684) (xy 24.402288 -218.832684)
			(xy 24.402288 -218.832176) (xy 24.402288 -218.337892) (xy 24.402789 -218.332629) (xy 24.410233 -218.325187)
			(xy 24.415496 -218.324684) (xy 24.931624 -218.324684) (xy 24.939435 -218.324383) (xy 24.954307 -218.319589)
			(xy 24.960834 -218.315286) (xy 24.981923 -218.300937) (xy 25.027584 -218.278206) (xy 25.07619 -218.262747)
			(xy 25.126593 -218.254924) (xy 25.177599 -218.254924) (xy 25.228002 -218.262747) (xy 25.276608 -218.278206)
			(xy 25.322269 -218.300937) (xy 25.343358 -218.315286) (xy 25.349878 -218.319597) (xy 25.364757 -218.324368)
			(xy 25.372568 -218.324684) (xy 25.888696 -218.324684) (xy 25.893956 -218.325197) (xy 25.901399 -218.332632)
			(xy 25.901904 -218.337892) (xy 25.901904 -218.83243) (xy 25.90188 -218.832684) (xy 31.946088 -218.832684)
			(xy 31.946088 -218.832176) (xy 31.946088 -218.337892) (xy 31.946589 -218.332629) (xy 31.954033 -218.325187)
			(xy 31.959296 -218.324684) (xy 32.475424 -218.324684) (xy 32.483235 -218.324383) (xy 32.498107 -218.319589)
			(xy 32.504634 -218.315286) (xy 32.525723 -218.300937) (xy 32.571384 -218.278206) (xy 32.61999 -218.262747)
			(xy 32.670393 -218.254924) (xy 32.721399 -218.254924) (xy 32.771802 -218.262747) (xy 32.820408 -218.278206)
			(xy 32.866069 -218.300937) (xy 32.887158 -218.315286) (xy 32.893678 -218.319597) (xy 32.908557 -218.324368)
			(xy 32.916368 -218.324684) (xy 33.432496 -218.324684) (xy 33.437756 -218.325197) (xy 33.445199 -218.332632)
			(xy 33.445704 -218.337892) (xy 33.445704 -218.83243) (xy 39.489888 -218.83243) (xy 39.489888 -218.337892)
			(xy 39.490389 -218.332629) (xy 39.497833 -218.325187) (xy 39.503096 -218.324684) (xy 39.503604 -218.324684)
			(xy 40.019478 -218.324684) (xy 40.027288 -218.324364) (xy 40.042159 -218.319583) (xy 40.048688 -218.315286)
			(xy 40.069777 -218.300937) (xy 40.115438 -218.278206) (xy 40.164044 -218.262747) (xy 40.214447 -218.254924)
			(xy 40.265453 -218.254924) (xy 40.315856 -218.262747) (xy 40.364462 -218.278206) (xy 40.410123 -218.300937)
			(xy 40.431212 -218.315286) (xy 40.437742 -218.319579) (xy 40.452613 -218.324361) (xy 40.460422 -218.324684)
			(xy 40.97655 -218.324684) (xy 40.981858 -218.325162) (xy 40.989435 -218.332594) (xy 40.990012 -218.337892)
			(xy 40.990012 -218.83243) (xy 40.989987 -218.832684) (xy 47.034196 -218.832684) (xy 47.034196 -218.832176)
			(xy 47.034196 -218.337892) (xy 47.03469 -218.332627) (xy 47.042139 -218.325185) (xy 47.047404 -218.324684)
			(xy 47.563532 -218.324684) (xy 47.57134 -218.324344) (xy 47.586211 -218.319576) (xy 47.592742 -218.315286)
			(xy 47.613831 -218.300937) (xy 47.659492 -218.278206) (xy 47.708098 -218.262747) (xy 47.758501 -218.254924)
			(xy 47.809507 -218.254924) (xy 47.85991 -218.262747) (xy 47.908516 -218.278206) (xy 47.954177 -218.300937)
			(xy 47.975266 -218.315286) (xy 47.981807 -218.319562) (xy 47.99667 -218.324355) (xy 48.004476 -218.324684)
			(xy 48.520604 -218.324684) (xy 48.525865 -218.325191) (xy 48.533307 -218.332631) (xy 48.533812 -218.337892)
			(xy 48.533812 -218.83243) (xy 54.577996 -218.83243) (xy 54.577996 -218.337892) (xy 54.57849 -218.332627)
			(xy 54.585939 -218.325185) (xy 54.591204 -218.324684) (xy 56.064658 -218.324684) (xy 56.069967 -218.325156)
			(xy 56.077544 -218.332592) (xy 56.07812 -218.337892) (xy 56.07812 -218.83243) (xy 56.078107 -218.832684)
			(xy 163.678108 -218.832684) (xy 163.678108 -218.832176) (xy 163.678108 -218.337892) (xy 163.678423 -218.332555)
			(xy 163.685978 -218.325013) (xy 163.691316 -218.324684) (xy 165.164516 -218.324684) (xy 165.169779 -218.325183)
			(xy 165.17722 -218.332629) (xy 165.177724 -218.337892) (xy 165.177724 -218.83243) (xy 171.221908 -218.83243)
			(xy 171.221908 -218.337892) (xy 171.222223 -218.332555) (xy 171.229778 -218.325013) (xy 171.235116 -218.324684)
			(xy 171.235624 -218.324684) (xy 171.751498 -218.324684) (xy 171.759308 -218.324372) (xy 171.77418 -218.319585)
			(xy 171.780708 -218.315286) (xy 171.801797 -218.300937) (xy 171.847458 -218.278206) (xy 171.896064 -218.262747)
			(xy 171.946467 -218.254924) (xy 171.997473 -218.254924) (xy 172.047876 -218.262747) (xy 172.096482 -218.278206)
			(xy 172.142143 -218.300937) (xy 172.163232 -218.315286) (xy 172.169758 -218.319587) (xy 172.184632 -218.324364)
			(xy 172.192442 -218.324684) (xy 172.70857 -218.324684) (xy 172.713881 -218.325148) (xy 172.721456 -218.33259)
			(xy 172.722032 -218.337892) (xy 172.722032 -218.83243) (xy 172.72201 -218.832684) (xy 178.766216 -218.832684)
			(xy 178.766216 -218.832176) (xy 178.766216 -218.337892) (xy 178.766524 -218.332553) (xy 178.774084 -218.325011)
			(xy 178.779424 -218.324684) (xy 179.295552 -218.324684) (xy 179.303361 -218.324353) (xy 179.318232 -218.319579)
			(xy 179.324762 -218.315286) (xy 179.345851 -218.300937) (xy 179.391512 -218.278206) (xy 179.440118 -218.262747)
			(xy 179.490521 -218.254924) (xy 179.541527 -218.254924) (xy 179.59193 -218.262747) (xy 179.640536 -218.278206)
			(xy 179.686197 -218.300937) (xy 179.707286 -218.315286) (xy 179.713822 -218.319569) (xy 179.728689 -218.324358)
			(xy 179.736496 -218.324684) (xy 180.252624 -218.324684) (xy 180.257888 -218.325178) (xy 180.265328 -218.332628)
			(xy 180.265832 -218.337892) (xy 180.265832 -218.83243) (xy 186.310016 -218.83243) (xy 186.310016 -218.337892)
			(xy 186.310324 -218.332553) (xy 186.317884 -218.325011) (xy 186.323224 -218.324684) (xy 186.323732 -218.324684)
			(xy 186.839606 -218.324684) (xy 186.847417 -218.324376) (xy 186.862288 -218.319586) (xy 186.868816 -218.315286)
			(xy 186.889905 -218.300937) (xy 186.935566 -218.278206) (xy 186.984172 -218.262747) (xy 187.034575 -218.254924)
			(xy 187.085581 -218.254924) (xy 187.135984 -218.262747) (xy 187.18459 -218.278206) (xy 187.230251 -218.300937)
			(xy 187.25134 -218.315286) (xy 187.257864 -218.31959) (xy 187.27274 -218.324365) (xy 187.28055 -218.324684)
			(xy 187.796678 -218.324684) (xy 187.80199 -218.325143) (xy 187.809565 -218.332589) (xy 187.81014 -218.337892)
			(xy 187.81014 -218.83243) (xy 187.810118 -218.832684) (xy 193.854324 -218.832684) (xy 193.854324 -218.832176)
			(xy 193.854324 -218.337892) (xy 193.854624 -218.332551) (xy 193.86219 -218.325008) (xy 193.867532 -218.324684)
			(xy 194.38366 -218.324684) (xy 194.391469 -218.324356) (xy 194.40634 -218.31958) (xy 194.41287 -218.315286)
			(xy 194.433959 -218.300937) (xy 194.47962 -218.278206) (xy 194.528226 -218.262747) (xy 194.578629 -218.254924)
			(xy 194.629635 -218.254924) (xy 194.680038 -218.262747) (xy 194.728644 -218.278206) (xy 194.774305 -218.300937)
			(xy 194.795394 -218.315286) (xy 194.801928 -218.319572) (xy 194.816796 -218.324359) (xy 194.824604 -218.324684)
			(xy 195.340732 -218.324684) (xy 195.345997 -218.325173) (xy 195.353437 -218.332626) (xy 195.35394 -218.337892)
			(xy 195.35394 -218.83243) (xy 195.353919 -218.832684) (xy 201.398124 -218.832684) (xy 201.398124 -218.832176)
			(xy 201.398124 -218.337892) (xy 201.398424 -218.332551) (xy 201.40599 -218.325008) (xy 201.411332 -218.324684)
			(xy 201.92746 -218.324684) (xy 201.935269 -218.324356) (xy 201.95014 -218.31958) (xy 201.95667 -218.315286)
			(xy 201.977759 -218.300937) (xy 202.02342 -218.278206) (xy 202.072026 -218.262747) (xy 202.122429 -218.254924)
			(xy 202.173435 -218.254924) (xy 202.223838 -218.262747) (xy 202.272444 -218.278206) (xy 202.318105 -218.300937)
			(xy 202.339194 -218.315286) (xy 202.345728 -218.319572) (xy 202.360596 -218.324359) (xy 202.368404 -218.324684)
			(xy 202.884532 -218.324684) (xy 202.889797 -218.325173) (xy 202.897237 -218.332626) (xy 202.89774 -218.337892)
			(xy 202.89774 -218.832176) (xy 264.798048 -218.832176) (xy 264.798048 -218.337638) (xy 264.798406 -218.332206)
			(xy 264.806079 -218.324517) (xy 264.81151 -218.324176) (xy 265.327638 -218.324176) (xy 265.335446 -218.32384)
			(xy 265.350318 -218.31907) (xy 265.356848 -218.314778) (xy 265.377937 -218.300429) (xy 265.423598 -218.277698)
			(xy 265.472204 -218.262239) (xy 265.522607 -218.254416) (xy 265.573613 -218.254416) (xy 265.624016 -218.262239)
			(xy 265.672622 -218.277698) (xy 265.718283 -218.300429) (xy 265.739372 -218.314778) (xy 265.745912 -218.319055)
			(xy 265.760775 -218.323847) (xy 265.768582 -218.324176) (xy 266.28471 -218.324176) (xy 266.290155 -218.324476)
			(xy 266.297843 -218.332191) (xy 266.298172 -218.337638) (xy 266.298172 -218.832176) (xy 272.342356 -218.832176)
			(xy 272.342356 -218.337638) (xy 272.34285 -218.332335) (xy 272.350272 -218.324761) (xy 272.355564 -218.324176)
			(xy 272.871692 -218.324176) (xy 272.879502 -218.323863) (xy 272.894374 -218.319077) (xy 272.900902 -218.314778)
			(xy 272.921991 -218.300429) (xy 272.967652 -218.277698) (xy 273.016258 -218.262239) (xy 273.066661 -218.254416)
			(xy 273.117667 -218.254416) (xy 273.16807 -218.262239) (xy 273.216676 -218.277698) (xy 273.262337 -218.300429)
			(xy 273.283426 -218.314778) (xy 273.289954 -218.319076) (xy 273.304827 -218.323855) (xy 273.312636 -218.324176)
			(xy 273.828764 -218.324176) (xy 273.834088 -218.324549) (xy 273.84163 -218.332062) (xy 273.841972 -218.337384)
			(xy 273.841972 -218.337892) (xy 273.841972 -218.832176) (xy 279.886156 -218.832176) (xy 279.886156 -218.337638)
			(xy 279.88665 -218.332335) (xy 279.894072 -218.324761) (xy 279.899364 -218.324176) (xy 280.415492 -218.324176)
			(xy 280.423302 -218.323863) (xy 280.438174 -218.319077) (xy 280.444702 -218.314778) (xy 280.465791 -218.300429)
			(xy 280.511452 -218.277698) (xy 280.560058 -218.262239) (xy 280.610461 -218.254416) (xy 280.661467 -218.254416)
			(xy 280.71187 -218.262239) (xy 280.760476 -218.277698) (xy 280.806137 -218.300429) (xy 280.827226 -218.314778)
			(xy 280.833754 -218.319076) (xy 280.848627 -218.323855) (xy 280.856436 -218.324176) (xy 281.372564 -218.324176)
			(xy 281.377888 -218.324549) (xy 281.38543 -218.332062) (xy 281.385772 -218.337384) (xy 281.385772 -218.337892)
			(xy 281.385772 -218.832176) (xy 287.429956 -218.832176) (xy 287.429956 -218.337638) (xy 287.430306 -218.332204)
			(xy 287.437984 -218.324514) (xy 287.443418 -218.324176) (xy 287.959546 -218.324176) (xy 287.967354 -218.323843)
			(xy 287.982226 -218.319071) (xy 287.988756 -218.314778) (xy 288.009845 -218.300429) (xy 288.055506 -218.277698)
			(xy 288.104112 -218.262239) (xy 288.154515 -218.254416) (xy 288.205521 -218.254416) (xy 288.255924 -218.262239)
			(xy 288.30453 -218.277698) (xy 288.350191 -218.300429) (xy 288.37128 -218.314778) (xy 288.377818 -218.319058)
			(xy 288.392683 -218.323848) (xy 288.40049 -218.324176) (xy 288.916618 -218.324176) (xy 288.922065 -218.324471)
			(xy 288.929752 -218.33219) (xy 288.93008 -218.337638) (xy 288.93008 -218.832176) (xy 294.974264 -218.832176)
			(xy 294.974264 -218.337638) (xy 294.974751 -218.332333) (xy 294.982177 -218.324758) (xy 294.987472 -218.324176)
			(xy 295.5036 -218.324176) (xy 295.511411 -218.323866) (xy 295.526282 -218.319078) (xy 295.53281 -218.314778)
			(xy 295.553899 -218.300429) (xy 295.59956 -218.277698) (xy 295.648166 -218.262239) (xy 295.698569 -218.254416)
			(xy 295.749575 -218.254416) (xy 295.799978 -218.262239) (xy 295.848584 -218.277698) (xy 295.894245 -218.300429)
			(xy 295.915334 -218.314778) (xy 295.92186 -218.319079) (xy 295.936734 -218.323856) (xy 295.944544 -218.324176)
			(xy 296.460672 -218.324176) (xy 296.465997 -218.324544) (xy 296.473538 -218.33206) (xy 296.47388 -218.337384)
			(xy 296.47388 -218.337892) (xy 296.47388 -218.832176) (xy 302.518064 -218.832176) (xy 302.518064 -218.337638)
			(xy 302.518407 -218.332202) (xy 302.52609 -218.324512) (xy 302.531526 -218.324176) (xy 304.004726 -218.324176)
			(xy 304.010174 -218.324465) (xy 304.01786 -218.332189) (xy 304.018188 -218.337638) (xy 304.018188 -218.832176)
			(xy 411.618176 -218.832176) (xy 411.618176 -218.337638) (xy 411.618653 -218.33233) (xy 411.626086 -218.324755)
			(xy 411.631384 -218.324176) (xy 413.104584 -218.324176) (xy 413.109841 -218.324704) (xy 413.117284 -218.332128)
			(xy 413.117792 -218.337384) (xy 413.117792 -218.337892) (xy 413.117792 -218.832176) (xy 419.161976 -218.832176)
			(xy 419.161976 -218.337638) (xy 419.162308 -218.332199) (xy 419.169999 -218.324508) (xy 419.175438 -218.324176)
			(xy 419.691566 -218.324176) (xy 419.699375 -218.323852) (xy 419.714247 -218.319074) (xy 419.720776 -218.314778)
			(xy 419.741865 -218.300429) (xy 419.787526 -218.277698) (xy 419.836132 -218.262239) (xy 419.886535 -218.254416)
			(xy 419.937541 -218.254416) (xy 419.987944 -218.262239) (xy 420.03655 -218.277698) (xy 420.082211 -218.300429)
			(xy 420.1033 -218.314778) (xy 420.109834 -218.319066) (xy 420.124702 -218.323851) (xy 420.13251 -218.324176)
			(xy 420.648638 -218.324176) (xy 420.654016 -218.324629) (xy 420.661601 -218.332258) (xy 420.6621 -218.337638)
			(xy 420.6621 -218.832176) (xy 426.706284 -218.832176) (xy 426.706284 -218.337638) (xy 426.706754 -218.332328)
			(xy 426.714192 -218.324752) (xy 426.719492 -218.324176) (xy 427.23562 -218.324176) (xy 427.243431 -218.323875)
			(xy 427.258303 -218.319081) (xy 427.26483 -218.314778) (xy 427.285919 -218.300429) (xy 427.33158 -218.277698)
			(xy 427.380186 -218.262239) (xy 427.430589 -218.254416) (xy 427.481595 -218.254416) (xy 427.531998 -218.262239)
			(xy 427.580604 -218.277698) (xy 427.626265 -218.300429) (xy 427.647354 -218.314778) (xy 427.653876 -218.319086)
			(xy 427.668753 -218.323859) (xy 427.676564 -218.324176) (xy 428.192692 -218.324176) (xy 428.19795 -218.324698)
			(xy 428.205392 -218.332127) (xy 428.2059 -218.337384) (xy 428.2059 -218.337892) (xy 428.2059 -218.832176)
			(xy 434.250084 -218.832176) (xy 434.250084 -218.337638) (xy 434.250409 -218.332197) (xy 434.258105 -218.324506)
			(xy 434.263546 -218.324176) (xy 434.779674 -218.324176) (xy 434.787484 -218.323856) (xy 434.802355 -218.319075)
			(xy 434.808884 -218.314778) (xy 434.829973 -218.300429) (xy 434.875634 -218.277698) (xy 434.92424 -218.262239)
			(xy 434.974643 -218.254416) (xy 435.025649 -218.254416) (xy 435.076052 -218.262239) (xy 435.124658 -218.277698)
			(xy 435.170319 -218.300429) (xy 435.191408 -218.314778) (xy 435.19794 -218.319069) (xy 435.21281 -218.323852)
			(xy 435.220618 -218.324176) (xy 435.736746 -218.324176) (xy 435.742125 -218.324624) (xy 435.74971 -218.332256)
			(xy 435.750208 -218.337638) (xy 435.750208 -218.832176) (xy 441.794392 -218.832176) (xy 441.794392 -218.337638)
			(xy 441.794943 -218.33235) (xy 441.802325 -218.324779) (xy 441.8076 -218.324176) (xy 442.323728 -218.324176)
			(xy 442.33154 -218.323878) (xy 442.346411 -218.319082) (xy 442.352938 -218.314778) (xy 442.374027 -218.300429)
			(xy 442.419688 -218.277698) (xy 442.468294 -218.262239) (xy 442.518697 -218.254416) (xy 442.569703 -218.254416)
			(xy 442.620106 -218.262239) (xy 442.668712 -218.277698) (xy 442.714373 -218.300429) (xy 442.735462 -218.314778)
			(xy 442.742004 -218.319051) (xy 442.756866 -218.323846) (xy 442.764672 -218.324176) (xy 443.2808 -218.324176)
			(xy 443.286059 -218.324693) (xy 443.2935 -218.332126) (xy 443.294008 -218.337384) (xy 443.294008 -218.337892)
			(xy 443.294008 -218.832176) (xy 449.338192 -218.832176) (xy 449.338192 -218.337638) (xy 449.338743 -218.33235)
			(xy 449.346125 -218.324779) (xy 449.3514 -218.324176) (xy 449.867528 -218.324176) (xy 449.87534 -218.323878)
			(xy 449.890211 -218.319082) (xy 449.896738 -218.314778) (xy 449.917827 -218.300429) (xy 449.963488 -218.277698)
			(xy 450.012094 -218.262239) (xy 450.062497 -218.254416) (xy 450.113503 -218.254416) (xy 450.163906 -218.262239)
			(xy 450.212512 -218.277698) (xy 450.258173 -218.300429) (xy 450.279262 -218.314778) (xy 450.285804 -218.319051)
			(xy 450.300666 -218.323846) (xy 450.308472 -218.324176) (xy 450.8246 -218.324176) (xy 450.829859 -218.324693)
			(xy 450.8373 -218.332126) (xy 450.837808 -218.337384) (xy 450.837808 -218.337892) (xy 450.837808 -218.832176)
			(xy 450.837457 -218.837505) (xy 450.829928 -218.845047) (xy 450.8246 -218.845384) (xy 450.308726 -218.845384)
			(xy 450.300849 -218.845642) (xy 450.285845 -218.850445) (xy 450.279262 -218.854782) (xy 450.258188 -218.869179)
			(xy 450.212542 -218.892005) (xy 450.163935 -218.907561) (xy 450.113517 -218.915479) (xy 450.088 -218.915996)
			(xy 450.062479 -218.915524) (xy 450.012051 -218.907624) (xy 449.96344 -218.892059) (xy 449.917802 -218.869199)
			(xy 449.896738 -218.854782) (xy 449.890141 -218.850477) (xy 449.875145 -218.845685) (xy 449.867274 -218.845384)
			(xy 449.3514 -218.845384) (xy 449.346062 -218.845071) (xy 449.338519 -218.837515) (xy 449.338192 -218.832176)
			(xy 443.294008 -218.832176) (xy 443.293657 -218.837505) (xy 443.286128 -218.845047) (xy 443.2808 -218.845384)
			(xy 442.764926 -218.845384) (xy 442.757049 -218.845642) (xy 442.742045 -218.850445) (xy 442.735462 -218.854782)
			(xy 442.714388 -218.869179) (xy 442.668742 -218.892005) (xy 442.620135 -218.907561) (xy 442.569717 -218.915479)
			(xy 442.5442 -218.915996) (xy 442.518679 -218.915524) (xy 442.468251 -218.907624) (xy 442.41964 -218.892059)
			(xy 442.374002 -218.869199) (xy 442.352938 -218.854782) (xy 442.346341 -218.850477) (xy 442.331345 -218.845685)
			(xy 442.323474 -218.845384) (xy 441.8076 -218.845384) (xy 441.802262 -218.845071) (xy 441.794719 -218.837515)
			(xy 441.794392 -218.832176) (xy 435.750208 -218.832176) (xy 435.749857 -218.837505) (xy 435.742328 -218.845047)
			(xy 435.737 -218.845384) (xy 435.736492 -218.845384) (xy 435.220872 -218.845384) (xy 435.212996 -218.845662)
			(xy 435.197992 -218.850452) (xy 435.191408 -218.854782) (xy 435.170349 -218.869202) (xy 435.124697 -218.892023)
			(xy 435.076086 -218.907573) (xy 435.025664 -218.915483) (xy 435.000146 -218.915996) (xy 434.974626 -218.915501)
			(xy 434.924199 -218.907608) (xy 434.875588 -218.89205) (xy 434.829949 -218.869196) (xy 434.808884 -218.854782)
			(xy 434.802299 -218.850456) (xy 434.787294 -218.845677) (xy 434.77942 -218.845384) (xy 434.263546 -218.845384)
			(xy 434.258253 -218.844849) (xy 434.25068 -218.837456) (xy 434.250084 -218.832176) (xy 428.2059 -218.832176)
			(xy 428.205556 -218.837507) (xy 428.198023 -218.84505) (xy 428.192692 -218.845384) (xy 427.676818 -218.845384)
			(xy 427.668944 -218.845681) (xy 427.65394 -218.850458) (xy 427.647354 -218.854782) (xy 427.626282 -218.869182)
			(xy 427.580635 -218.892008) (xy 427.532027 -218.907563) (xy 427.481609 -218.91548) (xy 427.456092 -218.915996)
			(xy 427.430573 -218.915478) (xy 427.380147 -218.907592) (xy 427.331535 -218.89204) (xy 427.285896 -218.869194)
			(xy 427.26483 -218.854782) (xy 427.258235 -218.850474) (xy 427.243237 -218.845683) (xy 427.235366 -218.845384)
			(xy 426.719492 -218.845384) (xy 426.714153 -218.845076) (xy 426.706611 -218.837516) (xy 426.706284 -218.832176)
			(xy 420.6621 -218.832176) (xy 420.661756 -218.837507) (xy 420.654223 -218.84505) (xy 420.648892 -218.845384)
			(xy 420.648384 -218.845384) (xy 420.132764 -218.845384) (xy 420.124888 -218.845658) (xy 420.109884 -218.85045)
			(xy 420.1033 -218.854782) (xy 420.082216 -218.869163) (xy 420.036573 -218.891993) (xy 419.987969 -218.907553)
			(xy 419.937554 -218.915476) (xy 419.912038 -218.915996) (xy 419.886518 -218.915505) (xy 419.836091 -218.907611)
			(xy 419.787479 -218.892051) (xy 419.741841 -218.869197) (xy 419.720776 -218.854782) (xy 419.714193 -218.850453)
			(xy 419.699186 -218.845675) (xy 419.691312 -218.845384) (xy 419.175438 -218.845384) (xy 419.170144 -218.844854)
			(xy 419.162572 -218.837457) (xy 419.161976 -218.832176) (xy 413.117792 -218.832176) (xy 413.117455 -218.837509)
			(xy 413.109917 -218.845052) (xy 413.104584 -218.845384) (xy 411.631384 -218.845384) (xy 411.626044 -218.845082)
			(xy 411.618502 -218.837517) (xy 411.618176 -218.832176) (xy 304.018188 -218.832176) (xy 304.017855 -218.83751)
			(xy 304.010314 -218.845053) (xy 304.00498 -218.845384) (xy 302.531526 -218.845384) (xy 302.526231 -218.844862)
			(xy 302.518659 -218.837459) (xy 302.518064 -218.832176) (xy 296.47388 -218.832176) (xy 296.473554 -218.837512)
			(xy 296.466008 -218.845056) (xy 296.460672 -218.845384) (xy 295.944798 -218.845384) (xy 295.936923 -218.845673)
			(xy 295.921919 -218.850455) (xy 295.915334 -218.854782) (xy 295.894268 -218.869191) (xy 295.848619 -218.892014)
			(xy 295.800009 -218.907567) (xy 295.74959 -218.915481) (xy 295.724072 -218.915996) (xy 295.698553 -218.915488)
			(xy 295.648126 -218.907599) (xy 295.599515 -218.892045) (xy 295.553876 -218.869195) (xy 295.53281 -218.854782)
			(xy 295.526219 -218.850466) (xy 295.511218 -218.84568) (xy 295.503346 -218.845384) (xy 294.987472 -218.845384)
			(xy 294.9822 -218.844922) (xy 294.974758 -218.83745) (xy 294.974264 -218.832176) (xy 288.93008 -218.832176)
			(xy 288.929754 -218.837512) (xy 288.922208 -218.845056) (xy 288.916872 -218.845384) (xy 288.916364 -218.845384)
			(xy 288.400744 -218.845384) (xy 288.392867 -218.84565) (xy 288.377863 -218.850448) (xy 288.37128 -218.854782)
			(xy 288.350201 -218.869171) (xy 288.304556 -218.891999) (xy 288.255951 -218.907557) (xy 288.205534 -218.915478)
			(xy 288.180018 -218.915996) (xy 288.154497 -218.915515) (xy 288.10407 -218.907618) (xy 288.055459 -218.892056)
			(xy 288.009821 -218.869198) (xy 287.988756 -218.854782) (xy 287.982177 -218.850445) (xy 287.967167 -218.845672)
			(xy 287.959292 -218.845384) (xy 287.443418 -218.845384) (xy 287.438122 -218.844868) (xy 287.430551 -218.837461)
			(xy 287.429956 -218.832176) (xy 281.385772 -218.832176) (xy 281.385453 -218.837514) (xy 281.377902 -218.845058)
			(xy 281.372564 -218.845384) (xy 280.85669 -218.845384) (xy 280.848815 -218.845669) (xy 280.833811 -218.850454)
			(xy 280.827226 -218.854782) (xy 280.806162 -218.869194) (xy 280.760512 -218.892017) (xy 280.711902 -218.907569)
			(xy 280.661482 -218.915482) (xy 280.635964 -218.915996) (xy 280.610444 -218.915492) (xy 280.560018 -218.907602)
			(xy 280.511406 -218.892046) (xy 280.465767 -218.869195) (xy 280.444702 -218.854782) (xy 280.438113 -218.850463)
			(xy 280.423111 -218.845679) (xy 280.415238 -218.845384) (xy 279.899364 -218.845384) (xy 279.894091 -218.844927)
			(xy 279.886649 -218.837451) (xy 279.886156 -218.832176) (xy 273.841972 -218.832176) (xy 273.841653 -218.837514)
			(xy 273.834102 -218.845058) (xy 273.828764 -218.845384) (xy 273.31289 -218.845384) (xy 273.305015 -218.845669)
			(xy 273.290011 -218.850454) (xy 273.283426 -218.854782) (xy 273.262362 -218.869194) (xy 273.216712 -218.892017)
			(xy 273.168102 -218.907569) (xy 273.117682 -218.915482) (xy 273.092164 -218.915996) (xy 273.066644 -218.915492)
			(xy 273.016218 -218.907602) (xy 272.967606 -218.892046) (xy 272.921967 -218.869195) (xy 272.900902 -218.854782)
			(xy 272.894313 -218.850463) (xy 272.879311 -218.845679) (xy 272.871438 -218.845384) (xy 272.355564 -218.845384)
			(xy 272.350291 -218.844927) (xy 272.342849 -218.837451) (xy 272.342356 -218.832176) (xy 266.298172 -218.832176)
			(xy 266.297853 -218.837514) (xy 266.290302 -218.845058) (xy 266.284964 -218.845384) (xy 266.284456 -218.845384)
			(xy 265.768836 -218.845384) (xy 265.760959 -218.845646) (xy 265.745955 -218.850447) (xy 265.739372 -218.854782)
			(xy 265.718295 -218.869175) (xy 265.67265 -218.892002) (xy 265.624044 -218.907559) (xy 265.573627 -218.915478)
			(xy 265.54811 -218.915996) (xy 265.522589 -218.915519) (xy 265.472162 -218.907621) (xy 265.42355 -218.892057)
			(xy 265.377912 -218.869199) (xy 265.356848 -218.854782) (xy 265.350271 -218.850442) (xy 265.33526 -218.845671)
			(xy 265.327384 -218.845384) (xy 264.81151 -218.845384) (xy 264.806213 -218.844873) (xy 264.798642 -218.837462)
			(xy 264.798048 -218.832176) (xy 202.89774 -218.832176) (xy 202.89774 -218.83243) (xy 202.897295 -218.837743)
			(xy 202.889836 -218.845313) (xy 202.884532 -218.845892) (xy 202.368658 -218.845892) (xy 202.36085 -218.846232)
			(xy 202.345979 -218.851) (xy 202.339448 -218.85529) (xy 202.318341 -218.869662) (xy 202.272612 -218.892383)
			(xy 202.223934 -218.907806) (xy 202.173464 -218.915566) (xy 202.147932 -218.915996) (xy 202.122403 -218.915538)
			(xy 202.07194 -218.907767) (xy 202.023268 -218.892345) (xy 201.977539 -218.869634) (xy 201.956416 -218.85529)
			(xy 201.949881 -218.851005) (xy 201.935014 -218.846218) (xy 201.927206 -218.845892) (xy 201.411332 -218.845892)
			(xy 201.406 -218.84555) (xy 201.398456 -218.838015) (xy 201.398124 -218.832684) (xy 195.353919 -218.832684)
			(xy 195.353495 -218.837743) (xy 195.346036 -218.845313) (xy 195.340732 -218.845892) (xy 194.824858 -218.845892)
			(xy 194.81705 -218.846232) (xy 194.802179 -218.851) (xy 194.795648 -218.85529) (xy 194.774541 -218.869662)
			(xy 194.728812 -218.892383) (xy 194.680134 -218.907806) (xy 194.629664 -218.915566) (xy 194.604132 -218.915996)
			(xy 194.578603 -218.915538) (xy 194.52814 -218.907767) (xy 194.479468 -218.892345) (xy 194.433739 -218.869634)
			(xy 194.412616 -218.85529) (xy 194.406081 -218.851005) (xy 194.391214 -218.846218) (xy 194.383406 -218.845892)
			(xy 193.867532 -218.845892) (xy 193.8622 -218.84555) (xy 193.854656 -218.838015) (xy 193.854324 -218.832684)
			(xy 187.810118 -218.832684) (xy 187.809667 -218.837803) (xy 187.802053 -218.845388) (xy 187.796678 -218.845892)
			(xy 187.280804 -218.845892) (xy 187.272994 -218.846209) (xy 187.258123 -218.850993) (xy 187.251594 -218.85529)
			(xy 187.230475 -218.869643) (xy 187.18475 -218.892367) (xy 187.136076 -218.907796) (xy 187.085609 -218.915563)
			(xy 187.060078 -218.915996) (xy 187.034548 -218.915565) (xy 186.984084 -218.907786) (xy 186.935412 -218.892355)
			(xy 186.889684 -218.869638) (xy 186.868562 -218.85529) (xy 186.862039 -218.850984) (xy 186.847162 -218.846211)
			(xy 186.839352 -218.845892) (xy 186.323478 -218.845892) (xy 186.318119 -218.845367) (xy 186.310536 -218.837789)
			(xy 186.310016 -218.83243) (xy 180.265832 -218.83243) (xy 180.265394 -218.837745) (xy 180.257931 -218.845316)
			(xy 180.252624 -218.845892) (xy 179.73675 -218.845892) (xy 179.728942 -218.846228) (xy 179.71407 -218.850999)
			(xy 179.70754 -218.85529) (xy 179.686436 -218.869666) (xy 179.640705 -218.892385) (xy 179.592027 -218.907808)
			(xy 179.541556 -218.915567) (xy 179.516024 -218.915996) (xy 179.490495 -218.915542) (xy 179.440032 -218.90777)
			(xy 179.391359 -218.892346) (xy 179.345631 -218.869635) (xy 179.324508 -218.85529) (xy 179.317975 -218.851002)
			(xy 179.303106 -218.846217) (xy 179.295298 -218.845892) (xy 178.779424 -218.845892) (xy 178.774091 -218.845555)
			(xy 178.766548 -218.838017) (xy 178.766216 -218.832684) (xy 172.72201 -218.832684) (xy 172.721567 -218.837805)
			(xy 172.713947 -218.845391) (xy 172.70857 -218.845892) (xy 172.192696 -218.845892) (xy 172.184886 -218.846205)
			(xy 172.170015 -218.850992) (xy 172.163486 -218.85529) (xy 172.142369 -218.869646) (xy 172.096643 -218.89237)
			(xy 172.047968 -218.907798) (xy 171.997501 -218.915563) (xy 171.97197 -218.915996) (xy 171.946439 -218.915569)
			(xy 171.895975 -218.907789) (xy 171.847303 -218.892357) (xy 171.801576 -218.869638) (xy 171.780454 -218.85529)
			(xy 171.773933 -218.850981) (xy 171.759055 -218.846209) (xy 171.751244 -218.845892) (xy 171.23537 -218.845892)
			(xy 171.23001 -218.845373) (xy 171.222427 -218.83779) (xy 171.221908 -218.83243) (xy 165.177724 -218.83243)
			(xy 165.177293 -218.837746) (xy 165.169825 -218.845318) (xy 165.164516 -218.845892) (xy 163.691316 -218.845892)
			(xy 163.685982 -218.845561) (xy 163.678439 -218.838018) (xy 163.678108 -218.832684) (xy 56.078107 -218.832684)
			(xy 56.077837 -218.837879) (xy 56.070109 -218.845566) (xy 56.064658 -218.845892) (xy 54.591458 -218.845892)
			(xy 54.586096 -218.845381) (xy 54.578515 -218.837792) (xy 54.577996 -218.83243) (xy 48.533812 -218.83243)
			(xy 48.533391 -218.837749) (xy 48.525916 -218.845321) (xy 48.520604 -218.845892) (xy 48.00473 -218.845892)
			(xy 47.996921 -218.84622) (xy 47.98205 -218.850996) (xy 47.97552 -218.85529) (xy 47.954393 -218.869631)
			(xy 47.908671 -218.892359) (xy 47.859999 -218.907791) (xy 47.809534 -218.915561) (xy 47.784004 -218.915996)
			(xy 47.758474 -218.915552) (xy 47.708011 -218.907777) (xy 47.659339 -218.89235) (xy 47.61361 -218.869636)
			(xy 47.592488 -218.85529) (xy 47.585959 -218.850994) (xy 47.571087 -218.846214) (xy 47.563278 -218.845892)
			(xy 47.047404 -218.845892) (xy 47.042068 -218.845569) (xy 47.034526 -218.83802) (xy 47.034196 -218.832684)
			(xy 40.989987 -218.832684) (xy 40.989475 -218.837786) (xy 40.981905 -218.845367) (xy 40.97655 -218.845892)
			(xy 40.460676 -218.845892) (xy 40.452865 -218.846197) (xy 40.437994 -218.850989) (xy 40.431466 -218.85529)
			(xy 40.410354 -218.869655) (xy 40.364627 -218.892377) (xy 40.31595 -218.907802) (xy 40.265482 -218.915565)
			(xy 40.23995 -218.915996) (xy 40.214421 -218.915529) (xy 40.163959 -218.907761) (xy 40.115286 -218.892341)
			(xy 40.069557 -218.869633) (xy 40.048434 -218.85529) (xy 40.041895 -218.851012) (xy 40.027031 -218.846221)
			(xy 40.019224 -218.845892) (xy 39.50335 -218.845892) (xy 39.497987 -218.845386) (xy 39.490406 -218.837793)
			(xy 39.489888 -218.83243) (xy 33.445704 -218.83243) (xy 33.445202 -218.837728) (xy 33.437783 -218.845295)
			(xy 33.432496 -218.845892) (xy 32.916622 -218.845892) (xy 32.908813 -218.846216) (xy 32.893942 -218.850995)
			(xy 32.887412 -218.85529) (xy 32.866288 -218.869635) (xy 32.820564 -218.892361) (xy 32.771892 -218.907792)
			(xy 32.721427 -218.915561) (xy 32.695896 -218.915996) (xy 32.670366 -218.915556) (xy 32.619903 -218.90778)
			(xy 32.57123 -218.892352) (xy 32.525502 -218.869637) (xy 32.50438 -218.85529) (xy 32.497853 -218.850991)
			(xy 32.482979 -218.846213) (xy 32.47517 -218.845892) (xy 31.959296 -218.845892) (xy 31.953959 -218.845574)
			(xy 31.946418 -218.838021) (xy 31.946088 -218.832684) (xy 25.90188 -218.832684) (xy 25.901402 -218.837728)
			(xy 25.893983 -218.845295) (xy 25.888696 -218.845892) (xy 25.372822 -218.845892) (xy 25.365013 -218.846216)
			(xy 25.350142 -218.850995) (xy 25.343612 -218.85529) (xy 25.322488 -218.869635) (xy 25.276764 -218.892361)
			(xy 25.228092 -218.907792) (xy 25.177627 -218.915561) (xy 25.152096 -218.915996) (xy 25.126566 -218.915556)
			(xy 25.076103 -218.90778) (xy 25.02743 -218.892352) (xy 24.981702 -218.869637) (xy 24.96058 -218.85529)
			(xy 24.954053 -218.850991) (xy 24.939179 -218.846213) (xy 24.93137 -218.845892) (xy 24.415496 -218.845892)
			(xy 24.410159 -218.845574) (xy 24.402618 -218.838021) (xy 24.402288 -218.832684) (xy 18.358079 -218.832684)
			(xy 18.357574 -218.837787) (xy 18.349999 -218.845369) (xy 18.344642 -218.845892) (xy 17.828768 -218.845892)
			(xy 17.820961 -218.846236) (xy 17.806089 -218.851001) (xy 17.799558 -218.85529) (xy 17.778449 -218.869658)
			(xy 17.73272 -218.892379) (xy 17.684043 -218.907804) (xy 17.633574 -218.915565) (xy 17.608042 -218.915996)
			(xy 17.582513 -218.915533) (xy 17.53205 -218.907764) (xy 17.483378 -218.892342) (xy 17.437649 -218.869634)
			(xy 17.416526 -218.85529) (xy 17.409989 -218.851009) (xy 17.395123 -218.84622) (xy 17.387316 -218.845892)
			(xy 16.871442 -218.845892) (xy 16.86602 -218.845495) (xy 16.858333 -218.83785) (xy 16.85798 -218.83243)
			(xy 2.509012 -218.83243) (xy 2.509012 -219.682568) (xy 20.958048 -219.682568) (xy 20.958048 -219.18803)
			(xy 20.958401 -219.182597) (xy 20.966077 -219.174909) (xy 20.97151 -219.174568) (xy 21.487638 -219.174568)
			(xy 21.495446 -219.174233) (xy 21.510318 -219.169462) (xy 21.516848 -219.16517) (xy 21.537937 -219.150821)
			(xy 21.583598 -219.12809) (xy 21.632204 -219.112631) (xy 21.682607 -219.104808) (xy 21.733613 -219.104808)
			(xy 21.784016 -219.112631) (xy 21.832622 -219.12809) (xy 21.878283 -219.150821) (xy 21.899372 -219.16517)
			(xy 21.905912 -219.169446) (xy 21.920776 -219.174239) (xy 21.928582 -219.174568) (xy 22.44471 -219.174568)
			(xy 22.450154 -219.174875) (xy 22.457841 -219.182585) (xy 22.458172 -219.18803) (xy 22.458172 -219.682568)
			(xy 28.502356 -219.682568) (xy 28.502356 -219.18803) (xy 28.502845 -219.182726) (xy 28.51027 -219.175152)
			(xy 28.515564 -219.174568) (xy 29.031692 -219.174568) (xy 29.039502 -219.174256) (xy 29.054374 -219.16947)
			(xy 29.060902 -219.16517) (xy 29.081991 -219.150821) (xy 29.127652 -219.12809) (xy 29.176258 -219.112631)
			(xy 29.226661 -219.104808) (xy 29.277667 -219.104808) (xy 29.32807 -219.112631) (xy 29.376676 -219.12809)
			(xy 29.422337 -219.150821) (xy 29.443426 -219.16517) (xy 29.449954 -219.169467) (xy 29.464827 -219.174247)
			(xy 29.472636 -219.174568) (xy 29.988764 -219.174568) (xy 29.994086 -219.174949) (xy 30.001627 -219.182456)
			(xy 30.001972 -219.187776) (xy 30.001972 -219.188284) (xy 30.001972 -219.682568) (xy 36.046156 -219.682568)
			(xy 36.046156 -219.18803) (xy 36.046645 -219.182726) (xy 36.05407 -219.175152) (xy 36.059364 -219.174568)
			(xy 36.575492 -219.174568) (xy 36.583302 -219.174256) (xy 36.598174 -219.16947) (xy 36.604702 -219.16517)
			(xy 36.625791 -219.150821) (xy 36.671452 -219.12809) (xy 36.720058 -219.112631) (xy 36.770461 -219.104808)
			(xy 36.821467 -219.104808) (xy 36.87187 -219.112631) (xy 36.920476 -219.12809) (xy 36.966137 -219.150821)
			(xy 36.987226 -219.16517) (xy 36.993754 -219.169467) (xy 37.008627 -219.174247) (xy 37.016436 -219.174568)
			(xy 37.532564 -219.174568) (xy 37.537886 -219.174949) (xy 37.545427 -219.182456) (xy 37.545772 -219.187776)
			(xy 37.545772 -219.188284) (xy 37.545772 -219.682568) (xy 43.589956 -219.682568) (xy 43.589956 -219.18803)
			(xy 43.590301 -219.182595) (xy 43.597983 -219.174906) (xy 43.603418 -219.174568) (xy 44.119546 -219.174568)
			(xy 44.127355 -219.174237) (xy 44.142226 -219.169463) (xy 44.148756 -219.16517) (xy 44.169845 -219.150821)
			(xy 44.215506 -219.12809) (xy 44.264112 -219.112631) (xy 44.314515 -219.104808) (xy 44.365521 -219.104808)
			(xy 44.415924 -219.112631) (xy 44.46453 -219.12809) (xy 44.510191 -219.150821) (xy 44.53128 -219.16517)
			(xy 44.537819 -219.169449) (xy 44.552683 -219.17424) (xy 44.56049 -219.174568) (xy 45.076618 -219.174568)
			(xy 45.082063 -219.17487) (xy 45.089749 -219.182584) (xy 45.09008 -219.18803) (xy 45.09008 -219.682568)
			(xy 51.134264 -219.682568) (xy 51.134264 -219.18803) (xy 51.134746 -219.182724) (xy 51.142176 -219.17515)
			(xy 51.147472 -219.174568) (xy 51.6636 -219.174568) (xy 51.671411 -219.17426) (xy 51.686282 -219.169471)
			(xy 51.69281 -219.16517) (xy 51.713899 -219.150821) (xy 51.75956 -219.12809) (xy 51.808166 -219.112631)
			(xy 51.858569 -219.104808) (xy 51.909575 -219.104808) (xy 51.959978 -219.112631) (xy 52.008584 -219.12809)
			(xy 52.054245 -219.150821) (xy 52.075334 -219.16517) (xy 52.081861 -219.16947) (xy 52.096734 -219.174248)
			(xy 52.104544 -219.174568) (xy 52.620672 -219.174568) (xy 52.625995 -219.174943) (xy 52.633536 -219.182455)
			(xy 52.63388 -219.187776) (xy 52.63388 -219.188284) (xy 52.63388 -219.682568) (xy 58.678064 -219.682568)
			(xy 58.678064 -219.18803) (xy 58.678402 -219.182593) (xy 58.686089 -219.174904) (xy 58.691526 -219.174568)
			(xy 60.164726 -219.174568) (xy 60.170172 -219.174865) (xy 60.177858 -219.182583) (xy 60.178188 -219.18803)
			(xy 60.178188 -219.682568) (xy 60.17785 -219.687901) (xy 60.170312 -219.695445) (xy 60.16498 -219.695776)
			(xy 60.164472 -219.695776) (xy 58.691526 -219.695776) (xy 58.686229 -219.695261) (xy 58.678657 -219.687854)
			(xy 58.678064 -219.682568) (xy 52.63388 -219.682568) (xy 52.633549 -219.687903) (xy 52.626007 -219.695447)
			(xy 52.620672 -219.695776) (xy 52.104798 -219.695776) (xy 52.096924 -219.696066) (xy 52.081919 -219.700848)
			(xy 52.075334 -219.705174) (xy 52.054267 -219.719582) (xy 52.008618 -219.742406) (xy 51.960009 -219.757959)
			(xy 51.90959 -219.765873) (xy 51.884072 -219.766388) (xy 51.858552 -219.765881) (xy 51.808126 -219.757992)
			(xy 51.759514 -219.742437) (xy 51.713875 -219.719587) (xy 51.69281 -219.705174) (xy 51.686214 -219.700867)
			(xy 51.671218 -219.696074) (xy 51.663346 -219.695776) (xy 51.147472 -219.695776) (xy 51.142128 -219.695489)
			(xy 51.134587 -219.687913) (xy 51.134264 -219.682568) (xy 45.09008 -219.682568) (xy 45.089749 -219.687903)
			(xy 45.082207 -219.695447) (xy 45.076872 -219.695776) (xy 45.076364 -219.695776) (xy 44.560744 -219.695776)
			(xy 44.552868 -219.696043) (xy 44.537864 -219.70084) (xy 44.53128 -219.705174) (xy 44.510201 -219.719562)
			(xy 44.464556 -219.742391) (xy 44.415951 -219.757949) (xy 44.365534 -219.76587) (xy 44.340018 -219.766388)
			(xy 44.314497 -219.765909) (xy 44.26407 -219.758011) (xy 44.215458 -219.742448) (xy 44.16982 -219.719591)
			(xy 44.148756 -219.705174) (xy 44.142172 -219.700846) (xy 44.127166 -219.696066) (xy 44.119292 -219.695776)
			(xy 43.603418 -219.695776) (xy 43.59812 -219.695267) (xy 43.590548 -219.687855) (xy 43.589956 -219.682568)
			(xy 37.545772 -219.682568) (xy 37.545448 -219.687905) (xy 37.537901 -219.69545) (xy 37.532564 -219.695776)
			(xy 37.01669 -219.695776) (xy 37.008815 -219.696063) (xy 36.993811 -219.700846) (xy 36.987226 -219.705174)
			(xy 36.966162 -219.719586) (xy 36.920512 -219.742409) (xy 36.871902 -219.757961) (xy 36.821482 -219.765874)
			(xy 36.795964 -219.766388) (xy 36.770444 -219.765885) (xy 36.720018 -219.757995) (xy 36.671406 -219.742439)
			(xy 36.625767 -219.719588) (xy 36.604702 -219.705174) (xy 36.598107 -219.700864) (xy 36.58311 -219.696073)
			(xy 36.575238 -219.695776) (xy 36.059364 -219.695776) (xy 36.054089 -219.695326) (xy 36.046647 -219.687845)
			(xy 36.046156 -219.682568) (xy 30.001972 -219.682568) (xy 30.001648 -219.687905) (xy 29.994101 -219.69545)
			(xy 29.988764 -219.695776) (xy 29.47289 -219.695776) (xy 29.465015 -219.696063) (xy 29.450011 -219.700846)
			(xy 29.443426 -219.705174) (xy 29.422362 -219.719586) (xy 29.376712 -219.742409) (xy 29.328102 -219.757961)
			(xy 29.277682 -219.765874) (xy 29.252164 -219.766388) (xy 29.226644 -219.765885) (xy 29.176218 -219.757995)
			(xy 29.127606 -219.742439) (xy 29.081967 -219.719588) (xy 29.060902 -219.705174) (xy 29.054307 -219.700864)
			(xy 29.03931 -219.696073) (xy 29.031438 -219.695776) (xy 28.515564 -219.695776) (xy 28.510289 -219.695326)
			(xy 28.502847 -219.687845) (xy 28.502356 -219.682568) (xy 22.458172 -219.682568) (xy 22.457848 -219.687905)
			(xy 22.450301 -219.69545) (xy 22.444964 -219.695776) (xy 22.444456 -219.695776) (xy 21.928836 -219.695776)
			(xy 21.920959 -219.69604) (xy 21.905955 -219.700839) (xy 21.899372 -219.705174) (xy 21.878295 -219.719566)
			(xy 21.83265 -219.742393) (xy 21.784044 -219.757951) (xy 21.733627 -219.76587) (xy 21.70811 -219.766388)
			(xy 21.682589 -219.765913) (xy 21.632162 -219.758014) (xy 21.58355 -219.74245) (xy 21.537912 -219.719591)
			(xy 21.516848 -219.705174) (xy 21.510266 -219.700843) (xy 21.495259 -219.696065) (xy 21.487384 -219.695776)
			(xy 20.97151 -219.695776) (xy 20.966211 -219.695272) (xy 20.95864 -219.687856) (xy 20.958048 -219.682568)
			(xy 2.509012 -219.682568) (xy 2.509012 -219.820372) (xy 129.049982 -219.820372) (xy 129.049982 -219.765828)
			(xy 129.057745 -219.71184) (xy 129.073111 -219.659505) (xy 129.095769 -219.609891) (xy 129.125257 -219.564005)
			(xy 129.160975 -219.522783) (xy 129.202196 -219.487064) (xy 129.24808 -219.457575) (xy 129.297694 -219.434915)
			(xy 129.350028 -219.419547) (xy 129.404016 -219.411783) (xy 129.431288 -219.411296) (xy 130.447288 -219.411296)
			(xy 130.474557 -219.411843) (xy 130.528539 -219.419602) (xy 130.580867 -219.434966) (xy 130.630476 -219.45762)
			(xy 130.676357 -219.487104) (xy 130.717574 -219.522818) (xy 130.753288 -219.564034) (xy 130.782774 -219.609913)
			(xy 130.80543 -219.659522) (xy 130.812197 -219.682568) (xy 167.778176 -219.682568) (xy 167.778176 -219.18803)
			(xy 167.778647 -219.182721) (xy 167.786085 -219.175146) (xy 167.791384 -219.174568) (xy 169.264584 -219.174568)
			(xy 169.269839 -219.175103) (xy 169.277281 -219.182522) (xy 169.277792 -219.187776) (xy 169.277792 -219.682568)
			(xy 175.321976 -219.682568) (xy 175.321976 -219.18803) (xy 175.322303 -219.18259) (xy 175.329998 -219.1749)
			(xy 175.335438 -219.174568) (xy 175.851566 -219.174568) (xy 175.859375 -219.174245) (xy 175.874247 -219.169466)
			(xy 175.880776 -219.16517) (xy 175.901865 -219.150821) (xy 175.947526 -219.12809) (xy 175.996132 -219.112631)
			(xy 176.046535 -219.104808) (xy 176.097541 -219.104808) (xy 176.147944 -219.112631) (xy 176.19655 -219.12809)
			(xy 176.242211 -219.150821) (xy 176.2633 -219.16517) (xy 176.269834 -219.169457) (xy 176.284702 -219.174243)
			(xy 176.29251 -219.174568) (xy 176.808638 -219.174568) (xy 176.814014 -219.175028) (xy 176.821599 -219.182652)
			(xy 176.8221 -219.18803) (xy 176.8221 -219.682568) (xy 182.866284 -219.682568) (xy 182.866284 -219.18803)
			(xy 182.866748 -219.182719) (xy 182.87419 -219.175144) (xy 182.879492 -219.174568) (xy 183.39562 -219.174568)
			(xy 183.403431 -219.174268) (xy 183.418303 -219.169473) (xy 183.42483 -219.16517) (xy 183.445919 -219.150821)
			(xy 183.49158 -219.12809) (xy 183.540186 -219.112631) (xy 183.590589 -219.104808) (xy 183.641595 -219.104808)
			(xy 183.691998 -219.112631) (xy 183.740604 -219.12809) (xy 183.786265 -219.150821) (xy 183.807354 -219.16517)
			(xy 183.813876 -219.169478) (xy 183.828753 -219.174251) (xy 183.836564 -219.174568) (xy 184.352692 -219.174568)
			(xy 184.357948 -219.175097) (xy 184.36539 -219.182521) (xy 184.3659 -219.187776) (xy 184.3659 -219.188284)
			(xy 184.3659 -219.682568) (xy 190.410084 -219.682568) (xy 190.410084 -219.18803) (xy 190.410404 -219.182588)
			(xy 190.418104 -219.174898) (xy 190.423546 -219.174568) (xy 190.939674 -219.174568) (xy 190.947484 -219.174248)
			(xy 190.962355 -219.169467) (xy 190.968884 -219.16517) (xy 190.989973 -219.150821) (xy 191.035634 -219.12809)
			(xy 191.08424 -219.112631) (xy 191.134643 -219.104808) (xy 191.185649 -219.104808) (xy 191.236052 -219.112631)
			(xy 191.284658 -219.12809) (xy 191.330319 -219.150821) (xy 191.351408 -219.16517) (xy 191.35794 -219.16946)
			(xy 191.37281 -219.174244) (xy 191.380618 -219.174568) (xy 191.896746 -219.174568) (xy 191.902123 -219.175023)
			(xy 191.909707 -219.182651) (xy 191.910208 -219.18803) (xy 191.910208 -219.682568) (xy 197.954392 -219.682568)
			(xy 197.954392 -219.18803) (xy 197.954938 -219.182741) (xy 197.962324 -219.175171) (xy 197.9676 -219.174568)
			(xy 198.483728 -219.174568) (xy 198.49154 -219.174272) (xy 198.506411 -219.169474) (xy 198.512938 -219.16517)
			(xy 198.534027 -219.150821) (xy 198.579688 -219.12809) (xy 198.628294 -219.112631) (xy 198.678697 -219.104808)
			(xy 198.729703 -219.104808) (xy 198.780106 -219.112631) (xy 198.828712 -219.12809) (xy 198.874373 -219.150821)
			(xy 198.895462 -219.16517) (xy 198.902005 -219.169442) (xy 198.916866 -219.174237) (xy 198.924672 -219.174568)
			(xy 199.4408 -219.174568) (xy 199.446057 -219.175092) (xy 199.453498 -219.18252) (xy 199.454008 -219.187776)
			(xy 199.454008 -219.188284) (xy 199.454008 -219.682568) (xy 205.498192 -219.682568) (xy 205.498192 -219.18803)
			(xy 205.498738 -219.182741) (xy 205.506124 -219.175171) (xy 205.5114 -219.174568) (xy 206.027528 -219.174568)
			(xy 206.03534 -219.174272) (xy 206.050211 -219.169474) (xy 206.056738 -219.16517) (xy 206.077827 -219.150821)
			(xy 206.123488 -219.12809) (xy 206.172094 -219.112631) (xy 206.222497 -219.104808) (xy 206.273503 -219.104808)
			(xy 206.323906 -219.112631) (xy 206.372512 -219.12809) (xy 206.418173 -219.150821) (xy 206.439262 -219.16517)
			(xy 206.445805 -219.169442) (xy 206.460666 -219.174237) (xy 206.468472 -219.174568) (xy 206.9846 -219.174568)
			(xy 206.989857 -219.175092) (xy 206.997298 -219.18252) (xy 206.997808 -219.187776) (xy 206.997808 -219.188284)
			(xy 206.997808 -219.682314) (xy 268.898116 -219.682314) (xy 268.898116 -219.187776) (xy 268.898581 -219.182505)
			(xy 268.906051 -219.175062) (xy 268.911324 -219.174568) (xy 268.911832 -219.174568) (xy 269.427706 -219.174568)
			(xy 269.435517 -219.174262) (xy 269.450389 -219.169471) (xy 269.456916 -219.16517) (xy 269.478005 -219.150821)
			(xy 269.523666 -219.12809) (xy 269.572272 -219.112631) (xy 269.622675 -219.104808) (xy 269.673681 -219.104808)
			(xy 269.724084 -219.112631) (xy 269.77269 -219.12809) (xy 269.818351 -219.150821) (xy 269.83944 -219.16517)
			(xy 269.845965 -219.169472) (xy 269.86084 -219.174249) (xy 269.86865 -219.174568) (xy 270.384778 -219.174568)
			(xy 270.390086 -219.175041) (xy 270.39766 -219.182478) (xy 270.39824 -219.187776) (xy 270.39824 -219.682314)
			(xy 270.398225 -219.682568) (xy 276.442424 -219.682568) (xy 276.442424 -219.68206) (xy 276.442424 -219.187776)
			(xy 276.442714 -219.182433) (xy 276.450287 -219.174891) (xy 276.455632 -219.174568) (xy 276.97176 -219.174568)
			(xy 276.979569 -219.174242) (xy 276.994441 -219.169465) (xy 277.00097 -219.16517) (xy 277.022059 -219.150821)
			(xy 277.06772 -219.12809) (xy 277.116326 -219.112631) (xy 277.166729 -219.104808) (xy 277.217735 -219.104808)
			(xy 277.268138 -219.112631) (xy 277.316744 -219.12809) (xy 277.362405 -219.150821) (xy 277.383494 -219.16517)
			(xy 277.390029 -219.169455) (xy 277.404896 -219.174242) (xy 277.412704 -219.174568) (xy 277.928832 -219.174568)
			(xy 277.934093 -219.175071) (xy 277.941532 -219.182515) (xy 277.94204 -219.187776) (xy 277.94204 -219.682314)
			(xy 277.942018 -219.682568) (xy 283.986224 -219.682568) (xy 283.986224 -219.68206) (xy 283.986224 -219.187776)
			(xy 283.986514 -219.182433) (xy 283.994087 -219.174891) (xy 283.999432 -219.174568) (xy 284.51556 -219.174568)
			(xy 284.523369 -219.174242) (xy 284.538241 -219.169465) (xy 284.54477 -219.16517) (xy 284.565859 -219.150821)
			(xy 284.61152 -219.12809) (xy 284.660126 -219.112631) (xy 284.710529 -219.104808) (xy 284.761535 -219.104808)
			(xy 284.811938 -219.112631) (xy 284.860544 -219.12809) (xy 284.906205 -219.150821) (xy 284.927294 -219.16517)
			(xy 284.933829 -219.169455) (xy 284.948696 -219.174242) (xy 284.956504 -219.174568) (xy 285.472632 -219.174568)
			(xy 285.477893 -219.175071) (xy 285.485332 -219.182515) (xy 285.48584 -219.187776) (xy 285.48584 -219.682314)
			(xy 291.530024 -219.682314) (xy 291.530024 -219.187776) (xy 291.530314 -219.182433) (xy 291.537887 -219.174891)
			(xy 291.543232 -219.174568) (xy 291.54374 -219.174568) (xy 292.059614 -219.174568) (xy 292.067425 -219.174266)
			(xy 292.082297 -219.169473) (xy 292.088824 -219.16517) (xy 292.109913 -219.150821) (xy 292.155574 -219.12809)
			(xy 292.20418 -219.112631) (xy 292.254583 -219.104808) (xy 292.305589 -219.104808) (xy 292.355992 -219.112631)
			(xy 292.404598 -219.12809) (xy 292.450259 -219.150821) (xy 292.471348 -219.16517) (xy 292.477871 -219.169475)
			(xy 292.492748 -219.17425) (xy 292.500558 -219.174568) (xy 293.016686 -219.174568) (xy 293.021995 -219.175036)
			(xy 293.029568 -219.182476) (xy 293.030148 -219.187776) (xy 293.030148 -219.682314) (xy 293.030125 -219.682568)
			(xy 299.074332 -219.682568) (xy 299.074332 -219.68206) (xy 299.074332 -219.187776) (xy 299.074615 -219.182431)
			(xy 299.082193 -219.174889) (xy 299.08754 -219.174568) (xy 299.603668 -219.174568) (xy 299.611477 -219.174246)
			(xy 299.626349 -219.169466) (xy 299.632878 -219.16517) (xy 299.653967 -219.150821) (xy 299.699628 -219.12809)
			(xy 299.748234 -219.112631) (xy 299.798637 -219.104808) (xy 299.849643 -219.104808) (xy 299.900046 -219.112631)
			(xy 299.948652 -219.12809) (xy 299.994313 -219.150821) (xy 300.015402 -219.16517) (xy 300.021936 -219.169458)
			(xy 300.036804 -219.174243) (xy 300.044612 -219.174568) (xy 300.56074 -219.174568) (xy 300.566002 -219.175066)
			(xy 300.573441 -219.182514) (xy 300.573948 -219.187776) (xy 300.573948 -219.682314) (xy 306.618132 -219.682314)
			(xy 306.618132 -219.187776) (xy 306.618415 -219.182431) (xy 306.625993 -219.174889) (xy 306.63134 -219.174568)
			(xy 306.631848 -219.174568) (xy 308.104794 -219.174568) (xy 308.110104 -219.17503) (xy 308.117677 -219.182475)
			(xy 308.118256 -219.187776) (xy 308.118256 -219.682314) (xy 308.118232 -219.682568) (xy 415.718244 -219.682568)
			(xy 415.718244 -219.187776) (xy 415.718774 -219.182522) (xy 415.726199 -219.175084) (xy 415.731452 -219.174568)
			(xy 417.204652 -219.174568) (xy 417.209972 -219.174957) (xy 417.217514 -219.182458) (xy 417.21786 -219.187776)
			(xy 417.21786 -219.682314) (xy 423.262044 -219.682314) (xy 423.262044 -219.187776) (xy 423.262574 -219.182522)
			(xy 423.269999 -219.175084) (xy 423.275252 -219.174568) (xy 423.27576 -219.174568) (xy 423.791634 -219.174568)
			(xy 423.799442 -219.174231) (xy 423.814314 -219.169462) (xy 423.820844 -219.16517) (xy 423.841933 -219.150821)
			(xy 423.887594 -219.12809) (xy 423.9362 -219.112631) (xy 423.986603 -219.104808) (xy 424.037609 -219.104808)
			(xy 424.088012 -219.112631) (xy 424.136618 -219.12809) (xy 424.182279 -219.150821) (xy 424.203368 -219.16517)
			(xy 424.209909 -219.169445) (xy 424.224772 -219.174238) (xy 424.232578 -219.174568) (xy 424.748706 -219.174568)
			(xy 424.754018 -219.175022) (xy 424.76159 -219.182473) (xy 424.762168 -219.187776) (xy 424.762168 -219.682314)
			(xy 424.762144 -219.682568) (xy 430.806352 -219.682568) (xy 430.806352 -219.68206) (xy 430.806352 -219.187776)
			(xy 430.806875 -219.18252) (xy 430.814305 -219.175081) (xy 430.81956 -219.174568) (xy 431.335688 -219.174568)
			(xy 431.343498 -219.174255) (xy 431.35837 -219.169469) (xy 431.364898 -219.16517) (xy 431.385987 -219.150821)
			(xy 431.431648 -219.12809) (xy 431.480254 -219.112631) (xy 431.530657 -219.104808) (xy 431.581663 -219.104808)
			(xy 431.632066 -219.112631) (xy 431.680672 -219.12809) (xy 431.726333 -219.150821) (xy 431.747422 -219.16517)
			(xy 431.753951 -219.169465) (xy 431.768823 -219.174246) (xy 431.776632 -219.174568) (xy 432.29276 -219.174568)
			(xy 432.298081 -219.174951) (xy 432.305623 -219.182457) (xy 432.305968 -219.187776) (xy 432.305968 -219.682314)
			(xy 438.350152 -219.682314) (xy 438.350152 -219.187776) (xy 438.350675 -219.18252) (xy 438.358105 -219.175081)
			(xy 438.36336 -219.174568) (xy 438.363868 -219.174568) (xy 438.879742 -219.174568) (xy 438.88755 -219.174235)
			(xy 438.902422 -219.169463) (xy 438.908952 -219.16517) (xy 438.930041 -219.150821) (xy 438.975702 -219.12809)
			(xy 439.024308 -219.112631) (xy 439.074711 -219.104808) (xy 439.125717 -219.104808) (xy 439.17612 -219.112631)
			(xy 439.224726 -219.12809) (xy 439.270387 -219.150821) (xy 439.291476 -219.16517) (xy 439.298015 -219.169448)
			(xy 439.312879 -219.174239) (xy 439.320686 -219.174568) (xy 439.836814 -219.174568) (xy 439.842126 -219.175017)
			(xy 439.849698 -219.182472) (xy 439.850276 -219.187776) (xy 439.850276 -219.682314) (xy 439.850252 -219.682568)
			(xy 445.89446 -219.682568) (xy 445.89446 -219.68206) (xy 445.89446 -219.187776) (xy 445.894976 -219.182518)
			(xy 445.90241 -219.175079) (xy 445.907668 -219.174568) (xy 446.423796 -219.174568) (xy 446.431607 -219.174258)
			(xy 446.446478 -219.16947) (xy 446.453006 -219.16517) (xy 446.474095 -219.150821) (xy 446.519756 -219.12809)
			(xy 446.568362 -219.112631) (xy 446.618765 -219.104808) (xy 446.669771 -219.104808) (xy 446.720174 -219.112631)
			(xy 446.76878 -219.12809) (xy 446.814441 -219.150821) (xy 446.83553 -219.16517) (xy 446.842057 -219.169468)
			(xy 446.856931 -219.174247) (xy 446.86474 -219.174568) (xy 447.380868 -219.174568) (xy 447.38619 -219.174946)
			(xy 447.393731 -219.182455) (xy 447.394076 -219.187776) (xy 447.394076 -219.682314) (xy 447.394053 -219.682568)
			(xy 453.43826 -219.682568) (xy 453.43826 -219.68206) (xy 453.43826 -219.187776) (xy 453.438776 -219.182518)
			(xy 453.44621 -219.175079) (xy 453.451468 -219.174568) (xy 453.967596 -219.174568) (xy 453.975407 -219.174258)
			(xy 453.990278 -219.16947) (xy 453.996806 -219.16517) (xy 454.017895 -219.150821) (xy 454.063556 -219.12809)
			(xy 454.112162 -219.112631) (xy 454.162565 -219.104808) (xy 454.213571 -219.104808) (xy 454.263974 -219.112631)
			(xy 454.31258 -219.12809) (xy 454.358241 -219.150821) (xy 454.37933 -219.16517) (xy 454.385857 -219.169468)
			(xy 454.400731 -219.174247) (xy 454.40854 -219.174568) (xy 454.924668 -219.174568) (xy 454.92999 -219.174946)
			(xy 454.937531 -219.182455) (xy 454.937876 -219.187776) (xy 454.937876 -219.682314) (xy 454.937388 -219.687616)
			(xy 454.92996 -219.695185) (xy 454.924668 -219.695776) (xy 454.408794 -219.695776) (xy 454.400982 -219.696074)
			(xy 454.386111 -219.70087) (xy 454.379584 -219.705174) (xy 454.358466 -219.719529) (xy 454.312741 -219.742254)
			(xy 454.264066 -219.757682) (xy 454.213599 -219.765447) (xy 454.188068 -219.76588) (xy 454.162537 -219.765457)
			(xy 454.112073 -219.757676) (xy 454.063401 -219.742243) (xy 454.017674 -219.719523) (xy 453.996552 -219.705174)
			(xy 453.990026 -219.700873) (xy 453.975152 -219.696095) (xy 453.967342 -219.695776) (xy 453.451468 -219.695776)
			(xy 453.446194 -219.695323) (xy 453.438751 -219.687845) (xy 453.43826 -219.682568) (xy 447.394053 -219.682568)
			(xy 447.393588 -219.687616) (xy 447.38616 -219.695185) (xy 447.380868 -219.695776) (xy 446.864994 -219.695776)
			(xy 446.857182 -219.696074) (xy 446.842311 -219.70087) (xy 446.835784 -219.705174) (xy 446.814666 -219.719529)
			(xy 446.768941 -219.742254) (xy 446.720266 -219.757682) (xy 446.669799 -219.765447) (xy 446.644268 -219.76588)
			(xy 446.618737 -219.765457) (xy 446.568273 -219.757676) (xy 446.519601 -219.742243) (xy 446.473874 -219.719523)
			(xy 446.452752 -219.705174) (xy 446.446226 -219.700873) (xy 446.431352 -219.696095) (xy 446.423542 -219.695776)
			(xy 445.907668 -219.695776) (xy 445.902394 -219.695323) (xy 445.894951 -219.687845) (xy 445.89446 -219.682568)
			(xy 439.850252 -219.682568) (xy 439.84976 -219.687676) (xy 439.842176 -219.69526) (xy 439.836814 -219.695776)
			(xy 439.32094 -219.695776) (xy 439.31313 -219.696094) (xy 439.298258 -219.700876) (xy 439.29173 -219.705174)
			(xy 439.270627 -219.719552) (xy 439.224896 -219.742272) (xy 439.176217 -219.757694) (xy 439.125747 -219.765451)
			(xy 439.100214 -219.76588) (xy 439.074684 -219.765434) (xy 439.024221 -219.75766) (xy 438.975548 -219.742234)
			(xy 438.92982 -219.71952) (xy 438.908698 -219.705174) (xy 438.902162 -219.70089) (xy 438.887296 -219.696101)
			(xy 438.879488 -219.695776) (xy 438.363614 -219.695776) (xy 438.358255 -219.695242) (xy 438.350669 -219.687672)
			(xy 438.350152 -219.682314) (xy 432.305968 -219.682314) (xy 432.305487 -219.687618) (xy 432.298054 -219.695188)
			(xy 432.29276 -219.695776) (xy 431.776886 -219.695776) (xy 431.769074 -219.696071) (xy 431.754202 -219.700869)
			(xy 431.747676 -219.705174) (xy 431.72656 -219.719532) (xy 431.680834 -219.742256) (xy 431.632159 -219.757684)
			(xy 431.581691 -219.765448) (xy 431.55616 -219.76588) (xy 431.530629 -219.765461) (xy 431.480165 -219.757679)
			(xy 431.431492 -219.742245) (xy 431.385765 -219.719524) (xy 431.364644 -219.705174) (xy 431.35812 -219.70087)
			(xy 431.343244 -219.696093) (xy 431.335434 -219.695776) (xy 430.81956 -219.695776) (xy 430.814285 -219.695329)
			(xy 430.806842 -219.687846) (xy 430.806352 -219.682568) (xy 424.762144 -219.682568) (xy 424.761659 -219.687678)
			(xy 424.75407 -219.695263) (xy 424.748706 -219.695776) (xy 424.232832 -219.695776) (xy 424.225022 -219.696091)
			(xy 424.21015 -219.700875) (xy 424.203622 -219.705174) (xy 424.182494 -219.719513) (xy 424.136772 -219.742241)
			(xy 424.088101 -219.757674) (xy 424.037636 -219.765444) (xy 424.012106 -219.76588) (xy 423.986576 -219.765438)
			(xy 423.936113 -219.757663) (xy 423.88744 -219.742236) (xy 423.841712 -219.719521) (xy 423.82059 -219.705174)
			(xy 423.814056 -219.700887) (xy 423.799188 -219.6961) (xy 423.79138 -219.695776) (xy 423.275506 -219.695776)
			(xy 423.270146 -219.695247) (xy 423.262561 -219.687673) (xy 423.262044 -219.682314) (xy 417.21786 -219.682314)
			(xy 417.217386 -219.68762) (xy 417.209948 -219.69519) (xy 417.204652 -219.695776) (xy 415.731452 -219.695776)
			(xy 415.726176 -219.695334) (xy 415.718734 -219.687847) (xy 415.718244 -219.682568) (xy 308.118232 -219.682568)
			(xy 308.117758 -219.687681) (xy 308.110162 -219.695266) (xy 308.104794 -219.695776) (xy 306.631594 -219.695776)
			(xy 306.626233 -219.695255) (xy 306.618648 -219.687675) (xy 306.618132 -219.682314) (xy 300.573948 -219.682314)
			(xy 300.573485 -219.687623) (xy 300.56604 -219.695193) (xy 300.56074 -219.695776) (xy 300.044866 -219.695776)
			(xy 300.037057 -219.696105) (xy 300.022185 -219.700879) (xy 300.015656 -219.705174) (xy 299.994546 -219.719541)
			(xy 299.948818 -219.742263) (xy 299.900141 -219.757688) (xy 299.849672 -219.765449) (xy 299.82414 -219.76588)
			(xy 299.798611 -219.765421) (xy 299.748148 -219.757651) (xy 299.699475 -219.742229) (xy 299.653747 -219.719518)
			(xy 299.632624 -219.705174) (xy 299.626082 -219.7009) (xy 299.61122 -219.696105) (xy 299.603414 -219.695776)
			(xy 299.08754 -219.695776) (xy 299.082205 -219.695443) (xy 299.07466 -219.687902) (xy 299.074332 -219.682568)
			(xy 293.030125 -219.682568) (xy 293.029657 -219.687683) (xy 293.022056 -219.695269) (xy 293.016686 -219.695776)
			(xy 292.500812 -219.695776) (xy 292.493001 -219.696082) (xy 292.478129 -219.700872) (xy 292.471602 -219.705174)
			(xy 292.450479 -219.719521) (xy 292.404756 -219.742248) (xy 292.356083 -219.757678) (xy 292.305617 -219.765446)
			(xy 292.280086 -219.76588) (xy 292.254556 -219.765448) (xy 292.204092 -219.75767) (xy 292.155419 -219.74224)
			(xy 292.109692 -219.719522) (xy 292.08857 -219.705174) (xy 292.08204 -219.70088) (xy 292.067169 -219.696097)
			(xy 292.05936 -219.695776) (xy 291.543486 -219.695776) (xy 291.538124 -219.69526) (xy 291.53054 -219.687676)
			(xy 291.530024 -219.682314) (xy 285.48584 -219.682314) (xy 285.485384 -219.687624) (xy 285.477934 -219.695196)
			(xy 285.472632 -219.695776) (xy 284.956758 -219.695776) (xy 284.948949 -219.696102) (xy 284.934077 -219.700878)
			(xy 284.927548 -219.705174) (xy 284.90644 -219.719545) (xy 284.860711 -219.742266) (xy 284.812034 -219.75769)
			(xy 284.761564 -219.76545) (xy 284.736032 -219.76588) (xy 284.710503 -219.765425) (xy 284.66004 -219.757654)
			(xy 284.611367 -219.74223) (xy 284.565639 -219.719519) (xy 284.544516 -219.705174) (xy 284.537976 -219.700897)
			(xy 284.523113 -219.696104) (xy 284.515306 -219.695776) (xy 283.999432 -219.695776) (xy 283.994096 -219.695448)
			(xy 283.986552 -219.687904) (xy 283.986224 -219.682568) (xy 277.942018 -219.682568) (xy 277.941584 -219.687624)
			(xy 277.934134 -219.695196) (xy 277.928832 -219.695776) (xy 277.412958 -219.695776) (xy 277.405149 -219.696102)
			(xy 277.390277 -219.700878) (xy 277.383748 -219.705174) (xy 277.36264 -219.719545) (xy 277.316911 -219.742266)
			(xy 277.268234 -219.75769) (xy 277.217764 -219.76545) (xy 277.192232 -219.76588) (xy 277.166703 -219.765425)
			(xy 277.11624 -219.757654) (xy 277.067567 -219.74223) (xy 277.021839 -219.719519) (xy 277.000716 -219.705174)
			(xy 276.994176 -219.700897) (xy 276.979313 -219.696104) (xy 276.971506 -219.695776) (xy 276.455632 -219.695776)
			(xy 276.450296 -219.695448) (xy 276.442752 -219.687904) (xy 276.442424 -219.682568) (xy 270.398225 -219.682568)
			(xy 270.397928 -219.687756) (xy 270.390221 -219.695442) (xy 270.384778 -219.695776) (xy 269.868904 -219.695776)
			(xy 269.861093 -219.696079) (xy 269.846221 -219.700871) (xy 269.839694 -219.705174) (xy 269.818573 -219.719525)
			(xy 269.772849 -219.74225) (xy 269.724175 -219.75768) (xy 269.673709 -219.765447) (xy 269.648178 -219.76588)
			(xy 269.622647 -219.765452) (xy 269.572183 -219.757673) (xy 269.523511 -219.742241) (xy 269.477784 -219.719522)
			(xy 269.456662 -219.705174) (xy 269.450134 -219.700877) (xy 269.435261 -219.696096) (xy 269.427452 -219.695776)
			(xy 268.911578 -219.695776) (xy 268.906215 -219.695266) (xy 268.898631 -219.687677) (xy 268.898116 -219.682314)
			(xy 206.997808 -219.682314) (xy 206.997808 -219.682568) (xy 206.997452 -219.687896) (xy 206.989927 -219.695439)
			(xy 206.9846 -219.695776) (xy 206.468726 -219.695776) (xy 206.460849 -219.696035) (xy 206.445845 -219.700838)
			(xy 206.439262 -219.705174) (xy 206.418188 -219.71957) (xy 206.372541 -219.742397) (xy 206.323934 -219.757953)
			(xy 206.273517 -219.765871) (xy 206.248 -219.766388) (xy 206.222479 -219.765918) (xy 206.172051 -219.758018)
			(xy 206.12344 -219.742452) (xy 206.077802 -219.719592) (xy 206.056738 -219.705174) (xy 206.050135 -219.700878)
			(xy 206.035144 -219.696078) (xy 206.027274 -219.695776) (xy 205.5114 -219.695776) (xy 205.50606 -219.69547)
			(xy 205.498517 -219.687909) (xy 205.498192 -219.682568) (xy 199.454008 -219.682568) (xy 199.453652 -219.687896)
			(xy 199.446127 -219.695439) (xy 199.4408 -219.695776) (xy 198.924926 -219.695776) (xy 198.917049 -219.696035)
			(xy 198.902045 -219.700838) (xy 198.895462 -219.705174) (xy 198.874388 -219.71957) (xy 198.828741 -219.742397)
			(xy 198.780134 -219.757953) (xy 198.729717 -219.765871) (xy 198.7042 -219.766388) (xy 198.678679 -219.765918)
			(xy 198.628251 -219.758018) (xy 198.57964 -219.742452) (xy 198.534002 -219.719592) (xy 198.512938 -219.705174)
			(xy 198.506335 -219.700878) (xy 198.491344 -219.696078) (xy 198.483474 -219.695776) (xy 197.9676 -219.695776)
			(xy 197.96226 -219.69547) (xy 197.954717 -219.687909) (xy 197.954392 -219.682568) (xy 191.910208 -219.682568)
			(xy 191.909852 -219.687896) (xy 191.902327 -219.695439) (xy 191.897 -219.695776) (xy 191.896492 -219.695776)
			(xy 191.380872 -219.695776) (xy 191.372997 -219.696055) (xy 191.357992 -219.700844) (xy 191.351408 -219.705174)
			(xy 191.330349 -219.719593) (xy 191.284697 -219.742415) (xy 191.236085 -219.757965) (xy 191.185664 -219.765875)
			(xy 191.160146 -219.766388) (xy 191.134626 -219.765895) (xy 191.084199 -219.758001) (xy 191.035587 -219.742443)
			(xy 190.989949 -219.719589) (xy 190.968884 -219.705174) (xy 190.962294 -219.700857) (xy 190.947293 -219.69607)
			(xy 190.93942 -219.695776) (xy 190.423546 -219.695776) (xy 190.418251 -219.695248) (xy 190.410678 -219.68785)
			(xy 190.410084 -219.682568) (xy 184.3659 -219.682568) (xy 184.365551 -219.687898) (xy 184.358021 -219.695441)
			(xy 184.352692 -219.695776) (xy 183.836818 -219.695776) (xy 183.828944 -219.696075) (xy 183.81394 -219.70085)
			(xy 183.807354 -219.705174) (xy 183.786282 -219.719573) (xy 183.740635 -219.742399) (xy 183.692027 -219.757955)
			(xy 183.641609 -219.765872) (xy 183.616092 -219.766388) (xy 183.590573 -219.765871) (xy 183.540147 -219.757985)
			(xy 183.491535 -219.742433) (xy 183.445896 -219.719586) (xy 183.42483 -219.705174) (xy 183.418229 -219.700875)
			(xy 183.403236 -219.696077) (xy 183.395366 -219.695776) (xy 182.879492 -219.695776) (xy 182.874151 -219.695476)
			(xy 182.866608 -219.68791) (xy 182.866284 -219.682568) (xy 176.8221 -219.682568) (xy 176.821751 -219.687898)
			(xy 176.814221 -219.695441) (xy 176.808892 -219.695776) (xy 176.808384 -219.695776) (xy 176.292764 -219.695776)
			(xy 176.284888 -219.696052) (xy 176.269884 -219.700843) (xy 176.2633 -219.705174) (xy 176.242215 -219.719554)
			(xy 176.196573 -219.742384) (xy 176.147969 -219.757945) (xy 176.097554 -219.765868) (xy 176.072038 -219.766388)
			(xy 176.046518 -219.765899) (xy 175.996091 -219.758004) (xy 175.947479 -219.742444) (xy 175.901841 -219.719589)
			(xy 175.880776 -219.705174) (xy 175.874187 -219.700854) (xy 175.859185 -219.696069) (xy 175.851312 -219.695776)
			(xy 175.335438 -219.695776) (xy 175.330142 -219.695253) (xy 175.32257 -219.687852) (xy 175.321976 -219.682568)
			(xy 169.277792 -219.682568) (xy 169.27745 -219.6879) (xy 169.269915 -219.695444) (xy 169.264584 -219.695776)
			(xy 167.791384 -219.695776) (xy 167.786042 -219.695481) (xy 167.7785 -219.687912) (xy 167.778176 -219.682568)
			(xy 130.812197 -219.682568) (xy 130.820795 -219.711849) (xy 130.828557 -219.765831) (xy 130.828557 -219.820369)
			(xy 130.820795 -219.874351) (xy 130.80543 -219.926678) (xy 130.782774 -219.976287) (xy 130.753288 -220.022166)
			(xy 130.717574 -220.063382) (xy 130.676357 -220.099096) (xy 130.630476 -220.12858) (xy 130.580867 -220.151234)
			(xy 130.528539 -220.166598) (xy 130.474557 -220.174357) (xy 130.447288 -220.17482) (xy 129.431288 -220.17482)
			(xy 129.404016 -220.174417) (xy 129.350028 -220.166653) (xy 129.297694 -220.151285) (xy 129.24808 -220.128625)
			(xy 129.202196 -220.099136) (xy 129.160975 -220.063417) (xy 129.125257 -220.022195) (xy 129.095769 -219.976309)
			(xy 129.073111 -219.926695) (xy 129.057745 -219.87436) (xy 129.049982 -219.820372) (xy 2.509012 -219.820372)
			(xy 2.509012 -220.532452) (xy 16.85798 -220.532452) (xy 16.85798 -220.037914) (xy 16.858293 -220.032471)
			(xy 16.865998 -220.024782) (xy 16.871442 -220.024452) (xy 17.38757 -220.024452) (xy 17.39538 -220.024133)
			(xy 17.410251 -220.019352) (xy 17.41678 -220.015054) (xy 17.437869 -220.000705) (xy 17.48353 -219.977974)
			(xy 17.532136 -219.962515) (xy 17.582539 -219.954692) (xy 17.633545 -219.954692) (xy 17.683948 -219.962515)
			(xy 17.732554 -219.977974) (xy 17.778215 -220.000705) (xy 17.799304 -220.015054) (xy 17.805838 -220.019341)
			(xy 17.820706 -220.024127) (xy 17.828514 -220.024452) (xy 18.344642 -220.024452) (xy 18.350014 -220.024924)
			(xy 18.357599 -220.03254) (xy 18.358104 -220.037914) (xy 18.358104 -220.532452) (xy 20.958048 -220.532452)
			(xy 20.958048 -220.037914) (xy 20.95839 -220.032479) (xy 20.966075 -220.024791) (xy 20.97151 -220.024452)
			(xy 21.487638 -220.024452) (xy 21.495447 -220.02412) (xy 21.510318 -220.019347) (xy 21.516848 -220.015054)
			(xy 21.537937 -220.000705) (xy 21.583598 -219.977974) (xy 21.632204 -219.962515) (xy 21.682607 -219.954692)
			(xy 21.733613 -219.954692) (xy 21.784016 -219.962515) (xy 21.832622 -219.977974) (xy 21.878283 -220.000705)
			(xy 21.899372 -220.015054) (xy 21.905913 -220.019329) (xy 21.920776 -220.024123) (xy 21.928582 -220.024452)
			(xy 22.44471 -220.024452) (xy 22.45015 -220.024774) (xy 22.457836 -220.032474) (xy 22.458172 -220.037914)
			(xy 22.458172 -220.532452) (xy 24.402288 -220.532452) (xy 24.402288 -220.037914) (xy 24.402738 -220.0326)
			(xy 24.410191 -220.025026) (xy 24.415496 -220.024452) (xy 24.931624 -220.024452) (xy 24.939436 -220.024157)
			(xy 24.954308 -220.019359) (xy 24.960834 -220.015054) (xy 24.981923 -220.000705) (xy 25.027584 -219.977974)
			(xy 25.07619 -219.962515) (xy 25.126593 -219.954692) (xy 25.177599 -219.954692) (xy 25.228002 -219.962515)
			(xy 25.276608 -219.977974) (xy 25.322269 -220.000705) (xy 25.343358 -220.015054) (xy 25.34988 -220.019362)
			(xy 25.364757 -220.024135) (xy 25.372568 -220.024452) (xy 25.888696 -220.024452) (xy 25.893949 -220.024993)
			(xy 25.901389 -220.032409) (xy 25.901904 -220.03766) (xy 25.901904 -220.038168) (xy 25.901904 -220.532452)
			(xy 28.502356 -220.532452) (xy 28.502356 -220.037914) (xy 28.502834 -220.032608) (xy 28.510268 -220.025035)
			(xy 28.515564 -220.024452) (xy 29.031692 -220.024452) (xy 29.039503 -220.024143) (xy 29.054374 -220.019354)
			(xy 29.060902 -220.015054) (xy 29.081991 -220.000705) (xy 29.127652 -219.977974) (xy 29.176258 -219.962515)
			(xy 29.226661 -219.954692) (xy 29.277667 -219.954692) (xy 29.32807 -219.962515) (xy 29.376676 -219.977974)
			(xy 29.422337 -220.000705) (xy 29.443426 -220.015054) (xy 29.449955 -220.019349) (xy 29.464827 -220.024131)
			(xy 29.472636 -220.024452) (xy 29.988764 -220.024452) (xy 29.994013 -220.025015) (xy 30.001455 -220.032414)
			(xy 30.001972 -220.03766) (xy 30.001972 -220.038168) (xy 30.001972 -220.532452) (xy 31.946088 -220.532452)
			(xy 31.946088 -220.037914) (xy 31.946538 -220.0326) (xy 31.953991 -220.025026) (xy 31.959296 -220.024452)
			(xy 32.475424 -220.024452) (xy 32.483236 -220.024157) (xy 32.498108 -220.019359) (xy 32.504634 -220.015054)
			(xy 32.525723 -220.000705) (xy 32.571384 -219.977974) (xy 32.61999 -219.962515) (xy 32.670393 -219.954692)
			(xy 32.721399 -219.954692) (xy 32.771802 -219.962515) (xy 32.820408 -219.977974) (xy 32.866069 -220.000705)
			(xy 32.887158 -220.015054) (xy 32.89368 -220.019362) (xy 32.908557 -220.024135) (xy 32.916368 -220.024452)
			(xy 33.432496 -220.024452) (xy 33.437749 -220.024993) (xy 33.445189 -220.032409) (xy 33.445704 -220.03766)
			(xy 33.445704 -220.038168) (xy 33.445704 -220.532452) (xy 36.046156 -220.532452) (xy 36.046156 -220.037914)
			(xy 36.046634 -220.032608) (xy 36.054068 -220.025035) (xy 36.059364 -220.024452) (xy 36.575492 -220.024452)
			(xy 36.583303 -220.024143) (xy 36.598174 -220.019354) (xy 36.604702 -220.015054) (xy 36.625791 -220.000705)
			(xy 36.671452 -219.977974) (xy 36.720058 -219.962515) (xy 36.770461 -219.954692) (xy 36.821467 -219.954692)
			(xy 36.87187 -219.962515) (xy 36.920476 -219.977974) (xy 36.966137 -220.000705) (xy 36.987226 -220.015054)
			(xy 36.993755 -220.019349) (xy 37.008627 -220.024131) (xy 37.016436 -220.024452) (xy 37.532564 -220.024452)
			(xy 37.537813 -220.025015) (xy 37.545255 -220.032414) (xy 37.545772 -220.03766) (xy 37.545772 -220.038168)
			(xy 37.545772 -220.532452) (xy 39.489888 -220.532452) (xy 39.489888 -220.037914) (xy 39.490455 -220.032564)
			(xy 39.498002 -220.02498) (xy 39.50335 -220.024452) (xy 40.019478 -220.024452) (xy 40.027288 -220.024137)
			(xy 40.04216 -220.019353) (xy 40.048688 -220.015054) (xy 40.069777 -220.000705) (xy 40.115438 -219.977974)
			(xy 40.164044 -219.962515) (xy 40.214447 -219.954692) (xy 40.265453 -219.954692) (xy 40.315856 -219.962515)
			(xy 40.364462 -219.977974) (xy 40.410123 -220.000705) (xy 40.431212 -220.015054) (xy 40.437744 -220.019344)
			(xy 40.452614 -220.024129) (xy 40.460422 -220.024452) (xy 40.97655 -220.024452) (xy 40.981923 -220.024919)
			(xy 40.989507 -220.032538) (xy 40.990012 -220.037914) (xy 40.990012 -220.532452) (xy 43.589956 -220.532452)
			(xy 43.589956 -220.037914) (xy 43.59029 -220.032477) (xy 43.597981 -220.024789) (xy 43.603418 -220.024452)
			(xy 44.119546 -220.024452) (xy 44.127355 -220.024123) (xy 44.142227 -220.019348) (xy 44.148756 -220.015054)
			(xy 44.169845 -220.000705) (xy 44.215506 -219.977974) (xy 44.264112 -219.962515) (xy 44.314515 -219.954692)
			(xy 44.365521 -219.954692) (xy 44.415924 -219.962515) (xy 44.46453 -219.977974) (xy 44.510191 -220.000705)
			(xy 44.53128 -220.015054) (xy 44.537819 -220.019332) (xy 44.552683 -220.024124) (xy 44.56049 -220.024452)
			(xy 45.076618 -220.024452) (xy 45.081988 -220.02494) (xy 45.089573 -220.032543) (xy 45.09008 -220.037914)
			(xy 45.09008 -220.532452) (xy 47.034196 -220.532452) (xy 47.034196 -220.037914) (xy 47.034727 -220.032622)
			(xy 47.042124 -220.025052) (xy 47.047404 -220.024452) (xy 47.563532 -220.024452) (xy 47.57134 -220.024117)
			(xy 47.586212 -220.019347) (xy 47.592742 -220.015054) (xy 47.613831 -220.000705) (xy 47.659492 -219.977974)
			(xy 47.708098 -219.962515) (xy 47.758501 -219.954692) (xy 47.809507 -219.954692) (xy 47.85991 -219.962515)
			(xy 47.908516 -219.977974) (xy 47.954177 -220.000705) (xy 47.975266 -220.015054) (xy 47.981809 -220.019326)
			(xy 47.99667 -220.024122) (xy 48.004476 -220.024452) (xy 48.520604 -220.024452) (xy 48.525858 -220.024988)
			(xy 48.533298 -220.032408) (xy 48.533812 -220.03766) (xy 48.533812 -220.038168) (xy 48.533812 -220.532452)
			(xy 51.134264 -220.532452) (xy 51.134264 -220.037914) (xy 51.134735 -220.032606) (xy 51.142174 -220.025033)
			(xy 51.147472 -220.024452) (xy 51.6636 -220.024452) (xy 51.671411 -220.024147) (xy 51.686283 -220.019356)
			(xy 51.69281 -220.015054) (xy 51.713899 -220.000705) (xy 51.75956 -219.977974) (xy 51.808166 -219.962515)
			(xy 51.858569 -219.954692) (xy 51.909575 -219.954692) (xy 51.959978 -219.962515) (xy 52.008584 -219.977974)
			(xy 52.054245 -220.000705) (xy 52.075334 -220.015054) (xy 52.081861 -220.019352) (xy 52.096734 -220.024132)
			(xy 52.104544 -220.024452) (xy 52.620672 -220.024452) (xy 52.625922 -220.025009) (xy 52.633364 -220.032413)
			(xy 52.63388 -220.03766) (xy 52.63388 -220.038168) (xy 52.63388 -220.532452) (xy 54.577996 -220.532452)
			(xy 54.577996 -220.037914) (xy 54.578555 -220.032562) (xy 54.586108 -220.024978) (xy 54.591458 -220.024452)
			(xy 56.064658 -220.024452) (xy 56.070091 -220.024809) (xy 56.07778 -220.032482) (xy 56.07812 -220.037914)
			(xy 56.07812 -220.532452) (xy 58.678064 -220.532452) (xy 58.678064 -220.037914) (xy 58.678391 -220.032475)
			(xy 58.686086 -220.024786) (xy 58.691526 -220.024452) (xy 60.164726 -220.024452) (xy 60.170096 -220.024935)
			(xy 60.177681 -220.032542) (xy 60.178188 -220.037914) (xy 60.178188 -220.532452) (xy 163.678108 -220.532452)
			(xy 163.678108 -220.037914) (xy 163.678629 -220.032619) (xy 163.686033 -220.025049) (xy 163.691316 -220.024452)
			(xy 165.164516 -220.024452) (xy 165.169771 -220.02498) (xy 165.177211 -220.032406) (xy 165.177724 -220.03766)
			(xy 165.177724 -220.038168) (xy 165.177724 -220.532452) (xy 167.778176 -220.532452) (xy 167.778176 -220.037914)
			(xy 167.778637 -220.032603) (xy 167.786082 -220.025029) (xy 167.791384 -220.024452) (xy 169.264584 -220.024452)
			(xy 169.269835 -220.025001) (xy 169.277276 -220.032411) (xy 169.277792 -220.03766) (xy 169.277792 -220.532452)
			(xy 171.221908 -220.532452) (xy 171.221908 -220.037914) (xy 171.222457 -220.032559) (xy 171.230017 -220.024974)
			(xy 171.23537 -220.024452) (xy 171.751498 -220.024452) (xy 171.759309 -220.024146) (xy 171.774181 -220.019356)
			(xy 171.780708 -220.015054) (xy 171.801797 -220.000705) (xy 171.847458 -219.977974) (xy 171.896064 -219.962515)
			(xy 171.946467 -219.954692) (xy 171.997473 -219.954692) (xy 172.047876 -219.962515) (xy 172.096482 -219.977974)
			(xy 172.142143 -220.000705) (xy 172.163232 -220.015054) (xy 172.16976 -220.019352) (xy 172.184633 -220.024131)
			(xy 172.192442 -220.024452) (xy 172.70857 -220.024452) (xy 172.714004 -220.024801) (xy 172.721693 -220.03248)
			(xy 172.722032 -220.037914) (xy 172.722032 -220.532452) (xy 175.321976 -220.532452) (xy 175.321976 -220.037914)
			(xy 175.322292 -220.032472) (xy 175.329995 -220.024783) (xy 175.335438 -220.024452) (xy 175.851566 -220.024452)
			(xy 175.859376 -220.024132) (xy 175.874247 -220.019351) (xy 175.880776 -220.015054) (xy 175.901865 -220.000705)
			(xy 175.947526 -219.977974) (xy 175.996132 -219.962515) (xy 176.046535 -219.954692) (xy 176.097541 -219.954692)
			(xy 176.147944 -219.962515) (xy 176.19655 -219.977974) (xy 176.242211 -220.000705) (xy 176.2633 -220.015054)
			(xy 176.269835 -220.019339) (xy 176.284702 -220.024127) (xy 176.29251 -220.024452) (xy 176.808638 -220.024452)
			(xy 176.81401 -220.024927) (xy 176.821594 -220.03254) (xy 176.8221 -220.037914) (xy 176.8221 -220.532452)
			(xy 178.766216 -220.532452) (xy 178.766216 -220.037914) (xy 178.76673 -220.032617) (xy 178.774139 -220.025047)
			(xy 178.779424 -220.024452) (xy 179.295552 -220.024452) (xy 179.303361 -220.024126) (xy 179.318233 -220.019349)
			(xy 179.324762 -220.015054) (xy 179.345851 -220.000705) (xy 179.391512 -219.977974) (xy 179.440118 -219.962515)
			(xy 179.490521 -219.954692) (xy 179.541527 -219.954692) (xy 179.59193 -219.962515) (xy 179.640536 -219.977974)
			(xy 179.686197 -220.000705) (xy 179.707286 -220.015054) (xy 179.713824 -220.019334) (xy 179.728689 -220.024125)
			(xy 179.736496 -220.024452) (xy 180.252624 -220.024452) (xy 180.25788 -220.024975) (xy 180.265319 -220.032405)
			(xy 180.265832 -220.03766) (xy 180.265832 -220.038168) (xy 180.265832 -220.532452) (xy 182.866284 -220.532452)
			(xy 182.866284 -220.037914) (xy 182.866738 -220.032601) (xy 182.874188 -220.025027) (xy 182.879492 -220.024452)
			(xy 183.39562 -220.024452) (xy 183.403432 -220.024155) (xy 183.418303 -220.019359) (xy 183.42483 -220.015054)
			(xy 183.445919 -220.000705) (xy 183.49158 -219.977974) (xy 183.540186 -219.962515) (xy 183.590589 -219.954692)
			(xy 183.641595 -219.954692) (xy 183.691998 -219.962515) (xy 183.740604 -219.977974) (xy 183.786265 -220.000705)
			(xy 183.807354 -220.015054) (xy 183.813877 -220.01936) (xy 183.828753 -220.024135) (xy 183.836564 -220.024452)
			(xy 184.352692 -220.024452) (xy 184.357944 -220.024996) (xy 184.365385 -220.03241) (xy 184.3659 -220.03766)
			(xy 184.3659 -220.038168) (xy 184.3659 -220.532452) (xy 186.310016 -220.532452) (xy 186.310016 -220.037914)
			(xy 186.310557 -220.032557) (xy 186.318122 -220.024972) (xy 186.323478 -220.024452) (xy 186.839606 -220.024452)
			(xy 186.847417 -220.024149) (xy 186.862289 -220.019357) (xy 186.868816 -220.015054) (xy 186.889905 -220.000705)
			(xy 186.935566 -219.977974) (xy 186.984172 -219.962515) (xy 187.034575 -219.954692) (xy 187.085581 -219.954692)
			(xy 187.135984 -219.962515) (xy 187.18459 -219.977974) (xy 187.230251 -220.000705) (xy 187.25134 -220.015054)
			(xy 187.257866 -220.019355) (xy 187.27274 -220.024133) (xy 187.28055 -220.024452) (xy 187.796678 -220.024452)
			(xy 187.802113 -220.024796) (xy 187.809801 -220.032479) (xy 187.81014 -220.037914) (xy 187.81014 -220.532452)
			(xy 190.410084 -220.532452) (xy 190.410084 -220.037914) (xy 190.410393 -220.03247) (xy 190.418101 -220.02478)
			(xy 190.423546 -220.024452) (xy 190.939674 -220.024452) (xy 190.947484 -220.024135) (xy 190.962356 -220.019352)
			(xy 190.968884 -220.015054) (xy 190.989973 -220.000705) (xy 191.035634 -219.977974) (xy 191.08424 -219.962515)
			(xy 191.134643 -219.954692) (xy 191.185649 -219.954692) (xy 191.236052 -219.962515) (xy 191.284658 -219.977974)
			(xy 191.330319 -220.000705) (xy 191.351408 -220.015054) (xy 191.357941 -220.019343) (xy 191.37281 -220.024128)
			(xy 191.380618 -220.024452) (xy 191.896746 -220.024452) (xy 191.902119 -220.024921) (xy 191.909703 -220.032539)
			(xy 191.910208 -220.037914) (xy 191.910208 -220.532452) (xy 193.854324 -220.532452) (xy 193.854324 -220.037914)
			(xy 193.854831 -220.032615) (xy 193.862245 -220.025044) (xy 193.867532 -220.024452) (xy 194.38366 -220.024452)
			(xy 194.391469 -220.024129) (xy 194.406341 -220.01935) (xy 194.41287 -220.015054) (xy 194.433959 -220.000705)
			(xy 194.47962 -219.977974) (xy 194.528226 -219.962515) (xy 194.578629 -219.954692) (xy 194.629635 -219.954692)
			(xy 194.680038 -219.962515) (xy 194.728644 -219.977974) (xy 194.774305 -220.000705) (xy 194.795394 -220.015054)
			(xy 194.80193 -220.019337) (xy 194.816797 -220.024126) (xy 194.824604 -220.024452) (xy 195.340732 -220.024452)
			(xy 195.345989 -220.024969) (xy 195.353427 -220.032403) (xy 195.35394 -220.03766) (xy 195.35394 -220.038168)
			(xy 195.35394 -220.532452) (xy 197.954392 -220.532452) (xy 197.954392 -220.037914) (xy 197.954927 -220.032623)
			(xy 197.962321 -220.025054) (xy 197.9676 -220.024452) (xy 198.483728 -220.024452) (xy 198.49154 -220.024158)
			(xy 198.506412 -220.01936) (xy 198.512938 -220.015054) (xy 198.534027 -220.000705) (xy 198.579688 -219.977974)
			(xy 198.628294 -219.962515) (xy 198.678697 -219.954692) (xy 198.729703 -219.954692) (xy 198.780106 -219.962515)
			(xy 198.828712 -219.977974) (xy 198.874373 -220.000705) (xy 198.895462 -220.015054) (xy 198.902005 -220.019325)
			(xy 198.916866 -220.024121) (xy 198.924672 -220.024452) (xy 199.4408 -220.024452) (xy 199.446053 -220.024991)
			(xy 199.453493 -220.032408) (xy 199.454008 -220.03766) (xy 199.454008 -220.038168) (xy 199.454008 -220.532452)
			(xy 201.398124 -220.532452) (xy 201.398124 -220.037914) (xy 201.398631 -220.032615) (xy 201.406045 -220.025044)
			(xy 201.411332 -220.024452) (xy 201.92746 -220.024452) (xy 201.935269 -220.024129) (xy 201.950141 -220.01935)
			(xy 201.95667 -220.015054) (xy 201.977759 -220.000705) (xy 202.02342 -219.977974) (xy 202.072026 -219.962515)
			(xy 202.122429 -219.954692) (xy 202.173435 -219.954692) (xy 202.223838 -219.962515) (xy 202.272444 -219.977974)
			(xy 202.318105 -220.000705) (xy 202.339194 -220.015054) (xy 202.34573 -220.019337) (xy 202.360597 -220.024126)
			(xy 202.368404 -220.024452) (xy 202.884532 -220.024452) (xy 202.889789 -220.024969) (xy 202.897227 -220.032403)
			(xy 202.89774 -220.03766) (xy 202.89774 -220.038168) (xy 202.89774 -220.532452) (xy 205.498192 -220.532452)
			(xy 205.498192 -220.037914) (xy 205.498727 -220.032623) (xy 205.506121 -220.025054) (xy 205.5114 -220.024452)
			(xy 206.027528 -220.024452) (xy 206.03534 -220.024158) (xy 206.050212 -220.01936) (xy 206.056738 -220.015054)
			(xy 206.077827 -220.000705) (xy 206.123488 -219.977974) (xy 206.172094 -219.962515) (xy 206.222497 -219.954692)
			(xy 206.273503 -219.954692) (xy 206.323906 -219.962515) (xy 206.372512 -219.977974) (xy 206.418173 -220.000705)
			(xy 206.439262 -220.015054) (xy 206.445805 -220.019325) (xy 206.460666 -220.024121) (xy 206.468472 -220.024452)
			(xy 206.9846 -220.024452) (xy 206.989853 -220.024991) (xy 206.997293 -220.032408) (xy 206.997808 -220.03766)
			(xy 206.997808 -220.038168) (xy 206.997808 -220.532198) (xy 264.798048 -220.532198) (xy 264.798048 -220.03766)
			(xy 264.798564 -220.032403) (xy 264.805999 -220.024965) (xy 264.811256 -220.024452) (xy 264.811764 -220.024452)
			(xy 265.327638 -220.024452) (xy 265.335447 -220.02412) (xy 265.350318 -220.019347) (xy 265.356848 -220.015054)
			(xy 265.377937 -220.000705) (xy 265.423598 -219.977974) (xy 265.472204 -219.962515) (xy 265.522607 -219.954692)
			(xy 265.573613 -219.954692) (xy 265.624016 -219.962515) (xy 265.672622 -219.977974) (xy 265.718283 -220.000705)
			(xy 265.739372 -220.015054) (xy 265.745913 -220.019329) (xy 265.760776 -220.024123) (xy 265.768582 -220.024452)
			(xy 266.28471 -220.024452) (xy 266.290018 -220.024918) (xy 266.297589 -220.032361) (xy 266.298172 -220.03766)
			(xy 266.298172 -220.532198) (xy 268.898116 -220.532198) (xy 268.898116 -220.03766) (xy 268.89857 -220.032387)
			(xy 268.906048 -220.024945) (xy 268.911324 -220.024452) (xy 268.911832 -220.024452) (xy 269.427706 -220.024452)
			(xy 269.435517 -220.024149) (xy 269.450389 -220.019357) (xy 269.456916 -220.015054) (xy 269.478005 -220.000705)
			(xy 269.523666 -219.977974) (xy 269.572272 -219.962515) (xy 269.622675 -219.954692) (xy 269.673681 -219.954692)
			(xy 269.724084 -219.962515) (xy 269.77269 -219.977974) (xy 269.818351 -220.000705) (xy 269.83944 -220.015054)
			(xy 269.845966 -220.019355) (xy 269.86084 -220.024133) (xy 269.86865 -220.024452) (xy 270.384778 -220.024452)
			(xy 270.390082 -220.024939) (xy 270.397656 -220.032366) (xy 270.39824 -220.03766) (xy 270.39824 -220.532198)
			(xy 270.398225 -220.532452) (xy 272.342356 -220.532452) (xy 272.342356 -220.531944) (xy 272.342356 -220.03766)
			(xy 272.342864 -220.032401) (xy 272.350305 -220.024963) (xy 272.355564 -220.024452) (xy 272.871692 -220.024452)
			(xy 272.879503 -220.024143) (xy 272.894374 -220.019354) (xy 272.900902 -220.015054) (xy 272.921991 -220.000705)
			(xy 272.967652 -219.977974) (xy 273.016258 -219.962515) (xy 273.066661 -219.954692) (xy 273.117667 -219.954692)
			(xy 273.16807 -219.962515) (xy 273.216676 -219.977974) (xy 273.262337 -220.000705) (xy 273.283426 -220.015054)
			(xy 273.289955 -220.019349) (xy 273.304827 -220.024131) (xy 273.312636 -220.024452) (xy 273.828764 -220.024452)
			(xy 273.834013 -220.025015) (xy 273.841455 -220.032414) (xy 273.841972 -220.03766) (xy 273.841972 -220.532198)
			(xy 273.841948 -220.532452) (xy 276.442424 -220.532452) (xy 276.442424 -220.531944) (xy 276.442424 -220.03766)
			(xy 276.442871 -220.032385) (xy 276.450354 -220.024942) (xy 276.455632 -220.024452) (xy 276.97176 -220.024452)
			(xy 276.979569 -220.024129) (xy 276.994441 -220.01935) (xy 277.00097 -220.015054) (xy 277.022059 -220.000705)
			(xy 277.06772 -219.977974) (xy 277.116326 -219.962515) (xy 277.166729 -219.954692) (xy 277.217735 -219.954692)
			(xy 277.268138 -219.962515) (xy 277.316744 -219.977974) (xy 277.362405 -220.000705) (xy 277.383494 -220.015054)
			(xy 277.39003 -220.019337) (xy 277.404897 -220.024126) (xy 277.412704 -220.024452) (xy 277.928832 -220.024452)
			(xy 277.934089 -220.024969) (xy 277.941527 -220.032403) (xy 277.94204 -220.03766) (xy 277.94204 -220.532198)
			(xy 277.942018 -220.532452) (xy 279.886156 -220.532452) (xy 279.886156 -220.531944) (xy 279.886156 -220.03766)
			(xy 279.886664 -220.032401) (xy 279.894105 -220.024963) (xy 279.899364 -220.024452) (xy 280.415492 -220.024452)
			(xy 280.423303 -220.024143) (xy 280.438174 -220.019354) (xy 280.444702 -220.015054) (xy 280.465791 -220.000705)
			(xy 280.511452 -219.977974) (xy 280.560058 -219.962515) (xy 280.610461 -219.954692) (xy 280.661467 -219.954692)
			(xy 280.71187 -219.962515) (xy 280.760476 -219.977974) (xy 280.806137 -220.000705) (xy 280.827226 -220.015054)
			(xy 280.833755 -220.019349) (xy 280.848627 -220.024131) (xy 280.856436 -220.024452) (xy 281.372564 -220.024452)
			(xy 281.377813 -220.025015) (xy 281.385255 -220.032414) (xy 281.385772 -220.03766) (xy 281.385772 -220.532198)
			(xy 281.385748 -220.532452) (xy 283.986224 -220.532452) (xy 283.986224 -220.531944) (xy 283.986224 -220.03766)
			(xy 283.986671 -220.032385) (xy 283.994154 -220.024942) (xy 283.999432 -220.024452) (xy 284.51556 -220.024452)
			(xy 284.523369 -220.024129) (xy 284.538241 -220.01935) (xy 284.54477 -220.015054) (xy 284.565859 -220.000705)
			(xy 284.61152 -219.977974) (xy 284.660126 -219.962515) (xy 284.710529 -219.954692) (xy 284.761535 -219.954692)
			(xy 284.811938 -219.962515) (xy 284.860544 -219.977974) (xy 284.906205 -220.000705) (xy 284.927294 -220.015054)
			(xy 284.93383 -220.019337) (xy 284.948697 -220.024126) (xy 284.956504 -220.024452) (xy 285.472632 -220.024452)
			(xy 285.477889 -220.024969) (xy 285.485327 -220.032403) (xy 285.48584 -220.03766) (xy 285.48584 -220.532198)
			(xy 287.429956 -220.532198) (xy 287.429956 -220.03766) (xy 287.430464 -220.032401) (xy 287.437905 -220.024963)
			(xy 287.443164 -220.024452) (xy 287.443672 -220.024452) (xy 287.959546 -220.024452) (xy 287.967355 -220.024123)
			(xy 287.982227 -220.019348) (xy 287.988756 -220.015054) (xy 288.009845 -220.000705) (xy 288.055506 -219.977974)
			(xy 288.104112 -219.962515) (xy 288.154515 -219.954692) (xy 288.205521 -219.954692) (xy 288.255924 -219.962515)
			(xy 288.30453 -219.977974) (xy 288.350191 -220.000705) (xy 288.37128 -220.015054) (xy 288.377819 -220.019332)
			(xy 288.392683 -220.024124) (xy 288.40049 -220.024452) (xy 288.916618 -220.024452) (xy 288.921927 -220.024912)
			(xy 288.929498 -220.03236) (xy 288.93008 -220.03766) (xy 288.93008 -220.532198) (xy 291.530024 -220.532198)
			(xy 291.530024 -220.03766) (xy 291.530471 -220.032385) (xy 291.537954 -220.024942) (xy 291.543232 -220.024452)
			(xy 291.54374 -220.024452) (xy 292.059614 -220.024452) (xy 292.067426 -220.024153) (xy 292.082297 -220.019358)
			(xy 292.088824 -220.015054) (xy 292.109913 -220.000705) (xy 292.155574 -219.977974) (xy 292.20418 -219.962515)
			(xy 292.254583 -219.954692) (xy 292.305589 -219.954692) (xy 292.355992 -219.962515) (xy 292.404598 -219.977974)
			(xy 292.450259 -220.000705) (xy 292.471348 -220.015054) (xy 292.477872 -220.019358) (xy 292.492748 -220.024134)
			(xy 292.500558 -220.024452) (xy 293.016686 -220.024452) (xy 293.021991 -220.024934) (xy 293.029564 -220.032365)
			(xy 293.030148 -220.03766) (xy 293.030148 -220.532198) (xy 293.030133 -220.532452) (xy 294.974264 -220.532452)
			(xy 294.974264 -220.531944) (xy 294.974264 -220.03766) (xy 294.974765 -220.032399) (xy 294.982211 -220.02496)
			(xy 294.987472 -220.024452) (xy 295.5036 -220.024452) (xy 295.511411 -220.024147) (xy 295.526283 -220.019356)
			(xy 295.53281 -220.015054) (xy 295.553899 -220.000705) (xy 295.59956 -219.977974) (xy 295.648166 -219.962515)
			(xy 295.698569 -219.954692) (xy 295.749575 -219.954692) (xy 295.799978 -219.962515) (xy 295.848584 -219.977974)
			(xy 295.894245 -220.000705) (xy 295.915334 -220.015054) (xy 295.921861 -220.019352) (xy 295.936734 -220.024132)
			(xy 295.944544 -220.024452) (xy 296.460672 -220.024452) (xy 296.465922 -220.025009) (xy 296.473364 -220.032413)
			(xy 296.47388 -220.03766) (xy 296.47388 -220.532198) (xy 296.473856 -220.532452) (xy 299.074332 -220.532452)
			(xy 299.074332 -220.531944) (xy 299.074332 -220.03766) (xy 299.074772 -220.032383) (xy 299.08226 -220.02494)
			(xy 299.08754 -220.024452) (xy 299.603668 -220.024452) (xy 299.611478 -220.024133) (xy 299.626349 -220.019351)
			(xy 299.632878 -220.015054) (xy 299.653967 -220.000705) (xy 299.699628 -219.977974) (xy 299.748234 -219.962515)
			(xy 299.798637 -219.954692) (xy 299.849643 -219.954692) (xy 299.900046 -219.962515) (xy 299.948652 -219.977974)
			(xy 299.994313 -220.000705) (xy 300.015402 -220.015054) (xy 300.021937 -220.01934) (xy 300.036804 -220.024127)
			(xy 300.044612 -220.024452) (xy 300.56074 -220.024452) (xy 300.565998 -220.024964) (xy 300.573436 -220.032402)
			(xy 300.573948 -220.03766) (xy 300.573948 -220.532198) (xy 302.518064 -220.532198) (xy 302.518064 -220.03766)
			(xy 302.518565 -220.032399) (xy 302.526011 -220.02496) (xy 302.531272 -220.024452) (xy 304.004726 -220.024452)
			(xy 304.010036 -220.024907) (xy 304.017606 -220.032359) (xy 304.018188 -220.03766) (xy 304.018188 -220.532198)
			(xy 306.618132 -220.532198) (xy 306.618132 -220.03766) (xy 306.618572 -220.032383) (xy 306.62606 -220.02494)
			(xy 306.63134 -220.024452) (xy 306.631848 -220.024452) (xy 308.104794 -220.024452) (xy 308.1101 -220.024928)
			(xy 308.117672 -220.032363) (xy 308.118256 -220.03766) (xy 308.118256 -220.532198) (xy 308.11824 -220.532452)
			(xy 411.618176 -220.532452) (xy 411.618176 -220.531944) (xy 411.618176 -220.03766) (xy 411.618666 -220.032396)
			(xy 411.626119 -220.024957) (xy 411.631384 -220.024452) (xy 413.104584 -220.024452) (xy 413.109835 -220.025001)
			(xy 413.117276 -220.032411) (xy 413.117792 -220.03766) (xy 413.117792 -220.532198) (xy 413.117767 -220.532452)
			(xy 415.718244 -220.532452) (xy 415.718244 -220.03766) (xy 415.718763 -220.032404) (xy 415.726196 -220.024966)
			(xy 415.731452 -220.024452) (xy 417.204652 -220.024452) (xy 417.209968 -220.024855) (xy 417.217509 -220.032346)
			(xy 417.21786 -220.03766) (xy 417.21786 -220.532198) (xy 419.161976 -220.532198) (xy 419.161976 -220.03766)
			(xy 419.162466 -220.032396) (xy 419.169919 -220.024957) (xy 419.175184 -220.024452) (xy 419.175692 -220.024452)
			(xy 419.691566 -220.024452) (xy 419.699376 -220.024132) (xy 419.714247 -220.019351) (xy 419.720776 -220.015054)
			(xy 419.741865 -220.000705) (xy 419.787526 -219.977974) (xy 419.836132 -219.962515) (xy 419.886535 -219.954692)
			(xy 419.937541 -219.954692) (xy 419.987944 -219.962515) (xy 420.03655 -219.977974) (xy 420.082211 -220.000705)
			(xy 420.1033 -220.015054) (xy 420.109835 -220.019339) (xy 420.124702 -220.024127) (xy 420.13251 -220.024452)
			(xy 420.648638 -220.024452) (xy 420.65395 -220.0249) (xy 420.661519 -220.032357) (xy 420.6621 -220.03766)
			(xy 420.6621 -220.532198) (xy 423.262044 -220.532198) (xy 423.262044 -220.03766) (xy 423.262563 -220.032404)
			(xy 423.269996 -220.024966) (xy 423.275252 -220.024452) (xy 423.27576 -220.024452) (xy 423.791634 -220.024452)
			(xy 423.799442 -220.024118) (xy 423.814314 -220.019347) (xy 423.820844 -220.015054) (xy 423.841933 -220.000705)
			(xy 423.887594 -219.977974) (xy 423.9362 -219.962515) (xy 423.986603 -219.954692) (xy 424.037609 -219.954692)
			(xy 424.088012 -219.962515) (xy 424.136618 -219.977974) (xy 424.182279 -220.000705) (xy 424.203368 -220.015054)
			(xy 424.20991 -220.019327) (xy 424.224772 -220.024122) (xy 424.232578 -220.024452) (xy 424.748706 -220.024452)
			(xy 424.754014 -220.02492) (xy 424.761585 -220.032362) (xy 424.762168 -220.03766) (xy 424.762168 -220.532198)
			(xy 424.762143 -220.532452) (xy 426.706284 -220.532452) (xy 426.706284 -220.531944) (xy 426.706284 -220.03766)
			(xy 426.706767 -220.032394) (xy 426.714225 -220.024954) (xy 426.719492 -220.024452) (xy 427.23562 -220.024452)
			(xy 427.243432 -220.024155) (xy 427.258303 -220.019359) (xy 427.26483 -220.015054) (xy 427.285919 -220.000705)
			(xy 427.33158 -219.977974) (xy 427.380186 -219.962515) (xy 427.430589 -219.954692) (xy 427.481595 -219.954692)
			(xy 427.531998 -219.962515) (xy 427.580604 -219.977974) (xy 427.626265 -220.000705) (xy 427.647354 -220.015054)
			(xy 427.653877 -220.01936) (xy 427.668753 -220.024135) (xy 427.676564 -220.024452) (xy 428.192692 -220.024452)
			(xy 428.197944 -220.024996) (xy 428.205385 -220.03241) (xy 428.2059 -220.03766) (xy 428.2059 -220.532198)
			(xy 428.205875 -220.532452) (xy 430.806352 -220.532452) (xy 430.806352 -220.531944) (xy 430.806352 -220.03766)
			(xy 430.806864 -220.032402) (xy 430.814302 -220.024964) (xy 430.81956 -220.024452) (xy 431.335688 -220.024452)
			(xy 431.343498 -220.024141) (xy 431.35837 -220.019354) (xy 431.364898 -220.015054) (xy 431.385987 -220.000705)
			(xy 431.431648 -219.977974) (xy 431.480254 -219.962515) (xy 431.530657 -219.954692) (xy 431.581663 -219.954692)
			(xy 431.632066 -219.962515) (xy 431.680672 -219.977974) (xy 431.726333 -220.000705) (xy 431.747422 -220.015054)
			(xy 431.753952 -220.019348) (xy 431.768823 -220.02413) (xy 431.776632 -220.024452) (xy 432.29276 -220.024452)
			(xy 432.298008 -220.025017) (xy 432.305451 -220.032415) (xy 432.305968 -220.03766) (xy 432.305968 -220.532198)
			(xy 434.250084 -220.532198) (xy 434.250084 -220.03766) (xy 434.250567 -220.032394) (xy 434.258025 -220.024954)
			(xy 434.263292 -220.024452) (xy 434.2638 -220.024452) (xy 434.779674 -220.024452) (xy 434.787484 -220.024135)
			(xy 434.802356 -220.019352) (xy 434.808884 -220.015054) (xy 434.829973 -220.000705) (xy 434.875634 -219.977974)
			(xy 434.92424 -219.962515) (xy 434.974643 -219.954692) (xy 435.025649 -219.954692) (xy 435.076052 -219.962515)
			(xy 435.124658 -219.977974) (xy 435.170319 -220.000705) (xy 435.191408 -220.015054) (xy 435.197941 -220.019343)
			(xy 435.21281 -220.024128) (xy 435.220618 -220.024452) (xy 435.736746 -220.024452) (xy 435.742047 -220.024961)
			(xy 435.749621 -220.032371) (xy 435.750208 -220.03766) (xy 435.750208 -220.532198) (xy 438.350152 -220.532198)
			(xy 438.350152 -220.03766) (xy 438.350664 -220.032402) (xy 438.358102 -220.024964) (xy 438.36336 -220.024452)
			(xy 438.363868 -220.024452) (xy 438.879742 -220.024452) (xy 438.887551 -220.024122) (xy 438.902423 -220.019348)
			(xy 438.908952 -220.015054) (xy 438.930041 -220.000705) (xy 438.975702 -219.977974) (xy 439.024308 -219.962515)
			(xy 439.074711 -219.954692) (xy 439.125717 -219.954692) (xy 439.17612 -219.962515) (xy 439.224726 -219.977974)
			(xy 439.270387 -220.000705) (xy 439.291476 -220.015054) (xy 439.298016 -220.01933) (xy 439.312879 -220.024123)
			(xy 439.320686 -220.024452) (xy 439.836814 -220.024452) (xy 439.842123 -220.024915) (xy 439.849693 -220.03236)
			(xy 439.850276 -220.03766) (xy 439.850276 -220.532198) (xy 439.850251 -220.532452) (xy 441.794392 -220.532452)
			(xy 441.794392 -220.531944) (xy 441.794392 -220.03766) (xy 441.794868 -220.032392) (xy 441.802331 -220.024952)
			(xy 441.8076 -220.024452) (xy 442.323728 -220.024452) (xy 442.33154 -220.024158) (xy 442.346412 -220.01936)
			(xy 442.352938 -220.015054) (xy 442.374027 -220.000705) (xy 442.419688 -219.977974) (xy 442.468294 -219.962515)
			(xy 442.518697 -219.954692) (xy 442.569703 -219.954692) (xy 442.620106 -219.962515) (xy 442.668712 -219.977974)
			(xy 442.714373 -220.000705) (xy 442.735462 -220.015054) (xy 442.742005 -220.019325) (xy 442.756866 -220.024121)
			(xy 442.764672 -220.024452) (xy 443.2808 -220.024452) (xy 443.286053 -220.024991) (xy 443.293493 -220.032408)
			(xy 443.294008 -220.03766) (xy 443.294008 -220.532198) (xy 443.293983 -220.532452) (xy 445.89446 -220.532452)
			(xy 445.89446 -220.531944) (xy 445.89446 -220.03766) (xy 445.894965 -220.0324) (xy 445.902408 -220.024962)
			(xy 445.907668 -220.024452) (xy 446.423796 -220.024452) (xy 446.431607 -220.024144) (xy 446.446478 -220.019355)
			(xy 446.453006 -220.015054) (xy 446.474095 -220.000705) (xy 446.519756 -219.977974) (xy 446.568362 -219.962515)
			(xy 446.618765 -219.954692) (xy 446.669771 -219.954692) (xy 446.720174 -219.962515) (xy 446.76878 -219.977974)
			(xy 446.814441 -220.000705) (xy 446.83553 -220.015054) (xy 446.842058 -220.019351) (xy 446.856931 -220.024131)
			(xy 446.86474 -220.024452) (xy 447.380868 -220.024452) (xy 447.386117 -220.025012) (xy 447.39356 -220.032413)
			(xy 447.394076 -220.03766) (xy 447.394076 -220.532198) (xy 447.394052 -220.532452) (xy 449.338192 -220.532452)
			(xy 449.338192 -220.531944) (xy 449.338192 -220.03766) (xy 449.338668 -220.032392) (xy 449.346131 -220.024952)
			(xy 449.3514 -220.024452) (xy 449.867528 -220.024452) (xy 449.87534 -220.024158) (xy 449.890212 -220.01936)
			(xy 449.896738 -220.015054) (xy 449.917827 -220.000705) (xy 449.963488 -219.977974) (xy 450.012094 -219.962515)
			(xy 450.062497 -219.954692) (xy 450.113503 -219.954692) (xy 450.163906 -219.962515) (xy 450.212512 -219.977974)
			(xy 450.258173 -220.000705) (xy 450.279262 -220.015054) (xy 450.285805 -220.019325) (xy 450.300666 -220.024121)
			(xy 450.308472 -220.024452) (xy 450.8246 -220.024452) (xy 450.829853 -220.024991) (xy 450.837293 -220.032408)
			(xy 450.837808 -220.03766) (xy 450.837808 -220.532198) (xy 450.837783 -220.532452) (xy 453.43826 -220.532452)
			(xy 453.43826 -220.531944) (xy 453.43826 -220.03766) (xy 453.438765 -220.0324) (xy 453.446208 -220.024962)
			(xy 453.451468 -220.024452) (xy 453.967596 -220.024452) (xy 453.975407 -220.024144) (xy 453.990278 -220.019355)
			(xy 453.996806 -220.015054) (xy 454.017895 -220.000705) (xy 454.063556 -219.977974) (xy 454.112162 -219.962515)
			(xy 454.162565 -219.954692) (xy 454.213571 -219.954692) (xy 454.263974 -219.962515) (xy 454.31258 -219.977974)
			(xy 454.358241 -220.000705) (xy 454.37933 -220.015054) (xy 454.385858 -220.019351) (xy 454.400731 -220.024131)
			(xy 454.40854 -220.024452) (xy 454.924668 -220.024452) (xy 454.929917 -220.025012) (xy 454.93736 -220.032413)
			(xy 454.937876 -220.03766) (xy 454.937876 -220.532198) (xy 454.937377 -220.537498) (xy 454.929957 -220.545068)
			(xy 454.924668 -220.54566) (xy 454.408794 -220.54566) (xy 454.400983 -220.545961) (xy 454.386111 -220.550755)
			(xy 454.379584 -220.555058) (xy 454.358465 -220.569411) (xy 454.31274 -220.592137) (xy 454.264066 -220.607566)
			(xy 454.213599 -220.615331) (xy 454.188068 -220.615764) (xy 454.162537 -220.615344) (xy 454.112073 -220.607563)
			(xy 454.0634 -220.592129) (xy 454.017673 -220.569408) (xy 453.996552 -220.555058) (xy 453.990027 -220.550755)
			(xy 453.975152 -220.545978) (xy 453.967342 -220.54566) (xy 453.451468 -220.54566) (xy 453.44612 -220.54539)
			(xy 453.438578 -220.537802) (xy 453.43826 -220.532452) (xy 450.837783 -220.532452) (xy 450.837281 -220.537491)
			(xy 450.829881 -220.545059) (xy 450.8246 -220.54566) (xy 450.308726 -220.54566) (xy 450.300916 -220.545975)
			(xy 450.286044 -220.550759) (xy 450.279516 -220.555058) (xy 450.258388 -220.569397) (xy 450.212666 -220.592126)
			(xy 450.163995 -220.607559) (xy 450.11353 -220.615329) (xy 450.088 -220.615764) (xy 450.06247 -220.615328)
			(xy 450.012006 -220.607552) (xy 449.963333 -220.592122) (xy 449.917606 -220.569406) (xy 449.896484 -220.555058)
			(xy 449.889952 -220.550767) (xy 449.875082 -220.545983) (xy 449.867274 -220.54566) (xy 449.3514 -220.54566)
			(xy 449.346056 -220.545369) (xy 449.338512 -220.537797) (xy 449.338192 -220.532452) (xy 447.394052 -220.532452)
			(xy 447.393577 -220.537498) (xy 447.386157 -220.545068) (xy 447.380868 -220.54566) (xy 446.864994 -220.54566)
			(xy 446.857183 -220.545961) (xy 446.842311 -220.550755) (xy 446.835784 -220.555058) (xy 446.814665 -220.569411)
			(xy 446.76894 -220.592137) (xy 446.720266 -220.607566) (xy 446.669799 -220.615331) (xy 446.644268 -220.615764)
			(xy 446.618737 -220.615344) (xy 446.568273 -220.607563) (xy 446.5196 -220.592129) (xy 446.473873 -220.569408)
			(xy 446.452752 -220.555058) (xy 446.446227 -220.550755) (xy 446.431352 -220.545978) (xy 446.423542 -220.54566)
			(xy 445.907668 -220.54566) (xy 445.90232 -220.54539) (xy 445.894778 -220.537802) (xy 445.89446 -220.532452)
			(xy 443.293983 -220.532452) (xy 443.293481 -220.537491) (xy 443.286081 -220.545059) (xy 443.2808 -220.54566)
			(xy 442.764926 -220.54566) (xy 442.757116 -220.545975) (xy 442.742244 -220.550759) (xy 442.735716 -220.555058)
			(xy 442.714588 -220.569397) (xy 442.668866 -220.592126) (xy 442.620195 -220.607559) (xy 442.56973 -220.615329)
			(xy 442.5442 -220.615764) (xy 442.51867 -220.615328) (xy 442.468206 -220.607552) (xy 442.419533 -220.592122)
			(xy 442.373806 -220.569406) (xy 442.352684 -220.555058) (xy 442.346152 -220.550767) (xy 442.331282 -220.545983)
			(xy 442.323474 -220.54566) (xy 441.8076 -220.54566) (xy 441.802256 -220.545369) (xy 441.794712 -220.537797)
			(xy 441.794392 -220.532452) (xy 439.850251 -220.532452) (xy 439.84975 -220.537558) (xy 439.842174 -220.545143)
			(xy 439.836814 -220.54566) (xy 439.32094 -220.54566) (xy 439.31313 -220.545981) (xy 439.298259 -220.550761)
			(xy 439.29173 -220.555058) (xy 439.270626 -220.569434) (xy 439.224896 -220.592155) (xy 439.176217 -220.607577)
			(xy 439.125746 -220.615335) (xy 439.100214 -220.615764) (xy 439.074684 -220.615321) (xy 439.02422 -220.607547)
			(xy 438.975548 -220.59212) (xy 438.92982 -220.569405) (xy 438.908698 -220.555058) (xy 438.902163 -220.550773)
			(xy 438.887296 -220.545985) (xy 438.879488 -220.54566) (xy 438.363614 -220.54566) (xy 438.358181 -220.545311)
			(xy 438.350494 -220.537631) (xy 438.350152 -220.532198) (xy 435.750208 -220.532198) (xy 435.749653 -220.537551)
			(xy 435.742097 -220.545134) (xy 435.736746 -220.54566) (xy 435.220872 -220.54566) (xy 435.21306 -220.545951)
			(xy 435.198188 -220.550752) (xy 435.191662 -220.555058) (xy 435.170549 -220.569421) (xy 435.124822 -220.592144)
			(xy 435.076146 -220.60757) (xy 435.025678 -220.615333) (xy 435.000146 -220.615764) (xy 434.974617 -220.615304)
			(xy 434.924154 -220.607536) (xy 434.875481 -220.592113) (xy 434.829753 -220.569403) (xy 434.80863 -220.555058)
			(xy 434.802088 -220.550785) (xy 434.787226 -220.54599) (xy 434.77942 -220.54566) (xy 434.263546 -220.54566)
			(xy 434.258117 -220.54529) (xy 434.250428 -220.537626) (xy 434.250084 -220.532198) (xy 432.305968 -220.532198)
			(xy 432.305476 -220.5375) (xy 432.298052 -220.545071) (xy 432.29276 -220.54566) (xy 431.776886 -220.54566)
			(xy 431.769074 -220.545957) (xy 431.754202 -220.550753) (xy 431.747676 -220.555058) (xy 431.726559 -220.569415)
			(xy 431.680834 -220.592139) (xy 431.632159 -220.607567) (xy 431.581691 -220.615332) (xy 431.55616 -220.615764)
			(xy 431.530629 -220.615348) (xy 431.480164 -220.607566) (xy 431.431492 -220.592131) (xy 431.385765 -220.569408)
			(xy 431.364644 -220.555058) (xy 431.358121 -220.550752) (xy 431.343245 -220.545977) (xy 431.335434 -220.54566)
			(xy 430.81956 -220.54566) (xy 430.81421 -220.545395) (xy 430.806669 -220.537803) (xy 430.806352 -220.532452)
			(xy 428.205875 -220.532452) (xy 428.20538 -220.537493) (xy 428.197975 -220.545061) (xy 428.192692 -220.54566)
			(xy 427.676818 -220.54566) (xy 427.669008 -220.545971) (xy 427.654136 -220.550758) (xy 427.647608 -220.555058)
			(xy 427.626482 -220.569401) (xy 427.58076 -220.592129) (xy 427.532088 -220.607561) (xy 427.481623 -220.61533)
			(xy 427.456092 -220.615764) (xy 427.430562 -220.615332) (xy 427.380098 -220.607554) (xy 427.331425 -220.592124)
			(xy 427.285698 -220.569406) (xy 427.264576 -220.555058) (xy 427.258046 -220.550764) (xy 427.243175 -220.545982)
			(xy 427.235366 -220.54566) (xy 426.719492 -220.54566) (xy 426.714147 -220.545374) (xy 426.706603 -220.537799)
			(xy 426.706284 -220.532452) (xy 424.762143 -220.532452) (xy 424.761649 -220.53756) (xy 424.754068 -220.545146)
			(xy 424.748706 -220.54566) (xy 424.232832 -220.54566) (xy 424.225022 -220.545977) (xy 424.21015 -220.55076)
			(xy 424.203622 -220.555058) (xy 424.182492 -220.569395) (xy 424.136771 -220.592124) (xy 424.088101 -220.607558)
			(xy 424.037636 -220.615328) (xy 424.012106 -220.615764) (xy 423.986576 -220.615325) (xy 423.936112 -220.60755)
			(xy 423.88744 -220.592121) (xy 423.841712 -220.569405) (xy 423.82059 -220.555058) (xy 423.814057 -220.55077)
			(xy 423.799188 -220.545984) (xy 423.79138 -220.54566) (xy 423.275506 -220.54566) (xy 423.270072 -220.545317)
			(xy 423.262385 -220.537632) (xy 423.262044 -220.532198) (xy 420.6621 -220.532198) (xy 420.661552 -220.537553)
			(xy 420.653991 -220.545136) (xy 420.648638 -220.54566) (xy 420.132764 -220.54566) (xy 420.124955 -220.545991)
			(xy 420.110083 -220.550764) (xy 420.103554 -220.555058) (xy 420.082443 -220.569424) (xy 420.036715 -220.592147)
			(xy 419.988039 -220.607572) (xy 419.93757 -220.615334) (xy 419.912038 -220.615764) (xy 419.886508 -220.615308)
			(xy 419.836045 -220.607538) (xy 419.787373 -220.592115) (xy 419.741645 -220.569403) (xy 419.720522 -220.555058)
			(xy 419.713981 -220.550782) (xy 419.699119 -220.545989) (xy 419.691312 -220.54566) (xy 419.175438 -220.54566)
			(xy 419.170008 -220.545295) (xy 419.162319 -220.537627) (xy 419.161976 -220.532198) (xy 417.21786 -220.532198)
			(xy 417.217375 -220.537502) (xy 417.209946 -220.545073) (xy 417.204652 -220.54566) (xy 415.731452 -220.54566)
			(xy 415.726172 -220.545232) (xy 415.718729 -220.537736) (xy 415.718244 -220.532452) (xy 413.117767 -220.532452)
			(xy 413.117279 -220.537494) (xy 413.109869 -220.545064) (xy 413.104584 -220.54566) (xy 411.631384 -220.54566)
			(xy 411.626038 -220.545379) (xy 411.618495 -220.5378) (xy 411.618176 -220.532452) (xy 308.11824 -220.532452)
			(xy 308.117919 -220.537634) (xy 308.11023 -220.54532) (xy 308.104794 -220.54566) (xy 306.631594 -220.54566)
			(xy 306.626229 -220.545154) (xy 306.618643 -220.537563) (xy 306.618132 -220.532198) (xy 304.018188 -220.532198)
			(xy 304.017651 -220.537555) (xy 304.010082 -220.54514) (xy 304.004726 -220.54566) (xy 302.531526 -220.54566)
			(xy 302.526094 -220.545303) (xy 302.518406 -220.537629) (xy 302.518064 -220.532198) (xy 300.573948 -220.532198)
			(xy 300.573474 -220.537505) (xy 300.566037 -220.545077) (xy 300.56074 -220.54566) (xy 300.044866 -220.54566)
			(xy 300.037057 -220.545992) (xy 300.022185 -220.550764) (xy 300.015656 -220.555058) (xy 299.994545 -220.569423)
			(xy 299.948817 -220.592146) (xy 299.900141 -220.607572) (xy 299.849672 -220.615333) (xy 299.82414 -220.615764)
			(xy 299.798611 -220.615307) (xy 299.748147 -220.607538) (xy 299.699475 -220.592114) (xy 299.653747 -220.569403)
			(xy 299.632624 -220.555058) (xy 299.626083 -220.550783) (xy 299.61122 -220.545989) (xy 299.603414 -220.54566)
			(xy 299.08754 -220.54566) (xy 299.082201 -220.545341) (xy 299.074655 -220.537791) (xy 299.074332 -220.532452)
			(xy 296.473856 -220.532452) (xy 296.473378 -220.537497) (xy 296.46596 -220.545067) (xy 296.460672 -220.54566)
			(xy 295.944798 -220.54566) (xy 295.936987 -220.545963) (xy 295.922115 -220.550755) (xy 295.915588 -220.555058)
			(xy 295.894468 -220.569409) (xy 295.848743 -220.592135) (xy 295.80007 -220.607565) (xy 295.749603 -220.615331)
			(xy 295.724072 -220.615764) (xy 295.698541 -220.615342) (xy 295.648077 -220.607561) (xy 295.599404 -220.592128)
			(xy 295.553677 -220.569407) (xy 295.532556 -220.555058) (xy 295.52603 -220.550757) (xy 295.511156 -220.545979)
			(xy 295.503346 -220.54566) (xy 294.987472 -220.54566) (xy 294.982124 -220.545387) (xy 294.974582 -220.537802)
			(xy 294.974264 -220.532452) (xy 293.030133 -220.532452) (xy 293.029818 -220.537636) (xy 293.022124 -220.545323)
			(xy 293.016686 -220.54566) (xy 292.500812 -220.54566) (xy 292.493001 -220.545969) (xy 292.47813 -220.550757)
			(xy 292.471602 -220.555058) (xy 292.450478 -220.569403) (xy 292.404755 -220.592131) (xy 292.356082 -220.607562)
			(xy 292.305617 -220.61533) (xy 292.280086 -220.615764) (xy 292.254555 -220.615335) (xy 292.204091 -220.607557)
			(xy 292.155419 -220.592125) (xy 292.109692 -220.569407) (xy 292.08857 -220.555058) (xy 292.082041 -220.550762)
			(xy 292.067169 -220.545981) (xy 292.05936 -220.54566) (xy 291.543486 -220.54566) (xy 291.53812 -220.545159)
			(xy 291.530535 -220.537565) (xy 291.530024 -220.532198) (xy 288.93008 -220.532198) (xy 288.92955 -220.537557)
			(xy 288.921977 -220.545142) (xy 288.916618 -220.54566) (xy 288.400744 -220.54566) (xy 288.392935 -220.545982)
			(xy 288.378063 -220.550761) (xy 288.371534 -220.555058) (xy 288.350429 -220.569433) (xy 288.304699 -220.592153)
			(xy 288.256021 -220.607576) (xy 288.20555 -220.615335) (xy 288.180018 -220.615764) (xy 288.154488 -220.615319)
			(xy 288.104025 -220.607545) (xy 288.055352 -220.592119) (xy 288.009624 -220.569404) (xy 287.988502 -220.555058)
			(xy 287.981966 -220.550774) (xy 287.9671 -220.545986) (xy 287.959292 -220.54566) (xy 287.443418 -220.54566)
			(xy 287.437985 -220.545309) (xy 287.430298 -220.537631) (xy 287.429956 -220.532198) (xy 285.48584 -220.532198)
			(xy 285.485373 -220.537507) (xy 285.477931 -220.545079) (xy 285.472632 -220.54566) (xy 284.956758 -220.54566)
			(xy 284.948949 -220.545988) (xy 284.934077 -220.550763) (xy 284.927548 -220.555058) (xy 284.906439 -220.569427)
			(xy 284.860711 -220.592149) (xy 284.812033 -220.607573) (xy 284.761564 -220.615334) (xy 284.736032 -220.615764)
			(xy 284.710502 -220.615311) (xy 284.660039 -220.60754) (xy 284.611367 -220.592116) (xy 284.565638 -220.569404)
			(xy 284.544516 -220.555058) (xy 284.537977 -220.55078) (xy 284.523113 -220.545988) (xy 284.515306 -220.54566)
			(xy 283.999432 -220.54566) (xy 283.994092 -220.545347) (xy 283.986547 -220.537792) (xy 283.986224 -220.532452)
			(xy 281.385748 -220.532452) (xy 281.385277 -220.537499) (xy 281.377854 -220.54507) (xy 281.372564 -220.54566)
			(xy 280.85669 -220.54566) (xy 280.848878 -220.54596) (xy 280.834007 -220.550754) (xy 280.82748 -220.555058)
			(xy 280.806362 -220.569413) (xy 280.760637 -220.592138) (xy 280.711962 -220.607567) (xy 280.661495 -220.615332)
			(xy 280.635964 -220.615764) (xy 280.610433 -220.615346) (xy 280.559968 -220.607564) (xy 280.511296 -220.59213)
			(xy 280.465569 -220.569408) (xy 280.444448 -220.555058) (xy 280.437924 -220.550754) (xy 280.423048 -220.545978)
			(xy 280.415238 -220.54566) (xy 279.899364 -220.54566) (xy 279.894015 -220.545393) (xy 279.886473 -220.537803)
			(xy 279.886156 -220.532452) (xy 277.942018 -220.532452) (xy 277.941573 -220.537507) (xy 277.934131 -220.545079)
			(xy 277.928832 -220.54566) (xy 277.412958 -220.54566) (xy 277.405149 -220.545988) (xy 277.390277 -220.550763)
			(xy 277.383748 -220.555058) (xy 277.362639 -220.569427) (xy 277.316911 -220.592149) (xy 277.268233 -220.607573)
			(xy 277.217764 -220.615334) (xy 277.192232 -220.615764) (xy 277.166702 -220.615311) (xy 277.116239 -220.60754)
			(xy 277.067567 -220.592116) (xy 277.021838 -220.569404) (xy 277.000716 -220.555058) (xy 276.994177 -220.55078)
			(xy 276.979313 -220.545988) (xy 276.971506 -220.54566) (xy 276.455632 -220.54566) (xy 276.450292 -220.545347)
			(xy 276.442747 -220.537792) (xy 276.442424 -220.532452) (xy 273.841948 -220.532452) (xy 273.841477 -220.537499)
			(xy 273.834054 -220.54507) (xy 273.828764 -220.54566) (xy 273.31289 -220.54566) (xy 273.305078 -220.54596)
			(xy 273.290207 -220.550754) (xy 273.28368 -220.555058) (xy 273.262562 -220.569413) (xy 273.216837 -220.592138)
			(xy 273.168162 -220.607567) (xy 273.117695 -220.615332) (xy 273.092164 -220.615764) (xy 273.066633 -220.615346)
			(xy 273.016168 -220.607564) (xy 272.967496 -220.59213) (xy 272.921769 -220.569408) (xy 272.900648 -220.555058)
			(xy 272.894124 -220.550754) (xy 272.879248 -220.545978) (xy 272.871438 -220.54566) (xy 272.355564 -220.54566)
			(xy 272.350215 -220.545393) (xy 272.342673 -220.537803) (xy 272.342356 -220.532452) (xy 270.398225 -220.532452)
			(xy 270.397917 -220.537638) (xy 270.390218 -220.545325) (xy 270.384778 -220.54566) (xy 269.868904 -220.54566)
			(xy 269.861093 -220.545965) (xy 269.846221 -220.550756) (xy 269.839694 -220.555058) (xy 269.818572 -220.569407)
			(xy 269.772848 -220.592133) (xy 269.724175 -220.607564) (xy 269.673709 -220.615331) (xy 269.648178 -220.615764)
			(xy 269.622647 -220.615339) (xy 269.572183 -220.607559) (xy 269.523511 -220.592127) (xy 269.477784 -220.569407)
			(xy 269.456662 -220.555058) (xy 269.450135 -220.550759) (xy 269.435262 -220.54598) (xy 269.427452 -220.54566)
			(xy 268.911578 -220.54566) (xy 268.906211 -220.545164) (xy 268.898626 -220.537566) (xy 268.898116 -220.532198)
			(xy 266.298172 -220.532198) (xy 266.297649 -220.537559) (xy 266.290071 -220.545145) (xy 266.28471 -220.54566)
			(xy 265.768836 -220.54566) (xy 265.761026 -220.545979) (xy 265.746154 -220.55076) (xy 265.739626 -220.555058)
			(xy 265.718495 -220.569393) (xy 265.672775 -220.592123) (xy 265.624104 -220.607557) (xy 265.57364 -220.615328)
			(xy 265.54811 -220.615764) (xy 265.52258 -220.615323) (xy 265.472116 -220.607548) (xy 265.423444 -220.59212)
			(xy 265.377716 -220.569405) (xy 265.356594 -220.555058) (xy 265.35006 -220.550771) (xy 265.335192 -220.545984)
			(xy 265.327384 -220.54566) (xy 264.81151 -220.54566) (xy 264.806076 -220.545314) (xy 264.798389 -220.537632)
			(xy 264.798048 -220.532198) (xy 206.997808 -220.532198) (xy 206.997808 -220.532452) (xy 206.997441 -220.537778)
			(xy 206.989924 -220.545321) (xy 206.9846 -220.54566) (xy 206.468726 -220.54566) (xy 206.460849 -220.545922)
			(xy 206.445845 -220.550723) (xy 206.439262 -220.555058) (xy 206.418186 -220.569452) (xy 206.372541 -220.59228)
			(xy 206.323934 -220.607837) (xy 206.273517 -220.615755) (xy 206.248 -220.616272) (xy 206.222479 -220.615805)
			(xy 206.172051 -220.607904) (xy 206.123439 -220.592338) (xy 206.077802 -220.569476) (xy 206.056738 -220.555058)
			(xy 206.050136 -220.55076) (xy 206.035144 -220.545962) (xy 206.027274 -220.54566) (xy 205.5114 -220.54566)
			(xy 205.506056 -220.545369) (xy 205.498512 -220.537797) (xy 205.498192 -220.532452) (xy 202.89774 -220.532452)
			(xy 202.897344 -220.53777) (xy 202.889848 -220.545312) (xy 202.884532 -220.54566) (xy 202.368658 -220.54566)
			(xy 202.360782 -220.545936) (xy 202.345778 -220.550728) (xy 202.339194 -220.555058) (xy 202.318109 -220.569438)
			(xy 202.272467 -220.592269) (xy 202.223863 -220.60783) (xy 202.173448 -220.615753) (xy 202.147932 -220.616272)
			(xy 202.122412 -220.615788) (xy 202.071984 -220.607893) (xy 202.023372 -220.592331) (xy 201.977734 -220.569474)
			(xy 201.95667 -220.555058) (xy 201.950084 -220.550734) (xy 201.93508 -220.545952) (xy 201.927206 -220.54566)
			(xy 201.411332 -220.54566) (xy 201.405992 -220.545347) (xy 201.398447 -220.537792) (xy 201.398124 -220.532452)
			(xy 199.454008 -220.532452) (xy 199.453641 -220.537778) (xy 199.446124 -220.545321) (xy 199.4408 -220.54566)
			(xy 198.924926 -220.54566) (xy 198.917049 -220.545922) (xy 198.902045 -220.550723) (xy 198.895462 -220.555058)
			(xy 198.874386 -220.569452) (xy 198.828741 -220.59228) (xy 198.780134 -220.607837) (xy 198.729717 -220.615755)
			(xy 198.7042 -220.616272) (xy 198.678679 -220.615805) (xy 198.628251 -220.607904) (xy 198.579639 -220.592338)
			(xy 198.534002 -220.569476) (xy 198.512938 -220.555058) (xy 198.506336 -220.55076) (xy 198.491344 -220.545962)
			(xy 198.483474 -220.54566) (xy 197.9676 -220.54566) (xy 197.962256 -220.545369) (xy 197.954712 -220.537797)
			(xy 197.954392 -220.532452) (xy 195.35394 -220.532452) (xy 195.353544 -220.53777) (xy 195.346048 -220.545312)
			(xy 195.340732 -220.54566) (xy 194.824858 -220.54566) (xy 194.816982 -220.545936) (xy 194.801978 -220.550728)
			(xy 194.795394 -220.555058) (xy 194.774309 -220.569438) (xy 194.728667 -220.592269) (xy 194.680063 -220.60783)
			(xy 194.629648 -220.615753) (xy 194.604132 -220.616272) (xy 194.578612 -220.615788) (xy 194.528184 -220.607893)
			(xy 194.479572 -220.592331) (xy 194.433934 -220.569474) (xy 194.41287 -220.555058) (xy 194.406284 -220.550734)
			(xy 194.39128 -220.545952) (xy 194.383406 -220.54566) (xy 193.867532 -220.54566) (xy 193.862192 -220.545347)
			(xy 193.854647 -220.537792) (xy 193.854324 -220.532452) (xy 191.910208 -220.532452) (xy 191.909841 -220.537778)
			(xy 191.902324 -220.545321) (xy 191.897 -220.54566) (xy 191.896492 -220.54566) (xy 191.380872 -220.54566)
			(xy 191.372997 -220.545942) (xy 191.357993 -220.550729) (xy 191.351408 -220.555058) (xy 191.330347 -220.569475)
			(xy 191.284696 -220.592298) (xy 191.236085 -220.607848) (xy 191.185664 -220.615759) (xy 191.160146 -220.616272)
			(xy 191.134626 -220.615781) (xy 191.084199 -220.607888) (xy 191.035587 -220.592328) (xy 190.989949 -220.569473)
			(xy 190.968884 -220.555058) (xy 190.962294 -220.55074) (xy 190.947293 -220.545954) (xy 190.93942 -220.54566)
			(xy 190.423546 -220.54566) (xy 190.418247 -220.545146) (xy 190.410673 -220.537739) (xy 190.410084 -220.532452)
			(xy 187.81014 -220.532452) (xy 187.809744 -220.53777) (xy 187.802248 -220.545312) (xy 187.796932 -220.54566)
			(xy 187.796424 -220.54566) (xy 187.280804 -220.54566) (xy 187.27293 -220.545955) (xy 187.257926 -220.550734)
			(xy 187.25134 -220.555058) (xy 187.23027 -220.569462) (xy 187.184623 -220.592287) (xy 187.136014 -220.607841)
			(xy 187.085595 -220.615757) (xy 187.060078 -220.616272) (xy 187.034558 -220.615765) (xy 186.984132 -220.607877)
			(xy 186.93552 -220.592322) (xy 186.889881 -220.569471) (xy 186.868816 -220.555058) (xy 186.862219 -220.550752)
			(xy 186.847223 -220.545959) (xy 186.839352 -220.54566) (xy 186.323478 -220.54566) (xy 186.318171 -220.545191)
			(xy 186.310601 -220.53775) (xy 186.310016 -220.532452) (xy 184.3659 -220.532452) (xy 184.36554 -220.53778)
			(xy 184.358019 -220.545324) (xy 184.352692 -220.54566) (xy 183.836818 -220.54566) (xy 183.828945 -220.545961)
			(xy 183.81394 -220.550735) (xy 183.807354 -220.555058) (xy 183.786281 -220.569456) (xy 183.740634 -220.592282)
			(xy 183.692027 -220.607838) (xy 183.641609 -220.615756) (xy 183.616092 -220.616272) (xy 183.590573 -220.615758)
			(xy 183.540147 -220.607872) (xy 183.491535 -220.592319) (xy 183.445896 -220.56947) (xy 183.42483 -220.555058)
			(xy 183.41823 -220.550757) (xy 183.403237 -220.545961) (xy 183.395366 -220.54566) (xy 182.879492 -220.54566)
			(xy 182.874147 -220.545374) (xy 182.866603 -220.537799) (xy 182.866284 -220.532452) (xy 180.265832 -220.532452)
			(xy 180.265443 -220.537772) (xy 180.257942 -220.545314) (xy 180.252624 -220.54566) (xy 179.73675 -220.54566)
			(xy 179.728874 -220.545932) (xy 179.71387 -220.550726) (xy 179.707286 -220.555058) (xy 179.686204 -220.569442)
			(xy 179.64056 -220.592272) (xy 179.591956 -220.607832) (xy 179.54154 -220.615753) (xy 179.516024 -220.616272)
			(xy 179.490503 -220.615792) (xy 179.440076 -220.607896) (xy 179.391464 -220.592333) (xy 179.345826 -220.569475)
			(xy 179.324762 -220.555058) (xy 179.318177 -220.550731) (xy 179.303172 -220.545951) (xy 179.295298 -220.54566)
			(xy 178.779424 -220.54566) (xy 178.774083 -220.545352) (xy 178.766538 -220.537793) (xy 178.766216 -220.532452)
			(xy 176.8221 -220.532452) (xy 176.82174 -220.53778) (xy 176.814219 -220.545324) (xy 176.808892 -220.54566)
			(xy 176.808384 -220.54566) (xy 176.292764 -220.54566) (xy 176.284889 -220.545938) (xy 176.269885 -220.550728)
			(xy 176.2633 -220.555058) (xy 176.242214 -220.569436) (xy 176.196572 -220.592267) (xy 176.147969 -220.607829)
			(xy 176.097554 -220.615752) (xy 176.072038 -220.616272) (xy 176.046518 -220.615785) (xy 175.99609 -220.607891)
			(xy 175.947479 -220.59233) (xy 175.901841 -220.569474) (xy 175.880776 -220.555058) (xy 175.874188 -220.550736)
			(xy 175.859185 -220.545953) (xy 175.851312 -220.54566) (xy 175.335438 -220.54566) (xy 175.330138 -220.545151)
			(xy 175.322565 -220.53774) (xy 175.321976 -220.532452) (xy 172.722032 -220.532452) (xy 172.721643 -220.537772)
			(xy 172.714142 -220.545314) (xy 172.708824 -220.54566) (xy 172.708316 -220.54566) (xy 172.192696 -220.54566)
			(xy 172.184822 -220.545952) (xy 172.169818 -220.550732) (xy 172.163232 -220.555058) (xy 172.142165 -220.569465)
			(xy 172.096516 -220.59229) (xy 172.047907 -220.607843) (xy 171.997488 -220.615757) (xy 171.97197 -220.616272)
			(xy 171.94645 -220.615769) (xy 171.896024 -220.60788) (xy 171.847412 -220.592324) (xy 171.801773 -220.569472)
			(xy 171.780708 -220.555058) (xy 171.774113 -220.550749) (xy 171.759116 -220.545957) (xy 171.751244 -220.54566)
			(xy 171.23537 -220.54566) (xy 171.230062 -220.545197) (xy 171.222493 -220.537751) (xy 171.221908 -220.532452)
			(xy 169.277792 -220.532452) (xy 169.277439 -220.537782) (xy 169.269913 -220.545326) (xy 169.264584 -220.54566)
			(xy 167.791384 -220.54566) (xy 167.786038 -220.545379) (xy 167.778495 -220.5378) (xy 167.778176 -220.532452)
			(xy 165.177724 -220.532452) (xy 165.177342 -220.537774) (xy 165.169836 -220.545317) (xy 165.164516 -220.54566)
			(xy 163.691316 -220.54566) (xy 163.685974 -220.545358) (xy 163.678429 -220.537795) (xy 163.678108 -220.532452)
			(xy 60.178188 -220.532452) (xy 60.177839 -220.537783) (xy 60.17031 -220.545327) (xy 60.16498 -220.54566)
			(xy 60.164472 -220.54566) (xy 58.691526 -220.54566) (xy 58.686225 -220.545159) (xy 58.678652 -220.537742)
			(xy 58.678064 -220.532452) (xy 56.07812 -220.532452) (xy 56.077742 -220.537775) (xy 56.070233 -220.545318)
			(xy 56.064912 -220.54566) (xy 54.591458 -220.54566) (xy 54.586149 -220.545205) (xy 54.57858 -220.537753)
			(xy 54.577996 -220.532452) (xy 52.63388 -220.532452) (xy 52.633538 -220.537785) (xy 52.626004 -220.54533)
			(xy 52.620672 -220.54566) (xy 52.104798 -220.54566) (xy 52.096924 -220.545953) (xy 52.08192 -220.550733)
			(xy 52.075334 -220.555058) (xy 52.054266 -220.569464) (xy 52.008618 -220.592289) (xy 51.960009 -220.607843)
			(xy 51.90959 -220.615757) (xy 51.884072 -220.616272) (xy 51.858552 -220.615768) (xy 51.808126 -220.607879)
			(xy 51.759514 -220.592323) (xy 51.713875 -220.569472) (xy 51.69281 -220.555058) (xy 51.686215 -220.55075)
			(xy 51.671218 -220.545958) (xy 51.663346 -220.54566) (xy 51.147472 -220.54566) (xy 51.142124 -220.545387)
			(xy 51.134582 -220.537802) (xy 51.134264 -220.532452) (xy 48.533812 -220.532452) (xy 48.533441 -220.537777)
			(xy 48.525927 -220.54532) (xy 48.520604 -220.54566) (xy 48.00473 -220.54566) (xy 47.996853 -220.545923)
			(xy 47.981849 -220.550723) (xy 47.975266 -220.555058) (xy 47.954189 -220.56945) (xy 47.908544 -220.592278)
			(xy 47.859938 -220.607836) (xy 47.809521 -220.615755) (xy 47.784004 -220.616272) (xy 47.758483 -220.615803)
			(xy 47.708055 -220.607903) (xy 47.659443 -220.592337) (xy 47.613806 -220.569476) (xy 47.592742 -220.555058)
			(xy 47.586162 -220.550723) (xy 47.571153 -220.545948) (xy 47.563278 -220.54566) (xy 47.047404 -220.54566)
			(xy 47.042061 -220.545366) (xy 47.034517 -220.537796) (xy 47.034196 -220.532452) (xy 45.09008 -220.532452)
			(xy 45.089738 -220.537785) (xy 45.082204 -220.54533) (xy 45.076872 -220.54566) (xy 45.076364 -220.54566)
			(xy 44.560744 -220.54566) (xy 44.552868 -220.54593) (xy 44.537864 -220.550726) (xy 44.53128 -220.555058)
			(xy 44.510199 -220.569444) (xy 44.464556 -220.592274) (xy 44.415951 -220.607833) (xy 44.365534 -220.615754)
			(xy 44.340018 -220.616272) (xy 44.314497 -220.615795) (xy 44.26407 -220.607898) (xy 44.215458 -220.592334)
			(xy 44.16982 -220.569475) (xy 44.148756 -220.555058) (xy 44.142173 -220.550729) (xy 44.127166 -220.54595)
			(xy 44.119292 -220.54566) (xy 43.603418 -220.54566) (xy 43.598116 -220.545165) (xy 43.590544 -220.537743)
			(xy 43.589956 -220.532452) (xy 40.990012 -220.532452) (xy 40.989641 -220.537777) (xy 40.982127 -220.54532)
			(xy 40.976804 -220.54566) (xy 40.976296 -220.54566) (xy 40.460676 -220.54566) (xy 40.452801 -220.545943)
			(xy 40.437797 -220.55073) (xy 40.431212 -220.555058) (xy 40.41015 -220.569474) (xy 40.3645 -220.592296)
			(xy 40.315889 -220.607847) (xy 40.265468 -220.615759) (xy 40.23995 -220.616272) (xy 40.21443 -220.615779)
			(xy 40.164003 -220.607887) (xy 40.115391 -220.592328) (xy 40.069753 -220.569473) (xy 40.048688 -220.555058)
			(xy 40.042098 -220.550741) (xy 40.027097 -220.545954) (xy 40.019224 -220.54566) (xy 39.50335 -220.54566)
			(xy 39.498052 -220.545143) (xy 39.490478 -220.537738) (xy 39.489888 -220.532452) (xy 37.545772 -220.532452)
			(xy 37.545437 -220.537787) (xy 37.537898 -220.545332) (xy 37.532564 -220.54566) (xy 37.01669 -220.54566)
			(xy 37.008816 -220.545949) (xy 36.993812 -220.550732) (xy 36.987226 -220.555058) (xy 36.96616 -220.569468)
			(xy 36.920511 -220.592292) (xy 36.871902 -220.607844) (xy 36.821482 -220.615758) (xy 36.795964 -220.616272)
			(xy 36.770444 -220.615772) (xy 36.720017 -220.607882) (xy 36.671406 -220.592325) (xy 36.625767 -220.569472)
			(xy 36.604702 -220.555058) (xy 36.598108 -220.550747) (xy 36.58311 -220.545957) (xy 36.575238 -220.54566)
			(xy 36.059364 -220.54566) (xy 36.054015 -220.545393) (xy 36.046473 -220.537803) (xy 36.046156 -220.532452)
			(xy 33.445704 -220.532452) (xy 33.44534 -220.537779) (xy 33.437822 -220.545323) (xy 33.432496 -220.54566)
			(xy 32.916622 -220.54566) (xy 32.908749 -220.545963) (xy 32.893745 -220.550736) (xy 32.887158 -220.555058)
			(xy 32.866083 -220.569454) (xy 32.820437 -220.592281) (xy 32.771831 -220.607837) (xy 32.721413 -220.615755)
			(xy 32.695896 -220.616272) (xy 32.670375 -220.615807) (xy 32.619947 -220.607905) (xy 32.571335 -220.592339)
			(xy 32.525698 -220.569477) (xy 32.504634 -220.555058) (xy 32.498033 -220.550759) (xy 32.48304 -220.545961)
			(xy 32.47517 -220.54566) (xy 31.959296 -220.54566) (xy 31.953951 -220.545371) (xy 31.946408 -220.537798)
			(xy 31.946088 -220.532452) (xy 30.001972 -220.532452) (xy 30.001637 -220.537787) (xy 29.994098 -220.545332)
			(xy 29.988764 -220.54566) (xy 29.47289 -220.54566) (xy 29.465016 -220.545949) (xy 29.450012 -220.550732)
			(xy 29.443426 -220.555058) (xy 29.42236 -220.569468) (xy 29.376711 -220.592292) (xy 29.328102 -220.607844)
			(xy 29.277682 -220.615758) (xy 29.252164 -220.616272) (xy 29.226644 -220.615772) (xy 29.176217 -220.607882)
			(xy 29.127606 -220.592325) (xy 29.081967 -220.569472) (xy 29.060902 -220.555058) (xy 29.054308 -220.550747)
			(xy 29.03931 -220.545957) (xy 29.031438 -220.54566) (xy 28.515564 -220.54566) (xy 28.510215 -220.545393)
			(xy 28.502673 -220.537803) (xy 28.502356 -220.532452) (xy 25.901904 -220.532452) (xy 25.90154 -220.537779)
			(xy 25.894022 -220.545323) (xy 25.888696 -220.54566) (xy 25.372822 -220.54566) (xy 25.364949 -220.545963)
			(xy 25.349945 -220.550736) (xy 25.343358 -220.555058) (xy 25.322283 -220.569454) (xy 25.276637 -220.592281)
			(xy 25.228031 -220.607837) (xy 25.177613 -220.615755) (xy 25.152096 -220.616272) (xy 25.126575 -220.615807)
			(xy 25.076147 -220.607905) (xy 25.027535 -220.592339) (xy 24.981898 -220.569477) (xy 24.960834 -220.555058)
			(xy 24.954233 -220.550759) (xy 24.93924 -220.545961) (xy 24.93137 -220.54566) (xy 24.415496 -220.54566)
			(xy 24.410151 -220.545371) (xy 24.402608 -220.537798) (xy 24.402288 -220.532452) (xy 22.458172 -220.532452)
			(xy 22.457837 -220.537787) (xy 22.450298 -220.545332) (xy 22.444964 -220.54566) (xy 22.444456 -220.54566)
			(xy 21.928836 -220.54566) (xy 21.920959 -220.545926) (xy 21.905955 -220.550724) (xy 21.899372 -220.555058)
			(xy 21.878294 -220.569448) (xy 21.832649 -220.592276) (xy 21.784043 -220.607835) (xy 21.733627 -220.615754)
			(xy 21.70811 -220.616272) (xy 21.682589 -220.6158) (xy 21.632161 -220.607901) (xy 21.58355 -220.592336)
			(xy 21.537912 -220.569476) (xy 21.516848 -220.555058) (xy 21.510266 -220.550726) (xy 21.495259 -220.545949)
			(xy 21.487384 -220.54566) (xy 20.97151 -220.54566) (xy 20.966207 -220.54517) (xy 20.958635 -220.537745)
			(xy 20.958048 -220.532452) (xy 18.358104 -220.532452) (xy 18.35774 -220.537779) (xy 18.350222 -220.545323)
			(xy 18.344896 -220.54566) (xy 18.344388 -220.54566) (xy 17.828768 -220.54566) (xy 17.820893 -220.54594)
			(xy 17.805889 -220.550729) (xy 17.799304 -220.555058) (xy 17.778217 -220.569434) (xy 17.732575 -220.592266)
			(xy 17.683972 -220.607828) (xy 17.633558 -220.615752) (xy 17.608042 -220.616272) (xy 17.582522 -220.615783)
			(xy 17.532095 -220.607889) (xy 17.483483 -220.592329) (xy 17.437845 -220.569474) (xy 17.41678 -220.555058)
			(xy 17.410191 -220.550738) (xy 17.395189 -220.545953) (xy 17.387316 -220.54566) (xy 16.871442 -220.54566)
			(xy 16.866143 -220.545149) (xy 16.858569 -220.537739) (xy 16.85798 -220.532452) (xy 2.509012 -220.532452)
			(xy 2.509012 -221.382336) (xy 16.85798 -221.382336) (xy 16.85798 -220.887798) (xy 16.858282 -220.882353)
			(xy 16.865996 -220.874664) (xy 16.871442 -220.874336) (xy 17.38757 -220.874336) (xy 17.39538 -220.87402)
			(xy 17.410252 -220.869237) (xy 17.41678 -220.864938) (xy 17.437869 -220.850589) (xy 17.48353 -220.827858)
			(xy 17.532136 -220.812399) (xy 17.582539 -220.804576) (xy 17.633545 -220.804576) (xy 17.683948 -220.812399)
			(xy 17.732554 -220.827858) (xy 17.778215 -220.850589) (xy 17.799304 -220.864938) (xy 17.805839 -220.869224)
			(xy 17.820706 -220.874011) (xy 17.828514 -220.874336) (xy 18.344642 -220.874336) (xy 18.350011 -220.874822)
			(xy 18.357594 -220.882428) (xy 18.358104 -220.887798) (xy 18.358104 -221.382336) (xy 24.402288 -221.382336)
			(xy 24.402288 -220.887798) (xy 24.402728 -220.882482) (xy 24.410188 -220.874909) (xy 24.415496 -220.874336)
			(xy 24.931624 -220.874336) (xy 24.939436 -220.874044) (xy 24.954308 -220.869244) (xy 24.960834 -220.864938)
			(xy 24.981923 -220.850589) (xy 25.027584 -220.827858) (xy 25.07619 -220.812399) (xy 25.126593 -220.804576)
			(xy 25.177599 -220.804576) (xy 25.228002 -220.812399) (xy 25.276608 -220.827858) (xy 25.322269 -220.850589)
			(xy 25.343358 -220.864938) (xy 25.349881 -220.869244) (xy 25.364757 -220.874019) (xy 25.372568 -220.874336)
			(xy 25.888696 -220.874336) (xy 25.894038 -220.874634) (xy 25.901582 -220.882201) (xy 25.901904 -220.887544)
			(xy 25.901904 -220.888052) (xy 25.901904 -221.382336) (xy 31.946088 -221.382336) (xy 31.946088 -220.887798)
			(xy 31.946528 -220.882482) (xy 31.953988 -220.874909) (xy 31.959296 -220.874336) (xy 32.475424 -220.874336)
			(xy 32.483236 -220.874044) (xy 32.498108 -220.869244) (xy 32.504634 -220.864938) (xy 32.525723 -220.850589)
			(xy 32.571384 -220.827858) (xy 32.61999 -220.812399) (xy 32.670393 -220.804576) (xy 32.721399 -220.804576)
			(xy 32.771802 -220.812399) (xy 32.820408 -220.827858) (xy 32.866069 -220.850589) (xy 32.887158 -220.864938)
			(xy 32.893681 -220.869244) (xy 32.908557 -220.874019) (xy 32.916368 -220.874336) (xy 33.432496 -220.874336)
			(xy 33.437838 -220.874634) (xy 33.445382 -220.882201) (xy 33.445704 -220.887544) (xy 33.445704 -220.888052)
			(xy 33.445704 -221.382336) (xy 39.489888 -221.382336) (xy 39.489888 -220.887798) (xy 39.490444 -220.882446)
			(xy 39.498 -220.874863) (xy 39.50335 -220.874336) (xy 40.019478 -220.874336) (xy 40.027288 -220.874024)
			(xy 40.04216 -220.869238) (xy 40.048688 -220.864938) (xy 40.069777 -220.850589) (xy 40.115438 -220.827858)
			(xy 40.164044 -220.812399) (xy 40.214447 -220.804576) (xy 40.265453 -220.804576) (xy 40.315856 -220.812399)
			(xy 40.364462 -220.827858) (xy 40.410123 -220.850589) (xy 40.431212 -220.864938) (xy 40.437745 -220.869227)
			(xy 40.452614 -220.874012) (xy 40.460422 -220.874336) (xy 40.97655 -220.874336) (xy 40.981919 -220.874817)
			(xy 40.989502 -220.882427) (xy 40.990012 -220.887798) (xy 40.990012 -221.382336) (xy 47.034196 -221.382336)
			(xy 47.034196 -220.887798) (xy 47.034716 -220.882504) (xy 47.042122 -220.874935) (xy 47.047404 -220.874336)
			(xy 47.563532 -220.874336) (xy 47.571341 -220.874004) (xy 47.586213 -220.869232) (xy 47.592742 -220.864938)
			(xy 47.613831 -220.850589) (xy 47.659492 -220.827858) (xy 47.708098 -220.812399) (xy 47.758501 -220.804576)
			(xy 47.809507 -220.804576) (xy 47.85991 -220.812399) (xy 47.908516 -220.827858) (xy 47.954177 -220.850589)
			(xy 47.975266 -220.864938) (xy 47.981809 -220.869209) (xy 47.99667 -220.874006) (xy 48.004476 -220.874336)
			(xy 48.520604 -220.874336) (xy 48.525948 -220.874629) (xy 48.533491 -220.882199) (xy 48.533812 -220.887544)
			(xy 48.533812 -220.888052) (xy 48.533812 -221.382336) (xy 54.577996 -221.382336) (xy 54.577996 -220.887798)
			(xy 54.578545 -220.882444) (xy 54.586106 -220.874861) (xy 54.591458 -220.874336) (xy 56.064658 -220.874336)
			(xy 56.070087 -220.874707) (xy 56.077775 -220.88237) (xy 56.07812 -220.887798) (xy 56.07812 -221.382336)
			(xy 163.678108 -221.382336) (xy 163.678108 -220.887798) (xy 163.678618 -220.882501) (xy 163.68603 -220.874932)
			(xy 163.691316 -220.874336) (xy 165.164516 -220.874336) (xy 165.169861 -220.87462) (xy 165.177404 -220.882197)
			(xy 165.177724 -220.887544) (xy 165.177724 -220.888052) (xy 165.177724 -221.382336) (xy 171.221908 -221.382336)
			(xy 171.221908 -220.887798) (xy 171.222446 -220.882441) (xy 171.230014 -220.874857) (xy 171.23537 -220.874336)
			(xy 171.751498 -220.874336) (xy 171.759309 -220.874032) (xy 171.774181 -220.86924) (xy 171.780708 -220.864938)
			(xy 171.801797 -220.850589) (xy 171.847458 -220.827858) (xy 171.896064 -220.812399) (xy 171.946467 -220.804576)
			(xy 171.997473 -220.804576) (xy 172.047876 -220.812399) (xy 172.096482 -220.827858) (xy 172.142143 -220.850589)
			(xy 172.163232 -220.864938) (xy 172.169761 -220.869234) (xy 172.184633 -220.874015) (xy 172.192442 -220.874336)
			(xy 172.70857 -220.874336) (xy 172.714 -220.874699) (xy 172.721688 -220.882369) (xy 172.722032 -220.887798)
			(xy 172.722032 -221.382336) (xy 178.766216 -221.382336) (xy 178.766216 -220.887798) (xy 178.766719 -220.882499)
			(xy 178.774136 -220.87493) (xy 178.779424 -220.874336) (xy 179.295552 -220.874336) (xy 179.303361 -220.874013)
			(xy 179.318233 -220.869234) (xy 179.324762 -220.864938) (xy 179.345851 -220.850589) (xy 179.391512 -220.827858)
			(xy 179.440118 -220.812399) (xy 179.490521 -220.804576) (xy 179.541527 -220.804576) (xy 179.59193 -220.812399)
			(xy 179.640536 -220.827858) (xy 179.686197 -220.850589) (xy 179.707286 -220.864938) (xy 179.713825 -220.869217)
			(xy 179.728689 -220.874009) (xy 179.736496 -220.874336) (xy 180.252624 -220.874336) (xy 180.25797 -220.874615)
			(xy 180.265512 -220.882196) (xy 180.265832 -220.887544) (xy 180.265832 -220.888052) (xy 180.265832 -221.382336)
			(xy 186.310016 -221.382336) (xy 186.310016 -220.887798) (xy 186.310547 -220.882439) (xy 186.31812 -220.874855)
			(xy 186.323478 -220.874336) (xy 186.839606 -220.874336) (xy 186.847417 -220.874035) (xy 186.862289 -220.869241)
			(xy 186.868816 -220.864938) (xy 186.889905 -220.850589) (xy 186.935566 -220.827858) (xy 186.984172 -220.812399)
			(xy 187.034575 -220.804576) (xy 187.085581 -220.804576) (xy 187.135984 -220.812399) (xy 187.18459 -220.827858)
			(xy 187.230251 -220.850589) (xy 187.25134 -220.864938) (xy 187.257867 -220.869237) (xy 187.27274 -220.874016)
			(xy 187.28055 -220.874336) (xy 187.796678 -220.874336) (xy 187.802109 -220.874694) (xy 187.809796 -220.882367)
			(xy 187.81014 -220.887798) (xy 187.81014 -221.382336) (xy 193.854324 -221.382336) (xy 193.854324 -220.887798)
			(xy 193.85482 -220.882497) (xy 193.862242 -220.874927) (xy 193.867532 -220.874336) (xy 194.38366 -220.874336)
			(xy 194.39147 -220.874016) (xy 194.406342 -220.869235) (xy 194.41287 -220.864938) (xy 194.433959 -220.850589)
			(xy 194.47962 -220.827858) (xy 194.528226 -220.812399) (xy 194.578629 -220.804576) (xy 194.629635 -220.804576)
			(xy 194.680038 -220.812399) (xy 194.728644 -220.827858) (xy 194.774305 -220.850589) (xy 194.795394 -220.864938)
			(xy 194.801931 -220.86922) (xy 194.816797 -220.87401) (xy 194.824604 -220.874336) (xy 195.340732 -220.874336)
			(xy 195.346079 -220.87461) (xy 195.353621 -220.882195) (xy 195.35394 -220.887544) (xy 195.35394 -220.888052)
			(xy 195.35394 -221.382336) (xy 201.398124 -221.382336) (xy 201.398124 -220.887798) (xy 201.39862 -220.882497)
			(xy 201.406042 -220.874927) (xy 201.411332 -220.874336) (xy 201.92746 -220.874336) (xy 201.93527 -220.874016)
			(xy 201.950142 -220.869235) (xy 201.95667 -220.864938) (xy 201.977759 -220.850589) (xy 202.02342 -220.827858)
			(xy 202.072026 -220.812399) (xy 202.122429 -220.804576) (xy 202.173435 -220.804576) (xy 202.223838 -220.812399)
			(xy 202.272444 -220.827858) (xy 202.318105 -220.850589) (xy 202.339194 -220.864938) (xy 202.345731 -220.86922)
			(xy 202.360597 -220.87401) (xy 202.368404 -220.874336) (xy 202.884532 -220.874336) (xy 202.889879 -220.87461)
			(xy 202.897421 -220.882195) (xy 202.89774 -220.887544) (xy 202.89774 -220.888052) (xy 202.89774 -221.382082)
			(xy 264.798048 -221.382082) (xy 264.798048 -220.887544) (xy 264.798619 -220.882297) (xy 264.806012 -220.874854)
			(xy 264.811256 -220.874336) (xy 264.811764 -220.874336) (xy 265.327638 -220.874336) (xy 265.335447 -220.874007)
			(xy 265.350319 -220.869233) (xy 265.356848 -220.864938) (xy 265.377937 -220.850589) (xy 265.423598 -220.827858)
			(xy 265.472204 -220.812399) (xy 265.522607 -220.804576) (xy 265.573613 -220.804576) (xy 265.624016 -220.812399)
			(xy 265.672622 -220.827858) (xy 265.718283 -220.850589) (xy 265.739372 -220.864938) (xy 265.745914 -220.869211)
			(xy 265.760776 -220.874007) (xy 265.768582 -220.874336) (xy 266.28471 -220.874336) (xy 266.290014 -220.874816)
			(xy 266.297585 -220.882249) (xy 266.298172 -220.887544) (xy 266.298172 -221.382082) (xy 266.298155 -221.382336)
			(xy 272.342356 -221.382336) (xy 272.342356 -221.381828) (xy 272.342356 -220.887544) (xy 272.342753 -220.882226)
			(xy 272.350249 -220.874685) (xy 272.355564 -220.874336) (xy 272.871692 -220.874336) (xy 272.879503 -220.87403)
			(xy 272.894375 -220.86924) (xy 272.900902 -220.864938) (xy 272.921991 -220.850589) (xy 272.967652 -220.827858)
			(xy 273.016258 -220.812399) (xy 273.066661 -220.804576) (xy 273.117667 -220.804576) (xy 273.16807 -220.812399)
			(xy 273.216676 -220.827858) (xy 273.262337 -220.850589) (xy 273.283426 -220.864938) (xy 273.289956 -220.869232)
			(xy 273.304827 -220.874014) (xy 273.312636 -220.874336) (xy 273.828764 -220.874336) (xy 273.834102 -220.874655)
			(xy 273.841648 -220.882206) (xy 273.841972 -220.887544) (xy 273.841972 -221.382082) (xy 273.841948 -221.382336)
			(xy 279.886156 -221.382336) (xy 279.886156 -221.381828) (xy 279.886156 -220.887544) (xy 279.886553 -220.882226)
			(xy 279.894049 -220.874685) (xy 279.899364 -220.874336) (xy 280.415492 -220.874336) (xy 280.423303 -220.87403)
			(xy 280.438175 -220.86924) (xy 280.444702 -220.864938) (xy 280.465791 -220.850589) (xy 280.511452 -220.827858)
			(xy 280.560058 -220.812399) (xy 280.610461 -220.804576) (xy 280.661467 -220.804576) (xy 280.71187 -220.812399)
			(xy 280.760476 -220.827858) (xy 280.806137 -220.850589) (xy 280.827226 -220.864938) (xy 280.833756 -220.869232)
			(xy 280.848627 -220.874014) (xy 280.856436 -220.874336) (xy 281.372564 -220.874336) (xy 281.377902 -220.874655)
			(xy 281.385448 -220.882206) (xy 281.385772 -220.887544) (xy 281.385772 -221.382082) (xy 287.429956 -221.382082)
			(xy 287.429956 -220.887544) (xy 287.430353 -220.882226) (xy 287.437849 -220.874685) (xy 287.443164 -220.874336)
			(xy 287.443672 -220.874336) (xy 287.959546 -220.874336) (xy 287.967355 -220.87401) (xy 287.982227 -220.869234)
			(xy 287.988756 -220.864938) (xy 288.009845 -220.850589) (xy 288.055506 -220.827858) (xy 288.104112 -220.812399)
			(xy 288.154515 -220.804576) (xy 288.205521 -220.804576) (xy 288.255924 -220.812399) (xy 288.30453 -220.827858)
			(xy 288.350191 -220.850589) (xy 288.37128 -220.864938) (xy 288.37782 -220.869214) (xy 288.392683 -220.874008)
			(xy 288.40049 -220.874336) (xy 288.916618 -220.874336) (xy 288.921923 -220.874811) (xy 288.929493 -220.882248)
			(xy 288.93008 -220.887544) (xy 288.93008 -221.382082) (xy 288.930054 -221.382336) (xy 294.974264 -221.382336)
			(xy 294.974264 -221.381828) (xy 294.974264 -220.887544) (xy 294.974654 -220.882224) (xy 294.982154 -220.874683)
			(xy 294.987472 -220.874336) (xy 295.5036 -220.874336) (xy 295.511411 -220.874033) (xy 295.526283 -220.869241)
			(xy 295.53281 -220.864938) (xy 295.553899 -220.850589) (xy 295.59956 -220.827858) (xy 295.648166 -220.812399)
			(xy 295.698569 -220.804576) (xy 295.749575 -220.804576) (xy 295.799978 -220.812399) (xy 295.848584 -220.827858)
			(xy 295.894245 -220.850589) (xy 295.915334 -220.864938) (xy 295.921862 -220.869235) (xy 295.936735 -220.874016)
			(xy 295.944544 -220.874336) (xy 296.460672 -220.874336) (xy 296.466011 -220.87465) (xy 296.473557 -220.882204)
			(xy 296.47388 -220.887544) (xy 296.47388 -221.382082) (xy 302.518064 -221.382082) (xy 302.518064 -220.887544)
			(xy 302.518454 -220.882224) (xy 302.525954 -220.874683) (xy 302.531272 -220.874336) (xy 304.004726 -220.874336)
			(xy 304.010032 -220.874806) (xy 304.017602 -220.882247) (xy 304.018188 -220.887544) (xy 304.018188 -221.382082)
			(xy 304.018162 -221.382336) (xy 411.618176 -221.382336) (xy 411.618176 -221.381828) (xy 411.618176 -220.887544)
			(xy 411.618555 -220.882221) (xy 411.626063 -220.874679) (xy 411.631384 -220.874336) (xy 413.104584 -220.874336)
			(xy 413.109925 -220.874642) (xy 413.117469 -220.882202) (xy 413.117792 -220.887544) (xy 413.117792 -221.382082)
			(xy 419.161976 -221.382082) (xy 419.161976 -220.887544) (xy 419.162355 -220.882221) (xy 419.169863 -220.874679)
			(xy 419.175184 -220.874336) (xy 419.175692 -220.874336) (xy 419.691566 -220.874336) (xy 419.699376 -220.874019)
			(xy 419.714248 -220.869236) (xy 419.720776 -220.864938) (xy 419.741865 -220.850589) (xy 419.787526 -220.827858)
			(xy 419.836132 -220.812399) (xy 419.886535 -220.804576) (xy 419.937541 -220.804576) (xy 419.987944 -220.812399)
			(xy 420.03655 -220.827858) (xy 420.082211 -220.850589) (xy 420.1033 -220.864938) (xy 420.109836 -220.869222)
			(xy 420.124702 -220.874011) (xy 420.13251 -220.874336) (xy 420.648638 -220.874336) (xy 420.653946 -220.874798)
			(xy 420.661514 -220.882245) (xy 420.6621 -220.887544) (xy 420.6621 -221.382082) (xy 420.662074 -221.382336)
			(xy 426.706284 -221.382336) (xy 426.706284 -221.381828) (xy 426.706284 -220.887544) (xy 426.706656 -220.882219)
			(xy 426.714169 -220.874676) (xy 426.719492 -220.874336) (xy 427.23562 -220.874336) (xy 427.243432 -220.874042)
			(xy 427.258304 -220.869244) (xy 427.26483 -220.864938) (xy 427.285919 -220.850589) (xy 427.33158 -220.827858)
			(xy 427.380186 -220.812399) (xy 427.430589 -220.804576) (xy 427.481595 -220.804576) (xy 427.531998 -220.812399)
			(xy 427.580604 -220.827858) (xy 427.626265 -220.850589) (xy 427.647354 -220.864938) (xy 427.653878 -220.869243)
			(xy 427.668754 -220.874019) (xy 427.676564 -220.874336) (xy 428.192692 -220.874336) (xy 428.198034 -220.874636)
			(xy 428.205578 -220.882201) (xy 428.2059 -220.887544) (xy 428.2059 -221.382082) (xy 434.250084 -221.382082)
			(xy 434.250084 -220.887544) (xy 434.250456 -220.882219) (xy 434.257969 -220.874676) (xy 434.263292 -220.874336)
			(xy 434.2638 -220.874336) (xy 434.779674 -220.874336) (xy 434.787484 -220.874022) (xy 434.802356 -220.869237)
			(xy 434.808884 -220.864938) (xy 434.829973 -220.850589) (xy 434.875634 -220.827858) (xy 434.92424 -220.812399)
			(xy 434.974643 -220.804576) (xy 435.025649 -220.804576) (xy 435.076052 -220.812399) (xy 435.124658 -220.827858)
			(xy 435.170319 -220.850589) (xy 435.191408 -220.864938) (xy 435.197942 -220.869225) (xy 435.21281 -220.874012)
			(xy 435.220618 -220.874336) (xy 435.736746 -220.874336) (xy 435.742043 -220.874859) (xy 435.749617 -220.88226)
			(xy 435.750208 -220.887544) (xy 435.750208 -221.382082) (xy 435.750181 -221.382336) (xy 441.794392 -221.382336)
			(xy 441.794392 -221.381828) (xy 441.794392 -220.887544) (xy 441.794756 -220.882218) (xy 441.802275 -220.874674)
			(xy 441.8076 -220.874336) (xy 442.323728 -220.874336) (xy 442.33154 -220.874045) (xy 442.346412 -220.869245)
			(xy 442.352938 -220.864938) (xy 442.374027 -220.850589) (xy 442.419688 -220.827858) (xy 442.468294 -220.812399)
			(xy 442.518697 -220.804576) (xy 442.569703 -220.804576) (xy 442.620106 -220.812399) (xy 442.668712 -220.827858)
			(xy 442.714373 -220.850589) (xy 442.735462 -220.864938) (xy 442.742006 -220.869207) (xy 442.756866 -220.874005)
			(xy 442.764672 -220.874336) (xy 443.2808 -220.874336) (xy 443.286143 -220.874631) (xy 443.293687 -220.8822)
			(xy 443.294008 -220.887544) (xy 443.294008 -221.382082) (xy 443.293982 -221.382336) (xy 449.338192 -221.382336)
			(xy 449.338192 -221.381828) (xy 449.338192 -220.887544) (xy 449.338556 -220.882218) (xy 449.346075 -220.874674)
			(xy 449.3514 -220.874336) (xy 449.867528 -220.874336) (xy 449.87534 -220.874045) (xy 449.890212 -220.869245)
			(xy 449.896738 -220.864938) (xy 449.917827 -220.850589) (xy 449.963488 -220.827858) (xy 450.012094 -220.812399)
			(xy 450.062497 -220.804576) (xy 450.113503 -220.804576) (xy 450.163906 -220.812399) (xy 450.212512 -220.827858)
			(xy 450.258173 -220.850589) (xy 450.279262 -220.864938) (xy 450.285806 -220.869207) (xy 450.300666 -220.874005)
			(xy 450.308472 -220.874336) (xy 450.8246 -220.874336) (xy 450.829943 -220.874631) (xy 450.837487 -220.8822)
			(xy 450.837808 -220.887544) (xy 450.837808 -221.382082) (xy 450.837271 -221.387373) (xy 450.829878 -221.394942)
			(xy 450.8246 -221.395544) (xy 450.308726 -221.395544) (xy 450.300916 -221.395862) (xy 450.286044 -221.400644)
			(xy 450.279516 -221.404942) (xy 450.258387 -221.419279) (xy 450.212666 -221.442009) (xy 450.163995 -221.457442)
			(xy 450.11353 -221.465213) (xy 450.088 -221.465648) (xy 450.06247 -221.465214) (xy 450.012006 -221.457438)
			(xy 449.963333 -221.442008) (xy 449.917606 -221.41929) (xy 449.896484 -221.404942) (xy 449.889953 -221.40065)
			(xy 449.875083 -221.395867) (xy 449.867274 -221.395544) (xy 449.3514 -221.395544) (xy 449.346146 -221.395009)
			(xy 449.338706 -221.387589) (xy 449.338192 -221.382336) (xy 443.293982 -221.382336) (xy 443.293471 -221.387373)
			(xy 443.286078 -221.394942) (xy 443.2808 -221.395544) (xy 442.764926 -221.395544) (xy 442.757116 -221.395862)
			(xy 442.742244 -221.400644) (xy 442.735716 -221.404942) (xy 442.714587 -221.419279) (xy 442.668866 -221.442009)
			(xy 442.620195 -221.457442) (xy 442.56973 -221.465213) (xy 442.5442 -221.465648) (xy 442.51867 -221.465214)
			(xy 442.468206 -221.457438) (xy 442.419533 -221.442008) (xy 442.373806 -221.41929) (xy 442.352684 -221.404942)
			(xy 442.346153 -221.40065) (xy 442.331283 -221.395867) (xy 442.323474 -221.395544) (xy 441.8076 -221.395544)
			(xy 441.802346 -221.395009) (xy 441.794906 -221.387589) (xy 441.794392 -221.382336) (xy 435.750181 -221.382336)
			(xy 435.749642 -221.387433) (xy 435.742094 -221.395017) (xy 435.736746 -221.395544) (xy 435.220872 -221.395544)
			(xy 435.21306 -221.395838) (xy 435.198188 -221.400637) (xy 435.191662 -221.404942) (xy 435.170548 -221.419303)
			(xy 435.124821 -221.442027) (xy 435.076146 -221.457454) (xy 435.025678 -221.465217) (xy 435.000146 -221.465648)
			(xy 434.974616 -221.465191) (xy 434.924153 -221.457422) (xy 434.875481 -221.441999) (xy 434.829752 -221.419287)
			(xy 434.80863 -221.404942) (xy 434.802089 -221.400668) (xy 434.787226 -221.395874) (xy 434.77942 -221.395544)
			(xy 434.263546 -221.395544) (xy 434.258113 -221.395188) (xy 434.250423 -221.387514) (xy 434.250084 -221.382082)
			(xy 428.2059 -221.382082) (xy 428.20537 -221.387375) (xy 428.197972 -221.394945) (xy 428.192692 -221.395544)
			(xy 427.676818 -221.395544) (xy 427.669008 -221.395858) (xy 427.654136 -221.400643) (xy 427.647608 -221.404942)
			(xy 427.626481 -221.419283) (xy 427.580759 -221.442012) (xy 427.532088 -221.457444) (xy 427.481623 -221.465213)
			(xy 427.456092 -221.465648) (xy 427.430561 -221.465218) (xy 427.380097 -221.457441) (xy 427.331425 -221.44201)
			(xy 427.285698 -221.419291) (xy 427.264576 -221.404942) (xy 427.258047 -221.400647) (xy 427.243175 -221.395866)
			(xy 427.235366 -221.395544) (xy 426.719492 -221.395544) (xy 426.714237 -221.395014) (xy 426.706797 -221.38759)
			(xy 426.706284 -221.382336) (xy 420.662074 -221.382336) (xy 420.661542 -221.387435) (xy 420.653989 -221.395019)
			(xy 420.648638 -221.395544) (xy 420.132764 -221.395544) (xy 420.124956 -221.395878) (xy 420.110084 -221.400649)
			(xy 420.103554 -221.404942) (xy 420.082442 -221.419306) (xy 420.036715 -221.44203) (xy 419.988039 -221.457456)
			(xy 419.93757 -221.465218) (xy 419.912038 -221.465648) (xy 419.886508 -221.465195) (xy 419.836045 -221.457425)
			(xy 419.787372 -221.442) (xy 419.741644 -221.419288) (xy 419.720522 -221.404942) (xy 419.713982 -221.400665)
			(xy 419.699119 -221.395872) (xy 419.691312 -221.395544) (xy 419.175438 -221.395544) (xy 419.170004 -221.395194)
			(xy 419.162314 -221.387516) (xy 419.161976 -221.382082) (xy 413.117792 -221.382082) (xy 413.117269 -221.387377)
			(xy 413.109866 -221.394947) (xy 413.104584 -221.395544) (xy 411.631384 -221.395544) (xy 411.626128 -221.39502)
			(xy 411.618688 -221.387591) (xy 411.618176 -221.382336) (xy 304.018162 -221.382336) (xy 304.01764 -221.387438)
			(xy 304.01008 -221.395023) (xy 304.004726 -221.395544) (xy 302.531526 -221.395544) (xy 302.52609 -221.395202)
			(xy 302.518402 -221.387518) (xy 302.518064 -221.382082) (xy 296.47388 -221.382082) (xy 296.473367 -221.387379)
			(xy 296.465958 -221.39495) (xy 296.460672 -221.395544) (xy 295.944798 -221.395544) (xy 295.936987 -221.395849)
			(xy 295.922115 -221.40064) (xy 295.915588 -221.404942) (xy 295.894466 -221.419291) (xy 295.848743 -221.442018)
			(xy 295.800069 -221.457448) (xy 295.749603 -221.465215) (xy 295.724072 -221.465648) (xy 295.698541 -221.465228)
			(xy 295.648076 -221.457448) (xy 295.599404 -221.442014) (xy 295.553677 -221.419292) (xy 295.532556 -221.404942)
			(xy 295.526031 -221.400639) (xy 295.511156 -221.395863) (xy 295.503346 -221.395544) (xy 294.987472 -221.395544)
			(xy 294.982215 -221.395028) (xy 294.974775 -221.387593) (xy 294.974264 -221.382336) (xy 288.930054 -221.382336)
			(xy 288.92954 -221.38744) (xy 288.921974 -221.395025) (xy 288.916618 -221.395544) (xy 288.400744 -221.395544)
			(xy 288.392935 -221.395869) (xy 288.378063 -221.400647) (xy 288.371534 -221.404942) (xy 288.350428 -221.419315)
			(xy 288.304698 -221.442036) (xy 288.25602 -221.45746) (xy 288.20555 -221.465219) (xy 288.180018 -221.465648)
			(xy 288.154488 -221.465205) (xy 288.104024 -221.457432) (xy 288.055352 -221.442005) (xy 288.009624 -221.419289)
			(xy 287.988502 -221.404942) (xy 287.981967 -221.400657) (xy 287.9671 -221.395869) (xy 287.959292 -221.395544)
			(xy 287.443418 -221.395544) (xy 287.437981 -221.395207) (xy 287.430293 -221.387519) (xy 287.429956 -221.382082)
			(xy 281.385772 -221.382082) (xy 281.385266 -221.387381) (xy 281.377852 -221.394953) (xy 281.372564 -221.395544)
			(xy 280.85669 -221.395544) (xy 280.848879 -221.395846) (xy 280.834007 -221.400639) (xy 280.82748 -221.404942)
			(xy 280.806361 -221.419295) (xy 280.760636 -221.442021) (xy 280.711962 -221.45745) (xy 280.661495 -221.465216)
			(xy 280.635964 -221.465648) (xy 280.610433 -221.465232) (xy 280.559968 -221.457451) (xy 280.511296 -221.442015)
			(xy 280.465569 -221.419293) (xy 280.444448 -221.404942) (xy 280.437925 -221.400636) (xy 280.423048 -221.395862)
			(xy 280.415238 -221.395544) (xy 279.899364 -221.395544) (xy 279.894106 -221.395033) (xy 279.886667 -221.387594)
			(xy 279.886156 -221.382336) (xy 273.841948 -221.382336) (xy 273.841466 -221.387381) (xy 273.834052 -221.394953)
			(xy 273.828764 -221.395544) (xy 273.31289 -221.395544) (xy 273.305079 -221.395846) (xy 273.290207 -221.400639)
			(xy 273.28368 -221.404942) (xy 273.262561 -221.419295) (xy 273.216836 -221.442021) (xy 273.168162 -221.45745)
			(xy 273.117695 -221.465216) (xy 273.092164 -221.465648) (xy 273.066633 -221.465232) (xy 273.016168 -221.457451)
			(xy 272.967496 -221.442015) (xy 272.921769 -221.419293) (xy 272.900648 -221.404942) (xy 272.894125 -221.400636)
			(xy 272.879248 -221.395862) (xy 272.871438 -221.395544) (xy 272.355564 -221.395544) (xy 272.350306 -221.395033)
			(xy 272.342867 -221.387594) (xy 272.342356 -221.382336) (xy 266.298155 -221.382336) (xy 266.29781 -221.387512)
			(xy 266.290139 -221.395199) (xy 266.28471 -221.395544) (xy 265.768836 -221.395544) (xy 265.761027 -221.395866)
			(xy 265.746155 -221.400646) (xy 265.739626 -221.404942) (xy 265.718494 -221.419275) (xy 265.672774 -221.442006)
			(xy 265.624104 -221.45744) (xy 265.57364 -221.465212) (xy 265.54811 -221.465648) (xy 265.52258 -221.465209)
			(xy 265.472116 -221.457435) (xy 265.423443 -221.442006) (xy 265.377716 -221.41929) (xy 265.356594 -221.404942)
			(xy 265.350061 -221.400654) (xy 265.335192 -221.395868) (xy 265.327384 -221.395544) (xy 264.81151 -221.395544)
			(xy 264.806072 -221.395212) (xy 264.798384 -221.38752) (xy 264.798048 -221.382082) (xy 202.89774 -221.382082)
			(xy 202.89774 -221.382336) (xy 202.897232 -221.387595) (xy 202.889791 -221.395034) (xy 202.884532 -221.395544)
			(xy 202.368658 -221.395544) (xy 202.360783 -221.395822) (xy 202.345779 -221.400612) (xy 202.339194 -221.404942)
			(xy 202.318108 -221.41932) (xy 202.272466 -221.442152) (xy 202.223863 -221.457713) (xy 202.173448 -221.465637)
			(xy 202.147932 -221.466156) (xy 202.122411 -221.465675) (xy 202.071984 -221.457779) (xy 202.023372 -221.442217)
			(xy 201.977734 -221.419359) (xy 201.95667 -221.404942) (xy 201.950084 -221.400617) (xy 201.93508 -221.395836)
			(xy 201.927206 -221.395544) (xy 201.411332 -221.395544) (xy 201.406082 -221.394988) (xy 201.398639 -221.387584)
			(xy 201.398124 -221.382336) (xy 195.35394 -221.382336) (xy 195.353432 -221.387595) (xy 195.345991 -221.395034)
			(xy 195.340732 -221.395544) (xy 194.824858 -221.395544) (xy 194.816983 -221.395822) (xy 194.801979 -221.400612)
			(xy 194.795394 -221.404942) (xy 194.774308 -221.41932) (xy 194.728666 -221.442152) (xy 194.680063 -221.457713)
			(xy 194.629648 -221.465637) (xy 194.604132 -221.466156) (xy 194.578611 -221.465675) (xy 194.528184 -221.457779)
			(xy 194.479572 -221.442217) (xy 194.433934 -221.419359) (xy 194.41287 -221.404942) (xy 194.406284 -221.400617)
			(xy 194.39128 -221.395836) (xy 194.383406 -221.395544) (xy 193.867532 -221.395544) (xy 193.862282 -221.394988)
			(xy 193.854839 -221.387584) (xy 193.854324 -221.382336) (xy 187.81014 -221.382336) (xy 187.809632 -221.387595)
			(xy 187.802191 -221.395034) (xy 187.796932 -221.395544) (xy 187.796424 -221.395544) (xy 187.280804 -221.395544)
			(xy 187.27293 -221.395842) (xy 187.257926 -221.400619) (xy 187.25134 -221.404942) (xy 187.230269 -221.419344)
			(xy 187.184622 -221.44217) (xy 187.136014 -221.457725) (xy 187.085595 -221.465641) (xy 187.060078 -221.466156)
			(xy 187.034558 -221.465652) (xy 186.984132 -221.457763) (xy 186.93552 -221.442208) (xy 186.889881 -221.419356)
			(xy 186.868816 -221.404942) (xy 186.86222 -221.400635) (xy 186.847224 -221.395842) (xy 186.839352 -221.395544)
			(xy 186.323478 -221.395544) (xy 186.318167 -221.39509) (xy 186.310597 -221.387638) (xy 186.310016 -221.382336)
			(xy 180.265832 -221.382336) (xy 180.265331 -221.387597) (xy 180.257886 -221.395036) (xy 180.252624 -221.395544)
			(xy 179.73675 -221.395544) (xy 179.728874 -221.395819) (xy 179.71387 -221.400611) (xy 179.707286 -221.404942)
			(xy 179.686202 -221.419324) (xy 179.64056 -221.442155) (xy 179.591956 -221.457715) (xy 179.54154 -221.465637)
			(xy 179.516024 -221.466156) (xy 179.490503 -221.465679) (xy 179.440075 -221.457782) (xy 179.391464 -221.442219)
			(xy 179.345826 -221.41936) (xy 179.324762 -221.404942) (xy 179.318178 -221.400614) (xy 179.303172 -221.395834)
			(xy 179.295298 -221.395544) (xy 178.779424 -221.395544) (xy 178.774173 -221.394993) (xy 178.766731 -221.387585)
			(xy 178.766216 -221.382336) (xy 172.722032 -221.382336) (xy 172.721531 -221.387597) (xy 172.714086 -221.395036)
			(xy 172.708824 -221.395544) (xy 172.708316 -221.395544) (xy 172.192696 -221.395544) (xy 172.184822 -221.395839)
			(xy 172.169818 -221.400618) (xy 172.163232 -221.404942) (xy 172.142163 -221.419347) (xy 172.096515 -221.442173)
			(xy 172.047907 -221.457727) (xy 171.997487 -221.465641) (xy 171.97197 -221.466156) (xy 171.94645 -221.465656)
			(xy 171.896023 -221.457766) (xy 171.847411 -221.442209) (xy 171.801773 -221.419357) (xy 171.780708 -221.404942)
			(xy 171.774114 -221.400631) (xy 171.759116 -221.395841) (xy 171.751244 -221.395544) (xy 171.23537 -221.395544)
			(xy 171.230058 -221.395095) (xy 171.222488 -221.387639) (xy 171.221908 -221.382336) (xy 165.177724 -221.382336)
			(xy 165.177231 -221.387599) (xy 165.16978 -221.395039) (xy 165.164516 -221.395544) (xy 163.691316 -221.395544)
			(xy 163.686064 -221.394998) (xy 163.678622 -221.387586) (xy 163.678108 -221.382336) (xy 56.07812 -221.382336)
			(xy 56.07763 -221.3876) (xy 56.070177 -221.39504) (xy 56.064912 -221.395544) (xy 54.591458 -221.395544)
			(xy 54.586145 -221.395103) (xy 54.578575 -221.387641) (xy 54.577996 -221.382336) (xy 48.533812 -221.382336)
			(xy 48.533329 -221.387602) (xy 48.525871 -221.395042) (xy 48.520604 -221.395544) (xy 48.00473 -221.395544)
			(xy 47.996854 -221.39581) (xy 47.98185 -221.400609) (xy 47.975266 -221.404942) (xy 47.954188 -221.419333)
			(xy 47.908543 -221.442161) (xy 47.859938 -221.457719) (xy 47.809521 -221.465639) (xy 47.784004 -221.466156)
			(xy 47.758483 -221.465689) (xy 47.708055 -221.457789) (xy 47.659443 -221.442223) (xy 47.613806 -221.419361)
			(xy 47.592742 -221.404942) (xy 47.586163 -221.400606) (xy 47.571153 -221.395831) (xy 47.563278 -221.395544)
			(xy 47.047404 -221.395544) (xy 47.04215 -221.395006) (xy 47.03471 -221.387588) (xy 47.034196 -221.382336)
			(xy 40.990012 -221.382336) (xy 40.989529 -221.387602) (xy 40.982071 -221.395042) (xy 40.976804 -221.395544)
			(xy 40.976296 -221.395544) (xy 40.460676 -221.395544) (xy 40.452801 -221.39583) (xy 40.437797 -221.400615)
			(xy 40.431212 -221.404942) (xy 40.410149 -221.419356) (xy 40.364499 -221.442179) (xy 40.315889 -221.457731)
			(xy 40.265468 -221.465643) (xy 40.23995 -221.466156) (xy 40.21443 -221.465666) (xy 40.164002 -221.457773)
			(xy 40.115391 -221.442213) (xy 40.069753 -221.419358) (xy 40.048688 -221.404942) (xy 40.042098 -221.400624)
			(xy 40.027097 -221.395838) (xy 40.019224 -221.395544) (xy 39.50335 -221.395544) (xy 39.498048 -221.395042)
			(xy 39.490473 -221.387627) (xy 39.489888 -221.382336) (xy 33.445704 -221.382336) (xy 33.445229 -221.387604)
			(xy 33.437765 -221.395045) (xy 33.432496 -221.395544) (xy 32.916622 -221.395544) (xy 32.908749 -221.39585)
			(xy 32.893745 -221.400621) (xy 32.887158 -221.404942) (xy 32.866082 -221.419336) (xy 32.820437 -221.442164)
			(xy 32.77183 -221.457721) (xy 32.721413 -221.465639) (xy 32.695896 -221.466156) (xy 32.670375 -221.465693)
			(xy 32.619946 -221.457792) (xy 32.571335 -221.442224) (xy 32.525698 -221.419361) (xy 32.504634 -221.404942)
			(xy 32.498034 -221.400641) (xy 32.483041 -221.395845) (xy 32.47517 -221.395544) (xy 31.959296 -221.395544)
			(xy 31.954041 -221.395012) (xy 31.946601 -221.387589) (xy 31.946088 -221.382336) (xy 25.901904 -221.382336)
			(xy 25.901429 -221.387604) (xy 25.893965 -221.395045) (xy 25.888696 -221.395544) (xy 25.372822 -221.395544)
			(xy 25.364949 -221.39585) (xy 25.349945 -221.400621) (xy 25.343358 -221.404942) (xy 25.322282 -221.419336)
			(xy 25.276637 -221.442164) (xy 25.22803 -221.457721) (xy 25.177613 -221.465639) (xy 25.152096 -221.466156)
			(xy 25.126575 -221.465693) (xy 25.076146 -221.457792) (xy 25.027535 -221.442224) (xy 24.981898 -221.419361)
			(xy 24.960834 -221.404942) (xy 24.954234 -221.400641) (xy 24.939241 -221.395845) (xy 24.93137 -221.395544)
			(xy 24.415496 -221.395544) (xy 24.410241 -221.395012) (xy 24.402801 -221.387589) (xy 24.402288 -221.382336)
			(xy 18.358104 -221.382336) (xy 18.357629 -221.387604) (xy 18.350165 -221.395045) (xy 18.344896 -221.395544)
			(xy 18.344388 -221.395544) (xy 17.828768 -221.395544) (xy 17.820893 -221.395827) (xy 17.805889 -221.400614)
			(xy 17.799304 -221.404942) (xy 17.778215 -221.419316) (xy 17.732575 -221.442149) (xy 17.683972 -221.457711)
			(xy 17.633558 -221.465636) (xy 17.608042 -221.466156) (xy 17.582522 -221.46567) (xy 17.532094 -221.457776)
			(xy 17.483482 -221.442215) (xy 17.437844 -221.419358) (xy 17.41678 -221.404942) (xy 17.410192 -221.400621)
			(xy 17.395189 -221.395837) (xy 17.387316 -221.395544) (xy 16.871442 -221.395544) (xy 16.866139 -221.395047)
			(xy 16.858565 -221.387628) (xy 16.85798 -221.382336) (xy 2.509012 -221.382336) (xy 2.509012 -222.232474)
			(xy 20.958048 -222.232474) (xy 20.958048 -221.737936) (xy 20.958614 -221.732688) (xy 20.966011 -221.725246)
			(xy 20.971256 -221.724728) (xy 20.971764 -221.724728) (xy 21.487638 -221.724728) (xy 21.495447 -221.7244)
			(xy 21.510319 -221.719625) (xy 21.516848 -221.71533) (xy 21.537937 -221.700981) (xy 21.583598 -221.67825)
			(xy 21.632204 -221.662791) (xy 21.682607 -221.654968) (xy 21.733613 -221.654968) (xy 21.784016 -221.662791)
			(xy 21.832622 -221.67825) (xy 21.878283 -221.700981) (xy 21.899372 -221.71533) (xy 21.905915 -221.719603)
			(xy 21.920776 -221.724398) (xy 21.928582 -221.724728) (xy 22.44471 -221.724728) (xy 22.450013 -221.725215)
			(xy 22.457582 -221.732644) (xy 22.458172 -221.737936) (xy 22.458172 -222.232474) (xy 22.458155 -222.232728)
			(xy 28.502356 -222.232728) (xy 28.502356 -222.23222) (xy 28.502356 -221.737936) (xy 28.502915 -221.732686)
			(xy 28.510317 -221.725244) (xy 28.515564 -221.724728) (xy 29.031692 -221.724728) (xy 29.039503 -221.724423)
			(xy 29.054375 -221.719632) (xy 29.060902 -221.71533) (xy 29.081991 -221.700981) (xy 29.127652 -221.67825)
			(xy 29.176258 -221.662791) (xy 29.226661 -221.654968) (xy 29.277667 -221.654968) (xy 29.32807 -221.662791)
			(xy 29.376676 -221.67825) (xy 29.422337 -221.700981) (xy 29.443426 -221.71533) (xy 29.449957 -221.719623)
			(xy 29.464827 -221.724406) (xy 29.472636 -221.724728) (xy 29.988764 -221.724728) (xy 29.9941 -221.725054)
			(xy 30.001646 -221.7326) (xy 30.001972 -221.737936) (xy 30.001972 -222.232474) (xy 30.001948 -222.232728)
			(xy 36.046156 -222.232728) (xy 36.046156 -222.23222) (xy 36.046156 -221.737936) (xy 36.046715 -221.732686)
			(xy 36.054117 -221.725244) (xy 36.059364 -221.724728) (xy 36.575492 -221.724728) (xy 36.583303 -221.724423)
			(xy 36.598175 -221.719632) (xy 36.604702 -221.71533) (xy 36.625791 -221.700981) (xy 36.671452 -221.67825)
			(xy 36.720058 -221.662791) (xy 36.770461 -221.654968) (xy 36.821467 -221.654968) (xy 36.87187 -221.662791)
			(xy 36.920476 -221.67825) (xy 36.966137 -221.700981) (xy 36.987226 -221.71533) (xy 36.993757 -221.719623)
			(xy 37.008627 -221.724406) (xy 37.016436 -221.724728) (xy 37.532564 -221.724728) (xy 37.5379 -221.725054)
			(xy 37.545446 -221.7326) (xy 37.545772 -221.737936) (xy 37.545772 -222.232474) (xy 43.589956 -222.232474)
			(xy 43.589956 -221.737936) (xy 43.590515 -221.732686) (xy 43.597917 -221.725244) (xy 43.603164 -221.724728)
			(xy 43.603672 -221.724728) (xy 44.119546 -221.724728) (xy 44.127355 -221.724403) (xy 44.142227 -221.719626)
			(xy 44.148756 -221.71533) (xy 44.169845 -221.700981) (xy 44.215506 -221.67825) (xy 44.264112 -221.662791)
			(xy 44.314515 -221.654968) (xy 44.365521 -221.654968) (xy 44.415924 -221.662791) (xy 44.46453 -221.67825)
			(xy 44.510191 -221.700981) (xy 44.53128 -221.71533) (xy 44.537821 -221.719606) (xy 44.552683 -221.7244)
			(xy 44.56049 -221.724728) (xy 45.076618 -221.724728) (xy 45.081922 -221.72521) (xy 45.089491 -221.732642)
			(xy 45.09008 -221.737936) (xy 45.09008 -222.232474) (xy 45.090062 -222.232728) (xy 51.134264 -222.232728)
			(xy 51.134264 -222.23222) (xy 51.134264 -221.737936) (xy 51.134648 -221.732615) (xy 51.142153 -221.725074)
			(xy 51.147472 -221.724728) (xy 51.6636 -221.724728) (xy 51.671411 -221.724426) (xy 51.686283 -221.719633)
			(xy 51.69281 -221.71533) (xy 51.713899 -221.700981) (xy 51.75956 -221.67825) (xy 51.808166 -221.662791)
			(xy 51.858569 -221.654968) (xy 51.909575 -221.654968) (xy 51.959978 -221.662791) (xy 52.008584 -221.67825)
			(xy 52.054245 -221.700981) (xy 52.075334 -221.71533) (xy 52.081863 -221.719626) (xy 52.096735 -221.724407)
			(xy 52.104544 -221.724728) (xy 52.620672 -221.724728) (xy 52.626009 -221.725049) (xy 52.633554 -221.732598)
			(xy 52.63388 -221.737936) (xy 52.63388 -222.232474) (xy 58.678064 -222.232474) (xy 58.678064 -221.737936)
			(xy 58.678448 -221.732615) (xy 58.685953 -221.725074) (xy 58.691272 -221.724728) (xy 58.69178 -221.724728)
			(xy 60.164726 -221.724728) (xy 60.17003 -221.725205) (xy 60.177599 -221.732641) (xy 60.178188 -221.737936)
			(xy 60.178188 -222.232474) (xy 60.178162 -222.232728) (xy 167.778176 -222.232728) (xy 167.778176 -221.737936)
			(xy 167.778549 -221.732612) (xy 167.786062 -221.72507) (xy 167.791384 -221.724728) (xy 169.264584 -221.724728)
			(xy 169.269923 -221.725041) (xy 169.277467 -221.732597) (xy 169.277792 -221.737936) (xy 169.277792 -222.232474)
			(xy 175.321976 -222.232474) (xy 175.321976 -221.737936) (xy 175.322349 -221.732612) (xy 175.329862 -221.72507)
			(xy 175.335184 -221.724728) (xy 175.335692 -221.724728) (xy 175.851566 -221.724728) (xy 175.859376 -221.724412)
			(xy 175.874248 -221.719629) (xy 175.880776 -221.71533) (xy 175.901865 -221.700981) (xy 175.947526 -221.67825)
			(xy 175.996132 -221.662791) (xy 176.046535 -221.654968) (xy 176.097541 -221.654968) (xy 176.147944 -221.662791)
			(xy 176.19655 -221.67825) (xy 176.242211 -221.700981) (xy 176.2633 -221.71533) (xy 176.269836 -221.719613)
			(xy 176.284702 -221.724403) (xy 176.29251 -221.724728) (xy 176.808638 -221.724728) (xy 176.813944 -221.725197)
			(xy 176.821512 -221.732639) (xy 176.8221 -221.737936) (xy 176.8221 -222.232474) (xy 176.822073 -222.232728)
			(xy 182.866284 -222.232728) (xy 182.866284 -222.23222) (xy 182.866284 -221.737936) (xy 182.86665 -221.73261)
			(xy 182.874168 -221.725068) (xy 182.879492 -221.724728) (xy 183.39562 -221.724728) (xy 183.403432 -221.724435)
			(xy 183.418304 -221.719636) (xy 183.42483 -221.71533) (xy 183.445919 -221.700981) (xy 183.49158 -221.67825)
			(xy 183.540186 -221.662791) (xy 183.590589 -221.654968) (xy 183.641595 -221.654968) (xy 183.691998 -221.662791)
			(xy 183.740604 -221.67825) (xy 183.786265 -221.700981) (xy 183.807354 -221.71533) (xy 183.813878 -221.719634)
			(xy 183.828754 -221.72441) (xy 183.836564 -221.724728) (xy 184.352692 -221.724728) (xy 184.358032 -221.725036)
			(xy 184.365576 -221.732595) (xy 184.3659 -221.737936) (xy 184.3659 -222.232474) (xy 190.410084 -222.232474)
			(xy 190.410084 -221.737936) (xy 190.41045 -221.73261) (xy 190.417968 -221.725068) (xy 190.423292 -221.724728)
			(xy 190.4238 -221.724728) (xy 190.939674 -221.724728) (xy 190.947484 -221.724415) (xy 190.962356 -221.71963)
			(xy 190.968884 -221.71533) (xy 190.989973 -221.700981) (xy 191.035634 -221.67825) (xy 191.08424 -221.662791)
			(xy 191.134643 -221.654968) (xy 191.185649 -221.654968) (xy 191.236052 -221.662791) (xy 191.284658 -221.67825)
			(xy 191.330319 -221.700981) (xy 191.351408 -221.71533) (xy 191.357943 -221.719616) (xy 191.37281 -221.724404)
			(xy 191.380618 -221.724728) (xy 191.896746 -221.724728) (xy 191.902041 -221.725258) (xy 191.909614 -221.732654)
			(xy 191.910208 -221.737936) (xy 191.910208 -222.232474) (xy 191.910181 -222.232728) (xy 197.954392 -222.232728)
			(xy 197.954392 -222.23222) (xy 197.954392 -221.737936) (xy 197.954751 -221.732608) (xy 197.962273 -221.725065)
			(xy 197.9676 -221.724728) (xy 198.483728 -221.724728) (xy 198.49154 -221.724438) (xy 198.506412 -221.719637)
			(xy 198.512938 -221.71533) (xy 198.534027 -221.700981) (xy 198.579688 -221.67825) (xy 198.628294 -221.662791)
			(xy 198.678697 -221.654968) (xy 198.729703 -221.654968) (xy 198.780106 -221.662791) (xy 198.828712 -221.67825)
			(xy 198.874373 -221.700981) (xy 198.895462 -221.71533) (xy 198.902007 -221.719599) (xy 198.916866 -221.724397)
			(xy 198.924672 -221.724728) (xy 199.4408 -221.724728) (xy 199.446141 -221.72503) (xy 199.453684 -221.732594)
			(xy 199.454008 -221.737936) (xy 199.454008 -222.232474) (xy 199.453982 -222.232728) (xy 205.498192 -222.232728)
			(xy 205.498192 -222.23222) (xy 205.498192 -221.737936) (xy 205.498551 -221.732608) (xy 205.506073 -221.725065)
			(xy 205.5114 -221.724728) (xy 206.027528 -221.724728) (xy 206.03534 -221.724438) (xy 206.050212 -221.719637)
			(xy 206.056738 -221.71533) (xy 206.077827 -221.700981) (xy 206.123488 -221.67825) (xy 206.172094 -221.662791)
			(xy 206.222497 -221.654968) (xy 206.273503 -221.654968) (xy 206.323906 -221.662791) (xy 206.372512 -221.67825)
			(xy 206.418173 -221.700981) (xy 206.439262 -221.71533) (xy 206.445807 -221.719599) (xy 206.460666 -221.724397)
			(xy 206.468472 -221.724728) (xy 206.9846 -221.724728) (xy 206.989941 -221.72503) (xy 206.997484 -221.732594)
			(xy 206.997808 -221.737936) (xy 206.997808 -222.23222) (xy 268.898116 -222.23222) (xy 268.898116 -221.737682)
			(xy 268.898636 -221.732321) (xy 268.906217 -221.724738) (xy 268.911578 -221.72422) (xy 269.427706 -221.72422)
			(xy 269.435518 -221.723922) (xy 269.45039 -221.719127) (xy 269.456916 -221.714822) (xy 269.478005 -221.700473)
			(xy 269.523666 -221.677742) (xy 269.572272 -221.662283) (xy 269.622675 -221.65446) (xy 269.673681 -221.65446)
			(xy 269.724084 -221.662283) (xy 269.77269 -221.677742) (xy 269.818351 -221.700473) (xy 269.83944 -221.714822)
			(xy 269.845968 -221.71912) (xy 269.86084 -221.7239) (xy 269.86865 -221.72422) (xy 270.384778 -221.72422)
			(xy 270.390205 -221.724592) (xy 270.397892 -221.732256) (xy 270.39824 -221.737682) (xy 270.39824 -222.23222)
			(xy 276.442424 -222.23222) (xy 276.442424 -221.737682) (xy 276.442909 -221.732379) (xy 276.450339 -221.72481)
			(xy 276.455632 -221.72422) (xy 276.97176 -221.72422) (xy 276.97957 -221.723903) (xy 276.994442 -221.719121)
			(xy 277.00097 -221.714822) (xy 277.022059 -221.700473) (xy 277.06772 -221.677742) (xy 277.116326 -221.662283)
			(xy 277.166729 -221.65446) (xy 277.217735 -221.65446) (xy 277.268138 -221.662283) (xy 277.316744 -221.677742)
			(xy 277.362405 -221.700473) (xy 277.383494 -221.714822) (xy 277.390032 -221.719102) (xy 277.404897 -221.723894)
			(xy 277.412704 -221.72422) (xy 277.928832 -221.72422) (xy 277.934105 -221.724676) (xy 277.941548 -221.732152)
			(xy 277.94204 -221.737428) (xy 277.94204 -221.737936) (xy 277.94204 -222.23222) (xy 283.986224 -222.23222)
			(xy 283.986224 -221.737682) (xy 283.986709 -221.732379) (xy 283.994139 -221.72481) (xy 283.999432 -221.72422)
			(xy 284.51556 -221.72422) (xy 284.52337 -221.723903) (xy 284.538242 -221.719121) (xy 284.54477 -221.714822)
			(xy 284.565859 -221.700473) (xy 284.61152 -221.677742) (xy 284.660126 -221.662283) (xy 284.710529 -221.65446)
			(xy 284.761535 -221.65446) (xy 284.811938 -221.662283) (xy 284.860544 -221.677742) (xy 284.906205 -221.700473)
			(xy 284.927294 -221.714822) (xy 284.933832 -221.719102) (xy 284.948697 -221.723894) (xy 284.956504 -221.72422)
			(xy 285.472632 -221.72422) (xy 285.477905 -221.724676) (xy 285.485348 -221.732152) (xy 285.48584 -221.737428)
			(xy 285.48584 -221.737936) (xy 285.48584 -222.23222) (xy 291.530024 -222.23222) (xy 291.530024 -221.737682)
			(xy 291.530537 -221.732319) (xy 291.538123 -221.724735) (xy 291.543486 -221.72422) (xy 292.059614 -221.72422)
			(xy 292.067426 -221.723926) (xy 292.082298 -221.719128) (xy 292.088824 -221.714822) (xy 292.109913 -221.700473)
			(xy 292.155574 -221.677742) (xy 292.20418 -221.662283) (xy 292.254583 -221.65446) (xy 292.305589 -221.65446)
			(xy 292.355992 -221.662283) (xy 292.404598 -221.677742) (xy 292.450259 -221.700473) (xy 292.471348 -221.714822)
			(xy 292.477874 -221.719123) (xy 292.492748 -221.723901) (xy 292.500558 -221.72422) (xy 293.016686 -221.72422)
			(xy 293.022044 -221.724758) (xy 293.029629 -221.732325) (xy 293.030148 -221.737682) (xy 293.030148 -222.23222)
			(xy 299.074332 -222.23222) (xy 299.074332 -221.737682) (xy 299.07481 -221.732377) (xy 299.082245 -221.724808)
			(xy 299.08754 -221.72422) (xy 299.603668 -221.72422) (xy 299.611478 -221.723906) (xy 299.62635 -221.719122)
			(xy 299.632878 -221.714822) (xy 299.653967 -221.700473) (xy 299.699628 -221.677742) (xy 299.748234 -221.662283)
			(xy 299.798637 -221.65446) (xy 299.849643 -221.65446) (xy 299.900046 -221.662283) (xy 299.948652 -221.677742)
			(xy 299.994313 -221.700473) (xy 300.015402 -221.714822) (xy 300.021938 -221.719105) (xy 300.036804 -221.723895)
			(xy 300.044612 -221.72422) (xy 300.56074 -221.72422) (xy 300.566014 -221.724671) (xy 300.573456 -221.732151)
			(xy 300.573948 -221.737428) (xy 300.573948 -221.737936) (xy 300.573948 -222.23222) (xy 306.618132 -222.23222)
			(xy 306.618132 -221.737682) (xy 306.618638 -221.732317) (xy 306.626229 -221.724733) (xy 306.631594 -221.72422)
			(xy 308.104794 -221.72422) (xy 308.110153 -221.724752) (xy 308.117738 -221.732324) (xy 308.118256 -221.737682)
			(xy 308.118256 -222.23222) (xy 415.718244 -222.23222) (xy 415.718244 -221.737682) (xy 415.718712 -221.732375)
			(xy 415.726154 -221.724804) (xy 415.731452 -221.72422) (xy 417.204652 -221.72422) (xy 417.209985 -221.724562)
			(xy 417.21753 -221.732096) (xy 417.21786 -221.737428) (xy 417.21786 -222.23222) (xy 423.262044 -222.23222)
			(xy 423.262044 -221.737682) (xy 423.262539 -221.732314) (xy 423.270138 -221.724729) (xy 423.275506 -221.72422)
			(xy 423.791634 -221.72422) (xy 423.799443 -221.723892) (xy 423.814315 -221.719117) (xy 423.820844 -221.714822)
			(xy 423.841933 -221.700473) (xy 423.887594 -221.677742) (xy 423.9362 -221.662283) (xy 423.986603 -221.65446)
			(xy 424.037609 -221.65446) (xy 424.088012 -221.662283) (xy 424.136618 -221.677742) (xy 424.182279 -221.700473)
			(xy 424.203368 -221.714822) (xy 424.209912 -221.719092) (xy 424.224772 -221.72389) (xy 424.232578 -221.72422)
			(xy 424.748706 -221.72422) (xy 424.754066 -221.724744) (xy 424.761651 -221.732322) (xy 424.762168 -221.737682)
			(xy 424.762168 -222.23222) (xy 430.806352 -222.23222) (xy 430.806352 -221.737682) (xy 430.806812 -221.732373)
			(xy 430.81426 -221.724802) (xy 430.81956 -221.72422) (xy 431.335688 -221.72422) (xy 431.343499 -221.723915)
			(xy 431.358371 -221.719124) (xy 431.364898 -221.714822) (xy 431.385987 -221.700473) (xy 431.431648 -221.677742)
			(xy 431.480254 -221.662283) (xy 431.530657 -221.65446) (xy 431.581663 -221.65446) (xy 431.632066 -221.662283)
			(xy 431.680672 -221.677742) (xy 431.726333 -221.700473) (xy 431.747422 -221.714822) (xy 431.753954 -221.719113)
			(xy 431.768823 -221.723898) (xy 431.776632 -221.72422) (xy 432.29276 -221.72422) (xy 432.298094 -221.724557)
			(xy 432.305639 -221.732095) (xy 432.305968 -221.737428) (xy 432.305968 -221.737936) (xy 432.305968 -222.23222)
			(xy 438.350152 -222.23222) (xy 438.350152 -221.737682) (xy 438.35064 -221.732312) (xy 438.358243 -221.724727)
			(xy 438.363614 -221.72422) (xy 438.879742 -221.72422) (xy 438.887551 -221.723895) (xy 438.902423 -221.719118)
			(xy 438.908952 -221.714822) (xy 438.930041 -221.700473) (xy 438.975702 -221.677742) (xy 439.024308 -221.662283)
			(xy 439.074711 -221.65446) (xy 439.125717 -221.65446) (xy 439.17612 -221.662283) (xy 439.224726 -221.677742)
			(xy 439.270387 -221.700473) (xy 439.291476 -221.714822) (xy 439.298018 -221.719095) (xy 439.31288 -221.723891)
			(xy 439.320686 -221.72422) (xy 439.836814 -221.72422) (xy 439.842175 -221.724739) (xy 439.849759 -221.732321)
			(xy 439.850276 -221.737682) (xy 439.850276 -222.23222) (xy 445.89446 -222.23222) (xy 445.89446 -221.737682)
			(xy 445.894913 -221.732371) (xy 445.902365 -221.7248) (xy 445.907668 -221.72422) (xy 446.423796 -221.72422)
			(xy 446.431607 -221.723918) (xy 446.446479 -221.719125) (xy 446.453006 -221.714822) (xy 446.474095 -221.700473)
			(xy 446.519756 -221.677742) (xy 446.568362 -221.662283) (xy 446.618765 -221.65446) (xy 446.669771 -221.65446)
			(xy 446.720174 -221.662283) (xy 446.76878 -221.677742) (xy 446.814441 -221.700473) (xy 446.83553 -221.714822)
			(xy 446.84206 -221.719116) (xy 446.856931 -221.723899) (xy 446.86474 -221.72422) (xy 447.380868 -221.72422)
			(xy 447.386203 -221.724551) (xy 447.393747 -221.732093) (xy 447.394076 -221.737428) (xy 447.394076 -221.737936)
			(xy 447.394076 -222.23222) (xy 453.43826 -222.23222) (xy 453.43826 -221.737682) (xy 453.438713 -221.732371)
			(xy 453.446165 -221.7248) (xy 453.451468 -221.72422) (xy 453.967596 -221.72422) (xy 453.975407 -221.723918)
			(xy 453.990279 -221.719125) (xy 453.996806 -221.714822) (xy 454.017895 -221.700473) (xy 454.063556 -221.677742)
			(xy 454.112162 -221.662283) (xy 454.162565 -221.65446) (xy 454.213571 -221.65446) (xy 454.263974 -221.662283)
			(xy 454.31258 -221.677742) (xy 454.358241 -221.700473) (xy 454.37933 -221.714822) (xy 454.38586 -221.719116)
			(xy 454.400731 -221.723899) (xy 454.40854 -221.72422) (xy 454.924668 -221.72422) (xy 454.930003 -221.724551)
			(xy 454.937547 -221.732093) (xy 454.937876 -221.737428) (xy 454.937876 -221.737936) (xy 454.937876 -222.23222)
			(xy 454.937583 -222.237563) (xy 454.930012 -222.245104) (xy 454.924668 -222.245428) (xy 454.408794 -222.245428)
			(xy 454.40092 -222.245725) (xy 454.385917 -222.250503) (xy 454.37933 -222.254826) (xy 454.358261 -222.26923)
			(xy 454.312613 -222.292056) (xy 454.264005 -222.307611) (xy 454.213585 -222.315525) (xy 454.188068 -222.31604)
			(xy 454.162549 -222.315526) (xy 454.112123 -222.307638) (xy 454.063512 -222.292085) (xy 454.017872 -222.269237)
			(xy 453.996806 -222.254826) (xy 453.990213 -222.250513) (xy 453.975214 -222.245725) (xy 453.967342 -222.245428)
			(xy 453.451468 -222.245428) (xy 453.446206 -222.244929) (xy 453.438767 -222.237482) (xy 453.43826 -222.23222)
			(xy 447.394076 -222.23222) (xy 447.393783 -222.237563) (xy 447.386212 -222.245104) (xy 447.380868 -222.245428)
			(xy 446.864994 -222.245428) (xy 446.85712 -222.245725) (xy 446.842117 -222.250503) (xy 446.83553 -222.254826)
			(xy 446.814461 -222.26923) (xy 446.768813 -222.292056) (xy 446.720205 -222.307611) (xy 446.669785 -222.315525)
			(xy 446.644268 -222.31604) (xy 446.618749 -222.315526) (xy 446.568323 -222.307638) (xy 446.519712 -222.292085)
			(xy 446.474072 -222.269237) (xy 446.453006 -222.254826) (xy 446.446413 -222.250513) (xy 446.431414 -222.245725)
			(xy 446.423542 -222.245428) (xy 445.907668 -222.245428) (xy 445.902406 -222.244929) (xy 445.894967 -222.237482)
			(xy 445.89446 -222.23222) (xy 439.850276 -222.23222) (xy 439.849983 -222.237563) (xy 439.842412 -222.245104)
			(xy 439.837068 -222.245428) (xy 439.83656 -222.245428) (xy 439.32094 -222.245428) (xy 439.313064 -222.245701)
			(xy 439.29806 -222.250495) (xy 439.291476 -222.254826) (xy 439.270394 -222.26921) (xy 439.224751 -222.292041)
			(xy 439.176146 -222.307601) (xy 439.12573 -222.315522) (xy 439.100214 -222.31604) (xy 439.074694 -222.315553)
			(xy 439.024267 -222.307657) (xy 438.975656 -222.292096) (xy 438.930017 -222.269241) (xy 438.908952 -222.254826)
			(xy 438.902371 -222.250492) (xy 438.887363 -222.245717) (xy 438.879488 -222.245428) (xy 438.363614 -222.245428)
			(xy 438.358304 -222.244964) (xy 438.35073 -222.237521) (xy 438.350152 -222.23222) (xy 432.305968 -222.23222)
			(xy 432.305683 -222.237565) (xy 432.298106 -222.245107) (xy 432.29276 -222.245428) (xy 431.776886 -222.245428)
			(xy 431.769012 -222.245721) (xy 431.754008 -222.250502) (xy 431.747422 -222.254826) (xy 431.726355 -222.269234)
			(xy 431.680707 -222.292059) (xy 431.632097 -222.307612) (xy 431.581678 -222.315526) (xy 431.55616 -222.31604)
			(xy 431.530641 -222.31553) (xy 431.480215 -222.30764) (xy 431.431603 -222.292086) (xy 431.385964 -222.269238)
			(xy 431.364898 -222.254826) (xy 431.358307 -222.25051) (xy 431.343307 -222.245724) (xy 431.335434 -222.245428)
			(xy 430.81956 -222.245428) (xy 430.814297 -222.244934) (xy 430.806858 -222.237484) (xy 430.806352 -222.23222)
			(xy 424.762168 -222.23222) (xy 424.761883 -222.237565) (xy 424.754306 -222.245107) (xy 424.74896 -222.245428)
			(xy 424.748452 -222.245428) (xy 424.232832 -222.245428) (xy 424.224956 -222.245698) (xy 424.209952 -222.250494)
			(xy 424.203368 -222.254826) (xy 424.182288 -222.269214) (xy 424.136644 -222.292044) (xy 424.088039 -222.307603)
			(xy 424.037623 -222.315522) (xy 424.012106 -222.31604) (xy 423.986586 -222.315557) (xy 423.936159 -222.307659)
			(xy 423.887547 -222.292097) (xy 423.841909 -222.269241) (xy 423.820844 -222.254826) (xy 423.814265 -222.250489)
			(xy 423.799255 -222.245716) (xy 423.79138 -222.245428) (xy 423.275506 -222.245428) (xy 423.270195 -222.244969)
			(xy 423.262622 -222.237522) (xy 423.262044 -222.23222) (xy 417.21786 -222.23222) (xy 417.217582 -222.237567)
			(xy 417.21 -222.245109) (xy 417.204652 -222.245428) (xy 415.731452 -222.245428) (xy 415.726188 -222.244939)
			(xy 415.71875 -222.237485) (xy 415.718244 -222.23222) (xy 308.118256 -222.23222) (xy 308.117723 -222.237474)
			(xy 308.110301 -222.244912) (xy 308.105048 -222.245428) (xy 308.10454 -222.245428) (xy 306.631594 -222.245428)
			(xy 306.626282 -222.244977) (xy 306.618709 -222.237524) (xy 306.618132 -222.23222) (xy 300.573948 -222.23222)
			(xy 300.573423 -222.237476) (xy 300.565995 -222.244915) (xy 300.56074 -222.245428) (xy 300.044866 -222.245428)
			(xy 300.036991 -222.245712) (xy 300.021987 -222.250499) (xy 300.015402 -222.254826) (xy 299.994313 -222.269199)
			(xy 299.948672 -222.292032) (xy 299.90007 -222.307595) (xy 299.849656 -222.31552) (xy 299.82414 -222.31604)
			(xy 299.79862 -222.31554) (xy 299.748194 -222.307647) (xy 299.699583 -222.29209) (xy 299.653944 -222.269239)
			(xy 299.632878 -222.254826) (xy 299.626292 -222.250502) (xy 299.611288 -222.245721) (xy 299.603414 -222.245428)
			(xy 299.08754 -222.245428) (xy 299.082218 -222.245048) (xy 299.074676 -222.23754) (xy 299.074332 -222.23222)
			(xy 293.030148 -222.23222) (xy 293.029623 -222.237476) (xy 293.022195 -222.244915) (xy 293.01694 -222.245428)
			(xy 293.016432 -222.245428) (xy 292.500812 -222.245428) (xy 292.492939 -222.245732) (xy 292.477935 -222.250505)
			(xy 292.471348 -222.254826) (xy 292.450274 -222.269222) (xy 292.404628 -222.29205) (xy 292.356021 -222.307607)
			(xy 292.305603 -222.315524) (xy 292.280086 -222.31604) (xy 292.254567 -222.315517) (xy 292.204142 -222.307631)
			(xy 292.15553 -222.292081) (xy 292.10989 -222.269236) (xy 292.088824 -222.254826) (xy 292.082227 -222.25052)
			(xy 292.067231 -222.245727) (xy 292.05936 -222.245428) (xy 291.543486 -222.245428) (xy 291.538173 -222.244982)
			(xy 291.530601 -222.237525) (xy 291.530024 -222.23222) (xy 285.48584 -222.23222) (xy 285.485322 -222.237477)
			(xy 285.477889 -222.244917) (xy 285.472632 -222.245428) (xy 284.956758 -222.245428) (xy 284.948883 -222.245709)
			(xy 284.933879 -222.250497) (xy 284.927294 -222.254826) (xy 284.906207 -222.269203) (xy 284.860566 -222.292035)
			(xy 284.811963 -222.307597) (xy 284.761548 -222.315521) (xy 284.736032 -222.31604) (xy 284.710512 -222.315544)
			(xy 284.660086 -222.30765) (xy 284.611474 -222.292092) (xy 284.565836 -222.26924) (xy 284.54477 -222.254826)
			(xy 284.538185 -222.250499) (xy 284.52318 -222.245719) (xy 284.515306 -222.245428) (xy 283.999432 -222.245428)
			(xy 283.994109 -222.245054) (xy 283.986567 -222.237542) (xy 283.986224 -222.23222) (xy 277.94204 -222.23222)
			(xy 277.941522 -222.237477) (xy 277.934089 -222.244917) (xy 277.928832 -222.245428) (xy 277.412958 -222.245428)
			(xy 277.405083 -222.245709) (xy 277.390079 -222.250497) (xy 277.383494 -222.254826) (xy 277.362407 -222.269203)
			(xy 277.316766 -222.292035) (xy 277.268163 -222.307597) (xy 277.217748 -222.315521) (xy 277.192232 -222.31604)
			(xy 277.166712 -222.315544) (xy 277.116286 -222.30765) (xy 277.067674 -222.292092) (xy 277.022036 -222.26924)
			(xy 277.00097 -222.254826) (xy 276.994385 -222.250499) (xy 276.97938 -222.245719) (xy 276.971506 -222.245428)
			(xy 276.455632 -222.245428) (xy 276.450309 -222.245054) (xy 276.442767 -222.237542) (xy 276.442424 -222.23222)
			(xy 270.39824 -222.23222) (xy 270.397722 -222.237477) (xy 270.390289 -222.244917) (xy 270.385032 -222.245428)
			(xy 270.384524 -222.245428) (xy 269.868904 -222.245428) (xy 269.861031 -222.245729) (xy 269.846027 -222.250504)
			(xy 269.83944 -222.254826) (xy 269.818368 -222.269226) (xy 269.772721 -222.292053) (xy 269.724114 -222.307609)
			(xy 269.673695 -222.315525) (xy 269.648178 -222.31604) (xy 269.622659 -222.315521) (xy 269.572234 -222.307634)
			(xy 269.523622 -222.292083) (xy 269.477982 -222.269237) (xy 269.456916 -222.254826) (xy 269.450321 -222.250517)
			(xy 269.435324 -222.245726) (xy 269.427452 -222.245428) (xy 268.911578 -222.245428) (xy 268.906264 -222.244988)
			(xy 268.898692 -222.237526) (xy 268.898116 -222.23222) (xy 206.997808 -222.23222) (xy 206.997808 -222.232474)
			(xy 206.997265 -222.237764) (xy 206.989877 -222.245334) (xy 206.9846 -222.245936) (xy 206.468726 -222.245936)
			(xy 206.460916 -222.246255) (xy 206.446045 -222.251037) (xy 206.439516 -222.255334) (xy 206.418386 -222.26967)
			(xy 206.372665 -222.292401) (xy 206.323995 -222.307834) (xy 206.27353 -222.315605) (xy 206.248 -222.31604)
			(xy 206.22247 -222.315608) (xy 206.172005 -222.307831) (xy 206.123333 -222.292401) (xy 206.077606 -222.269683)
			(xy 206.056484 -222.255334) (xy 206.049953 -222.251041) (xy 206.035083 -222.246259) (xy 206.027274 -222.245936)
			(xy 205.5114 -222.245936) (xy 205.506144 -222.245408) (xy 205.498703 -222.237983) (xy 205.498192 -222.232728)
			(xy 199.453982 -222.232728) (xy 199.453465 -222.237764) (xy 199.446077 -222.245334) (xy 199.4408 -222.245936)
			(xy 198.924926 -222.245936) (xy 198.917116 -222.246255) (xy 198.902245 -222.251037) (xy 198.895716 -222.255334)
			(xy 198.874586 -222.26967) (xy 198.828865 -222.292401) (xy 198.780195 -222.307834) (xy 198.72973 -222.315605)
			(xy 198.7042 -222.31604) (xy 198.67867 -222.315608) (xy 198.628205 -222.307831) (xy 198.579533 -222.292401)
			(xy 198.533806 -222.269683) (xy 198.512684 -222.255334) (xy 198.506153 -222.251041) (xy 198.491283 -222.246259)
			(xy 198.483474 -222.245936) (xy 197.9676 -222.245936) (xy 197.962344 -222.245408) (xy 197.954903 -222.237983)
			(xy 197.954392 -222.232728) (xy 191.910181 -222.232728) (xy 191.909637 -222.237824) (xy 191.902093 -222.245408)
			(xy 191.896746 -222.245936) (xy 191.380872 -222.245936) (xy 191.37306 -222.246232) (xy 191.358189 -222.251029)
			(xy 191.351662 -222.255334) (xy 191.330547 -222.269694) (xy 191.284821 -222.292419) (xy 191.236146 -222.307846)
			(xy 191.185678 -222.315609) (xy 191.160146 -222.31604) (xy 191.134616 -222.315585) (xy 191.084153 -222.307815)
			(xy 191.035481 -222.292392) (xy 190.989752 -222.26968) (xy 190.96863 -222.255334) (xy 190.962089 -222.251059)
			(xy 190.947226 -222.246265) (xy 190.93942 -222.245936) (xy 190.423546 -222.245936) (xy 190.418111 -222.245587)
			(xy 190.410421 -222.237909) (xy 190.410084 -222.232474) (xy 184.3659 -222.232474) (xy 184.365364 -222.237766)
			(xy 184.357971 -222.245336) (xy 184.352692 -222.245936) (xy 183.836818 -222.245936) (xy 183.829008 -222.246251)
			(xy 183.814136 -222.251035) (xy 183.807608 -222.255334) (xy 183.78648 -222.269674) (xy 183.740759 -222.292403)
			(xy 183.692087 -222.307836) (xy 183.641622 -222.315605) (xy 183.616092 -222.31604) (xy 183.590561 -222.315612)
			(xy 183.540097 -222.307834) (xy 183.491424 -222.292403) (xy 183.445697 -222.269683) (xy 183.424576 -222.255334)
			(xy 183.418047 -222.251038) (xy 183.403175 -222.246258) (xy 183.395366 -222.245936) (xy 182.879492 -222.245936)
			(xy 182.874235 -222.245413) (xy 182.866795 -222.237984) (xy 182.866284 -222.232728) (xy 176.822073 -222.232728)
			(xy 176.821536 -222.237826) (xy 176.813987 -222.245411) (xy 176.808638 -222.245936) (xy 176.292764 -222.245936)
			(xy 176.284956 -222.246271) (xy 176.270084 -222.251042) (xy 176.263554 -222.255334) (xy 176.242441 -222.269697)
			(xy 176.196714 -222.292421) (xy 176.148038 -222.307848) (xy 176.09757 -222.31561) (xy 176.072038 -222.31604)
			(xy 176.046508 -222.315589) (xy 175.996045 -222.307818) (xy 175.947372 -222.292393) (xy 175.901644 -222.26968)
			(xy 175.880522 -222.255334) (xy 175.873983 -222.251056) (xy 175.859119 -222.246264) (xy 175.851312 -222.245936)
			(xy 175.335438 -222.245936) (xy 175.330002 -222.245593) (xy 175.322312 -222.23791) (xy 175.321976 -222.232474)
			(xy 169.277792 -222.232474) (xy 169.277263 -222.237768) (xy 169.269865 -222.245338) (xy 169.264584 -222.245936)
			(xy 167.791384 -222.245936) (xy 167.786126 -222.245419) (xy 167.778686 -222.237986) (xy 167.778176 -222.232728)
			(xy 60.178162 -222.232728) (xy 60.177635 -222.237829) (xy 60.170079 -222.245414) (xy 60.164726 -222.245936)
			(xy 58.691526 -222.245936) (xy 58.686088 -222.245601) (xy 58.678399 -222.237912) (xy 58.678064 -222.232474)
			(xy 52.63388 -222.232474) (xy 52.633362 -222.23777) (xy 52.625956 -222.245342) (xy 52.620672 -222.245936)
			(xy 52.104798 -222.245936) (xy 52.096987 -222.246243) (xy 52.082116 -222.251033) (xy 52.075588 -222.255334)
			(xy 52.054466 -222.269683) (xy 52.008742 -222.29241) (xy 51.960069 -222.30784) (xy 51.909603 -222.315607)
			(xy 51.884072 -222.31604) (xy 51.858541 -222.315622) (xy 51.808076 -222.307841) (xy 51.759404 -222.292407)
			(xy 51.713677 -222.269684) (xy 51.692556 -222.255334) (xy 51.686031 -222.251031) (xy 51.671156 -222.246255)
			(xy 51.663346 -222.245936) (xy 51.147472 -222.245936) (xy 51.142213 -222.245427) (xy 51.134773 -222.237987)
			(xy 51.134264 -222.232728) (xy 45.090062 -222.232728) (xy 45.089705 -222.237901) (xy 45.082044 -222.245587)
			(xy 45.076618 -222.245936) (xy 44.560744 -222.245936) (xy 44.552935 -222.246263) (xy 44.538063 -222.251039)
			(xy 44.531534 -222.255334) (xy 44.510427 -222.269706) (xy 44.464698 -222.292428) (xy 44.41602 -222.307852)
			(xy 44.36555 -222.315611) (xy 44.340018 -222.31604) (xy 44.314488 -222.315599) (xy 44.264024 -222.307825)
			(xy 44.215351 -222.292397) (xy 44.169624 -222.269681) (xy 44.148502 -222.255334) (xy 44.141967 -222.251048)
			(xy 44.1271 -222.246261) (xy 44.119292 -222.245936) (xy 43.603418 -222.245936) (xy 43.597979 -222.245606)
			(xy 43.590291 -222.237913) (xy 43.589956 -222.232474) (xy 37.545772 -222.232474) (xy 37.545261 -222.237772)
			(xy 37.537851 -222.245344) (xy 37.532564 -222.245936) (xy 37.01669 -222.245936) (xy 37.008879 -222.246239)
			(xy 36.994007 -222.251032) (xy 36.98748 -222.255334) (xy 36.96636 -222.269686) (xy 36.920636 -222.292413)
			(xy 36.871962 -222.307842) (xy 36.821495 -222.315608) (xy 36.795964 -222.31604) (xy 36.770433 -222.315626)
			(xy 36.719968 -222.307844) (xy 36.671295 -222.292408) (xy 36.625569 -222.269685) (xy 36.604448 -222.255334)
			(xy 36.597925 -222.251028) (xy 36.583049 -222.246253) (xy 36.575238 -222.245936) (xy 36.059364 -222.245936)
			(xy 36.054104 -222.245432) (xy 36.046665 -222.237989) (xy 36.046156 -222.232728) (xy 30.001948 -222.232728)
			(xy 30.001461 -222.237772) (xy 29.994051 -222.245344) (xy 29.988764 -222.245936) (xy 29.47289 -222.245936)
			(xy 29.465079 -222.246239) (xy 29.450207 -222.251032) (xy 29.44368 -222.255334) (xy 29.42256 -222.269686)
			(xy 29.376836 -222.292413) (xy 29.328162 -222.307842) (xy 29.277695 -222.315608) (xy 29.252164 -222.31604)
			(xy 29.226633 -222.315626) (xy 29.176168 -222.307844) (xy 29.127495 -222.292408) (xy 29.081769 -222.269685)
			(xy 29.060648 -222.255334) (xy 29.054125 -222.251028) (xy 29.039249 -222.246253) (xy 29.031438 -222.245936)
			(xy 28.515564 -222.245936) (xy 28.510304 -222.245432) (xy 28.502865 -222.237989) (xy 28.502356 -222.232728)
			(xy 22.458155 -222.232728) (xy 22.457804 -222.237903) (xy 22.450138 -222.24559) (xy 22.44471 -222.245936)
			(xy 21.928836 -222.245936) (xy 21.921027 -222.246259) (xy 21.906155 -222.251038) (xy 21.899626 -222.255334)
			(xy 21.878493 -222.269666) (xy 21.832774 -222.292397) (xy 21.784104 -222.307832) (xy 21.73364 -222.315604)
			(xy 21.70811 -222.31604) (xy 21.68258 -222.315603) (xy 21.632116 -222.307828) (xy 21.583443 -222.292399)
			(xy 21.537716 -222.269682) (xy 21.516594 -222.255334) (xy 21.510061 -222.251045) (xy 21.495192 -222.24626)
			(xy 21.487384 -222.245936) (xy 20.97151 -222.245936) (xy 20.96607 -222.245612) (xy 20.958382 -222.237914)
			(xy 20.958048 -222.232474) (xy 2.509012 -222.232474) (xy 2.509012 -223.082358) (xy 16.85798 -223.082358)
			(xy 16.85798 -222.58782) (xy 16.858339 -222.582493) (xy 16.865862 -222.574952) (xy 16.871188 -222.574612)
			(xy 16.871696 -222.574612) (xy 17.38757 -222.574612) (xy 17.395381 -222.5743) (xy 17.410253 -222.569515)
			(xy 17.41678 -222.565214) (xy 17.437869 -222.550865) (xy 17.48353 -222.528134) (xy 17.532136 -222.512675)
			(xy 17.582539 -222.504852) (xy 17.633545 -222.504852) (xy 17.683948 -222.512675) (xy 17.732554 -222.528134)
			(xy 17.778215 -222.550865) (xy 17.799304 -222.565214) (xy 17.80584 -222.569497) (xy 17.820706 -222.574287)
			(xy 17.828514 -222.574612) (xy 18.344642 -222.574612) (xy 18.349945 -222.575092) (xy 18.357512 -222.582527)
			(xy 18.358104 -222.58782) (xy 18.358104 -223.082358) (xy 18.358077 -223.082612) (xy 24.402288 -223.082612)
			(xy 24.402288 -223.082104) (xy 24.402288 -222.58782) (xy 24.40264 -222.582491) (xy 24.410168 -222.574949)
			(xy 24.415496 -222.574612) (xy 24.931624 -222.574612) (xy 24.939437 -222.574323) (xy 24.954308 -222.569522)
			(xy 24.960834 -222.565214) (xy 24.981923 -222.550865) (xy 25.027584 -222.528134) (xy 25.07619 -222.512675)
			(xy 25.126593 -222.504852) (xy 25.177599 -222.504852) (xy 25.228002 -222.512675) (xy 25.276608 -222.528134)
			(xy 25.322269 -222.550865) (xy 25.343358 -222.565214) (xy 25.349882 -222.569518) (xy 25.364758 -222.574295)
			(xy 25.372568 -222.574612) (xy 25.888696 -222.574612) (xy 25.894033 -222.574932) (xy 25.901575 -222.582483)
			(xy 25.901904 -222.58782) (xy 25.901904 -223.082358) (xy 25.901878 -223.082612) (xy 31.946088 -223.082612)
			(xy 31.946088 -223.082104) (xy 31.946088 -222.58782) (xy 31.94644 -222.582491) (xy 31.953968 -222.574949)
			(xy 31.959296 -222.574612) (xy 32.475424 -222.574612) (xy 32.483237 -222.574323) (xy 32.498108 -222.569522)
			(xy 32.504634 -222.565214) (xy 32.525723 -222.550865) (xy 32.571384 -222.528134) (xy 32.61999 -222.512675)
			(xy 32.670393 -222.504852) (xy 32.721399 -222.504852) (xy 32.771802 -222.512675) (xy 32.820408 -222.528134)
			(xy 32.866069 -222.550865) (xy 32.887158 -222.565214) (xy 32.893682 -222.569518) (xy 32.908558 -222.574295)
			(xy 32.916368 -222.574612) (xy 33.432496 -222.574612) (xy 33.437833 -222.574932) (xy 33.445375 -222.582483)
			(xy 33.445704 -222.58782) (xy 33.445704 -223.082358) (xy 39.489888 -223.082358) (xy 39.489888 -222.58782)
			(xy 39.49024 -222.582491) (xy 39.497768 -222.574949) (xy 39.503096 -222.574612) (xy 39.503604 -222.574612)
			(xy 40.019478 -222.574612) (xy 40.027289 -222.574304) (xy 40.042161 -222.569516) (xy 40.048688 -222.565214)
			(xy 40.069777 -222.550865) (xy 40.115438 -222.528134) (xy 40.164044 -222.512675) (xy 40.214447 -222.504852)
			(xy 40.265453 -222.504852) (xy 40.315856 -222.512675) (xy 40.364462 -222.528134) (xy 40.410123 -222.550865)
			(xy 40.431212 -222.565214) (xy 40.437747 -222.5695) (xy 40.452614 -222.574288) (xy 40.460422 -222.574612)
			(xy 40.97655 -222.574612) (xy 40.981842 -222.575153) (xy 40.989414 -222.582542) (xy 40.990012 -222.58782)
			(xy 40.990012 -223.082358) (xy 40.989984 -223.082612) (xy 47.034196 -223.082612) (xy 47.034196 -223.082104)
			(xy 47.034196 -222.58782) (xy 47.03454 -222.582489) (xy 47.042074 -222.574947) (xy 47.047404 -222.574612)
			(xy 47.563532 -222.574612) (xy 47.571341 -222.574284) (xy 47.586213 -222.56951) (xy 47.592742 -222.565214)
			(xy 47.613831 -222.550865) (xy 47.659492 -222.528134) (xy 47.708098 -222.512675) (xy 47.758501 -222.504852)
			(xy 47.809507 -222.504852) (xy 47.85991 -222.512675) (xy 47.908516 -222.528134) (xy 47.954177 -222.550865)
			(xy 47.975266 -222.565214) (xy 47.981811 -222.569483) (xy 47.99667 -222.574281) (xy 48.004476 -222.574612)
			(xy 48.520604 -222.574612) (xy 48.525942 -222.574926) (xy 48.533483 -222.582482) (xy 48.533812 -222.58782)
			(xy 48.533812 -223.082358) (xy 54.577996 -223.082358) (xy 54.577996 -222.58782) (xy 54.57834 -222.582489)
			(xy 54.585874 -222.574947) (xy 54.591204 -222.574612) (xy 56.064658 -222.574612) (xy 56.069951 -222.575148)
			(xy 56.077522 -222.58254) (xy 56.07812 -222.58782) (xy 56.07812 -223.082358) (xy 56.078104 -223.082612)
			(xy 163.678108 -223.082612) (xy 163.678108 -223.082104) (xy 163.678108 -222.58782) (xy 163.678442 -222.582486)
			(xy 163.685983 -222.574943) (xy 163.691316 -222.574612) (xy 165.164516 -222.574612) (xy 165.169855 -222.574918)
			(xy 165.177397 -222.58248) (xy 165.177724 -222.58782) (xy 165.177724 -223.082358) (xy 171.221908 -223.082358)
			(xy 171.221908 -222.58782) (xy 171.222242 -222.582486) (xy 171.229783 -222.574943) (xy 171.235116 -222.574612)
			(xy 171.235624 -222.574612) (xy 171.751498 -222.574612) (xy 171.75931 -222.574312) (xy 171.774182 -222.569518)
			(xy 171.780708 -222.565214) (xy 171.801797 -222.550865) (xy 171.847458 -222.528134) (xy 171.896064 -222.512675)
			(xy 171.946467 -222.504852) (xy 171.997473 -222.504852) (xy 172.047876 -222.512675) (xy 172.096482 -222.528134)
			(xy 172.142143 -222.550865) (xy 172.163232 -222.565214) (xy 172.169762 -222.569508) (xy 172.184633 -222.574291)
			(xy 172.192442 -222.574612) (xy 172.70857 -222.574612) (xy 172.713864 -222.57514) (xy 172.721435 -222.582538)
			(xy 172.722032 -222.58782) (xy 172.722032 -223.082358) (xy 172.722016 -223.082612) (xy 178.766216 -223.082612)
			(xy 178.766216 -223.082104) (xy 178.766216 -222.58782) (xy 178.766542 -222.582484) (xy 178.774088 -222.574941)
			(xy 178.779424 -222.574612) (xy 179.295552 -222.574612) (xy 179.303362 -222.574293) (xy 179.318234 -222.569512)
			(xy 179.324762 -222.565214) (xy 179.345851 -222.550865) (xy 179.391512 -222.528134) (xy 179.440118 -222.512675)
			(xy 179.490521 -222.504852) (xy 179.541527 -222.504852) (xy 179.59193 -222.512675) (xy 179.640536 -222.528134)
			(xy 179.686197 -222.550865) (xy 179.707286 -222.565214) (xy 179.713826 -222.56949) (xy 179.728689 -222.574284)
			(xy 179.736496 -222.574612) (xy 180.252624 -222.574612) (xy 180.257894 -222.575081) (xy 180.265337 -222.582548)
			(xy 180.265832 -222.58782) (xy 180.265832 -223.082358) (xy 186.310016 -223.082358) (xy 186.310016 -222.58782)
			(xy 186.310342 -222.582484) (xy 186.317888 -222.574941) (xy 186.323224 -222.574612) (xy 186.323732 -222.574612)
			(xy 186.839606 -222.574612) (xy 186.847418 -222.574316) (xy 186.86229 -222.569519) (xy 186.868816 -222.565214)
			(xy 186.889905 -222.550865) (xy 186.935566 -222.528134) (xy 186.984172 -222.512675) (xy 187.034575 -222.504852)
			(xy 187.085581 -222.504852) (xy 187.135984 -222.512675) (xy 187.18459 -222.528134) (xy 187.230251 -222.550865)
			(xy 187.25134 -222.565214) (xy 187.257868 -222.569511) (xy 187.272741 -222.574292) (xy 187.28055 -222.574612)
			(xy 187.796678 -222.574612) (xy 187.801973 -222.575134) (xy 187.809544 -222.582537) (xy 187.81014 -222.58782)
			(xy 187.81014 -223.082358) (xy 187.810124 -223.082612) (xy 193.854324 -223.082612) (xy 193.854324 -223.082104)
			(xy 193.854324 -222.58782) (xy 193.854643 -222.582483) (xy 193.862194 -222.574938) (xy 193.867532 -222.574612)
			(xy 194.38366 -222.574612) (xy 194.39147 -222.574296) (xy 194.406342 -222.569513) (xy 194.41287 -222.565214)
			(xy 194.433959 -222.550865) (xy 194.47962 -222.528134) (xy 194.528226 -222.512675) (xy 194.578629 -222.504852)
			(xy 194.629635 -222.504852) (xy 194.680038 -222.512675) (xy 194.728644 -222.528134) (xy 194.774305 -222.550865)
			(xy 194.795394 -222.565214) (xy 194.801933 -222.569494) (xy 194.816797 -222.574285) (xy 194.824604 -222.574612)
			(xy 195.340732 -222.574612) (xy 195.346003 -222.575075) (xy 195.353445 -222.582547) (xy 195.35394 -222.58782)
			(xy 195.35394 -223.082358) (xy 195.353916 -223.082612) (xy 201.398124 -223.082612) (xy 201.398124 -223.082104)
			(xy 201.398124 -222.58782) (xy 201.398443 -222.582483) (xy 201.405994 -222.574938) (xy 201.411332 -222.574612)
			(xy 201.92746 -222.574612) (xy 201.93527 -222.574296) (xy 201.950142 -222.569513) (xy 201.95667 -222.565214)
			(xy 201.977759 -222.550865) (xy 202.02342 -222.528134) (xy 202.072026 -222.512675) (xy 202.122429 -222.504852)
			(xy 202.173435 -222.504852) (xy 202.223838 -222.512675) (xy 202.272444 -222.528134) (xy 202.318105 -222.550865)
			(xy 202.339194 -222.565214) (xy 202.345733 -222.569494) (xy 202.360597 -222.574285) (xy 202.368404 -222.574612)
			(xy 202.884532 -222.574612) (xy 202.889803 -222.575075) (xy 202.897245 -222.582547) (xy 202.89774 -222.58782)
			(xy 202.89774 -223.082104) (xy 264.798048 -223.082104) (xy 264.798048 -222.587566) (xy 264.798529 -222.582196)
			(xy 264.806138 -222.574611) (xy 264.81151 -222.574104) (xy 265.327638 -222.574104) (xy 265.335446 -222.573763)
			(xy 265.350317 -222.568996) (xy 265.356848 -222.564706) (xy 265.377937 -222.550357) (xy 265.423598 -222.527626)
			(xy 265.472204 -222.512167) (xy 265.522607 -222.504344) (xy 265.573613 -222.504344) (xy 265.624016 -222.512167)
			(xy 265.672622 -222.527626) (xy 265.718283 -222.550357) (xy 265.739372 -222.564706) (xy 265.74591 -222.568986)
			(xy 265.760775 -222.573776) (xy 265.768582 -222.574104) (xy 266.28471 -222.574104) (xy 266.290067 -222.57464)
			(xy 266.29765 -222.58221) (xy 266.298172 -222.587566) (xy 266.298172 -223.082104) (xy 272.342356 -223.082104)
			(xy 272.342356 -222.587566) (xy 272.342802 -222.582254) (xy 272.35026 -222.574684) (xy 272.355564 -222.574104)
			(xy 272.871692 -222.574104) (xy 272.879502 -222.573786) (xy 272.894373 -222.569003) (xy 272.900902 -222.564706)
			(xy 272.921991 -222.550357) (xy 272.967652 -222.527626) (xy 273.016258 -222.512167) (xy 273.066661 -222.504344)
			(xy 273.117667 -222.504344) (xy 273.16807 -222.512167) (xy 273.216676 -222.527626) (xy 273.262337 -222.550357)
			(xy 273.283426 -222.564706) (xy 273.289952 -222.569007) (xy 273.304826 -222.573784) (xy 273.312636 -222.574104)
			(xy 273.828764 -222.574104) (xy 273.834094 -222.574452) (xy 273.841638 -222.581982) (xy 273.841972 -222.587312)
			(xy 273.841972 -222.58782) (xy 273.841972 -223.082104) (xy 279.886156 -223.082104) (xy 279.886156 -222.587566)
			(xy 279.886602 -222.582254) (xy 279.89406 -222.574684) (xy 279.899364 -222.574104) (xy 280.415492 -222.574104)
			(xy 280.423302 -222.573786) (xy 280.438173 -222.569003) (xy 280.444702 -222.564706) (xy 280.465791 -222.550357)
			(xy 280.511452 -222.527626) (xy 280.560058 -222.512167) (xy 280.610461 -222.504344) (xy 280.661467 -222.504344)
			(xy 280.71187 -222.512167) (xy 280.760476 -222.527626) (xy 280.806137 -222.550357) (xy 280.827226 -222.564706)
			(xy 280.833752 -222.569007) (xy 280.848626 -222.573784) (xy 280.856436 -222.574104) (xy 281.372564 -222.574104)
			(xy 281.377894 -222.574452) (xy 281.385438 -222.581982) (xy 281.385772 -222.587312) (xy 281.385772 -222.58782)
			(xy 281.385772 -223.082104) (xy 287.429956 -223.082104) (xy 287.429956 -222.587566) (xy 287.43043 -222.582194)
			(xy 287.438044 -222.574609) (xy 287.443418 -222.574104) (xy 287.959546 -222.574104) (xy 287.967354 -222.573767)
			(xy 287.982225 -222.568997) (xy 287.988756 -222.564706) (xy 288.009845 -222.550357) (xy 288.055506 -222.527626)
			(xy 288.104112 -222.512167) (xy 288.154515 -222.504344) (xy 288.205521 -222.504344) (xy 288.255924 -222.512167)
			(xy 288.30453 -222.527626) (xy 288.350191 -222.550357) (xy 288.37128 -222.564706) (xy 288.377816 -222.568989)
			(xy 288.392683 -222.573777) (xy 288.40049 -222.574104) (xy 288.916618 -222.574104) (xy 288.921976 -222.574635)
			(xy 288.929559 -222.582209) (xy 288.93008 -222.587566) (xy 288.93008 -223.082104) (xy 294.974264 -223.082104)
			(xy 294.974264 -222.587566) (xy 294.974703 -222.582252) (xy 294.982166 -222.574682) (xy 294.987472 -222.574104)
			(xy 295.5036 -222.574104) (xy 295.51141 -222.57379) (xy 295.526281 -222.569004) (xy 295.53281 -222.564706)
			(xy 295.553899 -222.550357) (xy 295.59956 -222.527626) (xy 295.648166 -222.512167) (xy 295.698569 -222.504344)
			(xy 295.749575 -222.504344) (xy 295.799978 -222.512167) (xy 295.848584 -222.527626) (xy 295.894245 -222.550357)
			(xy 295.915334 -222.564706) (xy 295.921858 -222.56901) (xy 295.936734 -222.573785) (xy 295.944544 -222.574104)
			(xy 296.460672 -222.574104) (xy 296.466003 -222.574447) (xy 296.473547 -222.581981) (xy 296.47388 -222.587312)
			(xy 296.47388 -222.58782) (xy 296.47388 -223.082104) (xy 302.518064 -223.082104) (xy 302.518064 -222.587566)
			(xy 302.51853 -222.582192) (xy 302.52615 -222.574606) (xy 302.531526 -222.574104) (xy 304.004726 -222.574104)
			(xy 304.010085 -222.57463) (xy 304.017667 -222.582207) (xy 304.018188 -222.587566) (xy 304.018188 -223.082104)
			(xy 411.618176 -223.082104) (xy 411.618176 -222.587566) (xy 411.618605 -222.582249) (xy 411.626075 -222.574678)
			(xy 411.631384 -222.574104) (xy 413.104584 -222.574104) (xy 413.109917 -222.574439) (xy 413.11746 -222.581979)
			(xy 413.117792 -222.587312) (xy 413.117792 -222.58782) (xy 413.117792 -223.082104) (xy 419.161976 -223.082104)
			(xy 419.161976 -222.587566) (xy 419.16226 -222.582117) (xy 419.169988 -222.574431) (xy 419.175438 -222.574104)
			(xy 419.691566 -222.574104) (xy 419.699375 -222.573775) (xy 419.714246 -222.569) (xy 419.720776 -222.564706)
			(xy 419.741865 -222.550357) (xy 419.787526 -222.527626) (xy 419.836132 -222.512167) (xy 419.886535 -222.504344)
			(xy 419.937541 -222.504344) (xy 419.987944 -222.512167) (xy 420.03655 -222.527626) (xy 420.082211 -222.550357)
			(xy 420.1033 -222.564706) (xy 420.109832 -222.568997) (xy 420.124702 -222.57378) (xy 420.13251 -222.574104)
			(xy 420.648638 -222.574104) (xy 420.653998 -222.574622) (xy 420.66158 -222.582206) (xy 420.6621 -222.587566)
			(xy 420.6621 -223.082104) (xy 426.706284 -223.082104) (xy 426.706284 -222.587566) (xy 426.706706 -222.582247)
			(xy 426.71418 -222.574676) (xy 426.719492 -222.574104) (xy 427.23562 -222.574104) (xy 427.243431 -222.573798)
			(xy 427.258302 -222.569007) (xy 427.26483 -222.564706) (xy 427.285919 -222.550357) (xy 427.33158 -222.527626)
			(xy 427.380186 -222.512167) (xy 427.430589 -222.504344) (xy 427.481595 -222.504344) (xy 427.531998 -222.512167)
			(xy 427.580604 -222.527626) (xy 427.626265 -222.550357) (xy 427.647354 -222.564706) (xy 427.653874 -222.569017)
			(xy 427.668753 -222.573788) (xy 427.676564 -222.574104) (xy 428.192692 -222.574104) (xy 428.198026 -222.574433)
			(xy 428.205568 -222.581978) (xy 428.2059 -222.587312) (xy 428.2059 -222.58782) (xy 428.2059 -223.082104)
			(xy 434.250084 -223.082104) (xy 434.250084 -222.587566) (xy 434.250361 -222.582115) (xy 434.258094 -222.574429)
			(xy 434.263546 -222.574104) (xy 434.779674 -222.574104) (xy 434.787483 -222.573779) (xy 434.802354 -222.569001)
			(xy 434.808884 -222.564706) (xy 434.829973 -222.550357) (xy 434.875634 -222.527626) (xy 434.92424 -222.512167)
			(xy 434.974643 -222.504344) (xy 435.025649 -222.504344) (xy 435.076052 -222.512167) (xy 435.124658 -222.527626)
			(xy 435.170319 -222.550357) (xy 435.191408 -222.564706) (xy 435.197938 -222.569) (xy 435.212809 -222.573781)
			(xy 435.220618 -222.574104) (xy 435.736746 -222.574104) (xy 435.742107 -222.574616) (xy 435.749688 -222.582204)
			(xy 435.750208 -222.587566) (xy 435.750208 -223.082104) (xy 441.794392 -223.082104) (xy 441.794392 -222.587566)
			(xy 441.794895 -222.582269) (xy 441.802314 -222.574703) (xy 441.8076 -222.574104) (xy 442.323728 -222.574104)
			(xy 442.331539 -222.573801) (xy 442.34641 -222.569008) (xy 442.352938 -222.564706) (xy 442.374027 -222.550357)
			(xy 442.419688 -222.527626) (xy 442.468294 -222.512167) (xy 442.518697 -222.504344) (xy 442.569703 -222.504344)
			(xy 442.620106 -222.512167) (xy 442.668712 -222.527626) (xy 442.714373 -222.550357) (xy 442.735462 -222.564706)
			(xy 442.742002 -222.568982) (xy 442.756866 -222.573774) (xy 442.764672 -222.574104) (xy 443.2808 -222.574104)
			(xy 443.286135 -222.574428) (xy 443.293677 -222.581976) (xy 443.294008 -222.587312) (xy 443.294008 -222.58782)
			(xy 443.294008 -223.082104) (xy 449.338192 -223.082104) (xy 449.338192 -222.587566) (xy 449.338695 -222.582269)
			(xy 449.346114 -222.574703) (xy 449.3514 -222.574104) (xy 449.867528 -222.574104) (xy 449.875339 -222.573801)
			(xy 449.89021 -222.569008) (xy 449.896738 -222.564706) (xy 449.917827 -222.550357) (xy 449.963488 -222.527626)
			(xy 450.012094 -222.512167) (xy 450.062497 -222.504344) (xy 450.113503 -222.504344) (xy 450.163906 -222.512167)
			(xy 450.212512 -222.527626) (xy 450.258173 -222.550357) (xy 450.279262 -222.564706) (xy 450.285802 -222.568982)
			(xy 450.300666 -222.573774) (xy 450.308472 -222.574104) (xy 450.8246 -222.574104) (xy 450.829935 -222.574428)
			(xy 450.837477 -222.581976) (xy 450.837808 -222.587312) (xy 450.837808 -222.58782) (xy 450.837808 -223.082104)
			(xy 450.837308 -223.087367) (xy 450.829863 -223.09481) (xy 450.8246 -223.095312) (xy 450.308726 -223.095312)
			(xy 450.30085 -223.095582) (xy 450.285846 -223.100378) (xy 450.279262 -223.10471) (xy 450.258182 -223.119098)
			(xy 450.212539 -223.141929) (xy 450.163933 -223.157488) (xy 450.113517 -223.165407) (xy 450.088 -223.165924)
			(xy 450.062479 -223.165447) (xy 450.012052 -223.157548) (xy 449.963441 -223.141984) (xy 449.917803 -223.119126)
			(xy 449.896738 -223.10471) (xy 449.890139 -223.100408) (xy 449.875145 -223.095613) (xy 449.867274 -223.095312)
			(xy 449.3514 -223.095312) (xy 449.346138 -223.094806) (xy 449.338696 -223.087366) (xy 449.338192 -223.082104)
			(xy 443.294008 -223.082104) (xy 443.293508 -223.087367) (xy 443.286063 -223.09481) (xy 443.2808 -223.095312)
			(xy 442.764926 -223.095312) (xy 442.75705 -223.095582) (xy 442.742046 -223.100378) (xy 442.735462 -223.10471)
			(xy 442.714382 -223.119098) (xy 442.668739 -223.141929) (xy 442.620133 -223.157488) (xy 442.569717 -223.165407)
			(xy 442.5442 -223.165924) (xy 442.518679 -223.165447) (xy 442.468252 -223.157548) (xy 442.419641 -223.141984)
			(xy 442.374003 -223.119126) (xy 442.352938 -223.10471) (xy 442.346339 -223.100408) (xy 442.331345 -223.095613)
			(xy 442.323474 -223.095312) (xy 441.8076 -223.095312) (xy 441.802338 -223.094806) (xy 441.794896 -223.087366)
			(xy 441.794392 -223.082104) (xy 435.750208 -223.082104) (xy 435.749708 -223.087367) (xy 435.742263 -223.09481)
			(xy 435.737 -223.095312) (xy 435.736492 -223.095312) (xy 435.220872 -223.095312) (xy 435.212998 -223.095601)
			(xy 435.197994 -223.100385) (xy 435.191408 -223.10471) (xy 435.170344 -223.119122) (xy 435.124694 -223.141947)
			(xy 435.076084 -223.157499) (xy 435.025664 -223.165411) (xy 435.000146 -223.165924) (xy 434.974626 -223.165424)
			(xy 434.9242 -223.157532) (xy 434.875588 -223.141975) (xy 434.82995 -223.119123) (xy 434.808884 -223.10471)
			(xy 434.802297 -223.100387) (xy 434.787294 -223.095605) (xy 434.77942 -223.095312) (xy 434.263546 -223.095312)
			(xy 434.258236 -223.09484) (xy 434.25066 -223.087404) (xy 434.250084 -223.082104) (xy 428.2059 -223.082104)
			(xy 428.205575 -223.087439) (xy 428.198027 -223.09498) (xy 428.192692 -223.095312) (xy 427.676818 -223.095312)
			(xy 427.668945 -223.095622) (xy 427.653942 -223.100391) (xy 427.647354 -223.10471) (xy 427.626277 -223.119102)
			(xy 427.580632 -223.141931) (xy 427.532026 -223.157489) (xy 427.481609 -223.165408) (xy 427.456092 -223.165924)
			(xy 427.430573 -223.165401) (xy 427.380148 -223.157516) (xy 427.331536 -223.141965) (xy 427.285896 -223.11912)
			(xy 427.26483 -223.10471) (xy 427.258233 -223.100405) (xy 427.243237 -223.095612) (xy 427.235366 -223.095312)
			(xy 426.719492 -223.095312) (xy 426.714229 -223.094811) (xy 426.706787 -223.087367) (xy 426.706284 -223.082104)
			(xy 420.6621 -223.082104) (xy 420.661775 -223.087439) (xy 420.654227 -223.09498) (xy 420.648892 -223.095312)
			(xy 420.648384 -223.095312) (xy 420.132764 -223.095312) (xy 420.124889 -223.095598) (xy 420.109886 -223.100383)
			(xy 420.1033 -223.10471) (xy 420.08221 -223.119082) (xy 420.03657 -223.141916) (xy 419.987968 -223.157479)
			(xy 419.937554 -223.165404) (xy 419.912038 -223.165924) (xy 419.886518 -223.165428) (xy 419.836092 -223.157535)
			(xy 419.78748 -223.141976) (xy 419.741841 -223.119124) (xy 419.720776 -223.10471) (xy 419.714191 -223.100384)
			(xy 419.699186 -223.095604) (xy 419.691312 -223.095312) (xy 419.175438 -223.095312) (xy 419.170127 -223.094846)
			(xy 419.162551 -223.087405) (xy 419.161976 -223.082104) (xy 413.117792 -223.082104) (xy 413.117474 -223.087441)
			(xy 413.109921 -223.094982) (xy 413.104584 -223.095312) (xy 411.631384 -223.095312) (xy 411.62612 -223.094817)
			(xy 411.618679 -223.087368) (xy 411.618176 -223.082104) (xy 304.018188 -223.082104) (xy 304.017874 -223.087442)
			(xy 304.010318 -223.094983) (xy 304.00498 -223.095312) (xy 302.531526 -223.095312) (xy 302.526214 -223.094854)
			(xy 302.518638 -223.087407) (xy 302.518064 -223.082104) (xy 296.47388 -223.082104) (xy 296.473573 -223.087444)
			(xy 296.466012 -223.094986) (xy 296.460672 -223.095312) (xy 295.944798 -223.095312) (xy 295.936925 -223.095613)
			(xy 295.921921 -223.100388) (xy 295.915334 -223.10471) (xy 295.894262 -223.119111) (xy 295.848616 -223.141938)
			(xy 295.800008 -223.157493) (xy 295.749589 -223.165409) (xy 295.724072 -223.165924) (xy 295.698553 -223.165411)
			(xy 295.648127 -223.157523) (xy 295.599515 -223.14197) (xy 295.553876 -223.119122) (xy 295.53281 -223.10471)
			(xy 295.526217 -223.100397) (xy 295.511218 -223.095609) (xy 295.503346 -223.095312) (xy 294.987472 -223.095312)
			(xy 294.982207 -223.094824) (xy 294.974766 -223.08737) (xy 294.974264 -223.082104) (xy 288.93008 -223.082104)
			(xy 288.929773 -223.087444) (xy 288.922212 -223.094986) (xy 288.916872 -223.095312) (xy 288.916364 -223.095312)
			(xy 288.400744 -223.095312) (xy 288.392869 -223.09559) (xy 288.377865 -223.100381) (xy 288.37128 -223.10471)
			(xy 288.350195 -223.119091) (xy 288.304554 -223.141923) (xy 288.25595 -223.157484) (xy 288.205534 -223.165406)
			(xy 288.180018 -223.165924) (xy 288.154498 -223.165438) (xy 288.104071 -223.157542) (xy 288.055459 -223.14198)
			(xy 288.009821 -223.119125) (xy 287.988756 -223.10471) (xy 287.982176 -223.100376) (xy 287.967167 -223.095601)
			(xy 287.959292 -223.095312) (xy 287.443418 -223.095312) (xy 287.438105 -223.094859) (xy 287.43053 -223.087409)
			(xy 287.429956 -223.082104) (xy 281.385772 -223.082104) (xy 281.385472 -223.087446) (xy 281.377907 -223.094988)
			(xy 281.372564 -223.095312) (xy 280.85669 -223.095312) (xy 280.848816 -223.095609) (xy 280.833813 -223.100387)
			(xy 280.827226 -223.10471) (xy 280.806157 -223.119114) (xy 280.760509 -223.141941) (xy 280.711901 -223.157495)
			(xy 280.661481 -223.16541) (xy 280.635964 -223.165924) (xy 280.610445 -223.165415) (xy 280.560019 -223.157526)
			(xy 280.511407 -223.141971) (xy 280.465768 -223.119122) (xy 280.444702 -223.10471) (xy 280.438111 -223.100394)
			(xy 280.423111 -223.095608) (xy 280.415238 -223.095312) (xy 279.899364 -223.095312) (xy 279.894098 -223.094829)
			(xy 279.886658 -223.087371) (xy 279.886156 -223.082104) (xy 273.841972 -223.082104) (xy 273.841672 -223.087446)
			(xy 273.834107 -223.094988) (xy 273.828764 -223.095312) (xy 273.31289 -223.095312) (xy 273.305016 -223.095609)
			(xy 273.290013 -223.100387) (xy 273.283426 -223.10471) (xy 273.262357 -223.119114) (xy 273.216709 -223.141941)
			(xy 273.168101 -223.157495) (xy 273.117681 -223.16541) (xy 273.092164 -223.165924) (xy 273.066645 -223.165415)
			(xy 273.016219 -223.157526) (xy 272.967607 -223.141971) (xy 272.921968 -223.119122) (xy 272.900902 -223.10471)
			(xy 272.894311 -223.100394) (xy 272.879311 -223.095608) (xy 272.871438 -223.095312) (xy 272.355564 -223.095312)
			(xy 272.350298 -223.094829) (xy 272.342858 -223.087371) (xy 272.342356 -223.082104) (xy 266.298172 -223.082104)
			(xy 266.297872 -223.087446) (xy 266.290307 -223.094988) (xy 266.284964 -223.095312) (xy 266.284456 -223.095312)
			(xy 265.768836 -223.095312) (xy 265.76096 -223.095586) (xy 265.745957 -223.10038) (xy 265.739372 -223.10471)
			(xy 265.71829 -223.119094) (xy 265.672647 -223.141925) (xy 265.624042 -223.157485) (xy 265.573626 -223.165406)
			(xy 265.54811 -223.165924) (xy 265.52259 -223.165442) (xy 265.472163 -223.157544) (xy 265.423551 -223.141982)
			(xy 265.377913 -223.119126) (xy 265.356848 -223.10471) (xy 265.350269 -223.100373) (xy 265.335259 -223.0956)
			(xy 265.327384 -223.095312) (xy 264.81151 -223.095312) (xy 264.806196 -223.094864) (xy 264.798622 -223.08741)
			(xy 264.798048 -223.082104) (xy 202.89774 -223.082104) (xy 202.89774 -223.082358) (xy 202.897247 -223.087662)
			(xy 202.889825 -223.095236) (xy 202.884532 -223.09582) (xy 202.368658 -223.09582) (xy 202.36085 -223.096155)
			(xy 202.345978 -223.100926) (xy 202.339448 -223.105218) (xy 202.318336 -223.119582) (xy 202.272609 -223.142306)
			(xy 202.223933 -223.157732) (xy 202.173464 -223.165494) (xy 202.147932 -223.165924) (xy 202.122402 -223.165479)
			(xy 202.071938 -223.157707) (xy 202.023266 -223.14228) (xy 201.977538 -223.119565) (xy 201.956416 -223.105218)
			(xy 201.949879 -223.100936) (xy 201.935013 -223.096147) (xy 201.927206 -223.09582) (xy 201.411332 -223.09582)
			(xy 201.406007 -223.095453) (xy 201.398465 -223.087936) (xy 201.398124 -223.082612) (xy 195.353916 -223.082612)
			(xy 195.353447 -223.087662) (xy 195.346025 -223.095236) (xy 195.340732 -223.09582) (xy 194.824858 -223.09582)
			(xy 194.81705 -223.096155) (xy 194.802178 -223.100926) (xy 194.795648 -223.105218) (xy 194.774536 -223.119582)
			(xy 194.728809 -223.142306) (xy 194.680133 -223.157732) (xy 194.629664 -223.165494) (xy 194.604132 -223.165924)
			(xy 194.578602 -223.165479) (xy 194.528138 -223.157707) (xy 194.479466 -223.14228) (xy 194.433738 -223.119565)
			(xy 194.412616 -223.105218) (xy 194.406079 -223.100936) (xy 194.391213 -223.096147) (xy 194.383406 -223.09582)
			(xy 193.867532 -223.09582) (xy 193.862207 -223.095453) (xy 193.854665 -223.087936) (xy 193.854324 -223.082612)
			(xy 187.810124 -223.082612) (xy 187.80979 -223.087793) (xy 187.802112 -223.095482) (xy 187.796678 -223.09582)
			(xy 187.280804 -223.09582) (xy 187.272994 -223.096132) (xy 187.258122 -223.100919) (xy 187.251594 -223.105218)
			(xy 187.230469 -223.119562) (xy 187.184747 -223.142291) (xy 187.136074 -223.157723) (xy 187.085609 -223.16549)
			(xy 187.060078 -223.165924) (xy 187.034547 -223.165506) (xy 186.984082 -223.157726) (xy 186.935409 -223.142291)
			(xy 186.889683 -223.119569) (xy 186.868562 -223.105218) (xy 186.862037 -223.100915) (xy 186.847162 -223.096139)
			(xy 186.839352 -223.09582) (xy 186.323478 -223.09582) (xy 186.31803 -223.095531) (xy 186.310343 -223.087808)
			(xy 186.310016 -223.082358) (xy 180.265832 -223.082358) (xy 180.265346 -223.087664) (xy 180.257919 -223.095239)
			(xy 180.252624 -223.09582) (xy 179.73675 -223.09582) (xy 179.728942 -223.096152) (xy 179.71407 -223.100925)
			(xy 179.70754 -223.105218) (xy 179.68643 -223.119585) (xy 179.640702 -223.142309) (xy 179.592025 -223.157734)
			(xy 179.541556 -223.165495) (xy 179.516024 -223.165924) (xy 179.490494 -223.165483) (xy 179.44003 -223.157709)
			(xy 179.391357 -223.142282) (xy 179.34563 -223.119566) (xy 179.324508 -223.105218) (xy 179.317973 -223.100933)
			(xy 179.303106 -223.096146) (xy 179.295298 -223.09582) (xy 178.779424 -223.09582) (xy 178.774098 -223.095458)
			(xy 178.766556 -223.087937) (xy 178.766216 -223.082612) (xy 172.722016 -223.082612) (xy 172.72169 -223.087794)
			(xy 172.714006 -223.095485) (xy 172.70857 -223.09582) (xy 172.192696 -223.09582) (xy 172.184885 -223.096129)
			(xy 172.170014 -223.100918) (xy 172.163486 -223.105218) (xy 172.142363 -223.119566) (xy 172.09664 -223.142294)
			(xy 172.047967 -223.157724) (xy 171.997501 -223.165491) (xy 171.97197 -223.165924) (xy 171.946439 -223.16551)
			(xy 171.895974 -223.157728) (xy 171.847301 -223.142293) (xy 171.801575 -223.119569) (xy 171.780454 -223.105218)
			(xy 171.773931 -223.100912) (xy 171.759054 -223.096138) (xy 171.751244 -223.09582) (xy 171.23537 -223.09582)
			(xy 171.229921 -223.095537) (xy 171.222234 -223.087809) (xy 171.221908 -223.082358) (xy 165.177724 -223.082358)
			(xy 165.177245 -223.087666) (xy 165.169813 -223.095241) (xy 165.164516 -223.09582) (xy 163.691316 -223.09582)
			(xy 163.685989 -223.095464) (xy 163.678448 -223.087938) (xy 163.678108 -223.082612) (xy 56.078104 -223.082612)
			(xy 56.077788 -223.087797) (xy 56.070097 -223.095488) (xy 56.064658 -223.09582) (xy 54.591458 -223.09582)
			(xy 54.586079 -223.095373) (xy 54.578493 -223.08774) (xy 54.577996 -223.082358) (xy 48.533812 -223.082358)
			(xy 48.533343 -223.087668) (xy 48.525905 -223.095245) (xy 48.520604 -223.09582) (xy 48.00473 -223.09582)
			(xy 47.996921 -223.096143) (xy 47.982049 -223.100922) (xy 47.97552 -223.105218) (xy 47.954388 -223.119551)
			(xy 47.908668 -223.142282) (xy 47.859998 -223.157717) (xy 47.809534 -223.165489) (xy 47.784004 -223.165924)
			(xy 47.758473 -223.165493) (xy 47.708009 -223.157716) (xy 47.659336 -223.142286) (xy 47.613609 -223.119567)
			(xy 47.592488 -223.105218) (xy 47.585957 -223.100925) (xy 47.571087 -223.096143) (xy 47.563278 -223.09582)
			(xy 47.047404 -223.09582) (xy 47.042145 -223.095304) (xy 47.034702 -223.087871) (xy 47.034196 -223.082612)
			(xy 40.989984 -223.082612) (xy 40.989427 -223.087705) (xy 40.981893 -223.09529) (xy 40.97655 -223.09582)
			(xy 40.460676 -223.09582) (xy 40.452865 -223.09612) (xy 40.437993 -223.100915) (xy 40.431466 -223.105218)
			(xy 40.410349 -223.119574) (xy 40.364624 -223.1423) (xy 40.315949 -223.157729) (xy 40.265481 -223.165493)
			(xy 40.23995 -223.165924) (xy 40.21442 -223.16547) (xy 40.163957 -223.1577) (xy 40.115284 -223.142277)
			(xy 40.069556 -223.119564) (xy 40.048434 -223.105218) (xy 40.041893 -223.100943) (xy 40.02703 -223.09615)
			(xy 40.019224 -223.09582) (xy 39.50335 -223.09582) (xy 39.49797 -223.095378) (xy 39.490385 -223.087741)
			(xy 39.489888 -223.082358) (xy 33.445704 -223.082358) (xy 33.445154 -223.087647) (xy 33.437771 -223.095218)
			(xy 33.432496 -223.09582) (xy 32.916622 -223.09582) (xy 32.908812 -223.096139) (xy 32.893941 -223.100921)
			(xy 32.887412 -223.105218) (xy 32.866282 -223.119554) (xy 32.820561 -223.142285) (xy 32.771891 -223.157719)
			(xy 32.721426 -223.165489) (xy 32.695896 -223.165924) (xy 32.670365 -223.165497) (xy 32.619901 -223.157719)
			(xy 32.571228 -223.142288) (xy 32.525501 -223.119567) (xy 32.50438 -223.105218) (xy 32.497851 -223.100922)
			(xy 32.482979 -223.096142) (xy 32.47517 -223.09582) (xy 31.959296 -223.09582) (xy 31.954036 -223.095309)
			(xy 31.946594 -223.087872) (xy 31.946088 -223.082612) (xy 25.901878 -223.082612) (xy 25.901354 -223.087647)
			(xy 25.893971 -223.095218) (xy 25.888696 -223.09582) (xy 25.372822 -223.09582) (xy 25.365012 -223.096139)
			(xy 25.350141 -223.100921) (xy 25.343612 -223.105218) (xy 25.322482 -223.119554) (xy 25.276761 -223.142285)
			(xy 25.228091 -223.157719) (xy 25.177626 -223.165489) (xy 25.152096 -223.165924) (xy 25.126565 -223.165497)
			(xy 25.076101 -223.157719) (xy 25.027428 -223.142288) (xy 24.981701 -223.119567) (xy 24.96058 -223.105218)
			(xy 24.954051 -223.100922) (xy 24.939179 -223.096142) (xy 24.93137 -223.09582) (xy 24.415496 -223.09582)
			(xy 24.410236 -223.095309) (xy 24.402794 -223.087872) (xy 24.402288 -223.082612) (xy 18.358077 -223.082612)
			(xy 18.357526 -223.087707) (xy 18.349988 -223.095293) (xy 18.344642 -223.09582) (xy 17.828768 -223.09582)
			(xy 17.82096 -223.096159) (xy 17.806089 -223.100927) (xy 17.799558 -223.105218) (xy 17.778443 -223.119578)
			(xy 17.732717 -223.142303) (xy 17.684042 -223.15773) (xy 17.633574 -223.165493) (xy 17.608042 -223.165924)
			(xy 17.582512 -223.165474) (xy 17.532049 -223.157703) (xy 17.483376 -223.142278) (xy 17.437648 -223.119564)
			(xy 17.416526 -223.105218) (xy 17.409987 -223.10094) (xy 17.395123 -223.096149) (xy 17.387316 -223.09582)
			(xy 16.871442 -223.09582) (xy 16.866003 -223.095488) (xy 16.858312 -223.087797) (xy 16.85798 -223.082358)
			(xy 2.509012 -223.082358) (xy 2.509012 -223.932496) (xy 20.958048 -223.932496) (xy 20.958048 -223.437958)
			(xy 20.958523 -223.432586) (xy 20.966137 -223.425003) (xy 20.97151 -223.424496) (xy 21.487638 -223.424496)
			(xy 21.495446 -223.424157) (xy 21.510317 -223.419389) (xy 21.516848 -223.415098) (xy 21.537937 -223.400749)
			(xy 21.583598 -223.378018) (xy 21.632204 -223.362559) (xy 21.682607 -223.354736) (xy 21.733613 -223.354736)
			(xy 21.784016 -223.362559) (xy 21.832622 -223.378018) (xy 21.878283 -223.400749) (xy 21.899372 -223.415098)
			(xy 21.905911 -223.419377) (xy 21.920775 -223.424168) (xy 21.928582 -223.424496) (xy 22.44471 -223.424496)
			(xy 22.450065 -223.425039) (xy 22.457648 -223.432604) (xy 22.458172 -223.437958) (xy 22.458172 -223.932496)
			(xy 28.502356 -223.932496) (xy 28.502356 -223.437958) (xy 28.502797 -223.432645) (xy 28.510259 -223.425075)
			(xy 28.515564 -223.424496) (xy 29.031692 -223.424496) (xy 29.039502 -223.42418) (xy 29.054373 -223.419396)
			(xy 29.060902 -223.415098) (xy 29.081991 -223.400749) (xy 29.127652 -223.378018) (xy 29.176258 -223.362559)
			(xy 29.226661 -223.354736) (xy 29.277667 -223.354736) (xy 29.32807 -223.362559) (xy 29.376676 -223.378018)
			(xy 29.422337 -223.400749) (xy 29.443426 -223.415098) (xy 29.449953 -223.419398) (xy 29.464826 -223.424176)
			(xy 29.472636 -223.424496) (xy 29.988764 -223.424496) (xy 29.994092 -223.424851) (xy 30.001636 -223.432376)
			(xy 30.001972 -223.437704) (xy 30.001972 -223.438212) (xy 30.001972 -223.932496) (xy 36.046156 -223.932496)
			(xy 36.046156 -223.437958) (xy 36.046597 -223.432645) (xy 36.054059 -223.425075) (xy 36.059364 -223.424496)
			(xy 36.575492 -223.424496) (xy 36.583302 -223.42418) (xy 36.598173 -223.419396) (xy 36.604702 -223.415098)
			(xy 36.625791 -223.400749) (xy 36.671452 -223.378018) (xy 36.720058 -223.362559) (xy 36.770461 -223.354736)
			(xy 36.821467 -223.354736) (xy 36.87187 -223.362559) (xy 36.920476 -223.378018) (xy 36.966137 -223.400749)
			(xy 36.987226 -223.415098) (xy 36.993753 -223.419398) (xy 37.008626 -223.424176) (xy 37.016436 -223.424496)
			(xy 37.532564 -223.424496) (xy 37.537892 -223.424851) (xy 37.545436 -223.432376) (xy 37.545772 -223.437704)
			(xy 37.545772 -223.438212) (xy 37.545772 -223.932496) (xy 43.589956 -223.932496) (xy 43.589956 -223.437958)
			(xy 43.590424 -223.432585) (xy 43.598042 -223.425) (xy 43.603418 -223.424496) (xy 44.119546 -223.424496)
			(xy 44.127354 -223.42416) (xy 44.142226 -223.41939) (xy 44.148756 -223.415098) (xy 44.169845 -223.400749)
			(xy 44.215506 -223.378018) (xy 44.264112 -223.362559) (xy 44.314515 -223.354736) (xy 44.365521 -223.354736)
			(xy 44.415924 -223.362559) (xy 44.46453 -223.378018) (xy 44.510191 -223.400749) (xy 44.53128 -223.415098)
			(xy 44.537817 -223.41938) (xy 44.552683 -223.424169) (xy 44.56049 -223.424496) (xy 45.076618 -223.424496)
			(xy 45.081974 -223.425034) (xy 45.089556 -223.432603) (xy 45.09008 -223.437958) (xy 45.09008 -223.932496)
			(xy 51.134264 -223.932496) (xy 51.134264 -223.437958) (xy 51.134698 -223.432643) (xy 51.142165 -223.425073)
			(xy 51.147472 -223.424496) (xy 51.6636 -223.424496) (xy 51.67141 -223.424183) (xy 51.686282 -223.419397)
			(xy 51.69281 -223.415098) (xy 51.713899 -223.400749) (xy 51.75956 -223.378018) (xy 51.808166 -223.362559)
			(xy 51.858569 -223.354736) (xy 51.909575 -223.354736) (xy 51.959978 -223.362559) (xy 52.008584 -223.378018)
			(xy 52.054245 -223.400749) (xy 52.075334 -223.415098) (xy 52.081859 -223.419401) (xy 52.096734 -223.424177)
			(xy 52.104544 -223.424496) (xy 52.620672 -223.424496) (xy 52.626002 -223.424846) (xy 52.633544 -223.432375)
			(xy 52.63388 -223.437704) (xy 52.63388 -223.438212) (xy 52.63388 -223.932496) (xy 58.678064 -223.932496)
			(xy 58.678064 -223.437958) (xy 58.678525 -223.432583) (xy 58.686148 -223.424998) (xy 58.691526 -223.424496)
			(xy 60.164726 -223.424496) (xy 60.170083 -223.425029) (xy 60.177665 -223.432602) (xy 60.178188 -223.437958)
			(xy 60.178188 -223.932496) (xy 167.778176 -223.932496) (xy 167.778176 -223.437958) (xy 167.778599 -223.43264)
			(xy 167.786073 -223.425069) (xy 167.791384 -223.424496) (xy 169.264584 -223.424496) (xy 169.269915 -223.424838)
			(xy 169.277457 -223.432373) (xy 169.277792 -223.437704) (xy 169.277792 -223.932496) (xy 175.321976 -223.932496)
			(xy 175.321976 -223.437958) (xy 175.322426 -223.43258) (xy 175.330057 -223.424994) (xy 175.335438 -223.424496)
			(xy 175.851566 -223.424496) (xy 175.859375 -223.424169) (xy 175.874246 -223.419392) (xy 175.880776 -223.415098)
			(xy 175.901865 -223.400749) (xy 175.947526 -223.378018) (xy 175.996132 -223.362559) (xy 176.046535 -223.354736)
			(xy 176.097541 -223.354736) (xy 176.147944 -223.362559) (xy 176.19655 -223.378018) (xy 176.242211 -223.400749)
			(xy 176.2633 -223.415098) (xy 176.269832 -223.419388) (xy 176.284702 -223.424172) (xy 176.29251 -223.424496)
			(xy 176.808638 -223.424496) (xy 176.813996 -223.425021) (xy 176.821577 -223.4326) (xy 176.8221 -223.437958)
			(xy 176.8221 -223.932496) (xy 182.866284 -223.932496) (xy 182.866284 -223.437958) (xy 182.8667 -223.432638)
			(xy 182.874179 -223.425067) (xy 182.879492 -223.424496) (xy 183.39562 -223.424496) (xy 183.403431 -223.424191)
			(xy 183.418302 -223.419399) (xy 183.42483 -223.415098) (xy 183.445919 -223.400749) (xy 183.49158 -223.378018)
			(xy 183.540186 -223.362559) (xy 183.590589 -223.354736) (xy 183.641595 -223.354736) (xy 183.691998 -223.362559)
			(xy 183.740604 -223.378018) (xy 183.786265 -223.400749) (xy 183.807354 -223.415098) (xy 183.813874 -223.419409)
			(xy 183.828753 -223.42418) (xy 183.836564 -223.424496) (xy 184.352692 -223.424496) (xy 184.358024 -223.424832)
			(xy 184.365566 -223.432372) (xy 184.3659 -223.437704) (xy 184.3659 -223.438212) (xy 184.3659 -223.932496)
			(xy 190.410084 -223.932496) (xy 190.410084 -223.437958) (xy 190.410356 -223.432506) (xy 190.418092 -223.42482)
			(xy 190.423546 -223.424496) (xy 190.939674 -223.424496) (xy 190.947483 -223.424172) (xy 190.962355 -223.419393)
			(xy 190.968884 -223.415098) (xy 190.989973 -223.400749) (xy 191.035634 -223.378018) (xy 191.08424 -223.362559)
			(xy 191.134643 -223.354736) (xy 191.185649 -223.354736) (xy 191.236052 -223.362559) (xy 191.284658 -223.378018)
			(xy 191.330319 -223.400749) (xy 191.351408 -223.415098) (xy 191.357939 -223.419391) (xy 191.372809 -223.424173)
			(xy 191.380618 -223.424496) (xy 191.896746 -223.424496) (xy 191.902105 -223.425016) (xy 191.909686 -223.432598)
			(xy 191.910208 -223.437958) (xy 191.910208 -223.932496) (xy 197.954392 -223.932496) (xy 197.954392 -223.437958)
			(xy 197.954889 -223.43266) (xy 197.962312 -223.425094) (xy 197.9676 -223.424496) (xy 198.483728 -223.424496)
			(xy 198.491539 -223.424195) (xy 198.506411 -223.4194) (xy 198.512938 -223.415098) (xy 198.534027 -223.400749)
			(xy 198.579688 -223.378018) (xy 198.628294 -223.362559) (xy 198.678697 -223.354736) (xy 198.729703 -223.354736)
			(xy 198.780106 -223.362559) (xy 198.828712 -223.378018) (xy 198.874373 -223.400749) (xy 198.895462 -223.415098)
			(xy 198.902003 -223.419373) (xy 198.916866 -223.424166) (xy 198.924672 -223.424496) (xy 199.4408 -223.424496)
			(xy 199.446133 -223.424827) (xy 199.453675 -223.432371) (xy 199.454008 -223.437704) (xy 199.454008 -223.438212)
			(xy 199.454008 -223.932496) (xy 205.498192 -223.932496) (xy 205.498192 -223.437958) (xy 205.498689 -223.43266)
			(xy 205.506112 -223.425094) (xy 205.5114 -223.424496) (xy 206.027528 -223.424496) (xy 206.035339 -223.424195)
			(xy 206.050211 -223.4194) (xy 206.056738 -223.415098) (xy 206.077827 -223.400749) (xy 206.123488 -223.378018)
			(xy 206.172094 -223.362559) (xy 206.222497 -223.354736) (xy 206.273503 -223.354736) (xy 206.323906 -223.362559)
			(xy 206.372512 -223.378018) (xy 206.418173 -223.400749) (xy 206.439262 -223.415098) (xy 206.445803 -223.419373)
			(xy 206.460666 -223.424166) (xy 206.468472 -223.424496) (xy 206.9846 -223.424496) (xy 206.989933 -223.424827)
			(xy 206.997475 -223.432371) (xy 206.997808 -223.437704) (xy 206.997808 -223.438212) (xy 206.997808 -223.932242)
			(xy 268.898116 -223.932242) (xy 268.898116 -223.437704) (xy 268.898432 -223.432366) (xy 268.905986 -223.424824)
			(xy 268.911324 -223.424496) (xy 268.911832 -223.424496) (xy 269.427706 -223.424496) (xy 269.435516 -223.424186)
			(xy 269.450388 -223.419397) (xy 269.456916 -223.415098) (xy 269.478005 -223.400749) (xy 269.523666 -223.378018)
			(xy 269.572272 -223.362559) (xy 269.622675 -223.354736) (xy 269.673681 -223.354736) (xy 269.724084 -223.362559)
			(xy 269.77269 -223.378018) (xy 269.818351 -223.400749) (xy 269.83944 -223.415098) (xy 269.845963 -223.419403)
			(xy 269.86084 -223.424178) (xy 269.86865 -223.424496) (xy 270.384778 -223.424496) (xy 270.390069 -223.425032)
			(xy 270.397639 -223.432425) (xy 270.39824 -223.437704) (xy 270.39824 -223.932242) (xy 270.398218 -223.932496)
			(xy 276.442424 -223.932496) (xy 276.442424 -223.931988) (xy 276.442424 -223.437704) (xy 276.442733 -223.432365)
			(xy 276.450292 -223.424822) (xy 276.455632 -223.424496) (xy 276.97176 -223.424496) (xy 276.979569 -223.424166)
			(xy 276.99444 -223.419391) (xy 277.00097 -223.415098) (xy 277.022059 -223.400749) (xy 277.06772 -223.378018)
			(xy 277.116326 -223.362559) (xy 277.166729 -223.354736) (xy 277.217735 -223.354736) (xy 277.268138 -223.362559)
			(xy 277.316744 -223.378018) (xy 277.362405 -223.400749) (xy 277.383494 -223.415098) (xy 277.390028 -223.419386)
			(xy 277.404896 -223.424171) (xy 277.412704 -223.424496) (xy 277.928832 -223.424496) (xy 277.9341 -223.424974)
			(xy 277.941541 -223.432435) (xy 277.94204 -223.437704) (xy 277.94204 -223.932242) (xy 277.942019 -223.932496)
			(xy 283.986224 -223.932496) (xy 283.986224 -223.931988) (xy 283.986224 -223.437704) (xy 283.986533 -223.432365)
			(xy 283.994092 -223.424822) (xy 283.999432 -223.424496) (xy 284.51556 -223.424496) (xy 284.523369 -223.424166)
			(xy 284.53824 -223.419391) (xy 284.54477 -223.415098) (xy 284.565859 -223.400749) (xy 284.61152 -223.378018)
			(xy 284.660126 -223.362559) (xy 284.710529 -223.354736) (xy 284.761535 -223.354736) (xy 284.811938 -223.362559)
			(xy 284.860544 -223.378018) (xy 284.906205 -223.400749) (xy 284.927294 -223.415098) (xy 284.933828 -223.419386)
			(xy 284.948696 -223.424171) (xy 284.956504 -223.424496) (xy 285.472632 -223.424496) (xy 285.4779 -223.424974)
			(xy 285.485341 -223.432435) (xy 285.48584 -223.437704) (xy 285.48584 -223.932242) (xy 291.530024 -223.932242)
			(xy 291.530024 -223.437704) (xy 291.530333 -223.432365) (xy 291.537892 -223.424822) (xy 291.543232 -223.424496)
			(xy 291.54374 -223.424496) (xy 292.059614 -223.424496) (xy 292.067425 -223.424189) (xy 292.082296 -223.419398)
			(xy 292.088824 -223.415098) (xy 292.109913 -223.400749) (xy 292.155574 -223.378018) (xy 292.20418 -223.362559)
			(xy 292.254583 -223.354736) (xy 292.305589 -223.354736) (xy 292.355992 -223.362559) (xy 292.404598 -223.378018)
			(xy 292.450259 -223.400749) (xy 292.471348 -223.415098) (xy 292.47787 -223.419406) (xy 292.492747 -223.424179)
			(xy 292.500558 -223.424496) (xy 293.016686 -223.424496) (xy 293.021978 -223.425027) (xy 293.029548 -223.432424)
			(xy 293.030148 -223.437704) (xy 293.030148 -223.932242) (xy 293.030126 -223.932496) (xy 299.074332 -223.932496)
			(xy 299.074332 -223.931988) (xy 299.074332 -223.437704) (xy 299.074634 -223.432363) (xy 299.082198 -223.424819)
			(xy 299.08754 -223.424496) (xy 299.603668 -223.424496) (xy 299.611477 -223.42417) (xy 299.626348 -223.419392)
			(xy 299.632878 -223.415098) (xy 299.653967 -223.400749) (xy 299.699628 -223.378018) (xy 299.748234 -223.362559)
			(xy 299.798637 -223.354736) (xy 299.849643 -223.354736) (xy 299.900046 -223.362559) (xy 299.948652 -223.378018)
			(xy 299.994313 -223.400749) (xy 300.015402 -223.415098) (xy 300.021934 -223.419389) (xy 300.036804 -223.424172)
			(xy 300.044612 -223.424496) (xy 300.56074 -223.424496) (xy 300.566009 -223.424968) (xy 300.573449 -223.432434)
			(xy 300.573948 -223.437704) (xy 300.573948 -223.932242) (xy 306.618132 -223.932242) (xy 306.618132 -223.437704)
			(xy 306.618434 -223.432363) (xy 306.625998 -223.424819) (xy 306.63134 -223.424496) (xy 306.631848 -223.424496)
			(xy 308.104794 -223.424496) (xy 308.110087 -223.425022) (xy 308.117656 -223.432423) (xy 308.118256 -223.437704)
			(xy 308.118256 -223.932242) (xy 308.118233 -223.932496) (xy 415.718244 -223.932496) (xy 415.718244 -223.437704)
			(xy 415.718792 -223.432453) (xy 415.726203 -223.425013) (xy 415.731452 -223.424496) (xy 417.204652 -223.424496)
			(xy 417.209979 -223.42486) (xy 417.217523 -223.432378) (xy 417.21786 -223.437704) (xy 417.21786 -223.932242)
			(xy 423.262044 -223.932242) (xy 423.262044 -223.437704) (xy 423.262592 -223.432453) (xy 423.270003 -223.425013)
			(xy 423.275252 -223.424496) (xy 423.27576 -223.424496) (xy 423.791634 -223.424496) (xy 423.799442 -223.424155)
			(xy 423.814313 -223.419388) (xy 423.820844 -223.415098) (xy 423.841933 -223.400749) (xy 423.887594 -223.378018)
			(xy 423.9362 -223.362559) (xy 423.986603 -223.354736) (xy 424.037609 -223.354736) (xy 424.088012 -223.362559)
			(xy 424.136618 -223.378018) (xy 424.182279 -223.400749) (xy 424.203368 -223.415098) (xy 424.209907 -223.419376)
			(xy 424.224771 -223.424167) (xy 424.232578 -223.424496) (xy 424.748706 -223.424496) (xy 424.754001 -223.425014)
			(xy 424.761569 -223.432421) (xy 424.762168 -223.437704) (xy 424.762168 -223.932242) (xy 424.762145 -223.932496)
			(xy 430.806352 -223.932496) (xy 430.806352 -223.931988) (xy 430.806352 -223.437704) (xy 430.806893 -223.432451)
			(xy 430.814309 -223.425011) (xy 430.81956 -223.424496) (xy 431.335688 -223.424496) (xy 431.343498 -223.424178)
			(xy 431.358369 -223.419395) (xy 431.364898 -223.415098) (xy 431.385987 -223.400749) (xy 431.431648 -223.378018)
			(xy 431.480254 -223.362559) (xy 431.530657 -223.354736) (xy 431.581663 -223.354736) (xy 431.632066 -223.362559)
			(xy 431.680672 -223.378018) (xy 431.726333 -223.400749) (xy 431.747422 -223.415098) (xy 431.753949 -223.419396)
			(xy 431.768823 -223.424175) (xy 431.776632 -223.424496) (xy 432.29276 -223.424496) (xy 432.298088 -223.424854)
			(xy 432.305631 -223.432377) (xy 432.305968 -223.437704) (xy 432.305968 -223.932242) (xy 438.350152 -223.932242)
			(xy 438.350152 -223.437704) (xy 438.350693 -223.432451) (xy 438.358109 -223.425011) (xy 438.36336 -223.424496)
			(xy 438.363868 -223.424496) (xy 438.879742 -223.424496) (xy 438.88755 -223.424159) (xy 438.902422 -223.419389)
			(xy 438.908952 -223.415098) (xy 438.930041 -223.400749) (xy 438.975702 -223.378018) (xy 439.024308 -223.362559)
			(xy 439.074711 -223.354736) (xy 439.125717 -223.354736) (xy 439.17612 -223.362559) (xy 439.224726 -223.378018)
			(xy 439.270387 -223.400749) (xy 439.291476 -223.415098) (xy 439.298014 -223.419379) (xy 439.312879 -223.424168)
			(xy 439.320686 -223.424496) (xy 439.836814 -223.424496) (xy 439.84211 -223.425008) (xy 439.849678 -223.43242)
			(xy 439.850276 -223.437704) (xy 439.850276 -223.932242) (xy 439.850252 -223.932496) (xy 445.89446 -223.932496)
			(xy 445.89446 -223.931988) (xy 445.89446 -223.437704) (xy 445.894994 -223.432449) (xy 445.902415 -223.425008)
			(xy 445.907668 -223.424496) (xy 446.423796 -223.424496) (xy 446.431606 -223.424181) (xy 446.446477 -223.419396)
			(xy 446.453006 -223.415098) (xy 446.474095 -223.400749) (xy 446.519756 -223.378018) (xy 446.568362 -223.362559)
			(xy 446.618765 -223.354736) (xy 446.669771 -223.354736) (xy 446.720174 -223.362559) (xy 446.76878 -223.378018)
			(xy 446.814441 -223.400749) (xy 446.83553 -223.415098) (xy 446.842056 -223.419399) (xy 446.85693 -223.424176)
			(xy 446.86474 -223.424496) (xy 447.380868 -223.424496) (xy 447.386197 -223.424849) (xy 447.39374 -223.432376)
			(xy 447.394076 -223.437704) (xy 447.394076 -223.932242) (xy 447.394054 -223.932496) (xy 453.43826 -223.932496)
			(xy 453.43826 -223.931988) (xy 453.43826 -223.437704) (xy 453.438794 -223.432449) (xy 453.446215 -223.425008)
			(xy 453.451468 -223.424496) (xy 453.967596 -223.424496) (xy 453.975406 -223.424181) (xy 453.990277 -223.419396)
			(xy 453.996806 -223.415098) (xy 454.017895 -223.400749) (xy 454.063556 -223.378018) (xy 454.112162 -223.362559)
			(xy 454.162565 -223.354736) (xy 454.213571 -223.354736) (xy 454.263974 -223.362559) (xy 454.31258 -223.378018)
			(xy 454.358241 -223.400749) (xy 454.37933 -223.415098) (xy 454.385856 -223.419399) (xy 454.40073 -223.424176)
			(xy 454.40854 -223.424496) (xy 454.924668 -223.424496) (xy 454.929997 -223.424849) (xy 454.93754 -223.432376)
			(xy 454.937876 -223.437704) (xy 454.937876 -223.932242) (xy 454.937407 -223.937548) (xy 454.929964 -223.945115)
			(xy 454.924668 -223.945704) (xy 454.408794 -223.945704) (xy 454.400984 -223.946014) (xy 454.386112 -223.950803)
			(xy 454.379584 -223.955102) (xy 454.35846 -223.969448) (xy 454.312738 -223.992177) (xy 454.264065 -224.007608)
			(xy 454.213599 -224.015375) (xy 454.188068 -224.015808) (xy 454.162538 -224.01538) (xy 454.112074 -224.0076)
			(xy 454.063401 -223.992168) (xy 454.017674 -223.96945) (xy 453.996552 -223.955102) (xy 453.99003 -223.950794)
			(xy 453.975153 -223.946021) (xy 453.967342 -223.945704) (xy 453.451468 -223.945704) (xy 453.4462 -223.945226)
			(xy 453.438759 -223.937765) (xy 453.43826 -223.932496) (xy 447.394054 -223.932496) (xy 447.393607 -223.937548)
			(xy 447.386164 -223.945115) (xy 447.380868 -223.945704) (xy 446.864994 -223.945704) (xy 446.857184 -223.946014)
			(xy 446.842312 -223.950803) (xy 446.835784 -223.955102) (xy 446.81466 -223.969448) (xy 446.768938 -223.992177)
			(xy 446.720265 -224.007608) (xy 446.669799 -224.015375) (xy 446.644268 -224.015808) (xy 446.618738 -224.01538)
			(xy 446.568274 -224.0076) (xy 446.519601 -223.992168) (xy 446.473874 -223.96945) (xy 446.452752 -223.955102)
			(xy 446.44623 -223.950794) (xy 446.431353 -223.946021) (xy 446.423542 -223.945704) (xy 445.907668 -223.945704)
			(xy 445.9024 -223.945226) (xy 445.894959 -223.937765) (xy 445.89446 -223.932496) (xy 439.850252 -223.932496)
			(xy 439.849779 -223.937608) (xy 439.842181 -223.94519) (xy 439.836814 -223.945704) (xy 439.32094 -223.945704)
			(xy 439.313131 -223.946034) (xy 439.29826 -223.950809) (xy 439.29173 -223.955102) (xy 439.270622 -223.969472)
			(xy 439.224893 -223.992195) (xy 439.176216 -224.00762) (xy 439.125746 -224.015379) (xy 439.100214 -224.015808)
			(xy 439.074684 -224.015357) (xy 439.024222 -224.007584) (xy 438.975549 -223.992159) (xy 438.929821 -223.969447)
			(xy 438.908698 -223.955102) (xy 438.902166 -223.950811) (xy 438.887296 -223.946028) (xy 438.879488 -223.945704)
			(xy 438.363614 -223.945704) (xy 438.358262 -223.945145) (xy 438.350678 -223.937592) (xy 438.350152 -223.932242)
			(xy 432.305968 -223.932242) (xy 432.305506 -223.93755) (xy 432.298059 -223.945118) (xy 432.29276 -223.945704)
			(xy 431.776886 -223.945704) (xy 431.769075 -223.946011) (xy 431.754204 -223.950802) (xy 431.747676 -223.955102)
			(xy 431.726555 -223.969452) (xy 431.680831 -223.99218) (xy 431.632158 -224.00761) (xy 431.581691 -224.015376)
			(xy 431.55616 -224.015808) (xy 431.530629 -224.015384) (xy 431.480165 -224.007603) (xy 431.431493 -223.99217)
			(xy 431.385766 -223.96945) (xy 431.364644 -223.955102) (xy 431.358124 -223.950791) (xy 431.343245 -223.94602)
			(xy 431.335434 -223.945704) (xy 430.81956 -223.945704) (xy 430.814291 -223.945232) (xy 430.806851 -223.937766)
			(xy 430.806352 -223.932496) (xy 424.762145 -223.932496) (xy 424.761678 -223.93761) (xy 424.754075 -223.945193)
			(xy 424.748706 -223.945704) (xy 424.232832 -223.945704) (xy 424.225023 -223.94603) (xy 424.210152 -223.950808)
			(xy 424.203622 -223.955102) (xy 424.182488 -223.969432) (xy 424.136769 -223.992165) (xy 424.0881 -224.0076)
			(xy 424.037636 -224.015372) (xy 424.012106 -224.015808) (xy 423.986576 -224.015361) (xy 423.936113 -224.007587)
			(xy 423.887441 -223.992161) (xy 423.841713 -223.969447) (xy 423.82059 -223.955102) (xy 423.81406 -223.950808)
			(xy 423.799189 -223.946027) (xy 423.79138 -223.945704) (xy 423.275506 -223.945704) (xy 423.270153 -223.94515)
			(xy 423.262569 -223.937593) (xy 423.262044 -223.932242) (xy 417.21786 -223.932242) (xy 417.217405 -223.937551)
			(xy 417.209953 -223.94512) (xy 417.204652 -223.945704) (xy 415.731452 -223.945704) (xy 415.726182 -223.945237)
			(xy 415.718743 -223.937767) (xy 415.718244 -223.932496) (xy 308.118233 -223.932496) (xy 308.117777 -223.937613)
			(xy 308.110166 -223.945196) (xy 308.104794 -223.945704) (xy 306.631594 -223.945704) (xy 306.626239 -223.945158)
			(xy 306.618656 -223.937595) (xy 306.618132 -223.932242) (xy 300.573948 -223.932242) (xy 300.573503 -223.937554)
			(xy 300.566044 -223.945124) (xy 300.56074 -223.945704) (xy 300.044866 -223.945704) (xy 300.037058 -223.946045)
			(xy 300.022187 -223.950812) (xy 300.015656 -223.955102) (xy 299.99454 -223.969461) (xy 299.948815 -223.992187)
			(xy 299.90014 -224.007614) (xy 299.849672 -224.015377) (xy 299.82414 -224.015808) (xy 299.798611 -224.015344)
			(xy 299.748149 -224.007575) (xy 299.699476 -223.992154) (xy 299.653747 -223.969445) (xy 299.632624 -223.955102)
			(xy 299.626086 -223.950821) (xy 299.611221 -223.946032) (xy 299.603414 -223.945704) (xy 299.08754 -223.945704)
			(xy 299.082212 -223.945346) (xy 299.074669 -223.937823) (xy 299.074332 -223.932496) (xy 293.030126 -223.932496)
			(xy 293.029676 -223.937614) (xy 293.02206 -223.945199) (xy 293.016686 -223.945704) (xy 292.500812 -223.945704)
			(xy 292.493002 -223.946022) (xy 292.478131 -223.950805) (xy 292.471602 -223.955102) (xy 292.450473 -223.969441)
			(xy 292.404753 -223.992171) (xy 292.356081 -224.007605) (xy 292.305616 -224.015374) (xy 292.280086 -224.015808)
			(xy 292.254556 -224.015371) (xy 292.204092 -224.007594) (xy 292.15542 -223.992165) (xy 292.109692 -223.969449)
			(xy 292.08857 -223.955102) (xy 292.082044 -223.950801) (xy 292.06717 -223.946024) (xy 292.05936 -223.945704)
			(xy 291.543486 -223.945704) (xy 291.538131 -223.945163) (xy 291.530548 -223.937596) (xy 291.530024 -223.932242)
			(xy 285.48584 -223.932242) (xy 285.485403 -223.937556) (xy 285.477938 -223.945126) (xy 285.472632 -223.945704)
			(xy 284.956758 -223.945704) (xy 284.94895 -223.946041) (xy 284.934078 -223.950811) (xy 284.927548 -223.955102)
			(xy 284.906435 -223.969464) (xy 284.860708 -223.992189) (xy 284.812032 -224.007616) (xy 284.761564 -224.015378)
			(xy 284.736032 -224.015808) (xy 284.710503 -224.015348) (xy 284.66004 -224.007578) (xy 284.611368 -223.992155)
			(xy 284.565639 -223.969446) (xy 284.544516 -223.955102) (xy 284.53798 -223.950818) (xy 284.523113 -223.946031)
			(xy 284.515306 -223.945704) (xy 283.999432 -223.945704) (xy 283.994103 -223.945351) (xy 283.98656 -223.937824)
			(xy 283.986224 -223.932496) (xy 277.942019 -223.932496) (xy 277.941603 -223.937556) (xy 277.934138 -223.945126)
			(xy 277.928832 -223.945704) (xy 277.412958 -223.945704) (xy 277.40515 -223.946041) (xy 277.390278 -223.950811)
			(xy 277.383748 -223.955102) (xy 277.362635 -223.969464) (xy 277.316908 -223.992189) (xy 277.268232 -224.007616)
			(xy 277.217764 -224.015378) (xy 277.192232 -224.015808) (xy 277.166703 -224.015348) (xy 277.11624 -224.007578)
			(xy 277.067568 -223.992155) (xy 277.021839 -223.969446) (xy 277.000716 -223.955102) (xy 276.99418 -223.950818)
			(xy 276.979313 -223.946031) (xy 276.971506 -223.945704) (xy 276.455632 -223.945704) (xy 276.450303 -223.945351)
			(xy 276.44276 -223.937824) (xy 276.442424 -223.932496) (xy 270.398218 -223.932496) (xy 270.397775 -223.937616)
			(xy 270.390155 -223.945201) (xy 270.384778 -223.945704) (xy 269.868904 -223.945704) (xy 269.861094 -223.946019)
			(xy 269.846223 -223.950804) (xy 269.839694 -223.955102) (xy 269.818568 -223.969444) (xy 269.772846 -223.992174)
			(xy 269.724174 -224.007606) (xy 269.673709 -224.015374) (xy 269.648178 -224.015808) (xy 269.622648 -224.015375)
			(xy 269.572184 -224.007596) (xy 269.523512 -223.992166) (xy 269.477784 -223.969449) (xy 269.456662 -223.955102)
			(xy 269.450138 -223.950798) (xy 269.435262 -223.946023) (xy 269.427452 -223.945704) (xy 268.911578 -223.945704)
			(xy 268.906222 -223.945168) (xy 268.89864 -223.937598) (xy 268.898116 -223.932242) (xy 206.997808 -223.932242)
			(xy 206.997808 -223.932496) (xy 206.99747 -223.937828) (xy 206.989932 -223.945369) (xy 206.9846 -223.945704)
			(xy 206.468726 -223.945704) (xy 206.46085 -223.945975) (xy 206.445847 -223.950771) (xy 206.439262 -223.955102)
			(xy 206.418182 -223.969489) (xy 206.372538 -223.99232) (xy 206.323933 -224.007879) (xy 206.273517 -224.015799)
			(xy 206.248 -224.016316) (xy 206.222479 -224.015841) (xy 206.172052 -224.007941) (xy 206.12344 -223.992377)
			(xy 206.077803 -223.969519) (xy 206.056738 -223.955102) (xy 206.05014 -223.950799) (xy 206.035145 -223.946005)
			(xy 206.027274 -223.945704) (xy 205.5114 -223.945704) (xy 205.506067 -223.945373) (xy 205.498525 -223.937829)
			(xy 205.498192 -223.932496) (xy 199.454008 -223.932496) (xy 199.45367 -223.937828) (xy 199.446132 -223.945369)
			(xy 199.4408 -223.945704) (xy 198.924926 -223.945704) (xy 198.91705 -223.945975) (xy 198.902047 -223.950771)
			(xy 198.895462 -223.955102) (xy 198.874382 -223.969489) (xy 198.828738 -223.99232) (xy 198.780133 -224.007879)
			(xy 198.729717 -224.015799) (xy 198.7042 -224.016316) (xy 198.678679 -224.015841) (xy 198.628252 -224.007941)
			(xy 198.57964 -223.992377) (xy 198.534003 -223.969519) (xy 198.512938 -223.955102) (xy 198.50634 -223.950799)
			(xy 198.491345 -223.946005) (xy 198.483474 -223.945704) (xy 197.9676 -223.945704) (xy 197.962267 -223.945373)
			(xy 197.954725 -223.937829) (xy 197.954392 -223.932496) (xy 191.910208 -223.932496) (xy 191.90987 -223.937828)
			(xy 191.902332 -223.945369) (xy 191.897 -223.945704) (xy 191.896492 -223.945704) (xy 191.380872 -223.945704)
			(xy 191.372998 -223.945995) (xy 191.357994 -223.950777) (xy 191.351408 -223.955102) (xy 191.330343 -223.969513)
			(xy 191.284694 -223.992338) (xy 191.236084 -224.007891) (xy 191.185664 -224.015803) (xy 191.160146 -224.016316)
			(xy 191.134626 -224.015817) (xy 191.0842 -224.007925) (xy 191.035588 -223.992368) (xy 190.989949 -223.969516)
			(xy 190.968884 -223.955102) (xy 190.962298 -223.950778) (xy 190.947294 -223.945997) (xy 190.93942 -223.945704)
			(xy 190.423546 -223.945704) (xy 190.418257 -223.945151) (xy 190.410686 -223.937771) (xy 190.410084 -223.932496)
			(xy 184.3659 -223.932496) (xy 184.36557 -223.93783) (xy 184.358026 -223.945371) (xy 184.352692 -223.945704)
			(xy 183.836818 -223.945704) (xy 183.828946 -223.946014) (xy 183.813942 -223.950783) (xy 183.807354 -223.955102)
			(xy 183.786276 -223.969493) (xy 183.740632 -223.992323) (xy 183.692026 -224.007881) (xy 183.641609 -224.015799)
			(xy 183.616092 -224.016316) (xy 183.590573 -224.015794) (xy 183.540148 -224.007909) (xy 183.491536 -223.992358)
			(xy 183.445896 -223.969513) (xy 183.42483 -223.955102) (xy 183.418233 -223.950796) (xy 183.403237 -223.946004)
			(xy 183.395366 -223.945704) (xy 182.879492 -223.945704) (xy 182.874227 -223.94521) (xy 182.866785 -223.937761)
			(xy 182.866284 -223.932496) (xy 176.8221 -223.932496) (xy 176.82177 -223.93783) (xy 176.814226 -223.945371)
			(xy 176.808892 -223.945704) (xy 176.808384 -223.945704) (xy 176.292764 -223.945704) (xy 176.28489 -223.945991)
			(xy 176.269886 -223.950776) (xy 176.2633 -223.955102) (xy 176.242209 -223.969473) (xy 176.19657 -223.992307)
			(xy 176.147968 -224.007871) (xy 176.097554 -224.015796) (xy 176.072038 -224.016316) (xy 176.046518 -224.015821)
			(xy 175.996091 -224.007928) (xy 175.94748 -223.992369) (xy 175.901841 -223.969516) (xy 175.880776 -223.955102)
			(xy 175.874192 -223.950775) (xy 175.859186 -223.945996) (xy 175.851312 -223.945704) (xy 175.335438 -223.945704)
			(xy 175.330149 -223.945156) (xy 175.322578 -223.937772) (xy 175.321976 -223.932496) (xy 169.277792 -223.932496)
			(xy 169.277469 -223.937832) (xy 169.26992 -223.945374) (xy 169.264584 -223.945704) (xy 167.791384 -223.945704)
			(xy 167.786118 -223.945216) (xy 167.778676 -223.937762) (xy 167.778176 -223.932496) (xy 60.178188 -223.932496)
			(xy 60.177868 -223.937833) (xy 60.170317 -223.945375) (xy 60.16498 -223.945704) (xy 60.164472 -223.945704)
			(xy 58.691526 -223.945704) (xy 58.686235 -223.945165) (xy 58.678665 -223.937774) (xy 58.678064 -223.932496)
			(xy 52.63388 -223.932496) (xy 52.633568 -223.937834) (xy 52.626011 -223.945377) (xy 52.620672 -223.945704)
			(xy 52.104798 -223.945704) (xy 52.096925 -223.946006) (xy 52.081921 -223.950781) (xy 52.075334 -223.955102)
			(xy 52.054262 -223.969502) (xy 52.008615 -223.992329) (xy 51.960008 -224.007885) (xy 51.909589 -224.015801)
			(xy 51.884072 -224.016316) (xy 51.858553 -224.015804) (xy 51.808127 -224.007916) (xy 51.759515 -223.992362)
			(xy 51.713876 -223.969514) (xy 51.69281 -223.955102) (xy 51.686218 -223.950788) (xy 51.671218 -223.946001)
			(xy 51.663346 -223.945704) (xy 51.147472 -223.945704) (xy 51.142205 -223.945224) (xy 51.134764 -223.937764)
			(xy 51.134264 -223.932496) (xy 45.09008 -223.932496) (xy 45.089768 -223.937834) (xy 45.082211 -223.945377)
			(xy 45.076872 -223.945704) (xy 45.076364 -223.945704) (xy 44.560744 -223.945704) (xy 44.552869 -223.945983)
			(xy 44.537865 -223.950773) (xy 44.53128 -223.955102) (xy 44.510195 -223.969482) (xy 44.464553 -223.992314)
			(xy 44.41595 -224.007875) (xy 44.365534 -224.015798) (xy 44.340018 -224.016316) (xy 44.314498 -224.015831)
			(xy 44.264071 -224.007935) (xy 44.215459 -223.992373) (xy 44.169821 -223.969517) (xy 44.148756 -223.955102)
			(xy 44.142176 -223.950767) (xy 44.127167 -223.945993) (xy 44.119292 -223.945704) (xy 43.603418 -223.945704)
			(xy 43.598126 -223.94517) (xy 43.590557 -223.937775) (xy 43.589956 -223.932496) (xy 37.545772 -223.932496)
			(xy 37.545467 -223.937836) (xy 37.537905 -223.94538) (xy 37.532564 -223.945704) (xy 37.01669 -223.945704)
			(xy 37.008817 -223.946003) (xy 36.993813 -223.95078) (xy 36.987226 -223.955102) (xy 36.966156 -223.969505)
			(xy 36.920509 -223.992332) (xy 36.871901 -224.007887) (xy 36.821481 -224.015802) (xy 36.795964 -224.016316)
			(xy 36.770445 -224.015808) (xy 36.720018 -224.007919) (xy 36.671407 -223.992364) (xy 36.625768 -223.969515)
			(xy 36.604702 -223.955102) (xy 36.598112 -223.950785) (xy 36.583111 -223.945999) (xy 36.575238 -223.945704)
			(xy 36.059364 -223.945704) (xy 36.054096 -223.945229) (xy 36.046655 -223.937765) (xy 36.046156 -223.932496)
			(xy 30.001972 -223.932496) (xy 30.001667 -223.937836) (xy 29.994105 -223.94538) (xy 29.988764 -223.945704)
			(xy 29.47289 -223.945704) (xy 29.465017 -223.946003) (xy 29.450013 -223.95078) (xy 29.443426 -223.955102)
			(xy 29.422356 -223.969505) (xy 29.376709 -223.992332) (xy 29.328101 -224.007887) (xy 29.277681 -224.015802)
			(xy 29.252164 -224.016316) (xy 29.226645 -224.015808) (xy 29.176218 -224.007919) (xy 29.127607 -223.992364)
			(xy 29.081968 -223.969515) (xy 29.060902 -223.955102) (xy 29.054312 -223.950785) (xy 29.039311 -223.945999)
			(xy 29.031438 -223.945704) (xy 28.515564 -223.945704) (xy 28.510296 -223.945229) (xy 28.502855 -223.937765)
			(xy 28.502356 -223.932496) (xy 22.458172 -223.932496) (xy 22.457867 -223.937836) (xy 22.450305 -223.94538)
			(xy 22.444964 -223.945704) (xy 22.444456 -223.945704) (xy 21.928836 -223.945704) (xy 21.920961 -223.94598)
			(xy 21.905957 -223.950772) (xy 21.899372 -223.955102) (xy 21.878289 -223.969485) (xy 21.832647 -223.992317)
			(xy 21.784042 -224.007877) (xy 21.733626 -224.015798) (xy 21.70811 -224.016316) (xy 21.682589 -224.015835)
			(xy 21.632162 -224.007938) (xy 21.583551 -223.992375) (xy 21.537913 -223.969518) (xy 21.516848 -223.955102)
			(xy 21.51027 -223.950764) (xy 21.495259 -223.945991) (xy 21.487384 -223.945704) (xy 20.97151 -223.945704)
			(xy 20.966217 -223.945176) (xy 20.958648 -223.937777) (xy 20.958048 -223.932496) (xy 2.509012 -223.932496)
			(xy 2.509012 -224.78238) (xy 16.85798 -224.78238) (xy 16.85798 -224.287842) (xy 16.858312 -224.282403)
			(xy 16.866003 -224.274712) (xy 16.871442 -224.27438) (xy 17.38757 -224.27438) (xy 17.395379 -224.274057)
			(xy 17.410251 -224.269278) (xy 17.41678 -224.264982) (xy 17.437869 -224.250633) (xy 17.48353 -224.227902)
			(xy 17.532136 -224.212443) (xy 17.582539 -224.20462) (xy 17.633545 -224.20462) (xy 17.683948 -224.212443)
			(xy 17.732554 -224.227902) (xy 17.778215 -224.250633) (xy 17.799304 -224.264982) (xy 17.805837 -224.269272)
			(xy 17.820706 -224.274056) (xy 17.828514 -224.27438) (xy 18.344642 -224.27438) (xy 18.350021 -224.274827)
			(xy 18.357607 -224.28246) (xy 18.358104 -224.287842) (xy 18.358104 -224.78238) (xy 24.402288 -224.78238)
			(xy 24.402288 -224.287842) (xy 24.402757 -224.282532) (xy 24.410195 -224.274955) (xy 24.415496 -224.27438)
			(xy 24.931624 -224.27438) (xy 24.939435 -224.27408) (xy 24.954307 -224.269285) (xy 24.960834 -224.264982)
			(xy 24.981923 -224.250633) (xy 25.027584 -224.227902) (xy 25.07619 -224.212443) (xy 25.126593 -224.20462)
			(xy 25.177599 -224.20462) (xy 25.228002 -224.212443) (xy 25.276608 -224.227902) (xy 25.322269 -224.250633)
			(xy 25.343358 -224.264982) (xy 25.349879 -224.269292) (xy 25.364757 -224.274064) (xy 25.372568 -224.27438)
			(xy 25.888696 -224.27438) (xy 25.893955 -224.274896) (xy 25.901398 -224.282329) (xy 25.901904 -224.287588)
			(xy 25.901904 -224.288096) (xy 25.901904 -224.78238) (xy 31.946088 -224.78238) (xy 31.946088 -224.287842)
			(xy 31.946557 -224.282532) (xy 31.953995 -224.274955) (xy 31.959296 -224.27438) (xy 32.475424 -224.27438)
			(xy 32.483235 -224.27408) (xy 32.498107 -224.269285) (xy 32.504634 -224.264982) (xy 32.525723 -224.250633)
			(xy 32.571384 -224.227902) (xy 32.61999 -224.212443) (xy 32.670393 -224.20462) (xy 32.721399 -224.20462)
			(xy 32.771802 -224.212443) (xy 32.820408 -224.227902) (xy 32.866069 -224.250633) (xy 32.887158 -224.264982)
			(xy 32.893679 -224.269292) (xy 32.908557 -224.274064) (xy 32.916368 -224.27438) (xy 33.432496 -224.27438)
			(xy 33.437755 -224.274896) (xy 33.445198 -224.282329) (xy 33.445704 -224.287588) (xy 33.445704 -224.288096)
			(xy 33.445704 -224.78238) (xy 39.489888 -224.78238) (xy 39.489888 -224.287842) (xy 39.490473 -224.282495)
			(xy 39.498007 -224.27491) (xy 39.50335 -224.27438) (xy 40.019478 -224.27438) (xy 40.027288 -224.274061)
			(xy 40.042159 -224.269279) (xy 40.048688 -224.264982) (xy 40.069777 -224.250633) (xy 40.115438 -224.227902)
			(xy 40.164044 -224.212443) (xy 40.214447 -224.20462) (xy 40.265453 -224.20462) (xy 40.315856 -224.212443)
			(xy 40.364462 -224.227902) (xy 40.410123 -224.250633) (xy 40.431212 -224.264982) (xy 40.437743 -224.269275)
			(xy 40.452613 -224.274057) (xy 40.460422 -224.27438) (xy 40.97655 -224.27438) (xy 40.98193 -224.274822)
			(xy 40.989515 -224.282459) (xy 40.990012 -224.287842) (xy 40.990012 -224.78238) (xy 47.034196 -224.78238)
			(xy 47.034196 -224.287842) (xy 47.034746 -224.282553) (xy 47.042129 -224.274982) (xy 47.047404 -224.27438)
			(xy 47.563532 -224.27438) (xy 47.57134 -224.274041) (xy 47.586211 -224.269273) (xy 47.592742 -224.264982)
			(xy 47.613831 -224.250633) (xy 47.659492 -224.227902) (xy 47.708098 -224.212443) (xy 47.758501 -224.20462)
			(xy 47.809507 -224.20462) (xy 47.85991 -224.212443) (xy 47.908516 -224.227902) (xy 47.954177 -224.250633)
			(xy 47.975266 -224.264982) (xy 47.981807 -224.269257) (xy 47.99667 -224.27405) (xy 48.004476 -224.27438)
			(xy 48.520604 -224.27438) (xy 48.525864 -224.274891) (xy 48.533306 -224.282328) (xy 48.533812 -224.287588)
			(xy 48.533812 -224.288096) (xy 48.533812 -224.78238) (xy 54.577996 -224.78238) (xy 54.577996 -224.287842)
			(xy 54.578574 -224.282493) (xy 54.586112 -224.274907) (xy 54.591458 -224.27438) (xy 56.064658 -224.27438)
			(xy 56.070097 -224.274712) (xy 56.077788 -224.282403) (xy 56.07812 -224.287842) (xy 56.07812 -224.78238)
			(xy 163.678108 -224.78238) (xy 163.678108 -224.287842) (xy 163.678647 -224.28255) (xy 163.686037 -224.274979)
			(xy 163.691316 -224.27438) (xy 165.164516 -224.27438) (xy 165.169778 -224.274883) (xy 165.177219 -224.282326)
			(xy 165.177724 -224.287588) (xy 165.177724 -224.288096) (xy 165.177724 -224.78238) (xy 171.221908 -224.78238)
			(xy 171.221908 -224.287842) (xy 171.222305 -224.28242) (xy 171.22995 -224.274733) (xy 171.23537 -224.27438)
			(xy 171.751498 -224.27438) (xy 171.759308 -224.274069) (xy 171.77418 -224.269282) (xy 171.780708 -224.264982)
			(xy 171.801797 -224.250633) (xy 171.847458 -224.227902) (xy 171.896064 -224.212443) (xy 171.946467 -224.20462)
			(xy 171.997473 -224.20462) (xy 172.047876 -224.212443) (xy 172.096482 -224.227902) (xy 172.142143 -224.250633)
			(xy 172.163232 -224.264982) (xy 172.169758 -224.269282) (xy 172.184632 -224.27406) (xy 172.192442 -224.27438)
			(xy 172.70857 -224.27438) (xy 172.714011 -224.274704) (xy 172.721701 -224.282401) (xy 172.722032 -224.287842)
			(xy 172.722032 -224.78238) (xy 178.766216 -224.78238) (xy 178.766216 -224.287842) (xy 178.766748 -224.282548)
			(xy 178.774143 -224.274976) (xy 178.779424 -224.27438) (xy 179.295552 -224.27438) (xy 179.303361 -224.274049)
			(xy 179.318232 -224.269275) (xy 179.324762 -224.264982) (xy 179.345851 -224.250633) (xy 179.391512 -224.227902)
			(xy 179.440118 -224.212443) (xy 179.490521 -224.20462) (xy 179.541527 -224.20462) (xy 179.59193 -224.212443)
			(xy 179.640536 -224.227902) (xy 179.686197 -224.250633) (xy 179.707286 -224.264982) (xy 179.713823 -224.269265)
			(xy 179.728689 -224.274053) (xy 179.736496 -224.27438) (xy 180.252624 -224.27438) (xy 180.257887 -224.274878)
			(xy 180.265327 -224.282325) (xy 180.265832 -224.287588) (xy 180.265832 -224.288096) (xy 180.265832 -224.78238)
			(xy 186.310016 -224.78238) (xy 186.310016 -224.287842) (xy 186.310405 -224.282418) (xy 186.318056 -224.274731)
			(xy 186.323478 -224.27438) (xy 186.839606 -224.27438) (xy 186.847417 -224.274072) (xy 186.862288 -224.269283)
			(xy 186.868816 -224.264982) (xy 186.889905 -224.250633) (xy 186.935566 -224.227902) (xy 186.984172 -224.212443)
			(xy 187.034575 -224.20462) (xy 187.085581 -224.20462) (xy 187.135984 -224.212443) (xy 187.18459 -224.227902)
			(xy 187.230251 -224.250633) (xy 187.25134 -224.264982) (xy 187.257865 -224.269285) (xy 187.27274 -224.274061)
			(xy 187.28055 -224.27438) (xy 187.796678 -224.27438) (xy 187.80212 -224.274698) (xy 187.80981 -224.282399)
			(xy 187.81014 -224.287842) (xy 187.81014 -224.78238) (xy 193.854324 -224.78238) (xy 193.854324 -224.287842)
			(xy 193.854849 -224.282547) (xy 193.862249 -224.274974) (xy 193.867532 -224.27438) (xy 194.38366 -224.27438)
			(xy 194.391469 -224.274053) (xy 194.406341 -224.269277) (xy 194.41287 -224.264982) (xy 194.433959 -224.250633)
			(xy 194.47962 -224.227902) (xy 194.528226 -224.212443) (xy 194.578629 -224.20462) (xy 194.629635 -224.20462)
			(xy 194.680038 -224.212443) (xy 194.728644 -224.227902) (xy 194.774305 -224.250633) (xy 194.795394 -224.264982)
			(xy 194.801929 -224.269268) (xy 194.816796 -224.274054) (xy 194.824604 -224.27438) (xy 195.340732 -224.27438)
			(xy 195.345996 -224.274872) (xy 195.353436 -224.282324) (xy 195.35394 -224.287588) (xy 195.35394 -224.288096)
			(xy 195.35394 -224.78238) (xy 201.398124 -224.78238) (xy 201.398124 -224.287842) (xy 201.398649 -224.282547)
			(xy 201.406049 -224.274974) (xy 201.411332 -224.27438) (xy 201.92746 -224.27438) (xy 201.935269 -224.274053)
			(xy 201.950141 -224.269277) (xy 201.95667 -224.264982) (xy 201.977759 -224.250633) (xy 202.02342 -224.227902)
			(xy 202.072026 -224.212443) (xy 202.122429 -224.20462) (xy 202.173435 -224.20462) (xy 202.223838 -224.212443)
			(xy 202.272444 -224.227902) (xy 202.318105 -224.250633) (xy 202.339194 -224.264982) (xy 202.345729 -224.269268)
			(xy 202.360596 -224.274054) (xy 202.368404 -224.27438) (xy 202.884532 -224.27438) (xy 202.889796 -224.274872)
			(xy 202.897236 -224.282324) (xy 202.89774 -224.287588) (xy 202.89774 -224.288096) (xy 202.89774 -224.782126)
			(xy 264.798048 -224.782126) (xy 264.798048 -224.287588) (xy 264.798582 -224.282334) (xy 264.806004 -224.274895)
			(xy 264.811256 -224.27438) (xy 264.811764 -224.27438) (xy 265.327638 -224.27438) (xy 265.335446 -224.274043)
			(xy 265.350318 -224.269273) (xy 265.356848 -224.264982) (xy 265.377937 -224.250633) (xy 265.423598 -224.227902)
			(xy 265.472204 -224.212443) (xy 265.522607 -224.20462) (xy 265.573613 -224.20462) (xy 265.624016 -224.212443)
			(xy 265.672622 -224.227902) (xy 265.718283 -224.250633) (xy 265.739372 -224.264982) (xy 265.745912 -224.269259)
			(xy 265.760775 -224.274051) (xy 265.768582 -224.27438) (xy 266.28471 -224.27438) (xy 266.290025 -224.274821)
			(xy 266.297598 -224.282281) (xy 266.298172 -224.287588) (xy 266.298172 -224.782126) (xy 266.298148 -224.78238)
			(xy 272.342356 -224.78238) (xy 272.342356 -224.781872) (xy 272.342356 -224.287588) (xy 272.342883 -224.282333)
			(xy 272.350309 -224.274893) (xy 272.355564 -224.27438) (xy 272.871692 -224.27438) (xy 272.879502 -224.274066)
			(xy 272.894374 -224.269281) (xy 272.900902 -224.264982) (xy 272.921991 -224.250633) (xy 272.967652 -224.227902)
			(xy 273.016258 -224.212443) (xy 273.066661 -224.20462) (xy 273.117667 -224.20462) (xy 273.16807 -224.212443)
			(xy 273.216676 -224.227902) (xy 273.262337 -224.250633) (xy 273.283426 -224.264982) (xy 273.289954 -224.26928)
			(xy 273.304827 -224.274059) (xy 273.312636 -224.27438) (xy 273.828764 -224.27438) (xy 273.834089 -224.27475)
			(xy 273.841631 -224.282265) (xy 273.841972 -224.287588) (xy 273.841972 -224.782126) (xy 273.841949 -224.78238)
			(xy 279.886156 -224.78238) (xy 279.886156 -224.781872) (xy 279.886156 -224.287588) (xy 279.886683 -224.282333)
			(xy 279.894109 -224.274893) (xy 279.899364 -224.27438) (xy 280.415492 -224.27438) (xy 280.423302 -224.274066)
			(xy 280.438174 -224.269281) (xy 280.444702 -224.264982) (xy 280.465791 -224.250633) (xy 280.511452 -224.227902)
			(xy 280.560058 -224.212443) (xy 280.610461 -224.20462) (xy 280.661467 -224.20462) (xy 280.71187 -224.212443)
			(xy 280.760476 -224.227902) (xy 280.806137 -224.250633) (xy 280.827226 -224.264982) (xy 280.833754 -224.26928)
			(xy 280.848627 -224.274059) (xy 280.856436 -224.27438) (xy 281.372564 -224.27438) (xy 281.377889 -224.27475)
			(xy 281.385431 -224.282265) (xy 281.385772 -224.287588) (xy 281.385772 -224.782126) (xy 287.429956 -224.782126)
			(xy 287.429956 -224.287588) (xy 287.430483 -224.282333) (xy 287.437909 -224.274893) (xy 287.443164 -224.27438)
			(xy 287.443672 -224.27438) (xy 287.959546 -224.27438) (xy 287.967354 -224.274047) (xy 287.982226 -224.269274)
			(xy 287.988756 -224.264982) (xy 288.009845 -224.250633) (xy 288.055506 -224.227902) (xy 288.104112 -224.212443)
			(xy 288.154515 -224.20462) (xy 288.205521 -224.20462) (xy 288.255924 -224.212443) (xy 288.30453 -224.227902)
			(xy 288.350191 -224.250633) (xy 288.37128 -224.264982) (xy 288.377818 -224.269262) (xy 288.392683 -224.274052)
			(xy 288.40049 -224.27438) (xy 288.916618 -224.27438) (xy 288.921934 -224.274816) (xy 288.929506 -224.28228)
			(xy 288.93008 -224.287588) (xy 288.93008 -224.782126) (xy 288.930056 -224.78238) (xy 294.974264 -224.78238)
			(xy 294.974264 -224.781872) (xy 294.974264 -224.287588) (xy 294.974784 -224.282331) (xy 294.982215 -224.27489)
			(xy 294.987472 -224.27438) (xy 295.5036 -224.27438) (xy 295.51141 -224.27407) (xy 295.526282 -224.269282)
			(xy 295.53281 -224.264982) (xy 295.553899 -224.250633) (xy 295.59956 -224.227902) (xy 295.648166 -224.212443)
			(xy 295.698569 -224.20462) (xy 295.749575 -224.20462) (xy 295.799978 -224.212443) (xy 295.848584 -224.227902)
			(xy 295.894245 -224.250633) (xy 295.915334 -224.264982) (xy 295.92186 -224.269283) (xy 295.936734 -224.27406)
			(xy 295.944544 -224.27438) (xy 296.460672 -224.27438) (xy 296.465998 -224.274744) (xy 296.47354 -224.282263)
			(xy 296.47388 -224.287588) (xy 296.47388 -224.782126) (xy 302.518064 -224.782126) (xy 302.518064 -224.287588)
			(xy 302.518584 -224.282331) (xy 302.526015 -224.27489) (xy 302.531272 -224.27438) (xy 304.004726 -224.27438)
			(xy 304.010043 -224.274811) (xy 304.017614 -224.282279) (xy 304.018188 -224.287588) (xy 304.018188 -224.782126)
			(xy 304.018163 -224.78238) (xy 411.618176 -224.78238) (xy 411.618176 -224.781872) (xy 411.618176 -224.287588)
			(xy 411.618685 -224.282328) (xy 411.626124 -224.274887) (xy 411.631384 -224.27438) (xy 413.104584 -224.27438)
			(xy 413.109911 -224.274736) (xy 413.117452 -224.282262) (xy 413.117792 -224.287588) (xy 413.117792 -224.782126)
			(xy 419.161976 -224.782126) (xy 419.161976 -224.287588) (xy 419.162485 -224.282328) (xy 419.169924 -224.274887)
			(xy 419.175184 -224.27438) (xy 419.175692 -224.27438) (xy 419.691566 -224.27438) (xy 419.699375 -224.274055)
			(xy 419.714247 -224.269277) (xy 419.720776 -224.264982) (xy 419.741865 -224.250633) (xy 419.787526 -224.227902)
			(xy 419.836132 -224.212443) (xy 419.886535 -224.20462) (xy 419.937541 -224.20462) (xy 419.987944 -224.212443)
			(xy 420.03655 -224.227902) (xy 420.082211 -224.250633) (xy 420.1033 -224.264982) (xy 420.109833 -224.26927)
			(xy 420.124702 -224.274055) (xy 420.13251 -224.27438) (xy 420.648638 -224.27438) (xy 420.653956 -224.274803)
			(xy 420.661527 -224.282277) (xy 420.6621 -224.287588) (xy 420.6621 -224.782126) (xy 420.662075 -224.78238)
			(xy 426.706284 -224.78238) (xy 426.706284 -224.781872) (xy 426.706284 -224.287588) (xy 426.706786 -224.282326)
			(xy 426.71423 -224.274884) (xy 426.719492 -224.27438) (xy 427.23562 -224.27438) (xy 427.243431 -224.274078)
			(xy 427.258303 -224.269284) (xy 427.26483 -224.264982) (xy 427.285919 -224.250633) (xy 427.33158 -224.227902)
			(xy 427.380186 -224.212443) (xy 427.430589 -224.20462) (xy 427.481595 -224.20462) (xy 427.531998 -224.212443)
			(xy 427.580604 -224.227902) (xy 427.626265 -224.250633) (xy 427.647354 -224.264982) (xy 427.653875 -224.269291)
			(xy 427.668753 -224.274063) (xy 427.676564 -224.27438) (xy 428.192692 -224.27438) (xy 428.197951 -224.274899)
			(xy 428.205393 -224.28233) (xy 428.2059 -224.287588) (xy 428.2059 -224.782126) (xy 434.250084 -224.782126)
			(xy 434.250084 -224.287588) (xy 434.250586 -224.282326) (xy 434.25803 -224.274884) (xy 434.263292 -224.27438)
			(xy 434.2638 -224.27438) (xy 434.779674 -224.27438) (xy 434.787483 -224.274059) (xy 434.802355 -224.269278)
			(xy 434.808884 -224.264982) (xy 434.829973 -224.250633) (xy 434.875634 -224.227902) (xy 434.92424 -224.212443)
			(xy 434.974643 -224.20462) (xy 435.025649 -224.20462) (xy 435.076052 -224.212443) (xy 435.124658 -224.227902)
			(xy 435.170319 -224.250633) (xy 435.191408 -224.264982) (xy 435.19794 -224.269273) (xy 435.21281 -224.274056)
			(xy 435.220618 -224.27438) (xy 435.736746 -224.27438) (xy 435.742053 -224.274864) (xy 435.74963 -224.282291)
			(xy 435.750208 -224.287588) (xy 435.750208 -224.782126) (xy 435.750183 -224.78238) (xy 441.794392 -224.78238)
			(xy 441.794392 -224.781872) (xy 441.794392 -224.287588) (xy 441.794887 -224.282324) (xy 441.802335 -224.274882)
			(xy 441.8076 -224.27438) (xy 442.323728 -224.27438) (xy 442.33154 -224.274082) (xy 442.346411 -224.269285)
			(xy 442.352938 -224.264982) (xy 442.374027 -224.250633) (xy 442.419688 -224.227902) (xy 442.468294 -224.212443)
			(xy 442.518697 -224.20462) (xy 442.569703 -224.20462) (xy 442.620106 -224.212443) (xy 442.668712 -224.227902)
			(xy 442.714373 -224.250633) (xy 442.735462 -224.264982) (xy 442.742004 -224.269255) (xy 442.756866 -224.27405)
			(xy 442.764672 -224.27438) (xy 443.2808 -224.27438) (xy 443.28606 -224.274894) (xy 443.293502 -224.282329)
			(xy 443.294008 -224.287588) (xy 443.294008 -224.782126) (xy 443.293984 -224.78238) (xy 449.338192 -224.78238)
			(xy 449.338192 -224.781872) (xy 449.338192 -224.287588) (xy 449.338687 -224.282324) (xy 449.346135 -224.274882)
			(xy 449.3514 -224.27438) (xy 449.867528 -224.27438) (xy 449.87534 -224.274082) (xy 449.890211 -224.269285)
			(xy 449.896738 -224.264982) (xy 449.917827 -224.250633) (xy 449.963488 -224.227902) (xy 450.012094 -224.212443)
			(xy 450.062497 -224.20462) (xy 450.113503 -224.20462) (xy 450.163906 -224.212443) (xy 450.212512 -224.227902)
			(xy 450.258173 -224.250633) (xy 450.279262 -224.264982) (xy 450.285804 -224.269255) (xy 450.300666 -224.27405)
			(xy 450.308472 -224.27438) (xy 450.8246 -224.27438) (xy 450.82986 -224.274894) (xy 450.837302 -224.282329)
			(xy 450.837808 -224.287588) (xy 450.837808 -224.782126) (xy 450.8373 -224.787422) (xy 450.829885 -224.794989)
			(xy 450.8246 -224.795588) (xy 450.308726 -224.795588) (xy 450.300915 -224.795898) (xy 450.286043 -224.800685)
			(xy 450.279516 -224.804986) (xy 450.25839 -224.819329) (xy 450.212667 -224.842056) (xy 450.163996 -224.857487)
			(xy 450.113531 -224.865257) (xy 450.088 -224.865692) (xy 450.06247 -224.86525) (xy 450.012007 -224.857475)
			(xy 449.963334 -224.842047) (xy 449.917606 -224.819333) (xy 449.896484 -224.804986) (xy 449.88995 -224.800698)
			(xy 449.875082 -224.795911) (xy 449.867274 -224.795588) (xy 449.3514 -224.795588) (xy 449.346063 -224.795271)
			(xy 449.338521 -224.787718) (xy 449.338192 -224.78238) (xy 443.293984 -224.78238) (xy 443.2935 -224.787422)
			(xy 443.286085 -224.794989) (xy 443.2808 -224.795588) (xy 442.764926 -224.795588) (xy 442.757115 -224.795898)
			(xy 442.742243 -224.800685) (xy 442.735716 -224.804986) (xy 442.71459 -224.819329) (xy 442.668867 -224.842056)
			(xy 442.620196 -224.857487) (xy 442.569731 -224.865257) (xy 442.5442 -224.865692) (xy 442.51867 -224.86525)
			(xy 442.468207 -224.857475) (xy 442.419534 -224.842047) (xy 442.373806 -224.819333) (xy 442.352684 -224.804986)
			(xy 442.34615 -224.800698) (xy 442.331282 -224.795911) (xy 442.323474 -224.795588) (xy 441.8076 -224.795588)
			(xy 441.802263 -224.795271) (xy 441.794721 -224.787718) (xy 441.794392 -224.78238) (xy 435.750183 -224.78238)
			(xy 435.749671 -224.787482) (xy 435.742101 -224.795063) (xy 435.736746 -224.795588) (xy 435.220872 -224.795588)
			(xy 435.213059 -224.795875) (xy 435.198187 -224.800678) (xy 435.191662 -224.804986) (xy 435.170551 -224.819352)
			(xy 435.124823 -224.842074) (xy 435.076147 -224.857499) (xy 435.025678 -224.865261) (xy 435.000146 -224.865692)
			(xy 434.974617 -224.865227) (xy 434.924154 -224.857459) (xy 434.875482 -224.842038) (xy 434.829753 -224.81933)
			(xy 434.80863 -224.804986) (xy 434.802086 -224.800716) (xy 434.787226 -224.795918) (xy 434.77942 -224.795588)
			(xy 434.263546 -224.795588) (xy 434.258123 -224.795193) (xy 434.250436 -224.787546) (xy 434.250084 -224.782126)
			(xy 428.2059 -224.782126) (xy 428.205399 -224.787424) (xy 428.197979 -224.794992) (xy 428.192692 -224.795588)
			(xy 427.676818 -224.795588) (xy 427.669007 -224.795895) (xy 427.654135 -224.800684) (xy 427.647608 -224.804986)
			(xy 427.626484 -224.819332) (xy 427.580761 -224.842058) (xy 427.532088 -224.857489) (xy 427.481623 -224.865258)
			(xy 427.456092 -224.865692) (xy 427.430562 -224.865255) (xy 427.380098 -224.857478) (xy 427.331426 -224.842049)
			(xy 427.285698 -224.819333) (xy 427.264576 -224.804986) (xy 427.258044 -224.800695) (xy 427.243175 -224.79591)
			(xy 427.235366 -224.795588) (xy 426.719492 -224.795588) (xy 426.714154 -224.795277) (xy 426.706612 -224.787719)
			(xy 426.706284 -224.78238) (xy 420.662075 -224.78238) (xy 420.661571 -224.787484) (xy 420.653995 -224.795066)
			(xy 420.648638 -224.795588) (xy 420.132764 -224.795588) (xy 420.124955 -224.795914) (xy 420.110083 -224.80069)
			(xy 420.103554 -224.804986) (xy 420.082445 -224.819355) (xy 420.036717 -224.842077) (xy 419.988039 -224.857501)
			(xy 419.93757 -224.865262) (xy 419.912038 -224.865692) (xy 419.886509 -224.865231) (xy 419.836046 -224.857462)
			(xy 419.787374 -224.84204) (xy 419.741645 -224.81933) (xy 419.720522 -224.804986) (xy 419.71398 -224.800713)
			(xy 419.699118 -224.795917) (xy 419.691312 -224.795588) (xy 419.175438 -224.795588) (xy 419.170014 -224.795198)
			(xy 419.162328 -224.787548) (xy 419.161976 -224.782126) (xy 413.117792 -224.782126) (xy 413.117298 -224.787426)
			(xy 413.109873 -224.794993) (xy 413.104584 -224.795588) (xy 411.631384 -224.795588) (xy 411.626045 -224.795282)
			(xy 411.618503 -224.78772) (xy 411.618176 -224.78238) (xy 304.018163 -224.78238) (xy 304.017669 -224.787487)
			(xy 304.010087 -224.795069) (xy 304.004726 -224.795588) (xy 302.531526 -224.795588) (xy 302.526171 -224.795035)
			(xy 302.518586 -224.787479) (xy 302.518064 -224.782126) (xy 296.47388 -224.782126) (xy 296.473396 -224.787429)
			(xy 296.465965 -224.794997) (xy 296.460672 -224.795588) (xy 295.944798 -224.795588) (xy 295.936986 -224.795886)
			(xy 295.922114 -224.800681) (xy 295.915588 -224.804986) (xy 295.89447 -224.819341) (xy 295.848744 -224.842065)
			(xy 295.80007 -224.857493) (xy 295.749603 -224.865259) (xy 295.724072 -224.865692) (xy 295.698541 -224.865265)
			(xy 295.648077 -224.857485) (xy 295.599405 -224.842053) (xy 295.553678 -224.819334) (xy 295.532556 -224.804986)
			(xy 295.526029 -224.800687) (xy 295.511156 -224.795907) (xy 295.503346 -224.795588) (xy 294.987472 -224.795588)
			(xy 294.982201 -224.795122) (xy 294.974759 -224.787653) (xy 294.974264 -224.78238) (xy 288.930056 -224.78238)
			(xy 288.929569 -224.787489) (xy 288.921981 -224.795072) (xy 288.916618 -224.795588) (xy 288.400744 -224.795588)
			(xy 288.392934 -224.795906) (xy 288.378062 -224.800687) (xy 288.371534 -224.804986) (xy 288.350431 -224.819364)
			(xy 288.3047 -224.842083) (xy 288.256021 -224.857505) (xy 288.205551 -224.865263) (xy 288.180018 -224.865692)
			(xy 288.154488 -224.865241) (xy 288.104025 -224.857469) (xy 288.055353 -224.842044) (xy 288.009625 -224.819331)
			(xy 287.988502 -224.804986) (xy 287.981964 -224.800705) (xy 287.967099 -224.795914) (xy 287.959292 -224.795588)
			(xy 287.443418 -224.795588) (xy 287.438062 -224.79504) (xy 287.430477 -224.78748) (xy 287.429956 -224.782126)
			(xy 281.385772 -224.782126) (xy 281.385295 -224.78743) (xy 281.377859 -224.794999) (xy 281.372564 -224.795588)
			(xy 280.85669 -224.795588) (xy 280.848878 -224.795883) (xy 280.834006 -224.80068) (xy 280.82748 -224.804986)
			(xy 280.806364 -224.819344) (xy 280.760638 -224.842068) (xy 280.711963 -224.857495) (xy 280.661495 -224.86526)
			(xy 280.635964 -224.865692) (xy 280.610433 -224.865269) (xy 280.559969 -224.857488) (xy 280.511297 -224.842055)
			(xy 280.46557 -224.819335) (xy 280.444448 -224.804986) (xy 280.437922 -224.800684) (xy 280.423048 -224.795906)
			(xy 280.415238 -224.795588) (xy 279.899364 -224.795588) (xy 279.894092 -224.795127) (xy 279.886651 -224.787654)
			(xy 279.886156 -224.78238) (xy 273.841949 -224.78238) (xy 273.841495 -224.78743) (xy 273.834059 -224.794999)
			(xy 273.828764 -224.795588) (xy 273.31289 -224.795588) (xy 273.305078 -224.795883) (xy 273.290206 -224.80068)
			(xy 273.28368 -224.804986) (xy 273.262564 -224.819344) (xy 273.216838 -224.842068) (xy 273.168163 -224.857495)
			(xy 273.117695 -224.86526) (xy 273.092164 -224.865692) (xy 273.066633 -224.865269) (xy 273.016169 -224.857488)
			(xy 272.967497 -224.842055) (xy 272.92177 -224.819335) (xy 272.900648 -224.804986) (xy 272.894122 -224.800684)
			(xy 272.879248 -224.795906) (xy 272.871438 -224.795588) (xy 272.355564 -224.795588) (xy 272.350292 -224.795127)
			(xy 272.342851 -224.787654) (xy 272.342356 -224.78238) (xy 266.298148 -224.78238) (xy 266.297668 -224.787491)
			(xy 266.290075 -224.795074) (xy 266.28471 -224.795588) (xy 265.768836 -224.795588) (xy 265.761026 -224.795902)
			(xy 265.746154 -224.800686) (xy 265.739626 -224.804986) (xy 265.718497 -224.819324) (xy 265.672776 -224.842052)
			(xy 265.624105 -224.857485) (xy 265.57364 -224.865256) (xy 265.54811 -224.865692) (xy 265.52258 -224.865245)
			(xy 265.472117 -224.857472) (xy 265.423445 -224.842045) (xy 265.377717 -224.819332) (xy 265.356594 -224.804986)
			(xy 265.350058 -224.800702) (xy 265.335192 -224.795913) (xy 265.327384 -224.795588) (xy 264.81151 -224.795588)
			(xy 264.806154 -224.795045) (xy 264.798569 -224.787481) (xy 264.798048 -224.782126) (xy 202.89774 -224.782126)
			(xy 202.89774 -224.78238) (xy 202.897195 -224.787633) (xy 202.889783 -224.795075) (xy 202.884532 -224.795588)
			(xy 202.368658 -224.795588) (xy 202.360782 -224.795859) (xy 202.345778 -224.800653) (xy 202.339194 -224.804986)
			(xy 202.318112 -224.81937) (xy 202.272468 -224.842199) (xy 202.223864 -224.857758) (xy 202.173448 -224.865681)
			(xy 202.147932 -224.8662) (xy 202.122412 -224.865711) (xy 202.071985 -224.857816) (xy 202.023373 -224.842256)
			(xy 201.977735 -224.819401) (xy 201.95667 -224.804986) (xy 201.950088 -224.800655) (xy 201.935081 -224.795879)
			(xy 201.927206 -224.795588) (xy 201.411332 -224.795588) (xy 201.405999 -224.79525) (xy 201.398455 -224.787712)
			(xy 201.398124 -224.78238) (xy 195.35394 -224.78238) (xy 195.353395 -224.787633) (xy 195.345983 -224.795075)
			(xy 195.340732 -224.795588) (xy 194.824858 -224.795588) (xy 194.816982 -224.795859) (xy 194.801978 -224.800653)
			(xy 194.795394 -224.804986) (xy 194.774312 -224.81937) (xy 194.728668 -224.842199) (xy 194.680064 -224.857758)
			(xy 194.629648 -224.865681) (xy 194.604132 -224.8662) (xy 194.578612 -224.865711) (xy 194.528185 -224.857816)
			(xy 194.479573 -224.842256) (xy 194.433935 -224.819401) (xy 194.41287 -224.804986) (xy 194.406288 -224.800655)
			(xy 194.391281 -224.795879) (xy 194.383406 -224.795588) (xy 193.867532 -224.795588) (xy 193.862199 -224.79525)
			(xy 193.854655 -224.787712) (xy 193.854324 -224.78238) (xy 187.81014 -224.78238) (xy 187.809595 -224.787633)
			(xy 187.802183 -224.795075) (xy 187.796932 -224.795588) (xy 187.796424 -224.795588) (xy 187.280804 -224.795588)
			(xy 187.27293 -224.795878) (xy 187.257925 -224.800659) (xy 187.25134 -224.804986) (xy 187.230273 -224.819393)
			(xy 187.184624 -224.842217) (xy 187.136015 -224.85777) (xy 187.085595 -224.865685) (xy 187.060078 -224.8662)
			(xy 187.034559 -224.865688) (xy 186.984133 -224.8578) (xy 186.935521 -224.842247) (xy 186.889882 -224.819398)
			(xy 186.868816 -224.804986) (xy 186.862223 -224.800673) (xy 186.847224 -224.795885) (xy 186.839352 -224.795588)
			(xy 186.323478 -224.795588) (xy 186.318178 -224.795095) (xy 186.310609 -224.78767) (xy 186.310016 -224.78238)
			(xy 180.265832 -224.78238) (xy 180.265295 -224.787635) (xy 180.257877 -224.795077) (xy 180.252624 -224.795588)
			(xy 179.73675 -224.795588) (xy 179.728874 -224.795855) (xy 179.713869 -224.800652) (xy 179.707286 -224.804986)
			(xy 179.686206 -224.819373) (xy 179.640562 -224.842201) (xy 179.591956 -224.85776) (xy 179.54154 -224.865681)
			(xy 179.516024 -224.8662) (xy 179.490504 -224.865715) (xy 179.440076 -224.857819) (xy 179.391465 -224.842258)
			(xy 179.345827 -224.819402) (xy 179.324762 -224.804986) (xy 179.318182 -224.800652) (xy 179.303173 -224.795877)
			(xy 179.295298 -224.795588) (xy 178.779424 -224.795588) (xy 178.77409 -224.795255) (xy 178.766547 -224.787714)
			(xy 178.766216 -224.78238) (xy 172.722032 -224.78238) (xy 172.721495 -224.787635) (xy 172.714077 -224.795077)
			(xy 172.708824 -224.795588) (xy 172.708316 -224.795588) (xy 172.192696 -224.795588) (xy 172.184821 -224.795875)
			(xy 172.169817 -224.800658) (xy 172.163232 -224.804986) (xy 172.142167 -224.819396) (xy 172.096517 -224.842219)
			(xy 172.047907 -224.857772) (xy 171.997488 -224.865685) (xy 171.97197 -224.8662) (xy 171.946451 -224.865692)
			(xy 171.896024 -224.857803) (xy 171.847413 -224.842249) (xy 171.801774 -224.819399) (xy 171.780708 -224.804986)
			(xy 171.774117 -224.80067) (xy 171.759117 -224.795884) (xy 171.751244 -224.795588) (xy 171.23537 -224.795588)
			(xy 171.230069 -224.7951) (xy 171.222501 -224.787671) (xy 171.221908 -224.78238) (xy 165.177724 -224.78238)
			(xy 165.177362 -224.787706) (xy 165.169841 -224.795247) (xy 165.164516 -224.795588) (xy 163.691316 -224.795588)
			(xy 163.685981 -224.79526) (xy 163.678438 -224.787715) (xy 163.678108 -224.78238) (xy 56.07812 -224.78238)
			(xy 56.077761 -224.787707) (xy 56.070238 -224.795248) (xy 56.064912 -224.795588) (xy 54.591458 -224.795588)
			(xy 54.586155 -224.795108) (xy 54.578588 -224.787673) (xy 54.577996 -224.78238) (xy 48.533812 -224.78238)
			(xy 48.53346 -224.787709) (xy 48.525932 -224.795251) (xy 48.520604 -224.795588) (xy 48.00473 -224.795588)
			(xy 47.996853 -224.795847) (xy 47.981849 -224.80065) (xy 47.975266 -224.804986) (xy 47.954191 -224.819382)
			(xy 47.908545 -224.842208) (xy 47.859938 -224.857764) (xy 47.809521 -224.865683) (xy 47.784004 -224.8662)
			(xy 47.758483 -224.865725) (xy 47.708056 -224.857826) (xy 47.659444 -224.842262) (xy 47.613806 -224.819403)
			(xy 47.592742 -224.804986) (xy 47.586166 -224.800644) (xy 47.571154 -224.795874) (xy 47.563278 -224.795588)
			(xy 47.047404 -224.795588) (xy 47.042067 -224.795268) (xy 47.034525 -224.787717) (xy 47.034196 -224.78238)
			(xy 40.990012 -224.78238) (xy 40.98966 -224.787709) (xy 40.982132 -224.795251) (xy 40.976804 -224.795588)
			(xy 40.976296 -224.795588) (xy 40.460676 -224.795588) (xy 40.452801 -224.795867) (xy 40.437796 -224.800656)
			(xy 40.431212 -224.804986) (xy 40.410152 -224.819405) (xy 40.364501 -224.842226) (xy 40.315889 -224.857776)
			(xy 40.265468 -224.865687) (xy 40.23995 -224.8662) (xy 40.21443 -224.865702) (xy 40.164004 -224.85781)
			(xy 40.115392 -224.842253) (xy 40.069753 -224.8194) (xy 40.048688 -224.804986) (xy 40.042102 -224.800662)
			(xy 40.027098 -224.795881) (xy 40.019224 -224.795588) (xy 39.50335 -224.795588) (xy 39.498058 -224.795047)
			(xy 39.490486 -224.787658) (xy 39.489888 -224.78238) (xy 33.445704 -224.78238) (xy 33.44536 -224.787711)
			(xy 33.437826 -224.795253) (xy 33.432496 -224.795588) (xy 32.916622 -224.795588) (xy 32.908748 -224.795886)
			(xy 32.893744 -224.800662) (xy 32.887158 -224.804986) (xy 32.866086 -224.819385) (xy 32.820439 -224.842211)
			(xy 32.771831 -224.857766) (xy 32.721413 -224.865683) (xy 32.695896 -224.8662) (xy 32.670375 -224.865729)
			(xy 32.619947 -224.857829) (xy 32.571336 -224.842264) (xy 32.525698 -224.819404) (xy 32.504634 -224.804986)
			(xy 32.498037 -224.80068) (xy 32.483041 -224.795888) (xy 32.47517 -224.795588) (xy 31.959296 -224.795588)
			(xy 31.953958 -224.795274) (xy 31.946417 -224.787718) (xy 31.946088 -224.78238) (xy 25.901904 -224.78238)
			(xy 25.90156 -224.787711) (xy 25.894026 -224.795253) (xy 25.888696 -224.795588) (xy 25.372822 -224.795588)
			(xy 25.364948 -224.795886) (xy 25.349944 -224.800662) (xy 25.343358 -224.804986) (xy 25.322286 -224.819385)
			(xy 25.276639 -224.842211) (xy 25.228031 -224.857766) (xy 25.177613 -224.865683) (xy 25.152096 -224.8662)
			(xy 25.126575 -224.865729) (xy 25.076147 -224.857829) (xy 25.027536 -224.842264) (xy 24.981898 -224.819404)
			(xy 24.960834 -224.804986) (xy 24.954237 -224.80068) (xy 24.939241 -224.795888) (xy 24.93137 -224.795588)
			(xy 24.415496 -224.795588) (xy 24.410158 -224.795274) (xy 24.402617 -224.787718) (xy 24.402288 -224.78238)
			(xy 18.358104 -224.78238) (xy 18.35776 -224.787711) (xy 18.350226 -224.795253) (xy 18.344896 -224.795588)
			(xy 18.344388 -224.795588) (xy 17.828768 -224.795588) (xy 17.820892 -224.795863) (xy 17.805888 -224.800655)
			(xy 17.799304 -224.804986) (xy 17.778219 -224.819365) (xy 17.732576 -224.842195) (xy 17.683973 -224.857756)
			(xy 17.633558 -224.86568) (xy 17.608042 -224.8662) (xy 17.582522 -224.865706) (xy 17.532095 -224.857813)
			(xy 17.483484 -224.842254) (xy 17.437845 -224.819401) (xy 17.41678 -224.804986) (xy 17.410196 -224.800659)
			(xy 17.39519 -224.79588) (xy 17.387316 -224.795588) (xy 16.871442 -224.795588) (xy 16.866149 -224.795052)
			(xy 16.858578 -224.78766) (xy 16.85798 -224.78238) (xy 2.509012 -224.78238) (xy 2.509012 -225.632518)
			(xy 20.958048 -225.632518) (xy 20.958048 -225.13798) (xy 20.958577 -225.132725) (xy 20.966002 -225.125287)
			(xy 20.971256 -225.124772) (xy 20.971764 -225.124772) (xy 21.487638 -225.124772) (xy 21.495446 -225.124436)
			(xy 21.510318 -225.119666) (xy 21.516848 -225.115374) (xy 21.537937 -225.101025) (xy 21.583598 -225.078294)
			(xy 21.632204 -225.062835) (xy 21.682607 -225.055012) (xy 21.733613 -225.055012) (xy 21.784016 -225.062835)
			(xy 21.832622 -225.078294) (xy 21.878283 -225.101025) (xy 21.899372 -225.115374) (xy 21.905912 -225.119651)
			(xy 21.920775 -225.124443) (xy 21.928582 -225.124772) (xy 22.44471 -225.124772) (xy 22.450023 -225.12522)
			(xy 22.457595 -225.132675) (xy 22.458172 -225.13798) (xy 22.458172 -225.632518) (xy 22.458148 -225.632772)
			(xy 28.502356 -225.632772) (xy 28.502356 -225.632264) (xy 28.502356 -225.13798) (xy 28.502878 -225.132724)
			(xy 28.510308 -225.125284) (xy 28.515564 -225.124772) (xy 29.031692 -225.124772) (xy 29.039502 -225.12446)
			(xy 29.054374 -225.119673) (xy 29.060902 -225.115374) (xy 29.081991 -225.101025) (xy 29.127652 -225.078294)
			(xy 29.176258 -225.062835) (xy 29.226661 -225.055012) (xy 29.277667 -225.055012) (xy 29.32807 -225.062835)
			(xy 29.376676 -225.078294) (xy 29.422337 -225.101025) (xy 29.443426 -225.115374) (xy 29.449954 -225.119671)
			(xy 29.464827 -225.124451) (xy 29.472636 -225.124772) (xy 29.988764 -225.124772) (xy 29.994087 -225.125149)
			(xy 30.001629 -225.132659) (xy 30.001972 -225.13798) (xy 30.001972 -225.632518) (xy 30.001949 -225.632772)
			(xy 36.046156 -225.632772) (xy 36.046156 -225.632264) (xy 36.046156 -225.13798) (xy 36.046678 -225.132724)
			(xy 36.054108 -225.125284) (xy 36.059364 -225.124772) (xy 36.575492 -225.124772) (xy 36.583302 -225.12446)
			(xy 36.598174 -225.119673) (xy 36.604702 -225.115374) (xy 36.625791 -225.101025) (xy 36.671452 -225.078294)
			(xy 36.720058 -225.062835) (xy 36.770461 -225.055012) (xy 36.821467 -225.055012) (xy 36.87187 -225.062835)
			(xy 36.920476 -225.078294) (xy 36.966137 -225.101025) (xy 36.987226 -225.115374) (xy 36.993754 -225.119671)
			(xy 37.008627 -225.124451) (xy 37.016436 -225.124772) (xy 37.532564 -225.124772) (xy 37.537887 -225.125149)
			(xy 37.545429 -225.132659) (xy 37.545772 -225.13798) (xy 37.545772 -225.632518) (xy 43.589956 -225.632518)
			(xy 43.589956 -225.13798) (xy 43.590478 -225.132724) (xy 43.597908 -225.125284) (xy 43.603164 -225.124772)
			(xy 43.603672 -225.124772) (xy 44.119546 -225.124772) (xy 44.127354 -225.12444) (xy 44.142226 -225.119667)
			(xy 44.148756 -225.115374) (xy 44.169845 -225.101025) (xy 44.215506 -225.078294) (xy 44.264112 -225.062835)
			(xy 44.314515 -225.055012) (xy 44.365521 -225.055012) (xy 44.415924 -225.062835) (xy 44.46453 -225.078294)
			(xy 44.510191 -225.101025) (xy 44.53128 -225.115374) (xy 44.537818 -225.119654) (xy 44.552683 -225.124444)
			(xy 44.56049 -225.124772) (xy 45.076618 -225.124772) (xy 45.081932 -225.125215) (xy 45.089504 -225.132674)
			(xy 45.09008 -225.13798) (xy 45.09008 -225.632518) (xy 45.090056 -225.632772) (xy 51.134264 -225.632772)
			(xy 51.134264 -225.632264) (xy 51.134264 -225.13798) (xy 51.134779 -225.132722) (xy 51.142214 -225.125282)
			(xy 51.147472 -225.124772) (xy 51.6636 -225.124772) (xy 51.671411 -225.124463) (xy 51.686282 -225.119674)
			(xy 51.69281 -225.115374) (xy 51.713899 -225.101025) (xy 51.75956 -225.078294) (xy 51.808166 -225.062835)
			(xy 51.858569 -225.055012) (xy 51.909575 -225.055012) (xy 51.959978 -225.062835) (xy 52.008584 -225.078294)
			(xy 52.054245 -225.101025) (xy 52.075334 -225.115374) (xy 52.08186 -225.119674) (xy 52.096734 -225.124452)
			(xy 52.104544 -225.124772) (xy 52.620672 -225.124772) (xy 52.625996 -225.125143) (xy 52.633537 -225.132658)
			(xy 52.63388 -225.13798) (xy 52.63388 -225.632518) (xy 58.678064 -225.632518) (xy 58.678064 -225.13798)
			(xy 58.678579 -225.132722) (xy 58.686014 -225.125282) (xy 58.691272 -225.124772) (xy 58.69178 -225.124772)
			(xy 60.164726 -225.124772) (xy 60.170041 -225.12521) (xy 60.177612 -225.132673) (xy 60.178188 -225.13798)
			(xy 60.178188 -225.632518) (xy 60.178163 -225.632772) (xy 167.778176 -225.632772) (xy 167.778176 -225.13798)
			(xy 167.77868 -225.132719) (xy 167.786123 -225.125278) (xy 167.791384 -225.124772) (xy 169.264584 -225.124772)
			(xy 169.26984 -225.125303) (xy 169.277282 -225.132725) (xy 169.277792 -225.13798) (xy 169.277792 -225.632518)
			(xy 175.321976 -225.632518) (xy 175.321976 -225.13798) (xy 175.32248 -225.132719) (xy 175.329923 -225.125278)
			(xy 175.335184 -225.124772) (xy 175.335692 -225.124772) (xy 175.851566 -225.124772) (xy 175.859375 -225.124448)
			(xy 175.874247 -225.11967) (xy 175.880776 -225.115374) (xy 175.901865 -225.101025) (xy 175.947526 -225.078294)
			(xy 175.996132 -225.062835) (xy 176.046535 -225.055012) (xy 176.097541 -225.055012) (xy 176.147944 -225.062835)
			(xy 176.19655 -225.078294) (xy 176.242211 -225.101025) (xy 176.2633 -225.115374) (xy 176.269834 -225.119661)
			(xy 176.284702 -225.124447) (xy 176.29251 -225.124772) (xy 176.808638 -225.124772) (xy 176.813954 -225.125202)
			(xy 176.821525 -225.132671) (xy 176.8221 -225.13798) (xy 176.8221 -225.632518) (xy 176.822075 -225.632772)
			(xy 182.866284 -225.632772) (xy 182.866284 -225.632264) (xy 182.866284 -225.13798) (xy 182.866781 -225.132717)
			(xy 182.874228 -225.125276) (xy 182.879492 -225.124772) (xy 183.39562 -225.124772) (xy 183.403431 -225.124472)
			(xy 183.418303 -225.119677) (xy 183.42483 -225.115374) (xy 183.445919 -225.101025) (xy 183.49158 -225.078294)
			(xy 183.540186 -225.062835) (xy 183.590589 -225.055012) (xy 183.641595 -225.055012) (xy 183.691998 -225.062835)
			(xy 183.740604 -225.078294) (xy 183.786265 -225.101025) (xy 183.807354 -225.115374) (xy 183.813876 -225.119682)
			(xy 183.828753 -225.124455) (xy 183.836564 -225.124772) (xy 184.352692 -225.124772) (xy 184.357949 -225.125298)
			(xy 184.365391 -225.132724) (xy 184.3659 -225.13798) (xy 184.3659 -225.632518) (xy 190.410084 -225.632518)
			(xy 190.410084 -225.13798) (xy 190.410581 -225.132717) (xy 190.418028 -225.125276) (xy 190.423292 -225.124772)
			(xy 190.4238 -225.124772) (xy 190.939674 -225.124772) (xy 190.947484 -225.124452) (xy 190.962355 -225.119671)
			(xy 190.968884 -225.115374) (xy 190.989973 -225.101025) (xy 191.035634 -225.078294) (xy 191.08424 -225.062835)
			(xy 191.134643 -225.055012) (xy 191.185649 -225.055012) (xy 191.236052 -225.062835) (xy 191.284658 -225.078294)
			(xy 191.330319 -225.101025) (xy 191.351408 -225.115374) (xy 191.35794 -225.119664) (xy 191.37281 -225.124448)
			(xy 191.380618 -225.124772) (xy 191.896746 -225.124772) (xy 191.902051 -225.125263) (xy 191.909627 -225.132686)
			(xy 191.910208 -225.13798) (xy 191.910208 -225.632518) (xy 191.910182 -225.632772) (xy 197.954392 -225.632772)
			(xy 197.954392 -225.632264) (xy 197.954392 -225.13798) (xy 197.954881 -225.132715) (xy 197.962334 -225.125273)
			(xy 197.9676 -225.124772) (xy 198.483728 -225.124772) (xy 198.49154 -225.124475) (xy 198.506411 -225.119678)
			(xy 198.512938 -225.115374) (xy 198.534027 -225.101025) (xy 198.579688 -225.078294) (xy 198.628294 -225.062835)
			(xy 198.678697 -225.055012) (xy 198.729703 -225.055012) (xy 198.780106 -225.062835) (xy 198.828712 -225.078294)
			(xy 198.874373 -225.101025) (xy 198.895462 -225.115374) (xy 198.902004 -225.119647) (xy 198.916866 -225.124441)
			(xy 198.924672 -225.124772) (xy 199.4408 -225.124772) (xy 199.446058 -225.125293) (xy 199.453499 -225.132723)
			(xy 199.454008 -225.13798) (xy 199.454008 -225.632518) (xy 199.453983 -225.632772) (xy 205.498192 -225.632772)
			(xy 205.498192 -225.632264) (xy 205.498192 -225.13798) (xy 205.498681 -225.132715) (xy 205.506134 -225.125273)
			(xy 205.5114 -225.124772) (xy 206.027528 -225.124772) (xy 206.03534 -225.124475) (xy 206.050211 -225.119678)
			(xy 206.056738 -225.115374) (xy 206.077827 -225.101025) (xy 206.123488 -225.078294) (xy 206.172094 -225.062835)
			(xy 206.222497 -225.055012) (xy 206.273503 -225.055012) (xy 206.323906 -225.062835) (xy 206.372512 -225.078294)
			(xy 206.418173 -225.101025) (xy 206.439262 -225.115374) (xy 206.445804 -225.119647) (xy 206.460666 -225.124441)
			(xy 206.468472 -225.124772) (xy 206.9846 -225.124772) (xy 206.989858 -225.125293) (xy 206.997299 -225.132723)
			(xy 206.997808 -225.13798) (xy 206.997808 -225.632264) (xy 268.898116 -225.632264) (xy 268.898116 -225.137726)
			(xy 268.898494 -225.1323) (xy 268.906153 -225.124614) (xy 268.911578 -225.124264) (xy 269.427706 -225.124264)
			(xy 269.435517 -225.123959) (xy 269.450389 -225.119168) (xy 269.456916 -225.114866) (xy 269.478005 -225.100517)
			(xy 269.523666 -225.077786) (xy 269.572272 -225.062327) (xy 269.622675 -225.054504) (xy 269.673681 -225.054504)
			(xy 269.724084 -225.062327) (xy 269.77269 -225.077786) (xy 269.818351 -225.100517) (xy 269.83944 -225.114866)
			(xy 269.845965 -225.119168) (xy 269.86084 -225.123945) (xy 269.86865 -225.124264) (xy 270.384778 -225.124264)
			(xy 270.390216 -225.124597) (xy 270.397905 -225.132288) (xy 270.39824 -225.137726) (xy 270.39824 -225.632264)
			(xy 276.442424 -225.632264) (xy 276.442424 -225.137726) (xy 276.442939 -225.132429) (xy 276.450346 -225.124857)
			(xy 276.455632 -225.124264) (xy 276.97176 -225.124264) (xy 276.979569 -225.123939) (xy 276.994441 -225.119161)
			(xy 277.00097 -225.114866) (xy 277.022059 -225.100517) (xy 277.06772 -225.077786) (xy 277.116326 -225.062327)
			(xy 277.166729 -225.054504) (xy 277.217735 -225.054504) (xy 277.268138 -225.062327) (xy 277.316744 -225.077786)
			(xy 277.362405 -225.100517) (xy 277.383494 -225.114866) (xy 277.39003 -225.11915) (xy 277.404896 -225.123938)
			(xy 277.412704 -225.124264) (xy 277.928832 -225.124264) (xy 277.934092 -225.124771) (xy 277.941531 -225.132212)
			(xy 277.94204 -225.137472) (xy 277.94204 -225.13798) (xy 277.94204 -225.632264) (xy 283.986224 -225.632264)
			(xy 283.986224 -225.137726) (xy 283.986739 -225.132429) (xy 283.994146 -225.124857) (xy 283.999432 -225.124264)
			(xy 284.51556 -225.124264) (xy 284.523369 -225.123939) (xy 284.538241 -225.119161) (xy 284.54477 -225.114866)
			(xy 284.565859 -225.100517) (xy 284.61152 -225.077786) (xy 284.660126 -225.062327) (xy 284.710529 -225.054504)
			(xy 284.761535 -225.054504) (xy 284.811938 -225.062327) (xy 284.860544 -225.077786) (xy 284.906205 -225.100517)
			(xy 284.927294 -225.114866) (xy 284.93383 -225.11915) (xy 284.948696 -225.123938) (xy 284.956504 -225.124264)
			(xy 285.472632 -225.124264) (xy 285.477892 -225.124771) (xy 285.485331 -225.132212) (xy 285.48584 -225.137472)
			(xy 285.48584 -225.13798) (xy 285.48584 -225.632264) (xy 291.530024 -225.632264) (xy 291.530024 -225.137726)
			(xy 291.530395 -225.132298) (xy 291.538059 -225.124611) (xy 291.543486 -225.124264) (xy 292.059614 -225.124264)
			(xy 292.067425 -225.123962) (xy 292.082297 -225.119169) (xy 292.088824 -225.114866) (xy 292.109913 -225.100517)
			(xy 292.155574 -225.077786) (xy 292.20418 -225.062327) (xy 292.254583 -225.054504) (xy 292.305589 -225.054504)
			(xy 292.355992 -225.062327) (xy 292.404598 -225.077786) (xy 292.450259 -225.100517) (xy 292.471348 -225.114866)
			(xy 292.477872 -225.119171) (xy 292.492748 -225.123946) (xy 292.500558 -225.124264) (xy 293.016686 -225.124264)
			(xy 293.022125 -225.124591) (xy 293.029814 -225.132286) (xy 293.030148 -225.137726) (xy 293.030148 -225.632264)
			(xy 299.074332 -225.632264) (xy 299.074332 -225.137726) (xy 299.07484 -225.132427) (xy 299.082252 -225.124855)
			(xy 299.08754 -225.124264) (xy 299.603668 -225.124264) (xy 299.611477 -225.123943) (xy 299.626349 -225.119162)
			(xy 299.632878 -225.114866) (xy 299.653967 -225.100517) (xy 299.699628 -225.077786) (xy 299.748234 -225.062327)
			(xy 299.798637 -225.054504) (xy 299.849643 -225.054504) (xy 299.900046 -225.062327) (xy 299.948652 -225.077786)
			(xy 299.994313 -225.100517) (xy 300.015402 -225.114866) (xy 300.021936 -225.119153) (xy 300.036804 -225.123939)
			(xy 300.044612 -225.124264) (xy 300.56074 -225.124264) (xy 300.566001 -225.124765) (xy 300.57344 -225.132211)
			(xy 300.573948 -225.137472) (xy 300.573948 -225.13798) (xy 300.573948 -225.632264) (xy 306.618132 -225.632264)
			(xy 306.618132 -225.137726) (xy 306.618496 -225.132296) (xy 306.626165 -225.124609) (xy 306.631594 -225.124264)
			(xy 308.104794 -225.124264) (xy 308.110234 -225.124586) (xy 308.117922 -225.132285) (xy 308.118256 -225.137726)
			(xy 308.118256 -225.632264) (xy 415.718244 -225.632264) (xy 415.718244 -225.137726) (xy 415.718741 -225.132424)
			(xy 415.726161 -225.124851) (xy 415.731452 -225.124264) (xy 417.204652 -225.124264) (xy 417.209971 -225.124657)
			(xy 417.217513 -225.132155) (xy 417.21786 -225.137472) (xy 417.21786 -225.632264) (xy 423.262044 -225.632264)
			(xy 423.262044 -225.137726) (xy 423.262397 -225.132293) (xy 423.270074 -225.124605) (xy 423.275506 -225.124264)
			(xy 423.791634 -225.124264) (xy 423.799442 -225.123928) (xy 423.814314 -225.119158) (xy 423.820844 -225.114866)
			(xy 423.841933 -225.100517) (xy 423.887594 -225.077786) (xy 423.9362 -225.062327) (xy 423.986603 -225.054504)
			(xy 424.037609 -225.054504) (xy 424.088012 -225.062327) (xy 424.136618 -225.077786) (xy 424.182279 -225.100517)
			(xy 424.203368 -225.114866) (xy 424.209909 -225.11914) (xy 424.224772 -225.123934) (xy 424.232578 -225.124264)
			(xy 424.748706 -225.124264) (xy 424.754148 -225.124578) (xy 424.761835 -225.132283) (xy 424.762168 -225.137726)
			(xy 424.762168 -225.632264) (xy 430.806352 -225.632264) (xy 430.806352 -225.137726) (xy 430.806842 -225.132422)
			(xy 430.814267 -225.124849) (xy 430.81956 -225.124264) (xy 431.335688 -225.124264) (xy 431.343498 -225.123951)
			(xy 431.35837 -225.119165) (xy 431.364898 -225.114866) (xy 431.385987 -225.100517) (xy 431.431648 -225.077786)
			(xy 431.480254 -225.062327) (xy 431.530657 -225.054504) (xy 431.581663 -225.054504) (xy 431.632066 -225.062327)
			(xy 431.680672 -225.077786) (xy 431.726333 -225.100517) (xy 431.747422 -225.114866) (xy 431.753951 -225.119161)
			(xy 431.768823 -225.123942) (xy 431.776632 -225.124264) (xy 432.29276 -225.124264) (xy 432.29808 -225.124651)
			(xy 432.305622 -225.132154) (xy 432.305968 -225.137472) (xy 432.305968 -225.13798) (xy 432.305968 -225.632264)
			(xy 438.350152 -225.632264) (xy 438.350152 -225.137726) (xy 438.350498 -225.132291) (xy 438.35818 -225.124603)
			(xy 438.363614 -225.124264) (xy 438.879742 -225.124264) (xy 438.88755 -225.123932) (xy 438.902422 -225.119159)
			(xy 438.908952 -225.114866) (xy 438.930041 -225.100517) (xy 438.975702 -225.077786) (xy 439.024308 -225.062327)
			(xy 439.074711 -225.054504) (xy 439.125717 -225.054504) (xy 439.17612 -225.062327) (xy 439.224726 -225.077786)
			(xy 439.270387 -225.100517) (xy 439.291476 -225.114866) (xy 439.298016 -225.119143) (xy 439.312879 -225.123935)
			(xy 439.320686 -225.124264) (xy 439.836814 -225.124264) (xy 439.842257 -225.124573) (xy 439.849944 -225.132282)
			(xy 439.850276 -225.137726) (xy 439.850276 -225.632264) (xy 445.89446 -225.632264) (xy 445.89446 -225.137726)
			(xy 445.894943 -225.13242) (xy 445.902373 -225.124847) (xy 445.907668 -225.124264) (xy 446.423796 -225.124264)
			(xy 446.431607 -225.123955) (xy 446.446478 -225.119166) (xy 446.453006 -225.114866) (xy 446.474095 -225.100517)
			(xy 446.519756 -225.077786) (xy 446.568362 -225.062327) (xy 446.618765 -225.054504) (xy 446.669771 -225.054504)
			(xy 446.720174 -225.062327) (xy 446.76878 -225.077786) (xy 446.814441 -225.100517) (xy 446.83553 -225.114866)
			(xy 446.842058 -225.119164) (xy 446.856931 -225.123943) (xy 446.86474 -225.124264) (xy 447.380868 -225.124264)
			(xy 447.386189 -225.124646) (xy 447.39373 -225.132152) (xy 447.394076 -225.137472) (xy 447.394076 -225.13798)
			(xy 447.394076 -225.632264) (xy 453.43826 -225.632264) (xy 453.43826 -225.137726) (xy 453.438743 -225.13242)
			(xy 453.446173 -225.124847) (xy 453.451468 -225.124264) (xy 453.967596 -225.124264) (xy 453.975407 -225.123955)
			(xy 453.990278 -225.119166) (xy 453.996806 -225.114866) (xy 454.017895 -225.100517) (xy 454.063556 -225.077786)
			(xy 454.112162 -225.062327) (xy 454.162565 -225.054504) (xy 454.213571 -225.054504) (xy 454.263974 -225.062327)
			(xy 454.31258 -225.077786) (xy 454.358241 -225.100517) (xy 454.37933 -225.114866) (xy 454.385858 -225.119164)
			(xy 454.400731 -225.123943) (xy 454.40854 -225.124264) (xy 454.924668 -225.124264) (xy 454.929989 -225.124646)
			(xy 454.93753 -225.132152) (xy 454.937876 -225.137472) (xy 454.937876 -225.13798) (xy 454.937876 -225.632264)
			(xy 454.937546 -225.637599) (xy 454.930003 -225.645144) (xy 454.924668 -225.645472) (xy 454.408794 -225.645472)
			(xy 454.40092 -225.645761) (xy 454.385915 -225.650543) (xy 454.37933 -225.65487) (xy 454.358264 -225.669279)
			(xy 454.312615 -225.692103) (xy 454.264005 -225.707656) (xy 454.213586 -225.715569) (xy 454.188068 -225.716084)
			(xy 454.162548 -225.71558) (xy 454.112122 -225.70769) (xy 454.06351 -225.692135) (xy 454.017871 -225.669284)
			(xy 453.996806 -225.65487) (xy 453.990211 -225.650561) (xy 453.975214 -225.645769) (xy 453.967342 -225.645472)
			(xy 453.451468 -225.645472) (xy 453.446123 -225.645191) (xy 453.438582 -225.637611) (xy 453.43826 -225.632264)
			(xy 447.394076 -225.632264) (xy 447.393746 -225.637599) (xy 447.386203 -225.645144) (xy 447.380868 -225.645472)
			(xy 446.864994 -225.645472) (xy 446.85712 -225.645761) (xy 446.842115 -225.650543) (xy 446.83553 -225.65487)
			(xy 446.814464 -225.669279) (xy 446.768815 -225.692103) (xy 446.720205 -225.707656) (xy 446.669786 -225.715569)
			(xy 446.644268 -225.716084) (xy 446.618748 -225.71558) (xy 446.568322 -225.70769) (xy 446.51971 -225.692135)
			(xy 446.474071 -225.669284) (xy 446.453006 -225.65487) (xy 446.446411 -225.650561) (xy 446.431414 -225.645769)
			(xy 446.423542 -225.645472) (xy 445.907668 -225.645472) (xy 445.902323 -225.645191) (xy 445.894782 -225.637611)
			(xy 445.89446 -225.632264) (xy 439.850276 -225.632264) (xy 439.849946 -225.637599) (xy 439.842403 -225.645144)
			(xy 439.837068 -225.645472) (xy 439.83656 -225.645472) (xy 439.32094 -225.645472) (xy 439.313064 -225.645738)
			(xy 439.298059 -225.650536) (xy 439.291476 -225.65487) (xy 439.270397 -225.66926) (xy 439.224753 -225.692088)
			(xy 439.176147 -225.707646) (xy 439.125731 -225.715566) (xy 439.100214 -225.716084) (xy 439.074693 -225.715607)
			(xy 439.024266 -225.707709) (xy 438.975654 -225.692146) (xy 438.930016 -225.669287) (xy 438.908952 -225.65487)
			(xy 438.902369 -225.65054) (xy 438.887363 -225.645761) (xy 438.879488 -225.645472) (xy 438.363614 -225.645472)
			(xy 438.358314 -225.644969) (xy 438.350743 -225.637553) (xy 438.350152 -225.632264) (xy 432.305968 -225.632264)
			(xy 432.305645 -225.637601) (xy 432.298097 -225.645147) (xy 432.29276 -225.645472) (xy 431.776886 -225.645472)
			(xy 431.769011 -225.645758) (xy 431.754007 -225.650542) (xy 431.747422 -225.65487) (xy 431.726358 -225.669283)
			(xy 431.680708 -225.692106) (xy 431.632098 -225.707657) (xy 431.581678 -225.71557) (xy 431.55616 -225.716084)
			(xy 431.53064 -225.715584) (xy 431.480214 -225.707693) (xy 431.431602 -225.692136) (xy 431.385963 -225.669284)
			(xy 431.364898 -225.65487) (xy 431.358305 -225.650558) (xy 431.343306 -225.645768) (xy 431.335434 -225.645472)
			(xy 430.81956 -225.645472) (xy 430.814284 -225.645028) (xy 430.806841 -225.637543) (xy 430.806352 -225.632264)
			(xy 424.762168 -225.632264) (xy 424.761845 -225.637601) (xy 424.754297 -225.645147) (xy 424.74896 -225.645472)
			(xy 424.748452 -225.645472) (xy 424.232832 -225.645472) (xy 424.224955 -225.645735) (xy 424.209951 -225.650535)
			(xy 424.203368 -225.65487) (xy 424.182292 -225.669263) (xy 424.136646 -225.69209) (xy 424.08804 -225.707648)
			(xy 424.037623 -225.715567) (xy 424.012106 -225.716084) (xy 423.986585 -225.715611) (xy 423.936157 -225.707712)
			(xy 423.887546 -225.692147) (xy 423.841908 -225.669288) (xy 423.820844 -225.65487) (xy 423.814263 -225.650537)
			(xy 423.799255 -225.64576) (xy 423.79138 -225.645472) (xy 423.275506 -225.645472) (xy 423.270205 -225.644974)
			(xy 423.262635 -225.637554) (xy 423.262044 -225.632264) (xy 417.21786 -225.632264) (xy 417.217544 -225.637603)
			(xy 417.209991 -225.645149) (xy 417.204652 -225.645472) (xy 415.731452 -225.645472) (xy 415.726175 -225.645033)
			(xy 415.718733 -225.637544) (xy 415.718244 -225.632264) (xy 308.118256 -225.632264) (xy 308.117686 -225.637511)
			(xy 308.110292 -225.644953) (xy 308.105048 -225.645472) (xy 308.10454 -225.645472) (xy 306.631594 -225.645472)
			(xy 306.626292 -225.644982) (xy 306.618722 -225.637556) (xy 306.618132 -225.632264) (xy 300.573948 -225.632264)
			(xy 300.573385 -225.637513) (xy 300.565986 -225.644955) (xy 300.56074 -225.645472) (xy 300.044866 -225.645472)
			(xy 300.03699 -225.645749) (xy 300.021986 -225.65054) (xy 300.015402 -225.65487) (xy 299.994316 -225.669248)
			(xy 299.948674 -225.692079) (xy 299.900071 -225.70764) (xy 299.849656 -225.715564) (xy 299.82414 -225.716084)
			(xy 299.79862 -225.715594) (xy 299.748193 -225.7077) (xy 299.699581 -225.69214) (xy 299.653943 -225.669285)
			(xy 299.632878 -225.65487) (xy 299.626289 -225.65055) (xy 299.611287 -225.645765) (xy 299.603414 -225.645472)
			(xy 299.08754 -225.645472) (xy 299.082204 -225.645143) (xy 299.074659 -225.637599) (xy 299.074332 -225.632264)
			(xy 293.030148 -225.632264) (xy 293.029585 -225.637513) (xy 293.022186 -225.644955) (xy 293.01694 -225.645472)
			(xy 293.016432 -225.645472) (xy 292.500812 -225.645472) (xy 292.492938 -225.645769) (xy 292.477934 -225.650546)
			(xy 292.471348 -225.65487) (xy 292.450277 -225.669272) (xy 292.40463 -225.692097) (xy 292.356022 -225.707652)
			(xy 292.305603 -225.715568) (xy 292.280086 -225.716084) (xy 292.254567 -225.715571) (xy 292.204141 -225.707684)
			(xy 292.155529 -225.692131) (xy 292.10989 -225.669282) (xy 292.088824 -225.65487) (xy 292.082225 -225.650568)
			(xy 292.067231 -225.645772) (xy 292.05936 -225.645472) (xy 291.543486 -225.645472) (xy 291.538183 -225.644987)
			(xy 291.530614 -225.637557) (xy 291.530024 -225.632264) (xy 285.48584 -225.632264) (xy 285.485452 -225.637584)
			(xy 285.47795 -225.645125) (xy 285.472632 -225.645472) (xy 284.956758 -225.645472) (xy 284.948882 -225.645746)
			(xy 284.933878 -225.650539) (xy 284.927294 -225.65487) (xy 284.90621 -225.669252) (xy 284.860567 -225.692082)
			(xy 284.811963 -225.707642) (xy 284.761548 -225.715565) (xy 284.736032 -225.716084) (xy 284.710512 -225.715598)
			(xy 284.660084 -225.707703) (xy 284.611473 -225.692142) (xy 284.565835 -225.669286) (xy 284.54477 -225.65487)
			(xy 284.538183 -225.650547) (xy 284.52318 -225.645764) (xy 284.515306 -225.645472) (xy 283.999432 -225.645472)
			(xy 283.994095 -225.645148) (xy 283.98655 -225.637601) (xy 283.986224 -225.632264) (xy 277.94204 -225.632264)
			(xy 277.941652 -225.637584) (xy 277.93415 -225.645125) (xy 277.928832 -225.645472) (xy 277.412958 -225.645472)
			(xy 277.405082 -225.645746) (xy 277.390078 -225.650539) (xy 277.383494 -225.65487) (xy 277.36241 -225.669252)
			(xy 277.316767 -225.692082) (xy 277.268163 -225.707642) (xy 277.217748 -225.715565) (xy 277.192232 -225.716084)
			(xy 277.166712 -225.715598) (xy 277.116284 -225.707703) (xy 277.067673 -225.692142) (xy 277.022035 -225.669286)
			(xy 277.00097 -225.65487) (xy 276.994383 -225.650547) (xy 276.97938 -225.645764) (xy 276.971506 -225.645472)
			(xy 276.455632 -225.645472) (xy 276.450295 -225.645148) (xy 276.44275 -225.637601) (xy 276.442424 -225.632264)
			(xy 270.39824 -225.632264) (xy 270.397852 -225.637584) (xy 270.39035 -225.645125) (xy 270.385032 -225.645472)
			(xy 270.384524 -225.645472) (xy 269.868904 -225.645472) (xy 269.86103 -225.645765) (xy 269.846026 -225.650545)
			(xy 269.83944 -225.65487) (xy 269.818371 -225.669275) (xy 269.772723 -225.6921) (xy 269.724114 -225.707654)
			(xy 269.673695 -225.715569) (xy 269.648178 -225.716084) (xy 269.622659 -225.715575) (xy 269.572232 -225.707687)
			(xy 269.523621 -225.692133) (xy 269.477981 -225.669283) (xy 269.456916 -225.65487) (xy 269.450319 -225.650565)
			(xy 269.435323 -225.645771) (xy 269.427452 -225.645472) (xy 268.911578 -225.645472) (xy 268.906274 -225.644993)
			(xy 268.898705 -225.637558) (xy 268.898116 -225.632264) (xy 206.997808 -225.632264) (xy 206.997808 -225.632518)
			(xy 206.997295 -225.637813) (xy 206.989884 -225.645381) (xy 206.9846 -225.64598) (xy 206.468726 -225.64598)
			(xy 206.460915 -225.646291) (xy 206.446044 -225.651078) (xy 206.439516 -225.655378) (xy 206.41839 -225.66972)
			(xy 206.372667 -225.692447) (xy 206.323995 -225.707879) (xy 206.27353 -225.715649) (xy 206.248 -225.716084)
			(xy 206.22247 -225.715644) (xy 206.172006 -225.707869) (xy 206.123334 -225.69244) (xy 206.077606 -225.669725)
			(xy 206.056484 -225.655378) (xy 206.049951 -225.651089) (xy 206.035082 -225.646303) (xy 206.027274 -225.64598)
			(xy 205.5114 -225.64598) (xy 205.506061 -225.645671) (xy 205.498518 -225.638112) (xy 205.498192 -225.632772)
			(xy 199.453983 -225.632772) (xy 199.453495 -225.637813) (xy 199.446084 -225.645381) (xy 199.4408 -225.64598)
			(xy 198.924926 -225.64598) (xy 198.917115 -225.646291) (xy 198.902244 -225.651078) (xy 198.895716 -225.655378)
			(xy 198.87459 -225.66972) (xy 198.828867 -225.692447) (xy 198.780195 -225.707879) (xy 198.72973 -225.715649)
			(xy 198.7042 -225.716084) (xy 198.67867 -225.715644) (xy 198.628206 -225.707869) (xy 198.579534 -225.69244)
			(xy 198.533806 -225.669725) (xy 198.512684 -225.655378) (xy 198.506151 -225.651089) (xy 198.491282 -225.646303)
			(xy 198.483474 -225.64598) (xy 197.9676 -225.64598) (xy 197.962261 -225.645671) (xy 197.954718 -225.638112)
			(xy 197.954392 -225.632772) (xy 191.910182 -225.632772) (xy 191.909666 -225.637873) (xy 191.9021 -225.645455)
			(xy 191.896746 -225.64598) (xy 191.380872 -225.64598) (xy 191.373059 -225.646269) (xy 191.358188 -225.65107)
			(xy 191.351662 -225.655378) (xy 191.330551 -225.669743) (xy 191.284823 -225.692465) (xy 191.236146 -225.707891)
			(xy 191.185678 -225.715653) (xy 191.160146 -225.716084) (xy 191.134617 -225.715621) (xy 191.084154 -225.707852)
			(xy 191.035482 -225.692431) (xy 190.989753 -225.669722) (xy 190.96863 -225.655378) (xy 190.962087 -225.651107)
			(xy 190.947226 -225.64631) (xy 190.93942 -225.64598) (xy 190.423546 -225.64598) (xy 190.418122 -225.645592)
			(xy 190.410434 -225.637941) (xy 190.410084 -225.632518) (xy 184.3659 -225.632518) (xy 184.365394 -225.637815)
			(xy 184.357978 -225.645383) (xy 184.352692 -225.64598) (xy 183.836818 -225.64598) (xy 183.829007 -225.646288)
			(xy 183.814135 -225.651076) (xy 183.807608 -225.655378) (xy 183.786484 -225.669723) (xy 183.740761 -225.69245)
			(xy 183.692088 -225.707881) (xy 183.641623 -225.71565) (xy 183.616092 -225.716084) (xy 183.590562 -225.715648)
			(xy 183.540098 -225.707871) (xy 183.491426 -225.692442) (xy 183.445698 -225.669725) (xy 183.424576 -225.655378)
			(xy 183.418045 -225.651086) (xy 183.403175 -225.646302) (xy 183.395366 -225.64598) (xy 182.879492 -225.64598)
			(xy 182.874152 -225.645676) (xy 182.86661 -225.638113) (xy 182.866284 -225.632772) (xy 176.822075 -225.632772)
			(xy 176.821566 -225.637875) (xy 176.813994 -225.645458) (xy 176.808638 -225.64598) (xy 176.292764 -225.64598)
			(xy 176.284955 -225.646307) (xy 176.270083 -225.651082) (xy 176.263554 -225.655378) (xy 176.242445 -225.669746)
			(xy 176.196716 -225.692468) (xy 176.148039 -225.707893) (xy 176.09757 -225.715654) (xy 176.072038 -225.716084)
			(xy 176.046509 -225.715625) (xy 175.996046 -225.707855) (xy 175.947373 -225.692433) (xy 175.901645 -225.669722)
			(xy 175.880522 -225.655378) (xy 175.87398 -225.651104) (xy 175.859118 -225.646309) (xy 175.851312 -225.64598)
			(xy 175.335438 -225.64598) (xy 175.330012 -225.645597) (xy 175.322325 -225.637942) (xy 175.321976 -225.632518)
			(xy 169.277792 -225.632518) (xy 169.277293 -225.637817) (xy 169.269872 -225.645385) (xy 169.264584 -225.64598)
			(xy 167.791384 -225.64598) (xy 167.786043 -225.645681) (xy 167.778501 -225.638114) (xy 167.778176 -225.632772)
			(xy 60.178163 -225.632772) (xy 60.177664 -225.637878) (xy 60.170086 -225.645461) (xy 60.164726 -225.64598)
			(xy 58.691526 -225.64598) (xy 58.686099 -225.645605) (xy 58.678413 -225.637944) (xy 58.678064 -225.632518)
			(xy 52.63388 -225.632518) (xy 52.633391 -225.63782) (xy 52.625964 -225.645389) (xy 52.620672 -225.64598)
			(xy 52.104798 -225.64598) (xy 52.096986 -225.646279) (xy 52.082115 -225.651074) (xy 52.075588 -225.655378)
			(xy 52.054469 -225.669732) (xy 52.008744 -225.692457) (xy 51.96007 -225.707885) (xy 51.909603 -225.715651)
			(xy 51.884072 -225.716084) (xy 51.858541 -225.715658) (xy 51.808077 -225.707878) (xy 51.759405 -225.692446)
			(xy 51.713678 -225.669727) (xy 51.692556 -225.655378) (xy 51.686029 -225.651079) (xy 51.671156 -225.646299)
			(xy 51.663346 -225.64598) (xy 51.147472 -225.64598) (xy 51.142199 -225.645521) (xy 51.134756 -225.638047)
			(xy 51.134264 -225.632772) (xy 45.090056 -225.632772) (xy 45.089564 -225.63788) (xy 45.08198 -225.645464)
			(xy 45.076618 -225.64598) (xy 44.560744 -225.64598) (xy 44.552934 -225.646299) (xy 44.538062 -225.65108)
			(xy 44.531534 -225.655378) (xy 44.51043 -225.669755) (xy 44.4647 -225.692475) (xy 44.416021 -225.707897)
			(xy 44.36555 -225.715655) (xy 44.340018 -225.716084) (xy 44.314488 -225.715635) (xy 44.264025 -225.707862)
			(xy 44.215353 -225.692437) (xy 44.169625 -225.669724) (xy 44.148502 -225.655378) (xy 44.141965 -225.651096)
			(xy 44.127099 -225.646306) (xy 44.119292 -225.64598) (xy 43.603418 -225.64598) (xy 43.59806 -225.64544)
			(xy 43.590475 -225.637874) (xy 43.589956 -225.632518) (xy 37.545772 -225.632518) (xy 37.54529 -225.637822)
			(xy 37.537858 -225.645391) (xy 37.532564 -225.64598) (xy 37.01669 -225.64598) (xy 37.008878 -225.646276)
			(xy 36.994006 -225.651073) (xy 36.98748 -225.655378) (xy 36.966364 -225.669735) (xy 36.920638 -225.692459)
			(xy 36.871963 -225.707887) (xy 36.821495 -225.715652) (xy 36.795964 -225.716084) (xy 36.770433 -225.715662)
			(xy 36.719969 -225.707881) (xy 36.671297 -225.692448) (xy 36.62557 -225.669727) (xy 36.604448 -225.655378)
			(xy 36.597923 -225.651075) (xy 36.583048 -225.646298) (xy 36.575238 -225.64598) (xy 36.059364 -225.64598)
			(xy 36.05409 -225.645526) (xy 36.046648 -225.638048) (xy 36.046156 -225.632772) (xy 30.001949 -225.632772)
			(xy 30.00149 -225.637822) (xy 29.994058 -225.645391) (xy 29.988764 -225.64598) (xy 29.47289 -225.64598)
			(xy 29.465078 -225.646276) (xy 29.450206 -225.651073) (xy 29.44368 -225.655378) (xy 29.422564 -225.669735)
			(xy 29.376838 -225.692459) (xy 29.328163 -225.707887) (xy 29.277695 -225.715652) (xy 29.252164 -225.716084)
			(xy 29.226633 -225.715662) (xy 29.176169 -225.707881) (xy 29.127497 -225.692448) (xy 29.08177 -225.669727)
			(xy 29.060648 -225.655378) (xy 29.054123 -225.651075) (xy 29.039248 -225.646298) (xy 29.031438 -225.64598)
			(xy 28.515564 -225.64598) (xy 28.51029 -225.645526) (xy 28.502848 -225.638048) (xy 28.502356 -225.632772)
			(xy 22.458148 -225.632772) (xy 22.457663 -225.637882) (xy 22.450074 -225.645466) (xy 22.44471 -225.64598)
			(xy 21.928836 -225.64598) (xy 21.921026 -225.646296) (xy 21.906154 -225.651079) (xy 21.899626 -225.655378)
			(xy 21.878497 -225.669715) (xy 21.832775 -225.692444) (xy 21.784105 -225.707877) (xy 21.73364 -225.715648)
			(xy 21.70811 -225.716084) (xy 21.68258 -225.715639) (xy 21.632117 -225.707865) (xy 21.583444 -225.692438)
			(xy 21.537716 -225.669724) (xy 21.516594 -225.655378) (xy 21.510059 -225.651093) (xy 21.495192 -225.646305)
			(xy 21.487384 -225.64598) (xy 20.97151 -225.64598) (xy 20.966152 -225.645445) (xy 20.958567 -225.637875)
			(xy 20.958048 -225.632518) (xy 2.509012 -225.632518) (xy 2.509012 -226.482402) (xy 16.85798 -226.482402)
			(xy 16.85798 -225.987864) (xy 16.85847 -225.9826) (xy 16.865923 -225.97516) (xy 16.871188 -225.974656)
			(xy 16.871696 -225.974656) (xy 17.38757 -225.974656) (xy 17.39538 -225.974337) (xy 17.410251 -225.969555)
			(xy 17.41678 -225.965258) (xy 17.437869 -225.950909) (xy 17.48353 -225.928178) (xy 17.532136 -225.912719)
			(xy 17.582539 -225.904896) (xy 17.633545 -225.904896) (xy 17.683948 -225.912719) (xy 17.732554 -225.928178)
			(xy 17.778215 -225.950909) (xy 17.799304 -225.965258) (xy 17.805838 -225.969545) (xy 17.820706 -225.974331)
			(xy 17.828514 -225.974656) (xy 18.344642 -225.974656) (xy 18.349955 -225.975097) (xy 18.357525 -225.982559)
			(xy 18.358104 -225.987864) (xy 18.358104 -226.482402) (xy 18.358078 -226.482656) (xy 24.402288 -226.482656)
			(xy 24.402288 -226.482148) (xy 24.402288 -225.987864) (xy 24.402771 -225.982598) (xy 24.410229 -225.975158)
			(xy 24.415496 -225.974656) (xy 24.931624 -225.974656) (xy 24.939436 -225.97436) (xy 24.954307 -225.969563)
			(xy 24.960834 -225.965258) (xy 24.981923 -225.950909) (xy 25.027584 -225.928178) (xy 25.07619 -225.912719)
			(xy 25.126593 -225.904896) (xy 25.177599 -225.904896) (xy 25.228002 -225.912719) (xy 25.276608 -225.928178)
			(xy 25.322269 -225.950909) (xy 25.343358 -225.965258) (xy 25.34988 -225.969566) (xy 25.364757 -225.974339)
			(xy 25.372568 -225.974656) (xy 25.888696 -225.974656) (xy 25.89395 -225.975194) (xy 25.90139 -225.982612)
			(xy 25.901904 -225.987864) (xy 25.901904 -226.482402) (xy 25.901879 -226.482656) (xy 31.946088 -226.482656)
			(xy 31.946088 -226.482148) (xy 31.946088 -225.987864) (xy 31.946571 -225.982598) (xy 31.954029 -225.975158)
			(xy 31.959296 -225.974656) (xy 32.475424 -225.974656) (xy 32.483236 -225.97436) (xy 32.498107 -225.969563)
			(xy 32.504634 -225.965258) (xy 32.525723 -225.950909) (xy 32.571384 -225.928178) (xy 32.61999 -225.912719)
			(xy 32.670393 -225.904896) (xy 32.721399 -225.904896) (xy 32.771802 -225.912719) (xy 32.820408 -225.928178)
			(xy 32.866069 -225.950909) (xy 32.887158 -225.965258) (xy 32.89368 -225.969566) (xy 32.908557 -225.974339)
			(xy 32.916368 -225.974656) (xy 33.432496 -225.974656) (xy 33.43775 -225.975194) (xy 33.44519 -225.982612)
			(xy 33.445704 -225.987864) (xy 33.445704 -226.482402) (xy 39.489888 -226.482402) (xy 39.489888 -225.987864)
			(xy 39.490371 -225.982598) (xy 39.497829 -225.975158) (xy 39.503096 -225.974656) (xy 39.503604 -225.974656)
			(xy 40.019478 -225.974656) (xy 40.027288 -225.97434) (xy 40.04216 -225.969556) (xy 40.048688 -225.965258)
			(xy 40.069777 -225.950909) (xy 40.115438 -225.928178) (xy 40.164044 -225.912719) (xy 40.214447 -225.904896)
			(xy 40.265453 -225.904896) (xy 40.315856 -225.912719) (xy 40.364462 -225.928178) (xy 40.410123 -225.950909)
			(xy 40.431212 -225.965258) (xy 40.437744 -225.969548) (xy 40.452614 -225.974333) (xy 40.460422 -225.974656)
			(xy 40.97655 -225.974656) (xy 40.981852 -225.975158) (xy 40.989427 -225.982573) (xy 40.990012 -225.987864)
			(xy 40.990012 -226.482402) (xy 40.989986 -226.482656) (xy 47.034196 -226.482656) (xy 47.034196 -226.482148)
			(xy 47.034196 -225.987864) (xy 47.034671 -225.982596) (xy 47.042135 -225.975155) (xy 47.047404 -225.974656)
			(xy 47.563532 -225.974656) (xy 47.57134 -225.974321) (xy 47.586212 -225.96955) (xy 47.592742 -225.965258)
			(xy 47.613831 -225.950909) (xy 47.659492 -225.928178) (xy 47.708098 -225.912719) (xy 47.758501 -225.904896)
			(xy 47.809507 -225.904896) (xy 47.85991 -225.912719) (xy 47.908516 -225.928178) (xy 47.954177 -225.950909)
			(xy 47.975266 -225.965258) (xy 47.981808 -225.969531) (xy 47.99667 -225.974326) (xy 48.004476 -225.974656)
			(xy 48.520604 -225.974656) (xy 48.525859 -225.975188) (xy 48.533299 -225.982611) (xy 48.533812 -225.987864)
			(xy 48.533812 -226.482402) (xy 54.577996 -226.482402) (xy 54.577996 -225.987864) (xy 54.578471 -225.982596)
			(xy 54.585935 -225.975155) (xy 54.591204 -225.974656) (xy 56.064658 -225.974656) (xy 56.069961 -225.975153)
			(xy 56.077535 -225.982572) (xy 56.07812 -225.987864) (xy 56.07812 -226.482402) (xy 56.078106 -226.482656)
			(xy 163.678108 -226.482656) (xy 163.678108 -226.482148) (xy 163.678108 -225.987864) (xy 163.678573 -225.982593)
			(xy 163.686043 -225.975152) (xy 163.691316 -225.974656) (xy 165.164516 -225.974656) (xy 165.169772 -225.97518)
			(xy 165.177212 -225.982609) (xy 165.177724 -225.987864) (xy 165.177724 -226.482402) (xy 171.221908 -226.482402)
			(xy 171.221908 -225.987864) (xy 171.222373 -225.982593) (xy 171.229843 -225.975152) (xy 171.235116 -225.974656)
			(xy 171.235624 -225.974656) (xy 171.751498 -225.974656) (xy 171.759309 -225.974349) (xy 171.774181 -225.969559)
			(xy 171.780708 -225.965258) (xy 171.801797 -225.950909) (xy 171.847458 -225.928178) (xy 171.896064 -225.912719)
			(xy 171.946467 -225.904896) (xy 171.997473 -225.904896) (xy 172.047876 -225.912719) (xy 172.096482 -225.928178)
			(xy 172.142143 -225.950909) (xy 172.163232 -225.965258) (xy 172.16976 -225.969556) (xy 172.184633 -225.974336)
			(xy 172.192442 -225.974656) (xy 172.70857 -225.974656) (xy 172.713874 -225.975145) (xy 172.721448 -225.98257)
			(xy 172.722032 -225.987864) (xy 172.722032 -226.482402) (xy 172.722017 -226.482656) (xy 178.766216 -226.482656)
			(xy 178.766216 -226.482148) (xy 178.766216 -225.987864) (xy 178.766673 -225.982591) (xy 178.774149 -225.975149)
			(xy 178.779424 -225.974656) (xy 179.295552 -225.974656) (xy 179.303361 -225.974329) (xy 179.318233 -225.969553)
			(xy 179.324762 -225.965258) (xy 179.345851 -225.950909) (xy 179.391512 -225.928178) (xy 179.440118 -225.912719)
			(xy 179.490521 -225.904896) (xy 179.541527 -225.904896) (xy 179.59193 -225.912719) (xy 179.640536 -225.928178)
			(xy 179.686197 -225.950909) (xy 179.707286 -225.965258) (xy 179.713824 -225.969538) (xy 179.728689 -225.974329)
			(xy 179.736496 -225.974656) (xy 180.252624 -225.974656) (xy 180.257881 -225.975175) (xy 180.26532 -225.982608)
			(xy 180.265832 -225.987864) (xy 180.265832 -226.482402) (xy 186.310016 -226.482402) (xy 186.310016 -225.987864)
			(xy 186.310473 -225.982591) (xy 186.317949 -225.975149) (xy 186.323224 -225.974656) (xy 186.323732 -225.974656)
			(xy 186.839606 -225.974656) (xy 186.847417 -225.974352) (xy 186.862289 -225.96956) (xy 186.868816 -225.965258)
			(xy 186.889905 -225.950909) (xy 186.935566 -225.928178) (xy 186.984172 -225.912719) (xy 187.034575 -225.904896)
			(xy 187.085581 -225.904896) (xy 187.135984 -225.912719) (xy 187.18459 -225.928178) (xy 187.230251 -225.950909)
			(xy 187.25134 -225.965258) (xy 187.257866 -225.969559) (xy 187.27274 -225.974337) (xy 187.28055 -225.974656)
			(xy 187.796678 -225.974656) (xy 187.801983 -225.975139) (xy 187.809557 -225.982569) (xy 187.81014 -225.987864)
			(xy 187.81014 -226.482402) (xy 187.810125 -226.482656) (xy 193.854324 -226.482656) (xy 193.854324 -226.482148)
			(xy 193.854324 -225.987864) (xy 193.854774 -225.982589) (xy 193.862255 -225.975147) (xy 193.867532 -225.974656)
			(xy 194.38366 -225.974656) (xy 194.391469 -225.974333) (xy 194.406341 -225.969554) (xy 194.41287 -225.965258)
			(xy 194.433959 -225.950909) (xy 194.47962 -225.928178) (xy 194.528226 -225.912719) (xy 194.578629 -225.904896)
			(xy 194.629635 -225.904896) (xy 194.680038 -225.912719) (xy 194.728644 -225.928178) (xy 194.774305 -225.950909)
			(xy 194.795394 -225.965258) (xy 194.80193 -225.969542) (xy 194.816796 -225.97433) (xy 194.824604 -225.974656)
			(xy 195.340732 -225.974656) (xy 195.34599 -225.97517) (xy 195.353429 -225.982606) (xy 195.35394 -225.987864)
			(xy 195.35394 -226.482402) (xy 195.353918 -226.482656) (xy 201.398124 -226.482656) (xy 201.398124 -226.482148)
			(xy 201.398124 -225.987864) (xy 201.398574 -225.982589) (xy 201.406055 -225.975147) (xy 201.411332 -225.974656)
			(xy 201.92746 -225.974656) (xy 201.935269 -225.974333) (xy 201.950141 -225.969554) (xy 201.95667 -225.965258)
			(xy 201.977759 -225.950909) (xy 202.02342 -225.928178) (xy 202.072026 -225.912719) (xy 202.122429 -225.904896)
			(xy 202.173435 -225.904896) (xy 202.223838 -225.912719) (xy 202.272444 -225.928178) (xy 202.318105 -225.950909)
			(xy 202.339194 -225.965258) (xy 202.34573 -225.969542) (xy 202.360596 -225.97433) (xy 202.368404 -225.974656)
			(xy 202.884532 -225.974656) (xy 202.88979 -225.97517) (xy 202.897229 -225.982606) (xy 202.89774 -225.987864)
			(xy 202.89774 -226.482148) (xy 264.798048 -226.482148) (xy 264.798048 -225.98761) (xy 264.798387 -225.982174)
			(xy 264.806074 -225.974487) (xy 264.81151 -225.974148) (xy 265.327638 -225.974148) (xy 265.335447 -225.973817)
			(xy 265.350318 -225.969044) (xy 265.356848 -225.96475) (xy 265.377937 -225.950401) (xy 265.423598 -225.92767)
			(xy 265.472204 -225.912211) (xy 265.522607 -225.904388) (xy 265.573613 -225.904388) (xy 265.624016 -225.912211)
			(xy 265.672622 -225.92767) (xy 265.718283 -225.950401) (xy 265.739372 -225.96475) (xy 265.745913 -225.969024)
			(xy 265.760776 -225.973819) (xy 265.768582 -225.974148) (xy 266.28471 -225.974148) (xy 266.290078 -225.974645)
			(xy 266.297663 -225.982242) (xy 266.298172 -225.98761) (xy 266.298172 -226.482148) (xy 272.342356 -226.482148)
			(xy 272.342356 -225.98761) (xy 272.342831 -225.982303) (xy 272.350267 -225.97473) (xy 272.355564 -225.974148)
			(xy 272.871692 -225.974148) (xy 272.879503 -225.973839) (xy 272.894374 -225.969051) (xy 272.900902 -225.96475)
			(xy 272.921991 -225.950401) (xy 272.967652 -225.92767) (xy 273.016258 -225.912211) (xy 273.066661 -225.904388)
			(xy 273.117667 -225.904388) (xy 273.16807 -225.912211) (xy 273.216676 -225.92767) (xy 273.262337 -225.950401)
			(xy 273.283426 -225.96475) (xy 273.289955 -225.969045) (xy 273.304827 -225.973827) (xy 273.312636 -225.974148)
			(xy 273.828764 -225.974148) (xy 273.834012 -225.974714) (xy 273.841454 -225.982111) (xy 273.841972 -225.987356)
			(xy 273.841972 -225.987864) (xy 273.841972 -226.482148) (xy 279.886156 -226.482148) (xy 279.886156 -225.98761)
			(xy 279.886631 -225.982303) (xy 279.894067 -225.97473) (xy 279.899364 -225.974148) (xy 280.415492 -225.974148)
			(xy 280.423303 -225.973839) (xy 280.438174 -225.969051) (xy 280.444702 -225.96475) (xy 280.465791 -225.950401)
			(xy 280.511452 -225.92767) (xy 280.560058 -225.912211) (xy 280.610461 -225.904388) (xy 280.661467 -225.904388)
			(xy 280.71187 -225.912211) (xy 280.760476 -225.92767) (xy 280.806137 -225.950401) (xy 280.827226 -225.96475)
			(xy 280.833755 -225.969045) (xy 280.848627 -225.973827) (xy 280.856436 -225.974148) (xy 281.372564 -225.974148)
			(xy 281.377812 -225.974714) (xy 281.385254 -225.982111) (xy 281.385772 -225.987356) (xy 281.385772 -225.987864)
			(xy 281.385772 -226.482148) (xy 287.429956 -226.482148) (xy 287.429956 -225.98761) (xy 287.430288 -225.982172)
			(xy 287.43798 -225.974484) (xy 287.443418 -225.974148) (xy 287.959546 -225.974148) (xy 287.967355 -225.97382)
			(xy 287.982227 -225.969045) (xy 287.988756 -225.96475) (xy 288.009845 -225.950401) (xy 288.055506 -225.92767)
			(xy 288.104112 -225.912211) (xy 288.154515 -225.904388) (xy 288.205521 -225.904388) (xy 288.255924 -225.912211)
			(xy 288.30453 -225.92767) (xy 288.350191 -225.950401) (xy 288.37128 -225.96475) (xy 288.37782 -225.969027)
			(xy 288.392683 -225.97382) (xy 288.40049 -225.974148) (xy 288.916618 -225.974148) (xy 288.921987 -225.974639)
			(xy 288.929572 -225.98224) (xy 288.93008 -225.98761) (xy 288.93008 -226.482148) (xy 294.974264 -226.482148)
			(xy 294.974264 -225.98761) (xy 294.974733 -225.982302) (xy 294.982173 -225.974729) (xy 294.987472 -225.974148)
			(xy 295.5036 -225.974148) (xy 295.511411 -225.973843) (xy 295.526283 -225.969052) (xy 295.53281 -225.96475)
			(xy 295.553899 -225.950401) (xy 295.59956 -225.92767) (xy 295.648166 -225.912211) (xy 295.698569 -225.904388)
			(xy 295.749575 -225.904388) (xy 295.799978 -225.912211) (xy 295.848584 -225.92767) (xy 295.894245 -225.950401)
			(xy 295.915334 -225.96475) (xy 295.921862 -225.969048) (xy 295.936735 -225.973828) (xy 295.944544 -225.974148)
			(xy 296.460672 -225.974148) (xy 296.465921 -225.974709) (xy 296.473362 -225.98211) (xy 296.47388 -225.987356)
			(xy 296.47388 -225.987864) (xy 296.47388 -226.482148) (xy 302.518064 -226.482148) (xy 302.518064 -225.98761)
			(xy 302.518388 -225.98217) (xy 302.526086 -225.974482) (xy 302.531526 -225.974148) (xy 304.004726 -225.974148)
			(xy 304.010095 -225.974634) (xy 304.01768 -225.982239) (xy 304.018188 -225.98761) (xy 304.018188 -226.482148)
			(xy 411.618176 -226.482148) (xy 411.618176 -225.98761) (xy 411.618634 -225.982299) (xy 411.626082 -225.974725)
			(xy 411.631384 -225.974148) (xy 413.104584 -225.974148) (xy 413.109834 -225.974701) (xy 413.117275 -225.982108)
			(xy 413.117792 -225.987356) (xy 413.117792 -225.987864) (xy 413.117792 -226.482148) (xy 419.161976 -226.482148)
			(xy 419.161976 -225.98761) (xy 419.16229 -225.982167) (xy 419.169994 -225.974478) (xy 419.175438 -225.974148)
			(xy 419.691566 -225.974148) (xy 419.699376 -225.973828) (xy 419.714247 -225.969047) (xy 419.720776 -225.96475)
			(xy 419.741865 -225.950401) (xy 419.787526 -225.92767) (xy 419.836132 -225.912211) (xy 419.886535 -225.904388)
			(xy 419.937541 -225.904388) (xy 419.987944 -225.912211) (xy 420.03655 -225.92767) (xy 420.082211 -225.950401)
			(xy 420.1033 -225.96475) (xy 420.109835 -225.969035) (xy 420.124702 -225.973823) (xy 420.13251 -225.974148)
			(xy 420.648638 -225.974148) (xy 420.654009 -225.974626) (xy 420.661593 -225.982237) (xy 420.6621 -225.98761)
			(xy 420.6621 -226.482148) (xy 426.706284 -226.482148) (xy 426.706284 -225.98761) (xy 426.706735 -225.982297)
			(xy 426.714187 -225.974723) (xy 426.719492 -225.974148) (xy 427.23562 -225.974148) (xy 427.243432 -225.973852)
			(xy 427.258304 -225.969055) (xy 427.26483 -225.96475) (xy 427.285919 -225.950401) (xy 427.33158 -225.92767)
			(xy 427.380186 -225.912211) (xy 427.430589 -225.904388) (xy 427.481595 -225.904388) (xy 427.531998 -225.912211)
			(xy 427.580604 -225.92767) (xy 427.626265 -225.950401) (xy 427.647354 -225.96475) (xy 427.653877 -225.969056)
			(xy 427.668753 -225.973831) (xy 427.676564 -225.974148) (xy 428.192692 -225.974148) (xy 428.197943 -225.974695)
			(xy 428.205384 -225.982107) (xy 428.2059 -225.987356) (xy 428.2059 -225.987864) (xy 428.2059 -226.482148)
			(xy 434.250084 -226.482148) (xy 434.250084 -225.98761) (xy 434.25039 -225.982165) (xy 434.2581 -225.974476)
			(xy 434.263546 -225.974148) (xy 434.779674 -225.974148) (xy 434.787484 -225.973832) (xy 434.802356 -225.969048)
			(xy 434.808884 -225.96475) (xy 434.829973 -225.950401) (xy 434.875634 -225.92767) (xy 434.92424 -225.912211)
			(xy 434.974643 -225.904388) (xy 435.025649 -225.904388) (xy 435.076052 -225.912211) (xy 435.124658 -225.92767)
			(xy 435.170319 -225.950401) (xy 435.191408 -225.96475) (xy 435.197941 -225.969038) (xy 435.21281 -225.973824)
			(xy 435.220618 -225.974148) (xy 435.736746 -225.974148) (xy 435.742118 -225.974621) (xy 435.749701 -225.982236)
			(xy 435.750208 -225.98761) (xy 435.750208 -226.482148) (xy 441.794392 -226.482148) (xy 441.794392 -225.98761)
			(xy 441.794924 -225.982318) (xy 441.802321 -225.974749) (xy 441.8076 -225.974148) (xy 442.323728 -225.974148)
			(xy 442.33154 -225.973855) (xy 442.346412 -225.969056) (xy 442.352938 -225.96475) (xy 442.374027 -225.950401)
			(xy 442.419688 -225.92767) (xy 442.468294 -225.912211) (xy 442.518697 -225.904388) (xy 442.569703 -225.904388)
			(xy 442.620106 -225.912211) (xy 442.668712 -225.92767) (xy 442.714373 -225.950401) (xy 442.735462 -225.96475)
			(xy 442.742006 -225.969021) (xy 442.756866 -225.973817) (xy 442.764672 -225.974148) (xy 443.2808 -225.974148)
			(xy 443.286052 -225.97469) (xy 443.293492 -225.982106) (xy 443.294008 -225.987356) (xy 443.294008 -225.987864)
			(xy 443.294008 -226.482148) (xy 449.338192 -226.482148) (xy 449.338192 -225.98761) (xy 449.338724 -225.982318)
			(xy 449.346121 -225.974749) (xy 449.3514 -225.974148) (xy 449.867528 -225.974148) (xy 449.87534 -225.973855)
			(xy 449.890212 -225.969056) (xy 449.896738 -225.96475) (xy 449.917827 -225.950401) (xy 449.963488 -225.92767)
			(xy 450.012094 -225.912211) (xy 450.062497 -225.904388) (xy 450.113503 -225.904388) (xy 450.163906 -225.912211)
			(xy 450.212512 -225.92767) (xy 450.258173 -225.950401) (xy 450.279262 -225.96475) (xy 450.285806 -225.969021)
			(xy 450.300666 -225.973817) (xy 450.308472 -225.974148) (xy 450.8246 -225.974148) (xy 450.829852 -225.97469)
			(xy 450.837292 -225.982106) (xy 450.837808 -225.987356) (xy 450.837808 -225.987864) (xy 450.837808 -226.482148)
			(xy 450.837337 -226.487417) (xy 450.82987 -226.494856) (xy 450.8246 -226.495356) (xy 450.308726 -226.495356)
			(xy 450.300849 -226.495618) (xy 450.285845 -226.500419) (xy 450.279262 -226.504754) (xy 450.258186 -226.519148)
			(xy 450.212541 -226.541975) (xy 450.163934 -226.557533) (xy 450.113517 -226.565451) (xy 450.088 -226.565968)
			(xy 450.062479 -226.565501) (xy 450.012051 -226.557601) (xy 449.963439 -226.542034) (xy 449.917802 -226.519173)
			(xy 449.896738 -226.504754) (xy 449.890137 -226.500456) (xy 449.875144 -226.495658) (xy 449.867274 -226.495356)
			(xy 449.3514 -226.495356) (xy 449.346149 -226.49481) (xy 449.338709 -226.487397) (xy 449.338192 -226.482148)
			(xy 443.294008 -226.482148) (xy 443.293537 -226.487417) (xy 443.28607 -226.494856) (xy 443.2808 -226.495356)
			(xy 442.764926 -226.495356) (xy 442.757049 -226.495618) (xy 442.742045 -226.500419) (xy 442.735462 -226.504754)
			(xy 442.714386 -226.519148) (xy 442.668741 -226.541975) (xy 442.620134 -226.557533) (xy 442.569717 -226.565451)
			(xy 442.5442 -226.565968) (xy 442.518679 -226.565501) (xy 442.468251 -226.557601) (xy 442.419639 -226.542034)
			(xy 442.374002 -226.519173) (xy 442.352938 -226.504754) (xy 442.346337 -226.500456) (xy 442.331344 -226.495658)
			(xy 442.323474 -226.495356) (xy 441.8076 -226.495356) (xy 441.802349 -226.49481) (xy 441.794909 -226.487397)
			(xy 441.794392 -226.482148) (xy 435.750208 -226.482148) (xy 435.749737 -226.487417) (xy 435.74227 -226.494856)
			(xy 435.737 -226.495356) (xy 435.736492 -226.495356) (xy 435.220872 -226.495356) (xy 435.212997 -226.495638)
			(xy 435.197993 -226.500426) (xy 435.191408 -226.504754) (xy 435.170347 -226.519171) (xy 435.124696 -226.541993)
			(xy 435.076085 -226.557544) (xy 435.025664 -226.565455) (xy 435.000146 -226.565968) (xy 434.974626 -226.565478)
			(xy 434.924199 -226.557585) (xy 434.875587 -226.542025) (xy 434.829949 -226.51917) (xy 434.808884 -226.504754)
			(xy 434.802295 -226.500435) (xy 434.787293 -226.49565) (xy 434.77942 -226.495356) (xy 434.263546 -226.495356)
			(xy 434.258246 -226.494846) (xy 434.250672 -226.487436) (xy 434.250084 -226.482148) (xy 428.2059 -226.482148)
			(xy 428.205436 -226.487418) (xy 428.197964 -226.494859) (xy 428.192692 -226.495356) (xy 427.676818 -226.495356)
			(xy 427.668945 -226.495658) (xy 427.653941 -226.500432) (xy 427.647354 -226.504754) (xy 427.62628 -226.519151)
			(xy 427.580634 -226.541978) (xy 427.532027 -226.557534) (xy 427.481609 -226.565452) (xy 427.456092 -226.565968)
			(xy 427.430573 -226.565455) (xy 427.380146 -226.557569) (xy 427.331535 -226.542016) (xy 427.285895 -226.519167)
			(xy 427.26483 -226.504754) (xy 427.25823 -226.500453) (xy 427.243237 -226.495657) (xy 427.235366 -226.495356)
			(xy 426.719492 -226.495356) (xy 426.71424 -226.494816) (xy 426.7068 -226.487399) (xy 426.706284 -226.482148)
			(xy 420.6621 -226.482148) (xy 420.661636 -226.487418) (xy 420.654164 -226.494859) (xy 420.648892 -226.495356)
			(xy 420.648384 -226.495356) (xy 420.132764 -226.495356) (xy 420.124889 -226.495635) (xy 420.109885 -226.500425)
			(xy 420.1033 -226.504754) (xy 420.082213 -226.519131) (xy 420.036572 -226.541963) (xy 419.987969 -226.557524)
			(xy 419.937554 -226.565448) (xy 419.912038 -226.565968) (xy 419.886518 -226.565482) (xy 419.83609 -226.557587)
			(xy 419.787479 -226.542026) (xy 419.74184 -226.51917) (xy 419.720776 -226.504754) (xy 419.714188 -226.500432)
			(xy 419.699185 -226.495649) (xy 419.691312 -226.495356) (xy 419.175438 -226.495356) (xy 419.170137 -226.494851)
			(xy 419.162564 -226.487437) (xy 419.161976 -226.482148) (xy 413.117792 -226.482148) (xy 413.117335 -226.48742)
			(xy 413.109859 -226.494861) (xy 413.104584 -226.495356) (xy 411.631384 -226.495356) (xy 411.626131 -226.494821)
			(xy 411.618692 -226.4874) (xy 411.618176 -226.482148) (xy 304.018188 -226.482148) (xy 304.017735 -226.487421)
			(xy 304.010256 -226.494862) (xy 304.00498 -226.495356) (xy 302.531526 -226.495356) (xy 302.526224 -226.494859)
			(xy 302.518651 -226.487439) (xy 302.518064 -226.482148) (xy 296.47388 -226.482148) (xy 296.473434 -226.487423)
			(xy 296.46595 -226.494865) (xy 296.460672 -226.495356) (xy 295.944798 -226.495356) (xy 295.936924 -226.495649)
			(xy 295.92192 -226.500429) (xy 295.915334 -226.504754) (xy 295.894266 -226.51916) (xy 295.848618 -226.541985)
			(xy 295.800009 -226.557539) (xy 295.749589 -226.565453) (xy 295.724072 -226.565968) (xy 295.698552 -226.565465)
			(xy 295.648126 -226.557576) (xy 295.599514 -226.54202) (xy 295.553875 -226.519168) (xy 295.53281 -226.504754)
			(xy 295.526215 -226.500445) (xy 295.511218 -226.495654) (xy 295.503346 -226.495356) (xy 294.987472 -226.495356)
			(xy 294.982217 -226.494829) (xy 294.974779 -226.487402) (xy 294.974264 -226.482148) (xy 288.93008 -226.482148)
			(xy 288.929634 -226.487423) (xy 288.92215 -226.494865) (xy 288.916872 -226.495356) (xy 288.916364 -226.495356)
			(xy 288.400744 -226.495356) (xy 288.392868 -226.495626) (xy 288.377864 -226.500422) (xy 288.37128 -226.504754)
			(xy 288.350199 -226.51914) (xy 288.304555 -226.541969) (xy 288.25595 -226.557529) (xy 288.205534 -226.56545)
			(xy 288.180018 -226.565968) (xy 288.154497 -226.565492) (xy 288.104069 -226.557594) (xy 288.055458 -226.542031)
			(xy 288.00982 -226.519171) (xy 287.988756 -226.504754) (xy 287.982173 -226.500424) (xy 287.967166 -226.495646)
			(xy 287.959292 -226.495356) (xy 287.443418 -226.495356) (xy 287.438115 -226.494864) (xy 287.430543 -226.48744)
			(xy 287.429956 -226.482148) (xy 281.385772 -226.482148) (xy 281.385333 -226.487425) (xy 281.377844 -226.494867)
			(xy 281.372564 -226.495356) (xy 280.85669 -226.495356) (xy 280.848816 -226.495646) (xy 280.833812 -226.500428)
			(xy 280.827226 -226.504754) (xy 280.80616 -226.519163) (xy 280.760511 -226.541987) (xy 280.711901 -226.55754)
			(xy 280.661482 -226.565454) (xy 280.635964 -226.565968) (xy 280.610444 -226.565469) (xy 280.560017 -226.557578)
			(xy 280.511406 -226.542021) (xy 280.465767 -226.519168) (xy 280.444702 -226.504754) (xy 280.438109 -226.500442)
			(xy 280.42311 -226.495652) (xy 280.415238 -226.495356) (xy 279.899364 -226.495356) (xy 279.894109 -226.494834)
			(xy 279.886671 -226.487403) (xy 279.886156 -226.482148) (xy 273.841972 -226.482148) (xy 273.841533 -226.487425)
			(xy 273.834044 -226.494867) (xy 273.828764 -226.495356) (xy 273.31289 -226.495356) (xy 273.305016 -226.495646)
			(xy 273.290012 -226.500428) (xy 273.283426 -226.504754) (xy 273.26236 -226.519163) (xy 273.216711 -226.541987)
			(xy 273.168101 -226.55754) (xy 273.117682 -226.565454) (xy 273.092164 -226.565968) (xy 273.066644 -226.565469)
			(xy 273.016217 -226.557578) (xy 272.967606 -226.542021) (xy 272.921967 -226.519168) (xy 272.900902 -226.504754)
			(xy 272.894309 -226.500442) (xy 272.87931 -226.495652) (xy 272.871438 -226.495356) (xy 272.355564 -226.495356)
			(xy 272.350309 -226.494834) (xy 272.342871 -226.487403) (xy 272.342356 -226.482148) (xy 266.298172 -226.482148)
			(xy 266.297733 -226.487425) (xy 266.290244 -226.494867) (xy 266.284964 -226.495356) (xy 266.284456 -226.495356)
			(xy 265.768836 -226.495356) (xy 265.76096 -226.495623) (xy 265.745956 -226.50042) (xy 265.739372 -226.504754)
			(xy 265.718293 -226.519143) (xy 265.672649 -226.541972) (xy 265.624043 -226.55753) (xy 265.573627 -226.56545)
			(xy 265.54811 -226.565968) (xy 265.522589 -226.565496) (xy 265.472161 -226.557597) (xy 265.423549 -226.542032)
			(xy 265.377912 -226.519172) (xy 265.356848 -226.504754) (xy 265.350267 -226.500421) (xy 265.335259 -226.495645)
			(xy 265.327384 -226.495356) (xy 264.81151 -226.495356) (xy 264.806206 -226.49487) (xy 264.798634 -226.487442)
			(xy 264.798048 -226.482148) (xy 202.89774 -226.482148) (xy 202.89774 -226.482402) (xy 202.897276 -226.487711)
			(xy 202.889832 -226.495283) (xy 202.884532 -226.495864) (xy 202.368658 -226.495864) (xy 202.360849 -226.496192)
			(xy 202.345977 -226.500967) (xy 202.339448 -226.505262) (xy 202.318339 -226.519631) (xy 202.272611 -226.542353)
			(xy 202.223933 -226.557777) (xy 202.173464 -226.565538) (xy 202.147932 -226.565968) (xy 202.122402 -226.565515)
			(xy 202.071939 -226.557744) (xy 202.023267 -226.54232) (xy 201.977539 -226.519607) (xy 201.956416 -226.505262)
			(xy 201.949877 -226.500984) (xy 201.935013 -226.496192) (xy 201.927206 -226.495864) (xy 201.411332 -226.495864)
			(xy 201.405993 -226.495547) (xy 201.398448 -226.487995) (xy 201.398124 -226.482656) (xy 195.353918 -226.482656)
			(xy 195.353476 -226.487711) (xy 195.346032 -226.495283) (xy 195.340732 -226.495864) (xy 194.824858 -226.495864)
			(xy 194.817049 -226.496192) (xy 194.802177 -226.500967) (xy 194.795648 -226.505262) (xy 194.774539 -226.519631)
			(xy 194.728811 -226.542353) (xy 194.680133 -226.557777) (xy 194.629664 -226.565538) (xy 194.604132 -226.565968)
			(xy 194.578602 -226.565515) (xy 194.528139 -226.557744) (xy 194.479467 -226.54232) (xy 194.433739 -226.519607)
			(xy 194.412616 -226.505262) (xy 194.406077 -226.500984) (xy 194.391213 -226.496192) (xy 194.383406 -226.495864)
			(xy 193.867532 -226.495864) (xy 193.862193 -226.495547) (xy 193.854648 -226.487995) (xy 193.854324 -226.482656)
			(xy 187.810125 -226.482656) (xy 187.80982 -226.487842) (xy 187.802119 -226.49553) (xy 187.796678 -226.495864)
			(xy 187.280804 -226.495864) (xy 187.272993 -226.496169) (xy 187.258121 -226.50096) (xy 187.251594 -226.505262)
			(xy 187.230472 -226.519611) (xy 187.184748 -226.542338) (xy 187.136075 -226.557768) (xy 187.085609 -226.565535)
			(xy 187.060078 -226.565968) (xy 187.034547 -226.565542) (xy 186.984083 -226.557763) (xy 186.935411 -226.54233)
			(xy 186.889684 -226.519611) (xy 186.868562 -226.505262) (xy 186.862035 -226.500963) (xy 186.847162 -226.496184)
			(xy 186.839352 -226.495864) (xy 186.323478 -226.495864) (xy 186.318112 -226.495364) (xy 186.310528 -226.487769)
			(xy 186.310016 -226.482402) (xy 180.265832 -226.482402) (xy 180.265375 -226.487713) (xy 180.257926 -226.495285)
			(xy 180.252624 -226.495864) (xy 179.73675 -226.495864) (xy 179.728941 -226.496188) (xy 179.714069 -226.500966)
			(xy 179.70754 -226.505262) (xy 179.686433 -226.519635) (xy 179.640704 -226.542356) (xy 179.592026 -226.557779)
			(xy 179.541556 -226.565539) (xy 179.516024 -226.565968) (xy 179.490494 -226.565519) (xy 179.440031 -226.557747)
			(xy 179.391359 -226.542321) (xy 179.34563 -226.519608) (xy 179.324508 -226.505262) (xy 179.31797 -226.500981)
			(xy 179.303105 -226.496191) (xy 179.295298 -226.495864) (xy 178.779424 -226.495864) (xy 178.774084 -226.495553)
			(xy 178.766539 -226.487996) (xy 178.766216 -226.482656) (xy 172.722017 -226.482656) (xy 172.721719 -226.487844)
			(xy 172.714013 -226.495532) (xy 172.70857 -226.495864) (xy 172.192696 -226.495864) (xy 172.184885 -226.496165)
			(xy 172.170013 -226.500959) (xy 172.163486 -226.505262) (xy 172.142367 -226.519615) (xy 172.096642 -226.54234)
			(xy 172.047968 -226.557769) (xy 171.997501 -226.565535) (xy 171.97197 -226.565968) (xy 171.946439 -226.565546)
			(xy 171.895975 -226.557766) (xy 171.847302 -226.542332) (xy 171.801575 -226.519611) (xy 171.780454 -226.505262)
			(xy 171.773928 -226.50096) (xy 171.759054 -226.496183) (xy 171.751244 -226.495864) (xy 171.23537 -226.495864)
			(xy 171.230003 -226.49537) (xy 171.222419 -226.48777) (xy 171.221908 -226.482402) (xy 165.177724 -226.482402)
			(xy 165.177274 -226.487715) (xy 165.16982 -226.495288) (xy 165.164516 -226.495864) (xy 163.691316 -226.495864)
			(xy 163.685975 -226.495558) (xy 163.678431 -226.487998) (xy 163.678108 -226.482656) (xy 56.078106 -226.482656)
			(xy 56.077818 -226.487847) (xy 56.070104 -226.495536) (xy 56.064658 -226.495864) (xy 54.591458 -226.495864)
			(xy 54.586089 -226.495378) (xy 54.578506 -226.487772) (xy 54.577996 -226.482402) (xy 48.533812 -226.482402)
			(xy 48.533372 -226.487718) (xy 48.525912 -226.495291) (xy 48.520604 -226.495864) (xy 48.00473 -226.495864)
			(xy 47.99692 -226.49618) (xy 47.982048 -226.500963) (xy 47.97552 -226.505262) (xy 47.954391 -226.5196)
			(xy 47.90867 -226.542329) (xy 47.859999 -226.557762) (xy 47.809534 -226.565533) (xy 47.784004 -226.565968)
			(xy 47.758474 -226.565529) (xy 47.70801 -226.557754) (xy 47.659338 -226.542325) (xy 47.61361 -226.519609)
			(xy 47.592488 -226.505262) (xy 47.585955 -226.500973) (xy 47.571086 -226.496188) (xy 47.563278 -226.495864)
			(xy 47.047404 -226.495864) (xy 47.042062 -226.495566) (xy 47.034518 -226.487999) (xy 47.034196 -226.482656)
			(xy 40.989986 -226.482656) (xy 40.989456 -226.487754) (xy 40.9819 -226.495337) (xy 40.97655 -226.495864)
			(xy 40.460676 -226.495864) (xy 40.452864 -226.496156) (xy 40.437992 -226.500956) (xy 40.431466 -226.505262)
			(xy 40.410352 -226.519623) (xy 40.364625 -226.542347) (xy 40.31595 -226.557774) (xy 40.265482 -226.565537)
			(xy 40.23995 -226.565968) (xy 40.214421 -226.565506) (xy 40.163958 -226.557738) (xy 40.115285 -226.542316)
			(xy 40.069557 -226.519606) (xy 40.048434 -226.505262) (xy 40.041891 -226.500991) (xy 40.02703 -226.496194)
			(xy 40.019224 -226.495864) (xy 39.50335 -226.495864) (xy 39.497981 -226.495383) (xy 39.490398 -226.487773)
			(xy 39.489888 -226.482402) (xy 33.445704 -226.482402) (xy 33.445184 -226.487696) (xy 33.437778 -226.495265)
			(xy 33.432496 -226.495864) (xy 32.916622 -226.495864) (xy 32.908812 -226.496176) (xy 32.89394 -226.500962)
			(xy 32.887412 -226.505262) (xy 32.866285 -226.519603) (xy 32.820563 -226.542332) (xy 32.771892 -226.557764)
			(xy 32.721426 -226.565533) (xy 32.695896 -226.565968) (xy 32.670366 -226.565533) (xy 32.619902 -226.557756)
			(xy 32.571229 -226.542327) (xy 32.525502 -226.51961) (xy 32.50438 -226.505262) (xy 32.497849 -226.50097)
			(xy 32.482979 -226.496186) (xy 32.47517 -226.495864) (xy 31.959296 -226.495864) (xy 31.953952 -226.495571)
			(xy 31.946409 -226.488001) (xy 31.946088 -226.482656) (xy 25.901879 -226.482656) (xy 25.901384 -226.487696)
			(xy 25.893978 -226.495265) (xy 25.888696 -226.495864) (xy 25.372822 -226.495864) (xy 25.365012 -226.496176)
			(xy 25.35014 -226.500962) (xy 25.343612 -226.505262) (xy 25.322485 -226.519603) (xy 25.276763 -226.542332)
			(xy 25.228092 -226.557764) (xy 25.177626 -226.565533) (xy 25.152096 -226.565968) (xy 25.126566 -226.565533)
			(xy 25.076102 -226.557756) (xy 25.027429 -226.542327) (xy 24.981702 -226.51961) (xy 24.96058 -226.505262)
			(xy 24.954049 -226.50097) (xy 24.939179 -226.496186) (xy 24.93137 -226.495864) (xy 24.415496 -226.495864)
			(xy 24.410152 -226.495571) (xy 24.402609 -226.488001) (xy 24.402288 -226.482656) (xy 18.358078 -226.482656)
			(xy 18.357555 -226.487756) (xy 18.349994 -226.495339) (xy 18.344642 -226.495864) (xy 17.828768 -226.495864)
			(xy 17.820959 -226.496196) (xy 17.806087 -226.500968) (xy 17.799558 -226.505262) (xy 17.778446 -226.519627)
			(xy 17.732719 -226.54235) (xy 17.684043 -226.557775) (xy 17.633574 -226.565537) (xy 17.608042 -226.565968)
			(xy 17.582513 -226.56551) (xy 17.53205 -226.55774) (xy 17.483377 -226.542318) (xy 17.437649 -226.519607)
			(xy 17.416526 -226.505262) (xy 17.409984 -226.500988) (xy 17.395122 -226.496193) (xy 17.387316 -226.495864)
			(xy 16.871442 -226.495864) (xy 16.866013 -226.495493) (xy 16.858325 -226.48783) (xy 16.85798 -226.482402)
			(xy 2.509012 -226.482402) (xy 2.509012 -227.33254) (xy 20.958048 -227.33254) (xy 20.958048 -226.838002)
			(xy 20.958382 -226.832565) (xy 20.966073 -226.824879) (xy 20.97151 -226.82454) (xy 21.487638 -226.82454)
			(xy 21.495447 -226.82421) (xy 21.510319 -226.819436) (xy 21.516848 -226.815142) (xy 21.537937 -226.800793)
			(xy 21.583598 -226.778062) (xy 21.632204 -226.762603) (xy 21.682607 -226.75478) (xy 21.733613 -226.75478)
			(xy 21.784016 -226.762603) (xy 21.832622 -226.778062) (xy 21.878283 -226.800793) (xy 21.899372 -226.815142)
			(xy 21.905914 -226.819416) (xy 21.920776 -226.824211) (xy 21.928582 -226.82454) (xy 22.44471 -226.82454)
			(xy 22.450076 -226.825044) (xy 22.457661 -226.832636) (xy 22.458172 -226.838002) (xy 22.458172 -227.33254)
			(xy 28.502356 -227.33254) (xy 28.502356 -226.838002) (xy 28.502826 -226.832694) (xy 28.510266 -226.825122)
			(xy 28.515564 -226.82454) (xy 29.031692 -226.82454) (xy 29.039503 -226.824233) (xy 29.054375 -226.819443)
			(xy 29.060902 -226.815142) (xy 29.081991 -226.800793) (xy 29.127652 -226.778062) (xy 29.176258 -226.762603)
			(xy 29.226661 -226.75478) (xy 29.277667 -226.75478) (xy 29.32807 -226.762603) (xy 29.376676 -226.778062)
			(xy 29.422337 -226.800793) (xy 29.443426 -226.815142) (xy 29.449956 -226.819436) (xy 29.464827 -226.824218)
			(xy 29.472636 -226.82454) (xy 29.988764 -226.82454) (xy 29.994103 -226.824856) (xy 30.001649 -226.832409)
			(xy 30.001972 -226.837748) (xy 30.001972 -226.838256) (xy 30.001972 -227.33254) (xy 36.046156 -227.33254)
			(xy 36.046156 -226.838002) (xy 36.046626 -226.832694) (xy 36.054066 -226.825122) (xy 36.059364 -226.82454)
			(xy 36.575492 -226.82454) (xy 36.583303 -226.824233) (xy 36.598175 -226.819443) (xy 36.604702 -226.815142)
			(xy 36.625791 -226.800793) (xy 36.671452 -226.778062) (xy 36.720058 -226.762603) (xy 36.770461 -226.75478)
			(xy 36.821467 -226.75478) (xy 36.87187 -226.762603) (xy 36.920476 -226.778062) (xy 36.966137 -226.800793)
			(xy 36.987226 -226.815142) (xy 36.993756 -226.819436) (xy 37.008627 -226.824218) (xy 37.016436 -226.82454)
			(xy 37.532564 -226.82454) (xy 37.537903 -226.824856) (xy 37.545449 -226.832409) (xy 37.545772 -226.837748)
			(xy 37.545772 -226.838256) (xy 37.545772 -227.33254) (xy 43.589956 -227.33254) (xy 43.589956 -226.838002)
			(xy 43.590283 -226.832563) (xy 43.597979 -226.824876) (xy 43.603418 -226.82454) (xy 44.119546 -226.82454)
			(xy 44.127355 -226.824213) (xy 44.142227 -226.819437) (xy 44.148756 -226.815142) (xy 44.169845 -226.800793)
			(xy 44.215506 -226.778062) (xy 44.264112 -226.762603) (xy 44.314515 -226.75478) (xy 44.365521 -226.75478)
			(xy 44.415924 -226.762603) (xy 44.46453 -226.778062) (xy 44.510191 -226.800793) (xy 44.53128 -226.815142)
			(xy 44.53782 -226.819419) (xy 44.552683 -226.824212) (xy 44.56049 -226.82454) (xy 45.076618 -226.82454)
			(xy 45.081985 -226.825038) (xy 45.08957 -226.832635) (xy 45.09008 -226.838002) (xy 45.09008 -227.33254)
			(xy 51.134264 -227.33254) (xy 51.134264 -226.838002) (xy 51.134727 -226.832692) (xy 51.142172 -226.82512)
			(xy 51.147472 -226.82454) (xy 51.6636 -226.82454) (xy 51.671411 -226.824236) (xy 51.686283 -226.819444)
			(xy 51.69281 -226.815142) (xy 51.713899 -226.800793) (xy 51.75956 -226.778062) (xy 51.808166 -226.762603)
			(xy 51.858569 -226.75478) (xy 51.909575 -226.75478) (xy 51.959978 -226.762603) (xy 52.008584 -226.778062)
			(xy 52.054245 -226.800793) (xy 52.075334 -226.815142) (xy 52.081862 -226.819439) (xy 52.096735 -226.82422)
			(xy 52.104544 -226.82454) (xy 52.620672 -226.82454) (xy 52.626012 -226.82485) (xy 52.633558 -226.832407)
			(xy 52.63388 -226.837748) (xy 52.63388 -226.838256) (xy 52.63388 -227.33254) (xy 58.678064 -227.33254)
			(xy 58.678064 -226.838002) (xy 58.678383 -226.832561) (xy 58.686085 -226.824874) (xy 58.691526 -226.82454)
			(xy 60.164726 -226.82454) (xy 60.170093 -226.825033) (xy 60.177678 -226.832633) (xy 60.178188 -226.838002)
			(xy 60.178188 -227.33254) (xy 167.778176 -227.33254) (xy 167.778176 -226.838002) (xy 167.778629 -226.83269)
			(xy 167.78608 -226.825116) (xy 167.791384 -226.82454) (xy 169.264584 -226.82454) (xy 169.269926 -226.824842)
			(xy 169.277471 -226.832405) (xy 169.277792 -226.837748) (xy 169.277792 -227.33254) (xy 175.321976 -227.33254)
			(xy 175.321976 -226.838002) (xy 175.322285 -226.832558) (xy 175.329993 -226.82487) (xy 175.335438 -226.82454)
			(xy 175.851566 -226.82454) (xy 175.859376 -226.824222) (xy 175.874248 -226.81944) (xy 175.880776 -226.815142)
			(xy 175.901865 -226.800793) (xy 175.947526 -226.778062) (xy 175.996132 -226.762603) (xy 176.046535 -226.75478)
			(xy 176.097541 -226.75478) (xy 176.147944 -226.762603) (xy 176.19655 -226.778062) (xy 176.242211 -226.800793)
			(xy 176.2633 -226.815142) (xy 176.269836 -226.819426) (xy 176.284702 -226.824215) (xy 176.29251 -226.82454)
			(xy 176.808638 -226.82454) (xy 176.814007 -226.825026) (xy 176.82159 -226.832632) (xy 176.8221 -226.838002)
			(xy 176.8221 -227.33254) (xy 182.866284 -227.33254) (xy 182.866284 -226.838002) (xy 182.86673 -226.832688)
			(xy 182.874186 -226.825114) (xy 182.879492 -226.82454) (xy 183.39562 -226.82454) (xy 183.403432 -226.824245)
			(xy 183.418304 -226.819447) (xy 183.42483 -226.815142) (xy 183.445919 -226.800793) (xy 183.49158 -226.778062)
			(xy 183.540186 -226.762603) (xy 183.590589 -226.75478) (xy 183.641595 -226.75478) (xy 183.691998 -226.762603)
			(xy 183.740604 -226.778062) (xy 183.786265 -226.800793) (xy 183.807354 -226.815142) (xy 183.813878 -226.819447)
			(xy 183.828754 -226.824223) (xy 183.836564 -226.82454) (xy 184.352692 -226.82454) (xy 184.358035 -226.824837)
			(xy 184.365579 -226.832404) (xy 184.3659 -226.837748) (xy 184.3659 -226.838256) (xy 184.3659 -227.33254)
			(xy 190.410084 -227.33254) (xy 190.410084 -226.838002) (xy 190.410385 -226.832556) (xy 190.418099 -226.824868)
			(xy 190.423546 -226.82454) (xy 190.939674 -226.82454) (xy 190.947484 -226.824225) (xy 190.962356 -226.819441)
			(xy 190.968884 -226.815142) (xy 190.989973 -226.800793) (xy 191.035634 -226.778062) (xy 191.08424 -226.762603)
			(xy 191.134643 -226.75478) (xy 191.185649 -226.75478) (xy 191.236052 -226.762603) (xy 191.284658 -226.778062)
			(xy 191.330319 -226.800793) (xy 191.351408 -226.815142) (xy 191.357942 -226.819429) (xy 191.37281 -226.824216)
			(xy 191.380618 -226.82454) (xy 191.896746 -226.82454) (xy 191.902116 -226.82502) (xy 191.909699 -226.83263)
			(xy 191.910208 -226.838002) (xy 191.910208 -227.33254) (xy 197.954392 -227.33254) (xy 197.954392 -226.838002)
			(xy 197.954919 -226.832709) (xy 197.962319 -226.825141) (xy 197.9676 -226.82454) (xy 198.483728 -226.82454)
			(xy 198.49154 -226.824249) (xy 198.506412 -226.819448) (xy 198.512938 -226.815142) (xy 198.534027 -226.800793)
			(xy 198.579688 -226.778062) (xy 198.628294 -226.762603) (xy 198.678697 -226.75478) (xy 198.729703 -226.75478)
			(xy 198.780106 -226.762603) (xy 198.828712 -226.778062) (xy 198.874373 -226.800793) (xy 198.895462 -226.815142)
			(xy 198.902006 -226.819412) (xy 198.916866 -226.824209) (xy 198.924672 -226.82454) (xy 199.4408 -226.82454)
			(xy 199.446144 -226.824831) (xy 199.453688 -226.832403) (xy 199.454008 -226.837748) (xy 199.454008 -226.838256)
			(xy 199.454008 -227.33254) (xy 205.498192 -227.33254) (xy 205.498192 -226.838002) (xy 205.498719 -226.832709)
			(xy 205.506119 -226.825141) (xy 205.5114 -226.82454) (xy 206.027528 -226.82454) (xy 206.03534 -226.824249)
			(xy 206.050212 -226.819448) (xy 206.056738 -226.815142) (xy 206.077827 -226.800793) (xy 206.123488 -226.778062)
			(xy 206.172094 -226.762603) (xy 206.222497 -226.75478) (xy 206.273503 -226.75478) (xy 206.323906 -226.762603)
			(xy 206.372512 -226.778062) (xy 206.418173 -226.800793) (xy 206.439262 -226.815142) (xy 206.445806 -226.819412)
			(xy 206.460666 -226.824209) (xy 206.468472 -226.82454) (xy 206.9846 -226.82454) (xy 206.989944 -226.824831)
			(xy 206.997488 -226.832403) (xy 206.997808 -226.837748) (xy 206.997808 -226.838256) (xy 206.997808 -227.332286)
			(xy 268.898116 -227.332286) (xy 268.898116 -226.837748) (xy 268.898462 -226.832416) (xy 268.905993 -226.824871)
			(xy 268.911324 -226.82454) (xy 268.911832 -226.82454) (xy 269.427706 -226.82454) (xy 269.435517 -226.824239)
			(xy 269.450389 -226.819445) (xy 269.456916 -226.815142) (xy 269.478005 -226.800793) (xy 269.523666 -226.778062)
			(xy 269.572272 -226.762603) (xy 269.622675 -226.75478) (xy 269.673681 -226.75478) (xy 269.724084 -226.762603)
			(xy 269.77269 -226.778062) (xy 269.818351 -226.800793) (xy 269.83944 -226.815142) (xy 269.845967 -226.819442)
			(xy 269.86084 -226.824221) (xy 269.86865 -226.82454) (xy 270.384778 -226.82454) (xy 270.39008 -226.825038)
			(xy 270.397652 -226.832457) (xy 270.39824 -226.837748) (xy 270.39824 -227.332286) (xy 270.398225 -227.33254)
			(xy 276.442424 -227.33254) (xy 276.442424 -227.332032) (xy 276.442424 -226.837748) (xy 276.442762 -226.832414)
			(xy 276.450299 -226.824869) (xy 276.455632 -226.82454) (xy 276.97176 -226.82454) (xy 276.97957 -226.824219)
			(xy 276.994441 -226.819439) (xy 277.00097 -226.815142) (xy 277.022059 -226.800793) (xy 277.06772 -226.778062)
			(xy 277.116326 -226.762603) (xy 277.166729 -226.75478) (xy 277.217735 -226.75478) (xy 277.268138 -226.762603)
			(xy 277.316744 -226.778062) (xy 277.362405 -226.800793) (xy 277.383494 -226.815142) (xy 277.390031 -226.819424)
			(xy 277.404897 -226.824214) (xy 277.412704 -226.82454) (xy 277.928832 -226.82454) (xy 277.93418 -226.82481)
			(xy 277.941722 -226.832398) (xy 277.94204 -226.837748) (xy 277.94204 -227.332286) (xy 277.942017 -227.33254)
			(xy 283.986224 -227.33254) (xy 283.986224 -227.332032) (xy 283.986224 -226.837748) (xy 283.986562 -226.832414)
			(xy 283.994099 -226.824869) (xy 283.999432 -226.82454) (xy 284.51556 -226.82454) (xy 284.52337 -226.824219)
			(xy 284.538241 -226.819439) (xy 284.54477 -226.815142) (xy 284.565859 -226.800793) (xy 284.61152 -226.778062)
			(xy 284.660126 -226.762603) (xy 284.710529 -226.75478) (xy 284.761535 -226.75478) (xy 284.811938 -226.762603)
			(xy 284.860544 -226.778062) (xy 284.906205 -226.800793) (xy 284.927294 -226.815142) (xy 284.933831 -226.819424)
			(xy 284.948697 -226.824214) (xy 284.956504 -226.82454) (xy 285.472632 -226.82454) (xy 285.47798 -226.82481)
			(xy 285.485522 -226.832398) (xy 285.48584 -226.837748) (xy 285.48584 -227.332286) (xy 291.530024 -227.332286)
			(xy 291.530024 -226.837748) (xy 291.530362 -226.832414) (xy 291.537899 -226.824869) (xy 291.543232 -226.82454)
			(xy 291.54374 -226.82454) (xy 292.059614 -226.82454) (xy 292.067426 -226.824243) (xy 292.082298 -226.819447)
			(xy 292.088824 -226.815142) (xy 292.109913 -226.800793) (xy 292.155574 -226.778062) (xy 292.20418 -226.762603)
			(xy 292.254583 -226.75478) (xy 292.305589 -226.75478) (xy 292.355992 -226.762603) (xy 292.404598 -226.778062)
			(xy 292.450259 -226.800793) (xy 292.471348 -226.815142) (xy 292.477873 -226.819445) (xy 292.492748 -226.824222)
			(xy 292.500558 -226.82454) (xy 293.016686 -226.82454) (xy 293.021988 -226.825033) (xy 293.02956 -226.832456)
			(xy 293.030148 -226.837748) (xy 293.030148 -227.332286) (xy 293.030132 -227.33254) (xy 299.074332 -227.33254)
			(xy 299.074332 -227.332032) (xy 299.074332 -226.837748) (xy 299.074663 -226.832413) (xy 299.082205 -226.824866)
			(xy 299.08754 -226.82454) (xy 299.603668 -226.82454) (xy 299.611478 -226.824223) (xy 299.62635 -226.81944)
			(xy 299.632878 -226.815142) (xy 299.653967 -226.800793) (xy 299.699628 -226.778062) (xy 299.748234 -226.762603)
			(xy 299.798637 -226.75478) (xy 299.849643 -226.75478) (xy 299.900046 -226.762603) (xy 299.948652 -226.778062)
			(xy 299.994313 -226.800793) (xy 300.015402 -226.815142) (xy 300.021937 -226.819427) (xy 300.036804 -226.824215)
			(xy 300.044612 -226.82454) (xy 300.56074 -226.82454) (xy 300.56609 -226.824805) (xy 300.573631 -226.832397)
			(xy 300.573948 -226.837748) (xy 300.573948 -227.332286) (xy 306.618132 -227.332286) (xy 306.618132 -226.837748)
			(xy 306.618463 -226.832413) (xy 306.626005 -226.824866) (xy 306.63134 -226.82454) (xy 306.631848 -226.82454)
			(xy 308.104794 -226.82454) (xy 308.110097 -226.825027) (xy 308.117669 -226.832455) (xy 308.118256 -226.837748)
			(xy 308.118256 -227.332286) (xy 308.11824 -227.33254) (xy 415.718244 -227.33254) (xy 415.718244 -226.837748)
			(xy 415.718822 -226.832502) (xy 415.72621 -226.82506) (xy 415.731452 -226.82454) (xy 417.204652 -226.82454)
			(xy 417.209989 -226.824864) (xy 417.217536 -226.832411) (xy 417.21786 -226.837748) (xy 417.21786 -227.332286)
			(xy 423.262044 -227.332286) (xy 423.262044 -226.837748) (xy 423.262622 -226.832502) (xy 423.27001 -226.82506)
			(xy 423.275252 -226.82454) (xy 423.27576 -226.82454) (xy 423.791634 -226.82454) (xy 423.799443 -226.824208)
			(xy 423.814315 -226.819436) (xy 423.820844 -226.815142) (xy 423.841933 -226.800793) (xy 423.887594 -226.778062)
			(xy 423.9362 -226.762603) (xy 423.986603 -226.75478) (xy 424.037609 -226.75478) (xy 424.088012 -226.762603)
			(xy 424.136618 -226.778062) (xy 424.182279 -226.800793) (xy 424.203368 -226.815142) (xy 424.209911 -226.819414)
			(xy 424.224772 -226.82421) (xy 424.232578 -226.82454) (xy 424.748706 -226.82454) (xy 424.754011 -226.825019)
			(xy 424.761582 -226.832453) (xy 424.762168 -226.837748) (xy 424.762168 -227.332286) (xy 424.762151 -227.33254)
			(xy 430.806352 -227.33254) (xy 430.806352 -227.332032) (xy 430.806352 -226.837748) (xy 430.806755 -226.832432)
			(xy 430.814246 -226.824891) (xy 430.81956 -226.82454) (xy 431.335688 -226.82454) (xy 431.343499 -226.824231)
			(xy 431.35837 -226.819443) (xy 431.364898 -226.815142) (xy 431.385987 -226.800793) (xy 431.431648 -226.778062)
			(xy 431.480254 -226.762603) (xy 431.530657 -226.75478) (xy 431.581663 -226.75478) (xy 431.632066 -226.762603)
			(xy 431.680672 -226.778062) (xy 431.726333 -226.800793) (xy 431.747422 -226.815142) (xy 431.753953 -226.819435)
			(xy 431.768823 -226.824218) (xy 431.776632 -226.82454) (xy 432.29276 -226.82454) (xy 432.298099 -226.824859)
			(xy 432.305645 -226.832409) (xy 432.305968 -226.837748) (xy 432.305968 -227.332286) (xy 438.350152 -227.332286)
			(xy 438.350152 -226.837748) (xy 438.350555 -226.832432) (xy 438.358046 -226.824891) (xy 438.36336 -226.82454)
			(xy 438.363868 -226.82454) (xy 438.879742 -226.82454) (xy 438.887551 -226.824212) (xy 438.902423 -226.819437)
			(xy 438.908952 -226.815142) (xy 438.930041 -226.800793) (xy 438.975702 -226.778062) (xy 439.024308 -226.762603)
			(xy 439.074711 -226.75478) (xy 439.125717 -226.75478) (xy 439.17612 -226.762603) (xy 439.224726 -226.778062)
			(xy 439.270387 -226.800793) (xy 439.291476 -226.815142) (xy 439.298017 -226.819417) (xy 439.31288 -226.824211)
			(xy 439.320686 -226.82454) (xy 439.836814 -226.82454) (xy 439.84212 -226.825014) (xy 439.84969 -226.832452)
			(xy 439.850276 -226.837748) (xy 439.850276 -227.332286) (xy 439.850251 -227.33254) (xy 445.89446 -227.33254)
			(xy 445.89446 -227.332032) (xy 445.89446 -226.837748) (xy 445.894856 -226.83243) (xy 445.902352 -226.824888)
			(xy 445.907668 -226.82454) (xy 446.423796 -226.82454) (xy 446.431607 -226.824235) (xy 446.446479 -226.819444)
			(xy 446.453006 -226.815142) (xy 446.474095 -226.800793) (xy 446.519756 -226.778062) (xy 446.568362 -226.762603)
			(xy 446.618765 -226.75478) (xy 446.669771 -226.75478) (xy 446.720174 -226.762603) (xy 446.76878 -226.778062)
			(xy 446.814441 -226.800793) (xy 446.83553 -226.815142) (xy 446.842059 -226.819438) (xy 446.856931 -226.824219)
			(xy 446.86474 -226.82454) (xy 447.380868 -226.82454) (xy 447.386208 -226.824853) (xy 447.393753 -226.832408)
			(xy 447.394076 -226.837748) (xy 447.394076 -227.332286) (xy 447.394052 -227.33254) (xy 453.43826 -227.33254)
			(xy 453.43826 -227.332032) (xy 453.43826 -226.837748) (xy 453.438656 -226.83243) (xy 453.446152 -226.824888)
			(xy 453.451468 -226.82454) (xy 453.967596 -226.82454) (xy 453.975407 -226.824235) (xy 453.990279 -226.819444)
			(xy 453.996806 -226.815142) (xy 454.017895 -226.800793) (xy 454.063556 -226.778062) (xy 454.112162 -226.762603)
			(xy 454.162565 -226.75478) (xy 454.213571 -226.75478) (xy 454.263974 -226.762603) (xy 454.31258 -226.778062)
			(xy 454.358241 -226.800793) (xy 454.37933 -226.815142) (xy 454.385859 -226.819438) (xy 454.400731 -226.824219)
			(xy 454.40854 -226.82454) (xy 454.924668 -226.82454) (xy 454.930008 -226.824853) (xy 454.937553 -226.832408)
			(xy 454.937876 -226.837748) (xy 454.937876 -227.332286) (xy 454.937369 -227.337585) (xy 454.929955 -227.345156)
			(xy 454.924668 -227.345748) (xy 454.408794 -227.345748) (xy 454.400983 -227.346051) (xy 454.386111 -227.350843)
			(xy 454.379584 -227.355146) (xy 454.358464 -227.369498) (xy 454.31274 -227.392224) (xy 454.264066 -227.407653)
			(xy 454.213599 -227.415419) (xy 454.188068 -227.415852) (xy 454.162537 -227.415434) (xy 454.112072 -227.407653)
			(xy 454.0634 -227.392218) (xy 454.017673 -227.369496) (xy 453.996552 -227.355146) (xy 453.990028 -227.350842)
			(xy 453.975152 -227.346066) (xy 453.967342 -227.345748) (xy 453.451468 -227.345748) (xy 453.446211 -227.345231)
			(xy 453.438773 -227.337797) (xy 453.43826 -227.33254) (xy 447.394052 -227.33254) (xy 447.393569 -227.337585)
			(xy 447.386155 -227.345156) (xy 447.380868 -227.345748) (xy 446.864994 -227.345748) (xy 446.857183 -227.346051)
			(xy 446.842311 -227.350843) (xy 446.835784 -227.355146) (xy 446.814664 -227.369498) (xy 446.76894 -227.392224)
			(xy 446.720266 -227.407653) (xy 446.669799 -227.415419) (xy 446.644268 -227.415852) (xy 446.618737 -227.415434)
			(xy 446.568272 -227.407653) (xy 446.5196 -227.392218) (xy 446.473873 -227.369496) (xy 446.452752 -227.355146)
			(xy 446.446228 -227.350842) (xy 446.431352 -227.346066) (xy 446.423542 -227.345748) (xy 445.907668 -227.345748)
			(xy 445.902411 -227.345231) (xy 445.894973 -227.337797) (xy 445.89446 -227.33254) (xy 439.850251 -227.33254)
			(xy 439.849742 -227.337645) (xy 439.842172 -227.345231) (xy 439.836814 -227.345748) (xy 439.32094 -227.345748)
			(xy 439.313131 -227.346071) (xy 439.298259 -227.35085) (xy 439.29173 -227.355146) (xy 439.270625 -227.369521)
			(xy 439.224895 -227.392242) (xy 439.176217 -227.407665) (xy 439.125746 -227.415423) (xy 439.100214 -227.415852)
			(xy 439.074684 -227.415411) (xy 439.02422 -227.407637) (xy 438.975548 -227.392209) (xy 438.92982 -227.369493)
			(xy 438.908698 -227.355146) (xy 438.902163 -227.35086) (xy 438.887296 -227.346073) (xy 438.879488 -227.345748)
			(xy 438.363614 -227.345748) (xy 438.358178 -227.34541) (xy 438.35049 -227.337722) (xy 438.350152 -227.332286)
			(xy 432.305968 -227.332286) (xy 432.305468 -227.337587) (xy 432.29805 -227.345158) (xy 432.29276 -227.345748)
			(xy 431.776886 -227.345748) (xy 431.769074 -227.346047) (xy 431.754203 -227.350842) (xy 431.747676 -227.355146)
			(xy 431.726558 -227.369501) (xy 431.680833 -227.392227) (xy 431.632159 -227.407655) (xy 431.581691 -227.41542)
			(xy 431.55616 -227.415852) (xy 431.530629 -227.415438) (xy 431.480164 -227.407655) (xy 431.431492 -227.39222)
			(xy 431.385765 -227.369497) (xy 431.364644 -227.355146) (xy 431.358121 -227.350839) (xy 431.343245 -227.346065)
			(xy 431.335434 -227.345748) (xy 430.81956 -227.345748) (xy 430.814302 -227.345236) (xy 430.806864 -227.337798)
			(xy 430.806352 -227.33254) (xy 424.762151 -227.33254) (xy 424.761812 -227.337717) (xy 424.754137 -227.345404)
			(xy 424.748706 -227.345748) (xy 424.232832 -227.345748) (xy 424.225022 -227.346067) (xy 424.210151 -227.350849)
			(xy 424.203622 -227.355146) (xy 424.182491 -227.369481) (xy 424.136771 -227.392211) (xy 424.0881 -227.407645)
			(xy 424.037636 -227.415416) (xy 424.012106 -227.415852) (xy 423.986576 -227.415415) (xy 423.936112 -227.407639)
			(xy 423.887439 -227.392211) (xy 423.841712 -227.369494) (xy 423.82059 -227.355146) (xy 423.814057 -227.350857)
			(xy 423.799188 -227.346072) (xy 423.79138 -227.345748) (xy 423.275506 -227.345748) (xy 423.270069 -227.345415)
			(xy 423.262381 -227.337724) (xy 423.262044 -227.332286) (xy 417.21786 -227.332286) (xy 417.217367 -227.337588)
			(xy 417.209944 -227.34516) (xy 417.204652 -227.345748) (xy 415.731452 -227.345748) (xy 415.726193 -227.345241)
			(xy 415.718756 -227.337799) (xy 415.718244 -227.33254) (xy 308.11824 -227.33254) (xy 308.117911 -227.33772)
			(xy 308.110228 -227.345407) (xy 308.104794 -227.345748) (xy 306.631594 -227.345748) (xy 306.626155 -227.345423)
			(xy 306.618469 -227.337725) (xy 306.618132 -227.332286) (xy 300.573948 -227.332286) (xy 300.573466 -227.337591)
			(xy 300.566035 -227.345164) (xy 300.56074 -227.345748) (xy 300.044866 -227.345748) (xy 300.037058 -227.346082)
			(xy 300.022186 -227.350853) (xy 300.015656 -227.355146) (xy 299.994544 -227.36951) (xy 299.948817 -227.392233)
			(xy 299.90014 -227.407659) (xy 299.849672 -227.415421) (xy 299.82414 -227.415852) (xy 299.79861 -227.415398)
			(xy 299.748147 -227.407628) (xy 299.699475 -227.392204) (xy 299.653746 -227.369492) (xy 299.632624 -227.355146)
			(xy 299.626084 -227.35087) (xy 299.611221 -227.346077) (xy 299.603414 -227.345748) (xy 299.08754 -227.345748)
			(xy 299.082292 -227.345183) (xy 299.074849 -227.337785) (xy 299.074332 -227.33254) (xy 293.030132 -227.33254)
			(xy 293.02981 -227.337722) (xy 293.022122 -227.34541) (xy 293.016686 -227.345748) (xy 292.500812 -227.345748)
			(xy 292.493002 -227.346059) (xy 292.47813 -227.350846) (xy 292.471602 -227.355146) (xy 292.450477 -227.36949)
			(xy 292.404754 -227.392218) (xy 292.356082 -227.40765) (xy 292.305617 -227.415418) (xy 292.280086 -227.415852)
			(xy 292.254555 -227.415425) (xy 292.204091 -227.407646) (xy 292.155419 -227.392215) (xy 292.109691 -227.369495)
			(xy 292.08857 -227.355146) (xy 292.082042 -227.350849) (xy 292.067169 -227.346069) (xy 292.05936 -227.345748)
			(xy 291.543486 -227.345748) (xy 291.538117 -227.345257) (xy 291.530531 -227.337656) (xy 291.530024 -227.332286)
			(xy 285.48584 -227.332286) (xy 285.485365 -227.337593) (xy 285.477929 -227.345166) (xy 285.472632 -227.345748)
			(xy 284.956758 -227.345748) (xy 284.948949 -227.346078) (xy 284.934077 -227.350852) (xy 284.927548 -227.355146)
			(xy 284.906438 -227.369513) (xy 284.86071 -227.392236) (xy 284.812033 -227.407661) (xy 284.761564 -227.415422)
			(xy 284.736032 -227.415852) (xy 284.710502 -227.415402) (xy 284.660039 -227.40763) (xy 284.611366 -227.392205)
			(xy 284.565638 -227.369492) (xy 284.544516 -227.355146) (xy 284.537977 -227.350867) (xy 284.523113 -227.346076)
			(xy 284.515306 -227.345748) (xy 283.999432 -227.345748) (xy 283.994183 -227.345188) (xy 283.98674 -227.337787)
			(xy 283.986224 -227.33254) (xy 277.942017 -227.33254) (xy 277.941565 -227.337593) (xy 277.934129 -227.345166)
			(xy 277.928832 -227.345748) (xy 277.412958 -227.345748) (xy 277.405149 -227.346078) (xy 277.390277 -227.350852)
			(xy 277.383748 -227.355146) (xy 277.362638 -227.369513) (xy 277.31691 -227.392236) (xy 277.268233 -227.407661)
			(xy 277.217764 -227.415422) (xy 277.192232 -227.415852) (xy 277.166702 -227.415402) (xy 277.116239 -227.40763)
			(xy 277.067566 -227.392205) (xy 277.021838 -227.369492) (xy 277.000716 -227.355146) (xy 276.994177 -227.350867)
			(xy 276.979313 -227.346076) (xy 276.971506 -227.345748) (xy 276.455632 -227.345748) (xy 276.450383 -227.345188)
			(xy 276.44294 -227.337787) (xy 276.442424 -227.33254) (xy 270.398225 -227.33254) (xy 270.397909 -227.337724)
			(xy 270.390216 -227.345412) (xy 270.384778 -227.345748) (xy 269.868904 -227.345748) (xy 269.861093 -227.346056)
			(xy 269.846222 -227.350845) (xy 269.839694 -227.355146) (xy 269.818571 -227.369493) (xy 269.772848 -227.392221)
			(xy 269.724175 -227.407651) (xy 269.673709 -227.415419) (xy 269.648178 -227.415852) (xy 269.622647 -227.415429)
			(xy 269.572183 -227.407649) (xy 269.52351 -227.392216) (xy 269.477783 -227.369496) (xy 269.456662 -227.355146)
			(xy 269.450135 -227.350846) (xy 269.435262 -227.346068) (xy 269.427452 -227.345748) (xy 268.911578 -227.345748)
			(xy 268.906208 -227.345263) (xy 268.898623 -227.337657) (xy 268.898116 -227.332286) (xy 206.997808 -227.332286)
			(xy 206.997808 -227.33254) (xy 206.997332 -227.337808) (xy 206.989869 -227.345248) (xy 206.9846 -227.345748)
			(xy 206.468726 -227.345748) (xy 206.460849 -227.346012) (xy 206.445845 -227.350812) (xy 206.439262 -227.355146)
			(xy 206.418185 -227.369539) (xy 206.37254 -227.392367) (xy 206.323934 -227.407924) (xy 206.273517 -227.415843)
			(xy 206.248 -227.41636) (xy 206.222479 -227.415895) (xy 206.172051 -227.407994) (xy 206.123439 -227.392427)
			(xy 206.077802 -227.369565) (xy 206.056738 -227.355146) (xy 206.050137 -227.350847) (xy 206.035144 -227.34605)
			(xy 206.027274 -227.345748) (xy 205.5114 -227.345748) (xy 205.506147 -227.345209) (xy 205.498707 -227.337792)
			(xy 205.498192 -227.33254) (xy 199.454008 -227.33254) (xy 199.453532 -227.337808) (xy 199.446069 -227.345248)
			(xy 199.4408 -227.345748) (xy 198.924926 -227.345748) (xy 198.917049 -227.346012) (xy 198.902045 -227.350812)
			(xy 198.895462 -227.355146) (xy 198.874385 -227.369539) (xy 198.82874 -227.392367) (xy 198.780134 -227.407924)
			(xy 198.729717 -227.415843) (xy 198.7042 -227.41636) (xy 198.678679 -227.415895) (xy 198.628251 -227.407994)
			(xy 198.579639 -227.392427) (xy 198.534002 -227.369565) (xy 198.512938 -227.355146) (xy 198.506337 -227.350847)
			(xy 198.491344 -227.34605) (xy 198.483474 -227.345748) (xy 197.9676 -227.345748) (xy 197.962347 -227.345209)
			(xy 197.954907 -227.337792) (xy 197.954392 -227.33254) (xy 191.910208 -227.33254) (xy 191.909732 -227.337808)
			(xy 191.902269 -227.345248) (xy 191.897 -227.345748) (xy 191.896492 -227.345748) (xy 191.380872 -227.345748)
			(xy 191.372997 -227.346032) (xy 191.357993 -227.350818) (xy 191.351408 -227.355146) (xy 191.330346 -227.369562)
			(xy 191.284696 -227.392385) (xy 191.236085 -227.407936) (xy 191.185664 -227.415847) (xy 191.160146 -227.41636)
			(xy 191.134626 -227.415872) (xy 191.084198 -227.407978) (xy 191.035587 -227.392418) (xy 190.989949 -227.369562)
			(xy 190.968884 -227.355146) (xy 190.962295 -227.350827) (xy 190.947293 -227.346042) (xy 190.93942 -227.345748)
			(xy 190.423546 -227.345748) (xy 190.418244 -227.345245) (xy 190.41067 -227.33783) (xy 190.410084 -227.33254)
			(xy 184.3659 -227.33254) (xy 184.365431 -227.33781) (xy 184.357963 -227.34525) (xy 184.352692 -227.345748)
			(xy 183.836818 -227.345748) (xy 183.828945 -227.346051) (xy 183.813941 -227.350824) (xy 183.807354 -227.355146)
			(xy 183.78628 -227.369542) (xy 183.740634 -227.39237) (xy 183.692027 -227.407926) (xy 183.641609 -227.415844)
			(xy 183.616092 -227.41636) (xy 183.590573 -227.415849) (xy 183.540146 -227.407962) (xy 183.491534 -227.392408)
			(xy 183.445895 -227.369559) (xy 183.42483 -227.355146) (xy 183.418231 -227.350844) (xy 183.403237 -227.346049)
			(xy 183.395366 -227.345748) (xy 182.879492 -227.345748) (xy 182.874238 -227.345215) (xy 182.866798 -227.337793)
			(xy 182.866284 -227.33254) (xy 176.8221 -227.33254) (xy 176.821631 -227.33781) (xy 176.814163 -227.34525)
			(xy 176.808892 -227.345748) (xy 176.808384 -227.345748) (xy 176.292764 -227.345748) (xy 176.284889 -227.346028)
			(xy 176.269885 -227.350817) (xy 176.2633 -227.355146) (xy 176.242213 -227.369522) (xy 176.196571 -227.392354)
			(xy 176.147968 -227.407916) (xy 176.097554 -227.41584) (xy 176.072038 -227.41636) (xy 176.046518 -227.415876)
			(xy 175.99609 -227.407981) (xy 175.947478 -227.392419) (xy 175.90184 -227.369562) (xy 175.880776 -227.355146)
			(xy 175.874189 -227.350823) (xy 175.859186 -227.346041) (xy 175.851312 -227.345748) (xy 175.335438 -227.345748)
			(xy 175.330136 -227.34525) (xy 175.322562 -227.337831) (xy 175.321976 -227.33254) (xy 169.277792 -227.33254)
			(xy 169.27733 -227.337812) (xy 169.269858 -227.345253) (xy 169.264584 -227.345748) (xy 167.791384 -227.345748)
			(xy 167.786129 -227.34522) (xy 167.778689 -227.337794) (xy 167.778176 -227.33254) (xy 60.178188 -227.33254)
			(xy 60.17773 -227.337813) (xy 60.170255 -227.345254) (xy 60.16498 -227.345748) (xy 60.164472 -227.345748)
			(xy 58.691526 -227.345748) (xy 58.686222 -227.345258) (xy 58.678649 -227.337833) (xy 58.678064 -227.33254)
			(xy 52.63388 -227.33254) (xy 52.633429 -227.337814) (xy 52.625949 -227.345256) (xy 52.620672 -227.345748)
			(xy 52.104798 -227.345748) (xy 52.096924 -227.346043) (xy 52.08192 -227.350822) (xy 52.075334 -227.355146)
			(xy 52.054265 -227.369551) (xy 52.008617 -227.392376) (xy 51.960009 -227.40793) (xy 51.909589 -227.415845)
			(xy 51.884072 -227.41636) (xy 51.858552 -227.415859) (xy 51.808125 -227.407969) (xy 51.759514 -227.392412)
			(xy 51.713875 -227.36956) (xy 51.69281 -227.355146) (xy 51.686215 -227.350837) (xy 51.671218 -227.346046)
			(xy 51.663346 -227.345748) (xy 51.147472 -227.345748) (xy 51.142215 -227.345228) (xy 51.134777 -227.337796)
			(xy 51.134264 -227.33254) (xy 45.09008 -227.33254) (xy 45.089629 -227.337814) (xy 45.082149 -227.345256)
			(xy 45.076872 -227.345748) (xy 45.076364 -227.345748) (xy 44.560744 -227.345748) (xy 44.552868 -227.346019)
			(xy 44.537864 -227.350814) (xy 44.53128 -227.355146) (xy 44.510198 -227.369531) (xy 44.464555 -227.392361)
			(xy 44.41595 -227.407921) (xy 44.365534 -227.415842) (xy 44.340018 -227.41636) (xy 44.314497 -227.415886)
			(xy 44.264069 -227.407988) (xy 44.215458 -227.392423) (xy 44.16982 -227.369564) (xy 44.148756 -227.355146)
			(xy 44.142173 -227.350816) (xy 44.127167 -227.346038) (xy 44.119292 -227.345748) (xy 43.603418 -227.345748)
			(xy 43.598113 -227.345264) (xy 43.59054 -227.337835) (xy 43.589956 -227.33254) (xy 37.545772 -227.33254)
			(xy 37.545328 -227.337816) (xy 37.537843 -227.345259) (xy 37.532564 -227.345748) (xy 37.01669 -227.345748)
			(xy 37.008816 -227.346039) (xy 36.993812 -227.350821) (xy 36.987226 -227.355146) (xy 36.966159 -227.369554)
			(xy 36.920511 -227.392379) (xy 36.871901 -227.407932) (xy 36.821482 -227.415846) (xy 36.795964 -227.41636)
			(xy 36.770444 -227.415863) (xy 36.720017 -227.407972) (xy 36.671405 -227.392414) (xy 36.625767 -227.369561)
			(xy 36.604702 -227.355146) (xy 36.598109 -227.350833) (xy 36.58311 -227.346044) (xy 36.575238 -227.345748)
			(xy 36.059364 -227.345748) (xy 36.054107 -227.345233) (xy 36.046668 -227.337797) (xy 36.046156 -227.33254)
			(xy 30.001972 -227.33254) (xy 30.001528 -227.337816) (xy 29.994043 -227.345259) (xy 29.988764 -227.345748)
			(xy 29.47289 -227.345748) (xy 29.465016 -227.346039) (xy 29.450012 -227.350821) (xy 29.443426 -227.355146)
			(xy 29.422359 -227.369554) (xy 29.376711 -227.392379) (xy 29.328101 -227.407932) (xy 29.277682 -227.415846)
			(xy 29.252164 -227.41636) (xy 29.226644 -227.415863) (xy 29.176217 -227.407972) (xy 29.127605 -227.392414)
			(xy 29.081967 -227.369561) (xy 29.060902 -227.355146) (xy 29.054309 -227.350833) (xy 29.03931 -227.346044)
			(xy 29.031438 -227.345748) (xy 28.515564 -227.345748) (xy 28.510307 -227.345233) (xy 28.502868 -227.337797)
			(xy 28.502356 -227.33254) (xy 22.458172 -227.33254) (xy 22.457728 -227.337816) (xy 22.450243 -227.345259)
			(xy 22.444964 -227.345748) (xy 22.444456 -227.345748) (xy 21.928836 -227.345748) (xy 21.92096 -227.346016)
			(xy 21.905956 -227.350813) (xy 21.899372 -227.355146) (xy 21.878293 -227.369534) (xy 21.832648 -227.392364)
			(xy 21.784043 -227.407922) (xy 21.733627 -227.415842) (xy 21.70811 -227.41636) (xy 21.682589 -227.41589)
			(xy 21.632161 -227.40799) (xy 21.583549 -227.392425) (xy 21.537912 -227.369564) (xy 21.516848 -227.355146)
			(xy 21.510267 -227.350813) (xy 21.495259 -227.346036) (xy 21.487384 -227.345748) (xy 20.97151 -227.345748)
			(xy 20.966204 -227.345269) (xy 20.958632 -227.337836) (xy 20.958048 -227.33254) (xy 2.509012 -227.33254)
			(xy 2.509012 -228.182424) (xy 16.85798 -228.182424) (xy 16.85798 -227.687886) (xy 16.858274 -227.682439)
			(xy 16.865994 -227.674752) (xy 16.871442 -227.674424) (xy 17.38757 -227.674424) (xy 17.39538 -227.67411)
			(xy 17.410252 -227.669326) (xy 17.41678 -227.665026) (xy 17.437869 -227.650677) (xy 17.48353 -227.627946)
			(xy 17.532136 -227.612487) (xy 17.582539 -227.604664) (xy 17.633545 -227.604664) (xy 17.683948 -227.612487)
			(xy 17.732554 -227.627946) (xy 17.778215 -227.650677) (xy 17.799304 -227.665026) (xy 17.80584 -227.66931)
			(xy 17.820706 -227.674099) (xy 17.828514 -227.674424) (xy 18.344642 -227.674424) (xy 18.350008 -227.674921)
			(xy 18.35759 -227.682519) (xy 18.358104 -227.687886) (xy 18.358104 -228.182424) (xy 24.402288 -228.182424)
			(xy 24.402288 -227.687886) (xy 24.40272 -227.682569) (xy 24.410187 -227.674996) (xy 24.415496 -227.674424)
			(xy 24.931624 -227.674424) (xy 24.939436 -227.674133) (xy 24.954308 -227.669333) (xy 24.960834 -227.665026)
			(xy 24.981923 -227.650677) (xy 25.027584 -227.627946) (xy 25.07619 -227.612487) (xy 25.126593 -227.604664)
			(xy 25.177599 -227.604664) (xy 25.228002 -227.612487) (xy 25.276608 -227.627946) (xy 25.322269 -227.650677)
			(xy 25.343358 -227.665026) (xy 25.349882 -227.669331) (xy 25.364758 -227.674107) (xy 25.372568 -227.674424)
			(xy 25.888696 -227.674424) (xy 25.894035 -227.674733) (xy 25.901578 -227.682292) (xy 25.901904 -227.687632)
			(xy 25.901904 -227.68814) (xy 25.901904 -228.182424) (xy 31.946088 -228.182424) (xy 31.946088 -227.687886)
			(xy 31.94652 -227.682569) (xy 31.953987 -227.674996) (xy 31.959296 -227.674424) (xy 32.475424 -227.674424)
			(xy 32.483236 -227.674133) (xy 32.498108 -227.669333) (xy 32.504634 -227.665026) (xy 32.525723 -227.650677)
			(xy 32.571384 -227.627946) (xy 32.61999 -227.612487) (xy 32.670393 -227.604664) (xy 32.721399 -227.604664)
			(xy 32.771802 -227.612487) (xy 32.820408 -227.627946) (xy 32.866069 -227.650677) (xy 32.887158 -227.665026)
			(xy 32.893682 -227.669331) (xy 32.908558 -227.674107) (xy 32.916368 -227.674424) (xy 33.432496 -227.674424)
			(xy 33.437835 -227.674733) (xy 33.445378 -227.682292) (xy 33.445704 -227.687632) (xy 33.445704 -227.68814)
			(xy 33.445704 -228.182424) (xy 39.489888 -228.182424) (xy 39.489888 -227.687886) (xy 39.490436 -227.682532)
			(xy 39.497998 -227.674951) (xy 39.50335 -227.674424) (xy 40.019478 -227.674424) (xy 40.027289 -227.674114)
			(xy 40.042161 -227.669327) (xy 40.048688 -227.665026) (xy 40.069777 -227.650677) (xy 40.115438 -227.627946)
			(xy 40.164044 -227.612487) (xy 40.214447 -227.604664) (xy 40.265453 -227.604664) (xy 40.315856 -227.612487)
			(xy 40.364462 -227.627946) (xy 40.410123 -227.650677) (xy 40.431212 -227.665026) (xy 40.437746 -227.669314)
			(xy 40.452614 -227.6741) (xy 40.460422 -227.674424) (xy 40.97655 -227.674424) (xy 40.981917 -227.674916)
			(xy 40.989498 -227.682518) (xy 40.990012 -227.687886) (xy 40.990012 -228.182424) (xy 47.034196 -228.182424)
			(xy 47.034196 -227.687886) (xy 47.034708 -227.68259) (xy 47.04212 -227.675022) (xy 47.047404 -227.674424)
			(xy 47.563532 -227.674424) (xy 47.571341 -227.674094) (xy 47.586213 -227.669321) (xy 47.592742 -227.665026)
			(xy 47.613831 -227.650677) (xy 47.659492 -227.627946) (xy 47.708098 -227.612487) (xy 47.758501 -227.604664)
			(xy 47.809507 -227.604664) (xy 47.85991 -227.612487) (xy 47.908516 -227.627946) (xy 47.954177 -227.650677)
			(xy 47.975266 -227.665026) (xy 47.98181 -227.669296) (xy 47.99667 -227.674094) (xy 48.004476 -227.674424)
			(xy 48.520604 -227.674424) (xy 48.525945 -227.674727) (xy 48.533487 -227.682291) (xy 48.533812 -227.687632)
			(xy 48.533812 -227.68814) (xy 48.533812 -228.182424) (xy 54.577996 -228.182424) (xy 54.577996 -227.687886)
			(xy 54.578537 -227.682531) (xy 54.586104 -227.674948) (xy 54.591458 -227.674424) (xy 56.064658 -227.674424)
			(xy 56.070084 -227.674806) (xy 56.077771 -227.682462) (xy 56.07812 -227.687886) (xy 56.07812 -228.182424)
			(xy 163.678108 -228.182424) (xy 163.678108 -227.687886) (xy 163.67861 -227.682588) (xy 163.686029 -227.675019)
			(xy 163.691316 -227.674424) (xy 165.164516 -227.674424) (xy 165.169858 -227.674719) (xy 165.1774 -227.682288)
			(xy 165.177724 -227.687632) (xy 165.177724 -227.68814) (xy 165.177724 -228.182424) (xy 171.221908 -228.182424)
			(xy 171.221908 -227.687886) (xy 171.222438 -227.682528) (xy 171.230012 -227.674945) (xy 171.23537 -227.674424)
			(xy 171.751498 -227.674424) (xy 171.759309 -227.674122) (xy 171.774181 -227.669329) (xy 171.780708 -227.665026)
			(xy 171.801797 -227.650677) (xy 171.847458 -227.627946) (xy 171.896064 -227.612487) (xy 171.946467 -227.604664)
			(xy 171.997473 -227.604664) (xy 172.047876 -227.612487) (xy 172.096482 -227.627946) (xy 172.142143 -227.650677)
			(xy 172.163232 -227.665026) (xy 172.169761 -227.669321) (xy 172.184633 -227.674103) (xy 172.192442 -227.674424)
			(xy 172.70857 -227.674424) (xy 172.713997 -227.674798) (xy 172.721684 -227.68246) (xy 172.722032 -227.687886)
			(xy 172.722032 -228.182424) (xy 178.766216 -228.182424) (xy 178.766216 -227.687886) (xy 178.766711 -227.682586)
			(xy 178.774134 -227.675017) (xy 178.779424 -227.674424) (xy 179.295552 -227.674424) (xy 179.303362 -227.674103)
			(xy 179.318234 -227.669323) (xy 179.324762 -227.665026) (xy 179.345851 -227.650677) (xy 179.391512 -227.627946)
			(xy 179.440118 -227.612487) (xy 179.490521 -227.604664) (xy 179.541527 -227.604664) (xy 179.59193 -227.612487)
			(xy 179.640536 -227.627946) (xy 179.686197 -227.650677) (xy 179.707286 -227.665026) (xy 179.713826 -227.669304)
			(xy 179.728689 -227.674096) (xy 179.736496 -227.674424) (xy 180.252624 -227.674424) (xy 180.257967 -227.674714)
			(xy 180.265509 -227.682287) (xy 180.265832 -227.687632) (xy 180.265832 -227.68814) (xy 180.265832 -228.182424)
			(xy 186.310016 -228.182424) (xy 186.310016 -227.687886) (xy 186.310539 -227.682526) (xy 186.318118 -227.674942)
			(xy 186.323478 -227.674424) (xy 186.839606 -227.674424) (xy 186.847418 -227.674126) (xy 186.862289 -227.66933)
			(xy 186.868816 -227.665026) (xy 186.889905 -227.650677) (xy 186.935566 -227.627946) (xy 186.984172 -227.612487)
			(xy 187.034575 -227.604664) (xy 187.085581 -227.604664) (xy 187.135984 -227.612487) (xy 187.18459 -227.627946)
			(xy 187.230251 -227.650677) (xy 187.25134 -227.665026) (xy 187.257868 -227.669324) (xy 187.27274 -227.674104)
			(xy 187.28055 -227.674424) (xy 187.796678 -227.674424) (xy 187.802106 -227.674793) (xy 187.809793 -227.682459)
			(xy 187.81014 -227.687886) (xy 187.81014 -228.182424) (xy 193.854324 -228.182424) (xy 193.854324 -227.687886)
			(xy 193.854812 -227.682584) (xy 193.86224 -227.675015) (xy 193.867532 -227.674424) (xy 194.38366 -227.674424)
			(xy 194.39147 -227.674106) (xy 194.406342 -227.669324) (xy 194.41287 -227.665026) (xy 194.433959 -227.650677)
			(xy 194.47962 -227.627946) (xy 194.528226 -227.612487) (xy 194.578629 -227.604664) (xy 194.629635 -227.604664)
			(xy 194.680038 -227.612487) (xy 194.728644 -227.627946) (xy 194.774305 -227.650677) (xy 194.795394 -227.665026)
			(xy 194.801932 -227.669307) (xy 194.816797 -227.674098) (xy 194.824604 -227.674424) (xy 195.340732 -227.674424)
			(xy 195.346006 -227.674877) (xy 195.353449 -227.682355) (xy 195.35394 -227.687632) (xy 195.35394 -227.68814)
			(xy 195.35394 -228.182424) (xy 201.398124 -228.182424) (xy 201.398124 -227.687886) (xy 201.398612 -227.682584)
			(xy 201.40604 -227.675015) (xy 201.411332 -227.674424) (xy 201.92746 -227.674424) (xy 201.93527 -227.674106)
			(xy 201.950142 -227.669324) (xy 201.95667 -227.665026) (xy 201.977759 -227.650677) (xy 202.02342 -227.627946)
			(xy 202.072026 -227.612487) (xy 202.122429 -227.604664) (xy 202.173435 -227.604664) (xy 202.223838 -227.612487)
			(xy 202.272444 -227.627946) (xy 202.318105 -227.650677) (xy 202.339194 -227.665026) (xy 202.345732 -227.669307)
			(xy 202.360597 -227.674098) (xy 202.368404 -227.674424) (xy 202.884532 -227.674424) (xy 202.889806 -227.674877)
			(xy 202.897249 -227.682355) (xy 202.89774 -227.687632) (xy 202.89774 -227.68814) (xy 202.89774 -228.18217)
			(xy 264.798048 -228.18217) (xy 264.798048 -227.687632) (xy 264.798611 -227.682383) (xy 264.806011 -227.674942)
			(xy 264.811256 -227.674424) (xy 264.811764 -227.674424) (xy 265.327638 -227.674424) (xy 265.335447 -227.674097)
			(xy 265.350319 -227.669322) (xy 265.356848 -227.665026) (xy 265.377937 -227.650677) (xy 265.423598 -227.627946)
			(xy 265.472204 -227.612487) (xy 265.522607 -227.604664) (xy 265.573613 -227.604664) (xy 265.624016 -227.612487)
			(xy 265.672622 -227.627946) (xy 265.718283 -227.650677) (xy 265.739372 -227.665026) (xy 265.745915 -227.669298)
			(xy 265.760776 -227.674094) (xy 265.768582 -227.674424) (xy 266.28471 -227.674424) (xy 266.290012 -227.674915)
			(xy 266.297581 -227.682341) (xy 266.298172 -227.687632) (xy 266.298172 -228.18217) (xy 266.298155 -228.182424)
			(xy 272.342356 -228.182424) (xy 272.342356 -228.181916) (xy 272.342356 -227.687632) (xy 272.342912 -227.682382)
			(xy 272.350316 -227.674939) (xy 272.355564 -227.674424) (xy 272.871692 -227.674424) (xy 272.879503 -227.67412)
			(xy 272.894375 -227.669329) (xy 272.900902 -227.665026) (xy 272.921991 -227.650677) (xy 272.967652 -227.627946)
			(xy 273.016258 -227.612487) (xy 273.066661 -227.604664) (xy 273.117667 -227.604664) (xy 273.16807 -227.612487)
			(xy 273.216676 -227.627946) (xy 273.262337 -227.650677) (xy 273.283426 -227.665026) (xy 273.289957 -227.669319)
			(xy 273.304827 -227.674102) (xy 273.312636 -227.674424) (xy 273.828764 -227.674424) (xy 273.834099 -227.674754)
			(xy 273.841644 -227.682297) (xy 273.841972 -227.687632) (xy 273.841972 -228.18217) (xy 273.841947 -228.182424)
			(xy 279.886156 -228.182424) (xy 279.886156 -228.181916) (xy 279.886156 -227.687632) (xy 279.886712 -227.682382)
			(xy 279.894116 -227.674939) (xy 279.899364 -227.674424) (xy 280.415492 -227.674424) (xy 280.423303 -227.67412)
			(xy 280.438175 -227.669329) (xy 280.444702 -227.665026) (xy 280.465791 -227.650677) (xy 280.511452 -227.627946)
			(xy 280.560058 -227.612487) (xy 280.610461 -227.604664) (xy 280.661467 -227.604664) (xy 280.71187 -227.612487)
			(xy 280.760476 -227.627946) (xy 280.806137 -227.650677) (xy 280.827226 -227.665026) (xy 280.833757 -227.669319)
			(xy 280.848627 -227.674102) (xy 280.856436 -227.674424) (xy 281.372564 -227.674424) (xy 281.377899 -227.674754)
			(xy 281.385444 -227.682297) (xy 281.385772 -227.687632) (xy 281.385772 -228.18217) (xy 287.429956 -228.18217)
			(xy 287.429956 -227.687632) (xy 287.430512 -227.682382) (xy 287.437916 -227.674939) (xy 287.443164 -227.674424)
			(xy 287.443672 -227.674424) (xy 287.959546 -227.674424) (xy 287.967355 -227.6741) (xy 287.982227 -227.669323)
			(xy 287.988756 -227.665026) (xy 288.009845 -227.650677) (xy 288.055506 -227.627946) (xy 288.104112 -227.612487)
			(xy 288.154515 -227.604664) (xy 288.205521 -227.604664) (xy 288.255924 -227.612487) (xy 288.30453 -227.627946)
			(xy 288.350191 -227.650677) (xy 288.37128 -227.665026) (xy 288.377821 -227.669301) (xy 288.392684 -227.674096)
			(xy 288.40049 -227.674424) (xy 288.916618 -227.674424) (xy 288.921921 -227.674909) (xy 288.92949 -227.682339)
			(xy 288.93008 -227.687632) (xy 288.93008 -228.18217) (xy 288.930062 -228.182424) (xy 294.974264 -228.182424)
			(xy 294.974264 -228.181916) (xy 294.974264 -227.687632) (xy 294.974646 -227.682311) (xy 294.982152 -227.67477)
			(xy 294.987472 -227.674424) (xy 295.5036 -227.674424) (xy 295.511411 -227.674123) (xy 295.526283 -227.66933)
			(xy 295.53281 -227.665026) (xy 295.553899 -227.650677) (xy 295.59956 -227.627946) (xy 295.648166 -227.612487)
			(xy 295.698569 -227.604664) (xy 295.749575 -227.604664) (xy 295.799978 -227.612487) (xy 295.848584 -227.627946)
			(xy 295.894245 -227.650677) (xy 295.915334 -227.665026) (xy 295.921863 -227.669322) (xy 295.936735 -227.674103)
			(xy 295.944544 -227.674424) (xy 296.460672 -227.674424) (xy 296.466008 -227.674749) (xy 296.473553 -227.682296)
			(xy 296.47388 -227.687632) (xy 296.47388 -228.18217) (xy 302.518064 -228.18217) (xy 302.518064 -227.687632)
			(xy 302.518446 -227.682311) (xy 302.525952 -227.67477) (xy 302.531272 -227.674424) (xy 304.004726 -227.674424)
			(xy 304.01003 -227.674904) (xy 304.017598 -227.682338) (xy 304.018188 -227.687632) (xy 304.018188 -228.18217)
			(xy 304.01817 -228.182424) (xy 411.618176 -228.182424) (xy 411.618176 -228.181916) (xy 411.618176 -227.687632)
			(xy 411.618547 -227.682308) (xy 411.626061 -227.674766) (xy 411.631384 -227.674424) (xy 413.104584 -227.674424)
			(xy 413.109922 -227.674741) (xy 413.117466 -227.682294) (xy 413.117792 -227.687632) (xy 413.117792 -228.18217)
			(xy 419.161976 -228.18217) (xy 419.161976 -227.687632) (xy 419.162347 -227.682308) (xy 419.169861 -227.674766)
			(xy 419.175184 -227.674424) (xy 419.175692 -227.674424) (xy 419.691566 -227.674424) (xy 419.699376 -227.674109)
			(xy 419.714248 -227.669325) (xy 419.720776 -227.665026) (xy 419.741865 -227.650677) (xy 419.787526 -227.627946)
			(xy 419.836132 -227.612487) (xy 419.886535 -227.604664) (xy 419.937541 -227.604664) (xy 419.987944 -227.612487)
			(xy 420.03655 -227.627946) (xy 420.082211 -227.650677) (xy 420.1033 -227.665026) (xy 420.109837 -227.669309)
			(xy 420.124703 -227.674098) (xy 420.13251 -227.674424) (xy 420.648638 -227.674424) (xy 420.653943 -227.674896)
			(xy 420.661511 -227.682336) (xy 420.6621 -227.687632) (xy 420.6621 -228.18217) (xy 420.662073 -228.182424)
			(xy 426.706284 -228.182424) (xy 426.706284 -228.181916) (xy 426.706284 -227.687632) (xy 426.706648 -227.682306)
			(xy 426.714167 -227.674764) (xy 426.719492 -227.674424) (xy 427.23562 -227.674424) (xy 427.243432 -227.674131)
			(xy 427.258304 -227.669332) (xy 427.26483 -227.665026) (xy 427.285919 -227.650677) (xy 427.33158 -227.627946)
			(xy 427.380186 -227.612487) (xy 427.430589 -227.604664) (xy 427.481595 -227.604664) (xy 427.531998 -227.612487)
			(xy 427.580604 -227.627946) (xy 427.626265 -227.650677) (xy 427.647354 -227.665026) (xy 427.653879 -227.66933)
			(xy 427.668754 -227.674106) (xy 427.676564 -227.674424) (xy 428.192692 -227.674424) (xy 428.198031 -227.674735)
			(xy 428.205574 -227.682292) (xy 428.2059 -227.687632) (xy 428.2059 -228.18217) (xy 434.250084 -228.18217)
			(xy 434.250084 -227.687632) (xy 434.250448 -227.682306) (xy 434.257967 -227.674764) (xy 434.263292 -227.674424)
			(xy 434.2638 -227.674424) (xy 434.779674 -227.674424) (xy 434.787484 -227.674112) (xy 434.802356 -227.669326)
			(xy 434.808884 -227.665026) (xy 434.829973 -227.650677) (xy 434.875634 -227.627946) (xy 434.92424 -227.612487)
			(xy 434.974643 -227.604664) (xy 435.025649 -227.604664) (xy 435.076052 -227.612487) (xy 435.124658 -227.627946)
			(xy 435.170319 -227.650677) (xy 435.191408 -227.665026) (xy 435.197943 -227.669312) (xy 435.21281 -227.6741)
			(xy 435.220618 -227.674424) (xy 435.736746 -227.674424) (xy 435.74204 -227.674957) (xy 435.749613 -227.682351)
			(xy 435.750208 -227.687632) (xy 435.750208 -228.18217) (xy 435.750181 -228.182424) (xy 441.794392 -228.182424)
			(xy 441.794392 -228.181916) (xy 441.794392 -227.687632) (xy 441.794748 -227.682304) (xy 441.802273 -227.674761)
			(xy 441.8076 -227.674424) (xy 442.323728 -227.674424) (xy 442.331541 -227.674135) (xy 442.346412 -227.669333)
			(xy 442.352938 -227.665026) (xy 442.374027 -227.650677) (xy 442.419688 -227.627946) (xy 442.468294 -227.612487)
			(xy 442.518697 -227.604664) (xy 442.569703 -227.604664) (xy 442.620106 -227.612487) (xy 442.668712 -227.627946)
			(xy 442.714373 -227.650677) (xy 442.735462 -227.665026) (xy 442.742007 -227.669294) (xy 442.756866 -227.674093)
			(xy 442.764672 -227.674424) (xy 443.2808 -227.674424) (xy 443.28614 -227.67473) (xy 443.293683 -227.682291)
			(xy 443.294008 -227.687632) (xy 443.294008 -228.18217) (xy 443.293982 -228.182424) (xy 449.338192 -228.182424)
			(xy 449.338192 -228.181916) (xy 449.338192 -227.687632) (xy 449.338548 -227.682304) (xy 449.346073 -227.674761)
			(xy 449.3514 -227.674424) (xy 449.867528 -227.674424) (xy 449.875341 -227.674135) (xy 449.890212 -227.669333)
			(xy 449.896738 -227.665026) (xy 449.917827 -227.650677) (xy 449.963488 -227.627946) (xy 450.012094 -227.612487)
			(xy 450.062497 -227.604664) (xy 450.113503 -227.604664) (xy 450.163906 -227.612487) (xy 450.212512 -227.627946)
			(xy 450.258173 -227.650677) (xy 450.279262 -227.665026) (xy 450.285807 -227.669294) (xy 450.300666 -227.674093)
			(xy 450.308472 -227.674424) (xy 450.8246 -227.674424) (xy 450.82994 -227.67473) (xy 450.837483 -227.682291)
			(xy 450.837808 -227.687632) (xy 450.837808 -228.18217) (xy 450.837262 -228.187459) (xy 450.829876 -228.195029)
			(xy 450.8246 -228.195632) (xy 450.308726 -228.195632) (xy 450.300916 -228.195952) (xy 450.286045 -228.200733)
			(xy 450.279516 -228.20503) (xy 450.258386 -228.219366) (xy 450.212665 -228.242096) (xy 450.163995 -228.25753)
			(xy 450.11353 -228.265301) (xy 450.088 -228.265736) (xy 450.062469 -228.265305) (xy 450.012005 -228.257528)
			(xy 449.963333 -228.242097) (xy 449.917605 -228.219379) (xy 449.896484 -228.20503) (xy 449.889953 -228.200737)
			(xy 449.875083 -228.195955) (xy 449.867274 -228.195632) (xy 449.3514 -228.195632) (xy 449.346143 -228.195108)
			(xy 449.338702 -228.18768) (xy 449.338192 -228.182424) (xy 443.293982 -228.182424) (xy 443.293462 -228.187459)
			(xy 443.286076 -228.195029) (xy 443.2808 -228.195632) (xy 442.764926 -228.195632) (xy 442.757116 -228.195952)
			(xy 442.742245 -228.200733) (xy 442.735716 -228.20503) (xy 442.714586 -228.219366) (xy 442.668865 -228.242096)
			(xy 442.620195 -228.25753) (xy 442.56973 -228.265301) (xy 442.5442 -228.265736) (xy 442.518669 -228.265305)
			(xy 442.468205 -228.257528) (xy 442.419533 -228.242097) (xy 442.373805 -228.219379) (xy 442.352684 -228.20503)
			(xy 442.346153 -228.200737) (xy 442.331283 -228.195955) (xy 442.323474 -228.195632) (xy 441.8076 -228.195632)
			(xy 441.802343 -228.195108) (xy 441.794902 -228.18768) (xy 441.794392 -228.182424) (xy 435.750181 -228.182424)
			(xy 435.749634 -228.187519) (xy 435.742092 -228.195104) (xy 435.736746 -228.195632) (xy 435.220872 -228.195632)
			(xy 435.21306 -228.195928) (xy 435.198189 -228.200726) (xy 435.191662 -228.20503) (xy 435.170547 -228.219389)
			(xy 435.124821 -228.242114) (xy 435.076146 -228.257542) (xy 435.025678 -228.265305) (xy 435.000146 -228.265736)
			(xy 434.974616 -228.265282) (xy 434.924153 -228.257512) (xy 434.87548 -228.242088) (xy 434.829752 -228.219376)
			(xy 434.80863 -228.20503) (xy 434.802089 -228.200755) (xy 434.787226 -228.195961) (xy 434.77942 -228.195632)
			(xy 434.263546 -228.195632) (xy 434.25811 -228.195287) (xy 434.250419 -228.187606) (xy 434.250084 -228.18217)
			(xy 428.2059 -228.18217) (xy 428.205362 -228.187461) (xy 428.19797 -228.195032) (xy 428.192692 -228.195632)
			(xy 427.676818 -228.195632) (xy 427.669008 -228.195948) (xy 427.654136 -228.200732) (xy 427.647608 -228.20503)
			(xy 427.62648 -228.219369) (xy 427.580759 -228.242099) (xy 427.532087 -228.257532) (xy 427.481622 -228.265301)
			(xy 427.456092 -228.265736) (xy 427.430561 -228.265309) (xy 427.380097 -228.257531) (xy 427.331424 -228.242099)
			(xy 427.285697 -228.219379) (xy 427.264576 -228.20503) (xy 427.258047 -228.200734) (xy 427.243175 -228.195954)
			(xy 427.235366 -228.195632) (xy 426.719492 -228.195632) (xy 426.714234 -228.195113) (xy 426.706793 -228.187681)
			(xy 426.706284 -228.182424) (xy 420.662073 -228.182424) (xy 420.661534 -228.187521) (xy 420.653987 -228.195107)
			(xy 420.648638 -228.195632) (xy 420.132764 -228.195632) (xy 420.124956 -228.195968) (xy 420.110084 -228.200738)
			(xy 420.103554 -228.20503) (xy 420.082441 -228.219393) (xy 420.036714 -228.242117) (xy 419.988038 -228.257543)
			(xy 419.93757 -228.265306) (xy 419.912038 -228.265736) (xy 419.886508 -228.265286) (xy 419.836045 -228.257515)
			(xy 419.787372 -228.24209) (xy 419.741644 -228.219376) (xy 419.720522 -228.20503) (xy 419.713983 -228.200752)
			(xy 419.699119 -228.19596) (xy 419.691312 -228.195632) (xy 419.175438 -228.195632) (xy 419.170001 -228.195292)
			(xy 419.162311 -228.187607) (xy 419.161976 -228.18217) (xy 413.117792 -228.18217) (xy 413.117261 -228.187463)
			(xy 413.109865 -228.195034) (xy 413.104584 -228.195632) (xy 411.631384 -228.195632) (xy 411.626125 -228.195119)
			(xy 411.618685 -228.187683) (xy 411.618176 -228.182424) (xy 304.01817 -228.182424) (xy 304.017803 -228.187594)
			(xy 304.010149 -228.19528) (xy 304.004726 -228.195632) (xy 302.531526 -228.195632) (xy 302.526087 -228.1953)
			(xy 302.518398 -228.187609) (xy 302.518064 -228.18217) (xy 296.47388 -228.18217) (xy 296.473359 -228.187466)
			(xy 296.465956 -228.195038) (xy 296.460672 -228.195632) (xy 295.944798 -228.195632) (xy 295.936987 -228.195939)
			(xy 295.922116 -228.200729) (xy 295.915588 -228.20503) (xy 295.894466 -228.219378) (xy 295.848742 -228.242106)
			(xy 295.800069 -228.257536) (xy 295.749603 -228.265303) (xy 295.724072 -228.265736) (xy 295.698541 -228.265319)
			(xy 295.648076 -228.257538) (xy 295.599404 -228.242103) (xy 295.553677 -228.219381) (xy 295.532556 -228.20503)
			(xy 295.526032 -228.200726) (xy 295.511156 -228.195951) (xy 295.503346 -228.195632) (xy 294.987472 -228.195632)
			(xy 294.982212 -228.195126) (xy 294.974772 -228.187685) (xy 294.974264 -228.182424) (xy 288.930062 -228.182424)
			(xy 288.929702 -228.187596) (xy 288.922043 -228.195283) (xy 288.916618 -228.195632) (xy 288.400744 -228.195632)
			(xy 288.392935 -228.195959) (xy 288.378063 -228.200735) (xy 288.371534 -228.20503) (xy 288.350427 -228.219401)
			(xy 288.304698 -228.242124) (xy 288.25602 -228.257548) (xy 288.20555 -228.265307) (xy 288.180018 -228.265736)
			(xy 288.154488 -228.265296) (xy 288.104024 -228.257522) (xy 288.055351 -228.242094) (xy 288.009624 -228.219378)
			(xy 287.988502 -228.20503) (xy 287.981967 -228.200744) (xy 287.9671 -228.195957) (xy 287.959292 -228.195632)
			(xy 287.443418 -228.195632) (xy 287.437978 -228.195306) (xy 287.430289 -228.18761) (xy 287.429956 -228.18217)
			(xy 281.385772 -228.18217) (xy 281.385258 -228.187468) (xy 281.37785 -228.19504) (xy 281.372564 -228.195632)
			(xy 280.85669 -228.195632) (xy 280.848879 -228.195936) (xy 280.834007 -228.200728) (xy 280.82748 -228.20503)
			(xy 280.80636 -228.219382) (xy 280.760636 -228.242108) (xy 280.711962 -228.257538) (xy 280.661495 -228.265304)
			(xy 280.635964 -228.265736) (xy 280.610433 -228.265323) (xy 280.559968 -228.257541) (xy 280.511295 -228.242105)
			(xy 280.465569 -228.219381) (xy 280.444448 -228.20503) (xy 280.437925 -228.200723) (xy 280.423049 -228.195949)
			(xy 280.415238 -228.195632) (xy 279.899364 -228.195632) (xy 279.894103 -228.195131) (xy 279.886664 -228.187686)
			(xy 279.886156 -228.182424) (xy 273.841947 -228.182424) (xy 273.841458 -228.187468) (xy 273.83405 -228.19504)
			(xy 273.828764 -228.195632) (xy 273.31289 -228.195632) (xy 273.305079 -228.195936) (xy 273.290207 -228.200728)
			(xy 273.28368 -228.20503) (xy 273.26256 -228.219382) (xy 273.216836 -228.242108) (xy 273.168162 -228.257538)
			(xy 273.117695 -228.265304) (xy 273.092164 -228.265736) (xy 273.066633 -228.265323) (xy 273.016168 -228.257541)
			(xy 272.967495 -228.242105) (xy 272.921769 -228.219381) (xy 272.900648 -228.20503) (xy 272.894125 -228.200723)
			(xy 272.879249 -228.195949) (xy 272.871438 -228.195632) (xy 272.355564 -228.195632) (xy 272.350303 -228.195131)
			(xy 272.342864 -228.187686) (xy 272.342356 -228.182424) (xy 266.298155 -228.182424) (xy 266.297801 -228.187598)
			(xy 266.290137 -228.195285) (xy 266.28471 -228.195632) (xy 265.768836 -228.195632) (xy 265.761027 -228.195956)
			(xy 265.746155 -228.200734) (xy 265.739626 -228.20503) (xy 265.718493 -228.219362) (xy 265.672773 -228.242093)
			(xy 265.624104 -228.257528) (xy 265.57364 -228.2653) (xy 265.54811 -228.265736) (xy 265.52258 -228.2653)
			(xy 265.472116 -228.257525) (xy 265.423443 -228.242095) (xy 265.377716 -228.219378) (xy 265.356594 -228.20503)
			(xy 265.350061 -228.200741) (xy 265.335192 -228.195956) (xy 265.327384 -228.195632) (xy 264.81151 -228.195632)
			(xy 264.806069 -228.195311) (xy 264.798381 -228.187611) (xy 264.798048 -228.18217) (xy 202.89774 -228.18217)
			(xy 202.89774 -228.182424) (xy 202.897224 -228.187682) (xy 202.88979 -228.195121) (xy 202.884532 -228.195632)
			(xy 202.368658 -228.195632) (xy 202.360783 -228.195912) (xy 202.345779 -228.200701) (xy 202.339194 -228.20503)
			(xy 202.318107 -228.219407) (xy 202.272466 -228.242239) (xy 202.223863 -228.257801) (xy 202.173448 -228.265725)
			(xy 202.147932 -228.266244) (xy 202.122412 -228.265747) (xy 202.071986 -228.257854) (xy 202.023374 -228.242295)
			(xy 201.977736 -228.219443) (xy 201.95667 -228.20503) (xy 201.950085 -228.200704) (xy 201.93508 -228.195923)
			(xy 201.927206 -228.195632) (xy 201.411332 -228.195632) (xy 201.40601 -228.195254) (xy 201.398469 -228.187745)
			(xy 201.398124 -228.182424) (xy 195.35394 -228.182424) (xy 195.353424 -228.187682) (xy 195.34599 -228.195121)
			(xy 195.340732 -228.195632) (xy 194.824858 -228.195632) (xy 194.816983 -228.195912) (xy 194.801979 -228.200701)
			(xy 194.795394 -228.20503) (xy 194.774307 -228.219407) (xy 194.728666 -228.242239) (xy 194.680063 -228.257801)
			(xy 194.629648 -228.265725) (xy 194.604132 -228.266244) (xy 194.578612 -228.265747) (xy 194.528186 -228.257854)
			(xy 194.479574 -228.242295) (xy 194.433936 -228.219443) (xy 194.41287 -228.20503) (xy 194.406285 -228.200704)
			(xy 194.39128 -228.195923) (xy 194.383406 -228.195632) (xy 193.867532 -228.195632) (xy 193.86221 -228.195254)
			(xy 193.854669 -228.187745) (xy 193.854324 -228.182424) (xy 187.81014 -228.182424) (xy 187.809624 -228.187682)
			(xy 187.80219 -228.195121) (xy 187.796932 -228.195632) (xy 187.796424 -228.195632) (xy 187.280804 -228.195632)
			(xy 187.272931 -228.195932) (xy 187.257927 -228.200708) (xy 187.25134 -228.20503) (xy 187.230268 -228.21943)
			(xy 187.184622 -228.242257) (xy 187.136014 -228.257813) (xy 187.085595 -228.265729) (xy 187.060078 -228.266244)
			(xy 187.034559 -228.265724) (xy 186.984134 -228.257838) (xy 186.935522 -228.242286) (xy 186.889882 -228.219441)
			(xy 186.868816 -228.20503) (xy 186.862221 -228.200721) (xy 186.847224 -228.19593) (xy 186.839352 -228.195632)
			(xy 186.323478 -228.195632) (xy 186.318165 -228.195188) (xy 186.310593 -228.187729) (xy 186.310016 -228.182424)
			(xy 180.265832 -228.182424) (xy 180.265324 -228.187684) (xy 180.257884 -228.195124) (xy 180.252624 -228.195632)
			(xy 179.73675 -228.195632) (xy 179.728875 -228.195909) (xy 179.713871 -228.2007) (xy 179.707286 -228.20503)
			(xy 179.686201 -228.21941) (xy 179.640559 -228.242242) (xy 179.591955 -228.257803) (xy 179.54154 -228.265725)
			(xy 179.516024 -228.266244) (xy 179.490504 -228.265751) (xy 179.440078 -228.257856) (xy 179.391466 -228.242297)
			(xy 179.345827 -228.219444) (xy 179.324762 -228.20503) (xy 179.318179 -228.200701) (xy 179.303172 -228.195922)
			(xy 179.295298 -228.195632) (xy 178.779424 -228.195632) (xy 178.77417 -228.195092) (xy 178.766727 -228.187676)
			(xy 178.766216 -228.182424) (xy 172.722032 -228.182424) (xy 172.721524 -228.187684) (xy 172.714084 -228.195124)
			(xy 172.708824 -228.195632) (xy 172.708316 -228.195632) (xy 172.192696 -228.195632) (xy 172.184822 -228.195929)
			(xy 172.169818 -228.200707) (xy 172.163232 -228.20503) (xy 172.142162 -228.219434) (xy 172.096515 -228.24226)
			(xy 172.047906 -228.257814) (xy 171.997487 -228.265729) (xy 171.97197 -228.266244) (xy 171.946451 -228.265728)
			(xy 171.896025 -228.25784) (xy 171.847414 -228.242288) (xy 171.801774 -228.219441) (xy 171.780708 -228.20503)
			(xy 171.774115 -228.200718) (xy 171.759116 -228.195929) (xy 171.751244 -228.195632) (xy 171.23537 -228.195632)
			(xy 171.230055 -228.195194) (xy 171.222484 -228.187731) (xy 171.221908 -228.182424) (xy 165.177724 -228.182424)
			(xy 165.177223 -228.187686) (xy 165.169778 -228.195126) (xy 165.164516 -228.195632) (xy 163.691316 -228.195632)
			(xy 163.686061 -228.195097) (xy 163.678619 -228.187678) (xy 163.678108 -228.182424) (xy 56.07812 -228.182424)
			(xy 56.077622 -228.187687) (xy 56.070175 -228.195127) (xy 56.064912 -228.195632) (xy 54.591458 -228.195632)
			(xy 54.586142 -228.195202) (xy 54.578572 -228.187733) (xy 54.577996 -228.182424) (xy 48.533812 -228.182424)
			(xy 48.533321 -228.187689) (xy 48.525869 -228.195129) (xy 48.520604 -228.195632) (xy 48.00473 -228.195632)
			(xy 47.996854 -228.1959) (xy 47.98185 -228.200698) (xy 47.975266 -228.20503) (xy 47.954187 -228.219419)
			(xy 47.908543 -228.242249) (xy 47.859937 -228.257807) (xy 47.809521 -228.265727) (xy 47.784004 -228.266244)
			(xy 47.758484 -228.265761) (xy 47.708057 -228.257863) (xy 47.659445 -228.242301) (xy 47.613807 -228.219445)
			(xy 47.592742 -228.20503) (xy 47.586163 -228.200693) (xy 47.571153 -228.195919) (xy 47.563278 -228.195632)
			(xy 47.047404 -228.195632) (xy 47.042148 -228.195105) (xy 47.034706 -228.187679) (xy 47.034196 -228.182424)
			(xy 40.990012 -228.182424) (xy 40.989521 -228.187689) (xy 40.982069 -228.195129) (xy 40.976804 -228.195632)
			(xy 40.976296 -228.195632) (xy 40.460676 -228.195632) (xy 40.452802 -228.19592) (xy 40.437798 -228.200704)
			(xy 40.431212 -228.20503) (xy 40.410148 -228.219442) (xy 40.364499 -228.242267) (xy 40.315888 -228.257819)
			(xy 40.265468 -228.265731) (xy 40.23995 -228.266244) (xy 40.214431 -228.265738) (xy 40.164005 -228.257847)
			(xy 40.115393 -228.242292) (xy 40.069754 -228.219442) (xy 40.048688 -228.20503) (xy 40.042099 -228.200711)
			(xy 40.027097 -228.195926) (xy 40.019224 -228.195632) (xy 39.50335 -228.195632) (xy 39.498045 -228.19514)
			(xy 39.49047 -228.187718) (xy 39.489888 -228.182424) (xy 33.445704 -228.182424) (xy 33.445221 -228.187691)
			(xy 33.437764 -228.195132) (xy 33.432496 -228.195632) (xy 32.916622 -228.195632) (xy 32.908749 -228.19594)
			(xy 32.893745 -228.20071) (xy 32.887158 -228.20503) (xy 32.866081 -228.219423) (xy 32.820436 -228.242251)
			(xy 32.77183 -228.257809) (xy 32.721413 -228.265727) (xy 32.695896 -228.266244) (xy 32.670375 -228.265765)
			(xy 32.619948 -228.257866) (xy 32.571337 -228.242303) (xy 32.525699 -228.219446) (xy 32.504634 -228.20503)
			(xy 32.498035 -228.200728) (xy 32.483041 -228.195933) (xy 32.47517 -228.195632) (xy 31.959296 -228.195632)
			(xy 31.954038 -228.195111) (xy 31.946597 -228.187681) (xy 31.946088 -228.182424) (xy 25.901904 -228.182424)
			(xy 25.901421 -228.187691) (xy 25.893964 -228.195132) (xy 25.888696 -228.195632) (xy 25.372822 -228.195632)
			(xy 25.364949 -228.19594) (xy 25.349945 -228.20071) (xy 25.343358 -228.20503) (xy 25.322281 -228.219423)
			(xy 25.276636 -228.242251) (xy 25.22803 -228.257809) (xy 25.177613 -228.265727) (xy 25.152096 -228.266244)
			(xy 25.126575 -228.265765) (xy 25.076148 -228.257866) (xy 25.027537 -228.242303) (xy 24.981899 -228.219446)
			(xy 24.960834 -228.20503) (xy 24.954235 -228.200728) (xy 24.939241 -228.195933) (xy 24.93137 -228.195632)
			(xy 24.415496 -228.195632) (xy 24.410238 -228.195111) (xy 24.402797 -228.187681) (xy 24.402288 -228.182424)
			(xy 18.358104 -228.182424) (xy 18.357621 -228.187691) (xy 18.350164 -228.195132) (xy 18.344896 -228.195632)
			(xy 18.344388 -228.195632) (xy 17.828768 -228.195632) (xy 17.820893 -228.195916) (xy 17.805889 -228.200702)
			(xy 17.799304 -228.20503) (xy 17.778214 -228.219403) (xy 17.732574 -228.242236) (xy 17.683972 -228.257799)
			(xy 17.633558 -228.265724) (xy 17.608042 -228.266244) (xy 17.582522 -228.265742) (xy 17.532096 -228.25785)
			(xy 17.483485 -228.242293) (xy 17.437846 -228.219443) (xy 17.41678 -228.20503) (xy 17.410193 -228.200708)
			(xy 17.395189 -228.195925) (xy 17.387316 -228.195632) (xy 16.871442 -228.195632) (xy 16.866136 -228.195146)
			(xy 16.858561 -228.187719) (xy 16.85798 -228.182424) (xy 2.509012 -228.182424) (xy 2.509012 -229.032562)
			(xy 20.958048 -229.032562) (xy 20.958048 -228.538024) (xy 20.958606 -228.532775) (xy 20.966009 -228.525333)
			(xy 20.971256 -228.524816) (xy 20.971764 -228.524816) (xy 21.487638 -228.524816) (xy 21.495447 -228.52449)
			(xy 21.510319 -228.519714) (xy 21.516848 -228.515418) (xy 21.537937 -228.501069) (xy 21.583598 -228.478338)
			(xy 21.632204 -228.462879) (xy 21.682607 -228.455056) (xy 21.733613 -228.455056) (xy 21.784016 -228.462879)
			(xy 21.832622 -228.478338) (xy 21.878283 -228.501069) (xy 21.899372 -228.515418) (xy 21.905915 -228.519689)
			(xy 21.920776 -228.524486) (xy 21.928582 -228.524816) (xy 22.44471 -228.524816) (xy 22.45001 -228.525314)
			(xy 22.457579 -228.532735) (xy 22.458172 -228.538024) (xy 22.458172 -229.032562) (xy 22.458154 -229.032816)
			(xy 28.502356 -229.032816) (xy 28.502356 -229.032308) (xy 28.502356 -228.538024) (xy 28.502907 -228.532773)
			(xy 28.510315 -228.525331) (xy 28.515564 -228.524816) (xy 29.031692 -228.524816) (xy 29.039503 -228.524513)
			(xy 29.054375 -228.519721) (xy 29.060902 -228.515418) (xy 29.081991 -228.501069) (xy 29.127652 -228.478338)
			(xy 29.176258 -228.462879) (xy 29.226661 -228.455056) (xy 29.277667 -228.455056) (xy 29.32807 -228.462879)
			(xy 29.376676 -228.478338) (xy 29.422337 -228.501069) (xy 29.443426 -228.515418) (xy 29.449957 -228.51971)
			(xy 29.464827 -228.524494) (xy 29.472636 -228.524816) (xy 29.988764 -228.524816) (xy 29.994097 -228.525153)
			(xy 30.001642 -228.532691) (xy 30.001972 -228.538024) (xy 30.001972 -229.032562) (xy 30.001947 -229.032816)
			(xy 36.046156 -229.032816) (xy 36.046156 -229.032308) (xy 36.046156 -228.538024) (xy 36.046707 -228.532773)
			(xy 36.054115 -228.525331) (xy 36.059364 -228.524816) (xy 36.575492 -228.524816) (xy 36.583303 -228.524513)
			(xy 36.598175 -228.519721) (xy 36.604702 -228.515418) (xy 36.625791 -228.501069) (xy 36.671452 -228.478338)
			(xy 36.720058 -228.462879) (xy 36.770461 -228.455056) (xy 36.821467 -228.455056) (xy 36.87187 -228.462879)
			(xy 36.920476 -228.478338) (xy 36.966137 -228.501069) (xy 36.987226 -228.515418) (xy 36.993757 -228.51971)
			(xy 37.008627 -228.524494) (xy 37.016436 -228.524816) (xy 37.532564 -228.524816) (xy 37.537897 -228.525153)
			(xy 37.545442 -228.532691) (xy 37.545772 -228.538024) (xy 37.545772 -229.032562) (xy 43.589956 -229.032562)
			(xy 43.589956 -228.538024) (xy 43.590507 -228.532773) (xy 43.597915 -228.525331) (xy 43.603164 -228.524816)
			(xy 43.603672 -228.524816) (xy 44.119546 -228.524816) (xy 44.127356 -228.524494) (xy 44.142228 -228.519715)
			(xy 44.148756 -228.515418) (xy 44.169845 -228.501069) (xy 44.215506 -228.478338) (xy 44.264112 -228.462879)
			(xy 44.314515 -228.455056) (xy 44.365521 -228.455056) (xy 44.415924 -228.462879) (xy 44.46453 -228.478338)
			(xy 44.510191 -228.501069) (xy 44.53128 -228.515418) (xy 44.537821 -228.519693) (xy 44.552684 -228.524487)
			(xy 44.56049 -228.524816) (xy 45.076618 -228.524816) (xy 45.081919 -228.525308) (xy 45.089488 -228.532734)
			(xy 45.09008 -228.538024) (xy 45.09008 -229.032562) (xy 45.090062 -229.032816) (xy 51.134264 -229.032816)
			(xy 51.134264 -229.032308) (xy 51.134264 -228.538024) (xy 51.134808 -228.532771) (xy 51.142221 -228.525329)
			(xy 51.147472 -228.524816) (xy 51.6636 -228.524816) (xy 51.671412 -228.524516) (xy 51.686283 -228.519722)
			(xy 51.69281 -228.515418) (xy 51.713899 -228.501069) (xy 51.75956 -228.478338) (xy 51.808166 -228.462879)
			(xy 51.858569 -228.455056) (xy 51.909575 -228.455056) (xy 51.959978 -228.462879) (xy 52.008584 -228.478338)
			(xy 52.054245 -228.501069) (xy 52.075334 -228.515418) (xy 52.081863 -228.519713) (xy 52.096735 -228.524495)
			(xy 52.104544 -228.524816) (xy 52.620672 -228.524816) (xy 52.626006 -228.525148) (xy 52.633551 -228.53269)
			(xy 52.63388 -228.538024) (xy 52.63388 -229.032562) (xy 58.678064 -229.032562) (xy 58.678064 -228.538024)
			(xy 58.678608 -228.532771) (xy 58.686021 -228.525329) (xy 58.691272 -228.524816) (xy 58.69178 -228.524816)
			(xy 60.164726 -228.524816) (xy 60.170028 -228.525303) (xy 60.177596 -228.532732) (xy 60.178188 -228.538024)
			(xy 60.178188 -229.032562) (xy 60.17817 -229.032816) (xy 167.778176 -229.032816) (xy 167.778176 -228.538024)
			(xy 167.778541 -228.532699) (xy 167.78606 -228.525157) (xy 167.791384 -228.524816) (xy 169.264584 -228.524816)
			(xy 169.26992 -228.52514) (xy 169.277463 -228.532688) (xy 169.277792 -228.538024) (xy 169.277792 -229.032562)
			(xy 175.321976 -229.032562) (xy 175.321976 -228.538024) (xy 175.322341 -228.532699) (xy 175.32986 -228.525157)
			(xy 175.335184 -228.524816) (xy 175.335692 -228.524816) (xy 175.851566 -228.524816) (xy 175.859376 -228.524502)
			(xy 175.874248 -228.519718) (xy 175.880776 -228.515418) (xy 175.901865 -228.501069) (xy 175.947526 -228.478338)
			(xy 175.996132 -228.462879) (xy 176.046535 -228.455056) (xy 176.097541 -228.455056) (xy 176.147944 -228.462879)
			(xy 176.19655 -228.478338) (xy 176.242211 -228.501069) (xy 176.2633 -228.515418) (xy 176.269837 -228.5197)
			(xy 176.284703 -228.52449) (xy 176.29251 -228.524816) (xy 176.808638 -228.524816) (xy 176.813941 -228.525295)
			(xy 176.821509 -228.532731) (xy 176.8221 -228.538024) (xy 176.8221 -229.032562) (xy 176.822073 -229.032816)
			(xy 182.866284 -229.032816) (xy 182.866284 -229.032308) (xy 182.866284 -228.538024) (xy 182.866642 -228.532697)
			(xy 182.874166 -228.525155) (xy 182.879492 -228.524816) (xy 183.39562 -228.524816) (xy 183.403432 -228.524525)
			(xy 183.418304 -228.519725) (xy 183.42483 -228.515418) (xy 183.445919 -228.501069) (xy 183.49158 -228.478338)
			(xy 183.540186 -228.462879) (xy 183.590589 -228.455056) (xy 183.641595 -228.455056) (xy 183.691998 -228.462879)
			(xy 183.740604 -228.478338) (xy 183.786265 -228.501069) (xy 183.807354 -228.515418) (xy 183.813879 -228.519721)
			(xy 183.828754 -228.524498) (xy 183.836564 -228.524816) (xy 184.352692 -228.524816) (xy 184.358029 -228.525134)
			(xy 184.365572 -228.532687) (xy 184.3659 -228.538024) (xy 184.3659 -229.032562) (xy 190.410084 -229.032562)
			(xy 190.410084 -228.538024) (xy 190.410442 -228.532697) (xy 190.417966 -228.525155) (xy 190.423292 -228.524816)
			(xy 190.4238 -228.524816) (xy 190.939674 -228.524816) (xy 190.947485 -228.524505) (xy 190.962357 -228.519719)
			(xy 190.968884 -228.515418) (xy 190.989973 -228.501069) (xy 191.035634 -228.478338) (xy 191.08424 -228.462879)
			(xy 191.134643 -228.455056) (xy 191.185649 -228.455056) (xy 191.236052 -228.462879) (xy 191.284658 -228.478338)
			(xy 191.330319 -228.501069) (xy 191.351408 -228.515418) (xy 191.357943 -228.519703) (xy 191.37281 -228.524492)
			(xy 191.380618 -228.524816) (xy 191.896746 -228.524816) (xy 191.902038 -228.525356) (xy 191.909611 -228.532745)
			(xy 191.910208 -228.538024) (xy 191.910208 -229.032562) (xy 191.910181 -229.032816) (xy 197.954392 -229.032816)
			(xy 197.954392 -229.032308) (xy 197.954392 -228.538024) (xy 197.954743 -228.532695) (xy 197.962272 -228.525153)
			(xy 197.9676 -228.524816) (xy 198.483728 -228.524816) (xy 198.491541 -228.524528) (xy 198.506412 -228.519726)
			(xy 198.512938 -228.515418) (xy 198.534027 -228.501069) (xy 198.579688 -228.478338) (xy 198.628294 -228.462879)
			(xy 198.678697 -228.455056) (xy 198.729703 -228.455056) (xy 198.780106 -228.462879) (xy 198.828712 -228.478338)
			(xy 198.874373 -228.501069) (xy 198.895462 -228.515418) (xy 198.902008 -228.519686) (xy 198.916867 -228.524485)
			(xy 198.924672 -228.524816) (xy 199.4408 -228.524816) (xy 199.446138 -228.525129) (xy 199.453681 -228.532685)
			(xy 199.454008 -228.538024) (xy 199.454008 -229.032562) (xy 199.453982 -229.032816) (xy 205.498192 -229.032816)
			(xy 205.498192 -229.032308) (xy 205.498192 -228.538024) (xy 205.498543 -228.532695) (xy 205.506072 -228.525153)
			(xy 205.5114 -228.524816) (xy 206.027528 -228.524816) (xy 206.035341 -228.524528) (xy 206.050212 -228.519726)
			(xy 206.056738 -228.515418) (xy 206.077827 -228.501069) (xy 206.123488 -228.478338) (xy 206.172094 -228.462879)
			(xy 206.222497 -228.455056) (xy 206.273503 -228.455056) (xy 206.323906 -228.462879) (xy 206.372512 -228.478338)
			(xy 206.418173 -228.501069) (xy 206.439262 -228.515418) (xy 206.445808 -228.519686) (xy 206.460667 -228.524485)
			(xy 206.468472 -228.524816) (xy 206.9846 -228.524816) (xy 206.989938 -228.525129) (xy 206.997481 -228.532685)
			(xy 206.997808 -228.538024) (xy 206.997808 -229.032308) (xy 268.898116 -229.032308) (xy 268.898116 -228.53777)
			(xy 268.898628 -228.532408) (xy 268.906215 -228.524825) (xy 268.911578 -228.524308) (xy 269.427706 -228.524308)
			(xy 269.435516 -228.523996) (xy 269.450387 -228.519208) (xy 269.456916 -228.51491) (xy 269.478005 -228.500561)
			(xy 269.523666 -228.47783) (xy 269.572272 -228.462371) (xy 269.622675 -228.454548) (xy 269.673681 -228.454548)
			(xy 269.724084 -228.462371) (xy 269.77269 -228.47783) (xy 269.818351 -228.500561) (xy 269.83944 -228.51491)
			(xy 269.845963 -228.519216) (xy 269.86084 -228.52399) (xy 269.86865 -228.524308) (xy 270.384778 -228.524308)
			(xy 270.390132 -228.524862) (xy 270.397717 -228.532418) (xy 270.39824 -228.53777) (xy 270.39824 -229.032308)
			(xy 276.442424 -229.032308) (xy 276.442424 -228.53777) (xy 276.442901 -228.532466) (xy 276.450337 -228.524897)
			(xy 276.455632 -228.524308) (xy 276.97176 -228.524308) (xy 276.979568 -228.523976) (xy 276.99444 -228.519202)
			(xy 277.00097 -228.51491) (xy 277.022059 -228.500561) (xy 277.06772 -228.47783) (xy 277.116326 -228.462371)
			(xy 277.166729 -228.454548) (xy 277.217735 -228.454548) (xy 277.268138 -228.462371) (xy 277.316744 -228.47783)
			(xy 277.362405 -228.500561) (xy 277.383494 -228.51491) (xy 277.390027 -228.519199) (xy 277.404896 -228.523983)
			(xy 277.412704 -228.524308) (xy 277.928832 -228.524308) (xy 277.934102 -228.524775) (xy 277.941544 -228.532244)
			(xy 277.94204 -228.537516) (xy 277.94204 -228.538024) (xy 277.94204 -229.032308) (xy 283.986224 -229.032308)
			(xy 283.986224 -228.53777) (xy 283.986701 -228.532466) (xy 283.994137 -228.524897) (xy 283.999432 -228.524308)
			(xy 284.51556 -228.524308) (xy 284.523368 -228.523976) (xy 284.53824 -228.519202) (xy 284.54477 -228.51491)
			(xy 284.565859 -228.500561) (xy 284.61152 -228.47783) (xy 284.660126 -228.462371) (xy 284.710529 -228.454548)
			(xy 284.761535 -228.454548) (xy 284.811938 -228.462371) (xy 284.860544 -228.47783) (xy 284.906205 -228.500561)
			(xy 284.927294 -228.51491) (xy 284.933827 -228.519199) (xy 284.948696 -228.523983) (xy 284.956504 -228.524308)
			(xy 285.472632 -228.524308) (xy 285.477902 -228.524775) (xy 285.485344 -228.532244) (xy 285.48584 -228.537516)
			(xy 285.48584 -228.538024) (xy 285.48584 -229.032308) (xy 291.530024 -229.032308) (xy 291.530024 -228.53777)
			(xy 291.530529 -228.532406) (xy 291.538121 -228.524823) (xy 291.543486 -228.524308) (xy 292.059614 -228.524308)
			(xy 292.067424 -228.523999) (xy 292.082296 -228.51921) (xy 292.088824 -228.51491) (xy 292.109913 -228.500561)
			(xy 292.155574 -228.47783) (xy 292.20418 -228.462371) (xy 292.254583 -228.454548) (xy 292.305589 -228.454548)
			(xy 292.355992 -228.462371) (xy 292.404598 -228.47783) (xy 292.450259 -228.500561) (xy 292.471348 -228.51491)
			(xy 292.477869 -228.519219) (xy 292.492747 -228.523991) (xy 292.500558 -228.524308) (xy 293.016686 -228.524308)
			(xy 293.022041 -228.524857) (xy 293.029626 -228.532417) (xy 293.030148 -228.53777) (xy 293.030148 -229.032308)
			(xy 299.074332 -229.032308) (xy 299.074332 -228.53777) (xy 299.074802 -228.532464) (xy 299.082243 -228.524895)
			(xy 299.08754 -228.524308) (xy 299.603668 -228.524308) (xy 299.611477 -228.523979) (xy 299.626348 -228.519204)
			(xy 299.632878 -228.51491) (xy 299.653967 -228.500561) (xy 299.699628 -228.47783) (xy 299.748234 -228.462371)
			(xy 299.798637 -228.454548) (xy 299.849643 -228.454548) (xy 299.900046 -228.462371) (xy 299.948652 -228.47783)
			(xy 299.994313 -228.500561) (xy 300.015402 -228.51491) (xy 300.021933 -228.519202) (xy 300.036803 -228.523984)
			(xy 300.044612 -228.524308) (xy 300.56074 -228.524308) (xy 300.566012 -228.52477) (xy 300.573453 -228.532242)
			(xy 300.573948 -228.537516) (xy 300.573948 -228.538024) (xy 300.573948 -229.032308) (xy 306.618132 -229.032308)
			(xy 306.618132 -228.53777) (xy 306.61863 -228.532404) (xy 306.626227 -228.52482) (xy 306.631594 -228.524308)
			(xy 308.104794 -228.524308) (xy 308.11015 -228.524851) (xy 308.117734 -228.532415) (xy 308.118256 -228.53777)
			(xy 308.118256 -229.032308) (xy 415.718244 -229.032308) (xy 415.718244 -228.53777) (xy 415.718704 -228.532461)
			(xy 415.726152 -228.524891) (xy 415.731452 -228.524308) (xy 417.204652 -228.524308) (xy 417.209982 -228.524661)
			(xy 417.217526 -228.532187) (xy 417.21786 -228.537516) (xy 417.21786 -229.032308) (xy 423.262044 -229.032308)
			(xy 423.262044 -228.53777) (xy 423.262531 -228.532401) (xy 423.270136 -228.524817) (xy 423.275506 -228.524308)
			(xy 423.791634 -228.524308) (xy 423.799441 -228.523965) (xy 423.814313 -228.519199) (xy 423.820844 -228.51491)
			(xy 423.841933 -228.500561) (xy 423.887594 -228.47783) (xy 423.9362 -228.462371) (xy 423.986603 -228.454548)
			(xy 424.037609 -228.454548) (xy 424.088012 -228.462371) (xy 424.136618 -228.47783) (xy 424.182279 -228.500561)
			(xy 424.203368 -228.51491) (xy 424.209907 -228.519189) (xy 424.224771 -228.523979) (xy 424.232578 -228.524308)
			(xy 424.748706 -228.524308) (xy 424.754063 -228.524843) (xy 424.761647 -228.532413) (xy 424.762168 -228.53777)
			(xy 424.762168 -229.032308) (xy 430.806352 -229.032308) (xy 430.806352 -228.53777) (xy 430.806805 -228.532459)
			(xy 430.814258 -228.524889) (xy 430.81956 -228.524308) (xy 431.335688 -228.524308) (xy 431.343497 -228.523988)
			(xy 431.358369 -228.519206) (xy 431.364898 -228.51491) (xy 431.385987 -228.500561) (xy 431.431648 -228.47783)
			(xy 431.480254 -228.462371) (xy 431.530657 -228.454548) (xy 431.581663 -228.454548) (xy 431.632066 -228.462371)
			(xy 431.680672 -228.47783) (xy 431.726333 -228.500561) (xy 431.747422 -228.51491) (xy 431.753949 -228.519209)
			(xy 431.768822 -228.523987) (xy 431.776632 -228.524308) (xy 432.29276 -228.524308) (xy 432.298091 -228.524655)
			(xy 432.305635 -228.532186) (xy 432.305968 -228.537516) (xy 432.305968 -228.538024) (xy 432.305968 -229.032308)
			(xy 438.350152 -229.032308) (xy 438.350152 -228.53777) (xy 438.350632 -228.532399) (xy 438.358241 -228.524814)
			(xy 438.363614 -228.524308) (xy 438.879742 -228.524308) (xy 438.88755 -228.523968) (xy 438.902421 -228.5192)
			(xy 438.908952 -228.51491) (xy 438.930041 -228.500561) (xy 438.975702 -228.47783) (xy 439.024308 -228.462371)
			(xy 439.074711 -228.454548) (xy 439.125717 -228.454548) (xy 439.17612 -228.462371) (xy 439.224726 -228.47783)
			(xy 439.270387 -228.500561) (xy 439.291476 -228.51491) (xy 439.298013 -228.519192) (xy 439.312879 -228.52398)
			(xy 439.320686 -228.524308) (xy 439.836814 -228.524308) (xy 439.842172 -228.524838) (xy 439.849755 -228.532412)
			(xy 439.850276 -228.53777) (xy 439.850276 -229.032308) (xy 445.89446 -229.032308) (xy 445.89446 -228.53777)
			(xy 445.894905 -228.532457) (xy 445.902364 -228.524887) (xy 445.907668 -228.524308) (xy 446.423796 -228.524308)
			(xy 446.431606 -228.523991) (xy 446.446477 -228.519207) (xy 446.453006 -228.51491) (xy 446.474095 -228.500561)
			(xy 446.519756 -228.47783) (xy 446.568362 -228.462371) (xy 446.618765 -228.454548) (xy 446.669771 -228.454548)
			(xy 446.720174 -228.462371) (xy 446.76878 -228.47783) (xy 446.814441 -228.500561) (xy 446.83553 -228.51491)
			(xy 446.842055 -228.519212) (xy 446.85693 -228.523988) (xy 446.86474 -228.524308) (xy 447.380868 -228.524308)
			(xy 447.3862 -228.52465) (xy 447.393744 -228.532185) (xy 447.394076 -228.537516) (xy 447.394076 -228.538024)
			(xy 447.394076 -229.032308) (xy 453.43826 -229.032308) (xy 453.43826 -228.53777) (xy 453.438705 -228.532457)
			(xy 453.446164 -228.524887) (xy 453.451468 -228.524308) (xy 453.967596 -228.524308) (xy 453.975406 -228.523991)
			(xy 453.990277 -228.519207) (xy 453.996806 -228.51491) (xy 454.017895 -228.500561) (xy 454.063556 -228.47783)
			(xy 454.112162 -228.462371) (xy 454.162565 -228.454548) (xy 454.213571 -228.454548) (xy 454.263974 -228.462371)
			(xy 454.31258 -228.47783) (xy 454.358241 -228.500561) (xy 454.37933 -228.51491) (xy 454.385855 -228.519212)
			(xy 454.40073 -228.523988) (xy 454.40854 -228.524308) (xy 454.924668 -228.524308) (xy 454.93 -228.52465)
			(xy 454.937544 -228.532185) (xy 454.937876 -228.537516) (xy 454.937876 -228.538024) (xy 454.937876 -229.032308)
			(xy 454.937576 -229.037649) (xy 454.93001 -229.045192) (xy 454.924668 -229.045516) (xy 454.408794 -229.045516)
			(xy 454.40092 -229.045814) (xy 454.385917 -229.050591) (xy 454.37933 -229.054914) (xy 454.35826 -229.069317)
			(xy 454.312613 -229.092144) (xy 454.264004 -229.107698) (xy 454.213585 -229.115613) (xy 454.188068 -229.116128)
			(xy 454.162549 -229.115616) (xy 454.112123 -229.107728) (xy 454.063511 -229.092174) (xy 454.017872 -229.069326)
			(xy 453.996806 -229.054914) (xy 453.990214 -229.0506) (xy 453.975214 -229.045812) (xy 453.967342 -229.045516)
			(xy 453.451468 -229.045516) (xy 453.446203 -229.045027) (xy 453.438763 -229.037574) (xy 453.43826 -229.032308)
			(xy 447.394076 -229.032308) (xy 447.393776 -229.037649) (xy 447.38621 -229.045192) (xy 447.380868 -229.045516)
			(xy 446.864994 -229.045516) (xy 446.85712 -229.045814) (xy 446.842117 -229.050591) (xy 446.83553 -229.054914)
			(xy 446.81446 -229.069317) (xy 446.768813 -229.092144) (xy 446.720204 -229.107698) (xy 446.669785 -229.115613)
			(xy 446.644268 -229.116128) (xy 446.618749 -229.115616) (xy 446.568323 -229.107728) (xy 446.519711 -229.092174)
			(xy 446.474072 -229.069326) (xy 446.453006 -229.054914) (xy 446.446414 -229.0506) (xy 446.431414 -229.045812)
			(xy 446.423542 -229.045516) (xy 445.907668 -229.045516) (xy 445.902403 -229.045027) (xy 445.894963 -229.037574)
			(xy 445.89446 -229.032308) (xy 439.850276 -229.032308) (xy 439.849976 -229.037649) (xy 439.84241 -229.045192)
			(xy 439.837068 -229.045516) (xy 439.83656 -229.045516) (xy 439.32094 -229.045516) (xy 439.313064 -229.045791)
			(xy 439.298061 -229.050584) (xy 439.291476 -229.054914) (xy 439.270393 -229.069297) (xy 439.22475 -229.092128)
			(xy 439.176146 -229.107689) (xy 439.12573 -229.11561) (xy 439.100214 -229.116128) (xy 439.074694 -229.115643)
			(xy 439.024267 -229.107746) (xy 438.975655 -229.092185) (xy 438.930017 -229.069329) (xy 438.908952 -229.054914)
			(xy 438.902372 -229.050579) (xy 438.887363 -229.045804) (xy 438.879488 -229.045516) (xy 438.363614 -229.045516)
			(xy 438.358301 -229.045062) (xy 438.350727 -229.037612) (xy 438.350152 -229.032308) (xy 432.305968 -229.032308)
			(xy 432.305675 -229.037651) (xy 432.298104 -229.045194) (xy 432.29276 -229.045516) (xy 431.776886 -229.045516)
			(xy 431.769012 -229.045811) (xy 431.754008 -229.05059) (xy 431.747422 -229.054914) (xy 431.726354 -229.06932)
			(xy 431.680706 -229.092146) (xy 431.632097 -229.1077) (xy 431.581678 -229.115614) (xy 431.55616 -229.116128)
			(xy 431.530641 -229.11562) (xy 431.480215 -229.10773) (xy 431.431603 -229.092176) (xy 431.385964 -229.069326)
			(xy 431.364898 -229.054914) (xy 431.358308 -229.050597) (xy 431.343307 -229.045811) (xy 431.335434 -229.045516)
			(xy 430.81956 -229.045516) (xy 430.814294 -229.045033) (xy 430.806854 -229.037575) (xy 430.806352 -229.032308)
			(xy 424.762168 -229.032308) (xy 424.761875 -229.037651) (xy 424.754304 -229.045194) (xy 424.74896 -229.045516)
			(xy 424.748452 -229.045516) (xy 424.232832 -229.045516) (xy 424.224956 -229.045788) (xy 424.209953 -229.050583)
			(xy 424.203368 -229.054914) (xy 424.182287 -229.0693) (xy 424.136644 -229.092131) (xy 424.088039 -229.10769)
			(xy 424.037622 -229.11561) (xy 424.012106 -229.116128) (xy 423.986586 -229.115647) (xy 423.936158 -229.107749)
			(xy 423.887547 -229.092186) (xy 423.841909 -229.06933) (xy 423.820844 -229.054914) (xy 423.814266 -229.050576)
			(xy 423.799256 -229.045803) (xy 423.79138 -229.045516) (xy 423.275506 -229.045516) (xy 423.270192 -229.045068)
			(xy 423.262618 -229.037613) (xy 423.262044 -229.032308) (xy 417.21786 -229.032308) (xy 417.217574 -229.037653)
			(xy 417.209999 -229.045197) (xy 417.204652 -229.045516) (xy 415.731452 -229.045516) (xy 415.726185 -229.045038)
			(xy 415.718746 -229.037576) (xy 415.718244 -229.032308) (xy 308.118256 -229.032308) (xy 308.117716 -229.03756)
			(xy 308.110299 -229.045) (xy 308.105048 -229.045516) (xy 308.10454 -229.045516) (xy 306.631594 -229.045516)
			(xy 306.626279 -229.045076) (xy 306.618705 -229.037615) (xy 306.618132 -229.032308) (xy 300.573948 -229.032308)
			(xy 300.573415 -229.037562) (xy 300.565993 -229.045002) (xy 300.56074 -229.045516) (xy 300.044866 -229.045516)
			(xy 300.036991 -229.045802) (xy 300.021988 -229.050587) (xy 300.015402 -229.054914) (xy 299.994312 -229.069286)
			(xy 299.948672 -229.09212) (xy 299.90007 -229.107683) (xy 299.849656 -229.115608) (xy 299.82414 -229.116128)
			(xy 299.79862 -229.11563) (xy 299.748194 -229.107737) (xy 299.699582 -229.09218) (xy 299.653943 -229.069328)
			(xy 299.632878 -229.054914) (xy 299.626292 -229.050589) (xy 299.611288 -229.045808) (xy 299.603414 -229.045516)
			(xy 299.08754 -229.045516) (xy 299.082215 -229.045147) (xy 299.074672 -229.037632) (xy 299.074332 -229.032308)
			(xy 293.030148 -229.032308) (xy 293.029615 -229.037562) (xy 293.022193 -229.045002) (xy 293.01694 -229.045516)
			(xy 293.016432 -229.045516) (xy 292.500812 -229.045516) (xy 292.492939 -229.045822) (xy 292.477935 -229.050594)
			(xy 292.471348 -229.054914) (xy 292.450273 -229.069309) (xy 292.404627 -229.092138) (xy 292.356021 -229.107695)
			(xy 292.305603 -229.115612) (xy 292.280086 -229.116128) (xy 292.254567 -229.115607) (xy 292.204142 -229.107721)
			(xy 292.15553 -229.09217) (xy 292.10989 -229.069325) (xy 292.088824 -229.054914) (xy 292.082228 -229.050607)
			(xy 292.067231 -229.045815) (xy 292.05936 -229.045516) (xy 291.543486 -229.045516) (xy 291.53817 -229.045081)
			(xy 291.530597 -229.037616) (xy 291.530024 -229.032308) (xy 285.48584 -229.032308) (xy 285.485314 -229.037564)
			(xy 285.477887 -229.045004) (xy 285.472632 -229.045516) (xy 284.956758 -229.045516) (xy 284.948883 -229.045799)
			(xy 284.933879 -229.050586) (xy 284.927294 -229.054914) (xy 284.906206 -229.069289) (xy 284.860565 -229.092122)
			(xy 284.811962 -229.107685) (xy 284.761548 -229.115609) (xy 284.736032 -229.116128) (xy 284.710512 -229.115634)
			(xy 284.660085 -229.10774) (xy 284.611474 -229.092181) (xy 284.565835 -229.069328) (xy 284.54477 -229.054914)
			(xy 284.538186 -229.050586) (xy 284.52318 -229.045807) (xy 284.515306 -229.045516) (xy 283.999432 -229.045516)
			(xy 283.994106 -229.045152) (xy 283.986564 -229.037633) (xy 283.986224 -229.032308) (xy 277.94204 -229.032308)
			(xy 277.941514 -229.037564) (xy 277.934087 -229.045004) (xy 277.928832 -229.045516) (xy 277.412958 -229.045516)
			(xy 277.405083 -229.045799) (xy 277.390079 -229.050586) (xy 277.383494 -229.054914) (xy 277.362406 -229.069289)
			(xy 277.316765 -229.092122) (xy 277.268162 -229.107685) (xy 277.217748 -229.115609) (xy 277.192232 -229.116128)
			(xy 277.166712 -229.115634) (xy 277.116285 -229.10774) (xy 277.067674 -229.092181) (xy 277.022035 -229.069328)
			(xy 277.00097 -229.054914) (xy 276.994386 -229.050586) (xy 276.97938 -229.045807) (xy 276.971506 -229.045516)
			(xy 276.455632 -229.045516) (xy 276.450306 -229.045152) (xy 276.442764 -229.037633) (xy 276.442424 -229.032308)
			(xy 270.39824 -229.032308) (xy 270.397714 -229.037564) (xy 270.390287 -229.045004) (xy 270.385032 -229.045516)
			(xy 270.384524 -229.045516) (xy 269.868904 -229.045516) (xy 269.861031 -229.045819) (xy 269.846027 -229.050593)
			(xy 269.83944 -229.054914) (xy 269.818367 -229.069312) (xy 269.772721 -229.09214) (xy 269.724113 -229.107696)
			(xy 269.673695 -229.115613) (xy 269.648178 -229.116128) (xy 269.622659 -229.115611) (xy 269.572233 -229.107724)
			(xy 269.523622 -229.092172) (xy 269.477982 -229.069325) (xy 269.456916 -229.054914) (xy 269.450322 -229.050604)
			(xy 269.435324 -229.045814) (xy 269.427452 -229.045516) (xy 268.911578 -229.045516) (xy 268.906261 -229.045086)
			(xy 268.898688 -229.037618) (xy 268.898116 -229.032308) (xy 206.997808 -229.032308) (xy 206.997808 -229.032562)
			(xy 206.997257 -229.03785) (xy 206.989875 -229.045421) (xy 206.9846 -229.046024) (xy 206.468726 -229.046024)
			(xy 206.460916 -229.046344) (xy 206.446045 -229.051125) (xy 206.439516 -229.055422) (xy 206.418385 -229.069757)
			(xy 206.372665 -229.092488) (xy 206.323994 -229.107922) (xy 206.27353 -229.115693) (xy 206.248 -229.116128)
			(xy 206.222469 -229.115698) (xy 206.172005 -229.107921) (xy 206.123332 -229.09249) (xy 206.077605 -229.069771)
			(xy 206.056484 -229.055422) (xy 206.049954 -229.051128) (xy 206.035083 -229.046347) (xy 206.027274 -229.046024)
			(xy 205.5114 -229.046024) (xy 205.506141 -229.045507) (xy 205.4987 -229.038074) (xy 205.498192 -229.032816)
			(xy 199.453982 -229.032816) (xy 199.453457 -229.03785) (xy 199.446075 -229.045421) (xy 199.4408 -229.046024)
			(xy 198.924926 -229.046024) (xy 198.917116 -229.046344) (xy 198.902245 -229.051125) (xy 198.895716 -229.055422)
			(xy 198.874585 -229.069757) (xy 198.828865 -229.092488) (xy 198.780194 -229.107922) (xy 198.72973 -229.115693)
			(xy 198.7042 -229.116128) (xy 198.678669 -229.115698) (xy 198.628205 -229.107921) (xy 198.579532 -229.09249)
			(xy 198.533805 -229.069771) (xy 198.512684 -229.055422) (xy 198.506154 -229.051128) (xy 198.491283 -229.046347)
			(xy 198.483474 -229.046024) (xy 197.9676 -229.046024) (xy 197.962341 -229.045507) (xy 197.9549 -229.038074)
			(xy 197.954392 -229.032816) (xy 191.910181 -229.032816) (xy 191.909629 -229.03791) (xy 191.902091 -229.045496)
			(xy 191.896746 -229.046024) (xy 191.380872 -229.046024) (xy 191.37306 -229.046322) (xy 191.358189 -229.051118)
			(xy 191.351662 -229.055422) (xy 191.330546 -229.06978) (xy 191.284821 -229.092506) (xy 191.236145 -229.107934)
			(xy 191.185678 -229.115697) (xy 191.160146 -229.116128) (xy 191.134616 -229.115675) (xy 191.084153 -229.107905)
			(xy 191.03548 -229.092481) (xy 190.989752 -229.069768) (xy 190.96863 -229.055422) (xy 190.96209 -229.051146)
			(xy 190.947226 -229.046353) (xy 190.93942 -229.046024) (xy 190.423546 -229.046024) (xy 190.418108 -229.045686)
			(xy 190.410417 -229.038) (xy 190.410084 -229.032562) (xy 184.3659 -229.032562) (xy 184.365356 -229.037852)
			(xy 184.357969 -229.045423) (xy 184.352692 -229.046024) (xy 183.836818 -229.046024) (xy 183.829008 -229.046341)
			(xy 183.814137 -229.051124) (xy 183.807608 -229.055422) (xy 183.786479 -229.06976) (xy 183.740758 -229.09249)
			(xy 183.692087 -229.107924) (xy 183.641622 -229.115693) (xy 183.616092 -229.116128) (xy 183.590561 -229.115702)
			(xy 183.540097 -229.107924) (xy 183.491424 -229.092492) (xy 183.445697 -229.069772) (xy 183.424576 -229.055422)
			(xy 183.418048 -229.051125) (xy 183.403175 -229.046345) (xy 183.395366 -229.046024) (xy 182.879492 -229.046024)
			(xy 182.874232 -229.045512) (xy 182.866791 -229.038076) (xy 182.866284 -229.032816) (xy 176.822073 -229.032816)
			(xy 176.821528 -229.037912) (xy 176.813985 -229.045498) (xy 176.808638 -229.046024) (xy 176.292764 -229.046024)
			(xy 176.284956 -229.046361) (xy 176.270084 -229.051131) (xy 176.263554 -229.055422) (xy 176.24244 -229.069784)
			(xy 176.196714 -229.092509) (xy 176.148038 -229.107935) (xy 176.09757 -229.115697) (xy 176.072038 -229.116128)
			(xy 176.046508 -229.115679) (xy 175.996045 -229.107908) (xy 175.947372 -229.092483) (xy 175.901644 -229.069769)
			(xy 175.880522 -229.055422) (xy 175.873983 -229.051143) (xy 175.859119 -229.046352) (xy 175.851312 -229.046024)
			(xy 175.335438 -229.046024) (xy 175.329999 -229.045692) (xy 175.322308 -229.038001) (xy 175.321976 -229.032562)
			(xy 169.277792 -229.032562) (xy 169.277255 -229.037854) (xy 169.269863 -229.045425) (xy 169.264584 -229.046024)
			(xy 167.791384 -229.046024) (xy 167.786123 -229.045518) (xy 167.778682 -229.038077) (xy 167.778176 -229.032816)
			(xy 60.17817 -229.032816) (xy 60.177798 -229.037986) (xy 60.170148 -229.045672) (xy 60.164726 -229.046024)
			(xy 58.691526 -229.046024) (xy 58.686085 -229.0457) (xy 58.678396 -229.038003) (xy 58.678064 -229.032562)
			(xy 52.63388 -229.032562) (xy 52.633354 -229.037857) (xy 52.625954 -229.045429) (xy 52.620672 -229.046024)
			(xy 52.104798 -229.046024) (xy 52.096987 -229.046333) (xy 52.082116 -229.051122) (xy 52.075588 -229.055422)
			(xy 52.054465 -229.069769) (xy 52.008742 -229.092497) (xy 51.960069 -229.107928) (xy 51.909603 -229.115695)
			(xy 51.884072 -229.116128) (xy 51.858541 -229.115712) (xy 51.808076 -229.107931) (xy 51.759403 -229.092496)
			(xy 51.713677 -229.069773) (xy 51.692556 -229.055422) (xy 51.686032 -229.051118) (xy 51.671156 -229.046343)
			(xy 51.663346 -229.046024) (xy 51.147472 -229.046024) (xy 51.14221 -229.045526) (xy 51.13477 -229.038079)
			(xy 51.134264 -229.032816) (xy 45.090062 -229.032816) (xy 45.089697 -229.037988) (xy 45.082042 -229.045675)
			(xy 45.076618 -229.046024) (xy 44.560744 -229.046024) (xy 44.552935 -229.046353) (xy 44.538064 -229.051128)
			(xy 44.531534 -229.055422) (xy 44.510426 -229.069792) (xy 44.464698 -229.092515) (xy 44.41602 -229.10794)
			(xy 44.36555 -229.115699) (xy 44.340018 -229.116128) (xy 44.314488 -229.115689) (xy 44.264024 -229.107915)
			(xy 44.215351 -229.092487) (xy 44.169624 -229.06977) (xy 44.148502 -229.055422) (xy 44.141968 -229.051135)
			(xy 44.1271 -229.046349) (xy 44.119292 -229.046024) (xy 43.603418 -229.046024) (xy 43.597976 -229.045705)
			(xy 43.590287 -229.038004) (xy 43.589956 -229.032562) (xy 37.545772 -229.032562) (xy 37.545253 -229.037859)
			(xy 37.537849 -229.045431) (xy 37.532564 -229.046024) (xy 37.01669 -229.046024) (xy 37.008879 -229.046329)
			(xy 36.994008 -229.051121) (xy 36.98748 -229.055422) (xy 36.966359 -229.069773) (xy 36.920635 -229.0925)
			(xy 36.871962 -229.10793) (xy 36.821495 -229.115696) (xy 36.795964 -229.116128) (xy 36.770433 -229.115716)
			(xy 36.719968 -229.107934) (xy 36.671295 -229.092498) (xy 36.625569 -229.069773) (xy 36.604448 -229.055422)
			(xy 36.597926 -229.051114) (xy 36.583049 -229.046341) (xy 36.575238 -229.046024) (xy 36.059364 -229.046024)
			(xy 36.054101 -229.045531) (xy 36.046661 -229.03808) (xy 36.046156 -229.032816) (xy 30.001947 -229.032816)
			(xy 30.001453 -229.037859) (xy 29.994049 -229.045431) (xy 29.988764 -229.046024) (xy 29.47289 -229.046024)
			(xy 29.465079 -229.046329) (xy 29.450208 -229.051121) (xy 29.44368 -229.055422) (xy 29.422559 -229.069773)
			(xy 29.376835 -229.0925) (xy 29.328162 -229.10793) (xy 29.277695 -229.115696) (xy 29.252164 -229.116128)
			(xy 29.226633 -229.115716) (xy 29.176168 -229.107934) (xy 29.127495 -229.092498) (xy 29.081769 -229.069773)
			(xy 29.060648 -229.055422) (xy 29.054126 -229.051114) (xy 29.039249 -229.046341) (xy 29.031438 -229.046024)
			(xy 28.515564 -229.046024) (xy 28.510301 -229.045531) (xy 28.502861 -229.03808) (xy 28.502356 -229.032816)
			(xy 22.458154 -229.032816) (xy 22.457796 -229.037989) (xy 22.450136 -229.045677) (xy 22.44471 -229.046024)
			(xy 21.928836 -229.046024) (xy 21.921027 -229.046349) (xy 21.906155 -229.051127) (xy 21.899626 -229.055422)
			(xy 21.878492 -229.069753) (xy 21.832773 -229.092484) (xy 21.784104 -229.10792) (xy 21.73364 -229.115692)
			(xy 21.70811 -229.116128) (xy 21.68258 -229.115693) (xy 21.632115 -229.107918) (xy 21.583443 -229.092488)
			(xy 21.537716 -229.06977) (xy 21.516594 -229.055422) (xy 21.510062 -229.051132) (xy 21.495192 -229.046348)
			(xy 21.487384 -229.046024) (xy 20.97151 -229.046024) (xy 20.966067 -229.04571) (xy 20.958378 -229.038006)
			(xy 20.958048 -229.032562) (xy 2.509012 -229.032562) (xy 2.509012 -229.882446) (xy 16.85798 -229.882446)
			(xy 16.85798 -229.387908) (xy 16.858499 -229.382649) (xy 16.86593 -229.375207) (xy 16.871188 -229.3747)
			(xy 16.871696 -229.3747) (xy 17.38757 -229.3747) (xy 17.395379 -229.374374) (xy 17.41025 -229.369596)
			(xy 17.41678 -229.365302) (xy 17.437869 -229.350953) (xy 17.48353 -229.328222) (xy 17.532136 -229.312763)
			(xy 17.582539 -229.30494) (xy 17.633545 -229.30494) (xy 17.683948 -229.312763) (xy 17.732554 -229.328222)
			(xy 17.778215 -229.350953) (xy 17.799304 -229.365302) (xy 17.805835 -229.369594) (xy 17.820705 -229.374376)
			(xy 17.828514 -229.3747) (xy 18.344642 -229.3747) (xy 18.349942 -229.37519) (xy 18.357508 -229.382618)
			(xy 18.358104 -229.387908) (xy 18.358104 -229.882446) (xy 20.958048 -229.882446) (xy 20.958048 -229.387908)
			(xy 20.958595 -229.382657) (xy 20.966007 -229.375216) (xy 20.971256 -229.3747) (xy 20.971764 -229.3747)
			(xy 21.487638 -229.3747) (xy 21.495446 -229.37436) (xy 21.510317 -229.369592) (xy 21.516848 -229.365302)
			(xy 21.537937 -229.350953) (xy 21.583598 -229.328222) (xy 21.632204 -229.312763) (xy 21.682607 -229.30494)
			(xy 21.733613 -229.30494) (xy 21.784016 -229.312763) (xy 21.832622 -229.328222) (xy 21.878283 -229.350953)
			(xy 21.899372 -229.365302) (xy 21.90591 -229.369582) (xy 21.920775 -229.374372) (xy 21.928582 -229.3747)
			(xy 22.44471 -229.3747) (xy 22.450006 -229.375212) (xy 22.457574 -229.382623) (xy 22.458172 -229.387908)
			(xy 22.458172 -229.882446) (xy 22.458149 -229.8827) (xy 24.402288 -229.8827) (xy 24.402288 -229.882192)
			(xy 24.402288 -229.387908) (xy 24.402632 -229.382578) (xy 24.410166 -229.375037) (xy 24.415496 -229.3747)
			(xy 24.931624 -229.3747) (xy 24.939435 -229.374396) (xy 24.954306 -229.369603) (xy 24.960834 -229.365302)
			(xy 24.981923 -229.350953) (xy 25.027584 -229.328222) (xy 25.07619 -229.312763) (xy 25.126593 -229.30494)
			(xy 25.177599 -229.30494) (xy 25.228002 -229.312763) (xy 25.276608 -229.328222) (xy 25.322269 -229.350953)
			(xy 25.343358 -229.365302) (xy 25.349877 -229.369614) (xy 25.364757 -229.374384) (xy 25.372568 -229.3747)
			(xy 25.888696 -229.3747) (xy 25.89403 -229.37503) (xy 25.901571 -229.382574) (xy 25.901904 -229.387908)
			(xy 25.901904 -229.882446) (xy 25.901877 -229.8827) (xy 28.502356 -229.8827) (xy 28.502356 -229.882192)
			(xy 28.502356 -229.387908) (xy 28.502896 -229.382655) (xy 28.510313 -229.375214) (xy 28.515564 -229.3747)
			(xy 29.031692 -229.3747) (xy 29.039502 -229.374383) (xy 29.054373 -229.369599) (xy 29.060902 -229.365302)
			(xy 29.081991 -229.350953) (xy 29.127652 -229.328222) (xy 29.176258 -229.312763) (xy 29.226661 -229.30494)
			(xy 29.277667 -229.30494) (xy 29.32807 -229.312763) (xy 29.376676 -229.328222) (xy 29.422337 -229.350953)
			(xy 29.443426 -229.365302) (xy 29.449952 -229.369602) (xy 29.464826 -229.37438) (xy 29.472636 -229.3747)
			(xy 29.988764 -229.3747) (xy 29.994093 -229.375052) (xy 30.001637 -229.382579) (xy 30.001972 -229.387908)
			(xy 30.001972 -229.882446) (xy 30.001947 -229.8827) (xy 31.946088 -229.8827) (xy 31.946088 -229.882192)
			(xy 31.946088 -229.387908) (xy 31.946432 -229.382578) (xy 31.953966 -229.375037) (xy 31.959296 -229.3747)
			(xy 32.475424 -229.3747) (xy 32.483235 -229.374396) (xy 32.498106 -229.369603) (xy 32.504634 -229.365302)
			(xy 32.525723 -229.350953) (xy 32.571384 -229.328222) (xy 32.61999 -229.312763) (xy 32.670393 -229.30494)
			(xy 32.721399 -229.30494) (xy 32.771802 -229.312763) (xy 32.820408 -229.328222) (xy 32.866069 -229.350953)
			(xy 32.887158 -229.365302) (xy 32.893677 -229.369614) (xy 32.908557 -229.374384) (xy 32.916368 -229.3747)
			(xy 33.432496 -229.3747) (xy 33.43783 -229.37503) (xy 33.445371 -229.382574) (xy 33.445704 -229.387908)
			(xy 33.445704 -229.882446) (xy 33.445677 -229.8827) (xy 36.046156 -229.8827) (xy 36.046156 -229.882192)
			(xy 36.046156 -229.387908) (xy 36.046696 -229.382655) (xy 36.054113 -229.375214) (xy 36.059364 -229.3747)
			(xy 36.575492 -229.3747) (xy 36.583302 -229.374383) (xy 36.598173 -229.369599) (xy 36.604702 -229.365302)
			(xy 36.625791 -229.350953) (xy 36.671452 -229.328222) (xy 36.720058 -229.312763) (xy 36.770461 -229.30494)
			(xy 36.821467 -229.30494) (xy 36.87187 -229.312763) (xy 36.920476 -229.328222) (xy 36.966137 -229.350953)
			(xy 36.987226 -229.365302) (xy 36.993752 -229.369602) (xy 37.008626 -229.37438) (xy 37.016436 -229.3747)
			(xy 37.532564 -229.3747) (xy 37.537893 -229.375052) (xy 37.545437 -229.382579) (xy 37.545772 -229.387908)
			(xy 37.545772 -229.882446) (xy 39.489888 -229.882446) (xy 39.489888 -229.387908) (xy 39.490232 -229.382578)
			(xy 39.497766 -229.375037) (xy 39.503096 -229.3747) (xy 39.503604 -229.3747) (xy 40.019478 -229.3747)
			(xy 40.027287 -229.374377) (xy 40.042159 -229.369597) (xy 40.048688 -229.365302) (xy 40.069777 -229.350953)
			(xy 40.115438 -229.328222) (xy 40.164044 -229.312763) (xy 40.214447 -229.30494) (xy 40.265453 -229.30494)
			(xy 40.315856 -229.312763) (xy 40.364462 -229.328222) (xy 40.410123 -229.350953) (xy 40.431212 -229.365302)
			(xy 40.437741 -229.369597) (xy 40.452613 -229.374378) (xy 40.460422 -229.3747) (xy 40.97655 -229.3747)
			(xy 40.981839 -229.375252) (xy 40.98941 -229.382633) (xy 40.990012 -229.387908) (xy 40.990012 -229.882446)
			(xy 43.589956 -229.882446) (xy 43.589956 -229.387908) (xy 43.590496 -229.382655) (xy 43.597913 -229.375214)
			(xy 43.603164 -229.3747) (xy 43.603672 -229.3747) (xy 44.119546 -229.3747) (xy 44.127354 -229.374364)
			(xy 44.142226 -229.369593) (xy 44.148756 -229.365302) (xy 44.169845 -229.350953) (xy 44.215506 -229.328222)
			(xy 44.264112 -229.312763) (xy 44.314515 -229.30494) (xy 44.365521 -229.30494) (xy 44.415924 -229.312763)
			(xy 44.46453 -229.328222) (xy 44.510191 -229.350953) (xy 44.53128 -229.365302) (xy 44.537817 -229.369585)
			(xy 44.552683 -229.374373) (xy 44.56049 -229.3747) (xy 45.076618 -229.3747) (xy 45.081915 -229.375206)
			(xy 45.089483 -229.382622) (xy 45.09008 -229.387908) (xy 45.09008 -229.882446) (xy 45.090056 -229.8827)
			(xy 47.034196 -229.8827) (xy 47.034196 -229.882192) (xy 47.034196 -229.387908) (xy 47.034532 -229.382576)
			(xy 47.042072 -229.375034) (xy 47.047404 -229.3747) (xy 47.563532 -229.3747) (xy 47.571339 -229.374358)
			(xy 47.586211 -229.369591) (xy 47.592742 -229.365302) (xy 47.613831 -229.350953) (xy 47.659492 -229.328222)
			(xy 47.708098 -229.312763) (xy 47.758501 -229.30494) (xy 47.809507 -229.30494) (xy 47.85991 -229.312763)
			(xy 47.908516 -229.328222) (xy 47.954177 -229.350953) (xy 47.975266 -229.365302) (xy 47.981806 -229.369579)
			(xy 47.996669 -229.374371) (xy 48.004476 -229.3747) (xy 48.520604 -229.3747) (xy 48.525939 -229.375025)
			(xy 48.53348 -229.382573) (xy 48.533812 -229.387908) (xy 48.533812 -229.882446) (xy 48.533789 -229.8827)
			(xy 51.134264 -229.8827) (xy 51.134264 -229.882192) (xy 51.134264 -229.387908) (xy 51.134797 -229.382653)
			(xy 51.142218 -229.375211) (xy 51.147472 -229.3747) (xy 51.6636 -229.3747) (xy 51.67141 -229.374386)
			(xy 51.686281 -229.3696) (xy 51.69281 -229.365302) (xy 51.713899 -229.350953) (xy 51.75956 -229.328222)
			(xy 51.808166 -229.312763) (xy 51.858569 -229.30494) (xy 51.909575 -229.30494) (xy 51.959978 -229.312763)
			(xy 52.008584 -229.328222) (xy 52.054245 -229.350953) (xy 52.075334 -229.365302) (xy 52.081859 -229.369605)
			(xy 52.096734 -229.374381) (xy 52.104544 -229.3747) (xy 52.620672 -229.3747) (xy 52.626003 -229.375046)
			(xy 52.633546 -229.382578) (xy 52.63388 -229.387908) (xy 52.63388 -229.882446) (xy 54.577996 -229.882446)
			(xy 54.577996 -229.387908) (xy 54.578332 -229.382576) (xy 54.585872 -229.375034) (xy 54.591204 -229.3747)
			(xy 56.064658 -229.3747) (xy 56.069948 -229.375247) (xy 56.077519 -229.382632) (xy 56.07812 -229.387908)
			(xy 56.07812 -229.882446) (xy 58.678064 -229.882446) (xy 58.678064 -229.387908) (xy 58.678597 -229.382653)
			(xy 58.686018 -229.375211) (xy 58.691272 -229.3747) (xy 58.69178 -229.3747) (xy 60.164726 -229.3747)
			(xy 60.170024 -229.375201) (xy 60.177592 -229.382621) (xy 60.178188 -229.387908) (xy 60.178188 -229.882446)
			(xy 60.178164 -229.8827) (xy 163.678108 -229.8827) (xy 163.678108 -229.882192) (xy 163.678108 -229.387908)
			(xy 163.678434 -229.382573) (xy 163.685981 -229.37503) (xy 163.691316 -229.3747) (xy 165.164516 -229.3747)
			(xy 165.169783 -229.375185) (xy 165.177225 -229.38264) (xy 165.177724 -229.387908) (xy 165.177724 -229.882446)
			(xy 165.177701 -229.8827) (xy 167.778176 -229.8827) (xy 167.778176 -229.387908) (xy 167.778698 -229.38265)
			(xy 167.786127 -229.375208) (xy 167.791384 -229.3747) (xy 169.264584 -229.3747) (xy 169.269916 -229.375038)
			(xy 169.277458 -229.382576) (xy 169.277792 -229.387908) (xy 169.277792 -229.882446) (xy 171.221908 -229.882446)
			(xy 171.221908 -229.387908) (xy 171.222234 -229.382573) (xy 171.229781 -229.37503) (xy 171.235116 -229.3747)
			(xy 171.235624 -229.3747) (xy 171.751498 -229.3747) (xy 171.759308 -229.374386) (xy 171.774179 -229.3696)
			(xy 171.780708 -229.365302) (xy 171.801797 -229.350953) (xy 171.847458 -229.328222) (xy 171.896064 -229.312763)
			(xy 171.946467 -229.30494) (xy 171.997473 -229.30494) (xy 172.047876 -229.312763) (xy 172.096482 -229.328222)
			(xy 172.142143 -229.350953) (xy 172.163232 -229.365302) (xy 172.169757 -229.369604) (xy 172.184632 -229.37438)
			(xy 172.192442 -229.3747) (xy 172.70857 -229.3747) (xy 172.713861 -229.375238) (xy 172.721432 -229.38263)
			(xy 172.722032 -229.387908) (xy 172.722032 -229.882446) (xy 175.321976 -229.882446) (xy 175.321976 -229.387908)
			(xy 175.322498 -229.38265) (xy 175.329927 -229.375208) (xy 175.335184 -229.3747) (xy 175.335692 -229.3747)
			(xy 175.851566 -229.3747) (xy 175.859375 -229.374372) (xy 175.874246 -229.369596) (xy 175.880776 -229.365302)
			(xy 175.901865 -229.350953) (xy 175.947526 -229.328222) (xy 175.996132 -229.312763) (xy 176.046535 -229.30494)
			(xy 176.097541 -229.30494) (xy 176.147944 -229.312763) (xy 176.19655 -229.328222) (xy 176.242211 -229.350953)
			(xy 176.2633 -229.365302) (xy 176.269832 -229.369592) (xy 176.284702 -229.374376) (xy 176.29251 -229.3747)
			(xy 176.808638 -229.3747) (xy 176.813938 -229.375193) (xy 176.821504 -229.382619) (xy 176.8221 -229.387908)
			(xy 176.8221 -229.882446) (xy 176.822076 -229.8827) (xy 178.766216 -229.8827) (xy 178.766216 -229.882192)
			(xy 178.766216 -229.387908) (xy 178.766534 -229.382571) (xy 178.774087 -229.375028) (xy 178.779424 -229.3747)
			(xy 179.295552 -229.3747) (xy 179.30336 -229.374366) (xy 179.318232 -229.369594) (xy 179.324762 -229.365302)
			(xy 179.345851 -229.350953) (xy 179.391512 -229.328222) (xy 179.440118 -229.312763) (xy 179.490521 -229.30494)
			(xy 179.541527 -229.30494) (xy 179.59193 -229.312763) (xy 179.640536 -229.328222) (xy 179.686197 -229.350953)
			(xy 179.707286 -229.365302) (xy 179.713821 -229.369587) (xy 179.728688 -229.374374) (xy 179.736496 -229.3747)
			(xy 180.252624 -229.3747) (xy 180.257892 -229.37518) (xy 180.265333 -229.382639) (xy 180.265832 -229.387908)
			(xy 180.265832 -229.882446) (xy 180.265808 -229.8827) (xy 182.866284 -229.8827) (xy 182.866284 -229.882192)
			(xy 182.866284 -229.387908) (xy 182.866799 -229.382648) (xy 182.874233 -229.375205) (xy 182.879492 -229.3747)
			(xy 183.39562 -229.3747) (xy 183.403431 -229.374395) (xy 183.418302 -229.369603) (xy 183.42483 -229.365302)
			(xy 183.445919 -229.350953) (xy 183.49158 -229.328222) (xy 183.540186 -229.312763) (xy 183.590589 -229.30494)
			(xy 183.641595 -229.30494) (xy 183.691998 -229.312763) (xy 183.740604 -229.328222) (xy 183.786265 -229.350953)
			(xy 183.807354 -229.365302) (xy 183.813874 -229.369613) (xy 183.828753 -229.374384) (xy 183.836564 -229.3747)
			(xy 184.352692 -229.3747) (xy 184.358025 -229.375033) (xy 184.365567 -229.382575) (xy 184.3659 -229.387908)
			(xy 184.3659 -229.882446) (xy 186.310016 -229.882446) (xy 186.310016 -229.387908) (xy 186.310334 -229.382571)
			(xy 186.317887 -229.375028) (xy 186.323224 -229.3747) (xy 186.323732 -229.3747) (xy 186.839606 -229.3747)
			(xy 186.847416 -229.374389) (xy 186.862288 -229.369601) (xy 186.868816 -229.365302) (xy 186.889905 -229.350953)
			(xy 186.935566 -229.328222) (xy 186.984172 -229.312763) (xy 187.034575 -229.30494) (xy 187.085581 -229.30494)
			(xy 187.135984 -229.312763) (xy 187.18459 -229.328222) (xy 187.230251 -229.350953) (xy 187.25134 -229.365302)
			(xy 187.257863 -229.369608) (xy 187.27274 -229.374382) (xy 187.28055 -229.3747) (xy 187.796678 -229.3747)
			(xy 187.80197 -229.375233) (xy 187.80954 -229.382628) (xy 187.81014 -229.387908) (xy 187.81014 -229.882446)
			(xy 190.410084 -229.882446) (xy 190.410084 -229.387908) (xy 190.410599 -229.382648) (xy 190.418033 -229.375205)
			(xy 190.423292 -229.3747) (xy 190.4238 -229.3747) (xy 190.939674 -229.3747) (xy 190.947483 -229.374375)
			(xy 190.962355 -229.369597) (xy 190.968884 -229.365302) (xy 190.989973 -229.350953) (xy 191.035634 -229.328222)
			(xy 191.08424 -229.312763) (xy 191.134643 -229.30494) (xy 191.185649 -229.30494) (xy 191.236052 -229.312763)
			(xy 191.284658 -229.328222) (xy 191.330319 -229.350953) (xy 191.351408 -229.365302) (xy 191.357938 -229.369595)
			(xy 191.372809 -229.374377) (xy 191.380618 -229.3747) (xy 191.896746 -229.3747) (xy 191.902035 -229.375255)
			(xy 191.909606 -229.382634) (xy 191.910208 -229.387908) (xy 191.910208 -229.882446) (xy 191.910183 -229.8827)
			(xy 193.854324 -229.8827) (xy 193.854324 -229.882192) (xy 193.854324 -229.387908) (xy 193.854635 -229.382569)
			(xy 193.862192 -229.375026) (xy 193.867532 -229.3747) (xy 194.38366 -229.3747) (xy 194.391469 -229.374369)
			(xy 194.40634 -229.369595) (xy 194.41287 -229.365302) (xy 194.433959 -229.350953) (xy 194.47962 -229.328222)
			(xy 194.528226 -229.312763) (xy 194.578629 -229.30494) (xy 194.629635 -229.30494) (xy 194.680038 -229.312763)
			(xy 194.728644 -229.328222) (xy 194.774305 -229.350953) (xy 194.795394 -229.365302) (xy 194.801927 -229.36959)
			(xy 194.816796 -229.374375) (xy 194.824604 -229.3747) (xy 195.340732 -229.3747) (xy 195.346001 -229.375174)
			(xy 195.353442 -229.382638) (xy 195.35394 -229.387908) (xy 195.35394 -229.882446) (xy 195.353916 -229.8827)
			(xy 197.954392 -229.8827) (xy 197.954392 -229.882192) (xy 197.954392 -229.387908) (xy 197.954732 -229.382577)
			(xy 197.962269 -229.375035) (xy 197.9676 -229.3747) (xy 198.483728 -229.3747) (xy 198.491539 -229.374398)
			(xy 198.50641 -229.369604) (xy 198.512938 -229.365302) (xy 198.534027 -229.350953) (xy 198.579688 -229.328222)
			(xy 198.628294 -229.312763) (xy 198.678697 -229.30494) (xy 198.729703 -229.30494) (xy 198.780106 -229.312763)
			(xy 198.828712 -229.328222) (xy 198.874373 -229.350953) (xy 198.895462 -229.365302) (xy 198.902003 -229.369578)
			(xy 198.916866 -229.37437) (xy 198.924672 -229.3747) (xy 199.4408 -229.3747) (xy 199.446134 -229.375027)
			(xy 199.453676 -229.382574) (xy 199.454008 -229.387908) (xy 199.454008 -229.882446) (xy 199.453981 -229.8827)
			(xy 201.398124 -229.8827) (xy 201.398124 -229.882192) (xy 201.398124 -229.387908) (xy 201.398435 -229.382569)
			(xy 201.405992 -229.375026) (xy 201.411332 -229.3747) (xy 201.92746 -229.3747) (xy 201.935269 -229.374369)
			(xy 201.95014 -229.369595) (xy 201.95667 -229.365302) (xy 201.977759 -229.350953) (xy 202.02342 -229.328222)
			(xy 202.072026 -229.312763) (xy 202.122429 -229.30494) (xy 202.173435 -229.30494) (xy 202.223838 -229.312763)
			(xy 202.272444 -229.328222) (xy 202.318105 -229.350953) (xy 202.339194 -229.365302) (xy 202.345727 -229.36959)
			(xy 202.360596 -229.374375) (xy 202.368404 -229.3747) (xy 202.884532 -229.3747) (xy 202.889801 -229.375174)
			(xy 202.897242 -229.382638) (xy 202.89774 -229.387908) (xy 202.89774 -229.882446) (xy 202.897716 -229.8827)
			(xy 205.498192 -229.8827) (xy 205.498192 -229.882192) (xy 205.498192 -229.387908) (xy 205.498532 -229.382577)
			(xy 205.506069 -229.375035) (xy 205.5114 -229.3747) (xy 206.027528 -229.3747) (xy 206.035339 -229.374398)
			(xy 206.05021 -229.369604) (xy 206.056738 -229.365302) (xy 206.077827 -229.350953) (xy 206.123488 -229.328222)
			(xy 206.172094 -229.312763) (xy 206.222497 -229.30494) (xy 206.273503 -229.30494) (xy 206.323906 -229.312763)
			(xy 206.372512 -229.328222) (xy 206.418173 -229.350953) (xy 206.439262 -229.365302) (xy 206.445803 -229.369578)
			(xy 206.460666 -229.37437) (xy 206.468472 -229.3747) (xy 206.9846 -229.3747) (xy 206.989934 -229.375027)
			(xy 206.997476 -229.382574) (xy 206.997808 -229.387908) (xy 206.997808 -229.882192) (xy 264.798048 -229.882192)
			(xy 264.798048 -229.387654) (xy 264.798521 -229.382282) (xy 264.806136 -229.374699) (xy 264.81151 -229.374192)
			(xy 265.327638 -229.374192) (xy 265.335446 -229.373853) (xy 265.350317 -229.369084) (xy 265.356848 -229.364794)
			(xy 265.377937 -229.350445) (xy 265.423598 -229.327714) (xy 265.472204 -229.312255) (xy 265.522607 -229.304432)
			(xy 265.573613 -229.304432) (xy 265.624016 -229.312255) (xy 265.672622 -229.327714) (xy 265.718283 -229.350445)
			(xy 265.739372 -229.364794) (xy 265.745911 -229.369073) (xy 265.760775 -229.373864) (xy 265.768582 -229.374192)
			(xy 266.28471 -229.374192) (xy 266.290064 -229.374739) (xy 266.297647 -229.382301) (xy 266.298172 -229.387654)
			(xy 266.298172 -229.882192) (xy 268.898116 -229.882192) (xy 268.898116 -229.387654) (xy 268.898618 -229.38229)
			(xy 268.906213 -229.374708) (xy 268.911578 -229.374192) (xy 269.427706 -229.374192) (xy 269.435516 -229.373882)
			(xy 269.450388 -229.369094) (xy 269.456916 -229.364794) (xy 269.478005 -229.350445) (xy 269.523666 -229.327714)
			(xy 269.572272 -229.312255) (xy 269.622675 -229.304432) (xy 269.673681 -229.304432) (xy 269.724084 -229.312255)
			(xy 269.77269 -229.327714) (xy 269.818351 -229.350445) (xy 269.83944 -229.364794) (xy 269.845964 -229.369099)
			(xy 269.86084 -229.373874) (xy 269.86865 -229.374192) (xy 270.384778 -229.374192) (xy 270.390128 -229.374761)
			(xy 270.397712 -229.382306) (xy 270.39824 -229.387654) (xy 270.39824 -229.882192) (xy 272.342356 -229.882192)
			(xy 272.342356 -229.387654) (xy 272.342861 -229.382353) (xy 272.350274 -229.374777) (xy 272.355564 -229.374192)
			(xy 272.871692 -229.374192) (xy 272.879502 -229.373876) (xy 272.894373 -229.369092) (xy 272.900902 -229.364794)
			(xy 272.921991 -229.350445) (xy 272.967652 -229.327714) (xy 273.016258 -229.312255) (xy 273.066661 -229.304432)
			(xy 273.117667 -229.304432) (xy 273.16807 -229.312255) (xy 273.216676 -229.327714) (xy 273.262337 -229.350445)
			(xy 273.283426 -229.364794) (xy 273.289953 -229.369093) (xy 273.304826 -229.373872) (xy 273.312636 -229.374192)
			(xy 273.828764 -229.374192) (xy 273.834092 -229.374551) (xy 273.841635 -229.382073) (xy 273.841972 -229.3874)
			(xy 273.841972 -229.387908) (xy 273.841972 -229.882192) (xy 276.442424 -229.882192) (xy 276.442424 -229.387654)
			(xy 276.442957 -229.38236) (xy 276.450351 -229.374787) (xy 276.455632 -229.374192) (xy 276.97176 -229.374192)
			(xy 276.979569 -229.373863) (xy 276.99444 -229.369088) (xy 277.00097 -229.364794) (xy 277.022059 -229.350445)
			(xy 277.06772 -229.327714) (xy 277.116326 -229.312255) (xy 277.166729 -229.304432) (xy 277.217735 -229.304432)
			(xy 277.268138 -229.312255) (xy 277.316744 -229.327714) (xy 277.362405 -229.350445) (xy 277.383494 -229.364794)
			(xy 277.390028 -229.369081) (xy 277.404896 -229.373867) (xy 277.412704 -229.374192) (xy 277.928832 -229.374192)
			(xy 277.934099 -229.374673) (xy 277.941539 -229.382132) (xy 277.94204 -229.3874) (xy 277.94204 -229.387908)
			(xy 277.94204 -229.882192) (xy 279.886156 -229.882192) (xy 279.886156 -229.387654) (xy 279.886661 -229.382353)
			(xy 279.894074 -229.374777) (xy 279.899364 -229.374192) (xy 280.415492 -229.374192) (xy 280.423302 -229.373876)
			(xy 280.438173 -229.369092) (xy 280.444702 -229.364794) (xy 280.465791 -229.350445) (xy 280.511452 -229.327714)
			(xy 280.560058 -229.312255) (xy 280.610461 -229.304432) (xy 280.661467 -229.304432) (xy 280.71187 -229.312255)
			(xy 280.760476 -229.327714) (xy 280.806137 -229.350445) (xy 280.827226 -229.364794) (xy 280.833753 -229.369093)
			(xy 280.848626 -229.373872) (xy 280.856436 -229.374192) (xy 281.372564 -229.374192) (xy 281.377892 -229.374551)
			(xy 281.385435 -229.382073) (xy 281.385772 -229.3874) (xy 281.385772 -229.387908) (xy 281.385772 -229.882192)
			(xy 283.986224 -229.882192) (xy 283.986224 -229.387654) (xy 283.986757 -229.38236) (xy 283.994151 -229.374787)
			(xy 283.999432 -229.374192) (xy 284.51556 -229.374192) (xy 284.523369 -229.373863) (xy 284.53824 -229.369088)
			(xy 284.54477 -229.364794) (xy 284.565859 -229.350445) (xy 284.61152 -229.327714) (xy 284.660126 -229.312255)
			(xy 284.710529 -229.304432) (xy 284.761535 -229.304432) (xy 284.811938 -229.312255) (xy 284.860544 -229.327714)
			(xy 284.906205 -229.350445) (xy 284.927294 -229.364794) (xy 284.933828 -229.369081) (xy 284.948696 -229.373867)
			(xy 284.956504 -229.374192) (xy 285.472632 -229.374192) (xy 285.477899 -229.374673) (xy 285.485339 -229.382132)
			(xy 285.48584 -229.3874) (xy 285.48584 -229.387908) (xy 285.48584 -229.882192) (xy 287.429956 -229.882192)
			(xy 287.429956 -229.387654) (xy 287.430422 -229.38228) (xy 287.438042 -229.374696) (xy 287.443418 -229.374192)
			(xy 287.959546 -229.374192) (xy 287.967354 -229.373857) (xy 287.982226 -229.369086) (xy 287.988756 -229.364794)
			(xy 288.009845 -229.350445) (xy 288.055506 -229.327714) (xy 288.104112 -229.312255) (xy 288.154515 -229.304432)
			(xy 288.205521 -229.304432) (xy 288.255924 -229.312255) (xy 288.30453 -229.327714) (xy 288.350191 -229.350445)
			(xy 288.37128 -229.364794) (xy 288.377817 -229.369076) (xy 288.392683 -229.373865) (xy 288.40049 -229.374192)
			(xy 288.916618 -229.374192) (xy 288.921973 -229.374734) (xy 288.929555 -229.3823) (xy 288.93008 -229.387654)
			(xy 288.93008 -229.882192) (xy 291.530024 -229.882192) (xy 291.530024 -229.387654) (xy 291.530519 -229.382288)
			(xy 291.538119 -229.374706) (xy 291.543486 -229.374192) (xy 292.059614 -229.374192) (xy 292.067425 -229.373886)
			(xy 292.082296 -229.369095) (xy 292.088824 -229.364794) (xy 292.109913 -229.350445) (xy 292.155574 -229.327714)
			(xy 292.20418 -229.312255) (xy 292.254583 -229.304432) (xy 292.305589 -229.304432) (xy 292.355992 -229.312255)
			(xy 292.404598 -229.327714) (xy 292.450259 -229.350445) (xy 292.471348 -229.364794) (xy 292.47787 -229.369102)
			(xy 292.492747 -229.373875) (xy 292.500558 -229.374192) (xy 293.016686 -229.374192) (xy 293.022037 -229.374755)
			(xy 293.029621 -229.382305) (xy 293.030148 -229.387654) (xy 293.030148 -229.882192) (xy 294.974264 -229.882192)
			(xy 294.974264 -229.387654) (xy 294.974762 -229.382351) (xy 294.98218 -229.374775) (xy 294.987472 -229.374192)
			(xy 295.5036 -229.374192) (xy 295.51141 -229.37388) (xy 295.526282 -229.369093) (xy 295.53281 -229.364794)
			(xy 295.553899 -229.350445) (xy 295.59956 -229.327714) (xy 295.648166 -229.312255) (xy 295.698569 -229.304432)
			(xy 295.749575 -229.304432) (xy 295.799978 -229.312255) (xy 295.848584 -229.327714) (xy 295.894245 -229.350445)
			(xy 295.915334 -229.364794) (xy 295.921859 -229.369097) (xy 295.936734 -229.373873) (xy 295.944544 -229.374192)
			(xy 296.460672 -229.374192) (xy 296.466001 -229.374545) (xy 296.473543 -229.382072) (xy 296.47388 -229.3874)
			(xy 296.47388 -229.387908) (xy 296.47388 -229.882192) (xy 299.074332 -229.882192) (xy 299.074332 -229.387654)
			(xy 299.074858 -229.382358) (xy 299.082257 -229.374784) (xy 299.08754 -229.374192) (xy 299.603668 -229.374192)
			(xy 299.611477 -229.373866) (xy 299.626349 -229.369089) (xy 299.632878 -229.364794) (xy 299.653967 -229.350445)
			(xy 299.699628 -229.327714) (xy 299.748234 -229.312255) (xy 299.798637 -229.304432) (xy 299.849643 -229.304432)
			(xy 299.900046 -229.312255) (xy 299.948652 -229.327714) (xy 299.994313 -229.350445) (xy 300.015402 -229.364794)
			(xy 300.021934 -229.369084) (xy 300.036804 -229.373868) (xy 300.044612 -229.374192) (xy 300.56074 -229.374192)
			(xy 300.566008 -229.374668) (xy 300.573448 -229.382131) (xy 300.573948 -229.3874) (xy 300.573948 -229.387908)
			(xy 300.573948 -229.882192) (xy 302.518064 -229.882192) (xy 302.518064 -229.387654) (xy 302.518523 -229.382278)
			(xy 302.526148 -229.374694) (xy 302.531526 -229.374192) (xy 304.004726 -229.374192) (xy 304.010082 -229.374729)
			(xy 304.017663 -229.382299) (xy 304.018188 -229.387654) (xy 304.018188 -229.882192) (xy 306.618132 -229.882192)
			(xy 306.618132 -229.387654) (xy 306.618619 -229.382286) (xy 306.626225 -229.374703) (xy 306.631594 -229.374192)
			(xy 308.104794 -229.374192) (xy 308.110146 -229.37475) (xy 308.11773 -229.382304) (xy 308.118256 -229.387654)
			(xy 308.118256 -229.882192) (xy 411.618176 -229.882192) (xy 411.618176 -229.387654) (xy 411.618663 -229.382348)
			(xy 411.626089 -229.374772) (xy 411.631384 -229.374192) (xy 413.104584 -229.374192) (xy 413.109914 -229.374538)
			(xy 413.117456 -229.38207) (xy 413.117792 -229.3874) (xy 413.117792 -229.387908) (xy 413.117792 -229.882192)
			(xy 415.718244 -229.882192) (xy 415.718244 -229.387654) (xy 415.71876 -229.382355) (xy 415.726165 -229.374781)
			(xy 415.731452 -229.374192) (xy 417.204652 -229.374192) (xy 417.209978 -229.374559) (xy 417.217521 -229.382076)
			(xy 417.21786 -229.3874) (xy 417.21786 -229.882192) (xy 419.161976 -229.882192) (xy 419.161976 -229.387654)
			(xy 419.162424 -229.382275) (xy 419.170056 -229.37469) (xy 419.175438 -229.374192) (xy 419.691566 -229.374192)
			(xy 419.699375 -229.373865) (xy 419.714246 -229.369088) (xy 419.720776 -229.364794) (xy 419.741865 -229.350445)
			(xy 419.787526 -229.327714) (xy 419.836132 -229.312255) (xy 419.886535 -229.304432) (xy 419.937541 -229.304432)
			(xy 419.987944 -229.312255) (xy 420.03655 -229.327714) (xy 420.082211 -229.350445) (xy 420.1033 -229.364794)
			(xy 420.109833 -229.369084) (xy 420.124702 -229.373868) (xy 420.13251 -229.374192) (xy 420.648638 -229.374192)
			(xy 420.653995 -229.374721) (xy 420.661576 -229.382297) (xy 420.6621 -229.387654) (xy 420.6621 -229.882192)
			(xy 423.262044 -229.882192) (xy 423.262044 -229.387654) (xy 423.262521 -229.382283) (xy 423.270133 -229.3747)
			(xy 423.275506 -229.374192) (xy 423.791634 -229.374192) (xy 423.799442 -229.373851) (xy 423.814313 -229.369084)
			(xy 423.820844 -229.364794) (xy 423.841933 -229.350445) (xy 423.887594 -229.327714) (xy 423.9362 -229.312255)
			(xy 423.986603 -229.304432) (xy 424.037609 -229.304432) (xy 424.088012 -229.312255) (xy 424.136618 -229.327714)
			(xy 424.182279 -229.350445) (xy 424.203368 -229.364794) (xy 424.209908 -229.369071) (xy 424.224771 -229.373863)
			(xy 424.232578 -229.374192) (xy 424.748706 -229.374192) (xy 424.75406 -229.374742) (xy 424.761642 -229.382302)
			(xy 424.762168 -229.387654) (xy 424.762168 -229.882192) (xy 426.706284 -229.882192) (xy 426.706284 -229.387654)
			(xy 426.706764 -229.382346) (xy 426.714194 -229.374769) (xy 426.719492 -229.374192) (xy 427.23562 -229.374192)
			(xy 427.243431 -229.373888) (xy 427.258302 -229.369095) (xy 427.26483 -229.364794) (xy 427.285919 -229.350445)
			(xy 427.33158 -229.327714) (xy 427.380186 -229.312255) (xy 427.430589 -229.304432) (xy 427.481595 -229.304432)
			(xy 427.531998 -229.312255) (xy 427.580604 -229.327714) (xy 427.626265 -229.350445) (xy 427.647354 -229.364794)
			(xy 427.653875 -229.369104) (xy 427.668753 -229.373876) (xy 427.676564 -229.374192) (xy 428.192692 -229.374192)
			(xy 428.198023 -229.374532) (xy 428.205565 -229.382069) (xy 428.2059 -229.3874) (xy 428.2059 -229.387908)
			(xy 428.2059 -229.882192) (xy 430.806352 -229.882192) (xy 430.806352 -229.387654) (xy 430.806861 -229.382353)
			(xy 430.814271 -229.374779) (xy 430.81956 -229.374192) (xy 431.335688 -229.374192) (xy 431.343498 -229.373875)
			(xy 431.358369 -229.369091) (xy 431.364898 -229.364794) (xy 431.385987 -229.350445) (xy 431.431648 -229.327714)
			(xy 431.480254 -229.312255) (xy 431.530657 -229.304432) (xy 431.581663 -229.304432) (xy 431.632066 -229.312255)
			(xy 431.680672 -229.327714) (xy 431.726333 -229.350445) (xy 431.747422 -229.364794) (xy 431.75395 -229.369092)
			(xy 431.768823 -229.373871) (xy 431.776632 -229.374192) (xy 432.29276 -229.374192) (xy 432.298087 -229.374554)
			(xy 432.30563 -229.382074) (xy 432.305968 -229.3874) (xy 432.305968 -229.387908) (xy 432.305968 -229.882192)
			(xy 434.250084 -229.882192) (xy 434.250084 -229.387654) (xy 434.250525 -229.382273) (xy 434.258162 -229.374688)
			(xy 434.263546 -229.374192) (xy 434.779674 -229.374192) (xy 434.787483 -229.373869) (xy 434.802355 -229.36909)
			(xy 434.808884 -229.364794) (xy 434.829973 -229.350445) (xy 434.875634 -229.327714) (xy 434.92424 -229.312255)
			(xy 434.974643 -229.304432) (xy 435.025649 -229.304432) (xy 435.076052 -229.312255) (xy 435.124658 -229.327714)
			(xy 435.170319 -229.350445) (xy 435.191408 -229.364794) (xy 435.197939 -229.369087) (xy 435.212809 -229.373869)
			(xy 435.220618 -229.374192) (xy 435.736746 -229.374192) (xy 435.742104 -229.374715) (xy 435.749685 -229.382296)
			(xy 435.750208 -229.387654) (xy 435.750208 -229.882192) (xy 438.350152 -229.882192) (xy 438.350152 -229.387654)
			(xy 438.350621 -229.382281) (xy 438.358239 -229.374697) (xy 438.363614 -229.374192) (xy 438.879742 -229.374192)
			(xy 438.88755 -229.373855) (xy 438.902422 -229.369085) (xy 438.908952 -229.364794) (xy 438.930041 -229.350445)
			(xy 438.975702 -229.327714) (xy 439.024308 -229.312255) (xy 439.074711 -229.304432) (xy 439.125717 -229.304432)
			(xy 439.17612 -229.312255) (xy 439.224726 -229.327714) (xy 439.270387 -229.350445) (xy 439.291476 -229.364794)
			(xy 439.298014 -229.369074) (xy 439.312879 -229.373864) (xy 439.320686 -229.374192) (xy 439.836814 -229.374192)
			(xy 439.842168 -229.374737) (xy 439.849751 -229.382301) (xy 439.850276 -229.387654) (xy 439.850276 -229.882192)
			(xy 441.794392 -229.882192) (xy 441.794392 -229.387654) (xy 441.794954 -229.382367) (xy 441.802328 -229.374796)
			(xy 441.8076 -229.374192) (xy 442.323728 -229.374192) (xy 442.331539 -229.373892) (xy 442.346411 -229.369097)
			(xy 442.352938 -229.364794) (xy 442.374027 -229.350445) (xy 442.419688 -229.327714) (xy 442.468294 -229.312255)
			(xy 442.518697 -229.304432) (xy 442.569703 -229.304432) (xy 442.620106 -229.312255) (xy 442.668712 -229.327714)
			(xy 442.714373 -229.350445) (xy 442.735462 -229.364794) (xy 442.742003 -229.369069) (xy 442.756866 -229.373862)
			(xy 442.764672 -229.374192) (xy 443.2808 -229.374192) (xy 443.286063 -229.374695) (xy 443.293505 -229.382137)
			(xy 443.294008 -229.3874) (xy 443.294008 -229.387908) (xy 443.294008 -229.882192) (xy 445.89446 -229.882192)
			(xy 445.89446 -229.387654) (xy 445.894961 -229.382352) (xy 445.902377 -229.374776) (xy 445.907668 -229.374192)
			(xy 446.423796 -229.374192) (xy 446.431606 -229.373878) (xy 446.446478 -229.369092) (xy 446.453006 -229.364794)
			(xy 446.474095 -229.350445) (xy 446.519756 -229.327714) (xy 446.568362 -229.312255) (xy 446.618765 -229.304432)
			(xy 446.669771 -229.304432) (xy 446.720174 -229.312255) (xy 446.76878 -229.327714) (xy 446.814441 -229.350445)
			(xy 446.83553 -229.364794) (xy 446.842056 -229.369095) (xy 446.85693 -229.373872) (xy 446.86474 -229.374192)
			(xy 447.380868 -229.374192) (xy 447.386196 -229.374548) (xy 447.393739 -229.382073) (xy 447.394076 -229.3874)
			(xy 447.394076 -229.387908) (xy 447.394076 -229.882192) (xy 449.338192 -229.882192) (xy 449.338192 -229.387654)
			(xy 449.338754 -229.382367) (xy 449.346128 -229.374796) (xy 449.3514 -229.374192) (xy 449.867528 -229.374192)
			(xy 449.875339 -229.373892) (xy 449.890211 -229.369097) (xy 449.896738 -229.364794) (xy 449.917827 -229.350445)
			(xy 449.963488 -229.327714) (xy 450.012094 -229.312255) (xy 450.062497 -229.304432) (xy 450.113503 -229.304432)
			(xy 450.163906 -229.312255) (xy 450.212512 -229.327714) (xy 450.258173 -229.350445) (xy 450.279262 -229.364794)
			(xy 450.285803 -229.369069) (xy 450.300666 -229.373862) (xy 450.308472 -229.374192) (xy 450.8246 -229.374192)
			(xy 450.829863 -229.374695) (xy 450.837305 -229.382137) (xy 450.837808 -229.3874) (xy 450.837808 -229.387908)
			(xy 450.837808 -229.882192) (xy 453.43826 -229.882192) (xy 453.43826 -229.387654) (xy 453.438761 -229.382352)
			(xy 453.446177 -229.374776) (xy 453.451468 -229.374192) (xy 453.967596 -229.374192) (xy 453.975406 -229.373878)
			(xy 453.990278 -229.369092) (xy 453.996806 -229.364794) (xy 454.017895 -229.350445) (xy 454.063556 -229.327714)
			(xy 454.112162 -229.312255) (xy 454.162565 -229.304432) (xy 454.213571 -229.304432) (xy 454.263974 -229.312255)
			(xy 454.31258 -229.327714) (xy 454.358241 -229.350445) (xy 454.37933 -229.364794) (xy 454.385856 -229.369095)
			(xy 454.40073 -229.373872) (xy 454.40854 -229.374192) (xy 454.924668 -229.374192) (xy 454.929996 -229.374548)
			(xy 454.937539 -229.382073) (xy 454.937876 -229.3874) (xy 454.937876 -229.387908) (xy 454.937876 -229.882192)
			(xy 454.937565 -229.887531) (xy 454.930008 -229.895074) (xy 454.924668 -229.8954) (xy 454.408794 -229.8954)
			(xy 454.400921 -229.895701) (xy 454.385917 -229.900476) (xy 454.37933 -229.904798) (xy 454.358258 -229.919199)
			(xy 454.312612 -229.942027) (xy 454.264004 -229.957582) (xy 454.213585 -229.965497) (xy 454.188068 -229.966012)
			(xy 454.162549 -229.965503) (xy 454.112123 -229.957614) (xy 454.063511 -229.94206) (xy 454.017872 -229.91921)
			(xy 453.996806 -229.904798) (xy 453.990215 -229.900482) (xy 453.975215 -229.895696) (xy 453.967342 -229.8954)
			(xy 453.451468 -229.8954) (xy 453.446199 -229.894926) (xy 453.438758 -229.887462) (xy 453.43826 -229.882192)
			(xy 450.837808 -229.882192) (xy 450.837468 -229.887523) (xy 450.829931 -229.895065) (xy 450.8246 -229.8954)
			(xy 450.308726 -229.8954) (xy 450.30085 -229.895672) (xy 450.285847 -229.900467) (xy 450.279262 -229.904798)
			(xy 450.258182 -229.919185) (xy 450.212538 -229.942016) (xy 450.163933 -229.957575) (xy 450.113517 -229.965495)
			(xy 450.088 -229.966012) (xy 450.062479 -229.965537) (xy 450.012052 -229.957638) (xy 449.96344 -229.942073)
			(xy 449.917802 -229.919215) (xy 449.896738 -229.904798) (xy 449.89014 -229.900495) (xy 449.875145 -229.895701)
			(xy 449.867274 -229.8954) (xy 449.3514 -229.8954) (xy 449.346066 -229.895073) (xy 449.338524 -229.887526)
			(xy 449.338192 -229.882192) (xy 447.394076 -229.882192) (xy 447.393765 -229.887531) (xy 447.386208 -229.895074)
			(xy 447.380868 -229.8954) (xy 446.864994 -229.8954) (xy 446.857121 -229.895701) (xy 446.842117 -229.900476)
			(xy 446.83553 -229.904798) (xy 446.814458 -229.919199) (xy 446.768812 -229.942027) (xy 446.720204 -229.957582)
			(xy 446.669785 -229.965497) (xy 446.644268 -229.966012) (xy 446.618749 -229.965503) (xy 446.568323 -229.957614)
			(xy 446.519711 -229.94206) (xy 446.474072 -229.91921) (xy 446.453006 -229.904798) (xy 446.446415 -229.900482)
			(xy 446.431415 -229.895696) (xy 446.423542 -229.8954) (xy 445.907668 -229.8954) (xy 445.902399 -229.894926)
			(xy 445.894958 -229.887462) (xy 445.89446 -229.882192) (xy 443.294008 -229.882192) (xy 443.293668 -229.887523)
			(xy 443.286131 -229.895065) (xy 443.2808 -229.8954) (xy 442.764926 -229.8954) (xy 442.75705 -229.895672)
			(xy 442.742047 -229.900467) (xy 442.735462 -229.904798) (xy 442.714382 -229.919185) (xy 442.668738 -229.942016)
			(xy 442.620133 -229.957575) (xy 442.569717 -229.965495) (xy 442.5442 -229.966012) (xy 442.518679 -229.965537)
			(xy 442.468252 -229.957638) (xy 442.41964 -229.942073) (xy 442.374002 -229.919215) (xy 442.352938 -229.904798)
			(xy 442.34634 -229.900495) (xy 442.331345 -229.895701) (xy 442.323474 -229.8954) (xy 441.8076 -229.8954)
			(xy 441.802266 -229.895073) (xy 441.794724 -229.887526) (xy 441.794392 -229.882192) (xy 439.850276 -229.882192)
			(xy 439.849965 -229.887531) (xy 439.842408 -229.895074) (xy 439.837068 -229.8954) (xy 439.83656 -229.8954)
			(xy 439.32094 -229.8954) (xy 439.313065 -229.895678) (xy 439.298061 -229.900469) (xy 439.291476 -229.904798)
			(xy 439.270392 -229.919179) (xy 439.22475 -229.942011) (xy 439.176146 -229.957572) (xy 439.12573 -229.965494)
			(xy 439.100214 -229.966012) (xy 439.074694 -229.96553) (xy 439.024266 -229.957633) (xy 438.975655 -229.942071)
			(xy 438.930017 -229.919214) (xy 438.908952 -229.904798) (xy 438.902373 -229.900461) (xy 438.887363 -229.895688)
			(xy 438.879488 -229.8954) (xy 438.363614 -229.8954) (xy 438.358321 -229.894872) (xy 438.350751 -229.887473)
			(xy 438.350152 -229.882192) (xy 435.750208 -229.882192) (xy 435.749868 -229.887523) (xy 435.742331 -229.895065)
			(xy 435.737 -229.8954) (xy 435.736492 -229.8954) (xy 435.220872 -229.8954) (xy 435.212998 -229.895692)
			(xy 435.197994 -229.900473) (xy 435.191408 -229.904798) (xy 435.170343 -229.919208) (xy 435.124694 -229.942034)
			(xy 435.076084 -229.957587) (xy 435.025664 -229.965499) (xy 435.000146 -229.966012) (xy 434.974626 -229.965514)
			(xy 434.9242 -229.957622) (xy 434.875588 -229.942064) (xy 434.829949 -229.919212) (xy 434.808884 -229.904798)
			(xy 434.802298 -229.900474) (xy 434.787294 -229.895693) (xy 434.77942 -229.8954) (xy 434.263546 -229.8954)
			(xy 434.258256 -229.894851) (xy 434.250685 -229.887468) (xy 434.250084 -229.882192) (xy 432.305968 -229.882192)
			(xy 432.305664 -229.887533) (xy 432.298102 -229.895077) (xy 432.29276 -229.8954) (xy 431.776886 -229.8954)
			(xy 431.769012 -229.895698) (xy 431.754009 -229.900475) (xy 431.747422 -229.904798) (xy 431.726353 -229.919202)
			(xy 431.680705 -229.942029) (xy 431.632097 -229.957584) (xy 431.581678 -229.965498) (xy 431.55616 -229.966012)
			(xy 431.53064 -229.965507) (xy 431.480214 -229.957617) (xy 431.431603 -229.942061) (xy 431.385964 -229.919211)
			(xy 431.364898 -229.904798) (xy 431.358309 -229.900479) (xy 431.343307 -229.895695) (xy 431.335434 -229.8954)
			(xy 430.81956 -229.8954) (xy 430.81429 -229.894931) (xy 430.80685 -229.887463) (xy 430.806352 -229.882192)
			(xy 428.2059 -229.882192) (xy 428.205567 -229.887525) (xy 428.198025 -229.895067) (xy 428.192692 -229.8954)
			(xy 427.676818 -229.8954) (xy 427.668946 -229.895711) (xy 427.653942 -229.900479) (xy 427.647354 -229.904798)
			(xy 427.626276 -229.919188) (xy 427.580632 -229.942019) (xy 427.532026 -229.957577) (xy 427.481609 -229.965495)
			(xy 427.456092 -229.966012) (xy 427.430573 -229.965491) (xy 427.380148 -229.957606) (xy 427.331536 -229.942055)
			(xy 427.285896 -229.919209) (xy 427.26483 -229.904798) (xy 427.258234 -229.900492) (xy 427.243237 -229.8957)
			(xy 427.235366 -229.8954) (xy 426.719492 -229.8954) (xy 426.714226 -229.89491) (xy 426.706784 -229.887458)
			(xy 426.706284 -229.882192) (xy 424.762168 -229.882192) (xy 424.761864 -229.887533) (xy 424.754302 -229.895077)
			(xy 424.74896 -229.8954) (xy 424.748452 -229.8954) (xy 424.232832 -229.8954) (xy 424.224956 -229.895675)
			(xy 424.209953 -229.900468) (xy 424.203368 -229.904798) (xy 424.182286 -229.919182) (xy 424.136643 -229.942014)
			(xy 424.088039 -229.957574) (xy 424.037622 -229.965494) (xy 424.012106 -229.966012) (xy 423.986585 -229.965534)
			(xy 423.936158 -229.957636) (xy 423.887547 -229.942072) (xy 423.841909 -229.919214) (xy 423.820844 -229.904798)
			(xy 423.814267 -229.900458) (xy 423.799256 -229.895687) (xy 423.79138 -229.8954) (xy 423.275506 -229.8954)
			(xy 423.270212 -229.894878) (xy 423.262643 -229.887474) (xy 423.262044 -229.882192) (xy 420.6621 -229.882192)
			(xy 420.661767 -229.887525) (xy 420.654225 -229.895067) (xy 420.648892 -229.8954) (xy 420.648384 -229.8954)
			(xy 420.132764 -229.8954) (xy 420.12489 -229.895688) (xy 420.109886 -229.900472) (xy 420.1033 -229.904798)
			(xy 420.082209 -229.919169) (xy 420.036569 -229.942003) (xy 419.987968 -229.957567) (xy 419.937554 -229.965492)
			(xy 419.912038 -229.966012) (xy 419.886518 -229.965518) (xy 419.836091 -229.957625) (xy 419.78748 -229.942066)
			(xy 419.741841 -229.919212) (xy 419.720776 -229.904798) (xy 419.714192 -229.900471) (xy 419.699186 -229.895692)
			(xy 419.691312 -229.8954) (xy 419.175438 -229.8954) (xy 419.170148 -229.894856) (xy 419.162577 -229.887469)
			(xy 419.161976 -229.882192) (xy 417.21786 -229.882192) (xy 417.217563 -229.887535) (xy 417.209996 -229.895079)
			(xy 417.204652 -229.8954) (xy 415.731452 -229.8954) (xy 415.726182 -229.894936) (xy 415.718741 -229.887464)
			(xy 415.718244 -229.882192) (xy 413.117792 -229.882192) (xy 413.117466 -229.887527) (xy 413.109919 -229.89507)
			(xy 413.104584 -229.8954) (xy 411.631384 -229.8954) (xy 411.626117 -229.894915) (xy 411.618675 -229.88746)
			(xy 411.618176 -229.882192) (xy 308.118256 -229.882192) (xy 308.117705 -229.887442) (xy 308.110296 -229.894883)
			(xy 308.105048 -229.8954) (xy 308.10454 -229.8954) (xy 306.631594 -229.8954) (xy 306.626298 -229.894886)
			(xy 306.61873 -229.887476) (xy 306.618132 -229.882192) (xy 304.018188 -229.882192) (xy 304.017866 -229.887528)
			(xy 304.010316 -229.895071) (xy 304.00498 -229.8954) (xy 302.531526 -229.8954) (xy 302.526234 -229.894864)
			(xy 302.518664 -229.887471) (xy 302.518064 -229.882192) (xy 300.573948 -229.882192) (xy 300.573404 -229.887444)
			(xy 300.56599 -229.894885) (xy 300.56074 -229.8954) (xy 300.044866 -229.8954) (xy 300.036992 -229.895689)
			(xy 300.021988 -229.900473) (xy 300.015402 -229.904798) (xy 299.99431 -229.919168) (xy 299.948671 -229.942003)
			(xy 299.900069 -229.957567) (xy 299.849656 -229.965492) (xy 299.82414 -229.966012) (xy 299.79862 -229.965517)
			(xy 299.748193 -229.957624) (xy 299.699582 -229.942065) (xy 299.653943 -229.919212) (xy 299.632878 -229.904798)
			(xy 299.626293 -229.900471) (xy 299.611288 -229.895692) (xy 299.603414 -229.8954) (xy 299.08754 -229.8954)
			(xy 299.082211 -229.895045) (xy 299.074668 -229.88752) (xy 299.074332 -229.882192) (xy 296.47388 -229.882192)
			(xy 296.473565 -229.88753) (xy 296.466011 -229.895073) (xy 296.460672 -229.8954) (xy 295.944798 -229.8954)
			(xy 295.936925 -229.895703) (xy 295.921921 -229.900477) (xy 295.915334 -229.904798) (xy 295.894261 -229.919197)
			(xy 295.848615 -229.942025) (xy 295.800008 -229.957581) (xy 295.749589 -229.965497) (xy 295.724072 -229.966012)
			(xy 295.698553 -229.965501) (xy 295.648127 -229.957613) (xy 295.599515 -229.942059) (xy 295.553876 -229.91921)
			(xy 295.53281 -229.904798) (xy 295.526218 -229.900484) (xy 295.511218 -229.895697) (xy 295.503346 -229.8954)
			(xy 294.987472 -229.8954) (xy 294.982204 -229.894923) (xy 294.974762 -229.887461) (xy 294.974264 -229.882192)
			(xy 293.030148 -229.882192) (xy 293.029604 -229.887444) (xy 293.02219 -229.894885) (xy 293.01694 -229.8954)
			(xy 293.016432 -229.8954) (xy 292.500812 -229.8954) (xy 292.492939 -229.895709) (xy 292.477936 -229.900479)
			(xy 292.471348 -229.904798) (xy 292.450271 -229.919191) (xy 292.404627 -229.942021) (xy 292.35602 -229.957578)
			(xy 292.305603 -229.965496) (xy 292.280086 -229.966012) (xy 292.254567 -229.965494) (xy 292.204141 -229.957608)
			(xy 292.15553 -229.942056) (xy 292.10989 -229.919209) (xy 292.088824 -229.904798) (xy 292.082229 -229.900489)
			(xy 292.067232 -229.895699) (xy 292.05936 -229.8954) (xy 291.543486 -229.8954) (xy 291.538189 -229.894891)
			(xy 291.530621 -229.887477) (xy 291.530024 -229.882192) (xy 288.93008 -229.882192) (xy 288.929765 -229.88753)
			(xy 288.922211 -229.895073) (xy 288.916872 -229.8954) (xy 288.916364 -229.8954) (xy 288.400744 -229.8954)
			(xy 288.392869 -229.89568) (xy 288.377865 -229.90047) (xy 288.37128 -229.904798) (xy 288.350195 -229.919177)
			(xy 288.304553 -229.94201) (xy 288.255949 -229.957571) (xy 288.205534 -229.965494) (xy 288.180018 -229.966012)
			(xy 288.154498 -229.965528) (xy 288.104071 -229.957632) (xy 288.055459 -229.94207) (xy 288.009821 -229.919214)
			(xy 287.988756 -229.904798) (xy 287.982176 -229.900463) (xy 287.967167 -229.895689) (xy 287.959292 -229.8954)
			(xy 287.443418 -229.8954) (xy 287.438125 -229.89487) (xy 287.430555 -229.887472) (xy 287.429956 -229.882192)
			(xy 285.48584 -229.882192) (xy 285.485303 -229.887446) (xy 285.477885 -229.894887) (xy 285.472632 -229.8954)
			(xy 284.956758 -229.8954) (xy 284.948883 -229.895686) (xy 284.93388 -229.900472) (xy 284.927294 -229.904798)
			(xy 284.906205 -229.919171) (xy 284.860565 -229.942005) (xy 284.811962 -229.957568) (xy 284.761548 -229.965492)
			(xy 284.736032 -229.966012) (xy 284.710512 -229.965521) (xy 284.660085 -229.957627) (xy 284.611474 -229.942067)
			(xy 284.565835 -229.919213) (xy 284.54477 -229.904798) (xy 284.538187 -229.900468) (xy 284.52318 -229.895691)
			(xy 284.515306 -229.8954) (xy 283.999432 -229.8954) (xy 283.994102 -229.895051) (xy 283.986559 -229.887521)
			(xy 283.986224 -229.882192) (xy 281.385772 -229.882192) (xy 281.385464 -229.887532) (xy 281.377905 -229.895076)
			(xy 281.372564 -229.8954) (xy 280.85669 -229.8954) (xy 280.848817 -229.895699) (xy 280.833813 -229.900476)
			(xy 280.827226 -229.904798) (xy 280.806156 -229.919201) (xy 280.760509 -229.942028) (xy 280.7119 -229.957583)
			(xy 280.661481 -229.965498) (xy 280.635964 -229.966012) (xy 280.610445 -229.965505) (xy 280.560018 -229.957615)
			(xy 280.511407 -229.94206) (xy 280.465768 -229.919211) (xy 280.444702 -229.904798) (xy 280.438112 -229.900481)
			(xy 280.423111 -229.895695) (xy 280.415238 -229.8954) (xy 279.899364 -229.8954) (xy 279.894095 -229.894928)
			(xy 279.886654 -229.887463) (xy 279.886156 -229.882192) (xy 277.94204 -229.882192) (xy 277.941503 -229.887446)
			(xy 277.934085 -229.894887) (xy 277.928832 -229.8954) (xy 277.412958 -229.8954) (xy 277.405083 -229.895686)
			(xy 277.39008 -229.900472) (xy 277.383494 -229.904798) (xy 277.362405 -229.919171) (xy 277.316765 -229.942005)
			(xy 277.268162 -229.957568) (xy 277.217748 -229.965492) (xy 277.192232 -229.966012) (xy 277.166712 -229.965521)
			(xy 277.116285 -229.957627) (xy 277.067674 -229.942067) (xy 277.022035 -229.919213) (xy 277.00097 -229.904798)
			(xy 276.994387 -229.900468) (xy 276.97938 -229.895691) (xy 276.971506 -229.8954) (xy 276.455632 -229.8954)
			(xy 276.450302 -229.895051) (xy 276.442759 -229.887521) (xy 276.442424 -229.882192) (xy 273.841972 -229.882192)
			(xy 273.841664 -229.887532) (xy 273.834105 -229.895076) (xy 273.828764 -229.8954) (xy 273.31289 -229.8954)
			(xy 273.305017 -229.895699) (xy 273.290013 -229.900476) (xy 273.283426 -229.904798) (xy 273.262356 -229.919201)
			(xy 273.216709 -229.942028) (xy 273.1681 -229.957583) (xy 273.117681 -229.965498) (xy 273.092164 -229.966012)
			(xy 273.066645 -229.965505) (xy 273.016218 -229.957615) (xy 272.967607 -229.94206) (xy 272.921968 -229.919211)
			(xy 272.900902 -229.904798) (xy 272.894312 -229.900481) (xy 272.879311 -229.895695) (xy 272.871438 -229.8954)
			(xy 272.355564 -229.8954) (xy 272.350295 -229.894928) (xy 272.342854 -229.887463) (xy 272.342356 -229.882192)
			(xy 270.39824 -229.882192) (xy 270.397703 -229.887446) (xy 270.390285 -229.894887) (xy 270.385032 -229.8954)
			(xy 270.384524 -229.8954) (xy 269.868904 -229.8954) (xy 269.861031 -229.895705) (xy 269.846027 -229.900478)
			(xy 269.83944 -229.904798) (xy 269.818366 -229.919194) (xy 269.77272 -229.942023) (xy 269.724113 -229.95758)
			(xy 269.673695 -229.965497) (xy 269.648178 -229.966012) (xy 269.622659 -229.965498) (xy 269.572233 -229.957611)
			(xy 269.523621 -229.942058) (xy 269.477982 -229.91921) (xy 269.456916 -229.904798) (xy 269.450323 -229.900486)
			(xy 269.435324 -229.895697) (xy 269.427452 -229.8954) (xy 268.911578 -229.8954) (xy 268.906281 -229.894896)
			(xy 268.898713 -229.887479) (xy 268.898116 -229.882192) (xy 266.298172 -229.882192) (xy 266.297864 -229.887532)
			(xy 266.290305 -229.895076) (xy 266.284964 -229.8954) (xy 266.284456 -229.8954) (xy 265.768836 -229.8954)
			(xy 265.760961 -229.895676) (xy 265.745957 -229.900469) (xy 265.739372 -229.904798) (xy 265.718289 -229.919181)
			(xy 265.672646 -229.942013) (xy 265.624042 -229.957573) (xy 265.573626 -229.965494) (xy 265.54811 -229.966012)
			(xy 265.522589 -229.965532) (xy 265.472162 -229.957634) (xy 265.423551 -229.942071) (xy 265.377913 -229.919214)
			(xy 265.356848 -229.904798) (xy 265.35027 -229.90046) (xy 265.33526 -229.895687) (xy 265.327384 -229.8954)
			(xy 264.81151 -229.8954) (xy 264.806216 -229.894875) (xy 264.798647 -229.887474) (xy 264.798048 -229.882192)
			(xy 206.997808 -229.882192) (xy 206.997808 -229.882446) (xy 206.997246 -229.887733) (xy 206.989872 -229.895304)
			(xy 206.9846 -229.895908) (xy 206.468726 -229.895908) (xy 206.460917 -229.896231) (xy 206.446045 -229.90101)
			(xy 206.439516 -229.905306) (xy 206.418384 -229.919639) (xy 206.372664 -229.942371) (xy 206.323994 -229.957806)
			(xy 206.27353 -229.965577) (xy 206.248 -229.966012) (xy 206.22247 -229.965567) (xy 206.172007 -229.957792)
			(xy 206.123335 -229.942365) (xy 206.077607 -229.919652) (xy 206.056484 -229.905306) (xy 206.049955 -229.90101)
			(xy 206.035083 -229.89623) (xy 206.027274 -229.895908) (xy 205.5114 -229.895908) (xy 205.506137 -229.895405)
			(xy 205.498695 -229.887963) (xy 205.498192 -229.8827) (xy 202.897716 -229.8827) (xy 202.897239 -229.887748)
			(xy 202.889823 -229.895324) (xy 202.884532 -229.895908) (xy 202.368658 -229.895908) (xy 202.36085 -229.896245)
			(xy 202.345978 -229.901015) (xy 202.339448 -229.905306) (xy 202.318335 -229.919669) (xy 202.272608 -229.942394)
			(xy 202.223932 -229.95782) (xy 202.173464 -229.965582) (xy 202.147932 -229.966012) (xy 202.122403 -229.965551)
			(xy 202.07194 -229.957781) (xy 202.023268 -229.942359) (xy 201.977539 -229.91965) (xy 201.956416 -229.905306)
			(xy 201.94988 -229.901023) (xy 201.935013 -229.896235) (xy 201.927206 -229.895908) (xy 201.411332 -229.895908)
			(xy 201.406004 -229.895552) (xy 201.398461 -229.888027) (xy 201.398124 -229.8827) (xy 199.453981 -229.8827)
			(xy 199.453446 -229.887733) (xy 199.446072 -229.895304) (xy 199.4408 -229.895908) (xy 198.924926 -229.895908)
			(xy 198.917117 -229.896231) (xy 198.902245 -229.90101) (xy 198.895716 -229.905306) (xy 198.874584 -229.919639)
			(xy 198.828864 -229.942371) (xy 198.780194 -229.957806) (xy 198.72973 -229.965577) (xy 198.7042 -229.966012)
			(xy 198.67867 -229.965567) (xy 198.628207 -229.957792) (xy 198.579535 -229.942365) (xy 198.533807 -229.919652)
			(xy 198.512684 -229.905306) (xy 198.506155 -229.90101) (xy 198.491283 -229.89623) (xy 198.483474 -229.895908)
			(xy 197.9676 -229.895908) (xy 197.962337 -229.895405) (xy 197.954895 -229.887963) (xy 197.954392 -229.8827)
			(xy 195.353916 -229.8827) (xy 195.353439 -229.887748) (xy 195.346023 -229.895324) (xy 195.340732 -229.895908)
			(xy 194.824858 -229.895908) (xy 194.81705 -229.896245) (xy 194.802178 -229.901015) (xy 194.795648 -229.905306)
			(xy 194.774535 -229.919669) (xy 194.728808 -229.942394) (xy 194.680132 -229.95782) (xy 194.629664 -229.965582)
			(xy 194.604132 -229.966012) (xy 194.578603 -229.965551) (xy 194.52814 -229.957781) (xy 194.479468 -229.942359)
			(xy 194.433739 -229.91965) (xy 194.412616 -229.905306) (xy 194.40608 -229.901023) (xy 194.391213 -229.896235)
			(xy 194.383406 -229.895908) (xy 193.867532 -229.895908) (xy 193.862204 -229.895552) (xy 193.854661 -229.888027)
			(xy 193.854324 -229.8827) (xy 191.910183 -229.8827) (xy 191.909685 -229.887804) (xy 191.902104 -229.895385)
			(xy 191.896746 -229.895908) (xy 191.380872 -229.895908) (xy 191.373061 -229.896208) (xy 191.358189 -229.901003)
			(xy 191.351662 -229.905306) (xy 191.330545 -229.919662) (xy 191.28482 -229.942389) (xy 191.236145 -229.957817)
			(xy 191.185677 -229.965581) (xy 191.160146 -229.966012) (xy 191.134617 -229.965544) (xy 191.084155 -229.957776)
			(xy 191.035483 -229.942356) (xy 190.989753 -229.919649) (xy 190.96863 -229.905306) (xy 190.962091 -229.901028)
			(xy 190.947227 -229.896237) (xy 190.93942 -229.895908) (xy 190.423546 -229.895908) (xy 190.418199 -229.895323)
			(xy 190.410613 -229.88779) (xy 190.410084 -229.882446) (xy 187.81014 -229.882446) (xy 187.809678 -229.887821)
			(xy 187.802055 -229.895405) (xy 187.796678 -229.895908) (xy 187.280804 -229.895908) (xy 187.272994 -229.896222)
			(xy 187.258122 -229.901008) (xy 187.251594 -229.905306) (xy 187.230468 -229.919649) (xy 187.184746 -229.942378)
			(xy 187.136074 -229.95781) (xy 187.085609 -229.965578) (xy 187.060078 -229.966012) (xy 187.034548 -229.965578)
			(xy 186.984084 -229.9578) (xy 186.935412 -229.94237) (xy 186.889684 -229.919653) (xy 186.868562 -229.905306)
			(xy 186.862038 -229.901002) (xy 186.847162 -229.896227) (xy 186.839352 -229.895908) (xy 186.323478 -229.895908)
			(xy 186.318123 -229.895369) (xy 186.310541 -229.887801) (xy 186.310016 -229.882446) (xy 184.3659 -229.882446)
			(xy 184.365345 -229.887735) (xy 184.357966 -229.895306) (xy 184.352692 -229.895908) (xy 183.836818 -229.895908)
			(xy 183.829008 -229.896228) (xy 183.814137 -229.901009) (xy 183.807608 -229.905306) (xy 183.786478 -229.919643)
			(xy 183.740758 -229.942373) (xy 183.692087 -229.957807) (xy 183.641622 -229.965577) (xy 183.616092 -229.966012)
			(xy 183.590562 -229.965571) (xy 183.540099 -229.957795) (xy 183.491427 -229.942367) (xy 183.445699 -229.919652)
			(xy 183.424576 -229.905306) (xy 183.418049 -229.901007) (xy 183.403175 -229.896229) (xy 183.395366 -229.895908)
			(xy 182.879492 -229.895908) (xy 182.874228 -229.895411) (xy 182.866786 -229.887964) (xy 182.866284 -229.8827)
			(xy 180.265808 -229.8827) (xy 180.265338 -229.88775) (xy 180.257917 -229.895326) (xy 180.252624 -229.895908)
			(xy 179.73675 -229.895908) (xy 179.728942 -229.896241) (xy 179.71407 -229.901014) (xy 179.70754 -229.905306)
			(xy 179.686429 -229.919672) (xy 179.640702 -229.942396) (xy 179.592025 -229.957822) (xy 179.541556 -229.965583)
			(xy 179.516024 -229.966012) (xy 179.490495 -229.965555) (xy 179.440032 -229.957784) (xy 179.39136 -229.94236)
			(xy 179.345631 -229.91965) (xy 179.324508 -229.905306) (xy 179.317974 -229.90102) (xy 179.303106 -229.896233)
			(xy 179.295298 -229.895908) (xy 178.779424 -229.895908) (xy 178.774095 -229.895557) (xy 178.766553 -229.888028)
			(xy 178.766216 -229.8827) (xy 176.822076 -229.8827) (xy 176.821584 -229.887806) (xy 176.813999 -229.895387)
			(xy 176.808638 -229.895908) (xy 176.292764 -229.895908) (xy 176.284956 -229.896248) (xy 176.270085 -229.901016)
			(xy 176.263554 -229.905306) (xy 176.242439 -229.919666) (xy 176.196713 -229.942392) (xy 176.148038 -229.957819)
			(xy 176.09757 -229.965581) (xy 176.072038 -229.966012) (xy 176.046509 -229.965548) (xy 175.996047 -229.957779)
			(xy 175.947374 -229.942358) (xy 175.901645 -229.919649) (xy 175.880522 -229.905306) (xy 175.873985 -229.901025)
			(xy 175.859119 -229.896235) (xy 175.851312 -229.895908) (xy 175.335438 -229.895908) (xy 175.33009 -229.895329)
			(xy 175.322504 -229.887791) (xy 175.321976 -229.882446) (xy 172.722032 -229.882446) (xy 172.721577 -229.887823)
			(xy 172.713949 -229.895407) (xy 172.70857 -229.895908) (xy 172.192696 -229.895908) (xy 172.184886 -229.896219)
			(xy 172.170014 -229.901007) (xy 172.163486 -229.905306) (xy 172.142362 -229.919652) (xy 172.09664 -229.942381)
			(xy 172.047967 -229.957812) (xy 171.997501 -229.965579) (xy 171.97197 -229.966012) (xy 171.94644 -229.965582)
			(xy 171.895976 -229.957803) (xy 171.847304 -229.942371) (xy 171.801576 -229.919654) (xy 171.780454 -229.905306)
			(xy 171.773932 -229.900999) (xy 171.759055 -229.896226) (xy 171.751244 -229.895908) (xy 171.23537 -229.895908)
			(xy 171.230013 -229.895374) (xy 171.222432 -229.887802) (xy 171.221908 -229.882446) (xy 169.277792 -229.882446)
			(xy 169.277244 -229.887736) (xy 169.269861 -229.895309) (xy 169.264584 -229.895908) (xy 167.791384 -229.895908)
			(xy 167.786119 -229.895416) (xy 167.778678 -229.887965) (xy 167.778176 -229.8827) (xy 165.177701 -229.8827)
			(xy 165.177237 -229.887752) (xy 165.169811 -229.895328) (xy 165.164516 -229.895908) (xy 163.691316 -229.895908)
			(xy 163.685986 -229.895562) (xy 163.678444 -229.88803) (xy 163.678108 -229.8827) (xy 60.178164 -229.8827)
			(xy 60.177683 -229.887809) (xy 60.17009 -229.895391) (xy 60.164726 -229.895908) (xy 58.691526 -229.895908)
			(xy 58.686176 -229.895337) (xy 58.678592 -229.887793) (xy 58.678064 -229.882446) (xy 56.07812 -229.882446)
			(xy 56.077676 -229.887826) (xy 56.070041 -229.895411) (xy 56.064658 -229.895908) (xy 54.591458 -229.895908)
			(xy 54.5861 -229.895382) (xy 54.578519 -229.887804) (xy 54.577996 -229.882446) (xy 52.63388 -229.882446)
			(xy 52.633343 -229.887739) (xy 52.625952 -229.895312) (xy 52.620672 -229.895908) (xy 52.104798 -229.895908)
			(xy 52.096988 -229.896219) (xy 52.082116 -229.901007) (xy 52.075588 -229.905306) (xy 52.054464 -229.919651)
			(xy 52.008741 -229.94238) (xy 51.960069 -229.957812) (xy 51.909603 -229.965579) (xy 51.884072 -229.966012)
			(xy 51.858542 -229.965581) (xy 51.808078 -229.957802) (xy 51.759406 -229.942371) (xy 51.713678 -229.919654)
			(xy 51.692556 -229.905306) (xy 51.686033 -229.901) (xy 51.671156 -229.896226) (xy 51.663346 -229.895908)
			(xy 51.147472 -229.895908) (xy 51.142206 -229.895424) (xy 51.134765 -229.887967) (xy 51.134264 -229.8827)
			(xy 48.533789 -229.8827) (xy 48.533335 -229.887755) (xy 48.525903 -229.895332) (xy 48.520604 -229.895908)
			(xy 48.00473 -229.895908) (xy 47.996921 -229.896233) (xy 47.982049 -229.901011) (xy 47.97552 -229.905306)
			(xy 47.954387 -229.919637) (xy 47.908668 -229.942369) (xy 47.859998 -229.957805) (xy 47.809534 -229.965576)
			(xy 47.784004 -229.966012) (xy 47.758474 -229.965565) (xy 47.708011 -229.957791) (xy 47.659339 -229.942364)
			(xy 47.613611 -229.919651) (xy 47.592488 -229.905306) (xy 47.585958 -229.901012) (xy 47.571087 -229.896231)
			(xy 47.563278 -229.895908) (xy 47.047404 -229.895908) (xy 47.042072 -229.89557) (xy 47.034531 -229.888032)
			(xy 47.034196 -229.8827) (xy 45.090056 -229.8827) (xy 45.089582 -229.887811) (xy 45.081984 -229.895393)
			(xy 45.076618 -229.895908) (xy 44.560744 -229.895908) (xy 44.552935 -229.896239) (xy 44.538064 -229.901013)
			(xy 44.531534 -229.905306) (xy 44.510425 -229.919675) (xy 44.464697 -229.942398) (xy 44.41602 -229.957823)
			(xy 44.36555 -229.965583) (xy 44.340018 -229.966012) (xy 44.314489 -229.965558) (xy 44.264026 -229.957786)
			(xy 44.215354 -229.942362) (xy 44.169625 -229.919651) (xy 44.148502 -229.905306) (xy 44.141969 -229.901017)
			(xy 44.1271 -229.896233) (xy 44.119292 -229.895908) (xy 43.603418 -229.895908) (xy 43.598067 -229.895342)
			(xy 43.590483 -229.887794) (xy 43.589956 -229.882446) (xy 40.990012 -229.882446) (xy 40.989485 -229.887803)
			(xy 40.981907 -229.895384) (xy 40.97655 -229.895908) (xy 40.460676 -229.895908) (xy 40.452865 -229.89621)
			(xy 40.437994 -229.901004) (xy 40.431466 -229.905306) (xy 40.410348 -229.919661) (xy 40.364623 -229.942388)
			(xy 40.315949 -229.957816) (xy 40.265481 -229.965581) (xy 40.23995 -229.966012) (xy 40.214421 -229.965542)
			(xy 40.163959 -229.957775) (xy 40.115287 -229.942355) (xy 40.069558 -229.919648) (xy 40.048434 -229.905306)
			(xy 40.041894 -229.90103) (xy 40.02703 -229.896237) (xy 40.019224 -229.895908) (xy 39.50335 -229.895908)
			(xy 39.497991 -229.895387) (xy 39.490411 -229.887805) (xy 39.489888 -229.882446) (xy 37.545772 -229.882446)
			(xy 37.545242 -229.887741) (xy 37.537846 -229.895314) (xy 37.532564 -229.895908) (xy 37.01669 -229.895908)
			(xy 37.008879 -229.896216) (xy 36.994008 -229.901006) (xy 36.98748 -229.905306) (xy 36.966358 -229.919655)
			(xy 36.920635 -229.942383) (xy 36.871962 -229.957813) (xy 36.821495 -229.965579) (xy 36.795964 -229.966012)
			(xy 36.770433 -229.965585) (xy 36.71997 -229.957805) (xy 36.671297 -229.942373) (xy 36.62557 -229.919654)
			(xy 36.604448 -229.905306) (xy 36.597927 -229.900997) (xy 36.583049 -229.896225) (xy 36.575238 -229.895908)
			(xy 36.059364 -229.895908) (xy 36.054097 -229.895429) (xy 36.046657 -229.887968) (xy 36.046156 -229.8827)
			(xy 33.445677 -229.8827) (xy 33.445146 -229.887734) (xy 33.437769 -229.895305) (xy 33.432496 -229.895908)
			(xy 32.916622 -229.895908) (xy 32.908813 -229.89623) (xy 32.893941 -229.90101) (xy 32.887412 -229.905306)
			(xy 32.866281 -229.919641) (xy 32.820561 -229.942372) (xy 32.771891 -229.957806) (xy 32.721426 -229.965577)
			(xy 32.695896 -229.966012) (xy 32.670366 -229.965569) (xy 32.619903 -229.957794) (xy 32.571231 -229.942366)
			(xy 32.525503 -229.919652) (xy 32.50438 -229.905306) (xy 32.497852 -229.901009) (xy 32.482979 -229.896229)
			(xy 32.47517 -229.895908) (xy 31.959296 -229.895908) (xy 31.954033 -229.895408) (xy 31.94659 -229.887963)
			(xy 31.946088 -229.8827) (xy 30.001947 -229.8827) (xy 30.001442 -229.887741) (xy 29.994046 -229.895314)
			(xy 29.988764 -229.895908) (xy 29.47289 -229.895908) (xy 29.465079 -229.896216) (xy 29.450208 -229.901006)
			(xy 29.44368 -229.905306) (xy 29.422558 -229.919655) (xy 29.376835 -229.942383) (xy 29.328162 -229.957813)
			(xy 29.277695 -229.965579) (xy 29.252164 -229.966012) (xy 29.226633 -229.965585) (xy 29.17617 -229.957805)
			(xy 29.127497 -229.942373) (xy 29.08177 -229.919654) (xy 29.060648 -229.905306) (xy 29.054127 -229.900997)
			(xy 29.039249 -229.896225) (xy 29.031438 -229.895908) (xy 28.515564 -229.895908) (xy 28.510297 -229.895429)
			(xy 28.502857 -229.887968) (xy 28.502356 -229.8827) (xy 25.901877 -229.8827) (xy 25.901346 -229.887734)
			(xy 25.893969 -229.895305) (xy 25.888696 -229.895908) (xy 25.372822 -229.895908) (xy 25.365013 -229.89623)
			(xy 25.350141 -229.90101) (xy 25.343612 -229.905306) (xy 25.322481 -229.919641) (xy 25.276761 -229.942372)
			(xy 25.228091 -229.957806) (xy 25.177626 -229.965577) (xy 25.152096 -229.966012) (xy 25.126566 -229.965569)
			(xy 25.076103 -229.957794) (xy 25.027431 -229.942366) (xy 24.981703 -229.919652) (xy 24.96058 -229.905306)
			(xy 24.954052 -229.901009) (xy 24.939179 -229.896229) (xy 24.93137 -229.895908) (xy 24.415496 -229.895908)
			(xy 24.410233 -229.895408) (xy 24.40279 -229.887963) (xy 24.402288 -229.8827) (xy 22.458149 -229.8827)
			(xy 22.457681 -229.887813) (xy 22.450078 -229.895396) (xy 22.44471 -229.895908) (xy 21.928836 -229.895908)
			(xy 21.921027 -229.896235) (xy 21.906156 -229.901012) (xy 21.899626 -229.905306) (xy 21.878491 -229.919635)
			(xy 21.832772 -229.942367) (xy 21.784103 -229.957803) (xy 21.73364 -229.965576) (xy 21.70811 -229.966012)
			(xy 21.68258 -229.965562) (xy 21.632117 -229.957789) (xy 21.583445 -229.942363) (xy 21.537717 -229.919651)
			(xy 21.516594 -229.905306) (xy 21.510063 -229.901014) (xy 21.495193 -229.896231) (xy 21.487384 -229.895908)
			(xy 20.97151 -229.895908) (xy 20.966158 -229.895347) (xy 20.958575 -229.887795) (xy 20.958048 -229.882446)
			(xy 18.358104 -229.882446) (xy 18.357584 -229.887805) (xy 18.350002 -229.895386) (xy 18.344642 -229.895908)
			(xy 17.828768 -229.895908) (xy 17.82096 -229.896249) (xy 17.806089 -229.901016) (xy 17.799558 -229.905306)
			(xy 17.778442 -229.919664) (xy 17.732717 -229.94239) (xy 17.684042 -229.957818) (xy 17.633574 -229.965581)
			(xy 17.608042 -229.966012) (xy 17.582513 -229.965546) (xy 17.532051 -229.957778) (xy 17.483378 -229.942357)
			(xy 17.437649 -229.919649) (xy 17.416526 -229.905306) (xy 17.409988 -229.901026) (xy 17.395123 -229.896236)
			(xy 17.387316 -229.895908) (xy 16.871442 -229.895908) (xy 16.866094 -229.895326) (xy 16.858509 -229.88779)
			(xy 16.85798 -229.882446) (xy 2.509012 -229.882446) (xy 2.509012 -230.732584) (xy 16.85798 -230.732584)
			(xy 16.85798 -230.238046) (xy 16.858314 -230.232607) (xy 16.866003 -230.224916) (xy 16.871442 -230.224584)
			(xy 17.38757 -230.224584) (xy 17.395379 -230.22426) (xy 17.410251 -230.219482) (xy 17.41678 -230.215186)
			(xy 17.437869 -230.200837) (xy 17.48353 -230.178106) (xy 17.532136 -230.162647) (xy 17.582539 -230.154824)
			(xy 17.633545 -230.154824) (xy 17.683948 -230.162647) (xy 17.732554 -230.178106) (xy 17.778215 -230.200837)
			(xy 17.799304 -230.215186) (xy 17.805836 -230.219476) (xy 17.820706 -230.22426) (xy 17.828514 -230.224584)
			(xy 18.344642 -230.224584) (xy 18.350094 -230.224856) (xy 18.35778 -230.232592) (xy 18.358104 -230.238046)
			(xy 18.358104 -230.732584) (xy 24.402288 -230.732584) (xy 24.402288 -230.238046) (xy 24.40276 -230.232736)
			(xy 24.410196 -230.22516) (xy 24.415496 -230.224584) (xy 24.931624 -230.224584) (xy 24.939435 -230.224283)
			(xy 24.954307 -230.219489) (xy 24.960834 -230.215186) (xy 24.981923 -230.200837) (xy 25.027584 -230.178106)
			(xy 25.07619 -230.162647) (xy 25.126593 -230.154824) (xy 25.177599 -230.154824) (xy 25.228002 -230.162647)
			(xy 25.276608 -230.178106) (xy 25.322269 -230.200837) (xy 25.343358 -230.215186) (xy 25.349878 -230.219497)
			(xy 25.364757 -230.224268) (xy 25.372568 -230.224584) (xy 25.888696 -230.224584) (xy 25.893956 -230.225097)
			(xy 25.901399 -230.232532) (xy 25.901904 -230.237792) (xy 25.901904 -230.2383) (xy 25.901904 -230.732584)
			(xy 31.946088 -230.732584) (xy 31.946088 -230.238046) (xy 31.94656 -230.232736) (xy 31.953996 -230.22516)
			(xy 31.959296 -230.224584) (xy 32.475424 -230.224584) (xy 32.483235 -230.224283) (xy 32.498107 -230.219489)
			(xy 32.504634 -230.215186) (xy 32.525723 -230.200837) (xy 32.571384 -230.178106) (xy 32.61999 -230.162647)
			(xy 32.670393 -230.154824) (xy 32.721399 -230.154824) (xy 32.771802 -230.162647) (xy 32.820408 -230.178106)
			(xy 32.866069 -230.200837) (xy 32.887158 -230.215186) (xy 32.893678 -230.219497) (xy 32.908557 -230.224268)
			(xy 32.916368 -230.224584) (xy 33.432496 -230.224584) (xy 33.437756 -230.225097) (xy 33.445199 -230.232532)
			(xy 33.445704 -230.237792) (xy 33.445704 -230.2383) (xy 33.445704 -230.732584) (xy 39.489888 -230.732584)
			(xy 39.489888 -230.238046) (xy 39.490476 -230.232699) (xy 39.498007 -230.225114) (xy 39.50335 -230.224584)
			(xy 40.019478 -230.224584) (xy 40.027288 -230.224264) (xy 40.042159 -230.219483) (xy 40.048688 -230.215186)
			(xy 40.069777 -230.200837) (xy 40.115438 -230.178106) (xy 40.164044 -230.162647) (xy 40.214447 -230.154824)
			(xy 40.265453 -230.154824) (xy 40.315856 -230.162647) (xy 40.364462 -230.178106) (xy 40.410123 -230.200837)
			(xy 40.431212 -230.215186) (xy 40.437742 -230.219479) (xy 40.452613 -230.224261) (xy 40.460422 -230.224584)
			(xy 40.97655 -230.224584) (xy 40.981931 -230.225022) (xy 40.989516 -230.232662) (xy 40.990012 -230.238046)
			(xy 40.990012 -230.732584) (xy 47.034196 -230.732584) (xy 47.034196 -230.238046) (xy 47.034749 -230.232757)
			(xy 47.042129 -230.225186) (xy 47.047404 -230.224584) (xy 47.563532 -230.224584) (xy 47.57134 -230.224244)
			(xy 47.586211 -230.219476) (xy 47.592742 -230.215186) (xy 47.613831 -230.200837) (xy 47.659492 -230.178106)
			(xy 47.708098 -230.162647) (xy 47.758501 -230.154824) (xy 47.809507 -230.154824) (xy 47.85991 -230.162647)
			(xy 47.908516 -230.178106) (xy 47.954177 -230.200837) (xy 47.975266 -230.215186) (xy 47.981807 -230.219462)
			(xy 47.99667 -230.224255) (xy 48.004476 -230.224584) (xy 48.520604 -230.224584) (xy 48.525865 -230.225091)
			(xy 48.533307 -230.232531) (xy 48.533812 -230.237792) (xy 48.533812 -230.2383) (xy 48.533812 -230.732584)
			(xy 54.577996 -230.732584) (xy 54.577996 -230.238046) (xy 54.578406 -230.232627) (xy 54.586042 -230.224941)
			(xy 54.591458 -230.224584) (xy 56.064658 -230.224584) (xy 56.070098 -230.224912) (xy 56.07779 -230.232606)
			(xy 56.07812 -230.238046) (xy 56.07812 -230.732584) (xy 163.678108 -230.732584) (xy 163.678108 -230.238046)
			(xy 163.67865 -230.232755) (xy 163.686038 -230.225183) (xy 163.691316 -230.224584) (xy 165.164516 -230.224584)
			(xy 165.169779 -230.225083) (xy 165.17722 -230.232529) (xy 165.177724 -230.237792) (xy 165.177724 -230.2383)
			(xy 165.177724 -230.732584) (xy 171.221908 -230.732584) (xy 171.221908 -230.238046) (xy 171.222307 -230.232624)
			(xy 171.229951 -230.224938) (xy 171.23537 -230.224584) (xy 171.751498 -230.224584) (xy 171.759308 -230.224272)
			(xy 171.77418 -230.219485) (xy 171.780708 -230.215186) (xy 171.801797 -230.200837) (xy 171.847458 -230.178106)
			(xy 171.896064 -230.162647) (xy 171.946467 -230.154824) (xy 171.997473 -230.154824) (xy 172.047876 -230.162647)
			(xy 172.096482 -230.178106) (xy 172.142143 -230.200837) (xy 172.163232 -230.215186) (xy 172.169758 -230.219487)
			(xy 172.184632 -230.224264) (xy 172.192442 -230.224584) (xy 172.70857 -230.224584) (xy 172.714012 -230.224904)
			(xy 172.721702 -230.232604) (xy 172.722032 -230.238046) (xy 172.722032 -230.732584) (xy 178.766216 -230.732584)
			(xy 178.766216 -230.238046) (xy 178.766751 -230.232753) (xy 178.774144 -230.22518) (xy 178.779424 -230.224584)
			(xy 179.295552 -230.224584) (xy 179.303361 -230.224253) (xy 179.318232 -230.219479) (xy 179.324762 -230.215186)
			(xy 179.345851 -230.200837) (xy 179.391512 -230.178106) (xy 179.440118 -230.162647) (xy 179.490521 -230.154824)
			(xy 179.541527 -230.154824) (xy 179.59193 -230.162647) (xy 179.640536 -230.178106) (xy 179.686197 -230.200837)
			(xy 179.707286 -230.215186) (xy 179.713822 -230.219469) (xy 179.728689 -230.224258) (xy 179.736496 -230.224584)
			(xy 180.252624 -230.224584) (xy 180.257888 -230.225078) (xy 180.265328 -230.232528) (xy 180.265832 -230.237792)
			(xy 180.265832 -230.2383) (xy 180.265832 -230.732584) (xy 186.310016 -230.732584) (xy 186.310016 -230.238046)
			(xy 186.310408 -230.232623) (xy 186.318056 -230.224935) (xy 186.323478 -230.224584) (xy 186.839606 -230.224584)
			(xy 186.847417 -230.224276) (xy 186.862288 -230.219486) (xy 186.868816 -230.215186) (xy 186.889905 -230.200837)
			(xy 186.935566 -230.178106) (xy 186.984172 -230.162647) (xy 187.034575 -230.154824) (xy 187.085581 -230.154824)
			(xy 187.135984 -230.162647) (xy 187.18459 -230.178106) (xy 187.230251 -230.200837) (xy 187.25134 -230.215186)
			(xy 187.257864 -230.21949) (xy 187.27274 -230.224265) (xy 187.28055 -230.224584) (xy 187.796678 -230.224584)
			(xy 187.802121 -230.224899) (xy 187.809811 -230.232602) (xy 187.81014 -230.238046) (xy 187.81014 -230.732584)
			(xy 193.854324 -230.732584) (xy 193.854324 -230.238046) (xy 193.854852 -230.232751) (xy 193.86225 -230.225178)
			(xy 193.867532 -230.224584) (xy 194.38366 -230.224584) (xy 194.391469 -230.224256) (xy 194.40634 -230.21948)
			(xy 194.41287 -230.215186) (xy 194.433959 -230.200837) (xy 194.47962 -230.178106) (xy 194.528226 -230.162647)
			(xy 194.578629 -230.154824) (xy 194.629635 -230.154824) (xy 194.680038 -230.162647) (xy 194.728644 -230.178106)
			(xy 194.774305 -230.200837) (xy 194.795394 -230.215186) (xy 194.801928 -230.219472) (xy 194.816796 -230.224259)
			(xy 194.824604 -230.224584) (xy 195.340732 -230.224584) (xy 195.345997 -230.225073) (xy 195.353437 -230.232526)
			(xy 195.35394 -230.237792) (xy 195.35394 -230.2383) (xy 195.35394 -230.732584) (xy 201.398124 -230.732584)
			(xy 201.398124 -230.238046) (xy 201.398652 -230.232751) (xy 201.40605 -230.225178) (xy 201.411332 -230.224584)
			(xy 201.92746 -230.224584) (xy 201.935269 -230.224256) (xy 201.95014 -230.21948) (xy 201.95667 -230.215186)
			(xy 201.977759 -230.200837) (xy 202.02342 -230.178106) (xy 202.072026 -230.162647) (xy 202.122429 -230.154824)
			(xy 202.173435 -230.154824) (xy 202.223838 -230.162647) (xy 202.272444 -230.178106) (xy 202.318105 -230.200837)
			(xy 202.339194 -230.215186) (xy 202.345728 -230.219472) (xy 202.360596 -230.224259) (xy 202.368404 -230.224584)
			(xy 202.884532 -230.224584) (xy 202.889797 -230.225073) (xy 202.897237 -230.232526) (xy 202.89774 -230.237792)
			(xy 202.89774 -230.2383) (xy 202.89774 -230.73233) (xy 264.798048 -230.73233) (xy 264.798048 -230.237792)
			(xy 264.798585 -230.232539) (xy 264.806004 -230.225099) (xy 264.811256 -230.224584) (xy 264.811764 -230.224584)
			(xy 265.327638 -230.224584) (xy 265.335446 -230.224246) (xy 265.350318 -230.219477) (xy 265.356848 -230.215186)
			(xy 265.377937 -230.200837) (xy 265.423598 -230.178106) (xy 265.472204 -230.162647) (xy 265.522607 -230.154824)
			(xy 265.573613 -230.154824) (xy 265.624016 -230.162647) (xy 265.672622 -230.178106) (xy 265.718283 -230.200837)
			(xy 265.739372 -230.215186) (xy 265.745911 -230.219464) (xy 265.760775 -230.224256) (xy 265.768582 -230.224584)
			(xy 266.28471 -230.224584) (xy 266.290026 -230.225022) (xy 266.297599 -230.232484) (xy 266.298172 -230.237792)
			(xy 266.298172 -230.73233) (xy 266.298148 -230.732584) (xy 272.342356 -230.732584) (xy 272.342356 -230.732076)
			(xy 272.342356 -230.237792) (xy 272.342886 -230.232537) (xy 272.35031 -230.225097) (xy 272.355564 -230.224584)
			(xy 272.871692 -230.224584) (xy 272.879502 -230.22427) (xy 272.894374 -230.219484) (xy 272.900902 -230.215186)
			(xy 272.921991 -230.200837) (xy 272.967652 -230.178106) (xy 273.016258 -230.162647) (xy 273.066661 -230.154824)
			(xy 273.117667 -230.154824) (xy 273.16807 -230.162647) (xy 273.216676 -230.178106) (xy 273.262337 -230.200837)
			(xy 273.283426 -230.215186) (xy 273.289953 -230.219485) (xy 273.304827 -230.224263) (xy 273.312636 -230.224584)
			(xy 273.828764 -230.224584) (xy 273.83409 -230.22495) (xy 273.841632 -230.232468) (xy 273.841972 -230.237792)
			(xy 273.841972 -230.73233) (xy 273.841949 -230.732584) (xy 279.886156 -230.732584) (xy 279.886156 -230.732076)
			(xy 279.886156 -230.237792) (xy 279.886686 -230.232537) (xy 279.89411 -230.225097) (xy 279.899364 -230.224584)
			(xy 280.415492 -230.224584) (xy 280.423302 -230.22427) (xy 280.438174 -230.219484) (xy 280.444702 -230.215186)
			(xy 280.465791 -230.200837) (xy 280.511452 -230.178106) (xy 280.560058 -230.162647) (xy 280.610461 -230.154824)
			(xy 280.661467 -230.154824) (xy 280.71187 -230.162647) (xy 280.760476 -230.178106) (xy 280.806137 -230.200837)
			(xy 280.827226 -230.215186) (xy 280.833753 -230.219485) (xy 280.848627 -230.224263) (xy 280.856436 -230.224584)
			(xy 281.372564 -230.224584) (xy 281.37789 -230.22495) (xy 281.385432 -230.232468) (xy 281.385772 -230.237792)
			(xy 281.385772 -230.73233) (xy 287.429956 -230.73233) (xy 287.429956 -230.237792) (xy 287.430486 -230.232537)
			(xy 287.43791 -230.225097) (xy 287.443164 -230.224584) (xy 287.443672 -230.224584) (xy 287.959546 -230.224584)
			(xy 287.967354 -230.22425) (xy 287.982226 -230.219478) (xy 287.988756 -230.215186) (xy 288.009845 -230.200837)
			(xy 288.055506 -230.178106) (xy 288.104112 -230.162647) (xy 288.154515 -230.154824) (xy 288.205521 -230.154824)
			(xy 288.255924 -230.162647) (xy 288.30453 -230.178106) (xy 288.350191 -230.200837) (xy 288.37128 -230.215186)
			(xy 288.377817 -230.219467) (xy 288.392683 -230.224257) (xy 288.40049 -230.224584) (xy 288.916618 -230.224584)
			(xy 288.921935 -230.225016) (xy 288.929507 -230.232483) (xy 288.93008 -230.237792) (xy 288.93008 -230.73233)
			(xy 288.930056 -230.732584) (xy 294.974264 -230.732584) (xy 294.974264 -230.732076) (xy 294.974264 -230.237792)
			(xy 294.974787 -230.232535) (xy 294.982216 -230.225095) (xy 294.987472 -230.224584) (xy 295.5036 -230.224584)
			(xy 295.51141 -230.224273) (xy 295.526282 -230.219485) (xy 295.53281 -230.215186) (xy 295.553899 -230.200837)
			(xy 295.59956 -230.178106) (xy 295.648166 -230.162647) (xy 295.698569 -230.154824) (xy 295.749575 -230.154824)
			(xy 295.799978 -230.162647) (xy 295.848584 -230.178106) (xy 295.894245 -230.200837) (xy 295.915334 -230.215186)
			(xy 295.921859 -230.219488) (xy 295.936734 -230.224265) (xy 295.944544 -230.224584) (xy 296.460672 -230.224584)
			(xy 296.465999 -230.224945) (xy 296.473541 -230.232466) (xy 296.47388 -230.237792) (xy 296.47388 -230.73233)
			(xy 302.518064 -230.73233) (xy 302.518064 -230.237792) (xy 302.518587 -230.232535) (xy 302.526016 -230.225095)
			(xy 302.531272 -230.224584) (xy 304.004726 -230.224584) (xy 304.010044 -230.225011) (xy 304.017616 -230.232482)
			(xy 304.018188 -230.237792) (xy 304.018188 -230.73233) (xy 304.018164 -230.732584) (xy 411.618176 -230.732584)
			(xy 411.618176 -230.732076) (xy 411.618176 -230.237792) (xy 411.618688 -230.232532) (xy 411.626124 -230.225091)
			(xy 411.631384 -230.224584) (xy 413.104584 -230.224584) (xy 413.109912 -230.224937) (xy 413.117454 -230.232464)
			(xy 413.117792 -230.237792) (xy 413.117792 -230.73233) (xy 419.161976 -230.73233) (xy 419.161976 -230.237792)
			(xy 419.162488 -230.232532) (xy 419.169924 -230.225091) (xy 419.175184 -230.224584) (xy 419.175692 -230.224584)
			(xy 419.691566 -230.224584) (xy 419.699375 -230.224259) (xy 419.714247 -230.219481) (xy 419.720776 -230.215186)
			(xy 419.741865 -230.200837) (xy 419.787526 -230.178106) (xy 419.836132 -230.162647) (xy 419.886535 -230.154824)
			(xy 419.937541 -230.154824) (xy 419.987944 -230.162647) (xy 420.03655 -230.178106) (xy 420.082211 -230.200837)
			(xy 420.1033 -230.215186) (xy 420.109833 -230.219475) (xy 420.124702 -230.22426) (xy 420.13251 -230.224584)
			(xy 420.648638 -230.224584) (xy 420.653957 -230.225003) (xy 420.661528 -230.23248) (xy 420.6621 -230.237792)
			(xy 420.6621 -230.73233) (xy 420.662075 -230.732584) (xy 426.706284 -230.732584) (xy 426.706284 -230.732076)
			(xy 426.706284 -230.237792) (xy 426.706789 -230.23253) (xy 426.71423 -230.225089) (xy 426.719492 -230.224584)
			(xy 427.23562 -230.224584) (xy 427.243431 -230.224282) (xy 427.258303 -230.219488) (xy 427.26483 -230.215186)
			(xy 427.285919 -230.200837) (xy 427.33158 -230.178106) (xy 427.380186 -230.162647) (xy 427.430589 -230.154824)
			(xy 427.481595 -230.154824) (xy 427.531998 -230.162647) (xy 427.580604 -230.178106) (xy 427.626265 -230.200837)
			(xy 427.647354 -230.215186) (xy 427.653875 -230.219495) (xy 427.668753 -230.224268) (xy 427.676564 -230.224584)
			(xy 428.192692 -230.224584) (xy 428.197952 -230.225099) (xy 428.205395 -230.232533) (xy 428.2059 -230.237792)
			(xy 428.2059 -230.73233) (xy 434.250084 -230.73233) (xy 434.250084 -230.237792) (xy 434.250589 -230.23253)
			(xy 434.25803 -230.225089) (xy 434.263292 -230.224584) (xy 434.2638 -230.224584) (xy 434.779674 -230.224584)
			(xy 434.787483 -230.224262) (xy 434.802355 -230.219482) (xy 434.808884 -230.215186) (xy 434.829973 -230.200837)
			(xy 434.875634 -230.178106) (xy 434.92424 -230.162647) (xy 434.974643 -230.154824) (xy 435.025649 -230.154824)
			(xy 435.076052 -230.162647) (xy 435.124658 -230.178106) (xy 435.170319 -230.200837) (xy 435.191408 -230.215186)
			(xy 435.197939 -230.219478) (xy 435.212809 -230.224261) (xy 435.220618 -230.224584) (xy 435.736746 -230.224584)
			(xy 435.742054 -230.225064) (xy 435.749631 -230.232494) (xy 435.750208 -230.237792) (xy 435.750208 -230.73233)
			(xy 435.750183 -230.732584) (xy 441.794392 -230.732584) (xy 441.794392 -230.732076) (xy 441.794392 -230.237792)
			(xy 441.794889 -230.232528) (xy 441.802336 -230.225086) (xy 441.8076 -230.224584) (xy 442.323728 -230.224584)
			(xy 442.331539 -230.224285) (xy 442.346411 -230.219489) (xy 442.352938 -230.215186) (xy 442.374027 -230.200837)
			(xy 442.419688 -230.178106) (xy 442.468294 -230.162647) (xy 442.518697 -230.154824) (xy 442.569703 -230.154824)
			(xy 442.620106 -230.162647) (xy 442.668712 -230.178106) (xy 442.714373 -230.200837) (xy 442.735462 -230.215186)
			(xy 442.742003 -230.21946) (xy 442.756866 -230.224254) (xy 442.764672 -230.224584) (xy 443.2808 -230.224584)
			(xy 443.286061 -230.225094) (xy 443.293503 -230.232532) (xy 443.294008 -230.237792) (xy 443.294008 -230.73233)
			(xy 443.293984 -230.732584) (xy 449.338192 -230.732584) (xy 449.338192 -230.732076) (xy 449.338192 -230.237792)
			(xy 449.338689 -230.232528) (xy 449.346136 -230.225086) (xy 449.3514 -230.224584) (xy 449.867528 -230.224584)
			(xy 449.875339 -230.224285) (xy 449.890211 -230.219489) (xy 449.896738 -230.215186) (xy 449.917827 -230.200837)
			(xy 449.963488 -230.178106) (xy 450.012094 -230.162647) (xy 450.062497 -230.154824) (xy 450.113503 -230.154824)
			(xy 450.163906 -230.162647) (xy 450.212512 -230.178106) (xy 450.258173 -230.200837) (xy 450.279262 -230.215186)
			(xy 450.285803 -230.21946) (xy 450.300666 -230.224254) (xy 450.308472 -230.224584) (xy 450.8246 -230.224584)
			(xy 450.829861 -230.225094) (xy 450.837303 -230.232532) (xy 450.837808 -230.237792) (xy 450.837808 -230.73233)
			(xy 450.837303 -230.737627) (xy 450.829886 -230.745193) (xy 450.8246 -230.745792) (xy 450.308726 -230.745792)
			(xy 450.300917 -230.746118) (xy 450.286046 -230.750896) (xy 450.279516 -230.75519) (xy 450.25839 -230.769533)
			(xy 450.212668 -230.79226) (xy 450.163996 -230.807692) (xy 450.113531 -230.815461) (xy 450.088 -230.815896)
			(xy 450.06247 -230.815454) (xy 450.012007 -230.807679) (xy 449.963334 -230.792251) (xy 449.917606 -230.769536)
			(xy 449.896484 -230.75519) (xy 449.889956 -230.750893) (xy 449.875083 -230.746114) (xy 449.867274 -230.745792)
			(xy 449.3514 -230.745792) (xy 449.346064 -230.745472) (xy 449.338522 -230.737921) (xy 449.338192 -230.732584)
			(xy 443.293984 -230.732584) (xy 443.293503 -230.737627) (xy 443.286086 -230.745193) (xy 443.2808 -230.745792)
			(xy 442.764926 -230.745792) (xy 442.757117 -230.746118) (xy 442.742246 -230.750896) (xy 442.735716 -230.75519)
			(xy 442.71459 -230.769533) (xy 442.668868 -230.79226) (xy 442.620196 -230.807692) (xy 442.569731 -230.815461)
			(xy 442.5442 -230.815896) (xy 442.51867 -230.815454) (xy 442.468207 -230.807679) (xy 442.419534 -230.792251)
			(xy 442.373806 -230.769536) (xy 442.352684 -230.75519) (xy 442.346156 -230.750893) (xy 442.331283 -230.746114)
			(xy 442.323474 -230.745792) (xy 441.8076 -230.745792) (xy 441.802264 -230.745472) (xy 441.794722 -230.737921)
			(xy 441.794392 -230.732584) (xy 435.750183 -230.732584) (xy 435.749674 -230.737687) (xy 435.742102 -230.745268)
			(xy 435.736746 -230.745792) (xy 435.220872 -230.745792) (xy 435.213061 -230.746095) (xy 435.19819 -230.750889)
			(xy 435.191662 -230.75519) (xy 435.170552 -230.769556) (xy 435.124823 -230.792278) (xy 435.076147 -230.807703)
			(xy 435.025678 -230.815465) (xy 435.000146 -230.815896) (xy 434.974617 -230.815431) (xy 434.924154 -230.807663)
			(xy 434.875482 -230.792242) (xy 434.829753 -230.769533) (xy 434.80863 -230.75519) (xy 434.802092 -230.750911)
			(xy 434.787227 -230.74612) (xy 434.77942 -230.745792) (xy 434.263546 -230.745792) (xy 434.258124 -230.745393)
			(xy 434.250438 -230.737749) (xy 434.250084 -230.73233) (xy 428.2059 -230.73233) (xy 428.205402 -230.737629)
			(xy 428.19798 -230.745196) (xy 428.192692 -230.745792) (xy 427.676818 -230.745792) (xy 427.669009 -230.746115)
			(xy 427.654137 -230.750895) (xy 427.647608 -230.75519) (xy 427.626485 -230.769536) (xy 427.580761 -230.792263)
			(xy 427.532088 -230.807693) (xy 427.481623 -230.815462) (xy 427.456092 -230.815896) (xy 427.430562 -230.815458)
			(xy 427.380098 -230.807681) (xy 427.331426 -230.792253) (xy 427.285698 -230.769537) (xy 427.264576 -230.75519)
			(xy 427.25805 -230.75089) (xy 427.243176 -230.746113) (xy 427.235366 -230.745792) (xy 426.719492 -230.745792)
			(xy 426.714155 -230.745477) (xy 426.706613 -230.737922) (xy 426.706284 -230.732584) (xy 420.662075 -230.732584)
			(xy 420.661574 -230.737688) (xy 420.653996 -230.74527) (xy 420.648638 -230.745792) (xy 420.132764 -230.745792)
			(xy 420.124957 -230.746134) (xy 420.110085 -230.750901) (xy 420.103554 -230.75519) (xy 420.082446 -230.76956)
			(xy 420.036717 -230.792281) (xy 419.988039 -230.807705) (xy 419.93757 -230.815466) (xy 419.912038 -230.815896)
			(xy 419.886509 -230.815435) (xy 419.836046 -230.807665) (xy 419.787374 -230.792243) (xy 419.741645 -230.769534)
			(xy 419.720522 -230.75519) (xy 419.713985 -230.750907) (xy 419.699119 -230.746119) (xy 419.691312 -230.745792)
			(xy 419.175438 -230.745792) (xy 419.170015 -230.745398) (xy 419.162329 -230.737751) (xy 419.161976 -230.73233)
			(xy 413.117792 -230.73233) (xy 413.117301 -230.73763) (xy 413.109874 -230.745198) (xy 413.104584 -230.745792)
			(xy 411.631384 -230.745792) (xy 411.626115 -230.745315) (xy 411.618673 -230.737854) (xy 411.618176 -230.732584)
			(xy 304.018164 -230.732584) (xy 304.017672 -230.737691) (xy 304.010087 -230.745274) (xy 304.004726 -230.745792)
			(xy 302.531526 -230.745792) (xy 302.526172 -230.745235) (xy 302.518587 -230.737681) (xy 302.518064 -230.73233)
			(xy 296.47388 -230.73233) (xy 296.473399 -230.737633) (xy 296.465965 -230.745202) (xy 296.460672 -230.745792)
			(xy 295.944798 -230.745792) (xy 295.936988 -230.746106) (xy 295.922117 -230.750892) (xy 295.915588 -230.75519)
			(xy 295.89447 -230.769545) (xy 295.848745 -230.792269) (xy 295.80007 -230.807698) (xy 295.749603 -230.815463)
			(xy 295.724072 -230.815896) (xy 295.698541 -230.815468) (xy 295.648078 -230.807688) (xy 295.599405 -230.792257)
			(xy 295.553678 -230.769538) (xy 295.532556 -230.75519) (xy 295.526034 -230.750882) (xy 295.511157 -230.74611)
			(xy 295.503346 -230.745792) (xy 294.987472 -230.745792) (xy 294.982202 -230.745322) (xy 294.97476 -230.737856)
			(xy 294.974264 -230.732584) (xy 288.930056 -230.732584) (xy 288.929571 -230.737693) (xy 288.921982 -230.745276)
			(xy 288.916618 -230.745792) (xy 288.400744 -230.745792) (xy 288.392936 -230.746126) (xy 288.378064 -230.750898)
			(xy 288.371534 -230.75519) (xy 288.350431 -230.769568) (xy 288.3047 -230.792287) (xy 288.256021 -230.807709)
			(xy 288.205551 -230.815467) (xy 288.180018 -230.815896) (xy 288.154488 -230.815445) (xy 288.104025 -230.807672)
			(xy 288.055353 -230.792247) (xy 288.009625 -230.769535) (xy 287.988502 -230.75519) (xy 287.98197 -230.7509)
			(xy 287.9671 -230.746116) (xy 287.959292 -230.745792) (xy 287.443418 -230.745792) (xy 287.438063 -230.745241)
			(xy 287.430478 -230.737683) (xy 287.429956 -230.73233) (xy 281.385772 -230.73233) (xy 281.385298 -230.737635)
			(xy 281.37786 -230.745204) (xy 281.372564 -230.745792) (xy 280.85669 -230.745792) (xy 280.84888 -230.746103)
			(xy 280.834008 -230.750891) (xy 280.82748 -230.75519) (xy 280.806364 -230.769549) (xy 280.760638 -230.792272)
			(xy 280.711963 -230.807699) (xy 280.661495 -230.815464) (xy 280.635964 -230.815896) (xy 280.610433 -230.815472)
			(xy 280.559969 -230.807691) (xy 280.511297 -230.792258) (xy 280.46557 -230.769539) (xy 280.444448 -230.75519)
			(xy 280.437928 -230.750879) (xy 280.423049 -230.746109) (xy 280.415238 -230.745792) (xy 279.899364 -230.745792)
			(xy 279.894093 -230.745327) (xy 279.886652 -230.737857) (xy 279.886156 -230.732584) (xy 273.841949 -230.732584)
			(xy 273.841498 -230.737635) (xy 273.83406 -230.745204) (xy 273.828764 -230.745792) (xy 273.31289 -230.745792)
			(xy 273.30508 -230.746103) (xy 273.290208 -230.750891) (xy 273.28368 -230.75519) (xy 273.262564 -230.769549)
			(xy 273.216838 -230.792272) (xy 273.168163 -230.807699) (xy 273.117695 -230.815464) (xy 273.092164 -230.815896)
			(xy 273.066633 -230.815472) (xy 273.016169 -230.807691) (xy 272.967497 -230.792258) (xy 272.92177 -230.769539)
			(xy 272.900648 -230.75519) (xy 272.894128 -230.750879) (xy 272.879249 -230.746109) (xy 272.871438 -230.745792)
			(xy 272.355564 -230.745792) (xy 272.350293 -230.745327) (xy 272.342852 -230.737857) (xy 272.342356 -230.732584)
			(xy 266.298148 -230.732584) (xy 266.297671 -230.737695) (xy 266.290076 -230.745279) (xy 266.28471 -230.745792)
			(xy 265.768836 -230.745792) (xy 265.761027 -230.746122) (xy 265.746156 -230.750897) (xy 265.739626 -230.75519)
			(xy 265.718498 -230.769529) (xy 265.672776 -230.792257) (xy 265.624105 -230.807689) (xy 265.57364 -230.81546)
			(xy 265.54811 -230.815896) (xy 265.52258 -230.815449) (xy 265.472117 -230.807675) (xy 265.423445 -230.792249)
			(xy 265.377717 -230.769536) (xy 265.356594 -230.75519) (xy 265.350064 -230.750897) (xy 265.335193 -230.746115)
			(xy 265.327384 -230.745792) (xy 264.81151 -230.745792) (xy 264.806155 -230.745246) (xy 264.79857 -230.737684)
			(xy 264.798048 -230.73233) (xy 202.89774 -230.73233) (xy 202.89774 -230.732584) (xy 202.897198 -230.737837)
			(xy 202.889783 -230.745279) (xy 202.884532 -230.745792) (xy 202.368658 -230.745792) (xy 202.360782 -230.746062)
			(xy 202.345778 -230.750857) (xy 202.339194 -230.75519) (xy 202.318112 -230.769574) (xy 202.272468 -230.792403)
			(xy 202.223864 -230.807963) (xy 202.173448 -230.815885) (xy 202.147932 -230.816404) (xy 202.122412 -230.815915)
			(xy 202.071985 -230.80802) (xy 202.023373 -230.79246) (xy 201.977735 -230.769605) (xy 201.95667 -230.75519)
			(xy 201.950088 -230.75086) (xy 201.93508 -230.746083) (xy 201.927206 -230.745792) (xy 201.411332 -230.745792)
			(xy 201.406 -230.74545) (xy 201.398456 -230.737915) (xy 201.398124 -230.732584) (xy 195.35394 -230.732584)
			(xy 195.353398 -230.737837) (xy 195.345983 -230.745279) (xy 195.340732 -230.745792) (xy 194.824858 -230.745792)
			(xy 194.816982 -230.746062) (xy 194.801978 -230.750857) (xy 194.795394 -230.75519) (xy 194.774312 -230.769574)
			(xy 194.728668 -230.792403) (xy 194.680064 -230.807963) (xy 194.629648 -230.815885) (xy 194.604132 -230.816404)
			(xy 194.578612 -230.815915) (xy 194.528185 -230.80802) (xy 194.479573 -230.79246) (xy 194.433935 -230.769605)
			(xy 194.41287 -230.75519) (xy 194.406288 -230.75086) (xy 194.39128 -230.746083) (xy 194.383406 -230.745792)
			(xy 193.867532 -230.745792) (xy 193.8622 -230.74545) (xy 193.854656 -230.737915) (xy 193.854324 -230.732584)
			(xy 187.81014 -230.732584) (xy 187.809598 -230.737837) (xy 187.802183 -230.745279) (xy 187.796932 -230.745792)
			(xy 187.796424 -230.745792) (xy 187.280804 -230.745792) (xy 187.27293 -230.746082) (xy 187.257925 -230.750863)
			(xy 187.25134 -230.75519) (xy 187.230273 -230.769597) (xy 187.184624 -230.792421) (xy 187.136015 -230.807974)
			(xy 187.085596 -230.815889) (xy 187.060078 -230.816404) (xy 187.034559 -230.815892) (xy 186.984133 -230.808004)
			(xy 186.935521 -230.79245) (xy 186.889882 -230.769602) (xy 186.868816 -230.75519) (xy 186.862223 -230.750877)
			(xy 186.847224 -230.746089) (xy 186.839352 -230.745792) (xy 186.323478 -230.745792) (xy 186.318179 -230.745295)
			(xy 186.310611 -230.737873) (xy 186.310016 -230.732584) (xy 180.265832 -230.732584) (xy 180.265297 -230.737839)
			(xy 180.257878 -230.745281) (xy 180.252624 -230.745792) (xy 179.73675 -230.745792) (xy 179.728874 -230.746059)
			(xy 179.713869 -230.750856) (xy 179.707286 -230.75519) (xy 179.686206 -230.769578) (xy 179.640562 -230.792406)
			(xy 179.591957 -230.807964) (xy 179.54154 -230.815885) (xy 179.516024 -230.816404) (xy 179.490504 -230.815919)
			(xy 179.440077 -230.808023) (xy 179.391465 -230.792461) (xy 179.345827 -230.769606) (xy 179.324762 -230.75519)
			(xy 179.318181 -230.750857) (xy 179.303173 -230.746081) (xy 179.295298 -230.745792) (xy 178.779424 -230.745792)
			(xy 178.774091 -230.745455) (xy 178.766548 -230.737917) (xy 178.766216 -230.732584) (xy 172.722032 -230.732584)
			(xy 172.721497 -230.737839) (xy 172.714078 -230.745281) (xy 172.708824 -230.745792) (xy 172.708316 -230.745792)
			(xy 172.192696 -230.745792) (xy 172.184821 -230.746078) (xy 172.169817 -230.750862) (xy 172.163232 -230.75519)
			(xy 172.142167 -230.769601) (xy 172.096517 -230.792424) (xy 172.047908 -230.807976) (xy 171.997488 -230.815889)
			(xy 171.97197 -230.816404) (xy 171.946451 -230.815896) (xy 171.896024 -230.808007) (xy 171.847413 -230.792452)
			(xy 171.801774 -230.769603) (xy 171.780708 -230.75519) (xy 171.774117 -230.750874) (xy 171.759117 -230.746088)
			(xy 171.751244 -230.745792) (xy 171.23537 -230.745792) (xy 171.23007 -230.745301) (xy 171.222502 -230.737874)
			(xy 171.221908 -230.732584) (xy 165.177724 -230.732584) (xy 165.177196 -230.737841) (xy 165.169772 -230.745284)
			(xy 165.164516 -230.745792) (xy 163.691316 -230.745792) (xy 163.685982 -230.745461) (xy 163.678439 -230.737918)
			(xy 163.678108 -230.732584) (xy 56.07812 -230.732584) (xy 56.077764 -230.737911) (xy 56.070238 -230.745452)
			(xy 56.064912 -230.745792) (xy 54.591458 -230.745792) (xy 54.586156 -230.745309) (xy 54.578589 -230.737876)
			(xy 54.577996 -230.732584) (xy 48.533812 -230.732584) (xy 48.533463 -230.737913) (xy 48.525933 -230.745455)
			(xy 48.520604 -230.745792) (xy 48.00473 -230.745792) (xy 47.996853 -230.74605) (xy 47.981849 -230.750853)
			(xy 47.975266 -230.75519) (xy 47.954192 -230.769586) (xy 47.908545 -230.792412) (xy 47.859938 -230.807969)
			(xy 47.809521 -230.815887) (xy 47.784004 -230.816404) (xy 47.758483 -230.815929) (xy 47.708056 -230.80803)
			(xy 47.659444 -230.792465) (xy 47.613806 -230.769607) (xy 47.592742 -230.75519) (xy 47.586166 -230.750849)
			(xy 47.571154 -230.746078) (xy 47.563278 -230.745792) (xy 47.047404 -230.745792) (xy 47.042068 -230.745469)
			(xy 47.034526 -230.73792) (xy 47.034196 -230.732584) (xy 40.990012 -230.732584) (xy 40.989663 -230.737913)
			(xy 40.982133 -230.745455) (xy 40.976804 -230.745792) (xy 40.976296 -230.745792) (xy 40.460676 -230.745792)
			(xy 40.4528 -230.74607) (xy 40.437796 -230.750859) (xy 40.431212 -230.75519) (xy 40.410153 -230.769609)
			(xy 40.364501 -230.79243) (xy 40.315889 -230.80798) (xy 40.265468 -230.815891) (xy 40.23995 -230.816404)
			(xy 40.21443 -230.815906) (xy 40.164004 -230.808014) (xy 40.115392 -230.792456) (xy 40.069753 -230.769604)
			(xy 40.048688 -230.75519) (xy 40.042102 -230.750867) (xy 40.027098 -230.746085) (xy 40.019224 -230.745792)
			(xy 39.50335 -230.745792) (xy 39.498059 -230.745247) (xy 39.490487 -230.737861) (xy 39.489888 -230.732584)
			(xy 33.445704 -230.732584) (xy 33.445362 -230.737915) (xy 33.437827 -230.745457) (xy 33.432496 -230.745792)
			(xy 32.916622 -230.745792) (xy 32.908748 -230.746089) (xy 32.893744 -230.750865) (xy 32.887158 -230.75519)
			(xy 32.866086 -230.76959) (xy 32.820439 -230.792415) (xy 32.771831 -230.80797) (xy 32.721413 -230.815887)
			(xy 32.695896 -230.816404) (xy 32.670375 -230.815933) (xy 32.619947 -230.808032) (xy 32.571336 -230.792467)
			(xy 32.525698 -230.769607) (xy 32.504634 -230.75519) (xy 32.498037 -230.750884) (xy 32.483041 -230.746092)
			(xy 32.47517 -230.745792) (xy 31.959296 -230.745792) (xy 31.953959 -230.745474) (xy 31.946418 -230.737921)
			(xy 31.946088 -230.732584) (xy 25.901904 -230.732584) (xy 25.901562 -230.737915) (xy 25.894027 -230.745457)
			(xy 25.888696 -230.745792) (xy 25.372822 -230.745792) (xy 25.364948 -230.746089) (xy 25.349944 -230.750865)
			(xy 25.343358 -230.75519) (xy 25.322286 -230.76959) (xy 25.276639 -230.792415) (xy 25.228031 -230.80797)
			(xy 25.177613 -230.815887) (xy 25.152096 -230.816404) (xy 25.126575 -230.815933) (xy 25.076147 -230.808032)
			(xy 25.027536 -230.792467) (xy 24.981898 -230.769607) (xy 24.960834 -230.75519) (xy 24.954237 -230.750884)
			(xy 24.939241 -230.746092) (xy 24.93137 -230.745792) (xy 24.415496 -230.745792) (xy 24.410159 -230.745474)
			(xy 24.402618 -230.737921) (xy 24.402288 -230.732584) (xy 18.358104 -230.732584) (xy 18.357762 -230.737915)
			(xy 18.350227 -230.745457) (xy 18.344896 -230.745792) (xy 18.344388 -230.745792) (xy 17.828768 -230.745792)
			(xy 17.820892 -230.746066) (xy 17.805888 -230.750858) (xy 17.799304 -230.75519) (xy 17.778219 -230.76957)
			(xy 17.732577 -230.7924) (xy 17.683973 -230.80796) (xy 17.633558 -230.815884) (xy 17.608042 -230.816404)
			(xy 17.582522 -230.81591) (xy 17.532095 -230.808016) (xy 17.483484 -230.792458) (xy 17.437845 -230.769604)
			(xy 17.41678 -230.75519) (xy 17.410195 -230.750863) (xy 17.39519 -230.746084) (xy 17.387316 -230.745792)
			(xy 16.871442 -230.745792) (xy 16.86615 -230.745253) (xy 16.858579 -230.737863) (xy 16.85798 -230.732584)
			(xy 2.509012 -230.732584) (xy 2.509012 -231.582468) (xy 20.958048 -231.582468) (xy 20.958048 -231.08793)
			(xy 20.958401 -231.082497) (xy 20.966077 -231.074809) (xy 20.97151 -231.074468) (xy 21.487638 -231.074468)
			(xy 21.495446 -231.074133) (xy 21.510318 -231.069362) (xy 21.516848 -231.06507) (xy 21.537937 -231.050721)
			(xy 21.583598 -231.02799) (xy 21.632204 -231.012531) (xy 21.682607 -231.004708) (xy 21.733613 -231.004708)
			(xy 21.784016 -231.012531) (xy 21.832622 -231.02799) (xy 21.878283 -231.050721) (xy 21.899372 -231.06507)
			(xy 21.905912 -231.069346) (xy 21.920776 -231.074139) (xy 21.928582 -231.074468) (xy 22.44471 -231.074468)
			(xy 22.450154 -231.074775) (xy 22.457841 -231.082485) (xy 22.458172 -231.08793) (xy 22.458172 -231.582468)
			(xy 28.502356 -231.582468) (xy 28.502356 -231.08793) (xy 28.502845 -231.082626) (xy 28.51027 -231.075052)
			(xy 28.515564 -231.074468) (xy 29.031692 -231.074468) (xy 29.039502 -231.074156) (xy 29.054374 -231.06937)
			(xy 29.060902 -231.06507) (xy 29.081991 -231.050721) (xy 29.127652 -231.02799) (xy 29.176258 -231.012531)
			(xy 29.226661 -231.004708) (xy 29.277667 -231.004708) (xy 29.32807 -231.012531) (xy 29.376676 -231.02799)
			(xy 29.422337 -231.050721) (xy 29.443426 -231.06507) (xy 29.449954 -231.069367) (xy 29.464827 -231.074147)
			(xy 29.472636 -231.074468) (xy 29.988764 -231.074468) (xy 29.994086 -231.074849) (xy 30.001627 -231.082356)
			(xy 30.001972 -231.087676) (xy 30.001972 -231.088184) (xy 30.001972 -231.582468) (xy 36.046156 -231.582468)
			(xy 36.046156 -231.08793) (xy 36.046645 -231.082626) (xy 36.05407 -231.075052) (xy 36.059364 -231.074468)
			(xy 36.575492 -231.074468) (xy 36.583302 -231.074156) (xy 36.598174 -231.06937) (xy 36.604702 -231.06507)
			(xy 36.625791 -231.050721) (xy 36.671452 -231.02799) (xy 36.720058 -231.012531) (xy 36.770461 -231.004708)
			(xy 36.821467 -231.004708) (xy 36.87187 -231.012531) (xy 36.920476 -231.02799) (xy 36.966137 -231.050721)
			(xy 36.987226 -231.06507) (xy 36.993754 -231.069367) (xy 37.008627 -231.074147) (xy 37.016436 -231.074468)
			(xy 37.532564 -231.074468) (xy 37.537886 -231.074849) (xy 37.545427 -231.082356) (xy 37.545772 -231.087676)
			(xy 37.545772 -231.088184) (xy 37.545772 -231.582468) (xy 43.589956 -231.582468) (xy 43.589956 -231.08793)
			(xy 43.590301 -231.082495) (xy 43.597983 -231.074806) (xy 43.603418 -231.074468) (xy 44.119546 -231.074468)
			(xy 44.127355 -231.074137) (xy 44.142226 -231.069363) (xy 44.148756 -231.06507) (xy 44.169845 -231.050721)
			(xy 44.215506 -231.02799) (xy 44.264112 -231.012531) (xy 44.314515 -231.004708) (xy 44.365521 -231.004708)
			(xy 44.415924 -231.012531) (xy 44.46453 -231.02799) (xy 44.510191 -231.050721) (xy 44.53128 -231.06507)
			(xy 44.537819 -231.069349) (xy 44.552683 -231.07414) (xy 44.56049 -231.074468) (xy 45.076618 -231.074468)
			(xy 45.082063 -231.07477) (xy 45.089749 -231.082484) (xy 45.09008 -231.08793) (xy 45.09008 -231.582468)
			(xy 51.134264 -231.582468) (xy 51.134264 -231.08793) (xy 51.134746 -231.082624) (xy 51.142176 -231.07505)
			(xy 51.147472 -231.074468) (xy 51.6636 -231.074468) (xy 51.671411 -231.07416) (xy 51.686282 -231.069371)
			(xy 51.69281 -231.06507) (xy 51.713899 -231.050721) (xy 51.75956 -231.02799) (xy 51.808166 -231.012531)
			(xy 51.858569 -231.004708) (xy 51.909575 -231.004708) (xy 51.959978 -231.012531) (xy 52.008584 -231.02799)
			(xy 52.054245 -231.050721) (xy 52.075334 -231.06507) (xy 52.081861 -231.06937) (xy 52.096734 -231.074148)
			(xy 52.104544 -231.074468) (xy 52.620672 -231.074468) (xy 52.625995 -231.074843) (xy 52.633536 -231.082355)
			(xy 52.63388 -231.087676) (xy 52.63388 -231.088184) (xy 52.63388 -231.582468) (xy 58.678064 -231.582468)
			(xy 58.678064 -231.08793) (xy 58.678402 -231.082493) (xy 58.686089 -231.074804) (xy 58.691526 -231.074468)
			(xy 60.164726 -231.074468) (xy 60.170172 -231.074765) (xy 60.177858 -231.082483) (xy 60.178188 -231.08793)
			(xy 60.178188 -231.5243) (xy 100.194787 -231.5243) (xy 100.198963 -231.473911) (xy 100.211376 -231.424897)
			(xy 100.231688 -231.378595) (xy 100.259345 -231.336268) (xy 100.293592 -231.299071) (xy 100.333495 -231.268018)
			(xy 100.377964 -231.243958) (xy 100.425788 -231.227546) (xy 100.475661 -231.21923) (xy 100.500942 -231.21874)
			(xy 101.440996 -231.21874) (xy 101.466275 -231.219229) (xy 101.516144 -231.22755) (xy 101.563963 -231.243965)
			(xy 101.608428 -231.268028) (xy 101.648326 -231.299081) (xy 101.682568 -231.336278) (xy 101.710221 -231.378604)
			(xy 101.73053 -231.424903) (xy 101.742941 -231.473914) (xy 101.747117 -231.5243) (xy 103.014987 -231.5243)
			(xy 103.019163 -231.473915) (xy 103.031574 -231.424905) (xy 103.051883 -231.378605) (xy 103.079535 -231.33628)
			(xy 103.113777 -231.299084) (xy 103.153674 -231.268031) (xy 103.198139 -231.243969) (xy 103.245957 -231.227554)
			(xy 103.295825 -231.219233) (xy 103.321104 -231.21874) (xy 104.261158 -231.21874) (xy 104.286439 -231.219226)
			(xy 104.336313 -231.227542) (xy 104.384137 -231.243954) (xy 104.428608 -231.268015) (xy 104.468511 -231.299068)
			(xy 104.502758 -231.336265) (xy 104.530415 -231.378593) (xy 104.550727 -231.424896) (xy 104.563141 -231.473911)
			(xy 104.567317 -231.5243) (xy 105.834887 -231.5243) (xy 105.839063 -231.473914) (xy 105.851474 -231.424903)
			(xy 105.871784 -231.378603) (xy 105.899437 -231.336278) (xy 105.93368 -231.299081) (xy 105.973579 -231.268029)
			(xy 106.018044 -231.243967) (xy 106.065864 -231.227552) (xy 106.115733 -231.219232) (xy 106.141012 -231.21874)
			(xy 107.081066 -231.21874) (xy 107.106347 -231.219226) (xy 107.156219 -231.227544) (xy 107.204043 -231.243957)
			(xy 107.248512 -231.268018) (xy 107.288414 -231.299071) (xy 107.32266 -231.336268) (xy 107.350316 -231.378595)
			(xy 107.370628 -231.424897) (xy 107.383041 -231.473911) (xy 107.387217 -231.5243) (xy 107.383041 -231.574689)
			(xy 107.381071 -231.582468) (xy 167.778176 -231.582468) (xy 167.778176 -231.08793) (xy 167.778647 -231.082621)
			(xy 167.786085 -231.075046) (xy 167.791384 -231.074468) (xy 169.264584 -231.074468) (xy 169.269839 -231.075003)
			(xy 169.277281 -231.082422) (xy 169.277792 -231.087676) (xy 169.277792 -231.582468) (xy 175.321976 -231.582468)
			(xy 175.321976 -231.08793) (xy 175.322303 -231.08249) (xy 175.329998 -231.0748) (xy 175.335438 -231.074468)
			(xy 175.851566 -231.074468) (xy 175.859375 -231.074145) (xy 175.874247 -231.069366) (xy 175.880776 -231.06507)
			(xy 175.901865 -231.050721) (xy 175.947526 -231.02799) (xy 175.996132 -231.012531) (xy 176.046535 -231.004708)
			(xy 176.097541 -231.004708) (xy 176.147944 -231.012531) (xy 176.19655 -231.02799) (xy 176.242211 -231.050721)
			(xy 176.2633 -231.06507) (xy 176.269834 -231.069357) (xy 176.284702 -231.074143) (xy 176.29251 -231.074468)
			(xy 176.808638 -231.074468) (xy 176.814014 -231.074928) (xy 176.821599 -231.082552) (xy 176.8221 -231.08793)
			(xy 176.8221 -231.582468) (xy 182.866284 -231.582468) (xy 182.866284 -231.08793) (xy 182.866748 -231.082619)
			(xy 182.87419 -231.075044) (xy 182.879492 -231.074468) (xy 183.39562 -231.074468) (xy 183.403431 -231.074168)
			(xy 183.418303 -231.069373) (xy 183.42483 -231.06507) (xy 183.445919 -231.050721) (xy 183.49158 -231.02799)
			(xy 183.540186 -231.012531) (xy 183.590589 -231.004708) (xy 183.641595 -231.004708) (xy 183.691998 -231.012531)
			(xy 183.740604 -231.02799) (xy 183.786265 -231.050721) (xy 183.807354 -231.06507) (xy 183.813876 -231.069378)
			(xy 183.828753 -231.074151) (xy 183.836564 -231.074468) (xy 184.352692 -231.074468) (xy 184.357948 -231.074997)
			(xy 184.36539 -231.082421) (xy 184.3659 -231.087676) (xy 184.3659 -231.088184) (xy 184.3659 -231.582468)
			(xy 190.410084 -231.582468) (xy 190.410084 -231.08793) (xy 190.410404 -231.082488) (xy 190.418104 -231.074798)
			(xy 190.423546 -231.074468) (xy 190.939674 -231.074468) (xy 190.947484 -231.074148) (xy 190.962355 -231.069367)
			(xy 190.968884 -231.06507) (xy 190.989973 -231.050721) (xy 191.035634 -231.02799) (xy 191.08424 -231.012531)
			(xy 191.134643 -231.004708) (xy 191.185649 -231.004708) (xy 191.236052 -231.012531) (xy 191.284658 -231.02799)
			(xy 191.330319 -231.050721) (xy 191.351408 -231.06507) (xy 191.35794 -231.06936) (xy 191.37281 -231.074144)
			(xy 191.380618 -231.074468) (xy 191.896746 -231.074468) (xy 191.902123 -231.074923) (xy 191.909707 -231.082551)
			(xy 191.910208 -231.08793) (xy 191.910208 -231.582468) (xy 197.954392 -231.582468) (xy 197.954392 -231.08793)
			(xy 197.954938 -231.082641) (xy 197.962324 -231.075071) (xy 197.9676 -231.074468) (xy 198.483728 -231.074468)
			(xy 198.49154 -231.074172) (xy 198.506411 -231.069374) (xy 198.512938 -231.06507) (xy 198.534027 -231.050721)
			(xy 198.579688 -231.02799) (xy 198.628294 -231.012531) (xy 198.678697 -231.004708) (xy 198.729703 -231.004708)
			(xy 198.780106 -231.012531) (xy 198.828712 -231.02799) (xy 198.874373 -231.050721) (xy 198.895462 -231.06507)
			(xy 198.902005 -231.069342) (xy 198.916866 -231.074137) (xy 198.924672 -231.074468) (xy 199.4408 -231.074468)
			(xy 199.446057 -231.074992) (xy 199.453498 -231.08242) (xy 199.454008 -231.087676) (xy 199.454008 -231.088184)
			(xy 199.454008 -231.582468) (xy 205.498192 -231.582468) (xy 205.498192 -231.08793) (xy 205.498738 -231.082641)
			(xy 205.506124 -231.075071) (xy 205.5114 -231.074468) (xy 206.027528 -231.074468) (xy 206.03534 -231.074172)
			(xy 206.050211 -231.069374) (xy 206.056738 -231.06507) (xy 206.077827 -231.050721) (xy 206.123488 -231.02799)
			(xy 206.172094 -231.012531) (xy 206.222497 -231.004708) (xy 206.273503 -231.004708) (xy 206.323906 -231.012531)
			(xy 206.372512 -231.02799) (xy 206.418173 -231.050721) (xy 206.439262 -231.06507) (xy 206.445805 -231.069342)
			(xy 206.460666 -231.074137) (xy 206.468472 -231.074468) (xy 206.9846 -231.074468) (xy 206.989857 -231.074992)
			(xy 206.997298 -231.08242) (xy 206.997808 -231.087676) (xy 206.997808 -231.088184) (xy 206.997808 -231.582214)
			(xy 268.898116 -231.582214) (xy 268.898116 -231.087676) (xy 268.898581 -231.082405) (xy 268.906051 -231.074962)
			(xy 268.911324 -231.074468) (xy 268.911832 -231.074468) (xy 269.427706 -231.074468) (xy 269.435517 -231.074162)
			(xy 269.450389 -231.069371) (xy 269.456916 -231.06507) (xy 269.478005 -231.050721) (xy 269.523666 -231.02799)
			(xy 269.572272 -231.012531) (xy 269.622675 -231.004708) (xy 269.673681 -231.004708) (xy 269.724084 -231.012531)
			(xy 269.77269 -231.02799) (xy 269.818351 -231.050721) (xy 269.83944 -231.06507) (xy 269.845965 -231.069372)
			(xy 269.86084 -231.074149) (xy 269.86865 -231.074468) (xy 270.384778 -231.074468) (xy 270.390086 -231.074941)
			(xy 270.39766 -231.082378) (xy 270.39824 -231.087676) (xy 270.39824 -231.582214) (xy 270.398225 -231.582468)
			(xy 276.442424 -231.582468) (xy 276.442424 -231.58196) (xy 276.442424 -231.087676) (xy 276.442714 -231.082333)
			(xy 276.450287 -231.074791) (xy 276.455632 -231.074468) (xy 276.97176 -231.074468) (xy 276.979569 -231.074142)
			(xy 276.994441 -231.069365) (xy 277.00097 -231.06507) (xy 277.022059 -231.050721) (xy 277.06772 -231.02799)
			(xy 277.116326 -231.012531) (xy 277.166729 -231.004708) (xy 277.217735 -231.004708) (xy 277.268138 -231.012531)
			(xy 277.316744 -231.02799) (xy 277.362405 -231.050721) (xy 277.383494 -231.06507) (xy 277.390029 -231.069355)
			(xy 277.404896 -231.074142) (xy 277.412704 -231.074468) (xy 277.928832 -231.074468) (xy 277.934093 -231.074971)
			(xy 277.941532 -231.082415) (xy 277.94204 -231.087676) (xy 277.94204 -231.582214) (xy 277.942018 -231.582468)
			(xy 283.986224 -231.582468) (xy 283.986224 -231.58196) (xy 283.986224 -231.087676) (xy 283.986514 -231.082333)
			(xy 283.994087 -231.074791) (xy 283.999432 -231.074468) (xy 284.51556 -231.074468) (xy 284.523369 -231.074142)
			(xy 284.538241 -231.069365) (xy 284.54477 -231.06507) (xy 284.565859 -231.050721) (xy 284.61152 -231.02799)
			(xy 284.660126 -231.012531) (xy 284.710529 -231.004708) (xy 284.761535 -231.004708) (xy 284.811938 -231.012531)
			(xy 284.860544 -231.02799) (xy 284.906205 -231.050721) (xy 284.927294 -231.06507) (xy 284.933829 -231.069355)
			(xy 284.948696 -231.074142) (xy 284.956504 -231.074468) (xy 285.472632 -231.074468) (xy 285.477893 -231.074971)
			(xy 285.485332 -231.082415) (xy 285.48584 -231.087676) (xy 285.48584 -231.582214) (xy 291.530024 -231.582214)
			(xy 291.530024 -231.087676) (xy 291.530314 -231.082333) (xy 291.537887 -231.074791) (xy 291.543232 -231.074468)
			(xy 291.54374 -231.074468) (xy 292.059614 -231.074468) (xy 292.067425 -231.074166) (xy 292.082297 -231.069373)
			(xy 292.088824 -231.06507) (xy 292.109913 -231.050721) (xy 292.155574 -231.02799) (xy 292.20418 -231.012531)
			(xy 292.254583 -231.004708) (xy 292.305589 -231.004708) (xy 292.355992 -231.012531) (xy 292.404598 -231.02799)
			(xy 292.450259 -231.050721) (xy 292.471348 -231.06507) (xy 292.477871 -231.069375) (xy 292.492748 -231.07415)
			(xy 292.500558 -231.074468) (xy 293.016686 -231.074468) (xy 293.021995 -231.074936) (xy 293.029568 -231.082376)
			(xy 293.030148 -231.087676) (xy 293.030148 -231.582214) (xy 293.030125 -231.582468) (xy 299.074332 -231.582468)
			(xy 299.074332 -231.58196) (xy 299.074332 -231.087676) (xy 299.074615 -231.082331) (xy 299.082193 -231.074789)
			(xy 299.08754 -231.074468) (xy 299.603668 -231.074468) (xy 299.611477 -231.074146) (xy 299.626349 -231.069366)
			(xy 299.632878 -231.06507) (xy 299.653967 -231.050721) (xy 299.699628 -231.02799) (xy 299.748234 -231.012531)
			(xy 299.798637 -231.004708) (xy 299.849643 -231.004708) (xy 299.900046 -231.012531) (xy 299.948652 -231.02799)
			(xy 299.994313 -231.050721) (xy 300.015402 -231.06507) (xy 300.021936 -231.069358) (xy 300.036804 -231.074143)
			(xy 300.044612 -231.074468) (xy 300.56074 -231.074468) (xy 300.566002 -231.074966) (xy 300.573441 -231.082414)
			(xy 300.573948 -231.087676) (xy 300.573948 -231.582214) (xy 306.618132 -231.582214) (xy 306.618132 -231.087676)
			(xy 306.618415 -231.082331) (xy 306.625993 -231.074789) (xy 306.63134 -231.074468) (xy 306.631848 -231.074468)
			(xy 308.104794 -231.074468) (xy 308.110104 -231.07493) (xy 308.117677 -231.082375) (xy 308.118256 -231.087676)
			(xy 308.118256 -231.524) (xy 364.108988 -231.524) (xy 364.113159 -231.473663) (xy 364.125559 -231.4247)
			(xy 364.145849 -231.378445) (xy 364.173476 -231.336161) (xy 364.207685 -231.299001) (xy 364.247545 -231.267979)
			(xy 364.291968 -231.243941) (xy 364.339741 -231.227542) (xy 364.389561 -231.219231) (xy 364.414816 -231.21874)
			(xy 365.35487 -231.21874) (xy 365.380133 -231.219134) (xy 365.429971 -231.227446) (xy 365.477762 -231.243849)
			(xy 365.5222 -231.267894) (xy 365.562074 -231.298925) (xy 365.596297 -231.336097) (xy 365.623934 -231.378396)
			(xy 365.644231 -231.424666) (xy 365.656635 -231.473646) (xy 365.660808 -231.524) (xy 366.928888 -231.524)
			(xy 366.933059 -231.473662) (xy 366.945459 -231.424698) (xy 366.96575 -231.378443) (xy 366.993378 -231.336158)
			(xy 367.027588 -231.298998) (xy 367.067449 -231.267976) (xy 367.111873 -231.243938) (xy 367.159647 -231.227541)
			(xy 367.209469 -231.219231) (xy 367.234724 -231.21874) (xy 368.174778 -231.21874) (xy 368.200041 -231.219135)
			(xy 368.249878 -231.227448) (xy 368.297667 -231.243851) (xy 368.342104 -231.267896) (xy 368.381977 -231.298928)
			(xy 368.416199 -231.3361) (xy 368.443835 -231.378398) (xy 368.464132 -231.424667) (xy 368.476535 -231.473647)
			(xy 368.480708 -231.524) (xy 369.749117 -231.524) (xy 369.753287 -231.473671) (xy 369.765684 -231.424715)
			(xy 369.78597 -231.378467) (xy 369.813591 -231.336189) (xy 369.847793 -231.299033) (xy 369.887645 -231.268014)
			(xy 369.932059 -231.243976) (xy 369.979823 -231.227577) (xy 370.029635 -231.219263) (xy 370.054886 -231.21874)
			(xy 370.99494 -231.21874) (xy 371.020197 -231.219168) (xy 371.070022 -231.227489) (xy 371.117797 -231.243896)
			(xy 371.162221 -231.267942) (xy 371.202082 -231.298971) (xy 371.236292 -231.336138) (xy 371.263919 -231.378429)
			(xy 371.284209 -231.424689) (xy 371.296608 -231.473658) (xy 371.30078 -231.524) (xy 371.296608 -231.574342)
			(xy 371.29455 -231.582468) (xy 415.718244 -231.582468) (xy 415.718244 -231.087676) (xy 415.718774 -231.082422)
			(xy 415.726199 -231.074984) (xy 415.731452 -231.074468) (xy 417.204652 -231.074468) (xy 417.209972 -231.074857)
			(xy 417.217514 -231.082358) (xy 417.21786 -231.087676) (xy 417.21786 -231.582214) (xy 423.262044 -231.582214)
			(xy 423.262044 -231.087676) (xy 423.262574 -231.082422) (xy 423.269999 -231.074984) (xy 423.275252 -231.074468)
			(xy 423.27576 -231.074468) (xy 423.791634 -231.074468) (xy 423.799442 -231.074131) (xy 423.814314 -231.069362)
			(xy 423.820844 -231.06507) (xy 423.841933 -231.050721) (xy 423.887594 -231.02799) (xy 423.9362 -231.012531)
			(xy 423.986603 -231.004708) (xy 424.037609 -231.004708) (xy 424.088012 -231.012531) (xy 424.136618 -231.02799)
			(xy 424.182279 -231.050721) (xy 424.203368 -231.06507) (xy 424.209909 -231.069345) (xy 424.224772 -231.074138)
			(xy 424.232578 -231.074468) (xy 424.748706 -231.074468) (xy 424.754018 -231.074922) (xy 424.76159 -231.082373)
			(xy 424.762168 -231.087676) (xy 424.762168 -231.582214) (xy 424.762144 -231.582468) (xy 430.806352 -231.582468)
			(xy 430.806352 -231.58196) (xy 430.806352 -231.087676) (xy 430.806875 -231.08242) (xy 430.814305 -231.074981)
			(xy 430.81956 -231.074468) (xy 431.335688 -231.074468) (xy 431.343498 -231.074155) (xy 431.35837 -231.069369)
			(xy 431.364898 -231.06507) (xy 431.385987 -231.050721) (xy 431.431648 -231.02799) (xy 431.480254 -231.012531)
			(xy 431.530657 -231.004708) (xy 431.581663 -231.004708) (xy 431.632066 -231.012531) (xy 431.680672 -231.02799)
			(xy 431.726333 -231.050721) (xy 431.747422 -231.06507) (xy 431.753951 -231.069365) (xy 431.768823 -231.074146)
			(xy 431.776632 -231.074468) (xy 432.29276 -231.074468) (xy 432.298081 -231.074851) (xy 432.305623 -231.082357)
			(xy 432.305968 -231.087676) (xy 432.305968 -231.582214) (xy 438.350152 -231.582214) (xy 438.350152 -231.087676)
			(xy 438.350675 -231.08242) (xy 438.358105 -231.074981) (xy 438.36336 -231.074468) (xy 438.363868 -231.074468)
			(xy 438.879742 -231.074468) (xy 438.88755 -231.074135) (xy 438.902422 -231.069363) (xy 438.908952 -231.06507)
			(xy 438.930041 -231.050721) (xy 438.975702 -231.02799) (xy 439.024308 -231.012531) (xy 439.074711 -231.004708)
			(xy 439.125717 -231.004708) (xy 439.17612 -231.012531) (xy 439.224726 -231.02799) (xy 439.270387 -231.050721)
			(xy 439.291476 -231.06507) (xy 439.298015 -231.069348) (xy 439.312879 -231.074139) (xy 439.320686 -231.074468)
			(xy 439.836814 -231.074468) (xy 439.842126 -231.074917) (xy 439.849698 -231.082372) (xy 439.850276 -231.087676)
			(xy 439.850276 -231.582214) (xy 439.850252 -231.582468) (xy 445.89446 -231.582468) (xy 445.89446 -231.58196)
			(xy 445.89446 -231.087676) (xy 445.894976 -231.082418) (xy 445.90241 -231.074979) (xy 445.907668 -231.074468)
			(xy 446.423796 -231.074468) (xy 446.431607 -231.074158) (xy 446.446478 -231.06937) (xy 446.453006 -231.06507)
			(xy 446.474095 -231.050721) (xy 446.519756 -231.02799) (xy 446.568362 -231.012531) (xy 446.618765 -231.004708)
			(xy 446.669771 -231.004708) (xy 446.720174 -231.012531) (xy 446.76878 -231.02799) (xy 446.814441 -231.050721)
			(xy 446.83553 -231.06507) (xy 446.842057 -231.069368) (xy 446.856931 -231.074147) (xy 446.86474 -231.074468)
			(xy 447.380868 -231.074468) (xy 447.38619 -231.074846) (xy 447.393731 -231.082355) (xy 447.394076 -231.087676)
			(xy 447.394076 -231.582214) (xy 447.394053 -231.582468) (xy 453.43826 -231.582468) (xy 453.43826 -231.58196)
			(xy 453.43826 -231.087676) (xy 453.438776 -231.082418) (xy 453.44621 -231.074979) (xy 453.451468 -231.074468)
			(xy 453.967596 -231.074468) (xy 453.975407 -231.074158) (xy 453.990278 -231.06937) (xy 453.996806 -231.06507)
			(xy 454.017895 -231.050721) (xy 454.063556 -231.02799) (xy 454.112162 -231.012531) (xy 454.162565 -231.004708)
			(xy 454.213571 -231.004708) (xy 454.263974 -231.012531) (xy 454.31258 -231.02799) (xy 454.358241 -231.050721)
			(xy 454.37933 -231.06507) (xy 454.385857 -231.069368) (xy 454.400731 -231.074147) (xy 454.40854 -231.074468)
			(xy 454.924668 -231.074468) (xy 454.92999 -231.074846) (xy 454.937531 -231.082355) (xy 454.937876 -231.087676)
			(xy 454.937876 -231.582214) (xy 454.937388 -231.587516) (xy 454.92996 -231.595085) (xy 454.924668 -231.595676)
			(xy 454.408794 -231.595676) (xy 454.400982 -231.595974) (xy 454.386111 -231.60077) (xy 454.379584 -231.605074)
			(xy 454.358466 -231.619429) (xy 454.312741 -231.642154) (xy 454.264066 -231.657582) (xy 454.213599 -231.665347)
			(xy 454.188068 -231.66578) (xy 454.162537 -231.665357) (xy 454.112073 -231.657576) (xy 454.063401 -231.642143)
			(xy 454.017674 -231.619423) (xy 453.996552 -231.605074) (xy 453.990026 -231.600773) (xy 453.975152 -231.595995)
			(xy 453.967342 -231.595676) (xy 453.451468 -231.595676) (xy 453.446194 -231.595223) (xy 453.438751 -231.587745)
			(xy 453.43826 -231.582468) (xy 447.394053 -231.582468) (xy 447.393588 -231.587516) (xy 447.38616 -231.595085)
			(xy 447.380868 -231.595676) (xy 446.864994 -231.595676) (xy 446.857182 -231.595974) (xy 446.842311 -231.60077)
			(xy 446.835784 -231.605074) (xy 446.814666 -231.619429) (xy 446.768941 -231.642154) (xy 446.720266 -231.657582)
			(xy 446.669799 -231.665347) (xy 446.644268 -231.66578) (xy 446.618737 -231.665357) (xy 446.568273 -231.657576)
			(xy 446.519601 -231.642143) (xy 446.473874 -231.619423) (xy 446.452752 -231.605074) (xy 446.446226 -231.600773)
			(xy 446.431352 -231.595995) (xy 446.423542 -231.595676) (xy 445.907668 -231.595676) (xy 445.902394 -231.595223)
			(xy 445.894951 -231.587745) (xy 445.89446 -231.582468) (xy 439.850252 -231.582468) (xy 439.84976 -231.587576)
			(xy 439.842176 -231.59516) (xy 439.836814 -231.595676) (xy 439.32094 -231.595676) (xy 439.31313 -231.595994)
			(xy 439.298258 -231.600776) (xy 439.29173 -231.605074) (xy 439.270627 -231.619452) (xy 439.224896 -231.642172)
			(xy 439.176217 -231.657594) (xy 439.125747 -231.665351) (xy 439.100214 -231.66578) (xy 439.074684 -231.665334)
			(xy 439.024221 -231.65756) (xy 438.975548 -231.642134) (xy 438.92982 -231.61942) (xy 438.908698 -231.605074)
			(xy 438.902162 -231.60079) (xy 438.887296 -231.596001) (xy 438.879488 -231.595676) (xy 438.363614 -231.595676)
			(xy 438.358255 -231.595142) (xy 438.350669 -231.587572) (xy 438.350152 -231.582214) (xy 432.305968 -231.582214)
			(xy 432.305487 -231.587518) (xy 432.298054 -231.595088) (xy 432.29276 -231.595676) (xy 431.776886 -231.595676)
			(xy 431.769074 -231.595971) (xy 431.754202 -231.600769) (xy 431.747676 -231.605074) (xy 431.72656 -231.619432)
			(xy 431.680834 -231.642156) (xy 431.632159 -231.657584) (xy 431.581691 -231.665348) (xy 431.55616 -231.66578)
			(xy 431.530629 -231.665361) (xy 431.480165 -231.657579) (xy 431.431492 -231.642145) (xy 431.385765 -231.619424)
			(xy 431.364644 -231.605074) (xy 431.35812 -231.60077) (xy 431.343244 -231.595993) (xy 431.335434 -231.595676)
			(xy 430.81956 -231.595676) (xy 430.814285 -231.595229) (xy 430.806842 -231.587746) (xy 430.806352 -231.582468)
			(xy 424.762144 -231.582468) (xy 424.761659 -231.587578) (xy 424.75407 -231.595163) (xy 424.748706 -231.595676)
			(xy 424.232832 -231.595676) (xy 424.225022 -231.595991) (xy 424.21015 -231.600775) (xy 424.203622 -231.605074)
			(xy 424.182494 -231.619413) (xy 424.136772 -231.642141) (xy 424.088101 -231.657574) (xy 424.037636 -231.665344)
			(xy 424.012106 -231.66578) (xy 423.986576 -231.665338) (xy 423.936113 -231.657563) (xy 423.88744 -231.642136)
			(xy 423.841712 -231.619421) (xy 423.82059 -231.605074) (xy 423.814056 -231.600787) (xy 423.799188 -231.596)
			(xy 423.79138 -231.595676) (xy 423.275506 -231.595676) (xy 423.270146 -231.595147) (xy 423.262561 -231.587573)
			(xy 423.262044 -231.582214) (xy 417.21786 -231.582214) (xy 417.217386 -231.58752) (xy 417.209948 -231.59509)
			(xy 417.204652 -231.595676) (xy 415.731452 -231.595676) (xy 415.726176 -231.595234) (xy 415.718734 -231.587747)
			(xy 415.718244 -231.582468) (xy 371.29455 -231.582468) (xy 371.284209 -231.623311) (xy 371.263919 -231.669571)
			(xy 371.236292 -231.711862) (xy 371.202082 -231.749029) (xy 371.162221 -231.780058) (xy 371.117797 -231.804104)
			(xy 371.070022 -231.820511) (xy 371.020197 -231.828832) (xy 370.99494 -231.829356) (xy 370.054886 -231.829356)
			(xy 370.029635 -231.828737) (xy 369.979823 -231.820423) (xy 369.932059 -231.804024) (xy 369.887645 -231.779986)
			(xy 369.847793 -231.748967) (xy 369.813591 -231.711811) (xy 369.78597 -231.669533) (xy 369.765684 -231.623285)
			(xy 369.753287 -231.574329) (xy 369.749117 -231.524) (xy 368.480708 -231.524) (xy 368.476535 -231.574353)
			(xy 368.464132 -231.623333) (xy 368.443835 -231.669602) (xy 368.416199 -231.7119) (xy 368.381977 -231.749072)
			(xy 368.342104 -231.780104) (xy 368.297667 -231.804149) (xy 368.249878 -231.820552) (xy 368.200041 -231.828865)
			(xy 368.174778 -231.829356) (xy 367.234724 -231.829356) (xy 367.209469 -231.828769) (xy 367.159647 -231.820459)
			(xy 367.111873 -231.804062) (xy 367.067449 -231.780024) (xy 367.027588 -231.749002) (xy 366.993378 -231.711842)
			(xy 366.96575 -231.669557) (xy 366.945459 -231.623302) (xy 366.933059 -231.574337) (xy 366.928888 -231.524)
			(xy 365.660808 -231.524) (xy 365.656635 -231.574354) (xy 365.644231 -231.623334) (xy 365.623934 -231.669604)
			(xy 365.596297 -231.711903) (xy 365.562074 -231.749075) (xy 365.5222 -231.780106) (xy 365.477762 -231.804151)
			(xy 365.429971 -231.820554) (xy 365.380133 -231.828866) (xy 365.35487 -231.829356) (xy 364.414816 -231.829356)
			(xy 364.389561 -231.828769) (xy 364.339741 -231.820458) (xy 364.291968 -231.804059) (xy 364.247545 -231.780021)
			(xy 364.207685 -231.748999) (xy 364.173476 -231.711839) (xy 364.145849 -231.669555) (xy 364.125559 -231.6233)
			(xy 364.113159 -231.574337) (xy 364.108988 -231.524) (xy 308.118256 -231.524) (xy 308.118256 -231.582214)
			(xy 308.117758 -231.587581) (xy 308.110162 -231.595166) (xy 308.104794 -231.595676) (xy 306.631594 -231.595676)
			(xy 306.626233 -231.595155) (xy 306.618648 -231.587575) (xy 306.618132 -231.582214) (xy 300.573948 -231.582214)
			(xy 300.573485 -231.587523) (xy 300.56604 -231.595093) (xy 300.56074 -231.595676) (xy 300.044866 -231.595676)
			(xy 300.037057 -231.596005) (xy 300.022185 -231.600779) (xy 300.015656 -231.605074) (xy 299.994546 -231.619441)
			(xy 299.948818 -231.642163) (xy 299.900141 -231.657588) (xy 299.849672 -231.665349) (xy 299.82414 -231.66578)
			(xy 299.798611 -231.665321) (xy 299.748148 -231.657551) (xy 299.699475 -231.642129) (xy 299.653747 -231.619418)
			(xy 299.632624 -231.605074) (xy 299.626082 -231.6008) (xy 299.61122 -231.596005) (xy 299.603414 -231.595676)
			(xy 299.08754 -231.595676) (xy 299.082205 -231.595343) (xy 299.07466 -231.587802) (xy 299.074332 -231.582468)
			(xy 293.030125 -231.582468) (xy 293.029657 -231.587583) (xy 293.022056 -231.595169) (xy 293.016686 -231.595676)
			(xy 292.500812 -231.595676) (xy 292.493001 -231.595982) (xy 292.478129 -231.600772) (xy 292.471602 -231.605074)
			(xy 292.450479 -231.619421) (xy 292.404756 -231.642148) (xy 292.356083 -231.657578) (xy 292.305617 -231.665346)
			(xy 292.280086 -231.66578) (xy 292.254556 -231.665348) (xy 292.204092 -231.65757) (xy 292.155419 -231.64214)
			(xy 292.109692 -231.619422) (xy 292.08857 -231.605074) (xy 292.08204 -231.60078) (xy 292.067169 -231.595997)
			(xy 292.05936 -231.595676) (xy 291.543486 -231.595676) (xy 291.538124 -231.59516) (xy 291.53054 -231.587576)
			(xy 291.530024 -231.582214) (xy 285.48584 -231.582214) (xy 285.485384 -231.587524) (xy 285.477934 -231.595096)
			(xy 285.472632 -231.595676) (xy 284.956758 -231.595676) (xy 284.948949 -231.596002) (xy 284.934077 -231.600778)
			(xy 284.927548 -231.605074) (xy 284.90644 -231.619445) (xy 284.860711 -231.642166) (xy 284.812034 -231.65759)
			(xy 284.761564 -231.66535) (xy 284.736032 -231.66578) (xy 284.710503 -231.665325) (xy 284.66004 -231.657554)
			(xy 284.611367 -231.64213) (xy 284.565639 -231.619419) (xy 284.544516 -231.605074) (xy 284.537976 -231.600797)
			(xy 284.523113 -231.596004) (xy 284.515306 -231.595676) (xy 283.999432 -231.595676) (xy 283.994096 -231.595348)
			(xy 283.986552 -231.587804) (xy 283.986224 -231.582468) (xy 277.942018 -231.582468) (xy 277.941584 -231.587524)
			(xy 277.934134 -231.595096) (xy 277.928832 -231.595676) (xy 277.412958 -231.595676) (xy 277.405149 -231.596002)
			(xy 277.390277 -231.600778) (xy 277.383748 -231.605074) (xy 277.36264 -231.619445) (xy 277.316911 -231.642166)
			(xy 277.268234 -231.65759) (xy 277.217764 -231.66535) (xy 277.192232 -231.66578) (xy 277.166703 -231.665325)
			(xy 277.11624 -231.657554) (xy 277.067567 -231.64213) (xy 277.021839 -231.619419) (xy 277.000716 -231.605074)
			(xy 276.994176 -231.600797) (xy 276.979313 -231.596004) (xy 276.971506 -231.595676) (xy 276.455632 -231.595676)
			(xy 276.450296 -231.595348) (xy 276.442752 -231.587804) (xy 276.442424 -231.582468) (xy 270.398225 -231.582468)
			(xy 270.397928 -231.587656) (xy 270.390221 -231.595342) (xy 270.384778 -231.595676) (xy 269.868904 -231.595676)
			(xy 269.861093 -231.595979) (xy 269.846221 -231.600771) (xy 269.839694 -231.605074) (xy 269.818573 -231.619425)
			(xy 269.772849 -231.64215) (xy 269.724175 -231.65758) (xy 269.673709 -231.665347) (xy 269.648178 -231.66578)
			(xy 269.622647 -231.665352) (xy 269.572183 -231.657573) (xy 269.523511 -231.642141) (xy 269.477784 -231.619422)
			(xy 269.456662 -231.605074) (xy 269.450134 -231.600777) (xy 269.435261 -231.595996) (xy 269.427452 -231.595676)
			(xy 268.911578 -231.595676) (xy 268.906215 -231.595166) (xy 268.898631 -231.587577) (xy 268.898116 -231.582214)
			(xy 206.997808 -231.582214) (xy 206.997808 -231.582468) (xy 206.997452 -231.587796) (xy 206.989927 -231.595339)
			(xy 206.9846 -231.595676) (xy 206.468726 -231.595676) (xy 206.460849 -231.595935) (xy 206.445845 -231.600738)
			(xy 206.439262 -231.605074) (xy 206.418188 -231.61947) (xy 206.372541 -231.642297) (xy 206.323934 -231.657853)
			(xy 206.273517 -231.665771) (xy 206.248 -231.666288) (xy 206.222479 -231.665818) (xy 206.172051 -231.657918)
			(xy 206.12344 -231.642352) (xy 206.077802 -231.619492) (xy 206.056738 -231.605074) (xy 206.050135 -231.600778)
			(xy 206.035144 -231.595978) (xy 206.027274 -231.595676) (xy 205.5114 -231.595676) (xy 205.50606 -231.59537)
			(xy 205.498517 -231.587809) (xy 205.498192 -231.582468) (xy 199.454008 -231.582468) (xy 199.453652 -231.587796)
			(xy 199.446127 -231.595339) (xy 199.4408 -231.595676) (xy 198.924926 -231.595676) (xy 198.917049 -231.595935)
			(xy 198.902045 -231.600738) (xy 198.895462 -231.605074) (xy 198.874388 -231.61947) (xy 198.828741 -231.642297)
			(xy 198.780134 -231.657853) (xy 198.729717 -231.665771) (xy 198.7042 -231.666288) (xy 198.678679 -231.665818)
			(xy 198.628251 -231.657918) (xy 198.57964 -231.642352) (xy 198.534002 -231.619492) (xy 198.512938 -231.605074)
			(xy 198.506335 -231.600778) (xy 198.491344 -231.595978) (xy 198.483474 -231.595676) (xy 197.9676 -231.595676)
			(xy 197.96226 -231.59537) (xy 197.954717 -231.587809) (xy 197.954392 -231.582468) (xy 191.910208 -231.582468)
			(xy 191.909852 -231.587796) (xy 191.902327 -231.595339) (xy 191.897 -231.595676) (xy 191.896492 -231.595676)
			(xy 191.380872 -231.595676) (xy 191.372997 -231.595955) (xy 191.357992 -231.600744) (xy 191.351408 -231.605074)
			(xy 191.330349 -231.619493) (xy 191.284697 -231.642315) (xy 191.236085 -231.657865) (xy 191.185664 -231.665775)
			(xy 191.160146 -231.666288) (xy 191.134626 -231.665795) (xy 191.084199 -231.657901) (xy 191.035587 -231.642343)
			(xy 190.989949 -231.619489) (xy 190.968884 -231.605074) (xy 190.962294 -231.600757) (xy 190.947293 -231.59597)
			(xy 190.93942 -231.595676) (xy 190.423546 -231.595676) (xy 190.418251 -231.595148) (xy 190.410678 -231.58775)
			(xy 190.410084 -231.582468) (xy 184.3659 -231.582468) (xy 184.365551 -231.587798) (xy 184.358021 -231.595341)
			(xy 184.352692 -231.595676) (xy 183.836818 -231.595676) (xy 183.828944 -231.595975) (xy 183.81394 -231.60075)
			(xy 183.807354 -231.605074) (xy 183.786282 -231.619473) (xy 183.740635 -231.642299) (xy 183.692027 -231.657855)
			(xy 183.641609 -231.665772) (xy 183.616092 -231.666288) (xy 183.590573 -231.665771) (xy 183.540147 -231.657885)
			(xy 183.491535 -231.642333) (xy 183.445896 -231.619486) (xy 183.42483 -231.605074) (xy 183.418229 -231.600775)
			(xy 183.403236 -231.595977) (xy 183.395366 -231.595676) (xy 182.879492 -231.595676) (xy 182.874151 -231.595376)
			(xy 182.866608 -231.58781) (xy 182.866284 -231.582468) (xy 176.8221 -231.582468) (xy 176.821751 -231.587798)
			(xy 176.814221 -231.595341) (xy 176.808892 -231.595676) (xy 176.808384 -231.595676) (xy 176.292764 -231.595676)
			(xy 176.284888 -231.595952) (xy 176.269884 -231.600743) (xy 176.2633 -231.605074) (xy 176.242215 -231.619454)
			(xy 176.196573 -231.642284) (xy 176.147969 -231.657845) (xy 176.097554 -231.665768) (xy 176.072038 -231.666288)
			(xy 176.046518 -231.665799) (xy 175.996091 -231.657904) (xy 175.947479 -231.642344) (xy 175.901841 -231.619489)
			(xy 175.880776 -231.605074) (xy 175.874187 -231.600754) (xy 175.859185 -231.595969) (xy 175.851312 -231.595676)
			(xy 175.335438 -231.595676) (xy 175.330142 -231.595153) (xy 175.32257 -231.587752) (xy 175.321976 -231.582468)
			(xy 169.277792 -231.582468) (xy 169.27745 -231.5878) (xy 169.269915 -231.595344) (xy 169.264584 -231.595676)
			(xy 167.791384 -231.595676) (xy 167.786042 -231.595381) (xy 167.7785 -231.587812) (xy 167.778176 -231.582468)
			(xy 107.381071 -231.582468) (xy 107.370628 -231.623703) (xy 107.350316 -231.670005) (xy 107.32266 -231.712332)
			(xy 107.288414 -231.749529) (xy 107.248512 -231.780582) (xy 107.204043 -231.804643) (xy 107.156219 -231.821056)
			(xy 107.106347 -231.829374) (xy 107.081066 -231.829864) (xy 106.141012 -231.829864) (xy 106.115733 -231.829368)
			(xy 106.065864 -231.821048) (xy 106.018044 -231.804633) (xy 105.973579 -231.780571) (xy 105.93368 -231.749519)
			(xy 105.899437 -231.712322) (xy 105.871784 -231.669997) (xy 105.851474 -231.623697) (xy 105.839063 -231.574686)
			(xy 105.834887 -231.5243) (xy 104.567317 -231.5243) (xy 104.563141 -231.574689) (xy 104.550727 -231.623704)
			(xy 104.530415 -231.670007) (xy 104.502758 -231.712335) (xy 104.468511 -231.749532) (xy 104.428608 -231.780585)
			(xy 104.384137 -231.804646) (xy 104.336313 -231.821058) (xy 104.286439 -231.829374) (xy 104.261158 -231.829864)
			(xy 103.321104 -231.829864) (xy 103.295825 -231.829367) (xy 103.245957 -231.821046) (xy 103.198139 -231.804631)
			(xy 103.153674 -231.780569) (xy 103.113777 -231.749516) (xy 103.079535 -231.71232) (xy 103.051883 -231.669995)
			(xy 103.031574 -231.623695) (xy 103.019163 -231.574685) (xy 103.014987 -231.5243) (xy 101.747117 -231.5243)
			(xy 101.742941 -231.574686) (xy 101.73053 -231.623697) (xy 101.710221 -231.669996) (xy 101.682568 -231.712322)
			(xy 101.648326 -231.749519) (xy 101.608428 -231.780572) (xy 101.563963 -231.804635) (xy 101.516144 -231.82105)
			(xy 101.466275 -231.829371) (xy 101.440996 -231.829864) (xy 100.500942 -231.829864) (xy 100.475661 -231.82937)
			(xy 100.425788 -231.821054) (xy 100.377964 -231.804642) (xy 100.333495 -231.780582) (xy 100.293592 -231.749529)
			(xy 100.259345 -231.712332) (xy 100.231688 -231.670005) (xy 100.211376 -231.623703) (xy 100.198963 -231.574689)
			(xy 100.194787 -231.5243) (xy 60.178188 -231.5243) (xy 60.178188 -231.582468) (xy 60.17785 -231.587801)
			(xy 60.170312 -231.595345) (xy 60.16498 -231.595676) (xy 60.164472 -231.595676) (xy 58.691526 -231.595676)
			(xy 58.686229 -231.595161) (xy 58.678657 -231.587754) (xy 58.678064 -231.582468) (xy 52.63388 -231.582468)
			(xy 52.633549 -231.587803) (xy 52.626007 -231.595347) (xy 52.620672 -231.595676) (xy 52.104798 -231.595676)
			(xy 52.096924 -231.595966) (xy 52.081919 -231.600748) (xy 52.075334 -231.605074) (xy 52.054267 -231.619482)
			(xy 52.008618 -231.642306) (xy 51.960009 -231.657859) (xy 51.90959 -231.665773) (xy 51.884072 -231.666288)
			(xy 51.858552 -231.665781) (xy 51.808126 -231.657892) (xy 51.759514 -231.642337) (xy 51.713875 -231.619487)
			(xy 51.69281 -231.605074) (xy 51.686214 -231.600767) (xy 51.671218 -231.595974) (xy 51.663346 -231.595676)
			(xy 51.147472 -231.595676) (xy 51.142128 -231.595389) (xy 51.134587 -231.587813) (xy 51.134264 -231.582468)
			(xy 45.09008 -231.582468) (xy 45.089749 -231.587803) (xy 45.082207 -231.595347) (xy 45.076872 -231.595676)
			(xy 45.076364 -231.595676) (xy 44.560744 -231.595676) (xy 44.552868 -231.595943) (xy 44.537864 -231.60074)
			(xy 44.53128 -231.605074) (xy 44.510201 -231.619462) (xy 44.464556 -231.642291) (xy 44.415951 -231.657849)
			(xy 44.365534 -231.66577) (xy 44.340018 -231.666288) (xy 44.314497 -231.665809) (xy 44.26407 -231.657911)
			(xy 44.215458 -231.642348) (xy 44.16982 -231.619491) (xy 44.148756 -231.605074) (xy 44.142172 -231.600746)
			(xy 44.127166 -231.595966) (xy 44.119292 -231.595676) (xy 43.603418 -231.595676) (xy 43.59812 -231.595167)
			(xy 43.590548 -231.587755) (xy 43.589956 -231.582468) (xy 37.545772 -231.582468) (xy 37.545448 -231.587805)
			(xy 37.537901 -231.59535) (xy 37.532564 -231.595676) (xy 37.01669 -231.595676) (xy 37.008815 -231.595963)
			(xy 36.993811 -231.600746) (xy 36.987226 -231.605074) (xy 36.966162 -231.619486) (xy 36.920512 -231.642309)
			(xy 36.871902 -231.657861) (xy 36.821482 -231.665774) (xy 36.795964 -231.666288) (xy 36.770444 -231.665785)
			(xy 36.720018 -231.657895) (xy 36.671406 -231.642339) (xy 36.625767 -231.619488) (xy 36.604702 -231.605074)
			(xy 36.598107 -231.600764) (xy 36.58311 -231.595973) (xy 36.575238 -231.595676) (xy 36.059364 -231.595676)
			(xy 36.054089 -231.595226) (xy 36.046647 -231.587745) (xy 36.046156 -231.582468) (xy 30.001972 -231.582468)
			(xy 30.001648 -231.587805) (xy 29.994101 -231.59535) (xy 29.988764 -231.595676) (xy 29.47289 -231.595676)
			(xy 29.465015 -231.595963) (xy 29.450011 -231.600746) (xy 29.443426 -231.605074) (xy 29.422362 -231.619486)
			(xy 29.376712 -231.642309) (xy 29.328102 -231.657861) (xy 29.277682 -231.665774) (xy 29.252164 -231.666288)
			(xy 29.226644 -231.665785) (xy 29.176218 -231.657895) (xy 29.127606 -231.642339) (xy 29.081967 -231.619488)
			(xy 29.060902 -231.605074) (xy 29.054307 -231.600764) (xy 29.03931 -231.595973) (xy 29.031438 -231.595676)
			(xy 28.515564 -231.595676) (xy 28.510289 -231.595226) (xy 28.502847 -231.587745) (xy 28.502356 -231.582468)
			(xy 22.458172 -231.582468) (xy 22.457848 -231.587805) (xy 22.450301 -231.59535) (xy 22.444964 -231.595676)
			(xy 22.444456 -231.595676) (xy 21.928836 -231.595676) (xy 21.920959 -231.59594) (xy 21.905955 -231.600739)
			(xy 21.899372 -231.605074) (xy 21.878295 -231.619466) (xy 21.83265 -231.642293) (xy 21.784044 -231.657851)
			(xy 21.733627 -231.66577) (xy 21.70811 -231.666288) (xy 21.682589 -231.665813) (xy 21.632162 -231.657914)
			(xy 21.58355 -231.64235) (xy 21.537912 -231.619491) (xy 21.516848 -231.605074) (xy 21.510266 -231.600743)
			(xy 21.495259 -231.595965) (xy 21.487384 -231.595676) (xy 20.97151 -231.595676) (xy 20.966211 -231.595172)
			(xy 20.95864 -231.587756) (xy 20.958048 -231.582468) (xy 2.509012 -231.582468) (xy 2.509012 -232.432352)
			(xy 16.85798 -232.432352) (xy 16.85798 -231.937814) (xy 16.858293 -231.932371) (xy 16.865998 -231.924682)
			(xy 16.871442 -231.924352) (xy 17.38757 -231.924352) (xy 17.39538 -231.924033) (xy 17.410251 -231.919252)
			(xy 17.41678 -231.914954) (xy 17.437869 -231.900605) (xy 17.48353 -231.877874) (xy 17.532136 -231.862415)
			(xy 17.582539 -231.854592) (xy 17.633545 -231.854592) (xy 17.683948 -231.862415) (xy 17.732554 -231.877874)
			(xy 17.778215 -231.900605) (xy 17.799304 -231.914954) (xy 17.805838 -231.919241) (xy 17.820706 -231.924027)
			(xy 17.828514 -231.924352) (xy 18.344642 -231.924352) (xy 18.350014 -231.924824) (xy 18.357599 -231.93244)
			(xy 18.358104 -231.937814) (xy 18.358104 -232.432352) (xy 24.402288 -232.432352) (xy 24.402288 -231.937814)
			(xy 24.402738 -231.9325) (xy 24.410191 -231.924926) (xy 24.415496 -231.924352) (xy 24.931624 -231.924352)
			(xy 24.939436 -231.924057) (xy 24.954308 -231.919259) (xy 24.960834 -231.914954) (xy 24.981923 -231.900605)
			(xy 25.027584 -231.877874) (xy 25.07619 -231.862415) (xy 25.126593 -231.854592) (xy 25.177599 -231.854592)
			(xy 25.228002 -231.862415) (xy 25.276608 -231.877874) (xy 25.322269 -231.900605) (xy 25.343358 -231.914954)
			(xy 25.34988 -231.919262) (xy 25.364757 -231.924035) (xy 25.372568 -231.924352) (xy 25.888696 -231.924352)
			(xy 25.893949 -231.924893) (xy 25.901389 -231.932309) (xy 25.901904 -231.93756) (xy 25.901904 -231.938068)
			(xy 25.901904 -232.432352) (xy 31.946088 -232.432352) (xy 31.946088 -231.937814) (xy 31.946538 -231.9325)
			(xy 31.953991 -231.924926) (xy 31.959296 -231.924352) (xy 32.475424 -231.924352) (xy 32.483236 -231.924057)
			(xy 32.498108 -231.919259) (xy 32.504634 -231.914954) (xy 32.525723 -231.900605) (xy 32.571384 -231.877874)
			(xy 32.61999 -231.862415) (xy 32.670393 -231.854592) (xy 32.721399 -231.854592) (xy 32.771802 -231.862415)
			(xy 32.820408 -231.877874) (xy 32.866069 -231.900605) (xy 32.887158 -231.914954) (xy 32.89368 -231.919262)
			(xy 32.908557 -231.924035) (xy 32.916368 -231.924352) (xy 33.432496 -231.924352) (xy 33.437749 -231.924893)
			(xy 33.445189 -231.932309) (xy 33.445704 -231.93756) (xy 33.445704 -231.938068) (xy 33.445704 -232.432352)
			(xy 39.489888 -232.432352) (xy 39.489888 -231.937814) (xy 39.490455 -231.932464) (xy 39.498002 -231.92488)
			(xy 39.50335 -231.924352) (xy 40.019478 -231.924352) (xy 40.027288 -231.924037) (xy 40.04216 -231.919253)
			(xy 40.048688 -231.914954) (xy 40.069777 -231.900605) (xy 40.115438 -231.877874) (xy 40.164044 -231.862415)
			(xy 40.214447 -231.854592) (xy 40.265453 -231.854592) (xy 40.315856 -231.862415) (xy 40.364462 -231.877874)
			(xy 40.410123 -231.900605) (xy 40.431212 -231.914954) (xy 40.437744 -231.919244) (xy 40.452614 -231.924029)
			(xy 40.460422 -231.924352) (xy 40.97655 -231.924352) (xy 40.981923 -231.924819) (xy 40.989507 -231.932438)
			(xy 40.990012 -231.937814) (xy 40.990012 -232.432352) (xy 47.034196 -232.432352) (xy 47.034196 -231.937814)
			(xy 47.034727 -231.932522) (xy 47.042124 -231.924952) (xy 47.047404 -231.924352) (xy 47.563532 -231.924352)
			(xy 47.57134 -231.924017) (xy 47.586212 -231.919247) (xy 47.592742 -231.914954) (xy 47.613831 -231.900605)
			(xy 47.659492 -231.877874) (xy 47.708098 -231.862415) (xy 47.758501 -231.854592) (xy 47.809507 -231.854592)
			(xy 47.85991 -231.862415) (xy 47.908516 -231.877874) (xy 47.954177 -231.900605) (xy 47.975266 -231.914954)
			(xy 47.981809 -231.919226) (xy 47.99667 -231.924022) (xy 48.004476 -231.924352) (xy 48.520604 -231.924352)
			(xy 48.525858 -231.924888) (xy 48.533298 -231.932308) (xy 48.533812 -231.93756) (xy 48.533812 -231.938068)
			(xy 48.533812 -232.432352) (xy 54.577996 -232.432352) (xy 54.577996 -231.937814) (xy 54.578555 -231.932462)
			(xy 54.586108 -231.924878) (xy 54.591458 -231.924352) (xy 56.064658 -231.924352) (xy 56.070091 -231.924709)
			(xy 56.07778 -231.932382) (xy 56.07812 -231.937814) (xy 56.07812 -232.3343) (xy 108.185148 -232.3343)
			(xy 108.18932 -232.283956) (xy 108.201721 -232.234986) (xy 108.222014 -232.188725) (xy 108.249645 -232.146435)
			(xy 108.28386 -232.10927) (xy 108.323725 -232.078244) (xy 108.368154 -232.054203) (xy 108.415934 -232.037803)
			(xy 108.465762 -232.029491) (xy 108.49102 -232.029) (xy 109.431074 -232.029) (xy 109.456334 -232.029475)
			(xy 109.506165 -232.037786) (xy 109.553948 -232.054187) (xy 109.59838 -232.078229) (xy 109.638249 -232.109256)
			(xy 109.672466 -232.146423) (xy 109.700099 -232.188716) (xy 109.720393 -232.23498) (xy 109.732796 -232.283953)
			(xy 109.736968 -232.3343) (xy 109.732796 -232.384647) (xy 109.720714 -232.432352) (xy 163.678108 -232.432352)
			(xy 163.678108 -231.937814) (xy 163.678629 -231.932519) (xy 163.686033 -231.924949) (xy 163.691316 -231.924352)
			(xy 165.164516 -231.924352) (xy 165.169771 -231.92488) (xy 165.177211 -231.932306) (xy 165.177724 -231.93756)
			(xy 165.177724 -231.938068) (xy 165.177724 -232.432352) (xy 171.221908 -232.432352) (xy 171.221908 -231.937814)
			(xy 171.222457 -231.932459) (xy 171.230017 -231.924874) (xy 171.23537 -231.924352) (xy 171.751498 -231.924352)
			(xy 171.759309 -231.924046) (xy 171.774181 -231.919256) (xy 171.780708 -231.914954) (xy 171.801797 -231.900605)
			(xy 171.847458 -231.877874) (xy 171.896064 -231.862415) (xy 171.946467 -231.854592) (xy 171.997473 -231.854592)
			(xy 172.047876 -231.862415) (xy 172.096482 -231.877874) (xy 172.142143 -231.900605) (xy 172.163232 -231.914954)
			(xy 172.16976 -231.919252) (xy 172.184633 -231.924031) (xy 172.192442 -231.924352) (xy 172.70857 -231.924352)
			(xy 172.714004 -231.924701) (xy 172.721693 -231.93238) (xy 172.722032 -231.937814) (xy 172.722032 -232.432352)
			(xy 178.766216 -232.432352) (xy 178.766216 -231.937814) (xy 178.76673 -231.932517) (xy 178.774139 -231.924947)
			(xy 178.779424 -231.924352) (xy 179.295552 -231.924352) (xy 179.303361 -231.924026) (xy 179.318233 -231.919249)
			(xy 179.324762 -231.914954) (xy 179.345851 -231.900605) (xy 179.391512 -231.877874) (xy 179.440118 -231.862415)
			(xy 179.490521 -231.854592) (xy 179.541527 -231.854592) (xy 179.59193 -231.862415) (xy 179.640536 -231.877874)
			(xy 179.686197 -231.900605) (xy 179.707286 -231.914954) (xy 179.713824 -231.919234) (xy 179.728689 -231.924025)
			(xy 179.736496 -231.924352) (xy 180.252624 -231.924352) (xy 180.25788 -231.924875) (xy 180.265319 -231.932305)
			(xy 180.265832 -231.93756) (xy 180.265832 -231.938068) (xy 180.265832 -232.432352) (xy 186.310016 -232.432352)
			(xy 186.310016 -231.937814) (xy 186.310557 -231.932457) (xy 186.318122 -231.924872) (xy 186.323478 -231.924352)
			(xy 186.839606 -231.924352) (xy 186.847417 -231.924049) (xy 186.862289 -231.919257) (xy 186.868816 -231.914954)
			(xy 186.889905 -231.900605) (xy 186.935566 -231.877874) (xy 186.984172 -231.862415) (xy 187.034575 -231.854592)
			(xy 187.085581 -231.854592) (xy 187.135984 -231.862415) (xy 187.18459 -231.877874) (xy 187.230251 -231.900605)
			(xy 187.25134 -231.914954) (xy 187.257866 -231.919255) (xy 187.27274 -231.924033) (xy 187.28055 -231.924352)
			(xy 187.796678 -231.924352) (xy 187.802113 -231.924696) (xy 187.809801 -231.932379) (xy 187.81014 -231.937814)
			(xy 187.81014 -232.432352) (xy 193.854324 -232.432352) (xy 193.854324 -231.937814) (xy 193.854831 -231.932515)
			(xy 193.862245 -231.924944) (xy 193.867532 -231.924352) (xy 194.38366 -231.924352) (xy 194.391469 -231.924029)
			(xy 194.406341 -231.91925) (xy 194.41287 -231.914954) (xy 194.433959 -231.900605) (xy 194.47962 -231.877874)
			(xy 194.528226 -231.862415) (xy 194.578629 -231.854592) (xy 194.629635 -231.854592) (xy 194.680038 -231.862415)
			(xy 194.728644 -231.877874) (xy 194.774305 -231.900605) (xy 194.795394 -231.914954) (xy 194.80193 -231.919237)
			(xy 194.816797 -231.924026) (xy 194.824604 -231.924352) (xy 195.340732 -231.924352) (xy 195.345989 -231.924869)
			(xy 195.353427 -231.932303) (xy 195.35394 -231.93756) (xy 195.35394 -231.938068) (xy 195.35394 -232.432352)
			(xy 201.398124 -232.432352) (xy 201.398124 -231.937814) (xy 201.398631 -231.932515) (xy 201.406045 -231.924944)
			(xy 201.411332 -231.924352) (xy 201.92746 -231.924352) (xy 201.935269 -231.924029) (xy 201.950141 -231.91925)
			(xy 201.95667 -231.914954) (xy 201.977759 -231.900605) (xy 202.02342 -231.877874) (xy 202.072026 -231.862415)
			(xy 202.122429 -231.854592) (xy 202.173435 -231.854592) (xy 202.223838 -231.862415) (xy 202.272444 -231.877874)
			(xy 202.318105 -231.900605) (xy 202.339194 -231.914954) (xy 202.34573 -231.919237) (xy 202.360597 -231.924026)
			(xy 202.368404 -231.924352) (xy 202.884532 -231.924352) (xy 202.889789 -231.924869) (xy 202.897227 -231.932303)
			(xy 202.89774 -231.93756) (xy 202.89774 -231.938068) (xy 202.89774 -232.432098) (xy 264.798048 -232.432098)
			(xy 264.798048 -231.93756) (xy 264.798564 -231.932303) (xy 264.805999 -231.924865) (xy 264.811256 -231.924352)
			(xy 264.811764 -231.924352) (xy 265.327638 -231.924352) (xy 265.335447 -231.92402) (xy 265.350318 -231.919247)
			(xy 265.356848 -231.914954) (xy 265.377937 -231.900605) (xy 265.423598 -231.877874) (xy 265.472204 -231.862415)
			(xy 265.522607 -231.854592) (xy 265.573613 -231.854592) (xy 265.624016 -231.862415) (xy 265.672622 -231.877874)
			(xy 265.718283 -231.900605) (xy 265.739372 -231.914954) (xy 265.745913 -231.919229) (xy 265.760776 -231.924023)
			(xy 265.768582 -231.924352) (xy 266.28471 -231.924352) (xy 266.290018 -231.924818) (xy 266.297589 -231.932261)
			(xy 266.298172 -231.93756) (xy 266.298172 -232.432098) (xy 266.298147 -232.432352) (xy 272.342356 -232.432352)
			(xy 272.342356 -232.431844) (xy 272.342356 -231.93756) (xy 272.342864 -231.932301) (xy 272.350305 -231.924863)
			(xy 272.355564 -231.924352) (xy 272.871692 -231.924352) (xy 272.879503 -231.924043) (xy 272.894374 -231.919254)
			(xy 272.900902 -231.914954) (xy 272.921991 -231.900605) (xy 272.967652 -231.877874) (xy 273.016258 -231.862415)
			(xy 273.066661 -231.854592) (xy 273.117667 -231.854592) (xy 273.16807 -231.862415) (xy 273.216676 -231.877874)
			(xy 273.262337 -231.900605) (xy 273.283426 -231.914954) (xy 273.289955 -231.919249) (xy 273.304827 -231.924031)
			(xy 273.312636 -231.924352) (xy 273.828764 -231.924352) (xy 273.834013 -231.924915) (xy 273.841455 -231.932314)
			(xy 273.841972 -231.93756) (xy 273.841972 -232.432098) (xy 273.841948 -232.432352) (xy 279.886156 -232.432352)
			(xy 279.886156 -232.431844) (xy 279.886156 -231.93756) (xy 279.886664 -231.932301) (xy 279.894105 -231.924863)
			(xy 279.899364 -231.924352) (xy 280.415492 -231.924352) (xy 280.423303 -231.924043) (xy 280.438174 -231.919254)
			(xy 280.444702 -231.914954) (xy 280.465791 -231.900605) (xy 280.511452 -231.877874) (xy 280.560058 -231.862415)
			(xy 280.610461 -231.854592) (xy 280.661467 -231.854592) (xy 280.71187 -231.862415) (xy 280.760476 -231.877874)
			(xy 280.806137 -231.900605) (xy 280.827226 -231.914954) (xy 280.833755 -231.919249) (xy 280.848627 -231.924031)
			(xy 280.856436 -231.924352) (xy 281.372564 -231.924352) (xy 281.377813 -231.924915) (xy 281.385255 -231.932314)
			(xy 281.385772 -231.93756) (xy 281.385772 -232.432098) (xy 287.429956 -232.432098) (xy 287.429956 -231.93756)
			(xy 287.430464 -231.932301) (xy 287.437905 -231.924863) (xy 287.443164 -231.924352) (xy 287.443672 -231.924352)
			(xy 287.959546 -231.924352) (xy 287.967355 -231.924023) (xy 287.982227 -231.919248) (xy 287.988756 -231.914954)
			(xy 288.009845 -231.900605) (xy 288.055506 -231.877874) (xy 288.104112 -231.862415) (xy 288.154515 -231.854592)
			(xy 288.205521 -231.854592) (xy 288.255924 -231.862415) (xy 288.30453 -231.877874) (xy 288.350191 -231.900605)
			(xy 288.37128 -231.914954) (xy 288.377819 -231.919232) (xy 288.392683 -231.924024) (xy 288.40049 -231.924352)
			(xy 288.916618 -231.924352) (xy 288.921927 -231.924812) (xy 288.929498 -231.93226) (xy 288.93008 -231.93756)
			(xy 288.93008 -232.432098) (xy 288.930055 -232.432352) (xy 294.974264 -232.432352) (xy 294.974264 -232.431844)
			(xy 294.974264 -231.93756) (xy 294.974765 -231.932299) (xy 294.982211 -231.92486) (xy 294.987472 -231.924352)
			(xy 295.5036 -231.924352) (xy 295.511411 -231.924047) (xy 295.526283 -231.919256) (xy 295.53281 -231.914954)
			(xy 295.553899 -231.900605) (xy 295.59956 -231.877874) (xy 295.648166 -231.862415) (xy 295.698569 -231.854592)
			(xy 295.749575 -231.854592) (xy 295.799978 -231.862415) (xy 295.848584 -231.877874) (xy 295.894245 -231.900605)
			(xy 295.915334 -231.914954) (xy 295.921861 -231.919252) (xy 295.936734 -231.924032) (xy 295.944544 -231.924352)
			(xy 296.460672 -231.924352) (xy 296.465922 -231.924909) (xy 296.473364 -231.932313) (xy 296.47388 -231.93756)
			(xy 296.47388 -232.432098) (xy 302.518064 -232.432098) (xy 302.518064 -231.93756) (xy 302.518565 -231.932299)
			(xy 302.526011 -231.92486) (xy 302.531272 -231.924352) (xy 304.004726 -231.924352) (xy 304.010036 -231.924807)
			(xy 304.017606 -231.932259) (xy 304.018188 -231.93756) (xy 304.018188 -232.3341) (xy 361.758639 -232.3341)
			(xy 361.762815 -232.283707) (xy 361.775229 -232.234688) (xy 361.795541 -232.188381) (xy 361.823198 -232.14605)
			(xy 361.857446 -232.108848) (xy 361.89735 -232.07779) (xy 361.941822 -232.053724) (xy 361.989649 -232.037306)
			(xy 362.039525 -232.028985) (xy 362.064808 -232.028492) (xy 363.004862 -232.028492) (xy 363.030139 -232.029074)
			(xy 363.080004 -232.037389) (xy 363.127821 -232.053799) (xy 363.172283 -232.077857) (xy 363.21218 -232.108905)
			(xy 363.246421 -232.146096) (xy 363.274073 -232.188417) (xy 363.294382 -232.234712) (xy 363.306793 -232.283719)
			(xy 363.310969 -232.3341) (xy 363.306793 -232.384481) (xy 363.29467 -232.432352) (xy 411.618176 -232.432352)
			(xy 411.618176 -232.431844) (xy 411.618176 -231.93756) (xy 411.618666 -231.932296) (xy 411.626119 -231.924857)
			(xy 411.631384 -231.924352) (xy 413.104584 -231.924352) (xy 413.109835 -231.924901) (xy 413.117276 -231.932311)
			(xy 413.117792 -231.93756) (xy 413.117792 -232.432098) (xy 419.161976 -232.432098) (xy 419.161976 -231.93756)
			(xy 419.162466 -231.932296) (xy 419.169919 -231.924857) (xy 419.175184 -231.924352) (xy 419.175692 -231.924352)
			(xy 419.691566 -231.924352) (xy 419.699376 -231.924032) (xy 419.714247 -231.919251) (xy 419.720776 -231.914954)
			(xy 419.741865 -231.900605) (xy 419.787526 -231.877874) (xy 419.836132 -231.862415) (xy 419.886535 -231.854592)
			(xy 419.937541 -231.854592) (xy 419.987944 -231.862415) (xy 420.03655 -231.877874) (xy 420.082211 -231.900605)
			(xy 420.1033 -231.914954) (xy 420.109835 -231.919239) (xy 420.124702 -231.924027) (xy 420.13251 -231.924352)
			(xy 420.648638 -231.924352) (xy 420.65395 -231.9248) (xy 420.661519 -231.932257) (xy 420.6621 -231.93756)
			(xy 420.6621 -232.432098) (xy 420.662074 -232.432352) (xy 426.706284 -232.432352) (xy 426.706284 -232.431844)
			(xy 426.706284 -231.93756) (xy 426.706767 -231.932294) (xy 426.714225 -231.924854) (xy 426.719492 -231.924352)
			(xy 427.23562 -231.924352) (xy 427.243432 -231.924055) (xy 427.258303 -231.919259) (xy 427.26483 -231.914954)
			(xy 427.285919 -231.900605) (xy 427.33158 -231.877874) (xy 427.380186 -231.862415) (xy 427.430589 -231.854592)
			(xy 427.481595 -231.854592) (xy 427.531998 -231.862415) (xy 427.580604 -231.877874) (xy 427.626265 -231.900605)
			(xy 427.647354 -231.914954) (xy 427.653877 -231.91926) (xy 427.668753 -231.924035) (xy 427.676564 -231.924352)
			(xy 428.192692 -231.924352) (xy 428.197944 -231.924896) (xy 428.205385 -231.93231) (xy 428.2059 -231.93756)
			(xy 428.2059 -232.432098) (xy 434.250084 -232.432098) (xy 434.250084 -231.93756) (xy 434.250567 -231.932294)
			(xy 434.258025 -231.924854) (xy 434.263292 -231.924352) (xy 434.2638 -231.924352) (xy 434.779674 -231.924352)
			(xy 434.787484 -231.924035) (xy 434.802356 -231.919252) (xy 434.808884 -231.914954) (xy 434.829973 -231.900605)
			(xy 434.875634 -231.877874) (xy 434.92424 -231.862415) (xy 434.974643 -231.854592) (xy 435.025649 -231.854592)
			(xy 435.076052 -231.862415) (xy 435.124658 -231.877874) (xy 435.170319 -231.900605) (xy 435.191408 -231.914954)
			(xy 435.197941 -231.919243) (xy 435.21281 -231.924028) (xy 435.220618 -231.924352) (xy 435.736746 -231.924352)
			(xy 435.742047 -231.924861) (xy 435.749621 -231.932271) (xy 435.750208 -231.93756) (xy 435.750208 -232.432098)
			(xy 435.750182 -232.432352) (xy 441.794392 -232.432352) (xy 441.794392 -232.431844) (xy 441.794392 -231.93756)
			(xy 441.794868 -231.932292) (xy 441.802331 -231.924852) (xy 441.8076 -231.924352) (xy 442.323728 -231.924352)
			(xy 442.33154 -231.924058) (xy 442.346412 -231.91926) (xy 442.352938 -231.914954) (xy 442.374027 -231.900605)
			(xy 442.419688 -231.877874) (xy 442.468294 -231.862415) (xy 442.518697 -231.854592) (xy 442.569703 -231.854592)
			(xy 442.620106 -231.862415) (xy 442.668712 -231.877874) (xy 442.714373 -231.900605) (xy 442.735462 -231.914954)
			(xy 442.742005 -231.919225) (xy 442.756866 -231.924021) (xy 442.764672 -231.924352) (xy 443.2808 -231.924352)
			(xy 443.286053 -231.924891) (xy 443.293493 -231.932308) (xy 443.294008 -231.93756) (xy 443.294008 -232.432098)
			(xy 443.293983 -232.432352) (xy 449.338192 -232.432352) (xy 449.338192 -232.431844) (xy 449.338192 -231.93756)
			(xy 449.338668 -231.932292) (xy 449.346131 -231.924852) (xy 449.3514 -231.924352) (xy 449.867528 -231.924352)
			(xy 449.87534 -231.924058) (xy 449.890212 -231.91926) (xy 449.896738 -231.914954) (xy 449.917827 -231.900605)
			(xy 449.963488 -231.877874) (xy 450.012094 -231.862415) (xy 450.062497 -231.854592) (xy 450.113503 -231.854592)
			(xy 450.163906 -231.862415) (xy 450.212512 -231.877874) (xy 450.258173 -231.900605) (xy 450.279262 -231.914954)
			(xy 450.285805 -231.919225) (xy 450.300666 -231.924021) (xy 450.308472 -231.924352) (xy 450.8246 -231.924352)
			(xy 450.829853 -231.924891) (xy 450.837293 -231.932308) (xy 450.837808 -231.93756) (xy 450.837808 -232.432098)
			(xy 450.837281 -232.437391) (xy 450.829881 -232.444959) (xy 450.8246 -232.44556) (xy 450.308726 -232.44556)
			(xy 450.300916 -232.445875) (xy 450.286044 -232.450659) (xy 450.279516 -232.454958) (xy 450.258388 -232.469297)
			(xy 450.212666 -232.492026) (xy 450.163995 -232.507459) (xy 450.11353 -232.515229) (xy 450.088 -232.515664)
			(xy 450.06247 -232.515228) (xy 450.012006 -232.507452) (xy 449.963333 -232.492022) (xy 449.917606 -232.469306)
			(xy 449.896484 -232.454958) (xy 449.889952 -232.450667) (xy 449.875082 -232.445883) (xy 449.867274 -232.44556)
			(xy 449.3514 -232.44556) (xy 449.346056 -232.445269) (xy 449.338512 -232.437697) (xy 449.338192 -232.432352)
			(xy 443.293983 -232.432352) (xy 443.293481 -232.437391) (xy 443.286081 -232.444959) (xy 443.2808 -232.44556)
			(xy 442.764926 -232.44556) (xy 442.757116 -232.445875) (xy 442.742244 -232.450659) (xy 442.735716 -232.454958)
			(xy 442.714588 -232.469297) (xy 442.668866 -232.492026) (xy 442.620195 -232.507459) (xy 442.56973 -232.515229)
			(xy 442.5442 -232.515664) (xy 442.51867 -232.515228) (xy 442.468206 -232.507452) (xy 442.419533 -232.492022)
			(xy 442.373806 -232.469306) (xy 442.352684 -232.454958) (xy 442.346152 -232.450667) (xy 442.331282 -232.445883)
			(xy 442.323474 -232.44556) (xy 441.8076 -232.44556) (xy 441.802256 -232.445269) (xy 441.794712 -232.437697)
			(xy 441.794392 -232.432352) (xy 435.750182 -232.432352) (xy 435.749653 -232.437451) (xy 435.742097 -232.445034)
			(xy 435.736746 -232.44556) (xy 435.220872 -232.44556) (xy 435.21306 -232.445851) (xy 435.198188 -232.450652)
			(xy 435.191662 -232.454958) (xy 435.170549 -232.469321) (xy 435.124822 -232.492044) (xy 435.076146 -232.50747)
			(xy 435.025678 -232.515233) (xy 435.000146 -232.515664) (xy 434.974617 -232.515204) (xy 434.924154 -232.507436)
			(xy 434.875481 -232.492013) (xy 434.829753 -232.469303) (xy 434.80863 -232.454958) (xy 434.802088 -232.450685)
			(xy 434.787226 -232.44589) (xy 434.77942 -232.44556) (xy 434.263546 -232.44556) (xy 434.258117 -232.44519)
			(xy 434.250428 -232.437526) (xy 434.250084 -232.432098) (xy 428.2059 -232.432098) (xy 428.20538 -232.437393)
			(xy 428.197975 -232.444961) (xy 428.192692 -232.44556) (xy 427.676818 -232.44556) (xy 427.669008 -232.445871)
			(xy 427.654136 -232.450658) (xy 427.647608 -232.454958) (xy 427.626482 -232.469301) (xy 427.58076 -232.492029)
			(xy 427.532088 -232.507461) (xy 427.481623 -232.51523) (xy 427.456092 -232.515664) (xy 427.430562 -232.515232)
			(xy 427.380098 -232.507454) (xy 427.331425 -232.492024) (xy 427.285698 -232.469306) (xy 427.264576 -232.454958)
			(xy 427.258046 -232.450664) (xy 427.243175 -232.445882) (xy 427.235366 -232.44556) (xy 426.719492 -232.44556)
			(xy 426.714147 -232.445274) (xy 426.706603 -232.437699) (xy 426.706284 -232.432352) (xy 420.662074 -232.432352)
			(xy 420.661552 -232.437453) (xy 420.653991 -232.445036) (xy 420.648638 -232.44556) (xy 420.132764 -232.44556)
			(xy 420.124955 -232.445891) (xy 420.110083 -232.450664) (xy 420.103554 -232.454958) (xy 420.082443 -232.469324)
			(xy 420.036715 -232.492047) (xy 419.988039 -232.507472) (xy 419.93757 -232.515234) (xy 419.912038 -232.515664)
			(xy 419.886508 -232.515208) (xy 419.836045 -232.507438) (xy 419.787373 -232.492015) (xy 419.741645 -232.469303)
			(xy 419.720522 -232.454958) (xy 419.713981 -232.450682) (xy 419.699119 -232.445889) (xy 419.691312 -232.44556)
			(xy 419.175438 -232.44556) (xy 419.170008 -232.445195) (xy 419.162319 -232.437527) (xy 419.161976 -232.432098)
			(xy 413.117792 -232.432098) (xy 413.117279 -232.437394) (xy 413.109869 -232.444964) (xy 413.104584 -232.44556)
			(xy 411.631384 -232.44556) (xy 411.626038 -232.445279) (xy 411.618495 -232.4377) (xy 411.618176 -232.432352)
			(xy 363.29467 -232.432352) (xy 363.294382 -232.433488) (xy 363.274073 -232.479783) (xy 363.246421 -232.522104)
			(xy 363.21218 -232.559295) (xy 363.172283 -232.590343) (xy 363.127821 -232.614401) (xy 363.080004 -232.630811)
			(xy 363.030139 -232.639126) (xy 363.004862 -232.639616) (xy 362.064808 -232.639616) (xy 362.039525 -232.639215)
			(xy 361.989649 -232.630894) (xy 361.941822 -232.614476) (xy 361.89735 -232.59041) (xy 361.857446 -232.559352)
			(xy 361.823198 -232.52215) (xy 361.795541 -232.479819) (xy 361.775229 -232.433512) (xy 361.762815 -232.384493)
			(xy 361.758639 -232.3341) (xy 304.018188 -232.3341) (xy 304.018188 -232.432098) (xy 304.017651 -232.437455)
			(xy 304.010082 -232.44504) (xy 304.004726 -232.44556) (xy 302.531526 -232.44556) (xy 302.526094 -232.445203)
			(xy 302.518406 -232.437529) (xy 302.518064 -232.432098) (xy 296.47388 -232.432098) (xy 296.473378 -232.437397)
			(xy 296.46596 -232.444967) (xy 296.460672 -232.44556) (xy 295.944798 -232.44556) (xy 295.936987 -232.445863)
			(xy 295.922115 -232.450655) (xy 295.915588 -232.454958) (xy 295.894468 -232.469309) (xy 295.848743 -232.492035)
			(xy 295.80007 -232.507465) (xy 295.749603 -232.515231) (xy 295.724072 -232.515664) (xy 295.698541 -232.515242)
			(xy 295.648077 -232.507461) (xy 295.599404 -232.492028) (xy 295.553677 -232.469307) (xy 295.532556 -232.454958)
			(xy 295.52603 -232.450657) (xy 295.511156 -232.445879) (xy 295.503346 -232.44556) (xy 294.987472 -232.44556)
			(xy 294.982124 -232.445287) (xy 294.974582 -232.437702) (xy 294.974264 -232.432352) (xy 288.930055 -232.432352)
			(xy 288.92955 -232.437457) (xy 288.921977 -232.445042) (xy 288.916618 -232.44556) (xy 288.400744 -232.44556)
			(xy 288.392935 -232.445882) (xy 288.378063 -232.450661) (xy 288.371534 -232.454958) (xy 288.350429 -232.469333)
			(xy 288.304699 -232.492053) (xy 288.256021 -232.507476) (xy 288.20555 -232.515235) (xy 288.180018 -232.515664)
			(xy 288.154488 -232.515219) (xy 288.104025 -232.507445) (xy 288.055352 -232.492019) (xy 288.009624 -232.469304)
			(xy 287.988502 -232.454958) (xy 287.981966 -232.450674) (xy 287.9671 -232.445886) (xy 287.959292 -232.44556)
			(xy 287.443418 -232.44556) (xy 287.437985 -232.445209) (xy 287.430298 -232.437531) (xy 287.429956 -232.432098)
			(xy 281.385772 -232.432098) (xy 281.385277 -232.437399) (xy 281.377854 -232.44497) (xy 281.372564 -232.44556)
			(xy 280.85669 -232.44556) (xy 280.848878 -232.44586) (xy 280.834007 -232.450654) (xy 280.82748 -232.454958)
			(xy 280.806362 -232.469313) (xy 280.760637 -232.492038) (xy 280.711962 -232.507467) (xy 280.661495 -232.515232)
			(xy 280.635964 -232.515664) (xy 280.610433 -232.515246) (xy 280.559968 -232.507464) (xy 280.511296 -232.49203)
			(xy 280.465569 -232.469308) (xy 280.444448 -232.454958) (xy 280.437924 -232.450654) (xy 280.423048 -232.445878)
			(xy 280.415238 -232.44556) (xy 279.899364 -232.44556) (xy 279.894015 -232.445293) (xy 279.886473 -232.437703)
			(xy 279.886156 -232.432352) (xy 273.841948 -232.432352) (xy 273.841477 -232.437399) (xy 273.834054 -232.44497)
			(xy 273.828764 -232.44556) (xy 273.31289 -232.44556) (xy 273.305078 -232.44586) (xy 273.290207 -232.450654)
			(xy 273.28368 -232.454958) (xy 273.262562 -232.469313) (xy 273.216837 -232.492038) (xy 273.168162 -232.507467)
			(xy 273.117695 -232.515232) (xy 273.092164 -232.515664) (xy 273.066633 -232.515246) (xy 273.016168 -232.507464)
			(xy 272.967496 -232.49203) (xy 272.921769 -232.469308) (xy 272.900648 -232.454958) (xy 272.894124 -232.450654)
			(xy 272.879248 -232.445878) (xy 272.871438 -232.44556) (xy 272.355564 -232.44556) (xy 272.350215 -232.445293)
			(xy 272.342673 -232.437703) (xy 272.342356 -232.432352) (xy 266.298147 -232.432352) (xy 266.297649 -232.437459)
			(xy 266.290071 -232.445045) (xy 266.28471 -232.44556) (xy 265.768836 -232.44556) (xy 265.761026 -232.445879)
			(xy 265.746154 -232.45066) (xy 265.739626 -232.454958) (xy 265.718495 -232.469293) (xy 265.672775 -232.492023)
			(xy 265.624104 -232.507457) (xy 265.57364 -232.515228) (xy 265.54811 -232.515664) (xy 265.52258 -232.515223)
			(xy 265.472116 -232.507448) (xy 265.423444 -232.49202) (xy 265.377716 -232.469305) (xy 265.356594 -232.454958)
			(xy 265.35006 -232.450671) (xy 265.335192 -232.445884) (xy 265.327384 -232.44556) (xy 264.81151 -232.44556)
			(xy 264.806076 -232.445214) (xy 264.798389 -232.437532) (xy 264.798048 -232.432098) (xy 202.89774 -232.432098)
			(xy 202.89774 -232.432352) (xy 202.897344 -232.43767) (xy 202.889848 -232.445212) (xy 202.884532 -232.44556)
			(xy 202.368658 -232.44556) (xy 202.360782 -232.445836) (xy 202.345778 -232.450628) (xy 202.339194 -232.454958)
			(xy 202.318109 -232.469338) (xy 202.272467 -232.492169) (xy 202.223863 -232.50773) (xy 202.173448 -232.515653)
			(xy 202.147932 -232.516172) (xy 202.122412 -232.515688) (xy 202.071984 -232.507793) (xy 202.023372 -232.492231)
			(xy 201.977734 -232.469374) (xy 201.95667 -232.454958) (xy 201.950084 -232.450634) (xy 201.93508 -232.445852)
			(xy 201.927206 -232.44556) (xy 201.411332 -232.44556) (xy 201.405992 -232.445247) (xy 201.398447 -232.437692)
			(xy 201.398124 -232.432352) (xy 195.35394 -232.432352) (xy 195.353544 -232.43767) (xy 195.346048 -232.445212)
			(xy 195.340732 -232.44556) (xy 194.824858 -232.44556) (xy 194.816982 -232.445836) (xy 194.801978 -232.450628)
			(xy 194.795394 -232.454958) (xy 194.774309 -232.469338) (xy 194.728667 -232.492169) (xy 194.680063 -232.50773)
			(xy 194.629648 -232.515653) (xy 194.604132 -232.516172) (xy 194.578612 -232.515688) (xy 194.528184 -232.507793)
			(xy 194.479572 -232.492231) (xy 194.433934 -232.469374) (xy 194.41287 -232.454958) (xy 194.406284 -232.450634)
			(xy 194.39128 -232.445852) (xy 194.383406 -232.44556) (xy 193.867532 -232.44556) (xy 193.862192 -232.445247)
			(xy 193.854647 -232.437692) (xy 193.854324 -232.432352) (xy 187.81014 -232.432352) (xy 187.809744 -232.43767)
			(xy 187.802248 -232.445212) (xy 187.796932 -232.44556) (xy 187.796424 -232.44556) (xy 187.280804 -232.44556)
			(xy 187.27293 -232.445855) (xy 187.257926 -232.450634) (xy 187.25134 -232.454958) (xy 187.23027 -232.469362)
			(xy 187.184623 -232.492187) (xy 187.136014 -232.507741) (xy 187.085595 -232.515657) (xy 187.060078 -232.516172)
			(xy 187.034558 -232.515665) (xy 186.984132 -232.507777) (xy 186.93552 -232.492222) (xy 186.889881 -232.469371)
			(xy 186.868816 -232.454958) (xy 186.862219 -232.450652) (xy 186.847223 -232.445859) (xy 186.839352 -232.44556)
			(xy 186.323478 -232.44556) (xy 186.318171 -232.445091) (xy 186.310601 -232.43765) (xy 186.310016 -232.432352)
			(xy 180.265832 -232.432352) (xy 180.265443 -232.437672) (xy 180.257942 -232.445214) (xy 180.252624 -232.44556)
			(xy 179.73675 -232.44556) (xy 179.728874 -232.445832) (xy 179.71387 -232.450626) (xy 179.707286 -232.454958)
			(xy 179.686204 -232.469342) (xy 179.64056 -232.492172) (xy 179.591956 -232.507732) (xy 179.54154 -232.515653)
			(xy 179.516024 -232.516172) (xy 179.490503 -232.515692) (xy 179.440076 -232.507796) (xy 179.391464 -232.492233)
			(xy 179.345826 -232.469375) (xy 179.324762 -232.454958) (xy 179.318177 -232.450631) (xy 179.303172 -232.445851)
			(xy 179.295298 -232.44556) (xy 178.779424 -232.44556) (xy 178.774083 -232.445252) (xy 178.766538 -232.437693)
			(xy 178.766216 -232.432352) (xy 172.722032 -232.432352) (xy 172.721643 -232.437672) (xy 172.714142 -232.445214)
			(xy 172.708824 -232.44556) (xy 172.708316 -232.44556) (xy 172.192696 -232.44556) (xy 172.184822 -232.445852)
			(xy 172.169818 -232.450632) (xy 172.163232 -232.454958) (xy 172.142165 -232.469365) (xy 172.096516 -232.49219)
			(xy 172.047907 -232.507743) (xy 171.997488 -232.515657) (xy 171.97197 -232.516172) (xy 171.94645 -232.515669)
			(xy 171.896024 -232.50778) (xy 171.847412 -232.492224) (xy 171.801773 -232.469372) (xy 171.780708 -232.454958)
			(xy 171.774113 -232.450649) (xy 171.759116 -232.445857) (xy 171.751244 -232.44556) (xy 171.23537 -232.44556)
			(xy 171.230062 -232.445097) (xy 171.222493 -232.437651) (xy 171.221908 -232.432352) (xy 165.177724 -232.432352)
			(xy 165.177342 -232.437674) (xy 165.169836 -232.445217) (xy 165.164516 -232.44556) (xy 163.691316 -232.44556)
			(xy 163.685974 -232.445258) (xy 163.678429 -232.437695) (xy 163.678108 -232.432352) (xy 109.720714 -232.432352)
			(xy 109.720393 -232.43362) (xy 109.700099 -232.479884) (xy 109.672466 -232.522177) (xy 109.638249 -232.559344)
			(xy 109.59838 -232.590371) (xy 109.553948 -232.614413) (xy 109.506165 -232.630814) (xy 109.456334 -232.639125)
			(xy 109.431074 -232.639616) (xy 108.49102 -232.639616) (xy 108.465762 -232.639109) (xy 108.415934 -232.630797)
			(xy 108.368154 -232.614397) (xy 108.323725 -232.590356) (xy 108.28386 -232.55933) (xy 108.249645 -232.522165)
			(xy 108.222014 -232.479875) (xy 108.201721 -232.433614) (xy 108.18932 -232.384644) (xy 108.185148 -232.3343)
			(xy 56.07812 -232.3343) (xy 56.07812 -232.432352) (xy 56.077742 -232.437675) (xy 56.070233 -232.445218)
			(xy 56.064912 -232.44556) (xy 54.591458 -232.44556) (xy 54.586149 -232.445105) (xy 54.57858 -232.437653)
			(xy 54.577996 -232.432352) (xy 48.533812 -232.432352) (xy 48.533441 -232.437677) (xy 48.525927 -232.44522)
			(xy 48.520604 -232.44556) (xy 48.00473 -232.44556) (xy 47.996853 -232.445823) (xy 47.981849 -232.450623)
			(xy 47.975266 -232.454958) (xy 47.954189 -232.46935) (xy 47.908544 -232.492178) (xy 47.859938 -232.507736)
			(xy 47.809521 -232.515655) (xy 47.784004 -232.516172) (xy 47.758483 -232.515703) (xy 47.708055 -232.507803)
			(xy 47.659443 -232.492237) (xy 47.613806 -232.469376) (xy 47.592742 -232.454958) (xy 47.586162 -232.450623)
			(xy 47.571153 -232.445848) (xy 47.563278 -232.44556) (xy 47.047404 -232.44556) (xy 47.042061 -232.445266)
			(xy 47.034517 -232.437696) (xy 47.034196 -232.432352) (xy 40.990012 -232.432352) (xy 40.989641 -232.437677)
			(xy 40.982127 -232.44522) (xy 40.976804 -232.44556) (xy 40.976296 -232.44556) (xy 40.460676 -232.44556)
			(xy 40.452801 -232.445843) (xy 40.437797 -232.45063) (xy 40.431212 -232.454958) (xy 40.41015 -232.469374)
			(xy 40.3645 -232.492196) (xy 40.315889 -232.507747) (xy 40.265468 -232.515659) (xy 40.23995 -232.516172)
			(xy 40.21443 -232.515679) (xy 40.164003 -232.507787) (xy 40.115391 -232.492228) (xy 40.069753 -232.469373)
			(xy 40.048688 -232.454958) (xy 40.042098 -232.450641) (xy 40.027097 -232.445854) (xy 40.019224 -232.44556)
			(xy 39.50335 -232.44556) (xy 39.498052 -232.445043) (xy 39.490478 -232.437638) (xy 39.489888 -232.432352)
			(xy 33.445704 -232.432352) (xy 33.44534 -232.437679) (xy 33.437822 -232.445223) (xy 33.432496 -232.44556)
			(xy 32.916622 -232.44556) (xy 32.908749 -232.445863) (xy 32.893745 -232.450636) (xy 32.887158 -232.454958)
			(xy 32.866083 -232.469354) (xy 32.820437 -232.492181) (xy 32.771831 -232.507737) (xy 32.721413 -232.515655)
			(xy 32.695896 -232.516172) (xy 32.670375 -232.515707) (xy 32.619947 -232.507805) (xy 32.571335 -232.492239)
			(xy 32.525698 -232.469377) (xy 32.504634 -232.454958) (xy 32.498033 -232.450659) (xy 32.48304 -232.445861)
			(xy 32.47517 -232.44556) (xy 31.959296 -232.44556) (xy 31.953951 -232.445271) (xy 31.946408 -232.437698)
			(xy 31.946088 -232.432352) (xy 25.901904 -232.432352) (xy 25.90154 -232.437679) (xy 25.894022 -232.445223)
			(xy 25.888696 -232.44556) (xy 25.372822 -232.44556) (xy 25.364949 -232.445863) (xy 25.349945 -232.450636)
			(xy 25.343358 -232.454958) (xy 25.322283 -232.469354) (xy 25.276637 -232.492181) (xy 25.228031 -232.507737)
			(xy 25.177613 -232.515655) (xy 25.152096 -232.516172) (xy 25.126575 -232.515707) (xy 25.076147 -232.507805)
			(xy 25.027535 -232.492239) (xy 24.981898 -232.469377) (xy 24.960834 -232.454958) (xy 24.954233 -232.450659)
			(xy 24.93924 -232.445861) (xy 24.93137 -232.44556) (xy 24.415496 -232.44556) (xy 24.410151 -232.445271)
			(xy 24.402608 -232.437698) (xy 24.402288 -232.432352) (xy 18.358104 -232.432352) (xy 18.35774 -232.437679)
			(xy 18.350222 -232.445223) (xy 18.344896 -232.44556) (xy 18.344388 -232.44556) (xy 17.828768 -232.44556)
			(xy 17.820893 -232.44584) (xy 17.805889 -232.450629) (xy 17.799304 -232.454958) (xy 17.778217 -232.469334)
			(xy 17.732575 -232.492166) (xy 17.683972 -232.507728) (xy 17.633558 -232.515652) (xy 17.608042 -232.516172)
			(xy 17.582522 -232.515683) (xy 17.532095 -232.507789) (xy 17.483483 -232.492229) (xy 17.437845 -232.469374)
			(xy 17.41678 -232.454958) (xy 17.410191 -232.450638) (xy 17.395189 -232.445853) (xy 17.387316 -232.44556)
			(xy 16.871442 -232.44556) (xy 16.866143 -232.445049) (xy 16.858569 -232.437639) (xy 16.85798 -232.432352)
			(xy 2.509012 -232.432352) (xy 2.509012 -233.28249) (xy 20.958048 -233.28249) (xy 20.958048 -232.787952)
			(xy 20.958559 -232.782694) (xy 20.965998 -232.775257) (xy 20.971256 -232.774744) (xy 20.971764 -232.774744)
			(xy 21.487638 -232.774744) (xy 21.495447 -232.774413) (xy 21.510319 -232.76964) (xy 21.516848 -232.765346)
			(xy 21.537937 -232.750997) (xy 21.583598 -232.728266) (xy 21.632204 -232.712807) (xy 21.682607 -232.704984)
			(xy 21.733613 -232.704984) (xy 21.784016 -232.712807) (xy 21.832622 -232.728266) (xy 21.878283 -232.750997)
			(xy 21.899372 -232.765346) (xy 21.905914 -232.76962) (xy 21.920776 -232.774415) (xy 21.928582 -232.774744)
			(xy 22.44471 -232.774744) (xy 22.450016 -232.775217) (xy 22.457587 -232.782655) (xy 22.458172 -232.787952)
			(xy 22.458172 -233.28249) (xy 22.458147 -233.282744) (xy 28.502356 -233.282744) (xy 28.502356 -233.282236)
			(xy 28.502356 -232.787952) (xy 28.502859 -232.782692) (xy 28.510304 -232.775255) (xy 28.515564 -232.774744)
			(xy 29.031692 -232.774744) (xy 29.039503 -232.774436) (xy 29.054374 -232.769647) (xy 29.060902 -232.765346)
			(xy 29.081991 -232.750997) (xy 29.127652 -232.728266) (xy 29.176258 -232.712807) (xy 29.226661 -232.704984)
			(xy 29.277667 -232.704984) (xy 29.32807 -232.712807) (xy 29.376676 -232.728266) (xy 29.422337 -232.750997)
			(xy 29.443426 -232.765346) (xy 29.449956 -232.769641) (xy 29.464827 -232.774423) (xy 29.472636 -232.774744)
			(xy 29.988764 -232.774744) (xy 29.994011 -232.775314) (xy 30.001453 -232.782708) (xy 30.001972 -232.787952)
			(xy 30.001972 -233.28249) (xy 30.001948 -233.282744) (xy 36.046156 -233.282744) (xy 36.046156 -233.282236)
			(xy 36.046156 -232.787952) (xy 36.046659 -232.782692) (xy 36.054104 -232.775255) (xy 36.059364 -232.774744)
			(xy 36.575492 -232.774744) (xy 36.583303 -232.774436) (xy 36.598174 -232.769647) (xy 36.604702 -232.765346)
			(xy 36.625791 -232.750997) (xy 36.671452 -232.728266) (xy 36.720058 -232.712807) (xy 36.770461 -232.704984)
			(xy 36.821467 -232.704984) (xy 36.87187 -232.712807) (xy 36.920476 -232.728266) (xy 36.966137 -232.750997)
			(xy 36.987226 -232.765346) (xy 36.993756 -232.769641) (xy 37.008627 -232.774423) (xy 37.016436 -232.774744)
			(xy 37.532564 -232.774744) (xy 37.537811 -232.775314) (xy 37.545253 -232.782708) (xy 37.545772 -232.787952)
			(xy 37.545772 -233.28249) (xy 43.589956 -233.28249) (xy 43.589956 -232.787952) (xy 43.590459 -232.782692)
			(xy 43.597904 -232.775255) (xy 43.603164 -232.774744) (xy 43.603672 -232.774744) (xy 44.119546 -232.774744)
			(xy 44.127355 -232.774417) (xy 44.142227 -232.769641) (xy 44.148756 -232.765346) (xy 44.169845 -232.750997)
			(xy 44.215506 -232.728266) (xy 44.264112 -232.712807) (xy 44.314515 -232.704984) (xy 44.365521 -232.704984)
			(xy 44.415924 -232.712807) (xy 44.46453 -232.728266) (xy 44.510191 -232.750997) (xy 44.53128 -232.765346)
			(xy 44.53782 -232.769623) (xy 44.552683 -232.774416) (xy 44.56049 -232.774744) (xy 45.076618 -232.774744)
			(xy 45.081925 -232.775212) (xy 45.089496 -232.782654) (xy 45.09008 -232.787952) (xy 45.09008 -233.28249)
			(xy 45.090055 -233.282744) (xy 51.134264 -233.282744) (xy 51.134264 -233.282236) (xy 51.134264 -232.787952)
			(xy 51.13476 -232.78269) (xy 51.14221 -232.775252) (xy 51.147472 -232.774744) (xy 51.6636 -232.774744)
			(xy 51.671411 -232.77444) (xy 51.686283 -232.769648) (xy 51.69281 -232.765346) (xy 51.713899 -232.750997)
			(xy 51.75956 -232.728266) (xy 51.808166 -232.712807) (xy 51.858569 -232.704984) (xy 51.909575 -232.704984)
			(xy 51.959978 -232.712807) (xy 52.008584 -232.728266) (xy 52.054245 -232.750997) (xy 52.075334 -232.765346)
			(xy 52.081862 -232.769644) (xy 52.096735 -232.774424) (xy 52.104544 -232.774744) (xy 52.620672 -232.774744)
			(xy 52.62592 -232.775308) (xy 52.633361 -232.782707) (xy 52.63388 -232.787952) (xy 52.63388 -233.28249)
			(xy 58.678064 -233.28249) (xy 58.678064 -232.787952) (xy 58.67856 -232.78269) (xy 58.68601 -232.775252)
			(xy 58.691272 -232.774744) (xy 58.69178 -232.774744) (xy 60.164726 -232.774744) (xy 60.170034 -232.775207)
			(xy 60.177604 -232.782653) (xy 60.178188 -232.787952) (xy 60.178188 -233.1443) (xy 97.374899 -233.1443)
			(xy 97.379075 -233.093914) (xy 97.391487 -233.044903) (xy 97.411798 -232.998603) (xy 97.439453 -232.956278)
			(xy 97.473697 -232.919082) (xy 97.513597 -232.888031) (xy 97.558064 -232.863971) (xy 97.605885 -232.847559)
			(xy 97.655755 -232.839242) (xy 97.681034 -232.838752) (xy 98.621088 -232.838752) (xy 98.646369 -232.839216)
			(xy 98.69624 -232.847536) (xy 98.744062 -232.863952) (xy 98.78853 -232.888015) (xy 98.828431 -232.91907)
			(xy 98.862675 -232.956268) (xy 98.89033 -232.998596) (xy 98.910641 -233.044898) (xy 98.923053 -233.093912)
			(xy 98.927229 -233.1443) (xy 100.194799 -233.1443) (xy 100.198975 -233.093913) (xy 100.211388 -233.044901)
			(xy 100.231699 -232.998601) (xy 100.259355 -232.956275) (xy 100.2936 -232.91908) (xy 100.333501 -232.888028)
			(xy 100.377969 -232.863969) (xy 100.425791 -232.847557) (xy 100.475662 -232.839242) (xy 100.500942 -232.838752)
			(xy 101.440996 -232.838752) (xy 101.466276 -232.839217) (xy 101.516147 -232.847538) (xy 101.563968 -232.863954)
			(xy 101.608434 -232.888018) (xy 101.648334 -232.919073) (xy 101.682577 -232.956271) (xy 101.710231 -232.998598)
			(xy 101.730541 -233.044899) (xy 101.742953 -233.093912) (xy 101.747129 -233.1443) (xy 103.014999 -233.1443)
			(xy 103.019174 -233.093917) (xy 103.031585 -233.044909) (xy 103.051893 -232.998611) (xy 103.079545 -232.956288)
			(xy 103.113785 -232.919093) (xy 103.153681 -232.888042) (xy 103.198144 -232.86398) (xy 103.24596 -232.847565)
			(xy 103.295826 -232.839245) (xy 103.321104 -232.838752) (xy 104.261158 -232.838752) (xy 104.28644 -232.839214)
			(xy 104.336316 -232.84753) (xy 104.384142 -232.863943) (xy 104.428614 -232.888005) (xy 104.468519 -232.919059)
			(xy 104.502768 -232.956258) (xy 104.530426 -232.998587) (xy 104.550739 -233.044892) (xy 104.563153 -233.093909)
			(xy 104.567329 -233.1443) (xy 105.834899 -233.1443) (xy 105.839075 -233.093916) (xy 105.851486 -233.044907)
			(xy 105.871794 -232.998609) (xy 105.899447 -232.956285) (xy 105.933688 -232.91909) (xy 105.973585 -232.888039)
			(xy 106.018049 -232.863978) (xy 106.065867 -232.847564) (xy 106.115734 -232.839244) (xy 106.141012 -232.838752)
			(xy 107.081066 -232.838752) (xy 107.106348 -232.839214) (xy 107.156222 -232.847532) (xy 107.204047 -232.863946)
			(xy 107.248518 -232.888008) (xy 107.288422 -232.919062) (xy 107.32267 -232.956261) (xy 107.350327 -232.998589)
			(xy 107.370639 -233.044893) (xy 107.383053 -233.093909) (xy 107.387229 -233.1443) (xy 107.383053 -233.194691)
			(xy 107.370639 -233.243707) (xy 107.353515 -233.282744) (xy 167.778176 -233.282744) (xy 167.778176 -232.787952)
			(xy 167.778661 -232.782687) (xy 167.786118 -232.775249) (xy 167.791384 -232.774744) (xy 169.264584 -232.774744)
			(xy 169.269833 -232.7753) (xy 169.277274 -232.782705) (xy 169.277792 -232.787952) (xy 169.277792 -233.28249)
			(xy 175.321976 -233.28249) (xy 175.321976 -232.787952) (xy 175.322461 -232.782687) (xy 175.329918 -232.775249)
			(xy 175.335184 -232.774744) (xy 175.335692 -232.774744) (xy 175.851566 -232.774744) (xy 175.859376 -232.774425)
			(xy 175.874248 -232.769644) (xy 175.880776 -232.765346) (xy 175.901865 -232.750997) (xy 175.947526 -232.728266)
			(xy 175.996132 -232.712807) (xy 176.046535 -232.704984) (xy 176.097541 -232.704984) (xy 176.147944 -232.712807)
			(xy 176.19655 -232.728266) (xy 176.242211 -232.750997) (xy 176.2633 -232.765346) (xy 176.269835 -232.769631)
			(xy 176.284702 -232.774419) (xy 176.29251 -232.774744) (xy 176.808638 -232.774744) (xy 176.813948 -232.775199)
			(xy 176.821517 -232.782651) (xy 176.8221 -232.787952) (xy 176.8221 -233.28249) (xy 176.822074 -233.282744)
			(xy 182.866284 -233.282744) (xy 182.866284 -233.282236) (xy 182.866284 -232.787952) (xy 182.866762 -232.782685)
			(xy 182.874224 -232.775246) (xy 182.879492 -232.774744) (xy 183.39562 -232.774744) (xy 183.403432 -232.774448)
			(xy 183.418304 -232.769651) (xy 183.42483 -232.765346) (xy 183.445919 -232.750997) (xy 183.49158 -232.728266)
			(xy 183.540186 -232.712807) (xy 183.590589 -232.704984) (xy 183.641595 -232.704984) (xy 183.691998 -232.712807)
			(xy 183.740604 -232.728266) (xy 183.786265 -232.750997) (xy 183.807354 -232.765346) (xy 183.813877 -232.769651)
			(xy 183.828754 -232.774427) (xy 183.836564 -232.774744) (xy 184.352692 -232.774744) (xy 184.357942 -232.775295)
			(xy 184.365383 -232.782704) (xy 184.3659 -232.787952) (xy 184.3659 -233.28249) (xy 190.410084 -233.28249)
			(xy 190.410084 -232.787952) (xy 190.410562 -232.782685) (xy 190.418024 -232.775246) (xy 190.423292 -232.774744)
			(xy 190.4238 -232.774744) (xy 190.939674 -232.774744) (xy 190.947484 -232.774429) (xy 190.962356 -232.769645)
			(xy 190.968884 -232.765346) (xy 190.989973 -232.750997) (xy 191.035634 -232.728266) (xy 191.08424 -232.712807)
			(xy 191.134643 -232.704984) (xy 191.185649 -232.704984) (xy 191.236052 -232.712807) (xy 191.284658 -232.728266)
			(xy 191.330319 -232.750997) (xy 191.351408 -232.765346) (xy 191.357942 -232.769634) (xy 191.37281 -232.77442)
			(xy 191.380618 -232.774744) (xy 191.896746 -232.774744) (xy 191.902045 -232.77526) (xy 191.909619 -232.782665)
			(xy 191.910208 -232.787952) (xy 191.910208 -233.28249) (xy 191.910181 -233.282744) (xy 197.954392 -233.282744)
			(xy 197.954392 -233.282236) (xy 197.954392 -232.787952) (xy 197.954863 -232.782683) (xy 197.96233 -232.775244)
			(xy 197.9676 -232.774744) (xy 198.483728 -232.774744) (xy 198.49154 -232.774452) (xy 198.506412 -232.769652)
			(xy 198.512938 -232.765346) (xy 198.534027 -232.750997) (xy 198.579688 -232.728266) (xy 198.628294 -232.712807)
			(xy 198.678697 -232.704984) (xy 198.729703 -232.704984) (xy 198.780106 -232.712807) (xy 198.828712 -232.728266)
			(xy 198.874373 -232.750997) (xy 198.895462 -232.765346) (xy 198.902006 -232.769616) (xy 198.916866 -232.774413)
			(xy 198.924672 -232.774744) (xy 199.4408 -232.774744) (xy 199.446051 -232.77529) (xy 199.453491 -232.782703)
			(xy 199.454008 -232.787952) (xy 199.454008 -233.28249) (xy 199.453982 -233.282744) (xy 205.498192 -233.282744)
			(xy 205.498192 -233.282236) (xy 205.498192 -232.787952) (xy 205.498663 -232.782683) (xy 205.50613 -232.775244)
			(xy 205.5114 -232.774744) (xy 206.027528 -232.774744) (xy 206.03534 -232.774452) (xy 206.050212 -232.769652)
			(xy 206.056738 -232.765346) (xy 206.077827 -232.750997) (xy 206.123488 -232.728266) (xy 206.172094 -232.712807)
			(xy 206.222497 -232.704984) (xy 206.273503 -232.704984) (xy 206.323906 -232.712807) (xy 206.372512 -232.728266)
			(xy 206.418173 -232.750997) (xy 206.439262 -232.765346) (xy 206.445806 -232.769616) (xy 206.460666 -232.774413)
			(xy 206.468472 -232.774744) (xy 206.9846 -232.774744) (xy 206.989851 -232.77529) (xy 206.997291 -232.782703)
			(xy 206.997808 -232.787952) (xy 206.997808 -233.282236) (xy 268.898116 -233.282236) (xy 268.898116 -232.787698)
			(xy 268.898647 -232.782339) (xy 268.90622 -232.774755) (xy 268.911578 -232.774236) (xy 269.427706 -232.774236)
			(xy 269.435517 -232.773935) (xy 269.450389 -232.769141) (xy 269.456916 -232.764838) (xy 269.478005 -232.750489)
			(xy 269.523666 -232.727758) (xy 269.572272 -232.712299) (xy 269.622675 -232.704476) (xy 269.673681 -232.704476)
			(xy 269.724084 -232.712299) (xy 269.77269 -232.727758) (xy 269.818351 -232.750489) (xy 269.83944 -232.764838)
			(xy 269.845967 -232.769137) (xy 269.86084 -232.773916) (xy 269.86865 -232.774236) (xy 270.384778 -232.774236)
			(xy 270.390209 -232.774594) (xy 270.397896 -232.782267) (xy 270.39824 -232.787698) (xy 270.39824 -233.282236)
			(xy 276.442424 -233.282236) (xy 276.442424 -232.787698) (xy 276.44292 -232.782397) (xy 276.450342 -232.774827)
			(xy 276.455632 -232.774236) (xy 276.97176 -232.774236) (xy 276.97957 -232.773916) (xy 276.994442 -232.769135)
			(xy 277.00097 -232.764838) (xy 277.022059 -232.750489) (xy 277.06772 -232.727758) (xy 277.116326 -232.712299)
			(xy 277.166729 -232.704476) (xy 277.217735 -232.704476) (xy 277.268138 -232.712299) (xy 277.316744 -232.727758)
			(xy 277.362405 -232.750489) (xy 277.383494 -232.764838) (xy 277.390031 -232.76912) (xy 277.404897 -232.77391)
			(xy 277.412704 -232.774236) (xy 277.928832 -232.774236) (xy 277.934179 -232.77451) (xy 277.941721 -232.782095)
			(xy 277.94204 -232.787444) (xy 277.94204 -232.787952) (xy 277.94204 -233.282236) (xy 283.986224 -233.282236)
			(xy 283.986224 -232.787698) (xy 283.98672 -232.782397) (xy 283.994142 -232.774827) (xy 283.999432 -232.774236)
			(xy 284.51556 -232.774236) (xy 284.52337 -232.773916) (xy 284.538242 -232.769135) (xy 284.54477 -232.764838)
			(xy 284.565859 -232.750489) (xy 284.61152 -232.727758) (xy 284.660126 -232.712299) (xy 284.710529 -232.704476)
			(xy 284.761535 -232.704476) (xy 284.811938 -232.712299) (xy 284.860544 -232.727758) (xy 284.906205 -232.750489)
			(xy 284.927294 -232.764838) (xy 284.933831 -232.76912) (xy 284.948697 -232.77391) (xy 284.956504 -232.774236)
			(xy 285.472632 -232.774236) (xy 285.477979 -232.77451) (xy 285.485521 -232.782095) (xy 285.48584 -232.787444)
			(xy 285.48584 -232.787952) (xy 285.48584 -233.282236) (xy 291.530024 -233.282236) (xy 291.530024 -232.787698)
			(xy 291.530548 -232.782337) (xy 291.538126 -232.774753) (xy 291.543486 -232.774236) (xy 292.059614 -232.774236)
			(xy 292.067426 -232.773939) (xy 292.082297 -232.769142) (xy 292.088824 -232.764838) (xy 292.109913 -232.750489)
			(xy 292.155574 -232.727758) (xy 292.20418 -232.712299) (xy 292.254583 -232.704476) (xy 292.305589 -232.704476)
			(xy 292.355992 -232.712299) (xy 292.404598 -232.727758) (xy 292.450259 -232.750489) (xy 292.471348 -232.764838)
			(xy 292.477873 -232.76914) (xy 292.492748 -232.773918) (xy 292.500558 -232.774236) (xy 293.016686 -232.774236)
			(xy 293.022118 -232.774588) (xy 293.029805 -232.782266) (xy 293.030148 -232.787698) (xy 293.030148 -233.282236)
			(xy 299.074332 -233.282236) (xy 299.074332 -232.787698) (xy 299.074821 -232.782396) (xy 299.082248 -232.774825)
			(xy 299.08754 -232.774236) (xy 299.603668 -232.774236) (xy 299.611478 -232.773919) (xy 299.62635 -232.769137)
			(xy 299.632878 -232.764838) (xy 299.653967 -232.750489) (xy 299.699628 -232.727758) (xy 299.748234 -232.712299)
			(xy 299.798637 -232.704476) (xy 299.849643 -232.704476) (xy 299.900046 -232.712299) (xy 299.948652 -232.727758)
			(xy 299.994313 -232.750489) (xy 300.015402 -232.764838) (xy 300.021937 -232.769123) (xy 300.036804 -232.773911)
			(xy 300.044612 -232.774236) (xy 300.56074 -232.774236) (xy 300.566089 -232.774504) (xy 300.57363 -232.782094)
			(xy 300.573948 -232.787444) (xy 300.573948 -232.787952) (xy 300.573948 -233.282236) (xy 306.618132 -233.282236)
			(xy 306.618132 -232.787698) (xy 306.618649 -232.782335) (xy 306.626232 -232.77475) (xy 306.631594 -232.774236)
			(xy 308.104794 -232.774236) (xy 308.110228 -232.774583) (xy 308.117914 -232.782265) (xy 308.118256 -232.787698)
			(xy 308.118256 -233.1441) (xy 364.1089 -233.1441) (xy 364.113072 -233.093749) (xy 364.125476 -233.044771)
			(xy 364.145771 -232.998503) (xy 364.173406 -232.956207) (xy 364.207626 -232.919036) (xy 364.247497 -232.888005)
			(xy 364.291932 -232.86396) (xy 364.339719 -232.847557) (xy 364.389554 -232.839244) (xy 364.414816 -232.838752)
			(xy 365.35487 -232.838752) (xy 365.380126 -232.839322) (xy 365.42995 -232.847632) (xy 365.477726 -232.864029)
			(xy 365.522152 -232.888067) (xy 365.562015 -232.91909) (xy 365.596227 -232.956251) (xy 365.623856 -232.998537)
			(xy 365.644148 -233.044794) (xy 365.656548 -233.093761) (xy 365.66072 -233.1441) (xy 366.9288 -233.1441)
			(xy 366.932972 -233.093748) (xy 366.945376 -233.04477) (xy 366.965673 -232.998501) (xy 366.993308 -232.956204)
			(xy 367.027529 -232.919033) (xy 367.067401 -232.888002) (xy 367.111838 -232.863958) (xy 367.159626 -232.847555)
			(xy 367.209462 -232.839243) (xy 367.234724 -232.838752) (xy 368.174778 -232.838752) (xy 368.200034 -232.839323)
			(xy 368.249856 -232.847633) (xy 368.297632 -232.864032) (xy 368.342056 -232.88807) (xy 368.381918 -232.919093)
			(xy 368.416129 -232.956254) (xy 368.443757 -232.99854) (xy 368.464048 -233.044796) (xy 368.476449 -233.093761)
			(xy 368.48062 -233.1441) (xy 369.749029 -233.1441) (xy 369.7532 -233.093757) (xy 369.765601 -233.044787)
			(xy 369.785892 -232.998525) (xy 369.813521 -232.956235) (xy 369.847734 -232.919068) (xy 369.887597 -232.88804)
			(xy 369.932024 -232.863996) (xy 369.979802 -232.847591) (xy 370.029628 -232.839275) (xy 370.054886 -232.838752)
			(xy 370.99494 -232.838752) (xy 371.02019 -232.839357) (xy 371.07 -232.847674) (xy 371.117762 -232.864077)
			(xy 371.162173 -232.888116) (xy 371.202022 -232.919137) (xy 371.236222 -232.956293) (xy 371.263841 -232.998571)
			(xy 371.284125 -233.044818) (xy 371.296521 -233.093773) (xy 371.300691 -233.1441) (xy 372.568929 -233.1441)
			(xy 372.573101 -233.093756) (xy 372.585502 -233.044785) (xy 372.605794 -232.998523) (xy 372.633423 -232.956232)
			(xy 372.667637 -232.919066) (xy 372.707501 -232.888037) (xy 372.751929 -232.863993) (xy 372.799708 -232.84759)
			(xy 372.849536 -232.839274) (xy 372.874794 -232.838752) (xy 373.814848 -232.838752) (xy 373.840097 -232.839357)
			(xy 373.889906 -232.847676) (xy 373.937667 -232.864079) (xy 373.982077 -232.888119) (xy 374.021925 -232.919139)
			(xy 374.056124 -232.956295) (xy 374.083742 -232.998573) (xy 374.104026 -233.044819) (xy 374.116421 -233.093773)
			(xy 374.120591 -233.1441) (xy 374.116421 -233.194427) (xy 374.104026 -233.243381) (xy 374.086984 -233.282236)
			(xy 415.718244 -233.282236) (xy 415.718244 -232.787698) (xy 415.718723 -232.782393) (xy 415.726157 -232.774822)
			(xy 415.731452 -232.774236) (xy 417.204652 -232.774236) (xy 417.209988 -232.774564) (xy 417.217535 -232.782108)
			(xy 417.21786 -232.787444) (xy 417.21786 -233.282236) (xy 423.262044 -233.282236) (xy 423.262044 -232.787698)
			(xy 423.262378 -232.782261) (xy 423.270069 -232.774575) (xy 423.275506 -232.774236) (xy 423.791634 -232.774236)
			(xy 423.799443 -232.773905) (xy 423.814315 -232.769132) (xy 423.820844 -232.764838) (xy 423.841933 -232.750489)
			(xy 423.887594 -232.727758) (xy 423.9362 -232.712299) (xy 423.986603 -232.704476) (xy 424.037609 -232.704476)
			(xy 424.088012 -232.712299) (xy 424.136618 -232.727758) (xy 424.182279 -232.750489) (xy 424.203368 -232.764838)
			(xy 424.209911 -232.76911) (xy 424.224772 -232.773906) (xy 424.232578 -232.774236) (xy 424.748706 -232.774236)
			(xy 424.75407 -232.774746) (xy 424.761656 -232.782334) (xy 424.762168 -232.787698) (xy 424.762168 -233.282236)
			(xy 430.806352 -233.282236) (xy 430.806352 -232.787698) (xy 430.806823 -232.782391) (xy 430.814262 -232.774819)
			(xy 430.81956 -232.774236) (xy 431.335688 -232.774236) (xy 431.343499 -232.773928) (xy 431.358371 -232.769139)
			(xy 431.364898 -232.764838) (xy 431.385987 -232.750489) (xy 431.431648 -232.727758) (xy 431.480254 -232.712299)
			(xy 431.530657 -232.704476) (xy 431.581663 -232.704476) (xy 431.632066 -232.712299) (xy 431.680672 -232.727758)
			(xy 431.726333 -232.750489) (xy 431.747422 -232.764838) (xy 431.753953 -232.76913) (xy 431.768823 -232.773914)
			(xy 431.776632 -232.774236) (xy 432.29276 -232.774236) (xy 432.298098 -232.774558) (xy 432.305643 -232.782106)
			(xy 432.305968 -232.787444) (xy 432.305968 -232.787952) (xy 432.305968 -233.282236) (xy 438.350152 -233.282236)
			(xy 438.350152 -232.787698) (xy 438.350479 -232.782259) (xy 438.358175 -232.774573) (xy 438.363614 -232.774236)
			(xy 438.879742 -232.774236) (xy 438.887551 -232.773908) (xy 438.902423 -232.769133) (xy 438.908952 -232.764838)
			(xy 438.930041 -232.750489) (xy 438.975702 -232.727758) (xy 439.024308 -232.712299) (xy 439.074711 -232.704476)
			(xy 439.125717 -232.704476) (xy 439.17612 -232.712299) (xy 439.224726 -232.727758) (xy 439.270387 -232.750489)
			(xy 439.291476 -232.764838) (xy 439.298017 -232.769113) (xy 439.31288 -232.773907) (xy 439.320686 -232.774236)
			(xy 439.836814 -232.774236) (xy 439.842179 -232.774741) (xy 439.849764 -232.782332) (xy 439.850276 -232.787698)
			(xy 439.850276 -233.282236) (xy 445.89446 -233.282236) (xy 445.89446 -232.787698) (xy 445.894924 -232.782389)
			(xy 445.902368 -232.774817) (xy 445.907668 -232.774236) (xy 446.423796 -232.774236) (xy 446.431607 -232.773931)
			(xy 446.446479 -232.76914) (xy 446.453006 -232.764838) (xy 446.474095 -232.750489) (xy 446.519756 -232.727758)
			(xy 446.568362 -232.712299) (xy 446.618765 -232.704476) (xy 446.669771 -232.704476) (xy 446.720174 -232.712299)
			(xy 446.76878 -232.727758) (xy 446.814441 -232.750489) (xy 446.83553 -232.764838) (xy 446.842059 -232.769134)
			(xy 446.856931 -232.773915) (xy 446.86474 -232.774236) (xy 447.380868 -232.774236) (xy 447.386207 -232.774553)
			(xy 447.393752 -232.782105) (xy 447.394076 -232.787444) (xy 447.394076 -232.787952) (xy 447.394076 -233.282236)
			(xy 453.43826 -233.282236) (xy 453.43826 -232.787698) (xy 453.438724 -232.782389) (xy 453.446168 -232.774817)
			(xy 453.451468 -232.774236) (xy 453.967596 -232.774236) (xy 453.975407 -232.773931) (xy 453.990279 -232.76914)
			(xy 453.996806 -232.764838) (xy 454.017895 -232.750489) (xy 454.063556 -232.727758) (xy 454.112162 -232.712299)
			(xy 454.162565 -232.704476) (xy 454.213571 -232.704476) (xy 454.263974 -232.712299) (xy 454.31258 -232.727758)
			(xy 454.358241 -232.750489) (xy 454.37933 -232.764838) (xy 454.385859 -232.769134) (xy 454.400731 -232.773915)
			(xy 454.40854 -232.774236) (xy 454.924668 -232.774236) (xy 454.930007 -232.774553) (xy 454.937552 -232.782105)
			(xy 454.937876 -232.787444) (xy 454.937876 -232.787952) (xy 454.937876 -233.282236) (xy 454.937426 -233.287511)
			(xy 454.929945 -233.294953) (xy 454.924668 -233.295444) (xy 454.408794 -233.295444) (xy 454.40092 -233.295738)
			(xy 454.385916 -233.300517) (xy 454.37933 -233.304842) (xy 454.358262 -233.319248) (xy 454.312614 -233.342073)
			(xy 454.264005 -233.357627) (xy 454.213586 -233.365541) (xy 454.188068 -233.366056) (xy 454.162548 -233.365557)
			(xy 454.112121 -233.357667) (xy 454.063509 -233.34211) (xy 454.017871 -233.319257) (xy 453.996806 -233.304842)
			(xy 453.990212 -233.300531) (xy 453.975214 -233.295741) (xy 453.967342 -233.295444) (xy 453.451468 -233.295444)
			(xy 453.44621 -233.29493) (xy 453.438771 -233.287494) (xy 453.43826 -233.282236) (xy 447.394076 -233.282236)
			(xy 447.393626 -233.287511) (xy 447.386145 -233.294953) (xy 447.380868 -233.295444) (xy 446.864994 -233.295444)
			(xy 446.85712 -233.295738) (xy 446.842116 -233.300517) (xy 446.83553 -233.304842) (xy 446.814462 -233.319248)
			(xy 446.768814 -233.342073) (xy 446.720205 -233.357627) (xy 446.669786 -233.365541) (xy 446.644268 -233.366056)
			(xy 446.618748 -233.365557) (xy 446.568321 -233.357667) (xy 446.519709 -233.34211) (xy 446.474071 -233.319257)
			(xy 446.453006 -233.304842) (xy 446.446412 -233.300531) (xy 446.431414 -233.295741) (xy 446.423542 -233.295444)
			(xy 445.907668 -233.295444) (xy 445.90241 -233.29493) (xy 445.894971 -233.287494) (xy 445.89446 -233.282236)
			(xy 439.850276 -233.282236) (xy 439.849826 -233.287511) (xy 439.842345 -233.294953) (xy 439.837068 -233.295444)
			(xy 439.83656 -233.295444) (xy 439.32094 -233.295444) (xy 439.313064 -233.295714) (xy 439.29806 -233.30051)
			(xy 439.291476 -233.304842) (xy 439.270395 -233.319228) (xy 439.224752 -233.342058) (xy 439.176147 -233.357617)
			(xy 439.12573 -233.365538) (xy 439.100214 -233.366056) (xy 439.074693 -233.365584) (xy 439.024265 -233.357686)
			(xy 438.975653 -233.342121) (xy 438.930016 -233.31926) (xy 438.908952 -233.304842) (xy 438.90237 -233.30051)
			(xy 438.887363 -233.295733) (xy 438.879488 -233.295444) (xy 438.363614 -233.295444) (xy 438.358308 -233.294966)
			(xy 438.350735 -233.287532) (xy 438.350152 -233.282236) (xy 432.305968 -233.282236) (xy 432.305693 -233.287583)
			(xy 432.298109 -233.295124) (xy 432.29276 -233.295444) (xy 431.776886 -233.295444) (xy 431.769012 -233.295734)
			(xy 431.754008 -233.300516) (xy 431.747422 -233.304842) (xy 431.726356 -233.319251) (xy 431.680707 -233.342076)
			(xy 431.632098 -233.357629) (xy 431.581678 -233.365542) (xy 431.55616 -233.366056) (xy 431.53064 -233.365561)
			(xy 431.480213 -233.35767) (xy 431.431601 -233.342111) (xy 431.385963 -233.319257) (xy 431.364898 -233.304842)
			(xy 431.358306 -233.300528) (xy 431.343306 -233.29574) (xy 431.335434 -233.295444) (xy 430.81956 -233.295444)
			(xy 430.814301 -233.294936) (xy 430.806863 -233.287495) (xy 430.806352 -233.282236) (xy 424.762168 -233.282236)
			(xy 424.761893 -233.287583) (xy 424.754309 -233.295124) (xy 424.74896 -233.295444) (xy 424.748452 -233.295444)
			(xy 424.232832 -233.295444) (xy 424.224956 -233.295711) (xy 424.209952 -233.300509) (xy 424.203368 -233.304842)
			(xy 424.182289 -233.319232) (xy 424.136645 -233.342061) (xy 424.088039 -233.357619) (xy 424.037623 -233.365539)
			(xy 424.012106 -233.366056) (xy 423.986585 -233.365588) (xy 423.936157 -233.357688) (xy 423.887545 -233.342122)
			(xy 423.841908 -233.319261) (xy 423.820844 -233.304842) (xy 423.814264 -233.300507) (xy 423.799255 -233.295732)
			(xy 423.79138 -233.295444) (xy 423.275506 -233.295444) (xy 423.270199 -233.294971) (xy 423.262626 -233.287534)
			(xy 423.262044 -233.282236) (xy 417.21786 -233.282236) (xy 417.217593 -233.287585) (xy 417.210003 -233.295127)
			(xy 417.204652 -233.295444) (xy 415.731452 -233.295444) (xy 415.726192 -233.294941) (xy 415.718755 -233.287496)
			(xy 415.718244 -233.282236) (xy 374.086984 -233.282236) (xy 374.083742 -233.289627) (xy 374.056125 -233.331905)
			(xy 374.021925 -233.369061) (xy 373.982077 -233.400081) (xy 373.937667 -233.424121) (xy 373.889907 -233.440524)
			(xy 373.840097 -233.448843) (xy 373.814848 -233.449368) (xy 372.874794 -233.449368) (xy 372.849536 -233.448926)
			(xy 372.799708 -233.44061) (xy 372.751929 -233.424207) (xy 372.707501 -233.400163) (xy 372.667637 -233.369134)
			(xy 372.633423 -233.331968) (xy 372.605794 -233.289677) (xy 372.585502 -233.243415) (xy 372.573101 -233.194444)
			(xy 372.568929 -233.1441) (xy 371.300691 -233.1441) (xy 371.296521 -233.194427) (xy 371.284125 -233.243382)
			(xy 371.263841 -233.289629) (xy 371.236222 -233.331907) (xy 371.202022 -233.369063) (xy 371.162173 -233.400084)
			(xy 371.117762 -233.424123) (xy 371.07 -233.440526) (xy 371.02019 -233.448843) (xy 370.99494 -233.449368)
			(xy 370.054886 -233.449368) (xy 370.029628 -233.448925) (xy 369.979802 -233.440609) (xy 369.932024 -233.424204)
			(xy 369.887597 -233.40016) (xy 369.847734 -233.369132) (xy 369.813521 -233.331965) (xy 369.785892 -233.289675)
			(xy 369.765601 -233.243413) (xy 369.7532 -233.194443) (xy 369.749029 -233.1441) (xy 368.48062 -233.1441)
			(xy 368.476449 -233.194439) (xy 368.464048 -233.243404) (xy 368.443757 -233.28966) (xy 368.416129 -233.331946)
			(xy 368.381918 -233.369107) (xy 368.342056 -233.40013) (xy 368.297632 -233.424168) (xy 368.249856 -233.440567)
			(xy 368.200034 -233.448877) (xy 368.174778 -233.449368) (xy 367.234724 -233.449368) (xy 367.209462 -233.448957)
			(xy 367.159626 -233.440645) (xy 367.111838 -233.424242) (xy 367.067401 -233.400198) (xy 367.027529 -233.369167)
			(xy 366.993308 -233.331996) (xy 366.965673 -233.289699) (xy 366.945376 -233.24343) (xy 366.932972 -233.194452)
			(xy 366.9288 -233.1441) (xy 365.66072 -233.1441) (xy 365.656548 -233.194439) (xy 365.644148 -233.243406)
			(xy 365.623856 -233.289663) (xy 365.596227 -233.331949) (xy 365.562015 -233.36911) (xy 365.522152 -233.400133)
			(xy 365.477726 -233.424171) (xy 365.42995 -233.440568) (xy 365.380126 -233.448878) (xy 365.35487 -233.449368)
			(xy 364.414816 -233.449368) (xy 364.389554 -233.448956) (xy 364.339719 -233.440643) (xy 364.291932 -233.42424)
			(xy 364.247497 -233.400195) (xy 364.207626 -233.369164) (xy 364.173406 -233.331993) (xy 364.145771 -233.289697)
			(xy 364.125476 -233.243429) (xy 364.113072 -233.194451) (xy 364.1089 -233.1441) (xy 308.118256 -233.1441)
			(xy 308.118256 -233.282236) (xy 308.117734 -233.287491) (xy 308.110303 -233.294929) (xy 308.105048 -233.295444)
			(xy 308.10454 -233.295444) (xy 306.631594 -233.295444) (xy 306.626285 -233.294979) (xy 306.618714 -233.287536)
			(xy 306.618132 -233.282236) (xy 300.573948 -233.282236) (xy 300.573433 -233.287493) (xy 300.565997 -233.294932)
			(xy 300.56074 -233.295444) (xy 300.044866 -233.295444) (xy 300.036991 -233.295726) (xy 300.021987 -233.300514)
			(xy 300.015402 -233.304842) (xy 299.994314 -233.319217) (xy 299.948673 -233.342049) (xy 299.90007 -233.357612)
			(xy 299.849656 -233.365536) (xy 299.82414 -233.366056) (xy 299.79862 -233.365571) (xy 299.748192 -233.357677)
			(xy 299.69958 -233.342115) (xy 299.653942 -233.319258) (xy 299.632878 -233.304842) (xy 299.626291 -233.30052)
			(xy 299.611287 -233.295737) (xy 299.603414 -233.295444) (xy 299.08754 -233.295444) (xy 299.082222 -233.29505)
			(xy 299.074681 -233.287552) (xy 299.074332 -233.282236) (xy 293.030148 -233.282236) (xy 293.029633 -233.287493)
			(xy 293.022197 -233.294932) (xy 293.01694 -233.295444) (xy 293.016432 -233.295444) (xy 292.500812 -233.295444)
			(xy 292.492939 -233.295746) (xy 292.477935 -233.30052) (xy 292.471348 -233.304842) (xy 292.450275 -233.31924)
			(xy 292.404629 -233.342067) (xy 292.356021 -233.357623) (xy 292.305603 -233.36554) (xy 292.280086 -233.366056)
			(xy 292.254566 -233.365548) (xy 292.20414 -233.357661) (xy 292.155528 -233.342106) (xy 292.109889 -233.319255)
			(xy 292.088824 -233.304842) (xy 292.082226 -233.300538) (xy 292.067231 -233.295744) (xy 292.05936 -233.295444)
			(xy 291.543486 -233.295444) (xy 291.538176 -233.294984) (xy 291.530605 -233.287537) (xy 291.530024 -233.282236)
			(xy 285.48584 -233.282236) (xy 285.485332 -233.287495) (xy 285.477891 -233.294934) (xy 285.472632 -233.295444)
			(xy 284.956758 -233.295444) (xy 284.948883 -233.295722) (xy 284.933879 -233.300512) (xy 284.927294 -233.304842)
			(xy 284.906208 -233.31922) (xy 284.860566 -233.342052) (xy 284.811963 -233.357613) (xy 284.761548 -233.365537)
			(xy 284.736032 -233.366056) (xy 284.710511 -233.365575) (xy 284.660084 -233.357679) (xy 284.611472 -233.342117)
			(xy 284.565834 -233.319259) (xy 284.54477 -233.304842) (xy 284.538184 -233.300517) (xy 284.52318 -233.295736)
			(xy 284.515306 -233.295444) (xy 283.999432 -233.295444) (xy 283.994182 -233.294888) (xy 283.986739 -233.287484)
			(xy 283.986224 -233.282236) (xy 277.94204 -233.282236) (xy 277.941532 -233.287495) (xy 277.934091 -233.294934)
			(xy 277.928832 -233.295444) (xy 277.412958 -233.295444) (xy 277.405083 -233.295722) (xy 277.390079 -233.300512)
			(xy 277.383494 -233.304842) (xy 277.362408 -233.31922) (xy 277.316766 -233.342052) (xy 277.268163 -233.357613)
			(xy 277.217748 -233.365537) (xy 277.192232 -233.366056) (xy 277.166711 -233.365575) (xy 277.116284 -233.357679)
			(xy 277.067672 -233.342117) (xy 277.022034 -233.319259) (xy 277.00097 -233.304842) (xy 276.994384 -233.300517)
			(xy 276.97938 -233.295736) (xy 276.971506 -233.295444) (xy 276.455632 -233.295444) (xy 276.450382 -233.294888)
			(xy 276.442939 -233.287484) (xy 276.442424 -233.282236) (xy 270.39824 -233.282236) (xy 270.397732 -233.287495)
			(xy 270.390291 -233.294934) (xy 270.385032 -233.295444) (xy 270.384524 -233.295444) (xy 269.868904 -233.295444)
			(xy 269.86103 -233.295742) (xy 269.846026 -233.300519) (xy 269.83944 -233.304842) (xy 269.818369 -233.319244)
			(xy 269.772722 -233.34207) (xy 269.724114 -233.357625) (xy 269.673695 -233.365541) (xy 269.648178 -233.366056)
			(xy 269.622658 -233.365552) (xy 269.572232 -233.357663) (xy 269.52362 -233.342108) (xy 269.477981 -233.319256)
			(xy 269.456916 -233.304842) (xy 269.45032 -233.300535) (xy 269.435324 -233.295742) (xy 269.427452 -233.295444)
			(xy 268.911578 -233.295444) (xy 268.906267 -233.29499) (xy 268.898697 -233.287538) (xy 268.898116 -233.282236)
			(xy 206.997808 -233.282236) (xy 206.997808 -233.28249) (xy 206.997276 -233.287782) (xy 206.989879 -233.295351)
			(xy 206.9846 -233.295952) (xy 206.468726 -233.295952) (xy 206.460916 -233.296268) (xy 206.446044 -233.301052)
			(xy 206.439516 -233.30535) (xy 206.418387 -233.319688) (xy 206.372666 -233.342418) (xy 206.323995 -233.357851)
			(xy 206.27353 -233.365621) (xy 206.248 -233.366056) (xy 206.22247 -233.365621) (xy 206.172006 -233.357845)
			(xy 206.123333 -233.342415) (xy 206.077606 -233.319698) (xy 206.056484 -233.30535) (xy 206.049952 -233.301059)
			(xy 206.035083 -233.296275) (xy 206.027274 -233.295952) (xy 205.5114 -233.295952) (xy 205.506148 -233.29541)
			(xy 205.498708 -233.287994) (xy 205.498192 -233.282744) (xy 199.453982 -233.282744) (xy 199.453476 -233.287782)
			(xy 199.446079 -233.295351) (xy 199.4408 -233.295952) (xy 198.924926 -233.295952) (xy 198.917116 -233.296268)
			(xy 198.902244 -233.301052) (xy 198.895716 -233.30535) (xy 198.874587 -233.319688) (xy 198.828866 -233.342418)
			(xy 198.780195 -233.357851) (xy 198.72973 -233.365621) (xy 198.7042 -233.366056) (xy 198.67867 -233.365621)
			(xy 198.628206 -233.357845) (xy 198.579533 -233.342415) (xy 198.533806 -233.319698) (xy 198.512684 -233.30535)
			(xy 198.506152 -233.301059) (xy 198.491283 -233.296275) (xy 198.483474 -233.295952) (xy 197.9676 -233.295952)
			(xy 197.962348 -233.29541) (xy 197.954908 -233.287994) (xy 197.954392 -233.282744) (xy 191.910181 -233.282744)
			(xy 191.909647 -233.287842) (xy 191.902095 -233.295425) (xy 191.896746 -233.295952) (xy 191.380872 -233.295952)
			(xy 191.37306 -233.296245) (xy 191.358188 -233.301044) (xy 191.351662 -233.30535) (xy 191.330548 -233.319712)
			(xy 191.284822 -233.342436) (xy 191.236146 -233.357862) (xy 191.185678 -233.365625) (xy 191.160146 -233.366056)
			(xy 191.134617 -233.365598) (xy 191.084154 -233.357829) (xy 191.035481 -233.342406) (xy 190.989753 -233.319695)
			(xy 190.96863 -233.30535) (xy 190.962088 -233.301076) (xy 190.947226 -233.296282) (xy 190.93942 -233.295952)
			(xy 190.423546 -233.295952) (xy 190.418115 -233.295589) (xy 190.410425 -233.28792) (xy 190.410084 -233.28249)
			(xy 184.3659 -233.28249) (xy 184.365375 -233.287784) (xy 184.357974 -233.295353) (xy 184.352692 -233.295952)
			(xy 183.836818 -233.295952) (xy 183.829008 -233.296265) (xy 183.814136 -233.301051) (xy 183.807608 -233.30535)
			(xy 183.786482 -233.319692) (xy 183.740759 -233.34242) (xy 183.692088 -233.357852) (xy 183.641623 -233.365621)
			(xy 183.616092 -233.366056) (xy 183.590562 -233.365625) (xy 183.540097 -233.357848) (xy 183.491425 -233.342417)
			(xy 183.445698 -233.319698) (xy 183.424576 -233.30535) (xy 183.418046 -233.301056) (xy 183.403175 -233.296274)
			(xy 183.395366 -233.295952) (xy 182.879492 -233.295952) (xy 182.874239 -233.295415) (xy 182.866799 -233.287996)
			(xy 182.866284 -233.282744) (xy 176.822074 -233.282744) (xy 176.821547 -233.287844) (xy 176.81399 -233.295428)
			(xy 176.808638 -233.295952) (xy 176.292764 -233.295952) (xy 176.284955 -233.296284) (xy 176.270084 -233.301057)
			(xy 176.263554 -233.30535) (xy 176.242443 -233.319715) (xy 176.196715 -233.342438) (xy 176.148039 -233.357864)
			(xy 176.09757 -233.365626) (xy 176.072038 -233.366056) (xy 176.046508 -233.365602) (xy 175.996045 -233.357832)
			(xy 175.947373 -233.342408) (xy 175.901644 -233.319695) (xy 175.880522 -233.30535) (xy 175.873982 -233.301073)
			(xy 175.859119 -233.29628) (xy 175.851312 -233.295952) (xy 175.335438 -233.295952) (xy 175.330006 -233.295594)
			(xy 175.322317 -233.287921) (xy 175.321976 -233.28249) (xy 169.277792 -233.28249) (xy 169.277274 -233.287786)
			(xy 169.269868 -233.295356) (xy 169.264584 -233.295952) (xy 167.791384 -233.295952) (xy 167.78613 -233.295421)
			(xy 167.778691 -233.287997) (xy 167.778176 -233.282744) (xy 107.353515 -233.282744) (xy 107.350327 -233.290011)
			(xy 107.32267 -233.332339) (xy 107.288422 -233.369538) (xy 107.248518 -233.400592) (xy 107.204047 -233.424654)
			(xy 107.156222 -233.441068) (xy 107.106348 -233.449386) (xy 107.081066 -233.449876) (xy 106.141012 -233.449876)
			(xy 106.115734 -233.449356) (xy 106.065867 -233.441036) (xy 106.018049 -233.424622) (xy 105.973585 -233.400561)
			(xy 105.933688 -233.36951) (xy 105.899447 -233.332315) (xy 105.871794 -233.289991) (xy 105.851486 -233.243693)
			(xy 105.839075 -233.194684) (xy 105.834899 -233.1443) (xy 104.567329 -233.1443) (xy 104.563153 -233.194691)
			(xy 104.550739 -233.243708) (xy 104.530426 -233.290013) (xy 104.502768 -233.332342) (xy 104.468519 -233.369541)
			(xy 104.428614 -233.400595) (xy 104.384142 -233.424657) (xy 104.336316 -233.44107) (xy 104.28644 -233.449386)
			(xy 104.261158 -233.449876) (xy 103.321104 -233.449876) (xy 103.295826 -233.449355) (xy 103.24596 -233.441035)
			(xy 103.198144 -233.42462) (xy 103.153681 -233.400558) (xy 103.113785 -233.369507) (xy 103.079545 -233.332312)
			(xy 103.051893 -233.289989) (xy 103.031585 -233.243691) (xy 103.019174 -233.194683) (xy 103.014999 -233.1443)
			(xy 101.747129 -233.1443) (xy 101.742953 -233.194688) (xy 101.730541 -233.243701) (xy 101.710231 -233.290002)
			(xy 101.682577 -233.332329) (xy 101.648334 -233.369527) (xy 101.608434 -233.400582) (xy 101.563968 -233.424646)
			(xy 101.516147 -233.441062) (xy 101.466276 -233.449383) (xy 101.440996 -233.449876) (xy 100.500942 -233.449876)
			(xy 100.475662 -233.449358) (xy 100.425791 -233.441043) (xy 100.377969 -233.424631) (xy 100.333501 -233.400572)
			(xy 100.2936 -233.36952) (xy 100.259355 -233.332325) (xy 100.231699 -233.289999) (xy 100.211388 -233.243699)
			(xy 100.198975 -233.194687) (xy 100.194799 -233.1443) (xy 98.927229 -233.1443) (xy 98.923053 -233.194688)
			(xy 98.910641 -233.243702) (xy 98.89033 -233.290004) (xy 98.862675 -233.332332) (xy 98.828431 -233.36953)
			(xy 98.78853 -233.400585) (xy 98.744062 -233.424648) (xy 98.69624 -233.441064) (xy 98.646369 -233.449384)
			(xy 98.621088 -233.449876) (xy 97.681034 -233.449876) (xy 97.655755 -233.449358) (xy 97.605885 -233.441041)
			(xy 97.558064 -233.424629) (xy 97.513597 -233.400569) (xy 97.473697 -233.369518) (xy 97.439453 -233.332322)
			(xy 97.411798 -233.289997) (xy 97.391487 -233.243697) (xy 97.379075 -233.194686) (xy 97.374899 -233.1443)
			(xy 60.178188 -233.1443) (xy 60.178188 -233.28249) (xy 60.177645 -233.287846) (xy 60.170081 -233.295431)
			(xy 60.164726 -233.295952) (xy 58.691526 -233.295952) (xy 58.686092 -233.295602) (xy 58.678404 -233.287923)
			(xy 58.678064 -233.28249) (xy 52.63388 -233.28249) (xy 52.633373 -233.287788) (xy 52.625959 -233.295359)
			(xy 52.620672 -233.295952) (xy 52.104798 -233.295952) (xy 52.096987 -233.296256) (xy 52.082115 -233.301048)
			(xy 52.075588 -233.30535) (xy 52.054467 -233.3197) (xy 52.008743 -233.342427) (xy 51.96007 -233.357857)
			(xy 51.909603 -233.365623) (xy 51.884072 -233.366056) (xy 51.858541 -233.365635) (xy 51.808077 -233.357855)
			(xy 51.759404 -233.342421) (xy 51.713677 -233.3197) (xy 51.692556 -233.30535) (xy 51.686031 -233.301048)
			(xy 51.671156 -233.296271) (xy 51.663346 -233.295952) (xy 51.147472 -233.295952) (xy 51.142216 -233.295429)
			(xy 51.134778 -233.287999) (xy 51.134264 -233.282744) (xy 45.090055 -233.282744) (xy 45.089545 -233.287848)
			(xy 45.081975 -233.295433) (xy 45.076618 -233.295952) (xy 44.560744 -233.295952) (xy 44.552935 -233.296276)
			(xy 44.538063 -233.301054) (xy 44.531534 -233.30535) (xy 44.510428 -233.319724) (xy 44.464699 -233.342445)
			(xy 44.416021 -233.357868) (xy 44.36555 -233.365627) (xy 44.340018 -233.366056) (xy 44.314488 -233.365612)
			(xy 44.264024 -233.357839) (xy 44.215352 -233.342412) (xy 44.169624 -233.319697) (xy 44.148502 -233.30535)
			(xy 44.141966 -233.301066) (xy 44.1271 -233.296278) (xy 44.119292 -233.295952) (xy 43.603418 -233.295952)
			(xy 43.597983 -233.295608) (xy 43.590295 -233.287925) (xy 43.589956 -233.28249) (xy 37.545772 -233.28249)
			(xy 37.545272 -233.28779) (xy 37.537853 -233.295361) (xy 37.532564 -233.295952) (xy 37.01669 -233.295952)
			(xy 37.008879 -233.296252) (xy 36.994007 -233.301046) (xy 36.98748 -233.30535) (xy 36.966361 -233.319704)
			(xy 36.920636 -233.34243) (xy 36.871962 -233.357858) (xy 36.821495 -233.365624) (xy 36.795964 -233.366056)
			(xy 36.770433 -233.365639) (xy 36.719968 -233.357857) (xy 36.671296 -233.342423) (xy 36.625569 -233.3197)
			(xy 36.604448 -233.30535) (xy 36.597924 -233.301045) (xy 36.583048 -233.29627) (xy 36.575238 -233.295952)
			(xy 36.059364 -233.295952) (xy 36.054108 -233.295434) (xy 36.04667 -233.288) (xy 36.046156 -233.282744)
			(xy 30.001948 -233.282744) (xy 30.001472 -233.28779) (xy 29.994053 -233.295361) (xy 29.988764 -233.295952)
			(xy 29.47289 -233.295952) (xy 29.465079 -233.296252) (xy 29.450207 -233.301046) (xy 29.44368 -233.30535)
			(xy 29.422561 -233.319704) (xy 29.376836 -233.34243) (xy 29.328162 -233.357858) (xy 29.277695 -233.365624)
			(xy 29.252164 -233.366056) (xy 29.226633 -233.365639) (xy 29.176168 -233.357857) (xy 29.127496 -233.342423)
			(xy 29.081769 -233.3197) (xy 29.060648 -233.30535) (xy 29.054124 -233.301045) (xy 29.039248 -233.29627)
			(xy 29.031438 -233.295952) (xy 28.515564 -233.295952) (xy 28.510308 -233.295434) (xy 28.50287 -233.288)
			(xy 28.502356 -233.282744) (xy 22.458147 -233.282744) (xy 22.457644 -233.28785) (xy 22.450069 -233.295436)
			(xy 22.44471 -233.295952) (xy 21.928836 -233.295952) (xy 21.921026 -233.296272) (xy 21.906155 -233.301053)
			(xy 21.899626 -233.30535) (xy 21.878495 -233.319684) (xy 21.832774 -233.342414) (xy 21.784104 -233.357849)
			(xy 21.73364 -233.36562) (xy 21.70811 -233.366056) (xy 21.68258 -233.365616) (xy 21.632116 -233.357841)
			(xy 21.583444 -233.342413) (xy 21.537716 -233.319697) (xy 21.516594 -233.30535) (xy 21.51006 -233.301063)
			(xy 21.495192 -233.296276) (xy 21.487384 -233.295952) (xy 20.97151 -233.295952) (xy 20.966074 -233.295613)
			(xy 20.958387 -233.287926) (xy 20.958048 -233.28249) (xy 2.509012 -233.28249) (xy 2.509012 -234.132374)
			(xy 16.85798 -234.132374) (xy 16.85798 -233.637836) (xy 16.85835 -233.632511) (xy 16.865865 -233.624969)
			(xy 16.871188 -233.624628) (xy 16.871696 -233.624628) (xy 17.38757 -233.624628) (xy 17.39538 -233.624314)
			(xy 17.410252 -233.619529) (xy 17.41678 -233.61523) (xy 17.437869 -233.600881) (xy 17.48353 -233.57815)
			(xy 17.532136 -233.562691) (xy 17.582539 -233.554868) (xy 17.633545 -233.554868) (xy 17.683948 -233.562691)
			(xy 17.732554 -233.57815) (xy 17.778215 -233.600881) (xy 17.799304 -233.61523) (xy 17.805839 -233.619515)
			(xy 17.820706 -233.624303) (xy 17.828514 -233.624628) (xy 18.344642 -233.624628) (xy 18.349949 -233.625094)
			(xy 18.357517 -233.632538) (xy 18.358104 -233.637836) (xy 18.358104 -234.132374) (xy 18.358077 -234.132628)
			(xy 24.402288 -234.132628) (xy 24.402288 -234.13212) (xy 24.402288 -233.637836) (xy 24.402651 -233.632509)
			(xy 24.410171 -233.624967) (xy 24.415496 -233.624628) (xy 24.931624 -233.624628) (xy 24.939436 -233.624336)
			(xy 24.954308 -233.619536) (xy 24.960834 -233.61523) (xy 24.981923 -233.600881) (xy 25.027584 -233.57815)
			(xy 25.07619 -233.562691) (xy 25.126593 -233.554868) (xy 25.177599 -233.554868) (xy 25.228002 -233.562691)
			(xy 25.276608 -233.57815) (xy 25.322269 -233.600881) (xy 25.343358 -233.61523) (xy 25.349881 -233.619536)
			(xy 25.364757 -233.624311) (xy 25.372568 -233.624628) (xy 25.888696 -233.624628) (xy 25.894036 -233.624933)
			(xy 25.90158 -233.632495) (xy 25.901904 -233.637836) (xy 25.901904 -234.132374) (xy 25.901878 -234.132628)
			(xy 31.946088 -234.132628) (xy 31.946088 -234.13212) (xy 31.946088 -233.637836) (xy 31.946451 -233.632509)
			(xy 31.953971 -233.624967) (xy 31.959296 -233.624628) (xy 32.475424 -233.624628) (xy 32.483236 -233.624336)
			(xy 32.498108 -233.619536) (xy 32.504634 -233.61523) (xy 32.525723 -233.600881) (xy 32.571384 -233.57815)
			(xy 32.61999 -233.562691) (xy 32.670393 -233.554868) (xy 32.721399 -233.554868) (xy 32.771802 -233.562691)
			(xy 32.820408 -233.57815) (xy 32.866069 -233.600881) (xy 32.887158 -233.61523) (xy 32.893681 -233.619536)
			(xy 32.908557 -233.624311) (xy 32.916368 -233.624628) (xy 33.432496 -233.624628) (xy 33.437836 -233.624933)
			(xy 33.44538 -233.632495) (xy 33.445704 -233.637836) (xy 33.445704 -234.132374) (xy 39.489888 -234.132374)
			(xy 39.489888 -233.637836) (xy 39.490251 -233.632509) (xy 39.497771 -233.624967) (xy 39.503096 -233.624628)
			(xy 39.503604 -233.624628) (xy 40.019478 -233.624628) (xy 40.027289 -233.624317) (xy 40.04216 -233.61953)
			(xy 40.048688 -233.61523) (xy 40.069777 -233.600881) (xy 40.115438 -233.57815) (xy 40.164044 -233.562691)
			(xy 40.214447 -233.554868) (xy 40.265453 -233.554868) (xy 40.315856 -233.562691) (xy 40.364462 -233.57815)
			(xy 40.410123 -233.600881) (xy 40.431212 -233.61523) (xy 40.437746 -233.619518) (xy 40.452614 -233.624304)
			(xy 40.460422 -233.624628) (xy 40.97655 -233.624628) (xy 40.981845 -233.625155) (xy 40.989418 -233.632553)
			(xy 40.990012 -233.637836) (xy 40.990012 -234.132374) (xy 40.989985 -234.132628) (xy 47.034196 -234.132628)
			(xy 47.034196 -234.13212) (xy 47.034196 -233.637836) (xy 47.034551 -233.632508) (xy 47.042076 -233.624964)
			(xy 47.047404 -233.624628) (xy 47.563532 -233.624628) (xy 47.571341 -233.624298) (xy 47.586213 -233.619524)
			(xy 47.592742 -233.61523) (xy 47.613831 -233.600881) (xy 47.659492 -233.57815) (xy 47.708098 -233.562691)
			(xy 47.758501 -233.554868) (xy 47.809507 -233.554868) (xy 47.85991 -233.562691) (xy 47.908516 -233.57815)
			(xy 47.954177 -233.600881) (xy 47.975266 -233.61523) (xy 47.98181 -233.6195) (xy 47.99667 -233.624298)
			(xy 48.004476 -233.624628) (xy 48.520604 -233.624628) (xy 48.525946 -233.624928) (xy 48.533488 -233.632493)
			(xy 48.533812 -233.637836) (xy 48.533812 -234.132374) (xy 54.577996 -234.132374) (xy 54.577996 -233.637836)
			(xy 54.578351 -233.632508) (xy 54.585876 -233.624964) (xy 54.591204 -233.624628) (xy 56.064658 -233.624628)
			(xy 56.069954 -233.62515) (xy 56.077527 -233.632552) (xy 56.07812 -233.637836) (xy 56.07812 -233.9543)
			(xy 108.18516 -233.9543) (xy 108.189332 -233.903958) (xy 108.201733 -233.85499) (xy 108.222025 -233.808731)
			(xy 108.249654 -233.766443) (xy 108.283868 -233.729279) (xy 108.323732 -233.698254) (xy 108.368159 -233.674214)
			(xy 108.415937 -233.657814) (xy 108.465763 -233.649503) (xy 108.49102 -233.649012) (xy 109.431074 -233.649012)
			(xy 109.456335 -233.649463) (xy 109.506168 -233.657774) (xy 109.553953 -233.674176) (xy 109.598387 -233.698219)
			(xy 109.638257 -233.729247) (xy 109.672476 -233.766416) (xy 109.70011 -233.80871) (xy 109.720405 -233.854976)
			(xy 109.732808 -233.903951) (xy 109.73698 -233.9543) (xy 109.732808 -234.004649) (xy 109.720405 -234.053624)
			(xy 109.70011 -234.09989) (xy 109.67872 -234.132628) (xy 163.678108 -234.132628) (xy 163.678108 -234.13212)
			(xy 163.678108 -233.637836) (xy 163.678453 -233.632505) (xy 163.685985 -233.624961) (xy 163.691316 -233.624628)
			(xy 165.164516 -233.624628) (xy 165.169859 -233.624919) (xy 165.177402 -233.632491) (xy 165.177724 -233.637836)
			(xy 165.177724 -234.132374) (xy 171.221908 -234.132374) (xy 171.221908 -233.637836) (xy 171.222253 -233.632505)
			(xy 171.229785 -233.624961) (xy 171.235116 -233.624628) (xy 171.235624 -233.624628) (xy 171.751498 -233.624628)
			(xy 171.759309 -233.624325) (xy 171.774181 -233.619533) (xy 171.780708 -233.61523) (xy 171.801797 -233.600881)
			(xy 171.847458 -233.57815) (xy 171.896064 -233.562691) (xy 171.946467 -233.554868) (xy 171.997473 -233.554868)
			(xy 172.047876 -233.562691) (xy 172.096482 -233.57815) (xy 172.142143 -233.600881) (xy 172.163232 -233.61523)
			(xy 172.169761 -233.619526) (xy 172.184633 -233.624307) (xy 172.192442 -233.624628) (xy 172.70857 -233.624628)
			(xy 172.713868 -233.625142) (xy 172.72144 -233.63255) (xy 172.722032 -233.637836) (xy 172.722032 -234.132374)
			(xy 172.722016 -234.132628) (xy 178.766216 -234.132628) (xy 178.766216 -234.13212) (xy 178.766216 -233.637836)
			(xy 178.766553 -233.632503) (xy 178.774091 -233.624958) (xy 178.779424 -233.624628) (xy 179.295552 -233.624628)
			(xy 179.303362 -233.624306) (xy 179.318233 -233.619527) (xy 179.324762 -233.61523) (xy 179.345851 -233.600881)
			(xy 179.391512 -233.57815) (xy 179.440118 -233.562691) (xy 179.490521 -233.554868) (xy 179.541527 -233.554868)
			(xy 179.59193 -233.562691) (xy 179.640536 -233.57815) (xy 179.686197 -233.600881) (xy 179.707286 -233.61523)
			(xy 179.713825 -233.619508) (xy 179.728689 -233.6243) (xy 179.736496 -233.624628) (xy 180.252624 -233.624628)
			(xy 180.257968 -233.624914) (xy 180.26551 -233.63249) (xy 180.265832 -233.637836) (xy 180.265832 -234.132374)
			(xy 186.310016 -234.132374) (xy 186.310016 -233.637836) (xy 186.310353 -233.632503) (xy 186.317891 -233.624958)
			(xy 186.323224 -233.624628) (xy 186.323732 -233.624628) (xy 186.839606 -233.624628) (xy 186.847418 -233.624329)
			(xy 186.862289 -233.619534) (xy 186.868816 -233.61523) (xy 186.889905 -233.600881) (xy 186.935566 -233.57815)
			(xy 186.984172 -233.562691) (xy 187.034575 -233.554868) (xy 187.085581 -233.554868) (xy 187.135984 -233.562691)
			(xy 187.18459 -233.57815) (xy 187.230251 -233.600881) (xy 187.25134 -233.61523) (xy 187.257867 -233.619529)
			(xy 187.27274 -233.624308) (xy 187.28055 -233.624628) (xy 187.796678 -233.624628) (xy 187.801977 -233.625136)
			(xy 187.809549 -233.632549) (xy 187.81014 -233.637836) (xy 187.81014 -234.132374) (xy 187.810124 -234.132628)
			(xy 193.854324 -234.132628) (xy 193.854324 -234.13212) (xy 193.854324 -233.637836) (xy 193.854654 -233.632501)
			(xy 193.862197 -233.624956) (xy 193.867532 -233.624628) (xy 194.38366 -233.624628) (xy 194.39147 -233.624309)
			(xy 194.406342 -233.619528) (xy 194.41287 -233.61523) (xy 194.433959 -233.600881) (xy 194.47962 -233.57815)
			(xy 194.528226 -233.562691) (xy 194.578629 -233.554868) (xy 194.629635 -233.554868) (xy 194.680038 -233.562691)
			(xy 194.728644 -233.57815) (xy 194.774305 -233.600881) (xy 194.795394 -233.61523) (xy 194.801932 -233.619511)
			(xy 194.816797 -233.624302) (xy 194.824604 -233.624628) (xy 195.340732 -233.624628) (xy 195.346077 -233.624909)
			(xy 195.353618 -233.632489) (xy 195.35394 -233.637836) (xy 195.35394 -234.132374) (xy 195.353917 -234.132628)
			(xy 201.398124 -234.132628) (xy 201.398124 -234.13212) (xy 201.398124 -233.637836) (xy 201.398454 -233.632501)
			(xy 201.405997 -233.624956) (xy 201.411332 -233.624628) (xy 201.92746 -233.624628) (xy 201.93527 -233.624309)
			(xy 201.950142 -233.619528) (xy 201.95667 -233.61523) (xy 201.977759 -233.600881) (xy 202.02342 -233.57815)
			(xy 202.072026 -233.562691) (xy 202.122429 -233.554868) (xy 202.173435 -233.554868) (xy 202.223838 -233.562691)
			(xy 202.272444 -233.57815) (xy 202.318105 -233.600881) (xy 202.339194 -233.61523) (xy 202.345732 -233.619511)
			(xy 202.360597 -233.624302) (xy 202.368404 -233.624628) (xy 202.884532 -233.624628) (xy 202.889877 -233.624909)
			(xy 202.897418 -233.632489) (xy 202.89774 -233.637836) (xy 202.89774 -234.13212) (xy 264.798048 -234.13212)
			(xy 264.798048 -233.637582) (xy 264.798539 -233.632213) (xy 264.80614 -233.624628) (xy 264.81151 -233.62412)
			(xy 265.327638 -233.62412) (xy 265.335447 -233.623793) (xy 265.350319 -233.619018) (xy 265.356848 -233.614722)
			(xy 265.377937 -233.600373) (xy 265.423598 -233.577642) (xy 265.472204 -233.562183) (xy 265.522607 -233.55436)
			(xy 265.573613 -233.55436) (xy 265.624016 -233.562183) (xy 265.672622 -233.577642) (xy 265.718283 -233.600373)
			(xy 265.739372 -233.614722) (xy 265.745915 -233.618994) (xy 265.760776 -233.62379) (xy 265.768582 -233.62412)
			(xy 266.28471 -233.62412) (xy 266.290071 -233.624642) (xy 266.297655 -233.632222) (xy 266.298172 -233.637582)
			(xy 266.298172 -234.13212) (xy 272.342356 -234.13212) (xy 272.342356 -233.637582) (xy 272.342813 -233.632272)
			(xy 272.350263 -233.624701) (xy 272.355564 -233.62412) (xy 272.871692 -233.62412) (xy 272.879503 -233.623816)
			(xy 272.894375 -233.619025) (xy 272.900902 -233.614722) (xy 272.921991 -233.600373) (xy 272.967652 -233.577642)
			(xy 273.016258 -233.562183) (xy 273.066661 -233.55436) (xy 273.117667 -233.55436) (xy 273.16807 -233.562183)
			(xy 273.216676 -233.577642) (xy 273.262337 -233.600373) (xy 273.283426 -233.614722) (xy 273.289957 -233.619015)
			(xy 273.304827 -233.623798) (xy 273.312636 -233.62412) (xy 273.828764 -233.62412) (xy 273.834098 -233.624454)
			(xy 273.841643 -233.631994) (xy 273.841972 -233.637328) (xy 273.841972 -233.637836) (xy 273.841972 -234.13212)
			(xy 279.886156 -234.13212) (xy 279.886156 -233.637582) (xy 279.886613 -233.632272) (xy 279.894063 -233.624701)
			(xy 279.899364 -233.62412) (xy 280.415492 -233.62412) (xy 280.423303 -233.623816) (xy 280.438175 -233.619025)
			(xy 280.444702 -233.614722) (xy 280.465791 -233.600373) (xy 280.511452 -233.577642) (xy 280.560058 -233.562183)
			(xy 280.610461 -233.55436) (xy 280.661467 -233.55436) (xy 280.71187 -233.562183) (xy 280.760476 -233.577642)
			(xy 280.806137 -233.600373) (xy 280.827226 -233.614722) (xy 280.833757 -233.619015) (xy 280.848627 -233.623798)
			(xy 280.856436 -233.62412) (xy 281.372564 -233.62412) (xy 281.377898 -233.624454) (xy 281.385443 -233.631994)
			(xy 281.385772 -233.637328) (xy 281.385772 -233.637836) (xy 281.385772 -234.13212) (xy 287.429956 -234.13212)
			(xy 287.429956 -233.637582) (xy 287.43044 -233.632211) (xy 287.438046 -233.624626) (xy 287.443418 -233.62412)
			(xy 287.959546 -233.62412) (xy 287.967355 -233.623797) (xy 287.982228 -233.619019) (xy 287.988756 -233.614722)
			(xy 288.009845 -233.600373) (xy 288.055506 -233.577642) (xy 288.104112 -233.562183) (xy 288.154515 -233.55436)
			(xy 288.205521 -233.55436) (xy 288.255924 -233.562183) (xy 288.30453 -233.577642) (xy 288.350191 -233.600373)
			(xy 288.37128 -233.614722) (xy 288.377821 -233.618997) (xy 288.392684 -233.623792) (xy 288.40049 -233.62412)
			(xy 288.916618 -233.62412) (xy 288.92198 -233.624636) (xy 288.929564 -233.63222) (xy 288.93008 -233.637582)
			(xy 288.93008 -234.13212) (xy 294.974264 -234.13212) (xy 294.974264 -233.637582) (xy 294.974714 -233.63227)
			(xy 294.982168 -233.624698) (xy 294.987472 -233.62412) (xy 295.5036 -233.62412) (xy 295.511412 -233.62382)
			(xy 295.526283 -233.619026) (xy 295.53281 -233.614722) (xy 295.553899 -233.600373) (xy 295.59956 -233.577642)
			(xy 295.648166 -233.562183) (xy 295.698569 -233.55436) (xy 295.749575 -233.55436) (xy 295.799978 -233.562183)
			(xy 295.848584 -233.577642) (xy 295.894245 -233.600373) (xy 295.915334 -233.614722) (xy 295.921863 -233.619018)
			(xy 295.936735 -233.623799) (xy 295.944544 -233.62412) (xy 296.460672 -233.62412) (xy 296.466007 -233.624448)
			(xy 296.473552 -233.631993) (xy 296.47388 -233.637328) (xy 296.47388 -233.637836) (xy 296.47388 -234.13212)
			(xy 302.518064 -234.13212) (xy 302.518064 -233.637582) (xy 302.51837 -233.632138) (xy 302.526081 -233.624452)
			(xy 302.531526 -233.62412) (xy 304.004726 -233.62412) (xy 304.010089 -233.624631) (xy 304.017672 -233.632219)
			(xy 304.018188 -233.637582) (xy 304.018188 -233.9541) (xy 361.758651 -233.9541) (xy 361.762827 -233.903709)
			(xy 361.77524 -233.854692) (xy 361.795552 -233.808387) (xy 361.823208 -233.766057) (xy 361.857454 -233.728856)
			(xy 361.897357 -233.6978) (xy 361.941827 -233.673735) (xy 361.989652 -233.657318) (xy 362.039526 -233.648997)
			(xy 362.064808 -233.648504) (xy 363.004862 -233.648504) (xy 363.03014 -233.649062) (xy 363.080007 -233.657378)
			(xy 363.127825 -233.673788) (xy 363.17229 -233.697847) (xy 363.212188 -233.728896) (xy 363.246431 -233.766089)
			(xy 363.274084 -233.808411) (xy 363.294394 -233.854708) (xy 363.306805 -233.903717) (xy 363.310981 -233.9541)
			(xy 363.306805 -234.004483) (xy 363.294394 -234.053492) (xy 363.274084 -234.099789) (xy 363.252959 -234.13212)
			(xy 411.618176 -234.13212) (xy 411.618176 -233.637582) (xy 411.618615 -233.632267) (xy 411.626077 -233.624695)
			(xy 411.631384 -233.62412) (xy 413.104584 -233.62412) (xy 413.109921 -233.62444) (xy 413.117465 -233.631991)
			(xy 413.117792 -233.637328) (xy 413.117792 -233.637836) (xy 413.117792 -234.13212) (xy 419.161976 -234.13212)
			(xy 419.161976 -233.637582) (xy 419.162271 -233.632135) (xy 419.16999 -233.624448) (xy 419.175438 -233.62412)
			(xy 419.691566 -233.62412) (xy 419.699376 -233.623805) (xy 419.714248 -233.619021) (xy 419.720776 -233.614722)
			(xy 419.741865 -233.600373) (xy 419.787526 -233.577642) (xy 419.836132 -233.562183) (xy 419.886535 -233.55436)
			(xy 419.937541 -233.55436) (xy 419.987944 -233.562183) (xy 420.03655 -233.577642) (xy 420.082211 -233.600373)
			(xy 420.1033 -233.614722) (xy 420.109837 -233.619005) (xy 420.124703 -233.623794) (xy 420.13251 -233.62412)
			(xy 420.648638 -233.62412) (xy 420.654002 -233.624624) (xy 420.661584 -233.632217) (xy 420.6621 -233.637582)
			(xy 420.6621 -234.13212) (xy 426.706284 -234.13212) (xy 426.706284 -233.637582) (xy 426.706716 -233.632265)
			(xy 426.714183 -233.624693) (xy 426.719492 -233.62412) (xy 427.23562 -233.62412) (xy 427.243432 -233.623828)
			(xy 427.258304 -233.619028) (xy 427.26483 -233.614722) (xy 427.285919 -233.600373) (xy 427.33158 -233.577642)
			(xy 427.380186 -233.562183) (xy 427.430589 -233.55436) (xy 427.481595 -233.55436) (xy 427.531998 -233.562183)
			(xy 427.580604 -233.577642) (xy 427.626265 -233.600373) (xy 427.647354 -233.614722) (xy 427.653879 -233.619025)
			(xy 427.668754 -233.623802) (xy 427.676564 -233.62412) (xy 428.192692 -233.62412) (xy 428.19803 -233.624435)
			(xy 428.205573 -233.631989) (xy 428.2059 -233.637328) (xy 428.2059 -233.637836) (xy 428.2059 -234.13212)
			(xy 434.250084 -234.13212) (xy 434.250084 -233.637582) (xy 434.250372 -233.632133) (xy 434.258096 -233.624446)
			(xy 434.263546 -233.62412) (xy 434.779674 -233.62412) (xy 434.787485 -233.623809) (xy 434.802356 -233.619022)
			(xy 434.808884 -233.614722) (xy 434.829973 -233.600373) (xy 434.875634 -233.577642) (xy 434.92424 -233.562183)
			(xy 434.974643 -233.55436) (xy 435.025649 -233.55436) (xy 435.076052 -233.562183) (xy 435.124658 -233.577642)
			(xy 435.170319 -233.600373) (xy 435.191408 -233.614722) (xy 435.197943 -233.619008) (xy 435.21281 -233.623796)
			(xy 435.220618 -233.62412) (xy 435.736746 -233.62412) (xy 435.742111 -233.624618) (xy 435.749693 -233.632216)
			(xy 435.750208 -233.637582) (xy 435.750208 -234.13212) (xy 441.794392 -234.13212) (xy 441.794392 -233.637582)
			(xy 441.794905 -233.632287) (xy 441.802316 -233.624719) (xy 441.8076 -233.62412) (xy 442.323728 -233.62412)
			(xy 442.331541 -233.623831) (xy 442.346412 -233.61903) (xy 442.352938 -233.614722) (xy 442.374027 -233.600373)
			(xy 442.419688 -233.577642) (xy 442.468294 -233.562183) (xy 442.518697 -233.55436) (xy 442.569703 -233.55436)
			(xy 442.620106 -233.562183) (xy 442.668712 -233.577642) (xy 442.714373 -233.600373) (xy 442.735462 -233.614722)
			(xy 442.742007 -233.61899) (xy 442.756867 -233.623789) (xy 442.764672 -233.62412) (xy 443.2808 -233.62412)
			(xy 443.286139 -233.624429) (xy 443.293682 -233.631988) (xy 443.294008 -233.637328) (xy 443.294008 -233.637836)
			(xy 443.294008 -234.13212) (xy 449.338192 -234.13212) (xy 449.338192 -233.637582) (xy 449.338705 -233.632287)
			(xy 449.346116 -233.624719) (xy 449.3514 -233.62412) (xy 449.867528 -233.62412) (xy 449.875341 -233.623831)
			(xy 449.890212 -233.61903) (xy 449.896738 -233.614722) (xy 449.917827 -233.600373) (xy 449.963488 -233.577642)
			(xy 450.012094 -233.562183) (xy 450.062497 -233.55436) (xy 450.113503 -233.55436) (xy 450.163906 -233.562183)
			(xy 450.212512 -233.577642) (xy 450.258173 -233.600373) (xy 450.279262 -233.614722) (xy 450.285807 -233.61899)
			(xy 450.300667 -233.623789) (xy 450.308472 -233.62412) (xy 450.8246 -233.62412) (xy 450.829939 -233.624429)
			(xy 450.837482 -233.631988) (xy 450.837808 -233.637328) (xy 450.837808 -233.637836) (xy 450.837808 -234.13212)
			(xy 450.837319 -234.137385) (xy 450.829866 -234.144827) (xy 450.8246 -234.145328) (xy 450.308726 -234.145328)
			(xy 450.30085 -234.145595) (xy 450.285846 -234.150393) (xy 450.279262 -234.154726) (xy 450.258184 -234.169116)
			(xy 450.212539 -234.191946) (xy 450.163934 -234.207504) (xy 450.113517 -234.215423) (xy 450.088 -234.21594)
			(xy 450.062479 -234.21546) (xy 450.012052 -234.207561) (xy 449.963441 -234.191998) (xy 449.917803 -234.169142)
			(xy 449.896738 -234.154726) (xy 449.890138 -234.150426) (xy 449.875145 -234.145629) (xy 449.867274 -234.145328)
			(xy 449.3514 -234.145328) (xy 449.346142 -234.144807) (xy 449.338701 -234.137377) (xy 449.338192 -234.13212)
			(xy 443.294008 -234.13212) (xy 443.293519 -234.137385) (xy 443.286066 -234.144827) (xy 443.2808 -234.145328)
			(xy 442.764926 -234.145328) (xy 442.75705 -234.145595) (xy 442.742046 -234.150393) (xy 442.735462 -234.154726)
			(xy 442.714384 -234.169116) (xy 442.668739 -234.191946) (xy 442.620134 -234.207504) (xy 442.569717 -234.215423)
			(xy 442.5442 -234.21594) (xy 442.518679 -234.21546) (xy 442.468252 -234.207561) (xy 442.419641 -234.191998)
			(xy 442.374003 -234.169142) (xy 442.352938 -234.154726) (xy 442.346338 -234.150426) (xy 442.331345 -234.145629)
			(xy 442.323474 -234.145328) (xy 441.8076 -234.145328) (xy 441.802342 -234.144807) (xy 441.794901 -234.137377)
			(xy 441.794392 -234.13212) (xy 435.750208 -234.13212) (xy 435.749719 -234.137385) (xy 435.742266 -234.144827)
			(xy 435.737 -234.145328) (xy 435.736492 -234.145328) (xy 435.220872 -234.145328) (xy 435.212997 -234.145615)
			(xy 435.197994 -234.150399) (xy 435.191408 -234.154726) (xy 435.170345 -234.16914) (xy 435.124695 -234.191964)
			(xy 435.076085 -234.207515) (xy 435.025664 -234.215427) (xy 435.000146 -234.21594) (xy 434.974626 -234.215437)
			(xy 434.9242 -234.207545) (xy 434.875589 -234.191989) (xy 434.82995 -234.169139) (xy 434.808884 -234.154726)
			(xy 434.802296 -234.150405) (xy 434.787293 -234.145622) (xy 434.77942 -234.145328) (xy 434.263546 -234.145328)
			(xy 434.25824 -234.144842) (xy 434.250665 -234.137416) (xy 434.250084 -234.13212) (xy 428.2059 -234.13212)
			(xy 428.205418 -234.137387) (xy 428.19796 -234.144829) (xy 428.192692 -234.145328) (xy 427.676818 -234.145328)
			(xy 427.668945 -234.145635) (xy 427.653941 -234.150406) (xy 427.647354 -234.154726) (xy 427.626278 -234.16912)
			(xy 427.580633 -234.191948) (xy 427.532026 -234.207506) (xy 427.481609 -234.215424) (xy 427.456092 -234.21594)
			(xy 427.430573 -234.215414) (xy 427.380148 -234.207529) (xy 427.331537 -234.19198) (xy 427.285897 -234.169136)
			(xy 427.26483 -234.154726) (xy 427.258232 -234.150422) (xy 427.243237 -234.145628) (xy 427.235366 -234.145328)
			(xy 426.719492 -234.145328) (xy 426.714233 -234.144813) (xy 426.706792 -234.137378) (xy 426.706284 -234.13212)
			(xy 420.6621 -234.13212) (xy 420.661618 -234.137387) (xy 420.65416 -234.144829) (xy 420.648892 -234.145328)
			(xy 420.648384 -234.145328) (xy 420.132764 -234.145328) (xy 420.124889 -234.145611) (xy 420.109885 -234.150398)
			(xy 420.1033 -234.154726) (xy 420.082211 -234.1691) (xy 420.036571 -234.191933) (xy 419.987968 -234.207496)
			(xy 419.937554 -234.21542) (xy 419.912038 -234.21594) (xy 419.886518 -234.215441) (xy 419.836092 -234.207548)
			(xy 419.787481 -234.191991) (xy 419.741842 -234.169139) (xy 419.720776 -234.154726) (xy 419.71419 -234.150402)
			(xy 419.699186 -234.14562) (xy 419.691312 -234.145328) (xy 419.175438 -234.145328) (xy 419.170131 -234.144848)
			(xy 419.162556 -234.137417) (xy 419.161976 -234.13212) (xy 413.117792 -234.13212) (xy 413.117317 -234.137389)
			(xy 413.109854 -234.144831) (xy 413.104584 -234.145328) (xy 411.631384 -234.145328) (xy 411.626124 -234.144818)
			(xy 411.618683 -234.13738) (xy 411.618176 -234.13212) (xy 363.252959 -234.13212) (xy 363.246431 -234.142111)
			(xy 363.212188 -234.179304) (xy 363.17229 -234.210353) (xy 363.127825 -234.234412) (xy 363.080007 -234.250822)
			(xy 363.03014 -234.259138) (xy 363.004862 -234.259628) (xy 362.064808 -234.259628) (xy 362.039526 -234.259203)
			(xy 361.989652 -234.250882) (xy 361.941827 -234.234465) (xy 361.897357 -234.2104) (xy 361.857454 -234.179344)
			(xy 361.823208 -234.142143) (xy 361.795552 -234.099813) (xy 361.77524 -234.053508) (xy 361.762827 -234.004491)
			(xy 361.758651 -233.9541) (xy 304.018188 -233.9541) (xy 304.018188 -234.13212) (xy 304.017717 -234.13739)
			(xy 304.010251 -234.144833) (xy 304.00498 -234.145328) (xy 302.531526 -234.145328) (xy 302.526218 -234.144856)
			(xy 302.518643 -234.137419) (xy 302.518064 -234.13212) (xy 296.47388 -234.13212) (xy 296.473584 -234.137462)
			(xy 296.466015 -234.145003) (xy 296.460672 -234.145328) (xy 295.944798 -234.145328) (xy 295.936924 -234.145626)
			(xy 295.921921 -234.150403) (xy 295.915334 -234.154726) (xy 295.894264 -234.169128) (xy 295.848616 -234.191955)
			(xy 295.800008 -234.20751) (xy 295.749589 -234.215425) (xy 295.724072 -234.21594) (xy 295.698553 -234.215424)
			(xy 295.648127 -234.207536) (xy 295.599516 -234.191984) (xy 295.553876 -234.169137) (xy 295.53281 -234.154726)
			(xy 295.526216 -234.150415) (xy 295.511218 -234.145625) (xy 295.503346 -234.145328) (xy 294.987472 -234.145328)
			(xy 294.982211 -234.144826) (xy 294.974771 -234.137382) (xy 294.974264 -234.13212) (xy 288.93008 -234.13212)
			(xy 288.929784 -234.137462) (xy 288.922215 -234.145003) (xy 288.916872 -234.145328) (xy 288.916364 -234.145328)
			(xy 288.400744 -234.145328) (xy 288.392868 -234.145603) (xy 288.377865 -234.150396) (xy 288.37128 -234.154726)
			(xy 288.350197 -234.169109) (xy 288.304554 -234.19194) (xy 288.25595 -234.2075) (xy 288.205534 -234.215422)
			(xy 288.180018 -234.21594) (xy 288.154498 -234.215451) (xy 288.104071 -234.207555) (xy 288.05546 -234.191995)
			(xy 288.009821 -234.169141) (xy 287.988756 -234.154726) (xy 287.982174 -234.150394) (xy 287.967167 -234.145617)
			(xy 287.959292 -234.145328) (xy 287.443418 -234.145328) (xy 287.438108 -234.144861) (xy 287.430534 -234.13742)
			(xy 287.429956 -234.13212) (xy 281.385772 -234.13212) (xy 281.385483 -234.137464) (xy 281.377909 -234.145006)
			(xy 281.372564 -234.145328) (xy 280.85669 -234.145328) (xy 280.848816 -234.145623) (xy 280.833812 -234.150402)
			(xy 280.827226 -234.154726) (xy 280.806158 -234.169132) (xy 280.76051 -234.191958) (xy 280.711901 -234.207512)
			(xy 280.661482 -234.215426) (xy 280.635964 -234.21594) (xy 280.610445 -234.215428) (xy 280.560019 -234.207539)
			(xy 280.511408 -234.191985) (xy 280.465768 -234.169138) (xy 280.444702 -234.154726) (xy 280.43811 -234.150412)
			(xy 280.42311 -234.145624) (xy 280.415238 -234.145328) (xy 279.899364 -234.145328) (xy 279.894102 -234.144831)
			(xy 279.886663 -234.137383) (xy 279.886156 -234.13212) (xy 273.841972 -234.13212) (xy 273.841683 -234.137464)
			(xy 273.834109 -234.145006) (xy 273.828764 -234.145328) (xy 273.31289 -234.145328) (xy 273.305016 -234.145623)
			(xy 273.290012 -234.150402) (xy 273.283426 -234.154726) (xy 273.262358 -234.169132) (xy 273.21671 -234.191958)
			(xy 273.168101 -234.207512) (xy 273.117682 -234.215426) (xy 273.092164 -234.21594) (xy 273.066645 -234.215428)
			(xy 273.016219 -234.207539) (xy 272.967608 -234.191985) (xy 272.921968 -234.169138) (xy 272.900902 -234.154726)
			(xy 272.89431 -234.150412) (xy 272.87931 -234.145624) (xy 272.871438 -234.145328) (xy 272.355564 -234.145328)
			(xy 272.350302 -234.144831) (xy 272.342863 -234.137383) (xy 272.342356 -234.13212) (xy 266.298172 -234.13212)
			(xy 266.297883 -234.137464) (xy 266.290309 -234.145006) (xy 266.284964 -234.145328) (xy 266.284456 -234.145328)
			(xy 265.768836 -234.145328) (xy 265.76096 -234.145599) (xy 265.745956 -234.150395) (xy 265.739372 -234.154726)
			(xy 265.718291 -234.169112) (xy 265.672648 -234.191942) (xy 265.624043 -234.207502) (xy 265.573626 -234.215422)
			(xy 265.54811 -234.21594) (xy 265.52259 -234.215455) (xy 265.472163 -234.207558) (xy 265.423552 -234.191996)
			(xy 265.377913 -234.169141) (xy 265.356848 -234.154726) (xy 265.350268 -234.150391) (xy 265.335259 -234.145616)
			(xy 265.327384 -234.145328) (xy 264.81151 -234.145328) (xy 264.8062 -234.144866) (xy 264.798626 -234.137421)
			(xy 264.798048 -234.13212) (xy 202.89774 -234.13212) (xy 202.89774 -234.132374) (xy 202.897257 -234.13768)
			(xy 202.889827 -234.145253) (xy 202.884532 -234.145836) (xy 202.368658 -234.145836) (xy 202.36085 -234.146168)
			(xy 202.345978 -234.150941) (xy 202.339448 -234.155234) (xy 202.318337 -234.1696) (xy 202.27261 -234.192323)
			(xy 202.223933 -234.207749) (xy 202.173464 -234.21551) (xy 202.147932 -234.21594) (xy 202.122402 -234.215492)
			(xy 202.071939 -234.20772) (xy 202.023266 -234.192295) (xy 201.977538 -234.169581) (xy 201.956416 -234.155234)
			(xy 201.949878 -234.150954) (xy 201.935013 -234.146163) (xy 201.927206 -234.145836) (xy 201.411332 -234.145836)
			(xy 201.406011 -234.145454) (xy 201.39847 -234.137948) (xy 201.398124 -234.132628) (xy 195.353917 -234.132628)
			(xy 195.353457 -234.13768) (xy 195.346027 -234.145253) (xy 195.340732 -234.145836) (xy 194.824858 -234.145836)
			(xy 194.81705 -234.146168) (xy 194.802178 -234.150941) (xy 194.795648 -234.155234) (xy 194.774537 -234.1696)
			(xy 194.72881 -234.192323) (xy 194.680133 -234.207749) (xy 194.629664 -234.21551) (xy 194.604132 -234.21594)
			(xy 194.578602 -234.215492) (xy 194.528139 -234.20772) (xy 194.479466 -234.192295) (xy 194.433738 -234.169581)
			(xy 194.412616 -234.155234) (xy 194.406078 -234.150954) (xy 194.391213 -234.146163) (xy 194.383406 -234.145836)
			(xy 193.867532 -234.145836) (xy 193.862211 -234.145454) (xy 193.85467 -234.137948) (xy 193.854324 -234.132628)
			(xy 187.810124 -234.132628) (xy 187.809801 -234.137811) (xy 187.802115 -234.1455) (xy 187.796678 -234.145836)
			(xy 187.280804 -234.145836) (xy 187.272993 -234.146145) (xy 187.258122 -234.150934) (xy 187.251594 -234.155234)
			(xy 187.23047 -234.16958) (xy 187.184747 -234.192308) (xy 187.136075 -234.207739) (xy 187.085609 -234.215507)
			(xy 187.060078 -234.21594) (xy 187.034547 -234.215519) (xy 186.984082 -234.207739) (xy 186.93541 -234.192306)
			(xy 186.889683 -234.169584) (xy 186.868562 -234.155234) (xy 186.862036 -234.150933) (xy 186.847162 -234.146156)
			(xy 186.839352 -234.145836) (xy 186.323478 -234.145836) (xy 186.318034 -234.145533) (xy 186.310348 -234.137819)
			(xy 186.310016 -234.132374) (xy 180.265832 -234.132374) (xy 180.265356 -234.137682) (xy 180.257922 -234.145256)
			(xy 180.252624 -234.145836) (xy 179.73675 -234.145836) (xy 179.728941 -234.146165) (xy 179.71407 -234.15094)
			(xy 179.70754 -234.155234) (xy 179.686431 -234.169603) (xy 179.640703 -234.192326) (xy 179.592026 -234.207751)
			(xy 179.541556 -234.215511) (xy 179.516024 -234.21594) (xy 179.490494 -234.215496) (xy 179.44003 -234.207723)
			(xy 179.391358 -234.192296) (xy 179.34563 -234.169581) (xy 179.324508 -234.155234) (xy 179.317972 -234.150951)
			(xy 179.303105 -234.146162) (xy 179.295298 -234.145836) (xy 178.779424 -234.145836) (xy 178.774171 -234.145292)
			(xy 178.766729 -234.137879) (xy 178.766216 -234.132628) (xy 172.722016 -234.132628) (xy 172.7217 -234.137813)
			(xy 172.714009 -234.145502) (xy 172.70857 -234.145836) (xy 172.192696 -234.145836) (xy 172.184885 -234.146142)
			(xy 172.170013 -234.150932) (xy 172.163486 -234.155234) (xy 172.142364 -234.169583) (xy 172.096641 -234.192311)
			(xy 172.047967 -234.207741) (xy 171.997501 -234.215507) (xy 171.97197 -234.21594) (xy 171.946439 -234.215523)
			(xy 171.895974 -234.207742) (xy 171.847302 -234.192307) (xy 171.801575 -234.169585) (xy 171.780454 -234.155234)
			(xy 171.77393 -234.15093) (xy 171.759054 -234.146154) (xy 171.751244 -234.145836) (xy 171.23537 -234.145836)
			(xy 171.229996 -234.145367) (xy 171.222411 -234.13775) (xy 171.221908 -234.132374) (xy 165.177724 -234.132374)
			(xy 165.177255 -234.137683) (xy 165.169816 -234.145258) (xy 165.164516 -234.145836) (xy 163.691316 -234.145836)
			(xy 163.686062 -234.145298) (xy 163.67862 -234.13788) (xy 163.678108 -234.132628) (xy 109.67872 -234.132628)
			(xy 109.672476 -234.142184) (xy 109.638257 -234.179353) (xy 109.598387 -234.210381) (xy 109.553953 -234.234424)
			(xy 109.506168 -234.250826) (xy 109.456335 -234.259137) (xy 109.431074 -234.259628) (xy 108.49102 -234.259628)
			(xy 108.465763 -234.259097) (xy 108.415937 -234.250786) (xy 108.368159 -234.234386) (xy 108.323732 -234.210346)
			(xy 108.283868 -234.179321) (xy 108.249654 -234.142157) (xy 108.222025 -234.099869) (xy 108.201733 -234.05361)
			(xy 108.189332 -234.004642) (xy 108.18516 -233.9543) (xy 56.07812 -233.9543) (xy 56.07812 -234.132374)
			(xy 56.077799 -234.137816) (xy 56.0701 -234.145506) (xy 56.064658 -234.145836) (xy 54.591458 -234.145836)
			(xy 54.586083 -234.145375) (xy 54.578498 -234.137752) (xy 54.577996 -234.132374) (xy 48.533812 -234.132374)
			(xy 48.533354 -234.137686) (xy 48.525907 -234.145262) (xy 48.520604 -234.145836) (xy 48.00473 -234.145836)
			(xy 47.99692 -234.146157) (xy 47.982049 -234.150937) (xy 47.97552 -234.155234) (xy 47.954389 -234.169569)
			(xy 47.908669 -234.192299) (xy 47.859998 -234.207733) (xy 47.809534 -234.215505) (xy 47.784004 -234.21594)
			(xy 47.758474 -234.215506) (xy 47.708009 -234.20773) (xy 47.659337 -234.1923) (xy 47.61361 -234.169582)
			(xy 47.592488 -234.155234) (xy 47.585956 -234.150943) (xy 47.571087 -234.146159) (xy 47.563278 -234.145836)
			(xy 47.047404 -234.145836) (xy 47.042148 -234.145306) (xy 47.034707 -234.137882) (xy 47.034196 -234.132628)
			(xy 40.989985 -234.132628) (xy 40.989437 -234.137723) (xy 40.981896 -234.145307) (xy 40.97655 -234.145836)
			(xy 40.460676 -234.145836) (xy 40.452864 -234.146133) (xy 40.437993 -234.15093) (xy 40.431466 -234.155234)
			(xy 40.41035 -234.169592) (xy 40.364624 -234.192317) (xy 40.315949 -234.207745) (xy 40.265481 -234.215509)
			(xy 40.23995 -234.21594) (xy 40.21442 -234.215483) (xy 40.163957 -234.207714) (xy 40.115285 -234.192291)
			(xy 40.069556 -234.169579) (xy 40.048434 -234.155234) (xy 40.041892 -234.15096) (xy 40.02703 -234.146166)
			(xy 40.019224 -234.145836) (xy 39.50335 -234.145836) (xy 39.497974 -234.14538) (xy 39.49039 -234.137753)
			(xy 39.489888 -234.132374) (xy 33.445704 -234.132374) (xy 33.445165 -234.137665) (xy 33.437774 -234.145235)
			(xy 33.432496 -234.145836) (xy 32.916622 -234.145836) (xy 32.908812 -234.146153) (xy 32.893941 -234.150936)
			(xy 32.887412 -234.155234) (xy 32.866283 -234.169572) (xy 32.820562 -234.192302) (xy 32.771891 -234.207735)
			(xy 32.721426 -234.215505) (xy 32.695896 -234.21594) (xy 32.670365 -234.21551) (xy 32.619901 -234.207733)
			(xy 32.571229 -234.192302) (xy 32.525501 -234.169583) (xy 32.50438 -234.155234) (xy 32.49785 -234.15094)
			(xy 32.482979 -234.146158) (xy 32.47517 -234.145836) (xy 31.959296 -234.145836) (xy 31.954039 -234.145311)
			(xy 31.946599 -234.137884) (xy 31.946088 -234.132628) (xy 25.901878 -234.132628) (xy 25.901365 -234.137665)
			(xy 25.893974 -234.145235) (xy 25.888696 -234.145836) (xy 25.372822 -234.145836) (xy 25.365012 -234.146153)
			(xy 25.350141 -234.150936) (xy 25.343612 -234.155234) (xy 25.322483 -234.169572) (xy 25.276762 -234.192302)
			(xy 25.228091 -234.207735) (xy 25.177626 -234.215505) (xy 25.152096 -234.21594) (xy 25.126565 -234.21551)
			(xy 25.076101 -234.207733) (xy 25.027429 -234.192302) (xy 24.981701 -234.169583) (xy 24.96058 -234.155234)
			(xy 24.95405 -234.15094) (xy 24.939179 -234.146158) (xy 24.93137 -234.145836) (xy 24.415496 -234.145836)
			(xy 24.410239 -234.145311) (xy 24.402799 -234.137884) (xy 24.402288 -234.132628) (xy 18.358077 -234.132628)
			(xy 18.357537 -234.137725) (xy 18.34999 -234.145309) (xy 18.344642 -234.145836) (xy 17.828768 -234.145836)
			(xy 17.82096 -234.146173) (xy 17.806088 -234.150942) (xy 17.799558 -234.155234) (xy 17.778444 -234.169596)
			(xy 17.732718 -234.19232) (xy 17.684042 -234.207747) (xy 17.633574 -234.215509) (xy 17.608042 -234.21594)
			(xy 17.582512 -234.215487) (xy 17.532049 -234.207717) (xy 17.483376 -234.192293) (xy 17.437648 -234.16958)
			(xy 17.416526 -234.155234) (xy 17.409986 -234.150957) (xy 17.395123 -234.146165) (xy 17.387316 -234.145836)
			(xy 16.871442 -234.145836) (xy 16.866006 -234.14549) (xy 16.858317 -234.137809) (xy 16.85798 -234.132374)
			(xy 2.509012 -234.132374) (xy 2.509012 -234.982512) (xy 20.958048 -234.982512) (xy 20.958048 -234.487974)
			(xy 20.958534 -234.482605) (xy 20.966139 -234.47502) (xy 20.97151 -234.474512) (xy 21.487638 -234.474512)
			(xy 21.495447 -234.474187) (xy 21.510319 -234.46941) (xy 21.516848 -234.465114) (xy 21.537937 -234.450765)
			(xy 21.583598 -234.428034) (xy 21.632204 -234.412575) (xy 21.682607 -234.404752) (xy 21.733613 -234.404752)
			(xy 21.784016 -234.412575) (xy 21.832622 -234.428034) (xy 21.878283 -234.450765) (xy 21.899372 -234.465114)
			(xy 21.905916 -234.469385) (xy 21.920776 -234.474182) (xy 21.928582 -234.474512) (xy 22.44471 -234.474512)
			(xy 22.450069 -234.475041) (xy 22.457652 -234.482616) (xy 22.458172 -234.487974) (xy 22.458172 -234.982512)
			(xy 28.502356 -234.982512) (xy 28.502356 -234.487974) (xy 28.502808 -234.482663) (xy 28.510261 -234.475093)
			(xy 28.515564 -234.474512) (xy 29.031692 -234.474512) (xy 29.039503 -234.47421) (xy 29.054375 -234.469417)
			(xy 29.060902 -234.465114) (xy 29.081991 -234.450765) (xy 29.127652 -234.428034) (xy 29.176258 -234.412575)
			(xy 29.226661 -234.404752) (xy 29.277667 -234.404752) (xy 29.32807 -234.412575) (xy 29.376676 -234.428034)
			(xy 29.422337 -234.450765) (xy 29.443426 -234.465114) (xy 29.449957 -234.469406) (xy 29.464827 -234.47419)
			(xy 29.472636 -234.474512) (xy 29.988764 -234.474512) (xy 29.994096 -234.474853) (xy 30.001641 -234.482388)
			(xy 30.001972 -234.48772) (xy 30.001972 -234.488228) (xy 30.001972 -234.982512) (xy 36.046156 -234.982512)
			(xy 36.046156 -234.487974) (xy 36.046608 -234.482663) (xy 36.054061 -234.475093) (xy 36.059364 -234.474512)
			(xy 36.575492 -234.474512) (xy 36.583303 -234.47421) (xy 36.598175 -234.469417) (xy 36.604702 -234.465114)
			(xy 36.625791 -234.450765) (xy 36.671452 -234.428034) (xy 36.720058 -234.412575) (xy 36.770461 -234.404752)
			(xy 36.821467 -234.404752) (xy 36.87187 -234.412575) (xy 36.920476 -234.428034) (xy 36.966137 -234.450765)
			(xy 36.987226 -234.465114) (xy 36.993757 -234.469406) (xy 37.008627 -234.47419) (xy 37.016436 -234.474512)
			(xy 37.532564 -234.474512) (xy 37.537896 -234.474853) (xy 37.545441 -234.482388) (xy 37.545772 -234.48772)
			(xy 37.545772 -234.488228) (xy 37.545772 -234.982512) (xy 43.589956 -234.982512) (xy 43.589956 -234.487974)
			(xy 43.590435 -234.482603) (xy 43.598045 -234.475018) (xy 43.603418 -234.474512) (xy 44.119546 -234.474512)
			(xy 44.127356 -234.47419) (xy 44.142228 -234.469411) (xy 44.148756 -234.465114) (xy 44.169845 -234.450765)
			(xy 44.215506 -234.428034) (xy 44.264112 -234.412575) (xy 44.314515 -234.404752) (xy 44.365521 -234.404752)
			(xy 44.415924 -234.412575) (xy 44.46453 -234.428034) (xy 44.510191 -234.450765) (xy 44.53128 -234.465114)
			(xy 44.537822 -234.469388) (xy 44.552684 -234.474183) (xy 44.56049 -234.474512) (xy 45.076618 -234.474512)
			(xy 45.081978 -234.475036) (xy 45.089561 -234.482614) (xy 45.09008 -234.487974) (xy 45.09008 -234.982512)
			(xy 51.134264 -234.982512) (xy 51.134264 -234.487974) (xy 51.134709 -234.482661) (xy 51.142167 -234.47509)
			(xy 51.147472 -234.474512) (xy 51.6636 -234.474512) (xy 51.671412 -234.474213) (xy 51.686284 -234.469418)
			(xy 51.69281 -234.465114) (xy 51.713899 -234.450765) (xy 51.75956 -234.428034) (xy 51.808166 -234.412575)
			(xy 51.858569 -234.404752) (xy 51.909575 -234.404752) (xy 51.959978 -234.412575) (xy 52.008584 -234.428034)
			(xy 52.054245 -234.450765) (xy 52.075334 -234.465114) (xy 52.081864 -234.469409) (xy 52.096735 -234.474191)
			(xy 52.104544 -234.474512) (xy 52.620672 -234.474512) (xy 52.626005 -234.474847) (xy 52.633549 -234.482387)
			(xy 52.63388 -234.48772) (xy 52.63388 -234.488228) (xy 52.63388 -234.982512) (xy 58.678064 -234.982512)
			(xy 58.678064 -234.487974) (xy 58.678536 -234.482601) (xy 58.686151 -234.475015) (xy 58.691526 -234.474512)
			(xy 60.164726 -234.474512) (xy 60.170087 -234.475031) (xy 60.177669 -234.482613) (xy 60.178188 -234.487974)
			(xy 60.178188 -234.7643) (xy 97.374911 -234.7643) (xy 97.379087 -234.713916) (xy 97.391499 -234.664906)
			(xy 97.411808 -234.618609) (xy 97.439462 -234.576285) (xy 97.473705 -234.539091) (xy 97.513603 -234.508041)
			(xy 97.558069 -234.483982) (xy 97.605888 -234.467571) (xy 97.655756 -234.459254) (xy 97.681034 -234.458764)
			(xy 98.621088 -234.458764) (xy 98.64637 -234.459204) (xy 98.696243 -234.467525) (xy 98.744067 -234.483941)
			(xy 98.788537 -234.508005) (xy 98.828439 -234.539061) (xy 98.862685 -234.576261) (xy 98.890341 -234.61859)
			(xy 98.910652 -234.664894) (xy 98.923065 -234.71391) (xy 98.927241 -234.7643) (xy 100.194811 -234.7643)
			(xy 100.198987 -234.713915) (xy 100.211399 -234.664905) (xy 100.23171 -234.618606) (xy 100.259364 -234.576283)
			(xy 100.293608 -234.539088) (xy 100.333508 -234.508038) (xy 100.377974 -234.48398) (xy 100.425794 -234.467569)
			(xy 100.475663 -234.459254) (xy 100.500942 -234.458764) (xy 101.440996 -234.458764) (xy 101.466277 -234.459205)
			(xy 101.51615 -234.467526) (xy 101.563973 -234.483944) (xy 101.608441 -234.508008) (xy 101.648342 -234.539064)
			(xy 101.682587 -234.576263) (xy 101.710242 -234.618592) (xy 101.730553 -234.664896) (xy 101.742965 -234.713911)
			(xy 101.747141 -234.7643) (xy 103.015011 -234.7643) (xy 103.019186 -234.713919) (xy 103.031596 -234.664912)
			(xy 103.051904 -234.618617) (xy 103.079554 -234.576295) (xy 103.113793 -234.539102) (xy 103.153688 -234.508052)
			(xy 103.198148 -234.483991) (xy 103.245963 -234.467577) (xy 103.295827 -234.459257) (xy 103.321104 -234.458764)
			(xy 104.261158 -234.458764) (xy 104.286441 -234.459202) (xy 104.336319 -234.467519) (xy 104.384147 -234.483932)
			(xy 104.428621 -234.507995) (xy 104.468527 -234.53905) (xy 104.502777 -234.576251) (xy 104.530436 -234.618582)
			(xy 104.55075 -234.664888) (xy 104.563164 -234.713907) (xy 104.567341 -234.7643) (xy 105.834911 -234.7643)
			(xy 105.839086 -234.713918) (xy 105.851497 -234.664911) (xy 105.871805 -234.618615) (xy 105.899456 -234.576293)
			(xy 105.933697 -234.539099) (xy 105.973592 -234.508049) (xy 106.018054 -234.483989) (xy 106.06587 -234.467575)
			(xy 106.115735 -234.459256) (xy 106.141012 -234.458764) (xy 107.081066 -234.458764) (xy 107.106349 -234.459202)
			(xy 107.156225 -234.46752) (xy 107.204052 -234.483935) (xy 107.248525 -234.507998) (xy 107.28843 -234.539053)
			(xy 107.322679 -234.576253) (xy 107.350337 -234.618584) (xy 107.370651 -234.66489) (xy 107.383065 -234.713907)
			(xy 107.387241 -234.7643) (xy 107.383065 -234.814693) (xy 107.370651 -234.86371) (xy 107.350337 -234.910016)
			(xy 107.322679 -234.952347) (xy 107.294907 -234.982512) (xy 167.778176 -234.982512) (xy 167.778176 -234.487974)
			(xy 167.77861 -234.482658) (xy 167.786076 -234.475087) (xy 167.791384 -234.474512) (xy 169.264584 -234.474512)
			(xy 169.269919 -234.47484) (xy 169.277462 -234.482385) (xy 169.277792 -234.48772) (xy 169.277792 -234.982512)
			(xy 175.321976 -234.982512) (xy 175.321976 -234.487974) (xy 175.322265 -234.482526) (xy 175.329989 -234.47484)
			(xy 175.335438 -234.474512) (xy 175.851566 -234.474512) (xy 175.859376 -234.474199) (xy 175.874248 -234.469414)
			(xy 175.880776 -234.465114) (xy 175.901865 -234.450765) (xy 175.947526 -234.428034) (xy 175.996132 -234.412575)
			(xy 176.046535 -234.404752) (xy 176.097541 -234.404752) (xy 176.147944 -234.412575) (xy 176.19655 -234.428034)
			(xy 176.242211 -234.450765) (xy 176.2633 -234.465114) (xy 176.269837 -234.469396) (xy 176.284703 -234.474186)
			(xy 176.29251 -234.474512) (xy 176.808638 -234.474512) (xy 176.814 -234.475023) (xy 176.821582 -234.482611)
			(xy 176.8221 -234.487974) (xy 176.8221 -234.982512) (xy 182.866284 -234.982512) (xy 182.866284 -234.487974)
			(xy 182.866711 -234.482656) (xy 182.874182 -234.475084) (xy 182.879492 -234.474512) (xy 183.39562 -234.474512)
			(xy 183.403432 -234.474221) (xy 183.418304 -234.469421) (xy 183.42483 -234.465114) (xy 183.445919 -234.450765)
			(xy 183.49158 -234.428034) (xy 183.540186 -234.412575) (xy 183.590589 -234.404752) (xy 183.641595 -234.404752)
			(xy 183.691998 -234.412575) (xy 183.740604 -234.428034) (xy 183.786265 -234.450765) (xy 183.807354 -234.465114)
			(xy 183.813879 -234.469417) (xy 183.828754 -234.474194) (xy 183.836564 -234.474512) (xy 184.352692 -234.474512)
			(xy 184.358028 -234.474834) (xy 184.365571 -234.482384) (xy 184.3659 -234.48772) (xy 184.3659 -234.488228)
			(xy 184.3659 -234.982512) (xy 190.410084 -234.982512) (xy 190.410084 -234.487974) (xy 190.410366 -234.482524)
			(xy 190.418095 -234.474837) (xy 190.423546 -234.474512) (xy 190.939674 -234.474512) (xy 190.947485 -234.474202)
			(xy 190.962357 -234.469415) (xy 190.968884 -234.465114) (xy 190.989973 -234.450765) (xy 191.035634 -234.428034)
			(xy 191.08424 -234.412575) (xy 191.134643 -234.404752) (xy 191.185649 -234.404752) (xy 191.236052 -234.412575)
			(xy 191.284658 -234.428034) (xy 191.330319 -234.450765) (xy 191.351408 -234.465114) (xy 191.357943 -234.469399)
			(xy 191.37281 -234.474188) (xy 191.380618 -234.474512) (xy 191.896746 -234.474512) (xy 191.902109 -234.475017)
			(xy 191.909691 -234.48261) (xy 191.910208 -234.487974) (xy 191.910208 -234.982512) (xy 197.954392 -234.982512)
			(xy 197.954392 -234.487974) (xy 197.9549 -234.482678) (xy 197.962315 -234.475111) (xy 197.9676 -234.474512)
			(xy 198.483728 -234.474512) (xy 198.491541 -234.474225) (xy 198.506413 -234.469422) (xy 198.512938 -234.465114)
			(xy 198.534027 -234.450765) (xy 198.579688 -234.428034) (xy 198.628294 -234.412575) (xy 198.678697 -234.404752)
			(xy 198.729703 -234.404752) (xy 198.780106 -234.412575) (xy 198.828712 -234.428034) (xy 198.874373 -234.450765)
			(xy 198.895462 -234.465114) (xy 198.902008 -234.469381) (xy 198.916867 -234.474181) (xy 198.924672 -234.474512)
			(xy 199.4408 -234.474512) (xy 199.446137 -234.474829) (xy 199.453679 -234.482382) (xy 199.454008 -234.48772)
			(xy 199.454008 -234.488228) (xy 199.454008 -234.982512) (xy 205.498192 -234.982512) (xy 205.498192 -234.487974)
			(xy 205.4987 -234.482678) (xy 205.506115 -234.475111) (xy 205.5114 -234.474512) (xy 206.027528 -234.474512)
			(xy 206.035341 -234.474225) (xy 206.050213 -234.469422) (xy 206.056738 -234.465114) (xy 206.077827 -234.450765)
			(xy 206.123488 -234.428034) (xy 206.172094 -234.412575) (xy 206.222497 -234.404752) (xy 206.273503 -234.404752)
			(xy 206.323906 -234.412575) (xy 206.372512 -234.428034) (xy 206.418173 -234.450765) (xy 206.439262 -234.465114)
			(xy 206.445808 -234.469381) (xy 206.460667 -234.474181) (xy 206.468472 -234.474512) (xy 206.9846 -234.474512)
			(xy 206.989937 -234.474829) (xy 206.997479 -234.482382) (xy 206.997808 -234.48772) (xy 206.997808 -234.488228)
			(xy 206.997808 -234.982258) (xy 268.898116 -234.982258) (xy 268.898116 -234.48772) (xy 268.898442 -234.482384)
			(xy 268.905988 -234.474841) (xy 268.911324 -234.474512) (xy 268.911832 -234.474512) (xy 269.427706 -234.474512)
			(xy 269.435518 -234.474216) (xy 269.45039 -234.469419) (xy 269.456916 -234.465114) (xy 269.478005 -234.450765)
			(xy 269.523666 -234.428034) (xy 269.572272 -234.412575) (xy 269.622675 -234.404752) (xy 269.673681 -234.404752)
			(xy 269.724084 -234.412575) (xy 269.77269 -234.428034) (xy 269.818351 -234.450765) (xy 269.83944 -234.465114)
			(xy 269.845968 -234.469411) (xy 269.860841 -234.474192) (xy 269.86865 -234.474512) (xy 270.384778 -234.474512)
			(xy 270.390073 -234.475034) (xy 270.397644 -234.482437) (xy 270.39824 -234.48772) (xy 270.39824 -234.982258)
			(xy 270.398224 -234.982512) (xy 276.442424 -234.982512) (xy 276.442424 -234.982004) (xy 276.442424 -234.48772)
			(xy 276.442743 -234.482383) (xy 276.450294 -234.474838) (xy 276.455632 -234.474512) (xy 276.97176 -234.474512)
			(xy 276.97957 -234.474196) (xy 276.994442 -234.469413) (xy 277.00097 -234.465114) (xy 277.022059 -234.450765)
			(xy 277.06772 -234.428034) (xy 277.116326 -234.412575) (xy 277.166729 -234.404752) (xy 277.217735 -234.404752)
			(xy 277.268138 -234.412575) (xy 277.316744 -234.428034) (xy 277.362405 -234.450765) (xy 277.383494 -234.465114)
			(xy 277.390033 -234.469394) (xy 277.404897 -234.474185) (xy 277.412704 -234.474512) (xy 277.928832 -234.474512)
			(xy 277.934103 -234.474975) (xy 277.941545 -234.482447) (xy 277.94204 -234.48772) (xy 277.94204 -234.982258)
			(xy 277.942016 -234.982512) (xy 283.986224 -234.982512) (xy 283.986224 -234.982004) (xy 283.986224 -234.48772)
			(xy 283.986543 -234.482383) (xy 283.994094 -234.474838) (xy 283.999432 -234.474512) (xy 284.51556 -234.474512)
			(xy 284.52337 -234.474196) (xy 284.538242 -234.469413) (xy 284.54477 -234.465114) (xy 284.565859 -234.450765)
			(xy 284.61152 -234.428034) (xy 284.660126 -234.412575) (xy 284.710529 -234.404752) (xy 284.761535 -234.404752)
			(xy 284.811938 -234.412575) (xy 284.860544 -234.428034) (xy 284.906205 -234.450765) (xy 284.927294 -234.465114)
			(xy 284.933833 -234.469394) (xy 284.948697 -234.474185) (xy 284.956504 -234.474512) (xy 285.472632 -234.474512)
			(xy 285.477903 -234.474975) (xy 285.485345 -234.482447) (xy 285.48584 -234.48772) (xy 285.48584 -234.982258)
			(xy 291.530024 -234.982258) (xy 291.530024 -234.48772) (xy 291.530343 -234.482383) (xy 291.537894 -234.474838)
			(xy 291.543232 -234.474512) (xy 291.54374 -234.474512) (xy 292.059614 -234.474512) (xy 292.067426 -234.474219)
			(xy 292.082298 -234.46942) (xy 292.088824 -234.465114) (xy 292.109913 -234.450765) (xy 292.155574 -234.428034)
			(xy 292.20418 -234.412575) (xy 292.254583 -234.404752) (xy 292.305589 -234.404752) (xy 292.355992 -234.412575)
			(xy 292.404598 -234.428034) (xy 292.450259 -234.450765) (xy 292.471348 -234.465114) (xy 292.477875 -234.469414)
			(xy 292.492748 -234.474193) (xy 292.500558 -234.474512) (xy 293.016686 -234.474512) (xy 293.021982 -234.475029)
			(xy 293.029552 -234.482436) (xy 293.030148 -234.48772) (xy 293.030148 -234.982258) (xy 293.030131 -234.982512)
			(xy 299.074332 -234.982512) (xy 299.074332 -234.982004) (xy 299.074332 -234.48772) (xy 299.074644 -234.482381)
			(xy 299.0822 -234.474836) (xy 299.08754 -234.474512) (xy 299.603668 -234.474512) (xy 299.611478 -234.4742)
			(xy 299.62635 -234.469414) (xy 299.632878 -234.465114) (xy 299.653967 -234.450765) (xy 299.699628 -234.428034)
			(xy 299.748234 -234.412575) (xy 299.798637 -234.404752) (xy 299.849643 -234.404752) (xy 299.900046 -234.412575)
			(xy 299.948652 -234.428034) (xy 299.994313 -234.450765) (xy 300.015402 -234.465114) (xy 300.021939 -234.469397)
			(xy 300.036805 -234.474187) (xy 300.044612 -234.474512) (xy 300.56074 -234.474512) (xy 300.566013 -234.47497)
			(xy 300.573454 -234.482445) (xy 300.573948 -234.48772) (xy 300.573948 -234.982258) (xy 306.618132 -234.982258)
			(xy 306.618132 -234.48772) (xy 306.618444 -234.482381) (xy 306.626 -234.474836) (xy 306.63134 -234.474512)
			(xy 306.631848 -234.474512) (xy 308.104794 -234.474512) (xy 308.110091 -234.475024) (xy 308.117661 -234.482435)
			(xy 308.118256 -234.48772) (xy 308.118256 -234.7641) (xy 364.108912 -234.7641) (xy 364.113084 -234.713751)
			(xy 364.125487 -234.664775) (xy 364.145782 -234.618509) (xy 364.173416 -234.576214) (xy 364.207634 -234.539045)
			(xy 364.247504 -234.508015) (xy 364.291937 -234.483971) (xy 364.339722 -234.467569) (xy 364.389555 -234.459256)
			(xy 364.414816 -234.458764) (xy 365.35487 -234.458764) (xy 365.380127 -234.45931) (xy 365.429953 -234.46762)
			(xy 365.477731 -234.484018) (xy 365.522158 -234.508057) (xy 365.562023 -234.539081) (xy 365.596237 -234.576244)
			(xy 365.623867 -234.618532) (xy 365.644159 -234.664791) (xy 365.65656 -234.713759) (xy 365.660732 -234.7641)
			(xy 366.928812 -234.7641) (xy 366.932984 -234.71375) (xy 366.945387 -234.664774) (xy 366.965683 -234.618507)
			(xy 366.993318 -234.576212) (xy 367.027537 -234.539042) (xy 367.067408 -234.508013) (xy 367.111842 -234.483969)
			(xy 367.159629 -234.467567) (xy 367.209463 -234.459255) (xy 367.234724 -234.458764) (xy 368.174778 -234.458764)
			(xy 368.200035 -234.459311) (xy 368.249859 -234.467622) (xy 368.297636 -234.484021) (xy 368.342063 -234.50806)
			(xy 368.381926 -234.539084) (xy 368.416139 -234.576247) (xy 368.443768 -234.618534) (xy 368.46406 -234.664792)
			(xy 368.47646 -234.713759) (xy 368.480632 -234.7641) (xy 369.749041 -234.7641) (xy 369.753212 -234.713759)
			(xy 369.765612 -234.664791) (xy 369.785903 -234.618531) (xy 369.813531 -234.576242) (xy 369.847742 -234.539077)
			(xy 369.887604 -234.50805) (xy 369.932028 -234.484007) (xy 369.979805 -234.467603) (xy 370.029629 -234.459287)
			(xy 370.054886 -234.458764) (xy 370.99494 -234.458764) (xy 371.020191 -234.459345) (xy 371.070003 -234.467663)
			(xy 371.117767 -234.484066) (xy 371.16218 -234.508106) (xy 371.20203 -234.539128) (xy 371.236232 -234.576285)
			(xy 371.263852 -234.618565) (xy 371.284136 -234.664814) (xy 371.296533 -234.713771) (xy 371.300703 -234.7641)
			(xy 372.568941 -234.7641) (xy 372.573112 -234.713758) (xy 372.585513 -234.664789) (xy 372.605804 -234.618529)
			(xy 372.633433 -234.57624) (xy 372.667645 -234.539074) (xy 372.707508 -234.508047) (xy 372.751934 -234.484004)
			(xy 372.799711 -234.467601) (xy 372.849537 -234.459286) (xy 372.874794 -234.458764) (xy 373.814848 -234.458764)
			(xy 373.840098 -234.459345) (xy 373.889909 -234.467664) (xy 373.937672 -234.484068) (xy 373.982084 -234.508109)
			(xy 374.021933 -234.539131) (xy 374.056134 -234.576288) (xy 374.083753 -234.618567) (xy 374.104037 -234.664815)
			(xy 374.116433 -234.713771) (xy 374.120603 -234.7641) (xy 374.116433 -234.814429) (xy 374.104037 -234.863384)
			(xy 374.083753 -234.909633) (xy 374.056134 -234.951912) (xy 374.027968 -234.982512) (xy 415.718244 -234.982512)
			(xy 415.718244 -234.48772) (xy 415.718803 -234.482471) (xy 415.726206 -234.47503) (xy 415.731452 -234.474512)
			(xy 417.204652 -234.474512) (xy 417.209983 -234.474861) (xy 417.217527 -234.48239) (xy 417.21786 -234.48772)
			(xy 417.21786 -234.982258) (xy 423.262044 -234.982258) (xy 423.262044 -234.48772) (xy 423.262603 -234.482471)
			(xy 423.270006 -234.47503) (xy 423.275252 -234.474512) (xy 423.27576 -234.474512) (xy 423.791634 -234.474512)
			(xy 423.799443 -234.474185) (xy 423.814315 -234.46941) (xy 423.820844 -234.465114) (xy 423.841933 -234.450765)
			(xy 423.887594 -234.428034) (xy 423.9362 -234.412575) (xy 423.986603 -234.404752) (xy 424.037609 -234.404752)
			(xy 424.088012 -234.412575) (xy 424.136618 -234.428034) (xy 424.182279 -234.450765) (xy 424.203368 -234.465114)
			(xy 424.209912 -234.469384) (xy 424.224772 -234.474182) (xy 424.232578 -234.474512) (xy 424.748706 -234.474512)
			(xy 424.754004 -234.475016) (xy 424.761574 -234.482433) (xy 424.762168 -234.48772) (xy 424.762168 -234.982258)
			(xy 424.76215 -234.982512) (xy 430.806352 -234.982512) (xy 430.806352 -234.982004) (xy 430.806352 -234.48772)
			(xy 430.806904 -234.482469) (xy 430.814312 -234.475028) (xy 430.81956 -234.474512) (xy 431.335688 -234.474512)
			(xy 431.343499 -234.474208) (xy 431.358371 -234.469417) (xy 431.364898 -234.465114) (xy 431.385987 -234.450765)
			(xy 431.431648 -234.428034) (xy 431.480254 -234.412575) (xy 431.530657 -234.404752) (xy 431.581663 -234.404752)
			(xy 431.632066 -234.412575) (xy 431.680672 -234.428034) (xy 431.726333 -234.450765) (xy 431.747422 -234.465114)
			(xy 431.753954 -234.469404) (xy 431.768823 -234.47419) (xy 431.776632 -234.474512) (xy 432.29276 -234.474512)
			(xy 432.298092 -234.474856) (xy 432.305636 -234.482389) (xy 432.305968 -234.48772) (xy 432.305968 -234.982258)
			(xy 438.350152 -234.982258) (xy 438.350152 -234.48772) (xy 438.350704 -234.482469) (xy 438.358112 -234.475028)
			(xy 438.36336 -234.474512) (xy 438.363868 -234.474512) (xy 438.879742 -234.474512) (xy 438.887551 -234.474189)
			(xy 438.902424 -234.469411) (xy 438.908952 -234.465114) (xy 438.930041 -234.450765) (xy 438.975702 -234.428034)
			(xy 439.024308 -234.412575) (xy 439.074711 -234.404752) (xy 439.125717 -234.404752) (xy 439.17612 -234.412575)
			(xy 439.224726 -234.428034) (xy 439.270387 -234.450765) (xy 439.291476 -234.465114) (xy 439.298019 -234.469387)
			(xy 439.31288 -234.474183) (xy 439.320686 -234.474512) (xy 439.836814 -234.474512) (xy 439.842113 -234.475011)
			(xy 439.849682 -234.482431) (xy 439.850276 -234.48772) (xy 439.850276 -234.982258) (xy 439.850258 -234.982512)
			(xy 445.89446 -234.982512) (xy 445.89446 -234.982004) (xy 445.89446 -234.48772) (xy 445.895005 -234.482467)
			(xy 445.902417 -234.475025) (xy 445.907668 -234.474512) (xy 446.423796 -234.474512) (xy 446.431608 -234.474211)
			(xy 446.446479 -234.469418) (xy 446.453006 -234.465114) (xy 446.474095 -234.450765) (xy 446.519756 -234.428034)
			(xy 446.568362 -234.412575) (xy 446.618765 -234.404752) (xy 446.669771 -234.404752) (xy 446.720174 -234.412575)
			(xy 446.76878 -234.428034) (xy 446.814441 -234.450765) (xy 446.83553 -234.465114) (xy 446.842061 -234.469407)
			(xy 446.856931 -234.474191) (xy 446.86474 -234.474512) (xy 447.380868 -234.474512) (xy 447.386201 -234.47485)
			(xy 447.393745 -234.482388) (xy 447.394076 -234.48772) (xy 447.394076 -234.982258) (xy 447.394051 -234.982512)
			(xy 453.43826 -234.982512) (xy 453.43826 -234.982004) (xy 453.43826 -234.48772) (xy 453.438805 -234.482467)
			(xy 453.446217 -234.475025) (xy 453.451468 -234.474512) (xy 453.967596 -234.474512) (xy 453.975408 -234.474211)
			(xy 453.990279 -234.469418) (xy 453.996806 -234.465114) (xy 454.017895 -234.450765) (xy 454.063556 -234.428034)
			(xy 454.112162 -234.412575) (xy 454.162565 -234.404752) (xy 454.213571 -234.404752) (xy 454.263974 -234.412575)
			(xy 454.31258 -234.428034) (xy 454.358241 -234.450765) (xy 454.37933 -234.465114) (xy 454.385861 -234.469407)
			(xy 454.400731 -234.474191) (xy 454.40854 -234.474512) (xy 454.924668 -234.474512) (xy 454.930001 -234.47485)
			(xy 454.937545 -234.482388) (xy 454.937876 -234.48772) (xy 454.937876 -234.982258) (xy 454.937351 -234.987553)
			(xy 454.929951 -234.995126) (xy 454.924668 -234.99572) (xy 454.408794 -234.99572) (xy 454.400983 -234.996028)
			(xy 454.386112 -235.000817) (xy 454.379584 -235.005118) (xy 454.358462 -235.019466) (xy 454.312738 -235.042194)
			(xy 454.264065 -235.057625) (xy 454.213599 -235.065391) (xy 454.188068 -235.065824) (xy 454.162537 -235.065411)
			(xy 454.112072 -235.057629) (xy 454.063399 -235.042193) (xy 454.017673 -235.019469) (xy 453.996552 -235.005118)
			(xy 453.990029 -235.000812) (xy 453.975153 -234.996038) (xy 453.967342 -234.99572) (xy 453.451468 -234.99572)
			(xy 453.446204 -234.995228) (xy 453.438764 -234.987776) (xy 453.43826 -234.982512) (xy 447.394051 -234.982512)
			(xy 447.393551 -234.987553) (xy 447.386151 -234.995126) (xy 447.380868 -234.99572) (xy 446.864994 -234.99572)
			(xy 446.857183 -234.996028) (xy 446.842312 -235.000817) (xy 446.835784 -235.005118) (xy 446.814662 -235.019466)
			(xy 446.768938 -235.042194) (xy 446.720265 -235.057625) (xy 446.669799 -235.065391) (xy 446.644268 -235.065824)
			(xy 446.618737 -235.065411) (xy 446.568272 -235.057629) (xy 446.519599 -235.042193) (xy 446.473873 -235.019469)
			(xy 446.452752 -235.005118) (xy 446.446229 -235.000812) (xy 446.431353 -234.996038) (xy 446.423542 -234.99572)
			(xy 445.907668 -234.99572) (xy 445.902404 -234.995228) (xy 445.894964 -234.987776) (xy 445.89446 -234.982512)
			(xy 439.850258 -234.982512) (xy 439.849894 -234.987684) (xy 439.842238 -234.995371) (xy 439.836814 -234.99572)
			(xy 439.32094 -234.99572) (xy 439.313131 -234.996047) (xy 439.298259 -235.000823) (xy 439.29173 -235.005118)
			(xy 439.270623 -235.01949) (xy 439.224894 -235.042212) (xy 439.176216 -235.057636) (xy 439.125746 -235.065395)
			(xy 439.100214 -235.065824) (xy 439.074684 -235.065388) (xy 439.024219 -235.057613) (xy 438.975547 -235.042184)
			(xy 438.92982 -235.019466) (xy 438.908698 -235.005118) (xy 438.902165 -235.000829) (xy 438.887296 -234.996045)
			(xy 438.879488 -234.99572) (xy 438.363614 -234.99572) (xy 438.358171 -234.995407) (xy 438.350482 -234.987702)
			(xy 438.350152 -234.982258) (xy 432.305968 -234.982258) (xy 432.30545 -234.987555) (xy 432.298045 -234.995128)
			(xy 432.29276 -234.99572) (xy 431.776886 -234.99572) (xy 431.769075 -234.996024) (xy 431.754204 -235.000816)
			(xy 431.747676 -235.005118) (xy 431.726556 -235.01947) (xy 431.680832 -235.042197) (xy 431.632158 -235.057626)
			(xy 431.581691 -235.065392) (xy 431.55616 -235.065824) (xy 431.530629 -235.065415) (xy 431.480163 -235.057632)
			(xy 431.431491 -235.042195) (xy 431.385765 -235.01947) (xy 431.364644 -235.005118) (xy 431.358123 -235.000809)
			(xy 431.343245 -234.996037) (xy 431.335434 -234.99572) (xy 430.81956 -234.99572) (xy 430.814295 -234.995233)
			(xy 430.806856 -234.987778) (xy 430.806352 -234.982512) (xy 424.76215 -234.982512) (xy 424.761793 -234.987686)
			(xy 424.754132 -234.995374) (xy 424.748706 -234.99572) (xy 424.232832 -234.99572) (xy 424.225023 -234.996044)
			(xy 424.210151 -235.000822) (xy 424.203622 -235.005118) (xy 424.182489 -235.01945) (xy 424.13677 -235.042182)
			(xy 424.0881 -235.057617) (xy 424.037636 -235.065388) (xy 424.012106 -235.065824) (xy 423.986575 -235.065392)
			(xy 423.936111 -235.057616) (xy 423.887439 -235.042186) (xy 423.841711 -235.019467) (xy 423.82059 -235.005118)
			(xy 423.814059 -235.000826) (xy 423.799189 -234.996043) (xy 423.79138 -234.99572) (xy 423.275506 -234.99572)
			(xy 423.270062 -234.995413) (xy 423.262373 -234.987703) (xy 423.262044 -234.982258) (xy 417.21786 -234.982258)
			(xy 417.217349 -234.987557) (xy 417.209939 -234.995131) (xy 417.204652 -234.99572) (xy 415.731452 -234.99572)
			(xy 415.726186 -234.995238) (xy 415.718747 -234.987779) (xy 415.718244 -234.982512) (xy 374.027968 -234.982512)
			(xy 374.021933 -234.989069) (xy 373.982084 -235.020091) (xy 373.937672 -235.044132) (xy 373.889909 -235.060536)
			(xy 373.840098 -235.068855) (xy 373.814848 -235.06938) (xy 372.874794 -235.06938) (xy 372.849537 -235.068914)
			(xy 372.799711 -235.060599) (xy 372.751934 -235.044196) (xy 372.707508 -235.020153) (xy 372.667645 -234.989126)
			(xy 372.633433 -234.95196) (xy 372.605804 -234.909671) (xy 372.585513 -234.863411) (xy 372.573112 -234.814442)
			(xy 372.568941 -234.7641) (xy 371.300703 -234.7641) (xy 371.296533 -234.814429) (xy 371.284136 -234.863386)
			(xy 371.263852 -234.909635) (xy 371.236232 -234.951915) (xy 371.20203 -234.989072) (xy 371.16218 -235.020094)
			(xy 371.117767 -235.044134) (xy 371.070003 -235.060537) (xy 371.020191 -235.068855) (xy 370.99494 -235.06938)
			(xy 370.054886 -235.06938) (xy 370.029629 -235.068913) (xy 369.979805 -235.060597) (xy 369.932028 -235.044193)
			(xy 369.887604 -235.02015) (xy 369.847742 -234.989123) (xy 369.813531 -234.951958) (xy 369.785903 -234.909669)
			(xy 369.765612 -234.863409) (xy 369.753212 -234.814441) (xy 369.749041 -234.7641) (xy 368.480632 -234.7641)
			(xy 368.47646 -234.814441) (xy 368.46406 -234.863408) (xy 368.443768 -234.909666) (xy 368.416139 -234.951953)
			(xy 368.381926 -234.989116) (xy 368.342063 -235.02014) (xy 368.297636 -235.044179) (xy 368.249859 -235.060578)
			(xy 368.200035 -235.068889) (xy 368.174778 -235.06938) (xy 367.234724 -235.06938) (xy 367.209463 -235.068945)
			(xy 367.159629 -235.060633) (xy 367.111842 -235.044231) (xy 367.067408 -235.020187) (xy 367.027537 -234.989158)
			(xy 366.993318 -234.951988) (xy 366.965683 -234.909693) (xy 366.945387 -234.863426) (xy 366.932984 -234.81445)
			(xy 366.928812 -234.7641) (xy 365.660732 -234.7641) (xy 365.65656 -234.814441) (xy 365.644159 -234.863409)
			(xy 365.623867 -234.909668) (xy 365.596237 -234.951956) (xy 365.562023 -234.989119) (xy 365.522158 -235.020143)
			(xy 365.477731 -235.044182) (xy 365.429953 -235.06058) (xy 365.380127 -235.06889) (xy 365.35487 -235.06938)
			(xy 364.414816 -235.06938) (xy 364.389555 -235.068944) (xy 364.339722 -235.060631) (xy 364.291937 -235.044229)
			(xy 364.247504 -235.020185) (xy 364.207634 -234.989155) (xy 364.173416 -234.951986) (xy 364.145782 -234.909691)
			(xy 364.125487 -234.863425) (xy 364.113084 -234.814449) (xy 364.108912 -234.7641) (xy 308.118256 -234.7641)
			(xy 308.118256 -234.982258) (xy 308.117892 -234.987689) (xy 308.110224 -234.995377) (xy 308.104794 -234.99572)
			(xy 306.631594 -234.99572) (xy 306.626148 -234.99542) (xy 306.61846 -234.987705) (xy 306.618132 -234.982258)
			(xy 300.573948 -234.982258) (xy 300.573447 -234.98756) (xy 300.566031 -234.995134) (xy 300.56074 -234.99572)
			(xy 300.044866 -234.99572) (xy 300.037058 -234.996059) (xy 300.022187 -235.000827) (xy 300.015656 -235.005118)
			(xy 299.994542 -235.019478) (xy 299.948815 -235.042204) (xy 299.90014 -235.057631) (xy 299.849672 -235.065393)
			(xy 299.82414 -235.065824) (xy 299.79861 -235.065375) (xy 299.748147 -235.057604) (xy 299.699474 -235.042179)
			(xy 299.653746 -235.019465) (xy 299.632624 -235.005118) (xy 299.626085 -235.000839) (xy 299.611221 -234.996048)
			(xy 299.603414 -234.99572) (xy 299.08754 -234.99572) (xy 299.082216 -234.995347) (xy 299.074674 -234.987835)
			(xy 299.074332 -234.982512) (xy 293.030131 -234.982512) (xy 293.029791 -234.987691) (xy 293.022118 -234.99538)
			(xy 293.016686 -234.99572) (xy 292.500812 -234.99572) (xy 292.493002 -234.996035) (xy 292.47813 -235.00082)
			(xy 292.471602 -235.005118) (xy 292.450475 -235.019459) (xy 292.404753 -235.042188) (xy 292.356082 -235.057621)
			(xy 292.305617 -235.06539) (xy 292.280086 -235.065824) (xy 292.254555 -235.065402) (xy 292.20409 -235.057623)
			(xy 292.155418 -235.04219) (xy 292.109691 -235.019468) (xy 292.08857 -235.005118) (xy 292.082043 -235.000819)
			(xy 292.06717 -234.996041) (xy 292.05936 -234.99572) (xy 291.543486 -234.99572) (xy 291.538039 -234.995426)
			(xy 291.530352 -234.987706) (xy 291.530024 -234.982258) (xy 285.48584 -234.982258) (xy 285.485347 -234.987562)
			(xy 285.477925 -234.995136) (xy 285.472632 -234.99572) (xy 284.956758 -234.99572) (xy 284.94895 -234.996055)
			(xy 284.934078 -235.000826) (xy 284.927548 -235.005118) (xy 284.906436 -235.019482) (xy 284.860709 -235.042206)
			(xy 284.812033 -235.057632) (xy 284.761564 -235.065394) (xy 284.736032 -235.065824) (xy 284.710502 -235.065379)
			(xy 284.660038 -235.057607) (xy 284.611366 -235.04218) (xy 284.565638 -235.019465) (xy 284.544516 -235.005118)
			(xy 284.537979 -235.000836) (xy 284.523113 -234.996047) (xy 284.515306 -234.99572) (xy 283.999432 -234.99572)
			(xy 283.994107 -234.995353) (xy 283.986565 -234.987836) (xy 283.986224 -234.982512) (xy 277.942016 -234.982512)
			(xy 277.941547 -234.987562) (xy 277.934125 -234.995136) (xy 277.928832 -234.99572) (xy 277.412958 -234.99572)
			(xy 277.40515 -234.996055) (xy 277.390278 -235.000826) (xy 277.383748 -235.005118) (xy 277.362636 -235.019482)
			(xy 277.316909 -235.042206) (xy 277.268233 -235.057632) (xy 277.217764 -235.065394) (xy 277.192232 -235.065824)
			(xy 277.166702 -235.065379) (xy 277.116238 -235.057607) (xy 277.067566 -235.04218) (xy 277.021838 -235.019465)
			(xy 277.000716 -235.005118) (xy 276.994179 -235.000836) (xy 276.979313 -234.996047) (xy 276.971506 -234.99572)
			(xy 276.455632 -234.99572) (xy 276.450307 -234.995353) (xy 276.442765 -234.987836) (xy 276.442424 -234.982512)
			(xy 270.398224 -234.982512) (xy 270.39789 -234.987693) (xy 270.390212 -234.995382) (xy 270.384778 -234.99572)
			(xy 269.868904 -234.99572) (xy 269.861094 -234.996032) (xy 269.846222 -235.000819) (xy 269.839694 -235.005118)
			(xy 269.818569 -235.019462) (xy 269.772847 -235.042191) (xy 269.724174 -235.057623) (xy 269.673709 -235.06539)
			(xy 269.648178 -235.065824) (xy 269.622647 -235.065406) (xy 269.572182 -235.057626) (xy 269.523509 -235.042191)
			(xy 269.477783 -235.019469) (xy 269.456662 -235.005118) (xy 269.450137 -235.000815) (xy 269.435262 -234.996039)
			(xy 269.427452 -234.99572) (xy 268.911578 -234.99572) (xy 268.90613 -234.995431) (xy 268.898443 -234.987708)
			(xy 268.898116 -234.982258) (xy 206.997808 -234.982258) (xy 206.997808 -234.982512) (xy 206.997313 -234.987776)
			(xy 206.989865 -234.995218) (xy 206.9846 -234.99572) (xy 206.468726 -234.99572) (xy 206.46085 -234.995989)
			(xy 206.445846 -235.000786) (xy 206.439262 -235.005118) (xy 206.418183 -235.019507) (xy 206.372539 -235.042337)
			(xy 206.323933 -235.057896) (xy 206.273517 -235.065815) (xy 206.248 -235.066332) (xy 206.222479 -235.065854)
			(xy 206.172052 -235.057955) (xy 206.123441 -235.042391) (xy 206.077803 -235.019534) (xy 206.056738 -235.005118)
			(xy 206.050139 -235.000817) (xy 206.035145 -234.996021) (xy 206.027274 -234.99572) (xy 205.5114 -234.99572)
			(xy 205.50614 -234.995206) (xy 205.498698 -234.987771) (xy 205.498192 -234.982512) (xy 199.454008 -234.982512)
			(xy 199.453513 -234.987776) (xy 199.446065 -234.995218) (xy 199.4408 -234.99572) (xy 198.924926 -234.99572)
			(xy 198.91705 -234.995989) (xy 198.902046 -235.000786) (xy 198.895462 -235.005118) (xy 198.874383 -235.019507)
			(xy 198.828739 -235.042337) (xy 198.780133 -235.057896) (xy 198.729717 -235.065815) (xy 198.7042 -235.066332)
			(xy 198.678679 -235.065854) (xy 198.628252 -235.057955) (xy 198.579641 -235.042391) (xy 198.534003 -235.019534)
			(xy 198.512938 -235.005118) (xy 198.506339 -235.000817) (xy 198.491345 -234.996021) (xy 198.483474 -234.99572)
			(xy 197.9676 -234.99572) (xy 197.96234 -234.995206) (xy 197.954898 -234.987771) (xy 197.954392 -234.982512)
			(xy 191.910208 -234.982512) (xy 191.909713 -234.987776) (xy 191.902265 -234.995218) (xy 191.897 -234.99572)
			(xy 191.896492 -234.99572) (xy 191.380872 -234.99572) (xy 191.372998 -234.996008) (xy 191.357994 -235.000792)
			(xy 191.351408 -235.005118) (xy 191.330344 -235.019531) (xy 191.284695 -235.042355) (xy 191.236084 -235.057907)
			(xy 191.185664 -235.065819) (xy 191.160146 -235.066332) (xy 191.134626 -235.065831) (xy 191.0842 -235.057939)
			(xy 191.035589 -235.042382) (xy 190.98995 -235.019531) (xy 190.968884 -235.005118) (xy 190.962297 -235.000796)
			(xy 190.947293 -234.996013) (xy 190.93942 -234.99572) (xy 190.423546 -234.99572) (xy 190.418238 -234.995241)
			(xy 190.410662 -234.98781) (xy 190.410084 -234.982512) (xy 184.3659 -234.982512) (xy 184.365412 -234.987778)
			(xy 184.357959 -234.99522) (xy 184.352692 -234.99572) (xy 183.836818 -234.99572) (xy 183.828945 -234.996028)
			(xy 183.813942 -235.000798) (xy 183.807354 -235.005118) (xy 183.786277 -235.019511) (xy 183.740633 -235.04234)
			(xy 183.692026 -235.057897) (xy 183.641609 -235.065816) (xy 183.616092 -235.066332) (xy 183.590573 -235.065807)
			(xy 183.540148 -235.057922) (xy 183.491536 -235.042373) (xy 183.445896 -235.019528) (xy 183.42483 -235.005118)
			(xy 183.418232 -235.000814) (xy 183.403237 -234.99602) (xy 183.395366 -234.99572) (xy 182.879492 -234.99572)
			(xy 182.874231 -234.995212) (xy 182.86679 -234.987773) (xy 182.866284 -234.982512) (xy 176.8221 -234.982512)
			(xy 176.821612 -234.987778) (xy 176.814159 -234.99522) (xy 176.808892 -234.99572) (xy 176.808384 -234.99572)
			(xy 176.292764 -234.99572) (xy 176.284889 -234.996005) (xy 176.269885 -235.000791) (xy 176.2633 -235.005118)
			(xy 176.242211 -235.019491) (xy 176.19657 -235.042324) (xy 176.147968 -235.057888) (xy 176.097554 -235.065812)
			(xy 176.072038 -235.066332) (xy 176.046518 -235.065835) (xy 175.996092 -235.057941) (xy 175.94748 -235.042384)
			(xy 175.901841 -235.019532) (xy 175.880776 -235.005118) (xy 175.87419 -235.000793) (xy 175.859186 -234.996012)
			(xy 175.851312 -234.99572) (xy 175.335438 -234.99572) (xy 175.330129 -234.995247) (xy 175.322554 -234.987811)
			(xy 175.321976 -234.982512) (xy 169.277792 -234.982512) (xy 169.27748 -234.98785) (xy 169.269922 -234.995391)
			(xy 169.264584 -234.99572) (xy 167.791384 -234.99572) (xy 167.786122 -234.995217) (xy 167.778681 -234.987774)
			(xy 167.778176 -234.982512) (xy 107.294907 -234.982512) (xy 107.28843 -234.989547) (xy 107.248525 -235.020602)
			(xy 107.204052 -235.044665) (xy 107.156225 -235.06108) (xy 107.106349 -235.069398) (xy 107.081066 -235.069888)
			(xy 106.141012 -235.069888) (xy 106.115735 -235.069344) (xy 106.06587 -235.061025) (xy 106.018054 -235.044611)
			(xy 105.973592 -235.020551) (xy 105.933697 -234.989501) (xy 105.899456 -234.952307) (xy 105.871805 -234.909985)
			(xy 105.851497 -234.863689) (xy 105.839086 -234.814682) (xy 105.834911 -234.7643) (xy 104.567341 -234.7643)
			(xy 104.563164 -234.814693) (xy 104.55075 -234.863712) (xy 104.530436 -234.910018) (xy 104.502777 -234.952349)
			(xy 104.468527 -234.98955) (xy 104.428621 -235.020605) (xy 104.384147 -235.044668) (xy 104.336319 -235.061081)
			(xy 104.286441 -235.069398) (xy 104.261158 -235.069888) (xy 103.321104 -235.069888) (xy 103.295827 -235.069343)
			(xy 103.245963 -235.061023) (xy 103.198148 -235.044609) (xy 103.153688 -235.020548) (xy 103.113793 -234.989498)
			(xy 103.079554 -234.952305) (xy 103.051904 -234.909983) (xy 103.031596 -234.863688) (xy 103.019186 -234.814681)
			(xy 103.015011 -234.7643) (xy 101.747141 -234.7643) (xy 101.742965 -234.814689) (xy 101.730553 -234.863704)
			(xy 101.710242 -234.910008) (xy 101.682587 -234.952337) (xy 101.648342 -234.989536) (xy 101.608441 -235.020592)
			(xy 101.563973 -235.044656) (xy 101.51615 -235.061074) (xy 101.466277 -235.069395) (xy 101.440996 -235.069888)
			(xy 100.500942 -235.069888) (xy 100.475663 -235.069346) (xy 100.425794 -235.061031) (xy 100.377974 -235.04462)
			(xy 100.333508 -235.020562) (xy 100.293608 -234.989512) (xy 100.259364 -234.952317) (xy 100.23171 -234.909994)
			(xy 100.211399 -234.863695) (xy 100.198987 -234.814685) (xy 100.194811 -234.7643) (xy 98.927241 -234.7643)
			(xy 98.923065 -234.81469) (xy 98.910652 -234.863706) (xy 98.890341 -234.91001) (xy 98.862685 -234.952339)
			(xy 98.828439 -234.989539) (xy 98.788537 -235.020595) (xy 98.744067 -235.044659) (xy 98.696243 -235.061075)
			(xy 98.64637 -235.069396) (xy 98.621088 -235.069888) (xy 97.681034 -235.069888) (xy 97.655756 -235.069346)
			(xy 97.605888 -235.061029) (xy 97.558069 -235.044618) (xy 97.513603 -235.020559) (xy 97.473705 -234.989509)
			(xy 97.439462 -234.952315) (xy 97.411808 -234.909991) (xy 97.391499 -234.863694) (xy 97.379087 -234.814684)
			(xy 97.374911 -234.7643) (xy 60.178188 -234.7643) (xy 60.178188 -234.982512) (xy 60.177879 -234.987851)
			(xy 60.17032 -234.995392) (xy 60.16498 -234.99572) (xy 60.164472 -234.99572) (xy 58.691526 -234.99572)
			(xy 58.686216 -234.995255) (xy 58.678641 -234.987813) (xy 58.678064 -234.982512) (xy 52.63388 -234.982512)
			(xy 52.633578 -234.987853) (xy 52.626014 -234.995395) (xy 52.620672 -234.99572) (xy 52.104798 -234.99572)
			(xy 52.096925 -234.99602) (xy 52.081921 -235.000796) (xy 52.075334 -235.005118) (xy 52.054263 -235.019519)
			(xy 52.008616 -235.042346) (xy 51.960008 -235.057902) (xy 51.909589 -235.065817) (xy 51.884072 -235.066332)
			(xy 51.858553 -235.065817) (xy 51.808127 -235.057929) (xy 51.759516 -235.042377) (xy 51.713876 -235.019529)
			(xy 51.69281 -235.005118) (xy 51.686217 -235.000806) (xy 51.671218 -234.996017) (xy 51.663346 -234.99572)
			(xy 51.147472 -234.99572) (xy 51.142209 -234.995225) (xy 51.134768 -234.987776) (xy 51.134264 -234.982512)
			(xy 45.09008 -234.982512) (xy 45.089778 -234.987853) (xy 45.082214 -234.995395) (xy 45.076872 -234.99572)
			(xy 45.076364 -234.99572) (xy 44.560744 -234.99572) (xy 44.552869 -234.995996) (xy 44.537865 -235.000788)
			(xy 44.53128 -235.005118) (xy 44.510196 -235.0195) (xy 44.464554 -235.042331) (xy 44.41595 -235.057892)
			(xy 44.365534 -235.065814) (xy 44.340018 -235.066332) (xy 44.314498 -235.065845) (xy 44.264071 -235.057948)
			(xy 44.21546 -235.042388) (xy 44.169821 -235.019533) (xy 44.148756 -235.005118) (xy 44.142175 -235.000785)
			(xy 44.127167 -234.996009) (xy 44.119292 -234.99572) (xy 43.603418 -234.99572) (xy 43.598107 -234.99526)
			(xy 43.590532 -234.987814) (xy 43.589956 -234.982512) (xy 37.545772 -234.982512) (xy 37.545478 -234.987855)
			(xy 37.537908 -234.995397) (xy 37.532564 -234.99572) (xy 37.01669 -234.99572) (xy 37.008816 -234.996016)
			(xy 36.993812 -235.000794) (xy 36.987226 -235.005118) (xy 36.966157 -235.019523) (xy 36.92051 -235.042349)
			(xy 36.871901 -235.057903) (xy 36.821482 -235.065818) (xy 36.795964 -235.066332) (xy 36.770445 -235.065821)
			(xy 36.720019 -235.057932) (xy 36.671407 -235.042378) (xy 36.625768 -235.01953) (xy 36.604702 -235.005118)
			(xy 36.598111 -235.000803) (xy 36.58311 -234.996016) (xy 36.575238 -234.99572) (xy 36.059364 -234.99572)
			(xy 36.0541 -234.99523) (xy 36.04666 -234.987777) (xy 36.046156 -234.982512) (xy 30.001972 -234.982512)
			(xy 30.001678 -234.987855) (xy 29.994108 -234.995397) (xy 29.988764 -234.99572) (xy 29.47289 -234.99572)
			(xy 29.465016 -234.996016) (xy 29.450012 -235.000794) (xy 29.443426 -235.005118) (xy 29.422357 -235.019523)
			(xy 29.37671 -235.042349) (xy 29.328101 -235.057903) (xy 29.277682 -235.065818) (xy 29.252164 -235.066332)
			(xy 29.226645 -235.065821) (xy 29.176219 -235.057932) (xy 29.127607 -235.042378) (xy 29.081968 -235.01953)
			(xy 29.060902 -235.005118) (xy 29.054311 -235.000803) (xy 29.03931 -234.996016) (xy 29.031438 -234.99572)
			(xy 28.515564 -234.99572) (xy 28.5103 -234.99523) (xy 28.50286 -234.987777) (xy 28.502356 -234.982512)
			(xy 22.458172 -234.982512) (xy 22.457878 -234.987855) (xy 22.450308 -234.995397) (xy 22.444964 -234.99572)
			(xy 22.444456 -234.99572) (xy 21.928836 -234.99572) (xy 21.92096 -234.995993) (xy 21.905957 -235.000787)
			(xy 21.899372 -235.005118) (xy 21.87829 -235.019503) (xy 21.832647 -235.042334) (xy 21.784043 -235.057894)
			(xy 21.733626 -235.065814) (xy 21.70811 -235.066332) (xy 21.68259 -235.065849) (xy 21.632163 -235.057951)
			(xy 21.583551 -235.042389) (xy 21.537913 -235.019533) (xy 21.516848 -235.005118) (xy 21.510269 -235.000782)
			(xy 21.495259 -234.996008) (xy 21.487384 -234.99572) (xy 20.97151 -234.99572) (xy 20.966198 -234.995265)
			(xy 20.958624 -234.987815) (xy 20.958048 -234.982512) (xy 2.509012 -234.982512) (xy 2.509012 -235.832396)
			(xy 16.85798 -235.832396) (xy 16.85798 -235.337858) (xy 16.858427 -235.332479) (xy 16.86606 -235.324893)
			(xy 16.871442 -235.324396) (xy 17.38757 -235.324396) (xy 17.395379 -235.32407) (xy 17.410251 -235.319293)
			(xy 17.41678 -235.314998) (xy 17.437869 -235.300649) (xy 17.48353 -235.277918) (xy 17.532136 -235.262459)
			(xy 17.582539 -235.254636) (xy 17.633545 -235.254636) (xy 17.683948 -235.262459) (xy 17.732554 -235.277918)
			(xy 17.778215 -235.300649) (xy 17.799304 -235.314998) (xy 17.805835 -235.319289) (xy 17.820706 -235.324072)
			(xy 17.828514 -235.324396) (xy 18.344642 -235.324396) (xy 18.350001 -235.324918) (xy 18.357582 -235.332499)
			(xy 18.358104 -235.337858) (xy 18.358104 -235.832396) (xy 24.402288 -235.832396) (xy 24.402288 -235.337858)
			(xy 24.402701 -235.332537) (xy 24.410182 -235.324966) (xy 24.415496 -235.324396) (xy 24.931624 -235.324396)
			(xy 24.939435 -235.324093) (xy 24.954306 -235.3193) (xy 24.960834 -235.314998) (xy 24.981923 -235.300649)
			(xy 25.027584 -235.277918) (xy 25.07619 -235.262459) (xy 25.126593 -235.254636) (xy 25.177599 -235.254636)
			(xy 25.228002 -235.262459) (xy 25.276608 -235.277918) (xy 25.322269 -235.300649) (xy 25.343358 -235.314998)
			(xy 25.349877 -235.31931) (xy 25.364757 -235.32408) (xy 25.372568 -235.324396) (xy 25.888696 -235.324396)
			(xy 25.894029 -235.32473) (xy 25.90157 -235.332271) (xy 25.901904 -235.337604) (xy 25.901904 -235.338112)
			(xy 25.901904 -235.832396) (xy 31.946088 -235.832396) (xy 31.946088 -235.337858) (xy 31.946501 -235.332537)
			(xy 31.953982 -235.324966) (xy 31.959296 -235.324396) (xy 32.475424 -235.324396) (xy 32.483235 -235.324093)
			(xy 32.498106 -235.3193) (xy 32.504634 -235.314998) (xy 32.525723 -235.300649) (xy 32.571384 -235.277918)
			(xy 32.61999 -235.262459) (xy 32.670393 -235.254636) (xy 32.721399 -235.254636) (xy 32.771802 -235.262459)
			(xy 32.820408 -235.277918) (xy 32.866069 -235.300649) (xy 32.887158 -235.314998) (xy 32.893677 -235.31931)
			(xy 32.908557 -235.32408) (xy 32.916368 -235.324396) (xy 33.432496 -235.324396) (xy 33.437829 -235.32473)
			(xy 33.44537 -235.332271) (xy 33.445704 -235.337604) (xy 33.445704 -235.338112) (xy 33.445704 -235.832396)
			(xy 39.489888 -235.832396) (xy 39.489888 -235.337858) (xy 39.490417 -235.332501) (xy 39.497993 -235.32492)
			(xy 39.50335 -235.324396) (xy 40.019478 -235.324396) (xy 40.027287 -235.324074) (xy 40.042159 -235.319294)
			(xy 40.048688 -235.314998) (xy 40.069777 -235.300649) (xy 40.115438 -235.277918) (xy 40.164044 -235.262459)
			(xy 40.214447 -235.254636) (xy 40.265453 -235.254636) (xy 40.315856 -235.262459) (xy 40.364462 -235.277918)
			(xy 40.410123 -235.300649) (xy 40.431212 -235.314998) (xy 40.437742 -235.319292) (xy 40.452613 -235.324074)
			(xy 40.460422 -235.324396) (xy 40.97655 -235.324396) (xy 40.98191 -235.324913) (xy 40.98949 -235.332498)
			(xy 40.990012 -235.337858) (xy 40.990012 -235.832396) (xy 47.034196 -235.832396) (xy 47.034196 -235.337858)
			(xy 47.03469 -235.332559) (xy 47.042115 -235.324993) (xy 47.047404 -235.324396) (xy 47.563532 -235.324396)
			(xy 47.571339 -235.324054) (xy 47.586211 -235.319287) (xy 47.592742 -235.314998) (xy 47.613831 -235.300649)
			(xy 47.659492 -235.277918) (xy 47.708098 -235.262459) (xy 47.758501 -235.254636) (xy 47.809507 -235.254636)
			(xy 47.85991 -235.262459) (xy 47.908516 -235.277918) (xy 47.954177 -235.300649) (xy 47.975266 -235.314998)
			(xy 47.981806 -235.319275) (xy 47.996669 -235.324067) (xy 48.004476 -235.324396) (xy 48.520604 -235.324396)
			(xy 48.525868 -235.324892) (xy 48.533311 -235.332339) (xy 48.533812 -235.337604) (xy 48.533812 -235.338112)
			(xy 48.533812 -235.832396) (xy 54.577996 -235.832396) (xy 54.577996 -235.337858) (xy 54.578518 -235.332499)
			(xy 54.586099 -235.324918) (xy 54.591458 -235.324396) (xy 56.064658 -235.324396) (xy 56.070007 -235.324974)
			(xy 56.077593 -235.332512) (xy 56.07812 -235.337858) (xy 56.07812 -235.5743) (xy 108.185172 -235.5743)
			(xy 108.189343 -235.52396) (xy 108.201744 -235.474994) (xy 108.222035 -235.428736) (xy 108.249664 -235.38645)
			(xy 108.283876 -235.349288) (xy 108.323739 -235.318264) (xy 108.368164 -235.294225) (xy 108.41594 -235.277826)
			(xy 108.465764 -235.269515) (xy 108.49102 -235.269024) (xy 109.431074 -235.269024) (xy 109.456336 -235.269451)
			(xy 109.506171 -235.277763) (xy 109.553958 -235.294165) (xy 109.598393 -235.318208) (xy 109.638265 -235.349239)
			(xy 109.672485 -235.386409) (xy 109.70012 -235.428704) (xy 109.720416 -235.474972) (xy 109.73282 -235.523949)
			(xy 109.736992 -235.5743) (xy 109.73282 -235.624651) (xy 109.720416 -235.673628) (xy 109.70012 -235.719896)
			(xy 109.672485 -235.762191) (xy 109.638265 -235.799361) (xy 109.598393 -235.830392) (xy 109.594689 -235.832396)
			(xy 163.678108 -235.832396) (xy 163.678108 -235.337858) (xy 163.678591 -235.332556) (xy 163.686024 -235.324989)
			(xy 163.691316 -235.324396) (xy 165.164516 -235.324396) (xy 165.169782 -235.324884) (xy 165.177224 -235.332338)
			(xy 165.177724 -235.337604) (xy 165.177724 -235.338112) (xy 165.177724 -235.832396) (xy 171.221908 -235.832396)
			(xy 171.221908 -235.337858) (xy 171.222419 -235.332496) (xy 171.230008 -235.324915) (xy 171.23537 -235.324396)
			(xy 171.751498 -235.324396) (xy 171.759308 -235.324082) (xy 171.774179 -235.319296) (xy 171.780708 -235.314998)
			(xy 171.801797 -235.300649) (xy 171.847458 -235.277918) (xy 171.896064 -235.262459) (xy 171.946467 -235.254636)
			(xy 171.997473 -235.254636) (xy 172.047876 -235.262459) (xy 172.096482 -235.277918) (xy 172.142143 -235.300649)
			(xy 172.163232 -235.314998) (xy 172.169757 -235.3193) (xy 172.184632 -235.324076) (xy 172.192442 -235.324396)
			(xy 172.70857 -235.324396) (xy 172.71392 -235.324966) (xy 172.721505 -235.332511) (xy 172.722032 -235.337858)
			(xy 172.722032 -235.832396) (xy 178.766216 -235.832396) (xy 178.766216 -235.337858) (xy 178.766692 -235.332554)
			(xy 178.77413 -235.324987) (xy 178.779424 -235.324396) (xy 179.295552 -235.324396) (xy 179.30336 -235.324063)
			(xy 179.318232 -235.31929) (xy 179.324762 -235.314998) (xy 179.345851 -235.300649) (xy 179.391512 -235.277918)
			(xy 179.440118 -235.262459) (xy 179.490521 -235.254636) (xy 179.541527 -235.254636) (xy 179.59193 -235.262459)
			(xy 179.640536 -235.277918) (xy 179.686197 -235.300649) (xy 179.707286 -235.314998) (xy 179.713821 -235.319283)
			(xy 179.728688 -235.32407) (xy 179.736496 -235.324396) (xy 180.252624 -235.324396) (xy 180.257891 -235.324879)
			(xy 180.265332 -235.332336) (xy 180.265832 -235.337604) (xy 180.265832 -235.338112) (xy 180.265832 -235.832396)
			(xy 186.310016 -235.832396) (xy 186.310016 -235.337858) (xy 186.31052 -235.332494) (xy 186.318114 -235.324912)
			(xy 186.323478 -235.324396) (xy 186.839606 -235.324396) (xy 186.847416 -235.324086) (xy 186.862288 -235.319297)
			(xy 186.868816 -235.314998) (xy 186.889905 -235.300649) (xy 186.935566 -235.277918) (xy 186.984172 -235.262459)
			(xy 187.034575 -235.254636) (xy 187.085581 -235.254636) (xy 187.135984 -235.262459) (xy 187.18459 -235.277918)
			(xy 187.230251 -235.300649) (xy 187.25134 -235.314998) (xy 187.257863 -235.319303) (xy 187.27274 -235.324078)
			(xy 187.28055 -235.324396) (xy 187.796678 -235.324396) (xy 187.802029 -235.324961) (xy 187.809614 -235.332509)
			(xy 187.81014 -235.337858) (xy 187.81014 -235.832396) (xy 193.854324 -235.832396) (xy 193.854324 -235.337858)
			(xy 193.854793 -235.332552) (xy 193.862236 -235.324985) (xy 193.867532 -235.324396) (xy 194.38366 -235.324396)
			(xy 194.391469 -235.324066) (xy 194.40634 -235.319291) (xy 194.41287 -235.314998) (xy 194.433959 -235.300649)
			(xy 194.47962 -235.277918) (xy 194.528226 -235.262459) (xy 194.578629 -235.254636) (xy 194.629635 -235.254636)
			(xy 194.680038 -235.262459) (xy 194.728644 -235.277918) (xy 194.774305 -235.300649) (xy 194.795394 -235.314998)
			(xy 194.801928 -235.319286) (xy 194.816796 -235.324071) (xy 194.824604 -235.324396) (xy 195.340732 -235.324396)
			(xy 195.346 -235.324874) (xy 195.353441 -235.332335) (xy 195.35394 -235.337604) (xy 195.35394 -235.338112)
			(xy 195.35394 -235.832396) (xy 201.398124 -235.832396) (xy 201.398124 -235.337858) (xy 201.398593 -235.332552)
			(xy 201.406036 -235.324985) (xy 201.411332 -235.324396) (xy 201.92746 -235.324396) (xy 201.935269 -235.324066)
			(xy 201.95014 -235.319291) (xy 201.95667 -235.314998) (xy 201.977759 -235.300649) (xy 202.02342 -235.277918)
			(xy 202.072026 -235.262459) (xy 202.122429 -235.254636) (xy 202.173435 -235.254636) (xy 202.223838 -235.262459)
			(xy 202.272444 -235.277918) (xy 202.318105 -235.300649) (xy 202.339194 -235.314998) (xy 202.345728 -235.319286)
			(xy 202.360596 -235.324071) (xy 202.368404 -235.324396) (xy 202.884532 -235.324396) (xy 202.8898 -235.324874)
			(xy 202.897241 -235.332335) (xy 202.89774 -235.337604) (xy 202.89774 -235.338112) (xy 202.89774 -235.832142)
			(xy 264.798048 -235.832142) (xy 264.798048 -235.337604) (xy 264.798593 -235.332352) (xy 264.806006 -235.324912)
			(xy 264.811256 -235.324396) (xy 264.811764 -235.324396) (xy 265.327638 -235.324396) (xy 265.335446 -235.324057)
			(xy 265.350317 -235.319289) (xy 265.356848 -235.314998) (xy 265.377937 -235.300649) (xy 265.423598 -235.277918)
			(xy 265.472204 -235.262459) (xy 265.522607 -235.254636) (xy 265.573613 -235.254636) (xy 265.624016 -235.262459)
			(xy 265.672622 -235.277918) (xy 265.718283 -235.300649) (xy 265.739372 -235.314998) (xy 265.745911 -235.319277)
			(xy 265.760775 -235.324068) (xy 265.768582 -235.324396) (xy 266.28471 -235.324396) (xy 266.290005 -235.324911)
			(xy 266.297573 -235.33232) (xy 266.298172 -235.337604) (xy 266.298172 -235.832142) (xy 266.298149 -235.832396)
			(xy 272.342356 -235.832396) (xy 272.342356 -235.831888) (xy 272.342356 -235.337604) (xy 272.342894 -235.33235)
			(xy 272.350312 -235.32491) (xy 272.355564 -235.324396) (xy 272.871692 -235.324396) (xy 272.879502 -235.32408)
			(xy 272.894373 -235.319296) (xy 272.900902 -235.314998) (xy 272.921991 -235.300649) (xy 272.967652 -235.277918)
			(xy 273.016258 -235.262459) (xy 273.066661 -235.254636) (xy 273.117667 -235.254636) (xy 273.16807 -235.262459)
			(xy 273.216676 -235.277918) (xy 273.262337 -235.300649) (xy 273.283426 -235.314998) (xy 273.289953 -235.319298)
			(xy 273.304826 -235.324076) (xy 273.312636 -235.324396) (xy 273.828764 -235.324396) (xy 273.834092 -235.324751)
			(xy 273.841636 -235.332276) (xy 273.841972 -235.337604) (xy 273.841972 -235.832142) (xy 273.84195 -235.832396)
			(xy 279.886156 -235.832396) (xy 279.886156 -235.831888) (xy 279.886156 -235.337604) (xy 279.886694 -235.33235)
			(xy 279.894112 -235.32491) (xy 279.899364 -235.324396) (xy 280.415492 -235.324396) (xy 280.423302 -235.32408)
			(xy 280.438173 -235.319296) (xy 280.444702 -235.314998) (xy 280.465791 -235.300649) (xy 280.511452 -235.277918)
			(xy 280.560058 -235.262459) (xy 280.610461 -235.254636) (xy 280.661467 -235.254636) (xy 280.71187 -235.262459)
			(xy 280.760476 -235.277918) (xy 280.806137 -235.300649) (xy 280.827226 -235.314998) (xy 280.833753 -235.319298)
			(xy 280.848626 -235.324076) (xy 280.856436 -235.324396) (xy 281.372564 -235.324396) (xy 281.377892 -235.324751)
			(xy 281.385436 -235.332276) (xy 281.385772 -235.337604) (xy 281.385772 -235.832142) (xy 287.429956 -235.832142)
			(xy 287.429956 -235.337604) (xy 287.430494 -235.33235) (xy 287.437912 -235.32491) (xy 287.443164 -235.324396)
			(xy 287.443672 -235.324396) (xy 287.959546 -235.324396) (xy 287.967354 -235.32406) (xy 287.982226 -235.31929)
			(xy 287.988756 -235.314998) (xy 288.009845 -235.300649) (xy 288.055506 -235.277918) (xy 288.104112 -235.262459)
			(xy 288.154515 -235.254636) (xy 288.205521 -235.254636) (xy 288.255924 -235.262459) (xy 288.30453 -235.277918)
			(xy 288.350191 -235.300649) (xy 288.37128 -235.314998) (xy 288.377817 -235.31928) (xy 288.392683 -235.324069)
			(xy 288.40049 -235.324396) (xy 288.916618 -235.324396) (xy 288.921914 -235.324906) (xy 288.929482 -235.332319)
			(xy 288.93008 -235.337604) (xy 288.93008 -235.832142) (xy 288.930056 -235.832396) (xy 294.974264 -235.832396)
			(xy 294.974264 -235.831888) (xy 294.974264 -235.337604) (xy 294.974794 -235.332348) (xy 294.982218 -235.324907)
			(xy 294.987472 -235.324396) (xy 295.5036 -235.324396) (xy 295.51141 -235.324083) (xy 295.526282 -235.319297)
			(xy 295.53281 -235.314998) (xy 295.553899 -235.300649) (xy 295.59956 -235.277918) (xy 295.648166 -235.262459)
			(xy 295.698569 -235.254636) (xy 295.749575 -235.254636) (xy 295.799978 -235.262459) (xy 295.848584 -235.277918)
			(xy 295.894245 -235.300649) (xy 295.915334 -235.314998) (xy 295.921859 -235.319301) (xy 295.936734 -235.324077)
			(xy 295.944544 -235.324396) (xy 296.460672 -235.324396) (xy 296.466002 -235.324746) (xy 296.473544 -235.332275)
			(xy 296.47388 -235.337604) (xy 296.47388 -235.832142) (xy 302.518064 -235.832142) (xy 302.518064 -235.337604)
			(xy 302.518594 -235.332348) (xy 302.526018 -235.324907) (xy 302.531272 -235.324396) (xy 304.004726 -235.324396)
			(xy 304.010023 -235.3249) (xy 304.01759 -235.332318) (xy 304.018188 -235.337604) (xy 304.018188 -235.5741)
			(xy 361.758663 -235.5741) (xy 361.762839 -235.523711) (xy 361.775251 -235.474696) (xy 361.795562 -235.428393)
			(xy 361.823217 -235.386064) (xy 361.857462 -235.348865) (xy 361.897363 -235.31781) (xy 361.941832 -235.293746)
			(xy 361.989654 -235.27733) (xy 362.039527 -235.269008) (xy 362.064808 -235.268516) (xy 363.004862 -235.268516)
			(xy 363.030141 -235.26905) (xy 363.08001 -235.277366) (xy 363.12783 -235.293777) (xy 363.172297 -235.317836)
			(xy 363.212196 -235.348887) (xy 363.24644 -235.386081) (xy 363.274095 -235.428406) (xy 363.294405 -235.474704)
			(xy 363.306817 -235.523715) (xy 363.310993 -235.5741) (xy 363.306817 -235.624485) (xy 363.294405 -235.673496)
			(xy 363.274095 -235.719795) (xy 363.24644 -235.762119) (xy 363.212196 -235.799313) (xy 363.172297 -235.830364)
			(xy 363.168541 -235.832396) (xy 411.618176 -235.832396) (xy 411.618176 -235.831888) (xy 411.618176 -235.337604)
			(xy 411.618696 -235.332346) (xy 411.626126 -235.324904) (xy 411.631384 -235.324396) (xy 413.104584 -235.324396)
			(xy 413.109915 -235.324738) (xy 413.117457 -235.332273) (xy 413.117792 -235.337604) (xy 413.117792 -235.832142)
			(xy 419.161976 -235.832142) (xy 419.161976 -235.337604) (xy 419.162496 -235.332346) (xy 419.169926 -235.324904)
			(xy 419.175184 -235.324396) (xy 419.175692 -235.324396) (xy 419.691566 -235.324396) (xy 419.699375 -235.324069)
			(xy 419.714246 -235.319292) (xy 419.720776 -235.314998) (xy 419.741865 -235.300649) (xy 419.787526 -235.277918)
			(xy 419.836132 -235.262459) (xy 419.886535 -235.254636) (xy 419.937541 -235.254636) (xy 419.987944 -235.262459)
			(xy 420.03655 -235.277918) (xy 420.082211 -235.300649) (xy 420.1033 -235.314998) (xy 420.109832 -235.319288)
			(xy 420.124702 -235.324072) (xy 420.13251 -235.324396) (xy 420.648638 -235.324396) (xy 420.653937 -235.324892)
			(xy 420.661503 -235.332316) (xy 420.6621 -235.337604) (xy 420.6621 -235.832142) (xy 420.662075 -235.832396)
			(xy 426.706284 -235.832396) (xy 426.706284 -235.831888) (xy 426.706284 -235.337604) (xy 426.706797 -235.332344)
			(xy 426.714232 -235.324901) (xy 426.719492 -235.324396) (xy 427.23562 -235.324396) (xy 427.243431 -235.324091)
			(xy 427.258302 -235.319299) (xy 427.26483 -235.314998) (xy 427.285919 -235.300649) (xy 427.33158 -235.277918)
			(xy 427.380186 -235.262459) (xy 427.430589 -235.254636) (xy 427.481595 -235.254636) (xy 427.531998 -235.262459)
			(xy 427.580604 -235.277918) (xy 427.626265 -235.300649) (xy 427.647354 -235.314998) (xy 427.653874 -235.319309)
			(xy 427.668753 -235.32408) (xy 427.676564 -235.324396) (xy 428.192692 -235.324396) (xy 428.198024 -235.324732)
			(xy 428.205566 -235.332272) (xy 428.2059 -235.337604) (xy 428.2059 -235.832142) (xy 434.250084 -235.832142)
			(xy 434.250084 -235.337604) (xy 434.250597 -235.332344) (xy 434.258032 -235.324901) (xy 434.263292 -235.324396)
			(xy 434.2638 -235.324396) (xy 434.779674 -235.324396) (xy 434.787483 -235.324072) (xy 434.802355 -235.319293)
			(xy 434.808884 -235.314998) (xy 434.829973 -235.300649) (xy 434.875634 -235.277918) (xy 434.92424 -235.262459)
			(xy 434.974643 -235.254636) (xy 435.025649 -235.254636) (xy 435.076052 -235.262459) (xy 435.124658 -235.277918)
			(xy 435.170319 -235.300649) (xy 435.191408 -235.314998) (xy 435.197939 -235.319291) (xy 435.212809 -235.324073)
			(xy 435.220618 -235.324396) (xy 435.736746 -235.324396) (xy 435.742034 -235.324954) (xy 435.749605 -235.332331)
			(xy 435.750208 -235.337604) (xy 435.750208 -235.832142) (xy 435.750183 -235.832396) (xy 441.794392 -235.832396)
			(xy 441.794392 -235.831888) (xy 441.794392 -235.337604) (xy 441.79473 -235.332272) (xy 441.802268 -235.324731)
			(xy 441.8076 -235.324396) (xy 442.323728 -235.324396) (xy 442.331539 -235.324095) (xy 442.346411 -235.3193)
			(xy 442.352938 -235.314998) (xy 442.374027 -235.300649) (xy 442.419688 -235.277918) (xy 442.468294 -235.262459)
			(xy 442.518697 -235.254636) (xy 442.569703 -235.254636) (xy 442.620106 -235.262459) (xy 442.668712 -235.277918)
			(xy 442.714373 -235.300649) (xy 442.735462 -235.314998) (xy 442.742003 -235.319273) (xy 442.756866 -235.324066)
			(xy 442.764672 -235.324396) (xy 443.2808 -235.324396) (xy 443.286133 -235.324727) (xy 443.293675 -235.332271)
			(xy 443.294008 -235.337604) (xy 443.294008 -235.832142) (xy 443.293984 -235.832396) (xy 449.338192 -235.832396)
			(xy 449.338192 -235.831888) (xy 449.338192 -235.337604) (xy 449.33853 -235.332272) (xy 449.346068 -235.324731)
			(xy 449.3514 -235.324396) (xy 449.867528 -235.324396) (xy 449.875339 -235.324095) (xy 449.890211 -235.3193)
			(xy 449.896738 -235.314998) (xy 449.917827 -235.300649) (xy 449.963488 -235.277918) (xy 450.012094 -235.262459)
			(xy 450.062497 -235.254636) (xy 450.113503 -235.254636) (xy 450.163906 -235.262459) (xy 450.212512 -235.277918)
			(xy 450.258173 -235.300649) (xy 450.279262 -235.314998) (xy 450.285803 -235.319273) (xy 450.300666 -235.324066)
			(xy 450.308472 -235.324396) (xy 450.8246 -235.324396) (xy 450.829933 -235.324727) (xy 450.837475 -235.332271)
			(xy 450.837808 -235.337604) (xy 450.837808 -235.832142) (xy 450.837311 -235.83744) (xy 450.829888 -235.845006)
			(xy 450.8246 -235.845604) (xy 450.308726 -235.845604) (xy 450.300917 -235.845928) (xy 450.286045 -235.850707)
			(xy 450.279516 -235.855002) (xy 450.258384 -235.869335) (xy 450.212664 -235.892067) (xy 450.163994 -235.907502)
			(xy 450.11353 -235.915273) (xy 450.088 -235.915708) (xy 450.06247 -235.915264) (xy 450.012007 -235.907489)
			(xy 449.963335 -235.892062) (xy 449.917607 -235.869348) (xy 449.896484 -235.855002) (xy 449.889955 -235.850706)
			(xy 449.875083 -235.845926) (xy 449.867274 -235.845604) (xy 449.3514 -235.845604) (xy 449.346067 -235.845273)
			(xy 449.338525 -235.837729) (xy 449.338192 -235.832396) (xy 443.293984 -235.832396) (xy 443.293511 -235.83744)
			(xy 443.286088 -235.845006) (xy 443.2808 -235.845604) (xy 442.764926 -235.845604) (xy 442.757117 -235.845928)
			(xy 442.742245 -235.850707) (xy 442.735716 -235.855002) (xy 442.714584 -235.869335) (xy 442.668864 -235.892067)
			(xy 442.620194 -235.907502) (xy 442.56973 -235.915273) (xy 442.5442 -235.915708) (xy 442.51867 -235.915264)
			(xy 442.468207 -235.907489) (xy 442.419535 -235.892062) (xy 442.373807 -235.869348) (xy 442.352684 -235.855002)
			(xy 442.346155 -235.850706) (xy 442.331283 -235.845926) (xy 442.323474 -235.845604) (xy 441.8076 -235.845604)
			(xy 441.802267 -235.845273) (xy 441.794725 -235.837729) (xy 441.794392 -235.832396) (xy 435.750183 -235.832396)
			(xy 435.749682 -235.8375) (xy 435.742104 -235.845081) (xy 435.736746 -235.845604) (xy 435.220872 -235.845604)
			(xy 435.213061 -235.845905) (xy 435.198189 -235.8507) (xy 435.191662 -235.855002) (xy 435.170545 -235.869358)
			(xy 435.12482 -235.892085) (xy 435.076145 -235.907513) (xy 435.025677 -235.915277) (xy 435.000146 -235.915708)
			(xy 434.974617 -235.915241) (xy 434.924155 -235.907473) (xy 434.875482 -235.892052) (xy 434.829753 -235.869345)
			(xy 434.80863 -235.855002) (xy 434.802091 -235.850724) (xy 434.787227 -235.845933) (xy 434.77942 -235.845604)
			(xy 434.263546 -235.845604) (xy 434.258127 -235.845194) (xy 434.250441 -235.837558) (xy 434.250084 -235.832142)
			(xy 428.2059 -235.832142) (xy 428.20541 -235.837442) (xy 428.197982 -235.845008) (xy 428.192692 -235.845604)
			(xy 427.676818 -235.845604) (xy 427.669009 -235.845925) (xy 427.654137 -235.850706) (xy 427.647608 -235.855002)
			(xy 427.626478 -235.869338) (xy 427.580758 -235.892069) (xy 427.532087 -235.907503) (xy 427.481622 -235.915273)
			(xy 427.456092 -235.915708) (xy 427.430562 -235.915268) (xy 427.380099 -235.907492) (xy 427.331426 -235.892063)
			(xy 427.285698 -235.869348) (xy 427.264576 -235.855002) (xy 427.258049 -235.850703) (xy 427.243176 -235.845925)
			(xy 427.235366 -235.845604) (xy 426.719492 -235.845604) (xy 426.714227 -235.84511) (xy 426.706785 -235.837661)
			(xy 426.706284 -235.832396) (xy 420.662075 -235.832396) (xy 420.661581 -235.837502) (xy 420.653998 -235.845083)
			(xy 420.648638 -235.845604) (xy 420.132764 -235.845604) (xy 420.124956 -235.845944) (xy 420.110085 -235.850712)
			(xy 420.103554 -235.855002) (xy 420.082439 -235.869361) (xy 420.036713 -235.892087) (xy 419.988038 -235.907515)
			(xy 419.93757 -235.915277) (xy 419.912038 -235.915708) (xy 419.886509 -235.915245) (xy 419.836046 -235.907476)
			(xy 419.787374 -235.892054) (xy 419.741645 -235.869345) (xy 419.720522 -235.855002) (xy 419.713985 -235.850721)
			(xy 419.699119 -235.845931) (xy 419.691312 -235.845604) (xy 419.175438 -235.845604) (xy 419.170089 -235.845029)
			(xy 419.162503 -235.837488) (xy 419.161976 -235.832142) (xy 413.117792 -235.832142) (xy 413.117309 -235.837444)
			(xy 413.109876 -235.845011) (xy 413.104584 -235.845604) (xy 411.631384 -235.845604) (xy 411.626118 -235.845116)
			(xy 411.618676 -235.837662) (xy 411.618176 -235.832396) (xy 363.168541 -235.832396) (xy 363.12783 -235.854423)
			(xy 363.08001 -235.870834) (xy 363.030141 -235.87915) (xy 363.004862 -235.87964) (xy 362.064808 -235.87964)
			(xy 362.039527 -235.879192) (xy 361.989654 -235.87087) (xy 361.941832 -235.854454) (xy 361.897363 -235.83039)
			(xy 361.857462 -235.799335) (xy 361.823217 -235.762136) (xy 361.795562 -235.719807) (xy 361.775251 -235.673504)
			(xy 361.762839 -235.624489) (xy 361.758663 -235.5741) (xy 304.018188 -235.5741) (xy 304.018188 -235.832142)
			(xy 304.01768 -235.837505) (xy 304.010089 -235.845087) (xy 304.004726 -235.845604) (xy 302.531526 -235.845604)
			(xy 302.526175 -235.845037) (xy 302.518591 -235.83749) (xy 302.518064 -235.832142) (xy 296.47388 -235.832142)
			(xy 296.473407 -235.837447) (xy 296.465967 -235.845014) (xy 296.460672 -235.845604) (xy 295.944798 -235.845604)
			(xy 295.936988 -235.845916) (xy 295.922116 -235.850703) (xy 295.915588 -235.855002) (xy 295.894463 -235.869347)
			(xy 295.848741 -235.892076) (xy 295.800069 -235.907508) (xy 295.749603 -235.915275) (xy 295.724072 -235.915708)
			(xy 295.698542 -235.915278) (xy 295.648078 -235.907499) (xy 295.599406 -235.892067) (xy 295.553678 -235.86935)
			(xy 295.532556 -235.855002) (xy 295.526033 -235.850695) (xy 295.511157 -235.845922) (xy 295.503346 -235.845604)
			(xy 294.987472 -235.845604) (xy 294.982205 -235.845124) (xy 294.974764 -235.837664) (xy 294.974264 -235.832396)
			(xy 288.930056 -235.832396) (xy 288.929579 -235.837507) (xy 288.921984 -235.845089) (xy 288.916618 -235.845604)
			(xy 288.400744 -235.845604) (xy 288.392936 -235.845936) (xy 288.378064 -235.850709) (xy 288.371534 -235.855002)
			(xy 288.350424 -235.86937) (xy 288.304697 -235.892094) (xy 288.25602 -235.907519) (xy 288.20555 -235.915279)
			(xy 288.180018 -235.915708) (xy 288.154488 -235.915255) (xy 288.104026 -235.907483) (xy 288.055353 -235.892058)
			(xy 288.009625 -235.869347) (xy 287.988502 -235.855002) (xy 287.981969 -235.850713) (xy 287.9671 -235.845929)
			(xy 287.959292 -235.845604) (xy 287.443418 -235.845604) (xy 287.438066 -235.845042) (xy 287.430482 -235.837491)
			(xy 287.429956 -235.832142) (xy 281.385772 -235.832142) (xy 281.385306 -235.837449) (xy 281.377862 -235.845017)
			(xy 281.372564 -235.845604) (xy 280.85669 -235.845604) (xy 280.848879 -235.845913) (xy 280.834008 -235.850702)
			(xy 280.82748 -235.855002) (xy 280.806358 -235.86935) (xy 280.760635 -235.892079) (xy 280.711961 -235.907509)
			(xy 280.661495 -235.915275) (xy 280.635964 -235.915708) (xy 280.610433 -235.915282) (xy 280.55997 -235.907501)
			(xy 280.511297 -235.892069) (xy 280.46557 -235.86935) (xy 280.444448 -235.855002) (xy 280.437927 -235.850692)
			(xy 280.423049 -235.845921) (xy 280.415238 -235.845604) (xy 279.899364 -235.845604) (xy 279.894096 -235.845129)
			(xy 279.886655 -235.837665) (xy 279.886156 -235.832396) (xy 273.84195 -235.832396) (xy 273.841506 -235.837449)
			(xy 273.834062 -235.845017) (xy 273.828764 -235.845604) (xy 273.31289 -235.845604) (xy 273.305079 -235.845913)
			(xy 273.290208 -235.850702) (xy 273.28368 -235.855002) (xy 273.262558 -235.86935) (xy 273.216835 -235.892079)
			(xy 273.168161 -235.907509) (xy 273.117695 -235.915275) (xy 273.092164 -235.915708) (xy 273.066633 -235.915282)
			(xy 273.01617 -235.907501) (xy 272.967497 -235.892069) (xy 272.92177 -235.86935) (xy 272.900648 -235.855002)
			(xy 272.894127 -235.850692) (xy 272.879249 -235.845921) (xy 272.871438 -235.845604) (xy 272.355564 -235.845604)
			(xy 272.350296 -235.845129) (xy 272.342855 -235.837665) (xy 272.342356 -235.832396) (xy 266.298149 -235.832396)
			(xy 266.297679 -235.837509) (xy 266.290078 -235.845091) (xy 266.28471 -235.845604) (xy 265.768836 -235.845604)
			(xy 265.761027 -235.845932) (xy 265.746156 -235.850708) (xy 265.739626 -235.855002) (xy 265.718491 -235.86933)
			(xy 265.672772 -235.892063) (xy 265.624103 -235.907499) (xy 265.57364 -235.915272) (xy 265.54811 -235.915708)
			(xy 265.52258 -235.915259) (xy 265.472117 -235.907485) (xy 265.423445 -235.89206) (xy 265.377717 -235.869347)
			(xy 265.356594 -235.855002) (xy 265.350063 -235.85071) (xy 265.335193 -235.845927) (xy 265.327384 -235.845604)
			(xy 264.81151 -235.845604) (xy 264.806157 -235.845047) (xy 264.798574 -235.837493) (xy 264.798048 -235.832142)
			(xy 202.89774 -235.832142) (xy 202.89774 -235.832396) (xy 202.897206 -235.837651) (xy 202.889785 -235.845092)
			(xy 202.884532 -235.845604) (xy 202.368658 -235.845604) (xy 202.360783 -235.845889) (xy 202.34578 -235.850675)
			(xy 202.339194 -235.855002) (xy 202.318105 -235.869376) (xy 202.272465 -235.892209) (xy 202.223862 -235.907773)
			(xy 202.173448 -235.915696) (xy 202.147932 -235.916216) (xy 202.122412 -235.915724) (xy 202.071985 -235.90783)
			(xy 202.023374 -235.892271) (xy 201.977735 -235.869417) (xy 201.95667 -235.855002) (xy 201.950087 -235.850673)
			(xy 201.93508 -235.845895) (xy 201.927206 -235.845604) (xy 201.411332 -235.845604) (xy 201.406003 -235.845251)
			(xy 201.39846 -235.837724) (xy 201.398124 -235.832396) (xy 195.35394 -235.832396) (xy 195.353406 -235.837651)
			(xy 195.345985 -235.845092) (xy 195.340732 -235.845604) (xy 194.824858 -235.845604) (xy 194.816983 -235.845889)
			(xy 194.80198 -235.850675) (xy 194.795394 -235.855002) (xy 194.774305 -235.869376) (xy 194.728665 -235.892209)
			(xy 194.680062 -235.907773) (xy 194.629648 -235.915696) (xy 194.604132 -235.916216) (xy 194.578612 -235.915724)
			(xy 194.528185 -235.90783) (xy 194.479574 -235.892271) (xy 194.433935 -235.869417) (xy 194.41287 -235.855002)
			(xy 194.406287 -235.850673) (xy 194.39128 -235.845895) (xy 194.383406 -235.845604) (xy 193.867532 -235.845604)
			(xy 193.862203 -235.845251) (xy 193.85466 -235.837724) (xy 193.854324 -235.832396) (xy 187.81014 -235.832396)
			(xy 187.809606 -235.837651) (xy 187.802185 -235.845092) (xy 187.796932 -235.845604) (xy 187.796424 -235.845604)
			(xy 187.280804 -235.845604) (xy 187.272931 -235.845909) (xy 187.257927 -235.850681) (xy 187.25134 -235.855002)
			(xy 187.230266 -235.869399) (xy 187.18462 -235.892227) (xy 187.136013 -235.907784) (xy 187.085595 -235.915701)
			(xy 187.060078 -235.916216) (xy 187.034559 -235.915701) (xy 186.984133 -235.907814) (xy 186.935521 -235.892261)
			(xy 186.889882 -235.869414) (xy 186.868816 -235.855002) (xy 186.862223 -235.85069) (xy 186.847224 -235.845901)
			(xy 186.839352 -235.845604) (xy 186.323478 -235.845604) (xy 186.318181 -235.845097) (xy 186.310614 -235.837682)
			(xy 186.310016 -235.832396) (xy 180.265832 -235.832396) (xy 180.265305 -235.837652) (xy 180.257879 -235.845094)
			(xy 180.252624 -235.845604) (xy 179.73675 -235.845604) (xy 179.728875 -235.845885) (xy 179.713871 -235.850674)
			(xy 179.707286 -235.855002) (xy 179.686199 -235.869379) (xy 179.640558 -235.892212) (xy 179.591955 -235.907774)
			(xy 179.54154 -235.915697) (xy 179.516024 -235.916216) (xy 179.490504 -235.915728) (xy 179.440077 -235.907833)
			(xy 179.391465 -235.892272) (xy 179.345827 -235.869417) (xy 179.324762 -235.855002) (xy 179.318181 -235.85067)
			(xy 179.303173 -235.845894) (xy 179.295298 -235.845604) (xy 178.779424 -235.845604) (xy 178.774094 -235.845257)
			(xy 178.766551 -235.837725) (xy 178.766216 -235.832396) (xy 172.722032 -235.832396) (xy 172.721505 -235.837652)
			(xy 172.714079 -235.845094) (xy 172.708824 -235.845604) (xy 172.708316 -235.845604) (xy 172.192696 -235.845604)
			(xy 172.184823 -235.845905) (xy 172.169819 -235.85068) (xy 172.163232 -235.855002) (xy 172.14216 -235.869402)
			(xy 172.096514 -235.89223) (xy 172.047906 -235.907786) (xy 171.997487 -235.915701) (xy 171.97197 -235.916216)
			(xy 171.946451 -235.915705) (xy 171.896025 -235.907817) (xy 171.847413 -235.892263) (xy 171.801774 -235.869414)
			(xy 171.780708 -235.855002) (xy 171.774116 -235.850687) (xy 171.759116 -235.8459) (xy 171.751244 -235.845604)
			(xy 171.23537 -235.845604) (xy 171.230072 -235.845102) (xy 171.222505 -235.837683) (xy 171.221908 -235.832396)
			(xy 165.177724 -235.832396) (xy 165.177204 -235.837654) (xy 165.169774 -235.845096) (xy 165.164516 -235.845604)
			(xy 163.691316 -235.845604) (xy 163.685985 -235.845262) (xy 163.678443 -235.837727) (xy 163.678108 -235.832396)
			(xy 109.594689 -235.832396) (xy 109.553958 -235.854435) (xy 109.506171 -235.870837) (xy 109.456336 -235.879149)
			(xy 109.431074 -235.87964) (xy 108.49102 -235.87964) (xy 108.465764 -235.879085) (xy 108.41594 -235.870774)
			(xy 108.368164 -235.854375) (xy 108.323739 -235.830336) (xy 108.283876 -235.799312) (xy 108.249664 -235.76215)
			(xy 108.222035 -235.719864) (xy 108.201744 -235.673606) (xy 108.189343 -235.62464) (xy 108.185172 -235.5743)
			(xy 56.07812 -235.5743) (xy 56.07812 -235.832396) (xy 56.077604 -235.837655) (xy 56.070171 -235.845098)
			(xy 56.064912 -235.845604) (xy 54.591458 -235.845604) (xy 54.586159 -235.84511) (xy 54.578593 -235.837685)
			(xy 54.577996 -235.832396) (xy 48.533812 -235.832396) (xy 48.533303 -235.837657) (xy 48.525865 -235.8451)
			(xy 48.520604 -235.845604) (xy 48.00473 -235.845604) (xy 47.996854 -235.845877) (xy 47.981851 -235.850672)
			(xy 47.975266 -235.855002) (xy 47.954185 -235.869388) (xy 47.908542 -235.892219) (xy 47.859937 -235.907778)
			(xy 47.80952 -235.915699) (xy 47.784004 -235.916216) (xy 47.758483 -235.915738) (xy 47.708056 -235.90784)
			(xy 47.659445 -235.892276) (xy 47.613807 -235.869418) (xy 47.592742 -235.855002) (xy 47.586165 -235.850662)
			(xy 47.571154 -235.845891) (xy 47.563278 -235.845604) (xy 47.047404 -235.845604) (xy 47.042071 -235.84527)
			(xy 47.03453 -235.837729) (xy 47.034196 -235.832396) (xy 40.990012 -235.832396) (xy 40.989503 -235.837657)
			(xy 40.982065 -235.8451) (xy 40.976804 -235.845604) (xy 40.976296 -235.845604) (xy 40.460676 -235.845604)
			(xy 40.452802 -235.845897) (xy 40.437798 -235.850678) (xy 40.431212 -235.855002) (xy 40.410146 -235.869411)
			(xy 40.364497 -235.892237) (xy 40.315888 -235.90779) (xy 40.265468 -235.915703) (xy 40.23995 -235.916216)
			(xy 40.21443 -235.915715) (xy 40.164004 -235.907824) (xy 40.115392 -235.892267) (xy 40.069753 -235.869415)
			(xy 40.048688 -235.855002) (xy 40.042101 -235.85068) (xy 40.027097 -235.845897) (xy 40.019224 -235.845604)
			(xy 39.50335 -235.845604) (xy 39.498062 -235.845048) (xy 39.490491 -235.83767) (xy 39.489888 -235.832396)
			(xy 33.445704 -235.832396) (xy 33.44537 -235.837729) (xy 33.437829 -235.84527) (xy 33.432496 -235.845604)
			(xy 32.916622 -235.845604) (xy 32.90875 -235.845917) (xy 32.893746 -235.850684) (xy 32.887158 -235.855002)
			(xy 32.866079 -235.869391) (xy 32.820435 -235.892221) (xy 32.77183 -235.90778) (xy 32.721413 -235.915699)
			(xy 32.695896 -235.916216) (xy 32.670375 -235.915743) (xy 32.619948 -235.907843) (xy 32.571336 -235.892278)
			(xy 32.525698 -235.869419) (xy 32.504634 -235.855002) (xy 32.498037 -235.850697) (xy 32.483041 -235.845904)
			(xy 32.47517 -235.845604) (xy 31.959296 -235.845604) (xy 31.954032 -235.845108) (xy 31.946589 -235.837661)
			(xy 31.946088 -235.832396) (xy 25.901904 -235.832396) (xy 25.90157 -235.837729) (xy 25.894029 -235.84527)
			(xy 25.888696 -235.845604) (xy 25.372822 -235.845604) (xy 25.36495 -235.845917) (xy 25.349946 -235.850684)
			(xy 25.343358 -235.855002) (xy 25.322279 -235.869391) (xy 25.276635 -235.892221) (xy 25.22803 -235.90778)
			(xy 25.177613 -235.915699) (xy 25.152096 -235.916216) (xy 25.126575 -235.915743) (xy 25.076148 -235.907843)
			(xy 25.027536 -235.892278) (xy 24.981898 -235.869419) (xy 24.960834 -235.855002) (xy 24.954237 -235.850697)
			(xy 24.939241 -235.845904) (xy 24.93137 -235.845604) (xy 24.415496 -235.845604) (xy 24.410232 -235.845108)
			(xy 24.402789 -235.837661) (xy 24.402288 -235.832396) (xy 18.358104 -235.832396) (xy 18.35777 -235.837729)
			(xy 18.350229 -235.84527) (xy 18.344896 -235.845604) (xy 18.344388 -235.845604) (xy 17.828768 -235.845604)
			(xy 17.820894 -235.845893) (xy 17.80589 -235.850677) (xy 17.799304 -235.855002) (xy 17.778212 -235.869371)
			(xy 17.732573 -235.892206) (xy 17.683971 -235.90777) (xy 17.633558 -235.915696) (xy 17.608042 -235.916216)
			(xy 17.582522 -235.915719) (xy 17.532096 -235.907826) (xy 17.483484 -235.892268) (xy 17.437845 -235.869416)
			(xy 17.41678 -235.855002) (xy 17.410195 -235.850677) (xy 17.39519 -235.845896) (xy 17.387316 -235.845604)
			(xy 16.871442 -235.845604) (xy 16.866153 -235.845054) (xy 16.858582 -235.837671) (xy 16.85798 -235.832396)
			(xy 2.509012 -235.832396) (xy 2.509012 -236.682534) (xy 20.958048 -236.682534) (xy 20.958048 -236.187996)
			(xy 20.958587 -236.182743) (xy 20.966005 -236.175303) (xy 20.971256 -236.174788) (xy 20.971764 -236.174788)
			(xy 21.487638 -236.174788) (xy 21.495446 -236.17445) (xy 21.510317 -236.169681) (xy 21.516848 -236.16539)
			(xy 21.537937 -236.151041) (xy 21.583598 -236.12831) (xy 21.632204 -236.112851) (xy 21.682607 -236.105028)
			(xy 21.733613 -236.105028) (xy 21.784016 -236.112851) (xy 21.832622 -236.12831) (xy 21.878283 -236.151041)
			(xy 21.899372 -236.16539) (xy 21.905911 -236.169668) (xy 21.920775 -236.17446) (xy 21.928582 -236.174788)
			(xy 22.44471 -236.174788) (xy 22.450027 -236.175222) (xy 22.4576 -236.182687) (xy 22.458172 -236.187996)
			(xy 22.458172 -236.682534) (xy 22.458148 -236.682788) (xy 28.502356 -236.682788) (xy 28.502356 -236.68228)
			(xy 28.502356 -236.187996) (xy 28.502888 -236.182741) (xy 28.510311 -236.175301) (xy 28.515564 -236.174788)
			(xy 29.031692 -236.174788) (xy 29.039502 -236.174473) (xy 29.054373 -236.169688) (xy 29.060902 -236.16539)
			(xy 29.081991 -236.151041) (xy 29.127652 -236.12831) (xy 29.176258 -236.112851) (xy 29.226661 -236.105028)
			(xy 29.277667 -236.105028) (xy 29.32807 -236.112851) (xy 29.376676 -236.12831) (xy 29.422337 -236.151041)
			(xy 29.443426 -236.16539) (xy 29.449953 -236.169689) (xy 29.464826 -236.174467) (xy 29.472636 -236.174788)
			(xy 29.988764 -236.174788) (xy 29.994091 -236.175151) (xy 30.001633 -236.182671) (xy 30.001972 -236.187996)
			(xy 30.001972 -236.682534) (xy 30.001949 -236.682788) (xy 36.046156 -236.682788) (xy 36.046156 -236.68228)
			(xy 36.046156 -236.187996) (xy 36.046688 -236.182741) (xy 36.054111 -236.175301) (xy 36.059364 -236.174788)
			(xy 36.575492 -236.174788) (xy 36.583302 -236.174473) (xy 36.598173 -236.169688) (xy 36.604702 -236.16539)
			(xy 36.625791 -236.151041) (xy 36.671452 -236.12831) (xy 36.720058 -236.112851) (xy 36.770461 -236.105028)
			(xy 36.821467 -236.105028) (xy 36.87187 -236.112851) (xy 36.920476 -236.12831) (xy 36.966137 -236.151041)
			(xy 36.987226 -236.16539) (xy 36.993753 -236.169689) (xy 37.008626 -236.174467) (xy 37.016436 -236.174788)
			(xy 37.532564 -236.174788) (xy 37.537891 -236.175151) (xy 37.545433 -236.182671) (xy 37.545772 -236.187996)
			(xy 37.545772 -236.682534) (xy 43.589956 -236.682534) (xy 43.589956 -236.187996) (xy 43.590488 -236.182741)
			(xy 43.597911 -236.175301) (xy 43.603164 -236.174788) (xy 43.603672 -236.174788) (xy 44.119546 -236.174788)
			(xy 44.127354 -236.174454) (xy 44.142226 -236.169682) (xy 44.148756 -236.16539) (xy 44.169845 -236.151041)
			(xy 44.215506 -236.12831) (xy 44.264112 -236.112851) (xy 44.314515 -236.105028) (xy 44.365521 -236.105028)
			(xy 44.415924 -236.112851) (xy 44.46453 -236.12831) (xy 44.510191 -236.151041) (xy 44.53128 -236.16539)
			(xy 44.537817 -236.169671) (xy 44.552683 -236.174461) (xy 44.56049 -236.174788) (xy 45.076618 -236.174788)
			(xy 45.081936 -236.175217) (xy 45.089509 -236.182686) (xy 45.09008 -236.187996) (xy 45.09008 -236.682534)
			(xy 45.090056 -236.682788) (xy 51.134264 -236.682788) (xy 51.134264 -236.68228) (xy 51.134264 -236.187996)
			(xy 51.134789 -236.182739) (xy 51.142216 -236.175299) (xy 51.147472 -236.174788) (xy 51.6636 -236.174788)
			(xy 51.67141 -236.174476) (xy 51.686282 -236.169689) (xy 51.69281 -236.16539) (xy 51.713899 -236.151041)
			(xy 51.75956 -236.12831) (xy 51.808166 -236.112851) (xy 51.858569 -236.105028) (xy 51.909575 -236.105028)
			(xy 51.959978 -236.112851) (xy 52.008584 -236.12831) (xy 52.054245 -236.151041) (xy 52.075334 -236.16539)
			(xy 52.081859 -236.169692) (xy 52.096734 -236.174469) (xy 52.104544 -236.174788) (xy 52.620672 -236.174788)
			(xy 52.626 -236.175145) (xy 52.633542 -236.182669) (xy 52.63388 -236.187996) (xy 52.63388 -236.682534)
			(xy 58.678064 -236.682534) (xy 58.678064 -236.187996) (xy 58.678589 -236.182739) (xy 58.686016 -236.175299)
			(xy 58.691272 -236.174788) (xy 58.69178 -236.174788) (xy 60.164726 -236.174788) (xy 60.170045 -236.175212)
			(xy 60.177617 -236.182685) (xy 60.178188 -236.187996) (xy 60.178188 -236.3843) (xy 97.374923 -236.3843)
			(xy 97.379099 -236.333918) (xy 97.39151 -236.28491) (xy 97.411819 -236.238614) (xy 97.439471 -236.196293)
			(xy 97.473713 -236.1591) (xy 97.51361 -236.128051) (xy 97.558073 -236.103993) (xy 97.60589 -236.087582)
			(xy 97.655757 -236.079266) (xy 97.681034 -236.078776) (xy 98.621088 -236.078776) (xy 98.646371 -236.079192)
			(xy 98.696246 -236.087513) (xy 98.744072 -236.10393) (xy 98.788543 -236.127995) (xy 98.828447 -236.159052)
			(xy 98.862694 -236.196253) (xy 98.890351 -236.238584) (xy 98.910663 -236.28489) (xy 98.923077 -236.333908)
			(xy 98.927253 -236.3843) (xy 100.194823 -236.3843) (xy 100.198999 -236.333917) (xy 100.21141 -236.284909)
			(xy 100.23172 -236.238612) (xy 100.259374 -236.19629) (xy 100.293616 -236.159097) (xy 100.333514 -236.128048)
			(xy 100.377979 -236.103991) (xy 100.425797 -236.087581) (xy 100.475664 -236.079266) (xy 100.500942 -236.078776)
			(xy 101.440996 -236.078776) (xy 101.466278 -236.079193) (xy 101.516153 -236.087515) (xy 101.563977 -236.103933)
			(xy 101.608447 -236.127998) (xy 101.64835 -236.159055) (xy 101.682596 -236.196256) (xy 101.710252 -236.238586)
			(xy 101.730564 -236.284892) (xy 101.742977 -236.333909) (xy 101.747153 -236.3843) (xy 101.742977 -236.434691)
			(xy 101.730564 -236.483708) (xy 101.710252 -236.530014) (xy 101.682596 -236.572344) (xy 101.64835 -236.609545)
			(xy 101.608447 -236.640602) (xy 101.563977 -236.664667) (xy 101.516153 -236.681085) (xy 101.505947 -236.682788)
			(xy 167.778176 -236.682788) (xy 167.778176 -236.68228) (xy 167.778176 -236.187996) (xy 167.77869 -236.182737)
			(xy 167.786125 -236.175295) (xy 167.791384 -236.174788) (xy 169.264584 -236.174788) (xy 169.269913 -236.175137)
			(xy 169.277455 -236.182667) (xy 169.277792 -236.187996) (xy 169.277792 -236.682534) (xy 175.321976 -236.682534)
			(xy 175.321976 -236.187996) (xy 175.32249 -236.182737) (xy 175.329925 -236.175295) (xy 175.335184 -236.174788)
			(xy 175.335692 -236.174788) (xy 175.851566 -236.174788) (xy 175.859375 -236.174462) (xy 175.874247 -236.169685)
			(xy 175.880776 -236.16539) (xy 175.901865 -236.151041) (xy 175.947526 -236.12831) (xy 175.996132 -236.112851)
			(xy 176.046535 -236.105028) (xy 176.097541 -236.105028) (xy 176.147944 -236.112851) (xy 176.19655 -236.12831)
			(xy 176.242211 -236.151041) (xy 176.2633 -236.16539) (xy 176.269833 -236.169679) (xy 176.284702 -236.174464)
			(xy 176.29251 -236.174788) (xy 176.808638 -236.174788) (xy 176.813958 -236.175204) (xy 176.82153 -236.182683)
			(xy 176.8221 -236.187996) (xy 176.8221 -236.682534) (xy 176.822075 -236.682788) (xy 182.866284 -236.682788)
			(xy 182.866284 -236.68228) (xy 182.866284 -236.187996) (xy 182.866791 -236.182735) (xy 182.874231 -236.175293)
			(xy 182.879492 -236.174788) (xy 183.39562 -236.174788) (xy 183.403431 -236.174485) (xy 183.418302 -236.169692)
			(xy 183.42483 -236.16539) (xy 183.445919 -236.151041) (xy 183.49158 -236.12831) (xy 183.540186 -236.112851)
			(xy 183.590589 -236.105028) (xy 183.641595 -236.105028) (xy 183.691998 -236.112851) (xy 183.740604 -236.12831)
			(xy 183.786265 -236.151041) (xy 183.807354 -236.16539) (xy 183.813875 -236.1697) (xy 183.828753 -236.174472)
			(xy 183.836564 -236.174788) (xy 184.352692 -236.174788) (xy 184.358022 -236.175132) (xy 184.365563 -236.182666)
			(xy 184.3659 -236.187996) (xy 184.3659 -236.682534) (xy 190.410084 -236.682534) (xy 190.410084 -236.187996)
			(xy 190.410591 -236.182735) (xy 190.418031 -236.175293) (xy 190.423292 -236.174788) (xy 190.4238 -236.174788)
			(xy 190.939674 -236.174788) (xy 190.947483 -236.174465) (xy 190.962355 -236.169686) (xy 190.968884 -236.16539)
			(xy 190.989973 -236.151041) (xy 191.035634 -236.12831) (xy 191.08424 -236.112851) (xy 191.134643 -236.105028)
			(xy 191.185649 -236.105028) (xy 191.236052 -236.112851) (xy 191.284658 -236.12831) (xy 191.330319 -236.151041)
			(xy 191.351408 -236.16539) (xy 191.357939 -236.169682) (xy 191.372809 -236.174465) (xy 191.380618 -236.174788)
			(xy 191.896746 -236.174788) (xy 191.902055 -236.175265) (xy 191.909632 -236.182697) (xy 191.910208 -236.187996)
			(xy 191.910208 -236.682534) (xy 191.910183 -236.682788) (xy 197.954392 -236.682788) (xy 197.954392 -236.68228)
			(xy 197.954392 -236.187996) (xy 197.954892 -236.182733) (xy 197.962337 -236.17529) (xy 197.9676 -236.174788)
			(xy 198.483728 -236.174788) (xy 198.491539 -236.174488) (xy 198.506411 -236.169693) (xy 198.512938 -236.16539)
			(xy 198.534027 -236.151041) (xy 198.579688 -236.12831) (xy 198.628294 -236.112851) (xy 198.678697 -236.105028)
			(xy 198.729703 -236.105028) (xy 198.780106 -236.112851) (xy 198.828712 -236.12831) (xy 198.874373 -236.151041)
			(xy 198.895462 -236.16539) (xy 198.902003 -236.169665) (xy 198.916866 -236.174458) (xy 198.924672 -236.174788)
			(xy 199.4408 -236.174788) (xy 199.446062 -236.175294) (xy 199.453504 -236.182734) (xy 199.454008 -236.187996)
			(xy 199.454008 -236.682534) (xy 199.453984 -236.682788) (xy 205.498192 -236.682788) (xy 205.498192 -236.68228)
			(xy 205.498192 -236.187996) (xy 205.498692 -236.182733) (xy 205.506137 -236.17529) (xy 205.5114 -236.174788)
			(xy 206.027528 -236.174788) (xy 206.035339 -236.174488) (xy 206.050211 -236.169693) (xy 206.056738 -236.16539)
			(xy 206.077827 -236.151041) (xy 206.123488 -236.12831) (xy 206.172094 -236.112851) (xy 206.222497 -236.105028)
			(xy 206.273503 -236.105028) (xy 206.323906 -236.112851) (xy 206.372512 -236.12831) (xy 206.418173 -236.151041)
			(xy 206.439262 -236.16539) (xy 206.445803 -236.169665) (xy 206.460666 -236.174458) (xy 206.468472 -236.174788)
			(xy 206.9846 -236.174788) (xy 206.989862 -236.175294) (xy 206.997304 -236.182734) (xy 206.997808 -236.187996)
			(xy 206.997808 -236.68228) (xy 268.898116 -236.68228) (xy 268.898116 -236.187742) (xy 268.898505 -236.182318)
			(xy 268.906156 -236.174631) (xy 268.911578 -236.17428) (xy 269.427706 -236.17428) (xy 269.435517 -236.173972)
			(xy 269.450388 -236.169183) (xy 269.456916 -236.164882) (xy 269.478005 -236.150533) (xy 269.523666 -236.127802)
			(xy 269.572272 -236.112343) (xy 269.622675 -236.10452) (xy 269.673681 -236.10452) (xy 269.724084 -236.112343)
			(xy 269.77269 -236.127802) (xy 269.818351 -236.150533) (xy 269.83944 -236.164882) (xy 269.845965 -236.169185)
			(xy 269.86084 -236.173961) (xy 269.86865 -236.17428) (xy 270.384778 -236.17428) (xy 270.39022 -236.174598)
			(xy 270.39791 -236.182299) (xy 270.39824 -236.187742) (xy 270.39824 -236.68228) (xy 276.442424 -236.68228)
			(xy 276.442424 -236.187742) (xy 276.442949 -236.182447) (xy 276.450349 -236.174874) (xy 276.455632 -236.17428)
			(xy 276.97176 -236.17428) (xy 276.979569 -236.173953) (xy 276.994441 -236.169177) (xy 277.00097 -236.164882)
			(xy 277.022059 -236.150533) (xy 277.06772 -236.127802) (xy 277.116326 -236.112343) (xy 277.166729 -236.10452)
			(xy 277.217735 -236.10452) (xy 277.268138 -236.112343) (xy 277.316744 -236.127802) (xy 277.362405 -236.150533)
			(xy 277.383494 -236.164882) (xy 277.390029 -236.169168) (xy 277.404896 -236.173954) (xy 277.412704 -236.17428)
			(xy 277.928832 -236.17428) (xy 277.934096 -236.174772) (xy 277.941536 -236.182224) (xy 277.94204 -236.187488)
			(xy 277.94204 -236.187996) (xy 277.94204 -236.68228) (xy 283.986224 -236.68228) (xy 283.986224 -236.187742)
			(xy 283.986749 -236.182447) (xy 283.994149 -236.174874) (xy 283.999432 -236.17428) (xy 284.51556 -236.17428)
			(xy 284.523369 -236.173953) (xy 284.538241 -236.169177) (xy 284.54477 -236.164882) (xy 284.565859 -236.150533)
			(xy 284.61152 -236.127802) (xy 284.660126 -236.112343) (xy 284.710529 -236.10452) (xy 284.761535 -236.10452)
			(xy 284.811938 -236.112343) (xy 284.860544 -236.127802) (xy 284.906205 -236.150533) (xy 284.927294 -236.164882)
			(xy 284.933829 -236.169168) (xy 284.948696 -236.173954) (xy 284.956504 -236.17428) (xy 285.472632 -236.17428)
			(xy 285.477896 -236.174772) (xy 285.485336 -236.182224) (xy 285.48584 -236.187488) (xy 285.48584 -236.187996)
			(xy 285.48584 -236.68228) (xy 291.530024 -236.68228) (xy 291.530024 -236.187742) (xy 291.530406 -236.182316)
			(xy 291.538062 -236.174629) (xy 291.543486 -236.17428) (xy 292.059614 -236.17428) (xy 292.067425 -236.173976)
			(xy 292.082296 -236.169184) (xy 292.088824 -236.164882) (xy 292.109913 -236.150533) (xy 292.155574 -236.127802)
			(xy 292.20418 -236.112343) (xy 292.254583 -236.10452) (xy 292.305589 -236.10452) (xy 292.355992 -236.112343)
			(xy 292.404598 -236.127802) (xy 292.450259 -236.150533) (xy 292.471348 -236.164882) (xy 292.477871 -236.169188)
			(xy 292.492747 -236.173962) (xy 292.500558 -236.17428) (xy 293.016686 -236.17428) (xy 293.022129 -236.174593)
			(xy 293.029818 -236.182298) (xy 293.030148 -236.187742) (xy 293.030148 -236.68228) (xy 299.074332 -236.68228)
			(xy 299.074332 -236.187742) (xy 299.07485 -236.182445) (xy 299.082255 -236.174872) (xy 299.08754 -236.17428)
			(xy 299.603668 -236.17428) (xy 299.611477 -236.173956) (xy 299.626349 -236.169178) (xy 299.632878 -236.164882)
			(xy 299.653967 -236.150533) (xy 299.699628 -236.127802) (xy 299.748234 -236.112343) (xy 299.798637 -236.10452)
			(xy 299.849643 -236.10452) (xy 299.900046 -236.112343) (xy 299.948652 -236.127802) (xy 299.994313 -236.150533)
			(xy 300.015402 -236.164882) (xy 300.021935 -236.169171) (xy 300.036804 -236.173955) (xy 300.044612 -236.17428)
			(xy 300.56074 -236.17428) (xy 300.566005 -236.174767) (xy 300.573444 -236.182222) (xy 300.573948 -236.187488)
			(xy 300.573948 -236.187996) (xy 300.573948 -236.68228) (xy 306.618132 -236.68228) (xy 306.618132 -236.187742)
			(xy 306.618507 -236.182314) (xy 306.626168 -236.174626) (xy 306.631594 -236.17428) (xy 308.104794 -236.17428)
			(xy 308.110238 -236.174587) (xy 308.117927 -236.182297) (xy 308.118256 -236.187742) (xy 308.118256 -236.3841)
			(xy 369.749053 -236.3841) (xy 369.753224 -236.333761) (xy 369.765624 -236.284794) (xy 369.785913 -236.238537)
			(xy 369.81354 -236.19625) (xy 369.84775 -236.159086) (xy 369.88761 -236.12806) (xy 369.932033 -236.104018)
			(xy 369.979808 -236.087615) (xy 370.02963 -236.079299) (xy 370.054886 -236.078776) (xy 370.99494 -236.078776)
			(xy 371.020192 -236.079333) (xy 371.070006 -236.087651) (xy 371.117772 -236.104055) (xy 371.162186 -236.128096)
			(xy 371.202038 -236.159119) (xy 371.236241 -236.196278) (xy 371.263862 -236.238559) (xy 371.284148 -236.28481)
			(xy 371.296545 -236.333769) (xy 371.300715 -236.3841) (xy 372.568953 -236.3841) (xy 372.573124 -236.33376)
			(xy 372.585524 -236.284793) (xy 372.605815 -236.238535) (xy 372.633442 -236.196247) (xy 372.667653 -236.159083)
			(xy 372.707514 -236.128057) (xy 372.751939 -236.104015) (xy 372.799714 -236.087613) (xy 372.849538 -236.079298)
			(xy 372.874794 -236.078776) (xy 373.814848 -236.078776) (xy 373.840099 -236.079333) (xy 373.889912 -236.087653)
			(xy 373.937677 -236.104057) (xy 373.98209 -236.128099) (xy 374.021941 -236.159122) (xy 374.056143 -236.196281)
			(xy 374.083763 -236.238561) (xy 374.104048 -236.284812) (xy 374.116445 -236.333769) (xy 374.120615 -236.3841)
			(xy 374.116445 -236.434431) (xy 374.104048 -236.483388) (xy 374.083763 -236.529638) (xy 374.056143 -236.571919)
			(xy 374.021941 -236.609078) (xy 373.98209 -236.640101) (xy 373.937677 -236.664143) (xy 373.889912 -236.680547)
			(xy 373.879536 -236.68228) (xy 415.718244 -236.68228) (xy 415.718244 -236.187742) (xy 415.718752 -236.182442)
			(xy 415.726163 -236.174868) (xy 415.731452 -236.17428) (xy 417.204652 -236.17428) (xy 417.209975 -236.174658)
			(xy 417.217518 -236.182167) (xy 417.21786 -236.187488) (xy 417.21786 -236.187996) (xy 417.21786 -236.68228)
			(xy 423.262044 -236.68228) (xy 423.262044 -236.187742) (xy 423.262408 -236.182311) (xy 423.270076 -236.174623)
			(xy 423.275506 -236.17428) (xy 423.791634 -236.17428) (xy 423.799442 -236.173941) (xy 423.814313 -236.169173)
			(xy 423.820844 -236.164882) (xy 423.841933 -236.150533) (xy 423.887594 -236.127802) (xy 423.9362 -236.112343)
			(xy 423.986603 -236.10452) (xy 424.037609 -236.10452) (xy 424.088012 -236.112343) (xy 424.136618 -236.127802)
			(xy 424.182279 -236.150533) (xy 424.203368 -236.164882) (xy 424.209909 -236.169158) (xy 424.224772 -236.17395)
			(xy 424.232578 -236.17428) (xy 424.748706 -236.17428) (xy 424.754152 -236.17458) (xy 424.76184 -236.182295)
			(xy 424.762168 -236.187742) (xy 424.762168 -236.68228) (xy 430.806352 -236.68228) (xy 430.806352 -236.187742)
			(xy 430.806853 -236.18244) (xy 430.814269 -236.174866) (xy 430.81956 -236.17428) (xy 431.335688 -236.17428)
			(xy 431.343498 -236.173965) (xy 431.35837 -236.16918) (xy 431.364898 -236.164882) (xy 431.385987 -236.150533)
			(xy 431.431648 -236.127802) (xy 431.480254 -236.112343) (xy 431.530657 -236.10452) (xy 431.581663 -236.10452)
			(xy 431.632066 -236.112343) (xy 431.680672 -236.127802) (xy 431.726333 -236.150533) (xy 431.747422 -236.164882)
			(xy 431.753951 -236.169178) (xy 431.768823 -236.173958) (xy 431.776632 -236.17428) (xy 432.29276 -236.17428)
			(xy 432.298084 -236.174653) (xy 432.305626 -236.182165) (xy 432.305968 -236.187488) (xy 432.305968 -236.187996)
			(xy 432.305968 -236.68228) (xy 438.350152 -236.68228) (xy 438.350152 -236.187742) (xy 438.350509 -236.182309)
			(xy 438.358182 -236.17462) (xy 438.363614 -236.17428) (xy 438.879742 -236.17428) (xy 438.88755 -236.173945)
			(xy 438.902422 -236.169174) (xy 438.908952 -236.164882) (xy 438.930041 -236.150533) (xy 438.975702 -236.127802)
			(xy 439.024308 -236.112343) (xy 439.074711 -236.10452) (xy 439.125717 -236.10452) (xy 439.17612 -236.112343)
			(xy 439.224726 -236.127802) (xy 439.270387 -236.150533) (xy 439.291476 -236.164882) (xy 439.298015 -236.169161)
			(xy 439.312879 -236.173952) (xy 439.320686 -236.17428) (xy 439.836814 -236.17428) (xy 439.842261 -236.174574)
			(xy 439.849948 -236.182294) (xy 439.850276 -236.187742) (xy 439.850276 -236.68228) (xy 445.89446 -236.68228)
			(xy 445.89446 -236.187742) (xy 445.894953 -236.182438) (xy 445.902375 -236.174864) (xy 445.907668 -236.17428)
			(xy 446.423796 -236.17428) (xy 446.431606 -236.173968) (xy 446.446478 -236.169181) (xy 446.453006 -236.164882)
			(xy 446.474095 -236.150533) (xy 446.519756 -236.127802) (xy 446.568362 -236.112343) (xy 446.618765 -236.10452)
			(xy 446.669771 -236.10452) (xy 446.720174 -236.112343) (xy 446.76878 -236.127802) (xy 446.814441 -236.150533)
			(xy 446.83553 -236.164882) (xy 446.842057 -236.169181) (xy 446.85693 -236.173959) (xy 446.86474 -236.17428)
			(xy 447.380868 -236.17428) (xy 447.386193 -236.174647) (xy 447.393735 -236.182164) (xy 447.394076 -236.187488)
			(xy 447.394076 -236.187996) (xy 447.394076 -236.68228) (xy 453.43826 -236.68228) (xy 453.43826 -236.187742)
			(xy 453.438753 -236.182438) (xy 453.446175 -236.174864) (xy 453.451468 -236.17428) (xy 453.967596 -236.17428)
			(xy 453.975406 -236.173968) (xy 453.990278 -236.169181) (xy 453.996806 -236.164882) (xy 454.017895 -236.150533)
			(xy 454.063556 -236.127802) (xy 454.112162 -236.112343) (xy 454.162565 -236.10452) (xy 454.213571 -236.10452)
			(xy 454.263974 -236.112343) (xy 454.31258 -236.127802) (xy 454.358241 -236.150533) (xy 454.37933 -236.164882)
			(xy 454.385857 -236.169181) (xy 454.40073 -236.173959) (xy 454.40854 -236.17428) (xy 454.924668 -236.17428)
			(xy 454.929993 -236.174647) (xy 454.937535 -236.182164) (xy 454.937876 -236.187488) (xy 454.937876 -236.187996)
			(xy 454.937876 -236.68228) (xy 454.937557 -236.687617) (xy 454.930006 -236.695162) (xy 454.924668 -236.695488)
			(xy 454.408794 -236.695488) (xy 454.400919 -236.695774) (xy 454.385915 -236.700558) (xy 454.37933 -236.704886)
			(xy 454.358265 -236.719297) (xy 454.312616 -236.74212) (xy 454.264006 -236.757672) (xy 454.213586 -236.765586)
			(xy 454.188068 -236.7661) (xy 454.162549 -236.765593) (xy 454.112122 -236.757704) (xy 454.063511 -236.742149)
			(xy 454.017872 -236.719299) (xy 453.996806 -236.704886) (xy 453.990216 -236.700569) (xy 453.975215 -236.695784)
			(xy 453.967342 -236.695488) (xy 453.451468 -236.695488) (xy 453.446197 -236.695025) (xy 453.438755 -236.687553)
			(xy 453.43826 -236.68228) (xy 447.394076 -236.68228) (xy 447.393757 -236.687617) (xy 447.386206 -236.695162)
			(xy 447.380868 -236.695488) (xy 446.864994 -236.695488) (xy 446.857119 -236.695774) (xy 446.842115 -236.700558)
			(xy 446.83553 -236.704886) (xy 446.814465 -236.719297) (xy 446.768816 -236.74212) (xy 446.720206 -236.757672)
			(xy 446.669786 -236.765586) (xy 446.644268 -236.7661) (xy 446.618749 -236.765593) (xy 446.568322 -236.757704)
			(xy 446.519711 -236.742149) (xy 446.474072 -236.719299) (xy 446.453006 -236.704886) (xy 446.446416 -236.700569)
			(xy 446.431415 -236.695784) (xy 446.423542 -236.695488) (xy 445.907668 -236.695488) (xy 445.902397 -236.695025)
			(xy 445.894955 -236.687553) (xy 445.89446 -236.68228) (xy 439.850276 -236.68228) (xy 439.849957 -236.687617)
			(xy 439.842406 -236.695162) (xy 439.837068 -236.695488) (xy 439.83656 -236.695488) (xy 439.32094 -236.695488)
			(xy 439.313063 -236.695751) (xy 439.298059 -236.700551) (xy 439.291476 -236.704886) (xy 439.270399 -236.719277)
			(xy 439.224753 -236.742105) (xy 439.176147 -236.757662) (xy 439.125731 -236.765582) (xy 439.100214 -236.7661)
			(xy 439.074693 -236.76562) (xy 439.024266 -236.757723) (xy 438.975655 -236.74216) (xy 438.930017 -236.719302)
			(xy 438.908952 -236.704886) (xy 438.902374 -236.700548) (xy 438.887363 -236.695776) (xy 438.879488 -236.695488)
			(xy 438.363614 -236.695488) (xy 438.358318 -236.694971) (xy 438.350748 -236.687564) (xy 438.350152 -236.68228)
			(xy 432.305968 -236.68228) (xy 432.305656 -236.687619) (xy 432.2981 -236.695164) (xy 432.29276 -236.695488)
			(xy 431.776886 -236.695488) (xy 431.769011 -236.695771) (xy 431.754007 -236.700557) (xy 431.747422 -236.704886)
			(xy 431.72636 -236.719301) (xy 431.680709 -236.742123) (xy 431.632098 -236.757674) (xy 431.581678 -236.765586)
			(xy 431.55616 -236.7661) (xy 431.53064 -236.765597) (xy 431.480214 -236.757707) (xy 431.431602 -236.742151)
			(xy 431.385963 -236.719299) (xy 431.364898 -236.704886) (xy 431.358309 -236.700566) (xy 431.343307 -236.695783)
			(xy 431.335434 -236.695488) (xy 430.81956 -236.695488) (xy 430.814287 -236.69503) (xy 430.806846 -236.687555)
			(xy 430.806352 -236.68228) (xy 424.762168 -236.68228) (xy 424.761856 -236.687619) (xy 424.7543 -236.695164)
			(xy 424.74896 -236.695488) (xy 424.748452 -236.695488) (xy 424.232832 -236.695488) (xy 424.224955 -236.695748)
			(xy 424.209951 -236.70055) (xy 424.203368 -236.704886) (xy 424.182293 -236.719281) (xy 424.136647 -236.742107)
			(xy 424.08804 -236.757664) (xy 424.037623 -236.765583) (xy 424.012106 -236.7661) (xy 423.986585 -236.765624)
			(xy 423.936158 -236.757726) (xy 423.887546 -236.742162) (xy 423.841908 -236.719303) (xy 423.820844 -236.704886)
			(xy 423.814268 -236.700545) (xy 423.799256 -236.695775) (xy 423.79138 -236.695488) (xy 423.275506 -236.695488)
			(xy 423.270209 -236.694976) (xy 423.262639 -236.687565) (xy 423.262044 -236.68228) (xy 417.21786 -236.68228)
			(xy 417.217555 -236.687621) (xy 417.209994 -236.695166) (xy 417.204652 -236.695488) (xy 415.731452 -236.695488)
			(xy 415.726179 -236.695035) (xy 415.718738 -236.687556) (xy 415.718244 -236.68228) (xy 373.879536 -236.68228)
			(xy 373.840099 -236.688867) (xy 373.814848 -236.689392) (xy 372.874794 -236.689392) (xy 372.849538 -236.688902)
			(xy 372.799714 -236.680587) (xy 372.751939 -236.664185) (xy 372.707514 -236.640143) (xy 372.667653 -236.609117)
			(xy 372.633442 -236.571953) (xy 372.605815 -236.529665) (xy 372.585524 -236.483407) (xy 372.573124 -236.43444)
			(xy 372.568953 -236.3841) (xy 371.300715 -236.3841) (xy 371.296545 -236.434431) (xy 371.284148 -236.48339)
			(xy 371.263862 -236.529641) (xy 371.236241 -236.571922) (xy 371.202038 -236.609081) (xy 371.162186 -236.640104)
			(xy 371.117772 -236.664145) (xy 371.070006 -236.680549) (xy 371.020192 -236.688867) (xy 370.99494 -236.689392)
			(xy 370.054886 -236.689392) (xy 370.02963 -236.688901) (xy 369.979808 -236.680585) (xy 369.932033 -236.664182)
			(xy 369.88761 -236.64014) (xy 369.84775 -236.609114) (xy 369.81354 -236.57195) (xy 369.785913 -236.529663)
			(xy 369.765624 -236.483406) (xy 369.753224 -236.434439) (xy 369.749053 -236.3841) (xy 308.118256 -236.3841)
			(xy 308.118256 -236.68228) (xy 308.117697 -236.687529) (xy 308.110294 -236.69497) (xy 308.105048 -236.695488)
			(xy 308.10454 -236.695488) (xy 306.631594 -236.695488) (xy 306.626296 -236.694984) (xy 306.618726 -236.687567)
			(xy 306.618132 -236.68228) (xy 300.573948 -236.68228) (xy 300.573396 -236.687531) (xy 300.565988 -236.694972)
			(xy 300.56074 -236.695488) (xy 300.044866 -236.695488) (xy 300.03699 -236.695762) (xy 300.021986 -236.700554)
			(xy 300.015402 -236.704886) (xy 299.994317 -236.719266) (xy 299.948675 -236.742096) (xy 299.900071 -236.757657)
			(xy 299.849656 -236.76558) (xy 299.82414 -236.7661) (xy 299.79862 -236.765607) (xy 299.748193 -236.757714)
			(xy 299.699582 -236.742155) (xy 299.653943 -236.719301) (xy 299.632878 -236.704886) (xy 299.626294 -236.700558)
			(xy 299.611288 -236.69578) (xy 299.603414 -236.695488) (xy 299.08754 -236.695488) (xy 299.082208 -236.695144)
			(xy 299.074664 -236.687611) (xy 299.074332 -236.68228) (xy 293.030148 -236.68228) (xy 293.029596 -236.687531)
			(xy 293.022188 -236.694972) (xy 293.01694 -236.695488) (xy 293.016432 -236.695488) (xy 292.500812 -236.695488)
			(xy 292.492938 -236.695782) (xy 292.477934 -236.70056) (xy 292.471348 -236.704886) (xy 292.450278 -236.719289)
			(xy 292.40463 -236.742114) (xy 292.356022 -236.757668) (xy 292.305603 -236.765584) (xy 292.280086 -236.7661)
			(xy 292.254567 -236.765584) (xy 292.204141 -236.757698) (xy 292.155529 -236.742145) (xy 292.10989 -236.719298)
			(xy 292.088824 -236.704886) (xy 292.08223 -236.700576) (xy 292.067232 -236.695786) (xy 292.05936 -236.695488)
			(xy 291.543486 -236.695488) (xy 291.538187 -236.694989) (xy 291.530618 -236.687569) (xy 291.530024 -236.68228)
			(xy 285.48584 -236.68228) (xy 285.485295 -236.687533) (xy 285.477883 -236.694975) (xy 285.472632 -236.695488)
			(xy 284.956758 -236.695488) (xy 284.948882 -236.695759) (xy 284.933878 -236.700553) (xy 284.927294 -236.704886)
			(xy 284.906212 -236.71927) (xy 284.860568 -236.742099) (xy 284.811964 -236.757658) (xy 284.761548 -236.765581)
			(xy 284.736032 -236.7661) (xy 284.710512 -236.765611) (xy 284.660085 -236.757716) (xy 284.611473 -236.742156)
			(xy 284.565835 -236.719301) (xy 284.54477 -236.704886) (xy 284.538188 -236.700555) (xy 284.523181 -236.695779)
			(xy 284.515306 -236.695488) (xy 283.999432 -236.695488) (xy 283.994099 -236.69515) (xy 283.986555 -236.687612)
			(xy 283.986224 -236.68228) (xy 277.94204 -236.68228) (xy 277.941495 -236.687533) (xy 277.934083 -236.694975)
			(xy 277.928832 -236.695488) (xy 277.412958 -236.695488) (xy 277.405082 -236.695759) (xy 277.390078 -236.700553)
			(xy 277.383494 -236.704886) (xy 277.362412 -236.71927) (xy 277.316768 -236.742099) (xy 277.268164 -236.757658)
			(xy 277.217748 -236.765581) (xy 277.192232 -236.7661) (xy 277.166712 -236.765611) (xy 277.116285 -236.757716)
			(xy 277.067673 -236.742156) (xy 277.022035 -236.719301) (xy 277.00097 -236.704886) (xy 276.994388 -236.700555)
			(xy 276.979381 -236.695779) (xy 276.971506 -236.695488) (xy 276.455632 -236.695488) (xy 276.450299 -236.69515)
			(xy 276.442755 -236.687612) (xy 276.442424 -236.68228) (xy 270.39824 -236.68228) (xy 270.397695 -236.687533)
			(xy 270.390283 -236.694975) (xy 270.385032 -236.695488) (xy 270.384524 -236.695488) (xy 269.868904 -236.695488)
			(xy 269.86103 -236.695778) (xy 269.846025 -236.700559) (xy 269.83944 -236.704886) (xy 269.818373 -236.719293)
			(xy 269.772724 -236.742117) (xy 269.724115 -236.75767) (xy 269.673695 -236.765585) (xy 269.648178 -236.7661)
			(xy 269.622659 -236.765588) (xy 269.572233 -236.7577) (xy 269.523621 -236.742147) (xy 269.477982 -236.719298)
			(xy 269.456916 -236.704886) (xy 269.450323 -236.700573) (xy 269.435324 -236.695785) (xy 269.427452 -236.695488)
			(xy 268.911578 -236.695488) (xy 268.906278 -236.694995) (xy 268.898709 -236.68757) (xy 268.898116 -236.68228)
			(xy 206.997808 -236.68228) (xy 206.997808 -236.682534) (xy 206.997305 -236.687831) (xy 206.989886 -236.695397)
			(xy 206.9846 -236.695996) (xy 206.468726 -236.695996) (xy 206.460917 -236.696321) (xy 206.446046 -236.701099)
			(xy 206.439516 -236.705394) (xy 206.418383 -236.719726) (xy 206.372664 -236.742458) (xy 206.323994 -236.757893)
			(xy 206.27353 -236.765665) (xy 206.248 -236.7661) (xy 206.22247 -236.765657) (xy 206.172007 -236.757882)
			(xy 206.123334 -236.742455) (xy 206.077606 -236.71974) (xy 206.056484 -236.705394) (xy 206.049956 -236.701097)
			(xy 206.035083 -236.696318) (xy 206.027274 -236.695996) (xy 205.5114 -236.695996) (xy 205.506065 -236.695672)
			(xy 205.498523 -236.688124) (xy 205.498192 -236.682788) (xy 199.453984 -236.682788) (xy 199.453505 -236.687831)
			(xy 199.446086 -236.695397) (xy 199.4408 -236.695996) (xy 198.924926 -236.695996) (xy 198.917117 -236.696321)
			(xy 198.902246 -236.701099) (xy 198.895716 -236.705394) (xy 198.874583 -236.719726) (xy 198.828864 -236.742458)
			(xy 198.780194 -236.757893) (xy 198.72973 -236.765665) (xy 198.7042 -236.7661) (xy 198.67867 -236.765657)
			(xy 198.628207 -236.757882) (xy 198.579534 -236.742455) (xy 198.533806 -236.71974) (xy 198.512684 -236.705394)
			(xy 198.506156 -236.701097) (xy 198.491283 -236.696318) (xy 198.483474 -236.695996) (xy 197.9676 -236.695996)
			(xy 197.962265 -236.695672) (xy 197.954723 -236.688124) (xy 197.954392 -236.682788) (xy 191.910183 -236.682788)
			(xy 191.909677 -236.687891) (xy 191.902103 -236.695472) (xy 191.896746 -236.695996) (xy 191.380872 -236.695996)
			(xy 191.373061 -236.696299) (xy 191.35819 -236.701092) (xy 191.351662 -236.705394) (xy 191.330544 -236.719749)
			(xy 191.284819 -236.742476) (xy 191.236145 -236.757905) (xy 191.185677 -236.765669) (xy 191.160146 -236.7661)
			(xy 191.134617 -236.765634) (xy 191.084155 -236.757866) (xy 191.035482 -236.742445) (xy 190.989753 -236.719737)
			(xy 190.96863 -236.705394) (xy 190.962091 -236.701115) (xy 190.947227 -236.696325) (xy 190.93942 -236.695996)
			(xy 190.423546 -236.695996) (xy 190.418125 -236.695593) (xy 190.410439 -236.687952) (xy 190.410084 -236.682534)
			(xy 184.3659 -236.682534) (xy 184.365404 -236.687833) (xy 184.357981 -236.6954) (xy 184.352692 -236.695996)
			(xy 183.836818 -236.695996) (xy 183.829009 -236.696318) (xy 183.814137 -236.701098) (xy 183.807608 -236.705394)
			(xy 183.786477 -236.719729) (xy 183.740757 -236.742461) (xy 183.692087 -236.757895) (xy 183.641622 -236.765665)
			(xy 183.616092 -236.7661) (xy 183.590562 -236.765661) (xy 183.540098 -236.757885) (xy 183.491426 -236.742456)
			(xy 183.445698 -236.719741) (xy 183.424576 -236.705394) (xy 183.418049 -236.701094) (xy 183.403176 -236.696317)
			(xy 183.395366 -236.695996) (xy 182.879492 -236.695996) (xy 182.874156 -236.695678) (xy 182.866614 -236.688125)
			(xy 182.866284 -236.682788) (xy 176.822075 -236.682788) (xy 176.821576 -236.687893) (xy 176.813997 -236.695474)
			(xy 176.808638 -236.695996) (xy 176.292764 -236.695996) (xy 176.284956 -236.696337) (xy 176.270085 -236.701104)
			(xy 176.263554 -236.705394) (xy 176.242438 -236.719753) (xy 176.196713 -236.742479) (xy 176.148038 -236.757907)
			(xy 176.09757 -236.765669) (xy 176.072038 -236.7661) (xy 176.046509 -236.765638) (xy 175.996046 -236.757869)
			(xy 175.947374 -236.742447) (xy 175.901645 -236.719738) (xy 175.880522 -236.705394) (xy 175.873985 -236.701112)
			(xy 175.859119 -236.696323) (xy 175.851312 -236.695996) (xy 175.335438 -236.695996) (xy 175.330016 -236.695599)
			(xy 175.32233 -236.687954) (xy 175.321976 -236.682534) (xy 169.277792 -236.682534) (xy 169.277303 -236.687835)
			(xy 169.269875 -236.695402) (xy 169.264584 -236.695996) (xy 167.791384 -236.695996) (xy 167.786116 -236.695515)
			(xy 167.778674 -236.688057) (xy 167.778176 -236.682788) (xy 101.505947 -236.682788) (xy 101.466278 -236.689407)
			(xy 101.440996 -236.6899) (xy 100.500942 -236.6899) (xy 100.475664 -236.689334) (xy 100.425797 -236.681019)
			(xy 100.377979 -236.664609) (xy 100.333514 -236.640552) (xy 100.293616 -236.609503) (xy 100.259374 -236.57231)
			(xy 100.23172 -236.529988) (xy 100.21141 -236.483691) (xy 100.198999 -236.434683) (xy 100.194823 -236.3843)
			(xy 98.927253 -236.3843) (xy 98.923077 -236.434692) (xy 98.910663 -236.48371) (xy 98.890351 -236.530016)
			(xy 98.862694 -236.572347) (xy 98.828447 -236.609548) (xy 98.788543 -236.640605) (xy 98.744072 -236.66467)
			(xy 98.696246 -236.681087) (xy 98.646371 -236.689408) (xy 98.621088 -236.6899) (xy 97.681034 -236.6899)
			(xy 97.655757 -236.689334) (xy 97.60589 -236.681018) (xy 97.558073 -236.664607) (xy 97.51361 -236.640549)
			(xy 97.473713 -236.6095) (xy 97.439471 -236.572307) (xy 97.411819 -236.529986) (xy 97.39151 -236.48369)
			(xy 97.379099 -236.434682) (xy 97.374923 -236.3843) (xy 60.178188 -236.3843) (xy 60.178188 -236.682534)
			(xy 60.177675 -236.687896) (xy 60.170088 -236.695478) (xy 60.164726 -236.695996) (xy 58.691526 -236.695996)
			(xy 58.686173 -236.695436) (xy 58.678588 -236.687884) (xy 58.678064 -236.682534) (xy 52.63388 -236.682534)
			(xy 52.633402 -236.687838) (xy 52.625966 -236.695406) (xy 52.620672 -236.695996) (xy 52.104798 -236.695996)
			(xy 52.096988 -236.696309) (xy 52.082117 -236.701096) (xy 52.075588 -236.705394) (xy 52.054463 -236.719738)
			(xy 52.008741 -236.742467) (xy 51.960069 -236.757899) (xy 51.909603 -236.765667) (xy 51.884072 -236.7661)
			(xy 51.858542 -236.765671) (xy 51.808078 -236.757892) (xy 51.759405 -236.74246) (xy 51.713678 -236.719742)
			(xy 51.692556 -236.705394) (xy 51.686034 -236.701087) (xy 51.671157 -236.696314) (xy 51.663346 -236.695996)
			(xy 51.147472 -236.695996) (xy 51.142203 -236.695523) (xy 51.134761 -236.688059) (xy 51.134264 -236.682788)
			(xy 45.090056 -236.682788) (xy 45.089574 -236.687898) (xy 45.081982 -236.69548) (xy 45.076618 -236.695996)
			(xy 44.560744 -236.695996) (xy 44.552936 -236.696329) (xy 44.538064 -236.701102) (xy 44.531534 -236.705394)
			(xy 44.510424 -236.719761) (xy 44.464696 -236.742485) (xy 44.41602 -236.757911) (xy 44.36555 -236.765671)
			(xy 44.340018 -236.7661) (xy 44.314488 -236.765648) (xy 44.264025 -236.757876) (xy 44.215353 -236.742451)
			(xy 44.169625 -236.719739) (xy 44.148502 -236.705394) (xy 44.14197 -236.701104) (xy 44.1271 -236.69632)
			(xy 44.119292 -236.695996) (xy 43.603418 -236.695996) (xy 43.598064 -236.695441) (xy 43.590479 -236.687886)
			(xy 43.589956 -236.682534) (xy 37.545772 -236.682534) (xy 37.545301 -236.68784) (xy 37.53786 -236.695408)
			(xy 37.532564 -236.695996) (xy 37.01669 -236.695996) (xy 37.00888 -236.696306) (xy 36.994008 -236.701095)
			(xy 36.98748 -236.705394) (xy 36.966357 -236.719741) (xy 36.920634 -236.74247) (xy 36.871961 -236.757901)
			(xy 36.821495 -236.765667) (xy 36.795964 -236.7661) (xy 36.770433 -236.765675) (xy 36.719969 -236.757895)
			(xy 36.671297 -236.742462) (xy 36.62557 -236.719743) (xy 36.604448 -236.705394) (xy 36.597928 -236.701083)
			(xy 36.583049 -236.696313) (xy 36.575238 -236.695996) (xy 36.059364 -236.695996) (xy 36.054094 -236.695528)
			(xy 36.046653 -236.68806) (xy 36.046156 -236.682788) (xy 30.001949 -236.682788) (xy 30.001501 -236.68784)
			(xy 29.99406 -236.695408) (xy 29.988764 -236.695996) (xy 29.47289 -236.695996) (xy 29.46508 -236.696306)
			(xy 29.450208 -236.701095) (xy 29.44368 -236.705394) (xy 29.422557 -236.719741) (xy 29.376834 -236.74247)
			(xy 29.328161 -236.757901) (xy 29.277695 -236.765667) (xy 29.252164 -236.7661) (xy 29.226633 -236.765675)
			(xy 29.176169 -236.757895) (xy 29.127497 -236.742462) (xy 29.08177 -236.719743) (xy 29.060648 -236.705394)
			(xy 29.054128 -236.701083) (xy 29.039249 -236.696313) (xy 29.031438 -236.695996) (xy 28.515564 -236.695996)
			(xy 28.510294 -236.695528) (xy 28.502853 -236.68806) (xy 28.502356 -236.682788) (xy 22.458148 -236.682788)
			(xy 22.457673 -236.6879) (xy 22.450076 -236.695483) (xy 22.44471 -236.695996) (xy 21.928836 -236.695996)
			(xy 21.921027 -236.696326) (xy 21.906156 -236.701101) (xy 21.899626 -236.705394) (xy 21.87849 -236.719721)
			(xy 21.832772 -236.742455) (xy 21.784103 -236.757891) (xy 21.73364 -236.765664) (xy 21.70811 -236.7661)
			(xy 21.68258 -236.765652) (xy 21.632117 -236.757879) (xy 21.583445 -236.742453) (xy 21.537717 -236.71974)
			(xy 21.516594 -236.705394) (xy 21.510063 -236.701101) (xy 21.495193 -236.696319) (xy 21.487384 -236.695996)
			(xy 20.97151 -236.695996) (xy 20.966155 -236.695446) (xy 20.958571 -236.687887) (xy 20.958048 -236.682534)
			(xy 2.509012 -236.682534) (xy 2.509012 -237.532418) (xy 16.85798 -237.532418) (xy 16.85798 -237.03788)
			(xy 16.85848 -237.032618) (xy 16.865925 -237.025177) (xy 16.871188 -237.024672) (xy 16.871696 -237.024672)
			(xy 17.38757 -237.024672) (xy 17.395379 -237.024351) (xy 17.410251 -237.019571) (xy 17.41678 -237.015274)
			(xy 17.437869 -237.000925) (xy 17.48353 -236.978194) (xy 17.532136 -236.962735) (xy 17.582539 -236.954912)
			(xy 17.633545 -236.954912) (xy 17.683948 -236.962735) (xy 17.732554 -236.978194) (xy 17.778215 -237.000925)
			(xy 17.799304 -237.015274) (xy 17.805837 -237.019563) (xy 17.820706 -237.024348) (xy 17.828514 -237.024672)
			(xy 18.344642 -237.024672) (xy 18.349959 -237.025099) (xy 18.357529 -237.03257) (xy 18.358104 -237.03788)
			(xy 18.358104 -237.532418) (xy 18.358078 -237.532672) (xy 24.402288 -237.532672) (xy 24.402288 -237.532164)
			(xy 24.402288 -237.03788) (xy 24.402781 -237.032616) (xy 24.410231 -237.025175) (xy 24.415496 -237.024672)
			(xy 24.931624 -237.024672) (xy 24.939436 -237.024373) (xy 24.954307 -237.019578) (xy 24.960834 -237.015274)
			(xy 24.981923 -237.000925) (xy 25.027584 -236.978194) (xy 25.07619 -236.962735) (xy 25.126593 -236.954912)
			(xy 25.177599 -236.954912) (xy 25.228002 -236.962735) (xy 25.276608 -236.978194) (xy 25.322269 -237.000925)
			(xy 25.343358 -237.015274) (xy 25.349879 -237.019583) (xy 25.364757 -237.024355) (xy 25.372568 -237.024672)
			(xy 25.888696 -237.024672) (xy 25.893953 -237.025195) (xy 25.901395 -237.032623) (xy 25.901904 -237.03788)
			(xy 25.901904 -237.532418) (xy 25.90188 -237.532672) (xy 31.946088 -237.532672) (xy 31.946088 -237.532164)
			(xy 31.946088 -237.03788) (xy 31.946581 -237.032616) (xy 31.954031 -237.025175) (xy 31.959296 -237.024672)
			(xy 32.475424 -237.024672) (xy 32.483236 -237.024373) (xy 32.498107 -237.019578) (xy 32.504634 -237.015274)
			(xy 32.525723 -237.000925) (xy 32.571384 -236.978194) (xy 32.61999 -236.962735) (xy 32.670393 -236.954912)
			(xy 32.721399 -236.954912) (xy 32.771802 -236.962735) (xy 32.820408 -236.978194) (xy 32.866069 -237.000925)
			(xy 32.887158 -237.015274) (xy 32.893679 -237.019583) (xy 32.908557 -237.024355) (xy 32.916368 -237.024672)
			(xy 33.432496 -237.024672) (xy 33.437753 -237.025195) (xy 33.445195 -237.032623) (xy 33.445704 -237.03788)
			(xy 33.445704 -237.532418) (xy 39.489888 -237.532418) (xy 39.489888 -237.03788) (xy 39.490381 -237.032616)
			(xy 39.497831 -237.025175) (xy 39.503096 -237.024672) (xy 39.503604 -237.024672) (xy 40.019478 -237.024672)
			(xy 40.027288 -237.024354) (xy 40.042159 -237.019572) (xy 40.048688 -237.015274) (xy 40.069777 -237.000925)
			(xy 40.115438 -236.978194) (xy 40.164044 -236.962735) (xy 40.214447 -236.954912) (xy 40.265453 -236.954912)
			(xy 40.315856 -236.962735) (xy 40.364462 -236.978194) (xy 40.410123 -237.000925) (xy 40.431212 -237.015274)
			(xy 40.437743 -237.019566) (xy 40.452613 -237.024349) (xy 40.460422 -237.024672) (xy 40.97655 -237.024672)
			(xy 40.981856 -237.02516) (xy 40.989431 -237.032585) (xy 40.990012 -237.03788) (xy 40.990012 -237.532418)
			(xy 40.989986 -237.532672) (xy 47.034196 -237.532672) (xy 47.034196 -237.532164) (xy 47.034196 -237.03788)
			(xy 47.034682 -237.032614) (xy 47.042137 -237.025172) (xy 47.047404 -237.024672) (xy 47.563532 -237.024672)
			(xy 47.57134 -237.024334) (xy 47.586212 -237.019565) (xy 47.592742 -237.015274) (xy 47.613831 -237.000925)
			(xy 47.659492 -236.978194) (xy 47.708098 -236.962735) (xy 47.758501 -236.954912) (xy 47.809507 -236.954912)
			(xy 47.85991 -236.962735) (xy 47.908516 -236.978194) (xy 47.954177 -237.000925) (xy 47.975266 -237.015274)
			(xy 47.981807 -237.019548) (xy 47.99667 -237.024342) (xy 48.004476 -237.024672) (xy 48.520604 -237.024672)
			(xy 48.525862 -237.02519) (xy 48.533304 -237.032622) (xy 48.533812 -237.03788) (xy 48.533812 -237.532418)
			(xy 54.577996 -237.532418) (xy 54.577996 -237.03788) (xy 54.578482 -237.032614) (xy 54.585937 -237.025172)
			(xy 54.591204 -237.024672) (xy 54.591712 -237.024672) (xy 56.064658 -237.024672) (xy 56.069965 -237.025155)
			(xy 56.07754 -237.032584) (xy 56.07812 -237.03788) (xy 56.07812 -237.532418) (xy 56.078106 -237.532672)
			(xy 163.678108 -237.532672) (xy 163.678108 -237.532164) (xy 163.678108 -237.03788) (xy 163.678583 -237.032611)
			(xy 163.686046 -237.025169) (xy 163.691316 -237.024672) (xy 165.164516 -237.024672) (xy 165.169776 -237.025182)
			(xy 165.177217 -237.03262) (xy 165.177724 -237.03788) (xy 165.177724 -237.532418) (xy 171.221908 -237.532418)
			(xy 171.221908 -237.03788) (xy 171.222383 -237.032611) (xy 171.229846 -237.025169) (xy 171.235116 -237.024672)
			(xy 171.235624 -237.024672) (xy 171.751498 -237.024672) (xy 171.759309 -237.024362) (xy 171.77418 -237.019574)
			(xy 171.780708 -237.015274) (xy 171.801797 -237.000925) (xy 171.847458 -236.978194) (xy 171.896064 -236.962735)
			(xy 171.946467 -236.954912) (xy 171.997473 -236.954912) (xy 172.047876 -236.962735) (xy 172.096482 -236.978194)
			(xy 172.142143 -237.000925) (xy 172.163232 -237.015274) (xy 172.169759 -237.019574) (xy 172.184632 -237.024352)
			(xy 172.192442 -237.024672) (xy 172.70857 -237.024672) (xy 172.713878 -237.025147) (xy 172.721453 -237.032582)
			(xy 172.722032 -237.03788) (xy 172.722032 -237.532418) (xy 172.722018 -237.532672) (xy 178.766216 -237.532672)
			(xy 178.766216 -237.532164) (xy 178.766216 -237.03788) (xy 178.766516 -237.032539) (xy 178.774082 -237.024998)
			(xy 178.779424 -237.024672) (xy 179.295552 -237.024672) (xy 179.303361 -237.024342) (xy 179.318232 -237.019568)
			(xy 179.324762 -237.015274) (xy 179.345851 -237.000925) (xy 179.391512 -236.978194) (xy 179.440118 -236.962735)
			(xy 179.490521 -236.954912) (xy 179.541527 -236.954912) (xy 179.59193 -236.962735) (xy 179.640536 -236.978194)
			(xy 179.686197 -237.000925) (xy 179.707286 -237.015274) (xy 179.713823 -237.019556) (xy 179.728689 -237.024345)
			(xy 179.736496 -237.024672) (xy 180.252624 -237.024672) (xy 180.257885 -237.025177) (xy 180.265325 -237.032619)
			(xy 180.265832 -237.03788) (xy 180.265832 -237.532418) (xy 186.310016 -237.532418) (xy 186.310016 -237.03788)
			(xy 186.310316 -237.032539) (xy 186.317882 -237.024998) (xy 186.323224 -237.024672) (xy 186.323732 -237.024672)
			(xy 186.839606 -237.024672) (xy 186.847417 -237.024366) (xy 186.862288 -237.019575) (xy 186.868816 -237.015274)
			(xy 186.889905 -237.000925) (xy 186.935566 -236.978194) (xy 186.984172 -236.962735) (xy 187.034575 -236.954912)
			(xy 187.085581 -236.954912) (xy 187.135984 -236.962735) (xy 187.18459 -236.978194) (xy 187.230251 -237.000925)
			(xy 187.25134 -237.015274) (xy 187.257865 -237.019577) (xy 187.27274 -237.024353) (xy 187.28055 -237.024672)
			(xy 187.796678 -237.024672) (xy 187.801987 -237.025142) (xy 187.809561 -237.032581) (xy 187.81014 -237.03788)
			(xy 187.81014 -237.532418) (xy 187.810126 -237.532672) (xy 193.854324 -237.532672) (xy 193.854324 -237.532164)
			(xy 193.854324 -237.03788) (xy 193.854617 -237.032537) (xy 193.862188 -237.024996) (xy 193.867532 -237.024672)
			(xy 194.38366 -237.024672) (xy 194.391469 -237.024346) (xy 194.406341 -237.019569) (xy 194.41287 -237.015274)
			(xy 194.433959 -237.000925) (xy 194.47962 -236.978194) (xy 194.528226 -236.962735) (xy 194.578629 -236.954912)
			(xy 194.629635 -236.954912) (xy 194.680038 -236.962735) (xy 194.728644 -236.978194) (xy 194.774305 -237.000925)
			(xy 194.795394 -237.015274) (xy 194.801929 -237.019559) (xy 194.816796 -237.024346) (xy 194.824604 -237.024672)
			(xy 195.340732 -237.024672) (xy 195.345994 -237.025171) (xy 195.353433 -237.032618) (xy 195.35394 -237.03788)
			(xy 195.35394 -237.532418) (xy 195.353918 -237.532672) (xy 201.398124 -237.532672) (xy 201.398124 -237.532164)
			(xy 201.398124 -237.03788) (xy 201.398417 -237.032537) (xy 201.405988 -237.024996) (xy 201.411332 -237.024672)
			(xy 201.92746 -237.024672) (xy 201.935269 -237.024346) (xy 201.950141 -237.019569) (xy 201.95667 -237.015274)
			(xy 201.977759 -237.000925) (xy 202.02342 -236.978194) (xy 202.072026 -236.962735) (xy 202.122429 -236.954912)
			(xy 202.173435 -236.954912) (xy 202.223838 -236.962735) (xy 202.272444 -236.978194) (xy 202.318105 -237.000925)
			(xy 202.339194 -237.015274) (xy 202.345729 -237.019559) (xy 202.360596 -237.024346) (xy 202.368404 -237.024672)
			(xy 202.884532 -237.024672) (xy 202.889794 -237.025171) (xy 202.897233 -237.032618) (xy 202.89774 -237.03788)
			(xy 202.89774 -237.532164) (xy 264.798048 -237.532164) (xy 264.798048 -237.037626) (xy 264.798398 -237.032192)
			(xy 264.806077 -237.024504) (xy 264.81151 -237.024164) (xy 265.327638 -237.024164) (xy 265.335446 -237.02383)
			(xy 265.350318 -237.019058) (xy 265.356848 -237.014766) (xy 265.377937 -237.000417) (xy 265.423598 -236.977686)
			(xy 265.472204 -236.962227) (xy 265.522607 -236.954404) (xy 265.573613 -236.954404) (xy 265.624016 -236.962227)
			(xy 265.672622 -236.977686) (xy 265.718283 -237.000417) (xy 265.739372 -237.014766) (xy 265.745913 -237.019042)
			(xy 265.760776 -237.023835) (xy 265.768582 -237.024164) (xy 266.28471 -237.024164) (xy 266.290153 -237.024475)
			(xy 266.29784 -237.032183) (xy 266.298172 -237.037626) (xy 266.298172 -237.532164) (xy 272.342356 -237.532164)
			(xy 272.342356 -237.037626) (xy 272.342842 -237.032321) (xy 272.35027 -237.024748) (xy 272.355564 -237.024164)
			(xy 272.871692 -237.024164) (xy 272.879502 -237.023853) (xy 272.894374 -237.019066) (xy 272.900902 -237.014766)
			(xy 272.921991 -237.000417) (xy 272.967652 -236.977686) (xy 273.016258 -236.962227) (xy 273.066661 -236.954404)
			(xy 273.117667 -236.954404) (xy 273.16807 -236.962227) (xy 273.216676 -236.977686) (xy 273.262337 -237.000417)
			(xy 273.283426 -237.014766) (xy 273.289955 -237.019063) (xy 273.304827 -237.023843) (xy 273.312636 -237.024164)
			(xy 273.828764 -237.024164) (xy 273.834085 -237.024548) (xy 273.841626 -237.032053) (xy 273.841972 -237.037372)
			(xy 273.841972 -237.03788) (xy 273.841972 -237.532164) (xy 279.886156 -237.532164) (xy 279.886156 -237.037626)
			(xy 279.886642 -237.032321) (xy 279.89407 -237.024748) (xy 279.899364 -237.024164) (xy 280.415492 -237.024164)
			(xy 280.423302 -237.023853) (xy 280.438174 -237.019066) (xy 280.444702 -237.014766) (xy 280.465791 -237.000417)
			(xy 280.511452 -236.977686) (xy 280.560058 -236.962227) (xy 280.610461 -236.954404) (xy 280.661467 -236.954404)
			(xy 280.71187 -236.962227) (xy 280.760476 -236.977686) (xy 280.806137 -237.000417) (xy 280.827226 -237.014766)
			(xy 280.833755 -237.019063) (xy 280.848627 -237.023843) (xy 280.856436 -237.024164) (xy 281.372564 -237.024164)
			(xy 281.377885 -237.024548) (xy 281.385426 -237.032053) (xy 281.385772 -237.037372) (xy 281.385772 -237.03788)
			(xy 281.385772 -237.532164) (xy 287.429956 -237.532164) (xy 287.429956 -237.037626) (xy 287.430298 -237.03219)
			(xy 287.437982 -237.024502) (xy 287.443418 -237.024164) (xy 287.959546 -237.024164) (xy 287.967355 -237.023833)
			(xy 287.982226 -237.01906) (xy 287.988756 -237.014766) (xy 288.009845 -237.000417) (xy 288.055506 -236.977686)
			(xy 288.104112 -236.962227) (xy 288.154515 -236.954404) (xy 288.205521 -236.954404) (xy 288.255924 -236.962227)
			(xy 288.30453 -236.977686) (xy 288.350191 -237.000417) (xy 288.37128 -237.014766) (xy 288.377819 -237.019045)
			(xy 288.392683 -237.023836) (xy 288.40049 -237.024164) (xy 288.916618 -237.024164) (xy 288.922062 -237.02447)
			(xy 288.929748 -237.032181) (xy 288.93008 -237.037626) (xy 288.93008 -237.532164) (xy 294.974264 -237.532164)
			(xy 294.974264 -237.037626) (xy 294.974743 -237.032319) (xy 294.982175 -237.024745) (xy 294.987472 -237.024164)
			(xy 295.5036 -237.024164) (xy 295.511411 -237.023857) (xy 295.526282 -237.019067) (xy 295.53281 -237.014766)
			(xy 295.553899 -237.000417) (xy 295.59956 -236.977686) (xy 295.648166 -236.962227) (xy 295.698569 -236.954404)
			(xy 295.749575 -236.954404) (xy 295.799978 -236.962227) (xy 295.848584 -236.977686) (xy 295.894245 -237.000417)
			(xy 295.915334 -237.014766) (xy 295.921861 -237.019066) (xy 295.936734 -237.023844) (xy 295.944544 -237.024164)
			(xy 296.460672 -237.024164) (xy 296.465925 -237.02471) (xy 296.473367 -237.032122) (xy 296.47388 -237.037372)
			(xy 296.47388 -237.03788) (xy 296.47388 -237.532164) (xy 302.518064 -237.532164) (xy 302.518064 -237.037626)
			(xy 302.518399 -237.032188) (xy 302.526088 -237.024499) (xy 302.531526 -237.024164) (xy 304.004726 -237.024164)
			(xy 304.010099 -237.024636) (xy 304.017685 -237.032251) (xy 304.018188 -237.037626) (xy 304.018188 -237.532164)
			(xy 411.618176 -237.532164) (xy 411.618176 -237.037626) (xy 411.618645 -237.032317) (xy 411.626084 -237.024742)
			(xy 411.631384 -237.024164) (xy 413.104584 -237.024164) (xy 413.109838 -237.024702) (xy 413.11728 -237.03212)
			(xy 413.117792 -237.037372) (xy 413.117792 -237.03788) (xy 413.117792 -237.532164) (xy 419.161976 -237.532164)
			(xy 419.161976 -237.037626) (xy 419.1623 -237.032185) (xy 419.169997 -237.024496) (xy 419.175438 -237.024164)
			(xy 419.691566 -237.024164) (xy 419.699375 -237.023842) (xy 419.714247 -237.019062) (xy 419.720776 -237.014766)
			(xy 419.741865 -237.000417) (xy 419.787526 -236.977686) (xy 419.836132 -236.962227) (xy 419.886535 -236.954404)
			(xy 419.937541 -236.954404) (xy 419.987944 -236.962227) (xy 420.03655 -236.977686) (xy 420.082211 -237.000417)
			(xy 420.1033 -237.014766) (xy 420.109834 -237.019053) (xy 420.124702 -237.023839) (xy 420.13251 -237.024164)
			(xy 420.648638 -237.024164) (xy 420.654013 -237.024628) (xy 420.661598 -237.032249) (xy 420.6621 -237.037626)
			(xy 420.6621 -237.532164) (xy 426.706284 -237.532164) (xy 426.706284 -237.037626) (xy 426.706746 -237.032315)
			(xy 426.71419 -237.02474) (xy 426.719492 -237.024164) (xy 427.23562 -237.024164) (xy 427.243432 -237.023865)
			(xy 427.258303 -237.01907) (xy 427.26483 -237.014766) (xy 427.285919 -237.000417) (xy 427.33158 -236.977686)
			(xy 427.380186 -236.962227) (xy 427.430589 -236.954404) (xy 427.481595 -236.954404) (xy 427.531998 -236.962227)
			(xy 427.580604 -236.977686) (xy 427.626265 -237.000417) (xy 427.647354 -237.014766) (xy 427.653876 -237.019073)
			(xy 427.668753 -237.023847) (xy 427.676564 -237.024164) (xy 428.192692 -237.024164) (xy 428.197947 -237.024697)
			(xy 428.205389 -237.032118) (xy 428.2059 -237.037372) (xy 428.2059 -237.03788) (xy 428.2059 -237.532164)
			(xy 434.250084 -237.532164) (xy 434.250084 -237.037626) (xy 434.250401 -237.032183) (xy 434.258103 -237.024493)
			(xy 434.263546 -237.024164) (xy 434.779674 -237.024164) (xy 434.787484 -237.023845) (xy 434.802355 -237.019063)
			(xy 434.808884 -237.014766) (xy 434.829973 -237.000417) (xy 434.875634 -236.977686) (xy 434.92424 -236.962227)
			(xy 434.974643 -236.954404) (xy 435.025649 -236.954404) (xy 435.076052 -236.962227) (xy 435.124658 -236.977686)
			(xy 435.170319 -237.000417) (xy 435.191408 -237.014766) (xy 435.197941 -237.019056) (xy 435.21281 -237.02384)
			(xy 435.220618 -237.024164) (xy 435.736746 -237.024164) (xy 435.742122 -237.024623) (xy 435.749706 -237.032248)
			(xy 435.750208 -237.037626) (xy 435.750208 -237.532164) (xy 441.794392 -237.532164) (xy 441.794392 -237.037626)
			(xy 441.794935 -237.032336) (xy 441.802323 -237.024766) (xy 441.8076 -237.024164) (xy 442.323728 -237.024164)
			(xy 442.33154 -237.023868) (xy 442.346411 -237.019071) (xy 442.352938 -237.014766) (xy 442.374027 -237.000417)
			(xy 442.419688 -236.977686) (xy 442.468294 -236.962227) (xy 442.518697 -236.954404) (xy 442.569703 -236.954404)
			(xy 442.620106 -236.962227) (xy 442.668712 -236.977686) (xy 442.714373 -237.000417) (xy 442.735462 -237.014766)
			(xy 442.742005 -237.019038) (xy 442.756866 -237.023833) (xy 442.764672 -237.024164) (xy 443.2808 -237.024164)
			(xy 443.286056 -237.024692) (xy 443.293497 -237.032117) (xy 443.294008 -237.037372) (xy 443.294008 -237.03788)
			(xy 443.294008 -237.532164) (xy 449.338192 -237.532164) (xy 449.338192 -237.037626) (xy 449.338735 -237.032336)
			(xy 449.346123 -237.024766) (xy 449.3514 -237.024164) (xy 449.867528 -237.024164) (xy 449.87534 -237.023868)
			(xy 449.890211 -237.019071) (xy 449.896738 -237.014766) (xy 449.917827 -237.000417) (xy 449.963488 -236.977686)
			(xy 450.012094 -236.962227) (xy 450.062497 -236.954404) (xy 450.113503 -236.954404) (xy 450.163906 -236.962227)
			(xy 450.212512 -236.977686) (xy 450.258173 -237.000417) (xy 450.279262 -237.014766) (xy 450.285805 -237.019038)
			(xy 450.300666 -237.023833) (xy 450.308472 -237.024164) (xy 450.8246 -237.024164) (xy 450.829856 -237.024692)
			(xy 450.837297 -237.032117) (xy 450.837808 -237.037372) (xy 450.837808 -237.03788) (xy 450.837808 -237.532164)
			(xy 450.837449 -237.537492) (xy 450.829927 -237.545035) (xy 450.8246 -237.545372) (xy 450.308726 -237.545372)
			(xy 450.300849 -237.545632) (xy 450.285845 -237.550434) (xy 450.279262 -237.55477) (xy 450.258187 -237.569166)
			(xy 450.212541 -237.591992) (xy 450.163934 -237.607549) (xy 450.113517 -237.615467) (xy 450.088 -237.615984)
			(xy 450.062479 -237.615514) (xy 450.012051 -237.607614) (xy 449.963439 -237.592048) (xy 449.917802 -237.569188)
			(xy 449.896738 -237.55477) (xy 449.890136 -237.550474) (xy 449.875144 -237.545674) (xy 449.867274 -237.545372)
			(xy 449.3514 -237.545372) (xy 449.346059 -237.54507) (xy 449.338516 -237.537506) (xy 449.338192 -237.532164)
			(xy 443.294008 -237.532164) (xy 443.293649 -237.537492) (xy 443.286127 -237.545035) (xy 443.2808 -237.545372)
			(xy 442.764926 -237.545372) (xy 442.757049 -237.545632) (xy 442.742045 -237.550434) (xy 442.735462 -237.55477)
			(xy 442.714387 -237.569166) (xy 442.668741 -237.591992) (xy 442.620134 -237.607549) (xy 442.569717 -237.615467)
			(xy 442.5442 -237.615984) (xy 442.518679 -237.615514) (xy 442.468251 -237.607614) (xy 442.419639 -237.592048)
			(xy 442.374002 -237.569188) (xy 442.352938 -237.55477) (xy 442.346336 -237.550474) (xy 442.331344 -237.545674)
			(xy 442.323474 -237.545372) (xy 441.8076 -237.545372) (xy 441.802259 -237.54507) (xy 441.794716 -237.537506)
			(xy 441.794392 -237.532164) (xy 435.750208 -237.532164) (xy 435.749849 -237.537492) (xy 435.742327 -237.545035)
			(xy 435.737 -237.545372) (xy 435.736492 -237.545372) (xy 435.220872 -237.545372) (xy 435.212997 -237.545652)
			(xy 435.197993 -237.55044) (xy 435.191408 -237.55477) (xy 435.170348 -237.569189) (xy 435.124697 -237.59201)
			(xy 435.076085 -237.60756) (xy 435.025664 -237.615471) (xy 435.000146 -237.615984) (xy 434.974626 -237.615491)
			(xy 434.924199 -237.607598) (xy 434.875587 -237.592039) (xy 434.829949 -237.569185) (xy 434.808884 -237.55477)
			(xy 434.802294 -237.550453) (xy 434.787293 -237.545666) (xy 434.77942 -237.545372) (xy 434.263546 -237.545372)
			(xy 434.25825 -237.544848) (xy 434.250677 -237.537448) (xy 434.250084 -237.532164) (xy 428.2059 -237.532164)
			(xy 428.205548 -237.537493) (xy 428.198021 -237.545037) (xy 428.192692 -237.545372) (xy 427.676818 -237.545372)
			(xy 427.668944 -237.545671) (xy 427.65394 -237.550446) (xy 427.647354 -237.55477) (xy 427.626281 -237.569169)
			(xy 427.580635 -237.591995) (xy 427.532027 -237.607551) (xy 427.481609 -237.615468) (xy 427.456092 -237.615984)
			(xy 427.430573 -237.615468) (xy 427.380147 -237.607582) (xy 427.331535 -237.59203) (xy 427.285896 -237.569182)
			(xy 427.26483 -237.55477) (xy 427.258229 -237.55047) (xy 427.243237 -237.545673) (xy 427.235366 -237.545372)
			(xy 426.719492 -237.545372) (xy 426.71415 -237.545075) (xy 426.706607 -237.537507) (xy 426.706284 -237.532164)
			(xy 420.6621 -237.532164) (xy 420.661748 -237.537493) (xy 420.654221 -237.545037) (xy 420.648892 -237.545372)
			(xy 420.648384 -237.545372) (xy 420.132764 -237.545372) (xy 420.124888 -237.545648) (xy 420.109884 -237.550439)
			(xy 420.1033 -237.55477) (xy 420.082215 -237.569149) (xy 420.036572 -237.59198) (xy 419.987969 -237.607541)
			(xy 419.937554 -237.615464) (xy 419.912038 -237.615984) (xy 419.886518 -237.615495) (xy 419.836091 -237.607601)
			(xy 419.787479 -237.592041) (xy 419.741841 -237.569185) (xy 419.720776 -237.55477) (xy 419.714188 -237.55045)
			(xy 419.699185 -237.545665) (xy 419.691312 -237.545372) (xy 419.175438 -237.545372) (xy 419.170141 -237.544853)
			(xy 419.162569 -237.537449) (xy 419.161976 -237.532164) (xy 413.117792 -237.532164) (xy 413.117447 -237.537495)
			(xy 413.109915 -237.545039) (xy 413.104584 -237.545372) (xy 411.631384 -237.545372) (xy 411.626041 -237.545081)
			(xy 411.618498 -237.537509) (xy 411.618176 -237.532164) (xy 304.018188 -237.532164) (xy 304.017847 -237.537496)
			(xy 304.010312 -237.545041) (xy 304.00498 -237.545372) (xy 304.004472 -237.545372) (xy 302.531526 -237.545372)
			(xy 302.526228 -237.544861) (xy 302.518656 -237.537451) (xy 302.518064 -237.532164) (xy 296.47388 -237.532164)
			(xy 296.473546 -237.537498) (xy 296.466006 -237.545043) (xy 296.460672 -237.545372) (xy 295.944798 -237.545372)
			(xy 295.936924 -237.545663) (xy 295.921919 -237.550444) (xy 295.915334 -237.55477) (xy 295.894267 -237.569178)
			(xy 295.848618 -237.592002) (xy 295.800009 -237.607555) (xy 295.74959 -237.615469) (xy 295.724072 -237.615984)
			(xy 295.698552 -237.615478) (xy 295.648126 -237.607589) (xy 295.599514 -237.592034) (xy 295.553875 -237.569183)
			(xy 295.53281 -237.55477) (xy 295.526214 -237.550463) (xy 295.511218 -237.54567) (xy 295.503346 -237.545372)
			(xy 294.987472 -237.545372) (xy 294.982127 -237.545088) (xy 294.974586 -237.53751) (xy 294.974264 -237.532164)
			(xy 288.93008 -237.532164) (xy 288.929746 -237.537498) (xy 288.922206 -237.545043) (xy 288.916872 -237.545372)
			(xy 288.916364 -237.545372) (xy 288.400744 -237.545372) (xy 288.392868 -237.54564) (xy 288.377864 -237.550437)
			(xy 288.37128 -237.55477) (xy 288.3502 -237.569158) (xy 288.304556 -237.591986) (xy 288.255951 -237.607545)
			(xy 288.205534 -237.615466) (xy 288.180018 -237.615984) (xy 288.154497 -237.615505) (xy 288.10407 -237.607608)
			(xy 288.055458 -237.592045) (xy 288.00982 -237.569187) (xy 287.988756 -237.55477) (xy 287.982172 -237.550442)
			(xy 287.967166 -237.545662) (xy 287.959292 -237.545372) (xy 287.443418 -237.545372) (xy 287.438119 -237.544866)
			(xy 287.430547 -237.537452) (xy 287.429956 -237.532164) (xy 281.385772 -237.532164) (xy 281.385446 -237.5375)
			(xy 281.3779 -237.545046) (xy 281.372564 -237.545372) (xy 280.85669 -237.545372) (xy 280.848815 -237.545659)
			(xy 280.833811 -237.550443) (xy 280.827226 -237.55477) (xy 280.806161 -237.569181) (xy 280.760512 -237.592004)
			(xy 280.711902 -237.607557) (xy 280.661482 -237.61547) (xy 280.635964 -237.615984) (xy 280.610444 -237.615482)
			(xy 280.560018 -237.607592) (xy 280.511406 -237.592035) (xy 280.465767 -237.569184) (xy 280.444702 -237.55477)
			(xy 280.438108 -237.55046) (xy 280.42311 -237.545669) (xy 280.415238 -237.545372) (xy 279.899364 -237.545372)
			(xy 279.894088 -237.544925) (xy 279.886646 -237.537442) (xy 279.886156 -237.532164) (xy 273.841972 -237.532164)
			(xy 273.841646 -237.5375) (xy 273.8341 -237.545046) (xy 273.828764 -237.545372) (xy 273.31289 -237.545372)
			(xy 273.305015 -237.545659) (xy 273.290011 -237.550443) (xy 273.283426 -237.55477) (xy 273.262361 -237.569181)
			(xy 273.216712 -237.592004) (xy 273.168102 -237.607557) (xy 273.117682 -237.61547) (xy 273.092164 -237.615984)
			(xy 273.066644 -237.615482) (xy 273.016218 -237.607592) (xy 272.967606 -237.592035) (xy 272.921967 -237.569184)
			(xy 272.900902 -237.55477) (xy 272.894308 -237.55046) (xy 272.87931 -237.545669) (xy 272.871438 -237.545372)
			(xy 272.355564 -237.545372) (xy 272.350288 -237.544925) (xy 272.342846 -237.537442) (xy 272.342356 -237.532164)
			(xy 266.298172 -237.532164) (xy 266.297846 -237.5375) (xy 266.2903 -237.545046) (xy 266.284964 -237.545372)
			(xy 266.284456 -237.545372) (xy 265.768836 -237.545372) (xy 265.760959 -237.545636) (xy 265.745955 -237.550436)
			(xy 265.739372 -237.55477) (xy 265.718294 -237.569161) (xy 265.672649 -237.591989) (xy 265.624043 -237.607547)
			(xy 265.573627 -237.615466) (xy 265.54811 -237.615984) (xy 265.522589 -237.615509) (xy 265.472162 -237.607611)
			(xy 265.42355 -237.592046) (xy 265.377912 -237.569187) (xy 265.356848 -237.55477) (xy 265.350266 -237.550439)
			(xy 265.335259 -237.545661) (xy 265.327384 -237.545372) (xy 264.81151 -237.545372) (xy 264.80621 -237.544872)
			(xy 264.798639 -237.537453) (xy 264.798048 -237.532164) (xy 202.89774 -237.532164) (xy 202.89774 -237.532418)
			(xy 202.897287 -237.537729) (xy 202.889835 -237.5453) (xy 202.884532 -237.54588) (xy 202.368658 -237.54588)
			(xy 202.360849 -237.546205) (xy 202.345977 -237.550982) (xy 202.339448 -237.555278) (xy 202.31834 -237.569649)
			(xy 202.272611 -237.59237) (xy 202.223934 -237.607794) (xy 202.173464 -237.615554) (xy 202.147932 -237.615984)
			(xy 202.122403 -237.615528) (xy 202.07194 -237.607757) (xy 202.023267 -237.592334) (xy 201.977539 -237.569623)
			(xy 201.956416 -237.555278) (xy 201.949876 -237.551002) (xy 201.935013 -237.546208) (xy 201.927206 -237.54588)
			(xy 201.411332 -237.54588) (xy 201.405997 -237.545549) (xy 201.398453 -237.538007) (xy 201.398124 -237.532672)
			(xy 195.353918 -237.532672) (xy 195.353487 -237.537729) (xy 195.346035 -237.5453) (xy 195.340732 -237.54588)
			(xy 194.824858 -237.54588) (xy 194.817049 -237.546205) (xy 194.802177 -237.550982) (xy 194.795648 -237.555278)
			(xy 194.77454 -237.569649) (xy 194.728811 -237.59237) (xy 194.680134 -237.607794) (xy 194.629664 -237.615554)
			(xy 194.604132 -237.615984) (xy 194.578603 -237.615528) (xy 194.52814 -237.607757) (xy 194.479467 -237.592334)
			(xy 194.433739 -237.569623) (xy 194.412616 -237.555278) (xy 194.406076 -237.551002) (xy 194.391213 -237.546208)
			(xy 194.383406 -237.54588) (xy 193.867532 -237.54588) (xy 193.862197 -237.545549) (xy 193.854653 -237.538007)
			(xy 193.854324 -237.532672) (xy 187.810126 -237.532672) (xy 187.809831 -237.537861) (xy 187.802122 -237.545547)
			(xy 187.796678 -237.54588) (xy 187.280804 -237.54588) (xy 187.272993 -237.546182) (xy 187.258121 -237.550975)
			(xy 187.251594 -237.555278) (xy 187.230474 -237.569629) (xy 187.184749 -237.592355) (xy 187.136075 -237.607784)
			(xy 187.085609 -237.615551) (xy 187.060078 -237.615984) (xy 187.034547 -237.615555) (xy 186.984084 -237.607776)
			(xy 186.935411 -237.592345) (xy 186.889684 -237.569626) (xy 186.868562 -237.555278) (xy 186.862034 -237.550981)
			(xy 186.847161 -237.5462) (xy 186.839352 -237.54588) (xy 186.323478 -237.54588) (xy 186.318116 -237.545366)
			(xy 186.310532 -237.53778) (xy 186.310016 -237.532418) (xy 180.265832 -237.532418) (xy 180.265386 -237.537731)
			(xy 180.257929 -237.545303) (xy 180.252624 -237.54588) (xy 179.73675 -237.54588) (xy 179.72894 -237.546201)
			(xy 179.714068 -237.550981) (xy 179.70754 -237.555278) (xy 179.686435 -237.569652) (xy 179.640705 -237.592373)
			(xy 179.592026 -237.607796) (xy 179.541556 -237.615555) (xy 179.516024 -237.615984) (xy 179.490494 -237.615532)
			(xy 179.440031 -237.60776) (xy 179.391359 -237.592335) (xy 179.345631 -237.569623) (xy 179.324508 -237.555278)
			(xy 179.317969 -237.550999) (xy 179.303105 -237.546207) (xy 179.295298 -237.54588) (xy 178.779424 -237.54588)
			(xy 178.774088 -237.545554) (xy 178.766544 -237.538008) (xy 178.766216 -237.532672) (xy 172.722018 -237.532672)
			(xy 172.72173 -237.537863) (xy 172.714016 -237.545549) (xy 172.70857 -237.54588) (xy 172.192696 -237.54588)
			(xy 172.184884 -237.546179) (xy 172.170012 -237.550974) (xy 172.163486 -237.555278) (xy 172.142368 -237.569633)
			(xy 172.096643 -237.592357) (xy 172.047968 -237.607786) (xy 171.997501 -237.615551) (xy 171.97197 -237.615984)
			(xy 171.946439 -237.615559) (xy 171.895975 -237.607779) (xy 171.847303 -237.592346) (xy 171.801576 -237.569627)
			(xy 171.780454 -237.555278) (xy 171.773927 -237.550978) (xy 171.759054 -237.546199) (xy 171.751244 -237.54588)
			(xy 171.23537 -237.54588) (xy 171.230007 -237.545371) (xy 171.222424 -237.537782) (xy 171.221908 -237.532418)
			(xy 165.177724 -237.532418) (xy 165.177285 -237.537733) (xy 165.169823 -237.545305) (xy 165.164516 -237.54588)
			(xy 163.691316 -237.54588) (xy 163.685979 -237.54556) (xy 163.678435 -237.538009) (xy 163.678108 -237.532672)
			(xy 56.078106 -237.532672) (xy 56.077829 -237.537866) (xy 56.070107 -237.545553) (xy 56.064658 -237.54588)
			(xy 54.591458 -237.54588) (xy 54.586093 -237.545379) (xy 54.578511 -237.537784) (xy 54.577996 -237.532418)
			(xy 48.533812 -237.532418) (xy 48.533383 -237.537736) (xy 48.525914 -237.545309) (xy 48.520604 -237.54588)
			(xy 48.00473 -237.54588) (xy 47.99692 -237.546193) (xy 47.982048 -237.550978) (xy 47.97552 -237.555278)
			(xy 47.954392 -237.569618) (xy 47.90867 -237.592346) (xy 47.859999 -237.607778) (xy 47.809534 -237.615549)
			(xy 47.784004 -237.615984) (xy 47.758474 -237.615542) (xy 47.708011 -237.607767) (xy 47.659338 -237.592339)
			(xy 47.61361 -237.569625) (xy 47.592488 -237.555278) (xy 47.585954 -237.550991) (xy 47.571086 -237.546204)
			(xy 47.563278 -237.54588) (xy 47.047404 -237.54588) (xy 47.042066 -237.545568) (xy 47.034523 -237.538011)
			(xy 47.034196 -237.532672) (xy 40.989986 -237.532672) (xy 40.989467 -237.537772) (xy 40.981903 -237.545354)
			(xy 40.97655 -237.54588) (xy 40.460676 -237.54588) (xy 40.452864 -237.54617) (xy 40.437992 -237.550971)
			(xy 40.431466 -237.555278) (xy 40.410353 -237.569641) (xy 40.364626 -237.592364) (xy 40.31595 -237.60779)
			(xy 40.265482 -237.615553) (xy 40.23995 -237.615984) (xy 40.214421 -237.615519) (xy 40.163958 -237.607751)
			(xy 40.115286 -237.59233) (xy 40.069557 -237.569622) (xy 40.048434 -237.555278) (xy 40.04189 -237.551008)
			(xy 40.02703 -237.546211) (xy 40.019224 -237.54588) (xy 39.50335 -237.54588) (xy 39.497984 -237.545384)
			(xy 39.490403 -237.537785) (xy 39.489888 -237.532418) (xy 33.445704 -237.532418) (xy 33.445194 -237.537714)
			(xy 33.437781 -237.545282) (xy 33.432496 -237.54588) (xy 32.916622 -237.54588) (xy 32.908811 -237.54619)
			(xy 32.893939 -237.550977) (xy 32.887412 -237.555278) (xy 32.866287 -237.569621) (xy 32.820564 -237.592349)
			(xy 32.771892 -237.60778) (xy 32.721427 -237.615549) (xy 32.695896 -237.615984) (xy 32.670366 -237.615546)
			(xy 32.619902 -237.60777) (xy 32.57123 -237.592341) (xy 32.525502 -237.569625) (xy 32.50438 -237.555278)
			(xy 32.497848 -237.550988) (xy 32.482978 -237.546203) (xy 32.47517 -237.54588) (xy 31.959296 -237.54588)
			(xy 31.953956 -237.545573) (xy 31.946414 -237.538012) (xy 31.946088 -237.532672) (xy 25.90188 -237.532672)
			(xy 25.901394 -237.537714) (xy 25.893981 -237.545282) (xy 25.888696 -237.54588) (xy 25.372822 -237.54588)
			(xy 25.365011 -237.54619) (xy 25.350139 -237.550977) (xy 25.343612 -237.555278) (xy 25.322487 -237.569621)
			(xy 25.276764 -237.592349) (xy 25.228092 -237.60778) (xy 25.177627 -237.615549) (xy 25.152096 -237.615984)
			(xy 25.126566 -237.615546) (xy 25.076102 -237.60777) (xy 25.02743 -237.592341) (xy 24.981702 -237.569625)
			(xy 24.96058 -237.555278) (xy 24.954048 -237.550988) (xy 24.939178 -237.546203) (xy 24.93137 -237.54588)
			(xy 24.415496 -237.54588) (xy 24.410156 -237.545573) (xy 24.402614 -237.538012) (xy 24.402288 -237.532672)
			(xy 18.358078 -237.532672) (xy 18.357566 -237.537774) (xy 18.349997 -237.545356) (xy 18.344642 -237.54588)
			(xy 17.828768 -237.54588) (xy 17.820959 -237.546209) (xy 17.806087 -237.550983) (xy 17.799558 -237.555278)
			(xy 17.778448 -237.569645) (xy 17.73272 -237.592367) (xy 17.684043 -237.607792) (xy 17.633574 -237.615553)
			(xy 17.608042 -237.615984) (xy 17.582513 -237.615523) (xy 17.53205 -237.607754) (xy 17.483378 -237.592332)
			(xy 17.437649 -237.569622) (xy 17.416526 -237.555278) (xy 17.409983 -237.551005) (xy 17.395122 -237.546209)
			(xy 17.387316 -237.54588) (xy 16.871442 -237.54588) (xy 16.866017 -237.545494) (xy 16.85833 -237.537841)
			(xy 16.85798 -237.532418) (xy 2.509012 -237.532418) (xy 2.509012 -238.382556) (xy 20.958048 -238.382556)
			(xy 20.958048 -237.888018) (xy 20.958392 -237.882583) (xy 20.966075 -237.874895) (xy 20.97151 -237.874556)
			(xy 21.487638 -237.874556) (xy 21.495446 -237.874223) (xy 21.510318 -237.869451) (xy 21.516848 -237.865158)
			(xy 21.537937 -237.850809) (xy 21.583598 -237.828078) (xy 21.632204 -237.812619) (xy 21.682607 -237.804796)
			(xy 21.733613 -237.804796) (xy 21.784016 -237.812619) (xy 21.832622 -237.828078) (xy 21.878283 -237.850809)
			(xy 21.899372 -237.865158) (xy 21.905913 -237.869433) (xy 21.920776 -237.874227) (xy 21.928582 -237.874556)
			(xy 22.44471 -237.874556) (xy 22.450151 -237.874874) (xy 22.457837 -237.882577) (xy 22.458172 -237.888018)
			(xy 22.458172 -238.382556) (xy 28.502356 -238.382556) (xy 28.502356 -237.888018) (xy 28.502837 -237.882712)
			(xy 28.510268 -237.875139) (xy 28.515564 -237.874556) (xy 29.031692 -237.874556) (xy 29.039503 -237.874247)
			(xy 29.054374 -237.869459) (xy 29.060902 -237.865158) (xy 29.081991 -237.850809) (xy 29.127652 -237.828078)
			(xy 29.176258 -237.812619) (xy 29.226661 -237.804796) (xy 29.277667 -237.804796) (xy 29.32807 -237.812619)
			(xy 29.376676 -237.828078) (xy 29.422337 -237.850809) (xy 29.443426 -237.865158) (xy 29.449955 -237.869454)
			(xy 29.464827 -237.874235) (xy 29.472636 -237.874556) (xy 29.988764 -237.874556) (xy 29.994014 -237.875115)
			(xy 30.001456 -237.882517) (xy 30.001972 -237.887764) (xy 30.001972 -237.888272) (xy 30.001972 -238.382556)
			(xy 36.046156 -238.382556) (xy 36.046156 -237.888018) (xy 36.046637 -237.882712) (xy 36.054068 -237.875139)
			(xy 36.059364 -237.874556) (xy 36.575492 -237.874556) (xy 36.583303 -237.874247) (xy 36.598174 -237.869459)
			(xy 36.604702 -237.865158) (xy 36.625791 -237.850809) (xy 36.671452 -237.828078) (xy 36.720058 -237.812619)
			(xy 36.770461 -237.804796) (xy 36.821467 -237.804796) (xy 36.87187 -237.812619) (xy 36.920476 -237.828078)
			(xy 36.966137 -237.850809) (xy 36.987226 -237.865158) (xy 36.993755 -237.869454) (xy 37.008627 -237.874235)
			(xy 37.016436 -237.874556) (xy 37.532564 -237.874556) (xy 37.537814 -237.875115) (xy 37.545256 -237.882517)
			(xy 37.545772 -237.887764) (xy 37.545772 -237.888272) (xy 37.545772 -238.382556) (xy 43.589956 -238.382556)
			(xy 43.589956 -237.888018) (xy 43.590293 -237.882581) (xy 43.597981 -237.874893) (xy 43.603418 -237.874556)
			(xy 44.119546 -237.874556) (xy 44.127355 -237.874227) (xy 44.142227 -237.869452) (xy 44.148756 -237.865158)
			(xy 44.169845 -237.850809) (xy 44.215506 -237.828078) (xy 44.264112 -237.812619) (xy 44.314515 -237.804796)
			(xy 44.365521 -237.804796) (xy 44.415924 -237.812619) (xy 44.46453 -237.828078) (xy 44.510191 -237.850809)
			(xy 44.53128 -237.865158) (xy 44.537819 -237.869436) (xy 44.552683 -237.874228) (xy 44.56049 -237.874556)
			(xy 45.076618 -237.874556) (xy 45.081989 -237.87504) (xy 45.089574 -237.882646) (xy 45.09008 -237.888018)
			(xy 45.09008 -238.382556) (xy 51.134264 -238.382556) (xy 51.134264 -237.888018) (xy 51.134738 -237.88271)
			(xy 51.142174 -237.875137) (xy 51.147472 -237.874556) (xy 51.6636 -237.874556) (xy 51.671411 -237.87425)
			(xy 51.686283 -237.86946) (xy 51.69281 -237.865158) (xy 51.713899 -237.850809) (xy 51.75956 -237.828078)
			(xy 51.808166 -237.812619) (xy 51.858569 -237.804796) (xy 51.909575 -237.804796) (xy 51.959978 -237.812619)
			(xy 52.008584 -237.828078) (xy 52.054245 -237.850809) (xy 52.075334 -237.865158) (xy 52.081861 -237.869457)
			(xy 52.096734 -237.874236) (xy 52.104544 -237.874556) (xy 52.620672 -237.874556) (xy 52.625923 -237.87511)
			(xy 52.633365 -237.882516) (xy 52.63388 -237.887764) (xy 52.63388 -237.888272) (xy 52.63388 -238.382556)
			(xy 58.678064 -238.382556) (xy 58.678064 -237.888018) (xy 58.678394 -237.882579) (xy 58.686087 -237.874891)
			(xy 58.691526 -237.874556) (xy 60.164726 -237.874556) (xy 60.170097 -237.875035) (xy 60.177682 -237.882645)
			(xy 60.178188 -237.888018) (xy 60.178188 -238.382556) (xy 167.778176 -238.382556) (xy 167.778176 -237.888018)
			(xy 167.778639 -237.882708) (xy 167.786083 -237.875133) (xy 167.791384 -237.874556) (xy 169.264584 -237.874556)
			(xy 169.269836 -237.875102) (xy 169.277278 -237.882514) (xy 169.277792 -237.887764) (xy 169.277792 -237.888272)
			(xy 169.277792 -238.382556) (xy 175.321976 -238.382556) (xy 175.321976 -237.888018) (xy 175.322295 -237.882576)
			(xy 175.329996 -237.874887) (xy 175.335438 -237.874556) (xy 175.851566 -237.874556) (xy 175.859376 -237.874235)
			(xy 175.874247 -237.869455) (xy 175.880776 -237.865158) (xy 175.901865 -237.850809) (xy 175.947526 -237.828078)
			(xy 175.996132 -237.812619) (xy 176.046535 -237.804796) (xy 176.097541 -237.804796) (xy 176.147944 -237.812619)
			(xy 176.19655 -237.828078) (xy 176.242211 -237.850809) (xy 176.2633 -237.865158) (xy 176.269835 -237.869444)
			(xy 176.284702 -237.874231) (xy 176.29251 -237.874556) (xy 176.808638 -237.874556) (xy 176.814011 -237.875027)
			(xy 176.821595 -237.882643) (xy 176.8221 -237.888018) (xy 176.8221 -238.382556) (xy 182.866284 -238.382556)
			(xy 182.866284 -237.888018) (xy 182.86674 -237.882706) (xy 182.874189 -237.875131) (xy 182.879492 -237.874556)
			(xy 183.39562 -237.874556) (xy 183.403432 -237.874258) (xy 183.418303 -237.869462) (xy 183.42483 -237.865158)
			(xy 183.445919 -237.850809) (xy 183.49158 -237.828078) (xy 183.540186 -237.812619) (xy 183.590589 -237.804796)
			(xy 183.641595 -237.804796) (xy 183.691998 -237.812619) (xy 183.740604 -237.828078) (xy 183.786265 -237.850809)
			(xy 183.807354 -237.865158) (xy 183.813877 -237.869465) (xy 183.828753 -237.874239) (xy 183.836564 -237.874556)
			(xy 184.352692 -237.874556) (xy 184.357945 -237.875096) (xy 184.365386 -237.882513) (xy 184.3659 -237.887764)
			(xy 184.3659 -237.888272) (xy 184.3659 -238.382556) (xy 190.410084 -238.382556) (xy 190.410084 -237.888018)
			(xy 190.410396 -237.882574) (xy 190.418102 -237.874884) (xy 190.423546 -237.874556) (xy 190.939674 -237.874556)
			(xy 190.947484 -237.874238) (xy 190.962356 -237.869456) (xy 190.968884 -237.865158) (xy 190.989973 -237.850809)
			(xy 191.035634 -237.828078) (xy 191.08424 -237.812619) (xy 191.134643 -237.804796) (xy 191.185649 -237.804796)
			(xy 191.236052 -237.812619) (xy 191.284658 -237.828078) (xy 191.330319 -237.850809) (xy 191.351408 -237.865158)
			(xy 191.357941 -237.869447) (xy 191.37281 -237.874232) (xy 191.380618 -237.874556) (xy 191.896746 -237.874556)
			(xy 191.90212 -237.875022) (xy 191.909704 -237.882642) (xy 191.910208 -237.888018) (xy 191.910208 -238.382556)
			(xy 197.954392 -238.382556) (xy 197.954392 -237.888018) (xy 197.954929 -237.882727) (xy 197.962322 -237.875158)
			(xy 197.9676 -237.874556) (xy 198.483728 -237.874556) (xy 198.49154 -237.874262) (xy 198.506412 -237.869463)
			(xy 198.512938 -237.865158) (xy 198.534027 -237.850809) (xy 198.579688 -237.828078) (xy 198.628294 -237.812619)
			(xy 198.678697 -237.804796) (xy 198.729703 -237.804796) (xy 198.780106 -237.812619) (xy 198.828712 -237.828078)
			(xy 198.874373 -237.850809) (xy 198.895462 -237.865158) (xy 198.902005 -237.869429) (xy 198.916866 -237.874225)
			(xy 198.924672 -237.874556) (xy 199.4408 -237.874556) (xy 199.446054 -237.875091) (xy 199.453494 -237.882511)
			(xy 199.454008 -237.887764) (xy 199.454008 -237.888272) (xy 199.454008 -238.382556) (xy 205.498192 -238.382556)
			(xy 205.498192 -237.888018) (xy 205.498729 -237.882727) (xy 205.506122 -237.875158) (xy 205.5114 -237.874556)
			(xy 206.027528 -237.874556) (xy 206.03534 -237.874262) (xy 206.050212 -237.869463) (xy 206.056738 -237.865158)
			(xy 206.077827 -237.850809) (xy 206.123488 -237.828078) (xy 206.172094 -237.812619) (xy 206.222497 -237.804796)
			(xy 206.273503 -237.804796) (xy 206.323906 -237.812619) (xy 206.372512 -237.828078) (xy 206.418173 -237.850809)
			(xy 206.439262 -237.865158) (xy 206.445805 -237.869429) (xy 206.460666 -237.874225) (xy 206.468472 -237.874556)
			(xy 206.9846 -237.874556) (xy 206.989854 -237.875091) (xy 206.997294 -237.882511) (xy 206.997808 -237.887764)
			(xy 206.997808 -237.888272) (xy 206.997808 -238.382302) (xy 268.898116 -238.382302) (xy 268.898116 -237.887764)
			(xy 268.898573 -237.882491) (xy 268.906049 -237.875049) (xy 268.911324 -237.874556) (xy 268.911832 -237.874556)
			(xy 269.427706 -237.874556) (xy 269.435517 -237.874252) (xy 269.450389 -237.86946) (xy 269.456916 -237.865158)
			(xy 269.478005 -237.850809) (xy 269.523666 -237.828078) (xy 269.572272 -237.812619) (xy 269.622675 -237.804796)
			(xy 269.673681 -237.804796) (xy 269.724084 -237.812619) (xy 269.77269 -237.828078) (xy 269.818351 -237.850809)
			(xy 269.83944 -237.865158) (xy 269.845966 -237.869459) (xy 269.86084 -237.874237) (xy 269.86865 -237.874556)
			(xy 270.384778 -237.874556) (xy 270.390083 -237.875039) (xy 270.397657 -237.882469) (xy 270.39824 -237.887764)
			(xy 270.39824 -238.382302) (xy 270.398225 -238.382556) (xy 276.442424 -238.382556) (xy 276.442424 -238.382048)
			(xy 276.442424 -237.887764) (xy 276.442874 -237.882489) (xy 276.450355 -237.875047) (xy 276.455632 -237.874556)
			(xy 276.97176 -237.874556) (xy 276.979569 -237.874233) (xy 276.994441 -237.869454) (xy 277.00097 -237.865158)
			(xy 277.022059 -237.850809) (xy 277.06772 -237.828078) (xy 277.116326 -237.812619) (xy 277.166729 -237.804796)
			(xy 277.217735 -237.804796) (xy 277.268138 -237.812619) (xy 277.316744 -237.828078) (xy 277.362405 -237.850809)
			(xy 277.383494 -237.865158) (xy 277.39003 -237.869442) (xy 277.404896 -237.87423) (xy 277.412704 -237.874556)
			(xy 277.928832 -237.874556) (xy 277.93409 -237.87507) (xy 277.941529 -237.882506) (xy 277.94204 -237.887764)
			(xy 277.94204 -238.382302) (xy 277.942018 -238.382556) (xy 283.986224 -238.382556) (xy 283.986224 -238.382048)
			(xy 283.986224 -237.887764) (xy 283.986674 -237.882489) (xy 283.994155 -237.875047) (xy 283.999432 -237.874556)
			(xy 284.51556 -237.874556) (xy 284.523369 -237.874233) (xy 284.538241 -237.869454) (xy 284.54477 -237.865158)
			(xy 284.565859 -237.850809) (xy 284.61152 -237.828078) (xy 284.660126 -237.812619) (xy 284.710529 -237.804796)
			(xy 284.761535 -237.804796) (xy 284.811938 -237.812619) (xy 284.860544 -237.828078) (xy 284.906205 -237.850809)
			(xy 284.927294 -237.865158) (xy 284.93383 -237.869442) (xy 284.948696 -237.87423) (xy 284.956504 -237.874556)
			(xy 285.472632 -237.874556) (xy 285.47789 -237.87507) (xy 285.485329 -237.882506) (xy 285.48584 -237.887764)
			(xy 285.48584 -238.382302) (xy 291.530024 -238.382302) (xy 291.530024 -237.887764) (xy 291.530474 -237.882489)
			(xy 291.537955 -237.875047) (xy 291.543232 -237.874556) (xy 291.54374 -237.874556) (xy 292.059614 -237.874556)
			(xy 292.067425 -237.874256) (xy 292.082297 -237.869461) (xy 292.088824 -237.865158) (xy 292.109913 -237.850809)
			(xy 292.155574 -237.828078) (xy 292.20418 -237.812619) (xy 292.254583 -237.804796) (xy 292.305589 -237.804796)
			(xy 292.355992 -237.812619) (xy 292.404598 -237.828078) (xy 292.450259 -237.850809) (xy 292.471348 -237.865158)
			(xy 292.477872 -237.869462) (xy 292.492748 -237.874238) (xy 292.500558 -237.874556) (xy 293.016686 -237.874556)
			(xy 293.021992 -237.875034) (xy 293.029565 -237.882468) (xy 293.030148 -237.887764) (xy 293.030148 -238.382302)
			(xy 293.030133 -238.382556) (xy 299.074332 -238.382556) (xy 299.074332 -238.382048) (xy 299.074332 -237.887764)
			(xy 299.074607 -237.882417) (xy 299.082191 -237.874876) (xy 299.08754 -237.874556) (xy 299.603668 -237.874556)
			(xy 299.611478 -237.874236) (xy 299.626349 -237.869455) (xy 299.632878 -237.865158) (xy 299.653967 -237.850809)
			(xy 299.699628 -237.828078) (xy 299.748234 -237.812619) (xy 299.798637 -237.804796) (xy 299.849643 -237.804796)
			(xy 299.900046 -237.812619) (xy 299.948652 -237.828078) (xy 299.994313 -237.850809) (xy 300.015402 -237.865158)
			(xy 300.021936 -237.869445) (xy 300.036804 -237.874231) (xy 300.044612 -237.874556) (xy 300.56074 -237.874556)
			(xy 300.565999 -237.875064) (xy 300.573437 -237.882505) (xy 300.573948 -237.887764) (xy 300.573948 -238.382302)
			(xy 306.618132 -238.382302) (xy 306.618132 -237.887764) (xy 306.618407 -237.882417) (xy 306.625991 -237.874876)
			(xy 306.63134 -237.874556) (xy 306.631848 -237.874556) (xy 308.104794 -237.874556) (xy 308.110101 -237.875029)
			(xy 308.117674 -237.882466) (xy 308.118256 -237.887764) (xy 308.118256 -238.382302) (xy 308.11824 -238.382556)
			(xy 415.718244 -238.382556) (xy 415.718244 -238.382048) (xy 415.718244 -237.887764) (xy 415.718766 -237.882509)
			(xy 415.726197 -237.875071) (xy 415.731452 -237.874556) (xy 417.204652 -237.874556) (xy 417.209969 -237.874956)
			(xy 417.21751 -237.882449) (xy 417.21786 -237.887764) (xy 417.21786 -238.382302) (xy 423.262044 -238.382302)
			(xy 423.262044 -237.887764) (xy 423.262566 -237.882509) (xy 423.269997 -237.875071) (xy 423.275252 -237.874556)
			(xy 423.27576 -237.874556) (xy 423.791634 -237.874556) (xy 423.799442 -237.874222) (xy 423.814314 -237.869451)
			(xy 423.820844 -237.865158) (xy 423.841933 -237.850809) (xy 423.887594 -237.828078) (xy 423.9362 -237.812619)
			(xy 423.986603 -237.804796) (xy 424.037609 -237.804796) (xy 424.088012 -237.812619) (xy 424.136618 -237.828078)
			(xy 424.182279 -237.850809) (xy 424.203368 -237.865158) (xy 424.20991 -237.869432) (xy 424.224772 -237.874226)
			(xy 424.232578 -237.874556) (xy 424.748706 -237.874556) (xy 424.754015 -237.875021) (xy 424.761586 -237.882464)
			(xy 424.762168 -237.887764) (xy 424.762168 -238.382302) (xy 424.762144 -238.382556) (xy 430.806352 -238.382556)
			(xy 430.806352 -238.382048) (xy 430.806352 -237.887764) (xy 430.806867 -237.882507) (xy 430.814303 -237.875068)
			(xy 430.81956 -237.874556) (xy 431.335688 -237.874556) (xy 431.343498 -237.874244) (xy 431.35837 -237.869458)
			(xy 431.364898 -237.865158) (xy 431.385987 -237.850809) (xy 431.431648 -237.828078) (xy 431.480254 -237.812619)
			(xy 431.530657 -237.804796) (xy 431.581663 -237.804796) (xy 431.632066 -237.812619) (xy 431.680672 -237.828078)
			(xy 431.726333 -237.850809) (xy 431.747422 -237.865158) (xy 431.753952 -237.869452) (xy 431.768823 -237.874234)
			(xy 431.776632 -237.874556) (xy 432.29276 -237.874556) (xy 432.298078 -237.87495) (xy 432.305619 -237.882448)
			(xy 432.305968 -237.887764) (xy 432.305968 -238.382302) (xy 438.350152 -238.382302) (xy 438.350152 -237.887764)
			(xy 438.350667 -237.882507) (xy 438.358103 -237.875068) (xy 438.36336 -237.874556) (xy 438.363868 -237.874556)
			(xy 438.879742 -237.874556) (xy 438.887551 -237.874225) (xy 438.902422 -237.869452) (xy 438.908952 -237.865158)
			(xy 438.930041 -237.850809) (xy 438.975702 -237.828078) (xy 439.024308 -237.812619) (xy 439.074711 -237.804796)
			(xy 439.125717 -237.804796) (xy 439.17612 -237.812619) (xy 439.224726 -237.828078) (xy 439.270387 -237.850809)
			(xy 439.291476 -237.865158) (xy 439.298016 -237.869435) (xy 439.312879 -237.874227) (xy 439.320686 -237.874556)
			(xy 439.836814 -237.874556) (xy 439.842124 -237.875016) (xy 439.849695 -237.882463) (xy 439.850276 -237.887764)
			(xy 439.850276 -238.382302) (xy 439.850251 -238.382556) (xy 445.89446 -238.382556) (xy 445.89446 -238.382048)
			(xy 445.89446 -237.887764) (xy 445.894968 -237.882505) (xy 445.902409 -237.875066) (xy 445.907668 -237.874556)
			(xy 446.423796 -237.874556) (xy 446.431607 -237.874248) (xy 446.446478 -237.869459) (xy 446.453006 -237.865158)
			(xy 446.474095 -237.850809) (xy 446.519756 -237.828078) (xy 446.568362 -237.812619) (xy 446.618765 -237.804796)
			(xy 446.669771 -237.804796) (xy 446.720174 -237.812619) (xy 446.76878 -237.828078) (xy 446.814441 -237.850809)
			(xy 446.83553 -237.865158) (xy 446.842058 -237.869455) (xy 446.856931 -237.874235) (xy 446.86474 -237.874556)
			(xy 447.380868 -237.874556) (xy 447.386118 -237.875112) (xy 447.393561 -237.882516) (xy 447.394076 -237.887764)
			(xy 447.394076 -238.382302) (xy 447.394052 -238.382556) (xy 453.43826 -238.382556) (xy 453.43826 -238.382048)
			(xy 453.43826 -237.887764) (xy 453.438768 -237.882505) (xy 453.446209 -237.875066) (xy 453.451468 -237.874556)
			(xy 453.967596 -237.874556) (xy 453.975407 -237.874248) (xy 453.990278 -237.869459) (xy 453.996806 -237.865158)
			(xy 454.017895 -237.850809) (xy 454.063556 -237.828078) (xy 454.112162 -237.812619) (xy 454.162565 -237.804796)
			(xy 454.213571 -237.804796) (xy 454.263974 -237.812619) (xy 454.31258 -237.828078) (xy 454.358241 -237.850809)
			(xy 454.37933 -237.865158) (xy 454.385858 -237.869455) (xy 454.400731 -237.874235) (xy 454.40854 -237.874556)
			(xy 454.924668 -237.874556) (xy 454.929918 -237.875112) (xy 454.937361 -237.882516) (xy 454.937876 -237.887764)
			(xy 454.937876 -238.382302) (xy 454.93738 -238.387603) (xy 454.929958 -238.395173) (xy 454.924668 -238.395764)
			(xy 454.408794 -238.395764) (xy 454.400983 -238.396065) (xy 454.386111 -238.400859) (xy 454.379584 -238.405162)
			(xy 454.358465 -238.419516) (xy 454.31274 -238.442241) (xy 454.264066 -238.45767) (xy 454.213599 -238.465435)
			(xy 454.188068 -238.465868) (xy 454.162537 -238.465447) (xy 454.112073 -238.457666) (xy 454.0634 -238.442233)
			(xy 454.017673 -238.419512) (xy 453.996552 -238.405162) (xy 453.990027 -238.40086) (xy 453.975152 -238.396082)
			(xy 453.967342 -238.395764) (xy 453.451468 -238.395764) (xy 453.446121 -238.39549) (xy 453.438579 -238.387905)
			(xy 453.43826 -238.382556) (xy 447.394052 -238.382556) (xy 447.39358 -238.387603) (xy 447.386158 -238.395173)
			(xy 447.380868 -238.395764) (xy 446.864994 -238.395764) (xy 446.857183 -238.396065) (xy 446.842311 -238.400859)
			(xy 446.835784 -238.405162) (xy 446.814665 -238.419516) (xy 446.76894 -238.442241) (xy 446.720266 -238.45767)
			(xy 446.669799 -238.465435) (xy 446.644268 -238.465868) (xy 446.618737 -238.465447) (xy 446.568273 -238.457666)
			(xy 446.5196 -238.442233) (xy 446.473873 -238.419512) (xy 446.452752 -238.405162) (xy 446.446227 -238.40086)
			(xy 446.431352 -238.396082) (xy 446.423542 -238.395764) (xy 445.907668 -238.395764) (xy 445.902321 -238.39549)
			(xy 445.894779 -238.387905) (xy 445.89446 -238.382556) (xy 439.850251 -238.382556) (xy 439.849752 -238.387663)
			(xy 439.842174 -238.395247) (xy 439.836814 -238.395764) (xy 439.32094 -238.395764) (xy 439.31313 -238.396084)
			(xy 439.298258 -238.400865) (xy 439.29173 -238.405162) (xy 439.270626 -238.419539) (xy 439.224896 -238.442259)
			(xy 439.176217 -238.457681) (xy 439.125746 -238.465439) (xy 439.100214 -238.465868) (xy 439.074684 -238.465424)
			(xy 439.024221 -238.45765) (xy 438.975548 -238.442223) (xy 438.92982 -238.419509) (xy 438.908698 -238.405162)
			(xy 438.902163 -238.400877) (xy 438.887296 -238.396089) (xy 438.879488 -238.395764) (xy 438.363614 -238.395764)
			(xy 438.358182 -238.395412) (xy 438.350495 -238.387734) (xy 438.350152 -238.382302) (xy 432.305968 -238.382302)
			(xy 432.305479 -238.387604) (xy 432.298052 -238.395175) (xy 432.29276 -238.395764) (xy 431.776886 -238.395764)
			(xy 431.769074 -238.396061) (xy 431.754203 -238.400858) (xy 431.747676 -238.405162) (xy 431.726559 -238.419519)
			(xy 431.680834 -238.442244) (xy 431.632159 -238.457671) (xy 431.581691 -238.465436) (xy 431.55616 -238.465868)
			(xy 431.530629 -238.465451) (xy 431.480164 -238.457669) (xy 431.431492 -238.442234) (xy 431.385765 -238.419512)
			(xy 431.364644 -238.405162) (xy 431.358121 -238.400857) (xy 431.343244 -238.396081) (xy 431.335434 -238.395764)
			(xy 430.81956 -238.395764) (xy 430.814211 -238.395496) (xy 430.80667 -238.387906) (xy 430.806352 -238.382556)
			(xy 424.762144 -238.382556) (xy 424.761651 -238.387665) (xy 424.754068 -238.39525) (xy 424.748706 -238.395764)
			(xy 424.232832 -238.395764) (xy 424.225022 -238.396081) (xy 424.21015 -238.400863) (xy 424.203622 -238.405162)
			(xy 424.182493 -238.419499) (xy 424.136771 -238.442228) (xy 424.088101 -238.457662) (xy 424.037636 -238.465432)
			(xy 424.012106 -238.465868) (xy 423.986576 -238.465428) (xy 423.936112 -238.457653) (xy 423.88744 -238.442225)
			(xy 423.841712 -238.419509) (xy 423.82059 -238.405162) (xy 423.814056 -238.400874) (xy 423.799188 -238.396088)
			(xy 423.79138 -238.395764) (xy 423.275506 -238.395764) (xy 423.270072 -238.395417) (xy 423.262386 -238.387735)
			(xy 423.262044 -238.382302) (xy 417.21786 -238.382302) (xy 417.217378 -238.387606) (xy 417.209946 -238.395177)
			(xy 417.204652 -238.395764) (xy 415.731452 -238.395764) (xy 415.726173 -238.395333) (xy 415.718731 -238.387838)
			(xy 415.718244 -238.382556) (xy 308.11824 -238.382556) (xy 308.117922 -238.387739) (xy 308.110231 -238.395425)
			(xy 308.104794 -238.395764) (xy 306.631594 -238.395764) (xy 306.62623 -238.395254) (xy 306.618644 -238.387666)
			(xy 306.618132 -238.382302) (xy 300.573948 -238.382302) (xy 300.573477 -238.387609) (xy 300.566038 -238.395181)
			(xy 300.56074 -238.395764) (xy 300.044866 -238.395764) (xy 300.037057 -238.396095) (xy 300.022185 -238.400868)
			(xy 300.015656 -238.405162) (xy 299.994545 -238.419528) (xy 299.948817 -238.44225) (xy 299.900141 -238.457676)
			(xy 299.849672 -238.465437) (xy 299.82414 -238.465868) (xy 299.798611 -238.465411) (xy 299.748148 -238.457641)
			(xy 299.699475 -238.442218) (xy 299.653747 -238.419507) (xy 299.632624 -238.405162) (xy 299.626083 -238.400887)
			(xy 299.61122 -238.396093) (xy 299.603414 -238.395764) (xy 299.08754 -238.395764) (xy 299.082202 -238.395442)
			(xy 299.074657 -238.387894) (xy 299.074332 -238.382556) (xy 293.030133 -238.382556) (xy 293.029821 -238.387741)
			(xy 293.022125 -238.395427) (xy 293.016686 -238.395764) (xy 292.500812 -238.395764) (xy 292.493001 -238.396072)
			(xy 292.478129 -238.400861) (xy 292.471602 -238.405162) (xy 292.450478 -238.419508) (xy 292.404755 -238.442235)
			(xy 292.356082 -238.457666) (xy 292.305617 -238.465434) (xy 292.280086 -238.465868) (xy 292.254556 -238.465438)
			(xy 292.204091 -238.45766) (xy 292.155419 -238.442229) (xy 292.109692 -238.41951) (xy 292.08857 -238.405162)
			(xy 292.082041 -238.400866) (xy 292.067169 -238.396085) (xy 292.05936 -238.395764) (xy 291.543486 -238.395764)
			(xy 291.538121 -238.395259) (xy 291.530536 -238.387668) (xy 291.530024 -238.382302) (xy 285.48584 -238.382302)
			(xy 285.485376 -238.387611) (xy 285.477932 -238.395183) (xy 285.472632 -238.395764) (xy 284.956758 -238.395764)
			(xy 284.948949 -238.396092) (xy 284.934077 -238.400867) (xy 284.927548 -238.405162) (xy 284.906439 -238.419531)
			(xy 284.860711 -238.442253) (xy 284.812033 -238.457677) (xy 284.761564 -238.465438) (xy 284.736032 -238.465868)
			(xy 284.710502 -238.465415) (xy 284.660039 -238.457644) (xy 284.611367 -238.44222) (xy 284.565639 -238.419507)
			(xy 284.544516 -238.405162) (xy 284.537977 -238.400884) (xy 284.523113 -238.396092) (xy 284.515306 -238.395764)
			(xy 283.999432 -238.395764) (xy 283.994093 -238.395447) (xy 283.986548 -238.387895) (xy 283.986224 -238.382556)
			(xy 277.942018 -238.382556) (xy 277.941576 -238.387611) (xy 277.934132 -238.395183) (xy 277.928832 -238.395764)
			(xy 277.412958 -238.395764) (xy 277.405149 -238.396092) (xy 277.390277 -238.400867) (xy 277.383748 -238.405162)
			(xy 277.362639 -238.419531) (xy 277.316911 -238.442253) (xy 277.268233 -238.457677) (xy 277.217764 -238.465438)
			(xy 277.192232 -238.465868) (xy 277.166702 -238.465415) (xy 277.116239 -238.457644) (xy 277.067567 -238.44222)
			(xy 277.021839 -238.419507) (xy 277.000716 -238.405162) (xy 276.994177 -238.400884) (xy 276.979313 -238.396092)
			(xy 276.971506 -238.395764) (xy 276.455632 -238.395764) (xy 276.450293 -238.395447) (xy 276.442748 -238.387895)
			(xy 276.442424 -238.382556) (xy 270.398225 -238.382556) (xy 270.39792 -238.387742) (xy 270.390219 -238.39543)
			(xy 270.384778 -238.395764) (xy 269.868904 -238.395764) (xy 269.861093 -238.396069) (xy 269.846221 -238.40086)
			(xy 269.839694 -238.405162) (xy 269.818572 -238.419511) (xy 269.772848 -238.442238) (xy 269.724175 -238.457668)
			(xy 269.673709 -238.465435) (xy 269.648178 -238.465868) (xy 269.622647 -238.465442) (xy 269.572183 -238.457663)
			(xy 269.523511 -238.44223) (xy 269.477784 -238.419511) (xy 269.456662 -238.405162) (xy 269.450135 -238.400863)
			(xy 269.435262 -238.396084) (xy 269.427452 -238.395764) (xy 268.911578 -238.395764) (xy 268.906212 -238.395264)
			(xy 268.898628 -238.387669) (xy 268.898116 -238.382302) (xy 206.997808 -238.382302) (xy 206.997808 -238.382556)
			(xy 206.997444 -238.387882) (xy 206.989925 -238.395426) (xy 206.9846 -238.395764) (xy 206.468726 -238.395764)
			(xy 206.460849 -238.396025) (xy 206.445845 -238.400827) (xy 206.439262 -238.405162) (xy 206.418187 -238.419557)
			(xy 206.372541 -238.442384) (xy 206.323934 -238.457941) (xy 206.273517 -238.465859) (xy 206.248 -238.466376)
			(xy 206.222479 -238.465908) (xy 206.172051 -238.458007) (xy 206.123439 -238.442441) (xy 206.077802 -238.41958)
			(xy 206.056738 -238.405162) (xy 206.050136 -238.400865) (xy 206.035144 -238.396066) (xy 206.027274 -238.395764)
			(xy 205.5114 -238.395764) (xy 205.506057 -238.395469) (xy 205.498513 -238.3879) (xy 205.498192 -238.382556)
			(xy 199.454008 -238.382556) (xy 199.453644 -238.387882) (xy 199.446125 -238.395426) (xy 199.4408 -238.395764)
			(xy 198.924926 -238.395764) (xy 198.917049 -238.396025) (xy 198.902045 -238.400827) (xy 198.895462 -238.405162)
			(xy 198.874387 -238.419557) (xy 198.828741 -238.442384) (xy 198.780134 -238.457941) (xy 198.729717 -238.465859)
			(xy 198.7042 -238.466376) (xy 198.678679 -238.465908) (xy 198.628251 -238.458007) (xy 198.579639 -238.442441)
			(xy 198.534002 -238.41958) (xy 198.512938 -238.405162) (xy 198.506336 -238.400865) (xy 198.491344 -238.396066)
			(xy 198.483474 -238.395764) (xy 197.9676 -238.395764) (xy 197.962257 -238.395469) (xy 197.954713 -238.3879)
			(xy 197.954392 -238.382556) (xy 191.910208 -238.382556) (xy 191.909844 -238.387882) (xy 191.902325 -238.395426)
			(xy 191.897 -238.395764) (xy 191.896492 -238.395764) (xy 191.380872 -238.395764) (xy 191.372997 -238.396045)
			(xy 191.357993 -238.400833) (xy 191.351408 -238.405162) (xy 191.330348 -238.41958) (xy 191.284697 -238.442402)
			(xy 191.236085 -238.457952) (xy 191.185664 -238.465863) (xy 191.160146 -238.466376) (xy 191.134626 -238.465885)
			(xy 191.084199 -238.457991) (xy 191.035587 -238.442432) (xy 190.989949 -238.419577) (xy 190.968884 -238.405162)
			(xy 190.962294 -238.400844) (xy 190.947293 -238.396058) (xy 190.93942 -238.395764) (xy 190.423546 -238.395764)
			(xy 190.418248 -238.395247) (xy 190.410675 -238.387842) (xy 190.410084 -238.382556) (xy 184.3659 -238.382556)
			(xy 184.365543 -238.387884) (xy 184.358019 -238.395428) (xy 184.352692 -238.395764) (xy 183.836818 -238.395764)
			(xy 183.828945 -238.396065) (xy 183.81394 -238.400839) (xy 183.807354 -238.405162) (xy 183.786281 -238.41956)
			(xy 183.740634 -238.442387) (xy 183.692027 -238.457942) (xy 183.641609 -238.46586) (xy 183.616092 -238.466376)
			(xy 183.590573 -238.465862) (xy 183.540147 -238.457975) (xy 183.491535 -238.442423) (xy 183.445896 -238.419574)
			(xy 183.42483 -238.405162) (xy 183.41823 -238.400862) (xy 183.403237 -238.396065) (xy 183.395366 -238.395764)
			(xy 182.879492 -238.395764) (xy 182.874148 -238.395474) (xy 182.866605 -238.387901) (xy 182.866284 -238.382556)
			(xy 176.8221 -238.382556) (xy 176.821743 -238.387884) (xy 176.814219 -238.395428) (xy 176.808892 -238.395764)
			(xy 176.808384 -238.395764) (xy 176.292764 -238.395764) (xy 176.284889 -238.396042) (xy 176.269885 -238.400832)
			(xy 176.2633 -238.405162) (xy 176.242214 -238.41954) (xy 176.196572 -238.442371) (xy 176.147969 -238.457933)
			(xy 176.097554 -238.465856) (xy 176.072038 -238.466376) (xy 176.046518 -238.465889) (xy 175.99609 -238.457994)
			(xy 175.947479 -238.442434) (xy 175.901841 -238.419578) (xy 175.880776 -238.405162) (xy 175.874188 -238.400841)
			(xy 175.859185 -238.396057) (xy 175.851312 -238.395764) (xy 175.335438 -238.395764) (xy 175.330139 -238.395252)
			(xy 175.322566 -238.387843) (xy 175.321976 -238.382556) (xy 169.277792 -238.382556) (xy 169.277442 -238.387886)
			(xy 169.269914 -238.395431) (xy 169.264584 -238.395764) (xy 167.791384 -238.395764) (xy 167.786039 -238.39548)
			(xy 167.778496 -238.387903) (xy 167.778176 -238.382556) (xy 60.178188 -238.382556) (xy 60.177842 -238.387887)
			(xy 60.170311 -238.395432) (xy 60.16498 -238.395764) (xy 60.164472 -238.395764) (xy 58.691526 -238.395764)
			(xy 58.686226 -238.39526) (xy 58.678654 -238.387845) (xy 58.678064 -238.382556) (xy 52.63388 -238.382556)
			(xy 52.633541 -238.387889) (xy 52.626005 -238.395434) (xy 52.620672 -238.395764) (xy 52.104798 -238.395764)
			(xy 52.096924 -238.396056) (xy 52.08192 -238.400836) (xy 52.075334 -238.405162) (xy 52.054266 -238.419569)
			(xy 52.008618 -238.442393) (xy 51.960009 -238.457947) (xy 51.90959 -238.465861) (xy 51.884072 -238.466376)
			(xy 51.858552 -238.465872) (xy 51.808126 -238.457982) (xy 51.759514 -238.442427) (xy 51.713875 -238.419576)
			(xy 51.69281 -238.405162) (xy 51.686214 -238.400854) (xy 51.671218 -238.396062) (xy 51.663346 -238.395764)
			(xy 51.147472 -238.395764) (xy 51.142125 -238.395488) (xy 51.134583 -238.387905) (xy 51.134264 -238.382556)
			(xy 45.09008 -238.382556) (xy 45.089741 -238.387889) (xy 45.082205 -238.395434) (xy 45.076872 -238.395764)
			(xy 45.076364 -238.395764) (xy 44.560744 -238.395764) (xy 44.552868 -238.396033) (xy 44.537864 -238.400829)
			(xy 44.53128 -238.405162) (xy 44.5102 -238.419549) (xy 44.464556 -238.442378) (xy 44.415951 -238.457937)
			(xy 44.365534 -238.465858) (xy 44.340018 -238.466376) (xy 44.314497 -238.465899) (xy 44.26407 -238.458001)
			(xy 44.215458 -238.442438) (xy 44.16982 -238.419579) (xy 44.148756 -238.405162) (xy 44.142172 -238.400833)
			(xy 44.127166 -238.396054) (xy 44.119292 -238.395764) (xy 43.603418 -238.395764) (xy 43.598117 -238.395265)
			(xy 43.590545 -238.387846) (xy 43.589956 -238.382556) (xy 37.545772 -238.382556) (xy 37.54544 -238.387891)
			(xy 37.537899 -238.395437) (xy 37.532564 -238.395764) (xy 37.01669 -238.395764) (xy 37.008816 -238.396053)
			(xy 36.993811 -238.400835) (xy 36.987226 -238.405162) (xy 36.966161 -238.419572) (xy 36.920511 -238.442396)
			(xy 36.871902 -238.457948) (xy 36.821482 -238.465862) (xy 36.795964 -238.466376) (xy 36.770444 -238.465876)
			(xy 36.720018 -238.457985) (xy 36.671406 -238.442428) (xy 36.625767 -238.419576) (xy 36.604702 -238.405162)
			(xy 36.598108 -238.400851) (xy 36.58311 -238.396061) (xy 36.575238 -238.395764) (xy 36.059364 -238.395764)
			(xy 36.054016 -238.395493) (xy 36.046475 -238.387906) (xy 36.046156 -238.382556) (xy 30.001972 -238.382556)
			(xy 30.00164 -238.387891) (xy 29.994099 -238.395437) (xy 29.988764 -238.395764) (xy 29.47289 -238.395764)
			(xy 29.465016 -238.396053) (xy 29.450011 -238.400835) (xy 29.443426 -238.405162) (xy 29.422361 -238.419572)
			(xy 29.376711 -238.442396) (xy 29.328102 -238.457948) (xy 29.277682 -238.465862) (xy 29.252164 -238.466376)
			(xy 29.226644 -238.465876) (xy 29.176218 -238.457985) (xy 29.127606 -238.442428) (xy 29.081967 -238.419576)
			(xy 29.060902 -238.405162) (xy 29.054308 -238.400851) (xy 29.03931 -238.396061) (xy 29.031438 -238.395764)
			(xy 28.515564 -238.395764) (xy 28.510216 -238.395493) (xy 28.502675 -238.387906) (xy 28.502356 -238.382556)
			(xy 22.458172 -238.382556) (xy 22.45784 -238.387891) (xy 22.450299 -238.395437) (xy 22.444964 -238.395764)
			(xy 22.444456 -238.395764) (xy 21.928836 -238.395764) (xy 21.920959 -238.39603) (xy 21.905956 -238.400828)
			(xy 21.899372 -238.405162) (xy 21.878294 -238.419552) (xy 21.832649 -238.442381) (xy 21.784043 -238.457939)
			(xy 21.733627 -238.465858) (xy 21.70811 -238.466376) (xy 21.682589 -238.465903) (xy 21.632161 -238.458004)
			(xy 21.58355 -238.442439) (xy 21.537912 -238.41958) (xy 21.516848 -238.405162) (xy 21.510266 -238.40083)
			(xy 21.495259 -238.396053) (xy 21.487384 -238.395764) (xy 20.97151 -238.395764) (xy 20.966208 -238.395271)
			(xy 20.958636 -238.387848) (xy 20.958048 -238.382556) (xy 2.509012 -238.382556) (xy 2.509012 -239.23244)
			(xy 16.85798 -239.23244) (xy 16.85798 -238.737902) (xy 16.858285 -238.732457) (xy 16.865996 -238.724769)
			(xy 16.871442 -238.72444) (xy 17.38757 -238.72444) (xy 17.39538 -238.724124) (xy 17.410252 -238.71934)
			(xy 17.41678 -238.715042) (xy 17.437869 -238.700693) (xy 17.48353 -238.677962) (xy 17.532136 -238.662503)
			(xy 17.582539 -238.65468) (xy 17.633545 -238.65468) (xy 17.683948 -238.662503) (xy 17.732554 -238.677962)
			(xy 17.778215 -238.700693) (xy 17.799304 -238.715042) (xy 17.805839 -238.719328) (xy 17.820706 -238.724115)
			(xy 17.828514 -238.72444) (xy 18.344642 -238.72444) (xy 18.350012 -238.724923) (xy 18.357595 -238.732531)
			(xy 18.358104 -238.737902) (xy 18.358104 -239.23244) (xy 20.958048 -239.23244) (xy 20.958048 -238.737902)
			(xy 20.958382 -238.732465) (xy 20.966073 -238.724779) (xy 20.97151 -238.72444) (xy 21.487638 -238.72444)
			(xy 21.495447 -238.72411) (xy 21.510319 -238.719336) (xy 21.516848 -238.715042) (xy 21.537937 -238.700693)
			(xy 21.583598 -238.677962) (xy 21.632204 -238.662503) (xy 21.682607 -238.65468) (xy 21.733613 -238.65468)
			(xy 21.784016 -238.662503) (xy 21.832622 -238.677962) (xy 21.878283 -238.700693) (xy 21.899372 -238.715042)
			(xy 21.905914 -238.719316) (xy 21.920776 -238.724111) (xy 21.928582 -238.72444) (xy 22.44471 -238.72444)
			(xy 22.450076 -238.724944) (xy 22.457661 -238.732536) (xy 22.458172 -238.737902) (xy 22.458172 -239.23244)
			(xy 24.402288 -239.23244) (xy 24.402288 -238.737902) (xy 24.40273 -238.732587) (xy 24.410189 -238.725013)
			(xy 24.415496 -238.72444) (xy 24.931624 -238.72444) (xy 24.939436 -238.724147) (xy 24.954308 -238.719348)
			(xy 24.960834 -238.715042) (xy 24.981923 -238.700693) (xy 25.027584 -238.677962) (xy 25.07619 -238.662503)
			(xy 25.126593 -238.65468) (xy 25.177599 -238.65468) (xy 25.228002 -238.662503) (xy 25.276608 -238.677962)
			(xy 25.322269 -238.700693) (xy 25.343358 -238.715042) (xy 25.349881 -238.719349) (xy 25.364757 -238.724123)
			(xy 25.372568 -238.72444) (xy 25.888696 -238.72444) (xy 25.894039 -238.724734) (xy 25.901583 -238.732304)
			(xy 25.901904 -238.737648) (xy 25.901904 -238.738156) (xy 25.901904 -239.23244) (xy 28.502356 -239.23244)
			(xy 28.502356 -238.737902) (xy 28.502826 -238.732594) (xy 28.510266 -238.725022) (xy 28.515564 -238.72444)
			(xy 29.031692 -238.72444) (xy 29.039503 -238.724133) (xy 29.054375 -238.719343) (xy 29.060902 -238.715042)
			(xy 29.081991 -238.700693) (xy 29.127652 -238.677962) (xy 29.176258 -238.662503) (xy 29.226661 -238.65468)
			(xy 29.277667 -238.65468) (xy 29.32807 -238.662503) (xy 29.376676 -238.677962) (xy 29.422337 -238.700693)
			(xy 29.443426 -238.715042) (xy 29.449956 -238.719336) (xy 29.464827 -238.724118) (xy 29.472636 -238.72444)
			(xy 29.988764 -238.72444) (xy 29.994103 -238.724756) (xy 30.001649 -238.732309) (xy 30.001972 -238.737648)
			(xy 30.001972 -238.738156) (xy 30.001972 -239.23244) (xy 31.946088 -239.23244) (xy 31.946088 -238.737902)
			(xy 31.94653 -238.732587) (xy 31.953989 -238.725013) (xy 31.959296 -238.72444) (xy 32.475424 -238.72444)
			(xy 32.483236 -238.724147) (xy 32.498108 -238.719348) (xy 32.504634 -238.715042) (xy 32.525723 -238.700693)
			(xy 32.571384 -238.677962) (xy 32.61999 -238.662503) (xy 32.670393 -238.65468) (xy 32.721399 -238.65468)
			(xy 32.771802 -238.662503) (xy 32.820408 -238.677962) (xy 32.866069 -238.700693) (xy 32.887158 -238.715042)
			(xy 32.893681 -238.719349) (xy 32.908557 -238.724123) (xy 32.916368 -238.72444) (xy 33.432496 -238.72444)
			(xy 33.437839 -238.724734) (xy 33.445383 -238.732304) (xy 33.445704 -238.737648) (xy 33.445704 -238.738156)
			(xy 33.445704 -239.23244) (xy 36.046156 -239.23244) (xy 36.046156 -238.737902) (xy 36.046626 -238.732594)
			(xy 36.054066 -238.725022) (xy 36.059364 -238.72444) (xy 36.575492 -238.72444) (xy 36.583303 -238.724133)
			(xy 36.598175 -238.719343) (xy 36.604702 -238.715042) (xy 36.625791 -238.700693) (xy 36.671452 -238.677962)
			(xy 36.720058 -238.662503) (xy 36.770461 -238.65468) (xy 36.821467 -238.65468) (xy 36.87187 -238.662503)
			(xy 36.920476 -238.677962) (xy 36.966137 -238.700693) (xy 36.987226 -238.715042) (xy 36.993756 -238.719336)
			(xy 37.008627 -238.724118) (xy 37.016436 -238.72444) (xy 37.532564 -238.72444) (xy 37.537903 -238.724756)
			(xy 37.545449 -238.732309) (xy 37.545772 -238.737648) (xy 37.545772 -238.738156) (xy 37.545772 -239.23244)
			(xy 39.489888 -239.23244) (xy 39.489888 -238.737902) (xy 39.490447 -238.73255) (xy 39.498 -238.724967)
			(xy 39.50335 -238.72444) (xy 40.019478 -238.72444) (xy 40.027288 -238.724127) (xy 40.04216 -238.719342)
			(xy 40.048688 -238.715042) (xy 40.069777 -238.700693) (xy 40.115438 -238.677962) (xy 40.164044 -238.662503)
			(xy 40.214447 -238.65468) (xy 40.265453 -238.65468) (xy 40.315856 -238.662503) (xy 40.364462 -238.677962)
			(xy 40.410123 -238.700693) (xy 40.431212 -238.715042) (xy 40.437745 -238.719331) (xy 40.452614 -238.724116)
			(xy 40.460422 -238.72444) (xy 40.97655 -238.72444) (xy 40.98192 -238.724918) (xy 40.989503 -238.73253)
			(xy 40.990012 -238.737902) (xy 40.990012 -239.23244) (xy 43.589956 -239.23244) (xy 43.589956 -238.737902)
			(xy 43.590283 -238.732463) (xy 43.597979 -238.724776) (xy 43.603418 -238.72444) (xy 44.119546 -238.72444)
			(xy 44.127355 -238.724113) (xy 44.142227 -238.719337) (xy 44.148756 -238.715042) (xy 44.169845 -238.700693)
			(xy 44.215506 -238.677962) (xy 44.264112 -238.662503) (xy 44.314515 -238.65468) (xy 44.365521 -238.65468)
			(xy 44.415924 -238.662503) (xy 44.46453 -238.677962) (xy 44.510191 -238.700693) (xy 44.53128 -238.715042)
			(xy 44.53782 -238.719319) (xy 44.552683 -238.724112) (xy 44.56049 -238.72444) (xy 45.076618 -238.72444)
			(xy 45.081985 -238.724938) (xy 45.08957 -238.732535) (xy 45.09008 -238.737902) (xy 45.09008 -239.23244)
			(xy 47.034196 -239.23244) (xy 47.034196 -238.737902) (xy 47.034719 -238.732608) (xy 47.042122 -238.72504)
			(xy 47.047404 -238.72444) (xy 47.563532 -238.72444) (xy 47.571341 -238.724107) (xy 47.586212 -238.719336)
			(xy 47.592742 -238.715042) (xy 47.613831 -238.700693) (xy 47.659492 -238.677962) (xy 47.708098 -238.662503)
			(xy 47.758501 -238.65468) (xy 47.809507 -238.65468) (xy 47.85991 -238.662503) (xy 47.908516 -238.677962)
			(xy 47.954177 -238.700693) (xy 47.975266 -238.715042) (xy 47.981809 -238.719313) (xy 47.99667 -238.72411)
			(xy 48.004476 -238.72444) (xy 48.520604 -238.72444) (xy 48.525949 -238.724729) (xy 48.533492 -238.732302)
			(xy 48.533812 -238.737648) (xy 48.533812 -238.738156) (xy 48.533812 -239.23244) (xy 51.134264 -239.23244)
			(xy 51.134264 -238.737902) (xy 51.134727 -238.732592) (xy 51.142172 -238.72502) (xy 51.147472 -238.72444)
			(xy 51.6636 -238.72444) (xy 51.671411 -238.724136) (xy 51.686283 -238.719344) (xy 51.69281 -238.715042)
			(xy 51.713899 -238.700693) (xy 51.75956 -238.677962) (xy 51.808166 -238.662503) (xy 51.858569 -238.65468)
			(xy 51.909575 -238.65468) (xy 51.959978 -238.662503) (xy 52.008584 -238.677962) (xy 52.054245 -238.700693)
			(xy 52.075334 -238.715042) (xy 52.081862 -238.719339) (xy 52.096735 -238.72412) (xy 52.104544 -238.72444)
			(xy 52.620672 -238.72444) (xy 52.626012 -238.72475) (xy 52.633558 -238.732307) (xy 52.63388 -238.737648)
			(xy 52.63388 -238.738156) (xy 52.63388 -239.23244) (xy 54.577996 -239.23244) (xy 54.577996 -238.737902)
			(xy 54.578547 -238.732548) (xy 54.586106 -238.724965) (xy 54.591458 -238.72444) (xy 56.064658 -238.72444)
			(xy 56.070088 -238.724808) (xy 56.077776 -238.732473) (xy 56.07812 -238.737902) (xy 56.07812 -239.23244)
			(xy 58.678064 -239.23244) (xy 58.678064 -238.737902) (xy 58.678383 -238.732461) (xy 58.686085 -238.724774)
			(xy 58.691526 -238.72444) (xy 60.164726 -238.72444) (xy 60.170093 -238.724933) (xy 60.177678 -238.732533)
			(xy 60.178188 -238.737902) (xy 60.178188 -239.23244) (xy 163.678108 -239.23244) (xy 163.678108 -238.737902)
			(xy 163.678621 -238.732606) (xy 163.686031 -238.725036) (xy 163.691316 -238.72444) (xy 165.164516 -238.72444)
			(xy 165.169862 -238.724721) (xy 165.177405 -238.7323) (xy 165.177724 -238.737648) (xy 165.177724 -238.738156)
			(xy 165.177724 -239.23244) (xy 167.778176 -239.23244) (xy 167.778176 -238.737902) (xy 167.778629 -238.73259)
			(xy 167.78608 -238.725016) (xy 167.791384 -238.72444) (xy 169.264584 -238.72444) (xy 169.269926 -238.724742)
			(xy 169.277471 -238.732305) (xy 169.277792 -238.737648) (xy 169.277792 -238.738156) (xy 169.277792 -239.23244)
			(xy 171.221908 -239.23244) (xy 171.221908 -238.737902) (xy 171.222449 -238.732546) (xy 171.230015 -238.724961)
			(xy 171.23537 -238.72444) (xy 171.751498 -238.72444) (xy 171.759309 -238.724135) (xy 171.774181 -238.719344)
			(xy 171.780708 -238.715042) (xy 171.801797 -238.700693) (xy 171.847458 -238.677962) (xy 171.896064 -238.662503)
			(xy 171.946467 -238.65468) (xy 171.997473 -238.65468) (xy 172.047876 -238.662503) (xy 172.096482 -238.677962)
			(xy 172.142143 -238.700693) (xy 172.163232 -238.715042) (xy 172.169761 -238.719339) (xy 172.184633 -238.724119)
			(xy 172.192442 -238.72444) (xy 172.70857 -238.72444) (xy 172.714001 -238.7248) (xy 172.721689 -238.732472)
			(xy 172.722032 -238.737902) (xy 172.722032 -239.23244) (xy 175.321976 -239.23244) (xy 175.321976 -238.737902)
			(xy 175.322285 -238.732458) (xy 175.329993 -238.72477) (xy 175.335438 -238.72444) (xy 175.851566 -238.72444)
			(xy 175.859376 -238.724122) (xy 175.874248 -238.71934) (xy 175.880776 -238.715042) (xy 175.901865 -238.700693)
			(xy 175.947526 -238.677962) (xy 175.996132 -238.662503) (xy 176.046535 -238.65468) (xy 176.097541 -238.65468)
			(xy 176.147944 -238.662503) (xy 176.19655 -238.677962) (xy 176.242211 -238.700693) (xy 176.2633 -238.715042)
			(xy 176.269836 -238.719326) (xy 176.284702 -238.724115) (xy 176.29251 -238.72444) (xy 176.808638 -238.72444)
			(xy 176.814007 -238.724926) (xy 176.82159 -238.732532) (xy 176.8221 -238.737902) (xy 176.8221 -239.23244)
			(xy 178.766216 -239.23244) (xy 178.766216 -238.737902) (xy 178.766722 -238.732604) (xy 178.774137 -238.725034)
			(xy 178.779424 -238.72444) (xy 179.295552 -238.72444) (xy 179.303361 -238.724116) (xy 179.318233 -238.719338)
			(xy 179.324762 -238.715042) (xy 179.345851 -238.700693) (xy 179.391512 -238.677962) (xy 179.440118 -238.662503)
			(xy 179.490521 -238.65468) (xy 179.541527 -238.65468) (xy 179.59193 -238.662503) (xy 179.640536 -238.677962)
			(xy 179.686197 -238.700693) (xy 179.707286 -238.715042) (xy 179.713825 -238.719321) (xy 179.728689 -238.724113)
			(xy 179.736496 -238.72444) (xy 180.252624 -238.72444) (xy 180.257971 -238.724716) (xy 180.265513 -238.732299)
			(xy 180.265832 -238.737648) (xy 180.265832 -238.738156) (xy 180.265832 -239.23244) (xy 182.866284 -239.23244)
			(xy 182.866284 -238.737902) (xy 182.86673 -238.732588) (xy 182.874186 -238.725014) (xy 182.879492 -238.72444)
			(xy 183.39562 -238.72444) (xy 183.403432 -238.724145) (xy 183.418304 -238.719347) (xy 183.42483 -238.715042)
			(xy 183.445919 -238.700693) (xy 183.49158 -238.677962) (xy 183.540186 -238.662503) (xy 183.590589 -238.65468)
			(xy 183.641595 -238.65468) (xy 183.691998 -238.662503) (xy 183.740604 -238.677962) (xy 183.786265 -238.700693)
			(xy 183.807354 -238.715042) (xy 183.813878 -238.719347) (xy 183.828754 -238.724123) (xy 183.836564 -238.72444)
			(xy 184.352692 -238.72444) (xy 184.358035 -238.724737) (xy 184.365579 -238.732304) (xy 184.3659 -238.737648)
			(xy 184.3659 -238.738156) (xy 184.3659 -239.23244) (xy 186.310016 -239.23244) (xy 186.310016 -238.737902)
			(xy 186.310549 -238.732544) (xy 186.318121 -238.724959) (xy 186.323478 -238.72444) (xy 186.839606 -238.72444)
			(xy 186.847417 -238.724139) (xy 186.862289 -238.719345) (xy 186.868816 -238.715042) (xy 186.889905 -238.700693)
			(xy 186.935566 -238.677962) (xy 186.984172 -238.662503) (xy 187.034575 -238.65468) (xy 187.085581 -238.65468)
			(xy 187.135984 -238.662503) (xy 187.18459 -238.677962) (xy 187.230251 -238.700693) (xy 187.25134 -238.715042)
			(xy 187.257867 -238.719342) (xy 187.27274 -238.724121) (xy 187.28055 -238.72444) (xy 187.796678 -238.72444)
			(xy 187.80211 -238.724794) (xy 187.809798 -238.73247) (xy 187.81014 -238.737902) (xy 187.81014 -239.23244)
			(xy 190.410084 -239.23244) (xy 190.410084 -238.737902) (xy 190.410385 -238.732456) (xy 190.418099 -238.724768)
			(xy 190.423546 -238.72444) (xy 190.939674 -238.72444) (xy 190.947484 -238.724125) (xy 190.962356 -238.719341)
			(xy 190.968884 -238.715042) (xy 190.989973 -238.700693) (xy 191.035634 -238.677962) (xy 191.08424 -238.662503)
			(xy 191.134643 -238.65468) (xy 191.185649 -238.65468) (xy 191.236052 -238.662503) (xy 191.284658 -238.677962)
			(xy 191.330319 -238.700693) (xy 191.351408 -238.715042) (xy 191.357942 -238.719329) (xy 191.37281 -238.724116)
			(xy 191.380618 -238.72444) (xy 191.896746 -238.72444) (xy 191.902116 -238.72492) (xy 191.909699 -238.73253)
			(xy 191.910208 -238.737902) (xy 191.910208 -239.23244) (xy 193.854324 -239.23244) (xy 193.854324 -238.737902)
			(xy 193.854823 -238.732602) (xy 193.862243 -238.725032) (xy 193.867532 -238.72444) (xy 194.38366 -238.72444)
			(xy 194.39147 -238.724119) (xy 194.406341 -238.719339) (xy 194.41287 -238.715042) (xy 194.433959 -238.700693)
			(xy 194.47962 -238.677962) (xy 194.528226 -238.662503) (xy 194.578629 -238.65468) (xy 194.629635 -238.65468)
			(xy 194.680038 -238.662503) (xy 194.728644 -238.677962) (xy 194.774305 -238.700693) (xy 194.795394 -238.715042)
			(xy 194.801931 -238.719324) (xy 194.816797 -238.724114) (xy 194.824604 -238.72444) (xy 195.340732 -238.72444)
			(xy 195.34608 -238.72471) (xy 195.353622 -238.732298) (xy 195.35394 -238.737648) (xy 195.35394 -238.738156)
			(xy 195.35394 -239.23244) (xy 197.954392 -239.23244) (xy 197.954392 -238.737902) (xy 197.954919 -238.732609)
			(xy 197.962319 -238.725041) (xy 197.9676 -238.72444) (xy 198.483728 -238.72444) (xy 198.49154 -238.724149)
			(xy 198.506412 -238.719348) (xy 198.512938 -238.715042) (xy 198.534027 -238.700693) (xy 198.579688 -238.677962)
			(xy 198.628294 -238.662503) (xy 198.678697 -238.65468) (xy 198.729703 -238.65468) (xy 198.780106 -238.662503)
			(xy 198.828712 -238.677962) (xy 198.874373 -238.700693) (xy 198.895462 -238.715042) (xy 198.902006 -238.719312)
			(xy 198.916866 -238.724109) (xy 198.924672 -238.72444) (xy 199.4408 -238.72444) (xy 199.446144 -238.724731)
			(xy 199.453688 -238.732303) (xy 199.454008 -238.737648) (xy 199.454008 -238.738156) (xy 199.454008 -239.23244)
			(xy 201.398124 -239.23244) (xy 201.398124 -238.737902) (xy 201.398623 -238.732602) (xy 201.406043 -238.725032)
			(xy 201.411332 -238.72444) (xy 201.92746 -238.72444) (xy 201.93527 -238.724119) (xy 201.950141 -238.719339)
			(xy 201.95667 -238.715042) (xy 201.977759 -238.700693) (xy 202.02342 -238.677962) (xy 202.072026 -238.662503)
			(xy 202.122429 -238.65468) (xy 202.173435 -238.65468) (xy 202.223838 -238.662503) (xy 202.272444 -238.677962)
			(xy 202.318105 -238.700693) (xy 202.339194 -238.715042) (xy 202.345731 -238.719324) (xy 202.360597 -238.724114)
			(xy 202.368404 -238.72444) (xy 202.884532 -238.72444) (xy 202.88988 -238.72471) (xy 202.897422 -238.732298)
			(xy 202.89774 -238.737648) (xy 202.89774 -238.738156) (xy 202.89774 -239.23244) (xy 205.498192 -239.23244)
			(xy 205.498192 -238.737902) (xy 205.498719 -238.732609) (xy 205.506119 -238.725041) (xy 205.5114 -238.72444)
			(xy 206.027528 -238.72444) (xy 206.03534 -238.724149) (xy 206.050212 -238.719348) (xy 206.056738 -238.715042)
			(xy 206.077827 -238.700693) (xy 206.123488 -238.677962) (xy 206.172094 -238.662503) (xy 206.222497 -238.65468)
			(xy 206.273503 -238.65468) (xy 206.323906 -238.662503) (xy 206.372512 -238.677962) (xy 206.418173 -238.700693)
			(xy 206.439262 -238.715042) (xy 206.445806 -238.719312) (xy 206.460666 -238.724109) (xy 206.468472 -238.72444)
			(xy 206.9846 -238.72444) (xy 206.989944 -238.724731) (xy 206.997488 -238.732303) (xy 206.997808 -238.737648)
			(xy 206.997808 -238.738156) (xy 206.997808 -239.232186) (xy 264.798048 -239.232186) (xy 264.798048 -238.737648)
			(xy 264.798455 -238.732333) (xy 264.805943 -238.724792) (xy 264.811256 -238.72444) (xy 264.811764 -238.72444)
			(xy 265.327638 -238.72444) (xy 265.335447 -238.72411) (xy 265.350319 -238.719336) (xy 265.356848 -238.715042)
			(xy 265.377937 -238.700693) (xy 265.423598 -238.677962) (xy 265.472204 -238.662503) (xy 265.522607 -238.65468)
			(xy 265.573613 -238.65468) (xy 265.624016 -238.662503) (xy 265.672622 -238.677962) (xy 265.718283 -238.700693)
			(xy 265.739372 -238.715042) (xy 265.745914 -238.719316) (xy 265.760776 -238.724111) (xy 265.768582 -238.72444)
			(xy 266.28471 -238.72444) (xy 266.290015 -238.724917) (xy 266.297586 -238.732352) (xy 266.298172 -238.737648)
			(xy 266.298172 -239.232186) (xy 268.898116 -239.232186) (xy 268.898116 -238.737648) (xy 268.898462 -238.732316)
			(xy 268.905993 -238.724771) (xy 268.911324 -238.72444) (xy 268.911832 -238.72444) (xy 269.427706 -238.72444)
			(xy 269.435517 -238.724139) (xy 269.450389 -238.719345) (xy 269.456916 -238.715042) (xy 269.478005 -238.700693)
			(xy 269.523666 -238.677962) (xy 269.572272 -238.662503) (xy 269.622675 -238.65468) (xy 269.673681 -238.65468)
			(xy 269.724084 -238.662503) (xy 269.77269 -238.677962) (xy 269.818351 -238.700693) (xy 269.83944 -238.715042)
			(xy 269.845967 -238.719342) (xy 269.86084 -238.724121) (xy 269.86865 -238.72444) (xy 270.384778 -238.72444)
			(xy 270.39008 -238.724938) (xy 270.397652 -238.732357) (xy 270.39824 -238.737648) (xy 270.39824 -239.232186)
			(xy 270.398225 -239.23244) (xy 272.342356 -239.23244) (xy 272.342356 -239.231932) (xy 272.342356 -238.737648)
			(xy 272.342756 -238.732331) (xy 272.350249 -238.72479) (xy 272.355564 -238.72444) (xy 272.871692 -238.72444)
			(xy 272.879503 -238.724133) (xy 272.894375 -238.719343) (xy 272.900902 -238.715042) (xy 272.921991 -238.700693)
			(xy 272.967652 -238.677962) (xy 273.016258 -238.662503) (xy 273.066661 -238.65468) (xy 273.117667 -238.65468)
			(xy 273.16807 -238.662503) (xy 273.216676 -238.677962) (xy 273.262337 -238.700693) (xy 273.283426 -238.715042)
			(xy 273.289956 -238.719336) (xy 273.304827 -238.724118) (xy 273.312636 -238.72444) (xy 273.828764 -238.72444)
			(xy 273.834103 -238.724756) (xy 273.841649 -238.732309) (xy 273.841972 -238.737648) (xy 273.841972 -239.232186)
			(xy 273.841948 -239.23244) (xy 276.442424 -239.23244) (xy 276.442424 -239.231932) (xy 276.442424 -238.737648)
			(xy 276.442762 -238.732314) (xy 276.450299 -238.724769) (xy 276.455632 -238.72444) (xy 276.97176 -238.72444)
			(xy 276.97957 -238.724119) (xy 276.994441 -238.719339) (xy 277.00097 -238.715042) (xy 277.022059 -238.700693)
			(xy 277.06772 -238.677962) (xy 277.116326 -238.662503) (xy 277.166729 -238.65468) (xy 277.217735 -238.65468)
			(xy 277.268138 -238.662503) (xy 277.316744 -238.677962) (xy 277.362405 -238.700693) (xy 277.383494 -238.715042)
			(xy 277.390031 -238.719324) (xy 277.404897 -238.724114) (xy 277.412704 -238.72444) (xy 277.928832 -238.72444)
			(xy 277.93418 -238.72471) (xy 277.941722 -238.732298) (xy 277.94204 -238.737648) (xy 277.94204 -239.232186)
			(xy 277.942017 -239.23244) (xy 279.886156 -239.23244) (xy 279.886156 -239.231932) (xy 279.886156 -238.737648)
			(xy 279.886556 -238.732331) (xy 279.894049 -238.72479) (xy 279.899364 -238.72444) (xy 280.415492 -238.72444)
			(xy 280.423303 -238.724133) (xy 280.438175 -238.719343) (xy 280.444702 -238.715042) (xy 280.465791 -238.700693)
			(xy 280.511452 -238.677962) (xy 280.560058 -238.662503) (xy 280.610461 -238.65468) (xy 280.661467 -238.65468)
			(xy 280.71187 -238.662503) (xy 280.760476 -238.677962) (xy 280.806137 -238.700693) (xy 280.827226 -238.715042)
			(xy 280.833756 -238.719336) (xy 280.848627 -238.724118) (xy 280.856436 -238.72444) (xy 281.372564 -238.72444)
			(xy 281.377903 -238.724756) (xy 281.385449 -238.732309) (xy 281.385772 -238.737648) (xy 281.385772 -239.232186)
			(xy 281.385748 -239.23244) (xy 283.986224 -239.23244) (xy 283.986224 -239.231932) (xy 283.986224 -238.737648)
			(xy 283.986562 -238.732314) (xy 283.994099 -238.724769) (xy 283.999432 -238.72444) (xy 284.51556 -238.72444)
			(xy 284.52337 -238.724119) (xy 284.538241 -238.719339) (xy 284.54477 -238.715042) (xy 284.565859 -238.700693)
			(xy 284.61152 -238.677962) (xy 284.660126 -238.662503) (xy 284.710529 -238.65468) (xy 284.761535 -238.65468)
			(xy 284.811938 -238.662503) (xy 284.860544 -238.677962) (xy 284.906205 -238.700693) (xy 284.927294 -238.715042)
			(xy 284.933831 -238.719324) (xy 284.948697 -238.724114) (xy 284.956504 -238.72444) (xy 285.472632 -238.72444)
			(xy 285.47798 -238.72471) (xy 285.485522 -238.732298) (xy 285.48584 -238.737648) (xy 285.48584 -239.232186)
			(xy 287.429956 -239.232186) (xy 287.429956 -238.737648) (xy 287.430356 -238.732331) (xy 287.437849 -238.72479)
			(xy 287.443164 -238.72444) (xy 287.443672 -238.72444) (xy 287.959546 -238.72444) (xy 287.967355 -238.724113)
			(xy 287.982227 -238.719337) (xy 287.988756 -238.715042) (xy 288.009845 -238.700693) (xy 288.055506 -238.677962)
			(xy 288.104112 -238.662503) (xy 288.154515 -238.65468) (xy 288.205521 -238.65468) (xy 288.255924 -238.662503)
			(xy 288.30453 -238.677962) (xy 288.350191 -238.700693) (xy 288.37128 -238.715042) (xy 288.37782 -238.719319)
			(xy 288.392683 -238.724112) (xy 288.40049 -238.72444) (xy 288.916618 -238.72444) (xy 288.921924 -238.724911)
			(xy 288.929495 -238.732351) (xy 288.93008 -238.737648) (xy 288.93008 -239.232186) (xy 291.530024 -239.232186)
			(xy 291.530024 -238.737648) (xy 291.530362 -238.732314) (xy 291.537899 -238.724769) (xy 291.543232 -238.72444)
			(xy 291.54374 -238.72444) (xy 292.059614 -238.72444) (xy 292.067426 -238.724143) (xy 292.082298 -238.719347)
			(xy 292.088824 -238.715042) (xy 292.109913 -238.700693) (xy 292.155574 -238.677962) (xy 292.20418 -238.662503)
			(xy 292.254583 -238.65468) (xy 292.305589 -238.65468) (xy 292.355992 -238.662503) (xy 292.404598 -238.677962)
			(xy 292.450259 -238.700693) (xy 292.471348 -238.715042) (xy 292.477873 -238.719345) (xy 292.492748 -238.724122)
			(xy 292.500558 -238.72444) (xy 293.016686 -238.72444) (xy 293.021988 -238.724933) (xy 293.02956 -238.732356)
			(xy 293.030148 -238.737648) (xy 293.030148 -239.232186) (xy 293.030132 -239.23244) (xy 294.974264 -239.23244)
			(xy 294.974264 -239.231932) (xy 294.974264 -238.737648) (xy 294.974657 -238.732329) (xy 294.982155 -238.724787)
			(xy 294.987472 -238.72444) (xy 295.5036 -238.72444) (xy 295.511411 -238.724136) (xy 295.526283 -238.719344)
			(xy 295.53281 -238.715042) (xy 295.553899 -238.700693) (xy 295.59956 -238.677962) (xy 295.648166 -238.662503)
			(xy 295.698569 -238.65468) (xy 295.749575 -238.65468) (xy 295.799978 -238.662503) (xy 295.848584 -238.677962)
			(xy 295.894245 -238.700693) (xy 295.915334 -238.715042) (xy 295.921862 -238.719339) (xy 295.936735 -238.72412)
			(xy 295.944544 -238.72444) (xy 296.460672 -238.72444) (xy 296.466012 -238.72475) (xy 296.473558 -238.732307)
			(xy 296.47388 -238.737648) (xy 296.47388 -239.232186) (xy 296.473856 -239.23244) (xy 299.074332 -239.23244)
			(xy 299.074332 -239.231932) (xy 299.074332 -238.737648) (xy 299.074663 -238.732313) (xy 299.082205 -238.724766)
			(xy 299.08754 -238.72444) (xy 299.603668 -238.72444) (xy 299.611478 -238.724123) (xy 299.62635 -238.71934)
			(xy 299.632878 -238.715042) (xy 299.653967 -238.700693) (xy 299.699628 -238.677962) (xy 299.748234 -238.662503)
			(xy 299.798637 -238.65468) (xy 299.849643 -238.65468) (xy 299.900046 -238.662503) (xy 299.948652 -238.677962)
			(xy 299.994313 -238.700693) (xy 300.015402 -238.715042) (xy 300.021937 -238.719327) (xy 300.036804 -238.724115)
			(xy 300.044612 -238.72444) (xy 300.56074 -238.72444) (xy 300.56609 -238.724705) (xy 300.573631 -238.732297)
			(xy 300.573948 -238.737648) (xy 300.573948 -239.232186) (xy 302.518064 -239.232186) (xy 302.518064 -238.737648)
			(xy 302.518457 -238.732329) (xy 302.525955 -238.724787) (xy 302.531272 -238.72444) (xy 302.53178 -238.72444)
			(xy 304.004726 -238.72444) (xy 304.010033 -238.724906) (xy 304.017603 -238.73235) (xy 304.018188 -238.737648)
			(xy 304.018188 -239.232186) (xy 306.618132 -239.232186) (xy 306.618132 -238.737648) (xy 306.618463 -238.732313)
			(xy 306.626005 -238.724766) (xy 306.63134 -238.72444) (xy 306.631848 -238.72444) (xy 308.104794 -238.72444)
			(xy 308.110097 -238.724927) (xy 308.117669 -238.732355) (xy 308.118256 -238.737648) (xy 308.118256 -239.232186)
			(xy 308.11824 -239.23244) (xy 411.618176 -239.23244) (xy 411.618176 -239.231932) (xy 411.618176 -238.737648)
			(xy 411.618558 -238.732326) (xy 411.626064 -238.724783) (xy 411.631384 -238.72444) (xy 413.104584 -238.72444)
			(xy 413.109926 -238.724742) (xy 413.117471 -238.732305) (xy 413.117792 -238.737648) (xy 413.117792 -239.232186)
			(xy 413.117767 -239.23244) (xy 415.718244 -239.23244) (xy 415.718244 -239.231932) (xy 415.718244 -238.737648)
			(xy 415.718822 -238.732402) (xy 415.72621 -238.72496) (xy 415.731452 -238.72444) (xy 417.204652 -238.72444)
			(xy 417.209989 -238.724764) (xy 417.217536 -238.732311) (xy 417.21786 -238.737648) (xy 417.21786 -239.232186)
			(xy 419.161976 -239.232186) (xy 419.161976 -238.737648) (xy 419.162358 -238.732326) (xy 419.169864 -238.724783)
			(xy 419.175184 -238.72444) (xy 419.175692 -238.72444) (xy 419.691566 -238.72444) (xy 419.699376 -238.724122)
			(xy 419.714248 -238.71934) (xy 419.720776 -238.715042) (xy 419.741865 -238.700693) (xy 419.787526 -238.677962)
			(xy 419.836132 -238.662503) (xy 419.886535 -238.65468) (xy 419.937541 -238.65468) (xy 419.987944 -238.662503)
			(xy 420.03655 -238.677962) (xy 420.082211 -238.700693) (xy 420.1033 -238.715042) (xy 420.109836 -238.719326)
			(xy 420.124702 -238.724115) (xy 420.13251 -238.72444) (xy 420.648638 -238.72444) (xy 420.653947 -238.724898)
			(xy 420.661516 -238.732348) (xy 420.6621 -238.737648) (xy 420.6621 -239.232186) (xy 423.262044 -239.232186)
			(xy 423.262044 -238.737648) (xy 423.262622 -238.732402) (xy 423.27001 -238.72496) (xy 423.275252 -238.72444)
			(xy 423.27576 -238.72444) (xy 423.791634 -238.72444) (xy 423.799443 -238.724108) (xy 423.814315 -238.719336)
			(xy 423.820844 -238.715042) (xy 423.841933 -238.700693) (xy 423.887594 -238.677962) (xy 423.9362 -238.662503)
			(xy 423.986603 -238.65468) (xy 424.037609 -238.65468) (xy 424.088012 -238.662503) (xy 424.136618 -238.677962)
			(xy 424.182279 -238.700693) (xy 424.203368 -238.715042) (xy 424.209911 -238.719314) (xy 424.224772 -238.72411)
			(xy 424.232578 -238.72444) (xy 424.748706 -238.72444) (xy 424.754011 -238.724919) (xy 424.761582 -238.732353)
			(xy 424.762168 -238.737648) (xy 424.762168 -239.232186) (xy 424.762151 -239.23244) (xy 426.706284 -239.23244)
			(xy 426.706284 -239.231932) (xy 426.706284 -238.737648) (xy 426.706659 -238.732324) (xy 426.71417 -238.724781)
			(xy 426.719492 -238.72444) (xy 427.23562 -238.72444) (xy 427.243432 -238.724145) (xy 427.258304 -238.719347)
			(xy 427.26483 -238.715042) (xy 427.285919 -238.700693) (xy 427.33158 -238.677962) (xy 427.380186 -238.662503)
			(xy 427.430589 -238.65468) (xy 427.481595 -238.65468) (xy 427.531998 -238.662503) (xy 427.580604 -238.677962)
			(xy 427.626265 -238.700693) (xy 427.647354 -238.715042) (xy 427.653878 -238.719347) (xy 427.668754 -238.724123)
			(xy 427.676564 -238.72444) (xy 428.192692 -238.72444) (xy 428.198035 -238.724737) (xy 428.205579 -238.732304)
			(xy 428.2059 -238.737648) (xy 428.2059 -239.232186) (xy 428.205875 -239.23244) (xy 430.806352 -239.23244)
			(xy 430.806352 -239.231932) (xy 430.806352 -238.737648) (xy 430.806755 -238.732332) (xy 430.814246 -238.724791)
			(xy 430.81956 -238.72444) (xy 431.335688 -238.72444) (xy 431.343499 -238.724131) (xy 431.35837 -238.719343)
			(xy 431.364898 -238.715042) (xy 431.385987 -238.700693) (xy 431.431648 -238.677962) (xy 431.480254 -238.662503)
			(xy 431.530657 -238.65468) (xy 431.581663 -238.65468) (xy 431.632066 -238.662503) (xy 431.680672 -238.677962)
			(xy 431.726333 -238.700693) (xy 431.747422 -238.715042) (xy 431.753953 -238.719335) (xy 431.768823 -238.724118)
			(xy 431.776632 -238.72444) (xy 432.29276 -238.72444) (xy 432.298099 -238.724759) (xy 432.305645 -238.732309)
			(xy 432.305968 -238.737648) (xy 432.305968 -239.232186) (xy 434.250084 -239.232186) (xy 434.250084 -238.737648)
			(xy 434.250459 -238.732324) (xy 434.25797 -238.724781) (xy 434.263292 -238.72444) (xy 434.2638 -238.72444)
			(xy 434.779674 -238.72444) (xy 434.787484 -238.724125) (xy 434.802356 -238.719341) (xy 434.808884 -238.715042)
			(xy 434.829973 -238.700693) (xy 434.875634 -238.677962) (xy 434.92424 -238.662503) (xy 434.974643 -238.65468)
			(xy 435.025649 -238.65468) (xy 435.076052 -238.662503) (xy 435.124658 -238.677962) (xy 435.170319 -238.700693)
			(xy 435.191408 -238.715042) (xy 435.197942 -238.719329) (xy 435.21281 -238.724116) (xy 435.220618 -238.72444)
			(xy 435.736746 -238.72444) (xy 435.742044 -238.724959) (xy 435.749618 -238.732363) (xy 435.750208 -238.737648)
			(xy 435.750208 -239.232186) (xy 438.350152 -239.232186) (xy 438.350152 -238.737648) (xy 438.350555 -238.732332)
			(xy 438.358046 -238.724791) (xy 438.36336 -238.72444) (xy 438.363868 -238.72444) (xy 438.879742 -238.72444)
			(xy 438.887551 -238.724112) (xy 438.902423 -238.719337) (xy 438.908952 -238.715042) (xy 438.930041 -238.700693)
			(xy 438.975702 -238.677962) (xy 439.024308 -238.662503) (xy 439.074711 -238.65468) (xy 439.125717 -238.65468)
			(xy 439.17612 -238.662503) (xy 439.224726 -238.677962) (xy 439.270387 -238.700693) (xy 439.291476 -238.715042)
			(xy 439.298017 -238.719317) (xy 439.31288 -238.724111) (xy 439.320686 -238.72444) (xy 439.836814 -238.72444)
			(xy 439.84212 -238.724914) (xy 439.84969 -238.732352) (xy 439.850276 -238.737648) (xy 439.850276 -239.232186)
			(xy 439.850251 -239.23244) (xy 441.794392 -239.23244) (xy 441.794392 -239.231932) (xy 441.794392 -238.737648)
			(xy 441.794759 -238.732322) (xy 441.802276 -238.724779) (xy 441.8076 -238.72444) (xy 442.323728 -238.72444)
			(xy 442.33154 -238.724149) (xy 442.346412 -238.719348) (xy 442.352938 -238.715042) (xy 442.374027 -238.700693)
			(xy 442.419688 -238.677962) (xy 442.468294 -238.662503) (xy 442.518697 -238.65468) (xy 442.569703 -238.65468)
			(xy 442.620106 -238.662503) (xy 442.668712 -238.677962) (xy 442.714373 -238.700693) (xy 442.735462 -238.715042)
			(xy 442.742006 -238.719312) (xy 442.756866 -238.724109) (xy 442.764672 -238.72444) (xy 443.2808 -238.72444)
			(xy 443.286144 -238.724731) (xy 443.293688 -238.732303) (xy 443.294008 -238.737648) (xy 443.294008 -239.232186)
			(xy 443.293982 -239.23244) (xy 445.89446 -239.23244) (xy 445.89446 -239.231932) (xy 445.89446 -238.737648)
			(xy 445.894856 -238.73233) (xy 445.902352 -238.724788) (xy 445.907668 -238.72444) (xy 446.423796 -238.72444)
			(xy 446.431607 -238.724135) (xy 446.446479 -238.719344) (xy 446.453006 -238.715042) (xy 446.474095 -238.700693)
			(xy 446.519756 -238.677962) (xy 446.568362 -238.662503) (xy 446.618765 -238.65468) (xy 446.669771 -238.65468)
			(xy 446.720174 -238.662503) (xy 446.76878 -238.677962) (xy 446.814441 -238.700693) (xy 446.83553 -238.715042)
			(xy 446.842059 -238.719338) (xy 446.856931 -238.724119) (xy 446.86474 -238.72444) (xy 447.380868 -238.72444)
			(xy 447.386208 -238.724753) (xy 447.393753 -238.732308) (xy 447.394076 -238.737648) (xy 447.394076 -239.232186)
			(xy 447.394052 -239.23244) (xy 449.338192 -239.23244) (xy 449.338192 -239.231932) (xy 449.338192 -238.737648)
			(xy 449.338559 -238.732322) (xy 449.346076 -238.724779) (xy 449.3514 -238.72444) (xy 449.867528 -238.72444)
			(xy 449.87534 -238.724149) (xy 449.890212 -238.719348) (xy 449.896738 -238.715042) (xy 449.917827 -238.700693)
			(xy 449.963488 -238.677962) (xy 450.012094 -238.662503) (xy 450.062497 -238.65468) (xy 450.113503 -238.65468)
			(xy 450.163906 -238.662503) (xy 450.212512 -238.677962) (xy 450.258173 -238.700693) (xy 450.279262 -238.715042)
			(xy 450.285806 -238.719312) (xy 450.300666 -238.724109) (xy 450.308472 -238.72444) (xy 450.8246 -238.72444)
			(xy 450.829944 -238.724731) (xy 450.837488 -238.732303) (xy 450.837808 -238.737648) (xy 450.837808 -239.232186)
			(xy 450.837782 -239.23244) (xy 453.43826 -239.23244) (xy 453.43826 -239.231932) (xy 453.43826 -238.737648)
			(xy 453.438656 -238.73233) (xy 453.446152 -238.724788) (xy 453.451468 -238.72444) (xy 453.967596 -238.72444)
			(xy 453.975407 -238.724135) (xy 453.990279 -238.719344) (xy 453.996806 -238.715042) (xy 454.017895 -238.700693)
			(xy 454.063556 -238.677962) (xy 454.112162 -238.662503) (xy 454.162565 -238.65468) (xy 454.213571 -238.65468)
			(xy 454.263974 -238.662503) (xy 454.31258 -238.677962) (xy 454.358241 -238.700693) (xy 454.37933 -238.715042)
			(xy 454.385859 -238.719338) (xy 454.400731 -238.724119) (xy 454.40854 -238.72444) (xy 454.924668 -238.72444)
			(xy 454.930008 -238.724753) (xy 454.937553 -238.732308) (xy 454.937876 -238.737648) (xy 454.937876 -239.232186)
			(xy 454.937369 -239.237485) (xy 454.929955 -239.245056) (xy 454.924668 -239.245648) (xy 454.408794 -239.245648)
			(xy 454.400983 -239.245951) (xy 454.386111 -239.250743) (xy 454.379584 -239.255046) (xy 454.358464 -239.269398)
			(xy 454.31274 -239.292124) (xy 454.264066 -239.307553) (xy 454.213599 -239.315319) (xy 454.188068 -239.315752)
			(xy 454.162537 -239.315334) (xy 454.112072 -239.307553) (xy 454.0634 -239.292118) (xy 454.017673 -239.269396)
			(xy 453.996552 -239.255046) (xy 453.990028 -239.250742) (xy 453.975152 -239.245966) (xy 453.967342 -239.245648)
			(xy 453.451468 -239.245648) (xy 453.446211 -239.245131) (xy 453.438773 -239.237697) (xy 453.43826 -239.23244)
			(xy 450.837782 -239.23244) (xy 450.837273 -239.237477) (xy 450.829879 -239.245046) (xy 450.8246 -239.245648)
			(xy 450.308726 -239.245648) (xy 450.300916 -239.245965) (xy 450.286044 -239.250748) (xy 450.279516 -239.255046)
			(xy 450.258387 -239.269384) (xy 450.212666 -239.292113) (xy 450.163995 -239.307547) (xy 450.11353 -239.315317)
			(xy 450.088 -239.315752) (xy 450.06247 -239.315318) (xy 450.012006 -239.307542) (xy 449.963333 -239.292112)
			(xy 449.917606 -239.269394) (xy 449.896484 -239.255046) (xy 449.889953 -239.250754) (xy 449.875083 -239.245971)
			(xy 449.867274 -239.245648) (xy 449.3514 -239.245648) (xy 449.346147 -239.245109) (xy 449.338707 -239.237692)
			(xy 449.338192 -239.23244) (xy 447.394052 -239.23244) (xy 447.393569 -239.237485) (xy 447.386155 -239.245056)
			(xy 447.380868 -239.245648) (xy 446.864994 -239.245648) (xy 446.857183 -239.245951) (xy 446.842311 -239.250743)
			(xy 446.835784 -239.255046) (xy 446.814664 -239.269398) (xy 446.76894 -239.292124) (xy 446.720266 -239.307553)
			(xy 446.669799 -239.315319) (xy 446.644268 -239.315752) (xy 446.618737 -239.315334) (xy 446.568272 -239.307553)
			(xy 446.5196 -239.292118) (xy 446.473873 -239.269396) (xy 446.452752 -239.255046) (xy 446.446228 -239.250742)
			(xy 446.431352 -239.245966) (xy 446.423542 -239.245648) (xy 445.907668 -239.245648) (xy 445.902411 -239.245131)
			(xy 445.894973 -239.237697) (xy 445.89446 -239.23244) (xy 443.293982 -239.23244) (xy 443.293473 -239.237477)
			(xy 443.286079 -239.245046) (xy 443.2808 -239.245648) (xy 442.764926 -239.245648) (xy 442.757116 -239.245965)
			(xy 442.742244 -239.250748) (xy 442.735716 -239.255046) (xy 442.714587 -239.269384) (xy 442.668866 -239.292113)
			(xy 442.620195 -239.307547) (xy 442.56973 -239.315317) (xy 442.5442 -239.315752) (xy 442.51867 -239.315318)
			(xy 442.468206 -239.307542) (xy 442.419533 -239.292112) (xy 442.373806 -239.269394) (xy 442.352684 -239.255046)
			(xy 442.346153 -239.250754) (xy 442.331283 -239.245971) (xy 442.323474 -239.245648) (xy 441.8076 -239.245648)
			(xy 441.802347 -239.245109) (xy 441.794907 -239.237692) (xy 441.794392 -239.23244) (xy 439.850251 -239.23244)
			(xy 439.849742 -239.237545) (xy 439.842172 -239.245131) (xy 439.836814 -239.245648) (xy 439.32094 -239.245648)
			(xy 439.313131 -239.245971) (xy 439.298259 -239.25075) (xy 439.29173 -239.255046) (xy 439.270625 -239.269421)
			(xy 439.224895 -239.292142) (xy 439.176217 -239.307565) (xy 439.125746 -239.315323) (xy 439.100214 -239.315752)
			(xy 439.074684 -239.315311) (xy 439.02422 -239.307537) (xy 438.975548 -239.292109) (xy 438.92982 -239.269393)
			(xy 438.908698 -239.255046) (xy 438.902163 -239.25076) (xy 438.887296 -239.245973) (xy 438.879488 -239.245648)
			(xy 438.363614 -239.245648) (xy 438.358178 -239.24531) (xy 438.35049 -239.237622) (xy 438.350152 -239.232186)
			(xy 435.750208 -239.232186) (xy 435.749645 -239.237537) (xy 435.742095 -239.245121) (xy 435.736746 -239.245648)
			(xy 435.220872 -239.245648) (xy 435.21306 -239.245942) (xy 435.198188 -239.25074) (xy 435.191662 -239.255046)
			(xy 435.170548 -239.269407) (xy 435.124822 -239.292131) (xy 435.076146 -239.307558) (xy 435.025678 -239.315321)
			(xy 435.000146 -239.315752) (xy 434.974617 -239.315295) (xy 434.924153 -239.307525) (xy 434.875481 -239.292102)
			(xy 434.829753 -239.269391) (xy 434.80863 -239.255046) (xy 434.802088 -239.250772) (xy 434.787226 -239.245978)
			(xy 434.77942 -239.245648) (xy 434.263546 -239.245648) (xy 434.258114 -239.245289) (xy 434.250424 -239.237617)
			(xy 434.250084 -239.232186) (xy 432.305968 -239.232186) (xy 432.305468 -239.237487) (xy 432.29805 -239.245058)
			(xy 432.29276 -239.245648) (xy 431.776886 -239.245648) (xy 431.769074 -239.245947) (xy 431.754203 -239.250742)
			(xy 431.747676 -239.255046) (xy 431.726558 -239.269401) (xy 431.680833 -239.292127) (xy 431.632159 -239.307555)
			(xy 431.581691 -239.31532) (xy 431.55616 -239.315752) (xy 431.530629 -239.315338) (xy 431.480164 -239.307555)
			(xy 431.431492 -239.29212) (xy 431.385765 -239.269397) (xy 431.364644 -239.255046) (xy 431.358121 -239.250739)
			(xy 431.343245 -239.245965) (xy 431.335434 -239.245648) (xy 430.81956 -239.245648) (xy 430.814302 -239.245136)
			(xy 430.806864 -239.237698) (xy 430.806352 -239.23244) (xy 428.205875 -239.23244) (xy 428.205372 -239.237479)
			(xy 428.197973 -239.245049) (xy 428.192692 -239.245648) (xy 427.676818 -239.245648) (xy 427.669008 -239.245961)
			(xy 427.654136 -239.250747) (xy 427.647608 -239.255046) (xy 427.626481 -239.269387) (xy 427.580759 -239.292116)
			(xy 427.532088 -239.307548) (xy 427.481623 -239.315317) (xy 427.456092 -239.315752) (xy 427.430561 -239.315322)
			(xy 427.380097 -239.307544) (xy 427.331425 -239.292113) (xy 427.285698 -239.269395) (xy 427.264576 -239.255046)
			(xy 427.258046 -239.250751) (xy 427.243175 -239.24597) (xy 427.235366 -239.245648) (xy 426.719492 -239.245648)
			(xy 426.714238 -239.245115) (xy 426.706798 -239.237693) (xy 426.706284 -239.23244) (xy 424.762151 -239.23244)
			(xy 424.761812 -239.237617) (xy 424.754137 -239.245304) (xy 424.748706 -239.245648) (xy 424.232832 -239.245648)
			(xy 424.225022 -239.245967) (xy 424.210151 -239.250749) (xy 424.203622 -239.255046) (xy 424.182491 -239.269381)
			(xy 424.136771 -239.292111) (xy 424.0881 -239.307545) (xy 424.037636 -239.315316) (xy 424.012106 -239.315752)
			(xy 423.986576 -239.315315) (xy 423.936112 -239.307539) (xy 423.887439 -239.292111) (xy 423.841712 -239.269394)
			(xy 423.82059 -239.255046) (xy 423.814057 -239.250757) (xy 423.799188 -239.245972) (xy 423.79138 -239.245648)
			(xy 423.275506 -239.245648) (xy 423.270069 -239.245315) (xy 423.262381 -239.237624) (xy 423.262044 -239.232186)
			(xy 420.6621 -239.232186) (xy 420.661544 -239.237539) (xy 420.653989 -239.245123) (xy 420.648638 -239.245648)
			(xy 420.132764 -239.245648) (xy 420.124956 -239.245981) (xy 420.110084 -239.250753) (xy 420.103554 -239.255046)
			(xy 420.082442 -239.269411) (xy 420.036715 -239.292134) (xy 419.988039 -239.30756) (xy 419.93757 -239.315322)
			(xy 419.912038 -239.315752) (xy 419.886508 -239.315299) (xy 419.836045 -239.307528) (xy 419.787373 -239.292104)
			(xy 419.741644 -239.269392) (xy 419.720522 -239.255046) (xy 419.713982 -239.250769) (xy 419.699119 -239.245976)
			(xy 419.691312 -239.245648) (xy 419.175438 -239.245648) (xy 419.170005 -239.245294) (xy 419.162316 -239.237619)
			(xy 419.161976 -239.232186) (xy 417.21786 -239.232186) (xy 417.217367 -239.237488) (xy 417.209944 -239.24506)
			(xy 417.204652 -239.245648) (xy 415.731452 -239.245648) (xy 415.726193 -239.245141) (xy 415.718756 -239.237699)
			(xy 415.718244 -239.23244) (xy 413.117767 -239.23244) (xy 413.117271 -239.237481) (xy 413.109867 -239.245051)
			(xy 413.104584 -239.245648) (xy 411.631384 -239.245648) (xy 411.626129 -239.24512) (xy 411.618689 -239.237694)
			(xy 411.618176 -239.23244) (xy 308.11824 -239.23244) (xy 308.117911 -239.23762) (xy 308.110228 -239.245307)
			(xy 308.104794 -239.245648) (xy 306.631594 -239.245648) (xy 306.626155 -239.245323) (xy 306.618469 -239.237625)
			(xy 306.618132 -239.232186) (xy 304.018188 -239.232186) (xy 304.017643 -239.237542) (xy 304.01008 -239.245127)
			(xy 304.004726 -239.245648) (xy 302.531526 -239.245648) (xy 302.526091 -239.245302) (xy 302.518403 -239.23762)
			(xy 302.518064 -239.232186) (xy 300.573948 -239.232186) (xy 300.573466 -239.237491) (xy 300.566035 -239.245064)
			(xy 300.56074 -239.245648) (xy 300.044866 -239.245648) (xy 300.037058 -239.245982) (xy 300.022186 -239.250753)
			(xy 300.015656 -239.255046) (xy 299.994544 -239.26941) (xy 299.948817 -239.292133) (xy 299.90014 -239.307559)
			(xy 299.849672 -239.315321) (xy 299.82414 -239.315752) (xy 299.79861 -239.315298) (xy 299.748147 -239.307528)
			(xy 299.699475 -239.292104) (xy 299.653746 -239.269392) (xy 299.632624 -239.255046) (xy 299.626084 -239.25077)
			(xy 299.611221 -239.245977) (xy 299.603414 -239.245648) (xy 299.08754 -239.245648) (xy 299.082292 -239.245083)
			(xy 299.074849 -239.237685) (xy 299.074332 -239.23244) (xy 296.473856 -239.23244) (xy 296.47337 -239.237484)
			(xy 296.465958 -239.245054) (xy 296.460672 -239.245648) (xy 295.944798 -239.245648) (xy 295.936987 -239.245953)
			(xy 295.922115 -239.250744) (xy 295.915588 -239.255046) (xy 295.894467 -239.269396) (xy 295.848743 -239.292123)
			(xy 295.800069 -239.307553) (xy 295.749603 -239.315319) (xy 295.724072 -239.315752) (xy 295.698541 -239.315332)
			(xy 295.648076 -239.307551) (xy 295.599404 -239.292117) (xy 295.553677 -239.269396) (xy 295.532556 -239.255046)
			(xy 295.526031 -239.250744) (xy 295.511156 -239.245967) (xy 295.503346 -239.245648) (xy 294.987472 -239.245648)
			(xy 294.982215 -239.245128) (xy 294.974777 -239.237696) (xy 294.974264 -239.23244) (xy 293.030132 -239.23244)
			(xy 293.02981 -239.237622) (xy 293.022122 -239.24531) (xy 293.016686 -239.245648) (xy 292.500812 -239.245648)
			(xy 292.493002 -239.245959) (xy 292.47813 -239.250746) (xy 292.471602 -239.255046) (xy 292.450477 -239.26939)
			(xy 292.404754 -239.292118) (xy 292.356082 -239.30755) (xy 292.305617 -239.315318) (xy 292.280086 -239.315752)
			(xy 292.254555 -239.315325) (xy 292.204091 -239.307546) (xy 292.155419 -239.292115) (xy 292.109691 -239.269395)
			(xy 292.08857 -239.255046) (xy 292.082042 -239.250749) (xy 292.067169 -239.245969) (xy 292.05936 -239.245648)
			(xy 291.543486 -239.245648) (xy 291.538117 -239.245157) (xy 291.530531 -239.237556) (xy 291.530024 -239.232186)
			(xy 288.93008 -239.232186) (xy 288.929542 -239.237544) (xy 288.921975 -239.245129) (xy 288.916618 -239.245648)
			(xy 288.400744 -239.245648) (xy 288.392935 -239.245972) (xy 288.378063 -239.25075) (xy 288.371534 -239.255046)
			(xy 288.350428 -239.269419) (xy 288.304699 -239.292141) (xy 288.25602 -239.307564) (xy 288.20555 -239.315323)
			(xy 288.180018 -239.315752) (xy 288.154488 -239.315309) (xy 288.104024 -239.307535) (xy 288.055352 -239.292108)
			(xy 288.009624 -239.269393) (xy 287.988502 -239.255046) (xy 287.981967 -239.250761) (xy 287.9671 -239.245973)
			(xy 287.959292 -239.245648) (xy 287.443418 -239.245648) (xy 287.437982 -239.245307) (xy 287.430294 -239.237622)
			(xy 287.429956 -239.232186) (xy 285.48584 -239.232186) (xy 285.485365 -239.237493) (xy 285.477929 -239.245066)
			(xy 285.472632 -239.245648) (xy 284.956758 -239.245648) (xy 284.948949 -239.245978) (xy 284.934077 -239.250752)
			(xy 284.927548 -239.255046) (xy 284.906438 -239.269413) (xy 284.86071 -239.292136) (xy 284.812033 -239.307561)
			(xy 284.761564 -239.315322) (xy 284.736032 -239.315752) (xy 284.710502 -239.315302) (xy 284.660039 -239.30753)
			(xy 284.611366 -239.292105) (xy 284.565638 -239.269392) (xy 284.544516 -239.255046) (xy 284.537977 -239.250767)
			(xy 284.523113 -239.245976) (xy 284.515306 -239.245648) (xy 283.999432 -239.245648) (xy 283.994183 -239.245088)
			(xy 283.98674 -239.237687) (xy 283.986224 -239.23244) (xy 281.385748 -239.23244) (xy 281.385269 -239.237486)
			(xy 281.377853 -239.245057) (xy 281.372564 -239.245648) (xy 280.85669 -239.245648) (xy 280.848879 -239.245949)
			(xy 280.834007 -239.250743) (xy 280.82748 -239.255046) (xy 280.806361 -239.269399) (xy 280.760636 -239.292125)
			(xy 280.711962 -239.307554) (xy 280.661495 -239.31532) (xy 280.635964 -239.315752) (xy 280.610433 -239.315336)
			(xy 280.559968 -239.307554) (xy 280.511296 -239.292119) (xy 280.465569 -239.269396) (xy 280.444448 -239.255046)
			(xy 280.437925 -239.250741) (xy 280.423048 -239.245966) (xy 280.415238 -239.245648) (xy 279.899364 -239.245648)
			(xy 279.894107 -239.245133) (xy 279.886668 -239.237697) (xy 279.886156 -239.23244) (xy 277.942017 -239.23244)
			(xy 277.941565 -239.237493) (xy 277.934129 -239.245066) (xy 277.928832 -239.245648) (xy 277.412958 -239.245648)
			(xy 277.405149 -239.245978) (xy 277.390277 -239.250752) (xy 277.383748 -239.255046) (xy 277.362638 -239.269413)
			(xy 277.31691 -239.292136) (xy 277.268233 -239.307561) (xy 277.217764 -239.315322) (xy 277.192232 -239.315752)
			(xy 277.166702 -239.315302) (xy 277.116239 -239.30753) (xy 277.067566 -239.292105) (xy 277.021838 -239.269392)
			(xy 277.000716 -239.255046) (xy 276.994177 -239.250767) (xy 276.979313 -239.245976) (xy 276.971506 -239.245648)
			(xy 276.455632 -239.245648) (xy 276.450383 -239.245088) (xy 276.44294 -239.237687) (xy 276.442424 -239.23244)
			(xy 273.841948 -239.23244) (xy 273.841469 -239.237486) (xy 273.834053 -239.245057) (xy 273.828764 -239.245648)
			(xy 273.31289 -239.245648) (xy 273.305079 -239.245949) (xy 273.290207 -239.250743) (xy 273.28368 -239.255046)
			(xy 273.262561 -239.269399) (xy 273.216836 -239.292125) (xy 273.168162 -239.307554) (xy 273.117695 -239.31532)
			(xy 273.092164 -239.315752) (xy 273.066633 -239.315336) (xy 273.016168 -239.307554) (xy 272.967496 -239.292119)
			(xy 272.921769 -239.269396) (xy 272.900648 -239.255046) (xy 272.894125 -239.250741) (xy 272.879248 -239.245966)
			(xy 272.871438 -239.245648) (xy 272.355564 -239.245648) (xy 272.350307 -239.245133) (xy 272.342868 -239.237697)
			(xy 272.342356 -239.23244) (xy 270.398225 -239.23244) (xy 270.397909 -239.237624) (xy 270.390216 -239.245312)
			(xy 270.384778 -239.245648) (xy 269.868904 -239.245648) (xy 269.861093 -239.245956) (xy 269.846222 -239.250745)
			(xy 269.839694 -239.255046) (xy 269.818571 -239.269393) (xy 269.772848 -239.292121) (xy 269.724175 -239.307551)
			(xy 269.673709 -239.315319) (xy 269.648178 -239.315752) (xy 269.622647 -239.315329) (xy 269.572183 -239.307549)
			(xy 269.52351 -239.292116) (xy 269.477783 -239.269396) (xy 269.456662 -239.255046) (xy 269.450135 -239.250746)
			(xy 269.435262 -239.245968) (xy 269.427452 -239.245648) (xy 268.911578 -239.245648) (xy 268.906208 -239.245163)
			(xy 268.898623 -239.237557) (xy 268.898116 -239.232186) (xy 266.298172 -239.232186) (xy 266.297812 -239.237616)
			(xy 266.29014 -239.245303) (xy 266.28471 -239.245648) (xy 265.768836 -239.245648) (xy 265.761026 -239.245969)
			(xy 265.746155 -239.250749) (xy 265.739626 -239.255046) (xy 265.718494 -239.26938) (xy 265.672774 -239.29211)
			(xy 265.624104 -239.307544) (xy 265.57364 -239.315316) (xy 265.54811 -239.315752) (xy 265.52258 -239.315313)
			(xy 265.472116 -239.307538) (xy 265.423444 -239.29211) (xy 265.377716 -239.269393) (xy 265.356594 -239.255046)
			(xy 265.35006 -239.250758) (xy 265.335192 -239.245972) (xy 265.327384 -239.245648) (xy 264.81151 -239.245648)
			(xy 264.806073 -239.245313) (xy 264.798386 -239.237623) (xy 264.798048 -239.232186) (xy 206.997808 -239.232186)
			(xy 206.997808 -239.23244) (xy 206.997332 -239.237708) (xy 206.989869 -239.245148) (xy 206.9846 -239.245648)
			(xy 206.468726 -239.245648) (xy 206.460849 -239.245912) (xy 206.445845 -239.250712) (xy 206.439262 -239.255046)
			(xy 206.418185 -239.269439) (xy 206.37254 -239.292267) (xy 206.323934 -239.307824) (xy 206.273517 -239.315743)
			(xy 206.248 -239.31626) (xy 206.222479 -239.315795) (xy 206.172051 -239.307894) (xy 206.123439 -239.292327)
			(xy 206.077802 -239.269465) (xy 206.056738 -239.255046) (xy 206.050137 -239.250747) (xy 206.035144 -239.24595)
			(xy 206.027274 -239.245648) (xy 205.5114 -239.245648) (xy 205.506147 -239.245109) (xy 205.498707 -239.237692)
			(xy 205.498192 -239.23244) (xy 202.89774 -239.23244) (xy 202.897235 -239.2377) (xy 202.889792 -239.245138)
			(xy 202.884532 -239.245648) (xy 202.368658 -239.245648) (xy 202.360783 -239.245926) (xy 202.345779 -239.250716)
			(xy 202.339194 -239.255046) (xy 202.318108 -239.269425) (xy 202.272467 -239.292256) (xy 202.223863 -239.307818)
			(xy 202.173448 -239.315741) (xy 202.147932 -239.31626) (xy 202.122411 -239.315779) (xy 202.071984 -239.307883)
			(xy 202.023372 -239.292321) (xy 201.977734 -239.269463) (xy 201.95667 -239.255046) (xy 201.950084 -239.250721)
			(xy 201.93508 -239.24594) (xy 201.927206 -239.245648) (xy 201.411332 -239.245648) (xy 201.406083 -239.245088)
			(xy 201.39864 -239.237687) (xy 201.398124 -239.23244) (xy 199.454008 -239.23244) (xy 199.453532 -239.237708)
			(xy 199.446069 -239.245148) (xy 199.4408 -239.245648) (xy 198.924926 -239.245648) (xy 198.917049 -239.245912)
			(xy 198.902045 -239.250712) (xy 198.895462 -239.255046) (xy 198.874385 -239.269439) (xy 198.82874 -239.292267)
			(xy 198.780134 -239.307824) (xy 198.729717 -239.315743) (xy 198.7042 -239.31626) (xy 198.678679 -239.315795)
			(xy 198.628251 -239.307894) (xy 198.579639 -239.292327) (xy 198.534002 -239.269465) (xy 198.512938 -239.255046)
			(xy 198.506337 -239.250747) (xy 198.491344 -239.24595) (xy 198.483474 -239.245648) (xy 197.9676 -239.245648)
			(xy 197.962347 -239.245109) (xy 197.954907 -239.237692) (xy 197.954392 -239.23244) (xy 195.35394 -239.23244)
			(xy 195.353435 -239.2377) (xy 195.345992 -239.245138) (xy 195.340732 -239.245648) (xy 194.824858 -239.245648)
			(xy 194.816983 -239.245926) (xy 194.801979 -239.250716) (xy 194.795394 -239.255046) (xy 194.774308 -239.269425)
			(xy 194.728667 -239.292256) (xy 194.680063 -239.307818) (xy 194.629648 -239.315741) (xy 194.604132 -239.31626)
			(xy 194.578611 -239.315779) (xy 194.528184 -239.307883) (xy 194.479572 -239.292321) (xy 194.433934 -239.269463)
			(xy 194.41287 -239.255046) (xy 194.406284 -239.250721) (xy 194.39128 -239.24594) (xy 194.383406 -239.245648)
			(xy 193.867532 -239.245648) (xy 193.862283 -239.245088) (xy 193.85484 -239.237687) (xy 193.854324 -239.23244)
			(xy 191.910208 -239.23244) (xy 191.909732 -239.237708) (xy 191.902269 -239.245148) (xy 191.897 -239.245648)
			(xy 191.896492 -239.245648) (xy 191.380872 -239.245648) (xy 191.372997 -239.245932) (xy 191.357993 -239.250718)
			(xy 191.351408 -239.255046) (xy 191.330346 -239.269462) (xy 191.284696 -239.292285) (xy 191.236085 -239.307836)
			(xy 191.185664 -239.315747) (xy 191.160146 -239.31626) (xy 191.134626 -239.315772) (xy 191.084198 -239.307878)
			(xy 191.035587 -239.292318) (xy 190.989949 -239.269462) (xy 190.968884 -239.255046) (xy 190.962295 -239.250727)
			(xy 190.947293 -239.245942) (xy 190.93942 -239.245648) (xy 190.423546 -239.245648) (xy 190.418244 -239.245145)
			(xy 190.41067 -239.23773) (xy 190.410084 -239.23244) (xy 187.81014 -239.23244) (xy 187.809635 -239.2377)
			(xy 187.802192 -239.245138) (xy 187.796932 -239.245648) (xy 187.796424 -239.245648) (xy 187.280804 -239.245648)
			(xy 187.27293 -239.245945) (xy 187.257926 -239.250722) (xy 187.25134 -239.255046) (xy 187.230269 -239.269448)
			(xy 187.184622 -239.292274) (xy 187.136014 -239.307829) (xy 187.085595 -239.315745) (xy 187.060078 -239.31626)
			(xy 187.034558 -239.315756) (xy 186.984132 -239.307867) (xy 186.93552 -239.292311) (xy 186.889881 -239.26946)
			(xy 186.868816 -239.255046) (xy 186.86222 -239.250739) (xy 186.847223 -239.245946) (xy 186.839352 -239.245648)
			(xy 186.323478 -239.245648) (xy 186.318168 -239.24519) (xy 186.310598 -239.237741) (xy 186.310016 -239.23244)
			(xy 184.3659 -239.23244) (xy 184.365431 -239.23771) (xy 184.357963 -239.24515) (xy 184.352692 -239.245648)
			(xy 183.836818 -239.245648) (xy 183.828945 -239.245951) (xy 183.813941 -239.250724) (xy 183.807354 -239.255046)
			(xy 183.78628 -239.269442) (xy 183.740634 -239.29227) (xy 183.692027 -239.307826) (xy 183.641609 -239.315744)
			(xy 183.616092 -239.31626) (xy 183.590573 -239.315749) (xy 183.540146 -239.307862) (xy 183.491534 -239.292308)
			(xy 183.445895 -239.269459) (xy 183.42483 -239.255046) (xy 183.418231 -239.250744) (xy 183.403237 -239.245949)
			(xy 183.395366 -239.245648) (xy 182.879492 -239.245648) (xy 182.874238 -239.245115) (xy 182.866798 -239.237693)
			(xy 182.866284 -239.23244) (xy 180.265832 -239.23244) (xy 180.265334 -239.237702) (xy 180.257886 -239.245141)
			(xy 180.252624 -239.245648) (xy 179.73675 -239.245648) (xy 179.728874 -239.245922) (xy 179.71387 -239.250715)
			(xy 179.707286 -239.255046) (xy 179.686203 -239.269428) (xy 179.64056 -239.292259) (xy 179.591956 -239.307819)
			(xy 179.54154 -239.315741) (xy 179.516024 -239.31626) (xy 179.490503 -239.315783) (xy 179.440075 -239.307886)
			(xy 179.391464 -239.292322) (xy 179.345826 -239.269463) (xy 179.324762 -239.255046) (xy 179.318178 -239.250718)
			(xy 179.303172 -239.245938) (xy 179.295298 -239.245648) (xy 178.779424 -239.245648) (xy 178.774174 -239.245093)
			(xy 178.766732 -239.237688) (xy 178.766216 -239.23244) (xy 176.8221 -239.23244) (xy 176.821631 -239.23771)
			(xy 176.814163 -239.24515) (xy 176.808892 -239.245648) (xy 176.808384 -239.245648) (xy 176.292764 -239.245648)
			(xy 176.284889 -239.245928) (xy 176.269885 -239.250717) (xy 176.2633 -239.255046) (xy 176.242213 -239.269422)
			(xy 176.196571 -239.292254) (xy 176.147968 -239.307816) (xy 176.097554 -239.31574) (xy 176.072038 -239.31626)
			(xy 176.046518 -239.315776) (xy 175.99609 -239.307881) (xy 175.947478 -239.292319) (xy 175.90184 -239.269462)
			(xy 175.880776 -239.255046) (xy 175.874189 -239.250723) (xy 175.859186 -239.245941) (xy 175.851312 -239.245648)
			(xy 175.335438 -239.245648) (xy 175.330136 -239.24515) (xy 175.322562 -239.237731) (xy 175.321976 -239.23244)
			(xy 172.722032 -239.23244) (xy 172.721534 -239.237702) (xy 172.714086 -239.245141) (xy 172.708824 -239.245648)
			(xy 172.708316 -239.245648) (xy 172.192696 -239.245648) (xy 172.184822 -239.245942) (xy 172.169818 -239.250721)
			(xy 172.163232 -239.255046) (xy 172.142164 -239.269452) (xy 172.096516 -239.292277) (xy 172.047907 -239.307831)
			(xy 171.997487 -239.315745) (xy 171.97197 -239.31626) (xy 171.94645 -239.31576) (xy 171.896023 -239.307869)
			(xy 171.847412 -239.292313) (xy 171.801773 -239.26946) (xy 171.780708 -239.255046) (xy 171.774114 -239.250736)
			(xy 171.759116 -239.245945) (xy 171.751244 -239.245648) (xy 171.23537 -239.245648) (xy 171.230059 -239.245195)
			(xy 171.222489 -239.237742) (xy 171.221908 -239.23244) (xy 169.277792 -239.23244) (xy 169.27733 -239.237712)
			(xy 169.269858 -239.245153) (xy 169.264584 -239.245648) (xy 167.791384 -239.245648) (xy 167.786129 -239.24512)
			(xy 167.778689 -239.237694) (xy 167.778176 -239.23244) (xy 165.177724 -239.23244) (xy 165.177234 -239.237704)
			(xy 165.169781 -239.245143) (xy 165.164516 -239.245648) (xy 163.691316 -239.245648) (xy 163.686065 -239.245099)
			(xy 163.678624 -239.237689) (xy 163.678108 -239.23244) (xy 60.178188 -239.23244) (xy 60.17773 -239.237713)
			(xy 60.170255 -239.245154) (xy 60.16498 -239.245648) (xy 60.164472 -239.245648) (xy 58.691526 -239.245648)
			(xy 58.686222 -239.245158) (xy 58.678649 -239.237733) (xy 58.678064 -239.23244) (xy 56.07812 -239.23244)
			(xy 56.077633 -239.237705) (xy 56.070178 -239.245144) (xy 56.064912 -239.245648) (xy 56.064404 -239.245648)
			(xy 54.591458 -239.245648) (xy 54.586146 -239.245203) (xy 54.578576 -239.237744) (xy 54.577996 -239.23244)
			(xy 52.63388 -239.23244) (xy 52.633429 -239.237714) (xy 52.625949 -239.245156) (xy 52.620672 -239.245648)
			(xy 52.104798 -239.245648) (xy 52.096924 -239.245943) (xy 52.08192 -239.250722) (xy 52.075334 -239.255046)
			(xy 52.054265 -239.269451) (xy 52.008617 -239.292276) (xy 51.960009 -239.30783) (xy 51.909589 -239.315745)
			(xy 51.884072 -239.31626) (xy 51.858552 -239.315759) (xy 51.808125 -239.307869) (xy 51.759514 -239.292312)
			(xy 51.713875 -239.26946) (xy 51.69281 -239.255046) (xy 51.686215 -239.250737) (xy 51.671218 -239.245946)
			(xy 51.663346 -239.245648) (xy 51.147472 -239.245648) (xy 51.142215 -239.245128) (xy 51.134777 -239.237696)
			(xy 51.134264 -239.23244) (xy 48.533812 -239.23244) (xy 48.533332 -239.237707) (xy 48.525872 -239.245147)
			(xy 48.520604 -239.245648) (xy 48.00473 -239.245648) (xy 47.996853 -239.245913) (xy 47.98185 -239.250712)
			(xy 47.975266 -239.255046) (xy 47.954188 -239.269437) (xy 47.908544 -239.292266) (xy 47.859938 -239.307824)
			(xy 47.809521 -239.315743) (xy 47.784004 -239.31626) (xy 47.758483 -239.315793) (xy 47.708055 -239.307893)
			(xy 47.659443 -239.292326) (xy 47.613806 -239.269465) (xy 47.592742 -239.255046) (xy 47.586162 -239.25071)
			(xy 47.571153 -239.245936) (xy 47.563278 -239.245648) (xy 47.047404 -239.245648) (xy 47.042151 -239.245107)
			(xy 47.034711 -239.237691) (xy 47.034196 -239.23244) (xy 45.09008 -239.23244) (xy 45.089629 -239.237714)
			(xy 45.082149 -239.245156) (xy 45.076872 -239.245648) (xy 45.076364 -239.245648) (xy 44.560744 -239.245648)
			(xy 44.552868 -239.245919) (xy 44.537864 -239.250714) (xy 44.53128 -239.255046) (xy 44.510198 -239.269431)
			(xy 44.464555 -239.292261) (xy 44.41595 -239.307821) (xy 44.365534 -239.315742) (xy 44.340018 -239.31626)
			(xy 44.314497 -239.315786) (xy 44.264069 -239.307888) (xy 44.215458 -239.292323) (xy 44.16982 -239.269464)
			(xy 44.148756 -239.255046) (xy 44.142173 -239.250716) (xy 44.127167 -239.245938) (xy 44.119292 -239.245648)
			(xy 43.603418 -239.245648) (xy 43.598113 -239.245164) (xy 43.59054 -239.237735) (xy 43.589956 -239.23244)
			(xy 40.990012 -239.23244) (xy 40.989532 -239.237707) (xy 40.982072 -239.245147) (xy 40.976804 -239.245648)
			(xy 40.976296 -239.245648) (xy 40.460676 -239.245648) (xy 40.452801 -239.245933) (xy 40.437797 -239.250719)
			(xy 40.431212 -239.255046) (xy 40.410149 -239.26946) (xy 40.364499 -239.292284) (xy 40.315889 -239.307835)
			(xy 40.265468 -239.315747) (xy 40.23995 -239.31626) (xy 40.21443 -239.31577) (xy 40.164003 -239.307876)
			(xy 40.115391 -239.292317) (xy 40.069753 -239.269462) (xy 40.048688 -239.255046) (xy 40.042098 -239.250728)
			(xy 40.027097 -239.245942) (xy 40.019224 -239.245648) (xy 39.50335 -239.245648) (xy 39.498049 -239.245142)
			(xy 39.490475 -239.237729) (xy 39.489888 -239.23244) (xy 37.545772 -239.23244) (xy 37.545328 -239.237716)
			(xy 37.537843 -239.245159) (xy 37.532564 -239.245648) (xy 37.01669 -239.245648) (xy 37.008816 -239.245939)
			(xy 36.993812 -239.250721) (xy 36.987226 -239.255046) (xy 36.966159 -239.269454) (xy 36.920511 -239.292279)
			(xy 36.871901 -239.307832) (xy 36.821482 -239.315746) (xy 36.795964 -239.31626) (xy 36.770444 -239.315763)
			(xy 36.720017 -239.307872) (xy 36.671405 -239.292314) (xy 36.625767 -239.269461) (xy 36.604702 -239.255046)
			(xy 36.598109 -239.250733) (xy 36.58311 -239.245944) (xy 36.575238 -239.245648) (xy 36.059364 -239.245648)
			(xy 36.054107 -239.245133) (xy 36.046668 -239.237697) (xy 36.046156 -239.23244) (xy 33.445704 -239.23244)
			(xy 33.445232 -239.237709) (xy 33.437766 -239.245149) (xy 33.432496 -239.245648) (xy 32.916622 -239.245648)
			(xy 32.908749 -239.245953) (xy 32.893745 -239.250725) (xy 32.887158 -239.255046) (xy 32.866082 -239.26944)
			(xy 32.820437 -239.292268) (xy 32.77183 -239.307825) (xy 32.721413 -239.315743) (xy 32.695896 -239.31626)
			(xy 32.670375 -239.315797) (xy 32.619946 -239.307895) (xy 32.571335 -239.292328) (xy 32.525698 -239.269465)
			(xy 32.504634 -239.255046) (xy 32.498034 -239.250746) (xy 32.483041 -239.245949) (xy 32.47517 -239.245648)
			(xy 31.959296 -239.245648) (xy 31.954042 -239.245112) (xy 31.946602 -239.237692) (xy 31.946088 -239.23244)
			(xy 30.001972 -239.23244) (xy 30.001528 -239.237716) (xy 29.994043 -239.245159) (xy 29.988764 -239.245648)
			(xy 29.47289 -239.245648) (xy 29.465016 -239.245939) (xy 29.450012 -239.250721) (xy 29.443426 -239.255046)
			(xy 29.422359 -239.269454) (xy 29.376711 -239.292279) (xy 29.328101 -239.307832) (xy 29.277682 -239.315746)
			(xy 29.252164 -239.31626) (xy 29.226644 -239.315763) (xy 29.176217 -239.307872) (xy 29.127605 -239.292314)
			(xy 29.081967 -239.269461) (xy 29.060902 -239.255046) (xy 29.054309 -239.250733) (xy 29.03931 -239.245944)
			(xy 29.031438 -239.245648) (xy 28.515564 -239.245648) (xy 28.510307 -239.245133) (xy 28.502868 -239.237697)
			(xy 28.502356 -239.23244) (xy 25.901904 -239.23244) (xy 25.901432 -239.237709) (xy 25.893966 -239.245149)
			(xy 25.888696 -239.245648) (xy 25.372822 -239.245648) (xy 25.364949 -239.245953) (xy 25.349945 -239.250725)
			(xy 25.343358 -239.255046) (xy 25.322282 -239.26944) (xy 25.276637 -239.292268) (xy 25.22803 -239.307825)
			(xy 25.177613 -239.315743) (xy 25.152096 -239.31626) (xy 25.126575 -239.315797) (xy 25.076146 -239.307895)
			(xy 25.027535 -239.292328) (xy 24.981898 -239.269465) (xy 24.960834 -239.255046) (xy 24.954234 -239.250746)
			(xy 24.939241 -239.245949) (xy 24.93137 -239.245648) (xy 24.415496 -239.245648) (xy 24.410242 -239.245112)
			(xy 24.402802 -239.237692) (xy 24.402288 -239.23244) (xy 22.458172 -239.23244) (xy 22.457728 -239.237716)
			(xy 22.450243 -239.245159) (xy 22.444964 -239.245648) (xy 22.444456 -239.245648) (xy 21.928836 -239.245648)
			(xy 21.92096 -239.245916) (xy 21.905956 -239.250713) (xy 21.899372 -239.255046) (xy 21.878293 -239.269434)
			(xy 21.832648 -239.292264) (xy 21.784043 -239.307822) (xy 21.733627 -239.315742) (xy 21.70811 -239.31626)
			(xy 21.682589 -239.31579) (xy 21.632161 -239.30789) (xy 21.583549 -239.292325) (xy 21.537912 -239.269464)
			(xy 21.516848 -239.255046) (xy 21.510267 -239.250713) (xy 21.495259 -239.245936) (xy 21.487384 -239.245648)
			(xy 20.97151 -239.245648) (xy 20.966204 -239.245169) (xy 20.958632 -239.237736) (xy 20.958048 -239.23244)
			(xy 18.358104 -239.23244) (xy 18.357632 -239.237709) (xy 18.350166 -239.245149) (xy 18.344896 -239.245648)
			(xy 18.344388 -239.245648) (xy 17.828768 -239.245648) (xy 17.820893 -239.24593) (xy 17.805889 -239.250718)
			(xy 17.799304 -239.255046) (xy 17.778216 -239.269421) (xy 17.732575 -239.292253) (xy 17.683972 -239.307815)
			(xy 17.633558 -239.31574) (xy 17.608042 -239.31626) (xy 17.582522 -239.315774) (xy 17.532094 -239.307879)
			(xy 17.483482 -239.292319) (xy 17.437844 -239.269462) (xy 17.41678 -239.255046) (xy 17.410192 -239.250725)
			(xy 17.395189 -239.245941) (xy 17.387316 -239.245648) (xy 16.871442 -239.245648) (xy 16.86614 -239.245147)
			(xy 16.858566 -239.237731) (xy 16.85798 -239.23244) (xy 2.509012 -239.23244) (xy 2.509012 -240.082578)
			(xy 16.85798 -240.082578) (xy 16.85798 -239.58804) (xy 16.858353 -239.582716) (xy 16.865865 -239.575174)
			(xy 16.871188 -239.574832) (xy 16.871696 -239.574832) (xy 17.38757 -239.574832) (xy 17.39538 -239.574517)
			(xy 17.410252 -239.569733) (xy 17.41678 -239.565434) (xy 17.437869 -239.551085) (xy 17.48353 -239.528354)
			(xy 17.532136 -239.512895) (xy 17.582539 -239.505072) (xy 17.633545 -239.505072) (xy 17.683948 -239.512895)
			(xy 17.732554 -239.528354) (xy 17.778215 -239.551085) (xy 17.799304 -239.565434) (xy 17.805839 -239.569719)
			(xy 17.820706 -239.574507) (xy 17.828514 -239.574832) (xy 18.344642 -239.574832) (xy 18.34995 -239.575294)
			(xy 18.357518 -239.582741) (xy 18.358104 -239.58804) (xy 18.358104 -240.082578) (xy 18.358077 -240.082832)
			(xy 24.402288 -240.082832) (xy 24.402288 -240.082324) (xy 24.402288 -239.58804) (xy 24.402653 -239.582714)
			(xy 24.410171 -239.575171) (xy 24.415496 -239.574832) (xy 24.931624 -239.574832) (xy 24.939436 -239.57454)
			(xy 24.954308 -239.56974) (xy 24.960834 -239.565434) (xy 24.981923 -239.551085) (xy 25.027584 -239.528354)
			(xy 25.07619 -239.512895) (xy 25.126593 -239.505072) (xy 25.177599 -239.505072) (xy 25.228002 -239.512895)
			(xy 25.276608 -239.528354) (xy 25.322269 -239.551085) (xy 25.343358 -239.565434) (xy 25.349881 -239.56974)
			(xy 25.364757 -239.574515) (xy 25.372568 -239.574832) (xy 25.888696 -239.574832) (xy 25.894037 -239.575134)
			(xy 25.901581 -239.582698) (xy 25.901904 -239.58804) (xy 25.901904 -240.082578) (xy 25.901878 -240.082832)
			(xy 31.946088 -240.082832) (xy 31.946088 -240.082324) (xy 31.946088 -239.58804) (xy 31.946453 -239.582714)
			(xy 31.953971 -239.575171) (xy 31.959296 -239.574832) (xy 32.475424 -239.574832) (xy 32.483236 -239.57454)
			(xy 32.498108 -239.56974) (xy 32.504634 -239.565434) (xy 32.525723 -239.551085) (xy 32.571384 -239.528354)
			(xy 32.61999 -239.512895) (xy 32.670393 -239.505072) (xy 32.721399 -239.505072) (xy 32.771802 -239.512895)
			(xy 32.820408 -239.528354) (xy 32.866069 -239.551085) (xy 32.887158 -239.565434) (xy 32.893681 -239.56974)
			(xy 32.908557 -239.574515) (xy 32.916368 -239.574832) (xy 33.432496 -239.574832) (xy 33.437837 -239.575134)
			(xy 33.445381 -239.582698) (xy 33.445704 -239.58804) (xy 33.445704 -240.082578) (xy 39.489888 -240.082578)
			(xy 39.489888 -239.58804) (xy 39.490253 -239.582714) (xy 39.497771 -239.575171) (xy 39.503096 -239.574832)
			(xy 39.503604 -239.574832) (xy 40.019478 -239.574832) (xy 40.027288 -239.57452) (xy 40.04216 -239.569734)
			(xy 40.048688 -239.565434) (xy 40.069777 -239.551085) (xy 40.115438 -239.528354) (xy 40.164044 -239.512895)
			(xy 40.214447 -239.505072) (xy 40.265453 -239.505072) (xy 40.315856 -239.512895) (xy 40.364462 -239.528354)
			(xy 40.410123 -239.551085) (xy 40.431212 -239.565434) (xy 40.437745 -239.569722) (xy 40.452614 -239.574508)
			(xy 40.460422 -239.574832) (xy 40.97655 -239.574832) (xy 40.981846 -239.575356) (xy 40.98942 -239.582756)
			(xy 40.990012 -239.58804) (xy 40.990012 -240.082578) (xy 40.989985 -240.082832) (xy 47.034196 -240.082832)
			(xy 47.034196 -240.082324) (xy 47.034196 -239.58804) (xy 47.034554 -239.582712) (xy 47.042077 -239.575169)
			(xy 47.047404 -239.574832) (xy 47.563532 -239.574832) (xy 47.571341 -239.574501) (xy 47.586213 -239.569728)
			(xy 47.592742 -239.565434) (xy 47.613831 -239.551085) (xy 47.659492 -239.528354) (xy 47.708098 -239.512895)
			(xy 47.758501 -239.505072) (xy 47.809507 -239.505072) (xy 47.85991 -239.512895) (xy 47.908516 -239.528354)
			(xy 47.954177 -239.551085) (xy 47.975266 -239.565434) (xy 47.98181 -239.569705) (xy 47.99667 -239.574502)
			(xy 48.004476 -239.574832) (xy 48.520604 -239.574832) (xy 48.525947 -239.575128) (xy 48.53349 -239.582696)
			(xy 48.533812 -239.58804) (xy 48.533812 -240.082578) (xy 54.577996 -240.082578) (xy 54.577996 -239.58804)
			(xy 54.578354 -239.582712) (xy 54.585877 -239.575169) (xy 54.591204 -239.574832) (xy 54.591712 -239.574832)
			(xy 56.064658 -239.574832) (xy 56.069955 -239.57535) (xy 56.077528 -239.582755) (xy 56.07812 -239.58804)
			(xy 56.07812 -240.082578) (xy 56.078105 -240.082832) (xy 163.678108 -240.082832) (xy 163.678108 -240.082324)
			(xy 163.678108 -239.58804) (xy 163.678455 -239.582709) (xy 163.685986 -239.575165) (xy 163.691316 -239.574832)
			(xy 165.164516 -239.574832) (xy 165.16986 -239.57512) (xy 165.177403 -239.582694) (xy 165.177724 -239.58804)
			(xy 165.177724 -240.082578) (xy 171.221908 -240.082578) (xy 171.221908 -239.58804) (xy 171.222255 -239.582709)
			(xy 171.229786 -239.575165) (xy 171.235116 -239.574832) (xy 171.235624 -239.574832) (xy 171.751498 -239.574832)
			(xy 171.759309 -239.574529) (xy 171.774181 -239.569737) (xy 171.780708 -239.565434) (xy 171.801797 -239.551085)
			(xy 171.847458 -239.528354) (xy 171.896064 -239.512895) (xy 171.946467 -239.505072) (xy 171.997473 -239.505072)
			(xy 172.047876 -239.512895) (xy 172.096482 -239.528354) (xy 172.142143 -239.551085) (xy 172.163232 -239.565434)
			(xy 172.169761 -239.56973) (xy 172.184633 -239.574511) (xy 172.192442 -239.574832) (xy 172.70857 -239.574832)
			(xy 172.713869 -239.575342) (xy 172.721441 -239.582753) (xy 172.722032 -239.58804) (xy 172.722032 -240.082578)
			(xy 172.722017 -240.082832) (xy 178.766216 -240.082832) (xy 178.766216 -240.082324) (xy 178.766216 -239.58804)
			(xy 178.766556 -239.582707) (xy 178.774092 -239.575163) (xy 178.779424 -239.574832) (xy 179.295552 -239.574832)
			(xy 179.303361 -239.574509) (xy 179.318233 -239.569731) (xy 179.324762 -239.565434) (xy 179.345851 -239.551085)
			(xy 179.391512 -239.528354) (xy 179.440118 -239.512895) (xy 179.490521 -239.505072) (xy 179.541527 -239.505072)
			(xy 179.59193 -239.512895) (xy 179.640536 -239.528354) (xy 179.686197 -239.551085) (xy 179.707286 -239.565434)
			(xy 179.713825 -239.569712) (xy 179.728689 -239.574505) (xy 179.736496 -239.574832) (xy 180.252624 -239.574832)
			(xy 180.257969 -239.575115) (xy 180.265511 -239.582693) (xy 180.265832 -239.58804) (xy 180.265832 -240.082578)
			(xy 186.310016 -240.082578) (xy 186.310016 -239.58804) (xy 186.310356 -239.582707) (xy 186.317892 -239.575163)
			(xy 186.323224 -239.574832) (xy 186.323732 -239.574832) (xy 186.839606 -239.574832) (xy 186.847418 -239.574532)
			(xy 186.862289 -239.569738) (xy 186.868816 -239.565434) (xy 186.889905 -239.551085) (xy 186.935566 -239.528354)
			(xy 186.984172 -239.512895) (xy 187.034575 -239.505072) (xy 187.085581 -239.505072) (xy 187.135984 -239.512895)
			(xy 187.18459 -239.528354) (xy 187.230251 -239.551085) (xy 187.25134 -239.565434) (xy 187.257867 -239.569733)
			(xy 187.27274 -239.574512) (xy 187.28055 -239.574832) (xy 187.796678 -239.574832) (xy 187.801978 -239.575337)
			(xy 187.80955 -239.582751) (xy 187.81014 -239.58804) (xy 187.81014 -240.082578) (xy 187.810124 -240.082832)
			(xy 193.854324 -240.082832) (xy 193.854324 -240.082324) (xy 193.854324 -239.58804) (xy 193.854657 -239.582705)
			(xy 193.862198 -239.57516) (xy 193.867532 -239.574832) (xy 194.38366 -239.574832) (xy 194.39147 -239.574513)
			(xy 194.406342 -239.569732) (xy 194.41287 -239.565434) (xy 194.433959 -239.551085) (xy 194.47962 -239.528354)
			(xy 194.528226 -239.512895) (xy 194.578629 -239.505072) (xy 194.629635 -239.505072) (xy 194.680038 -239.512895)
			(xy 194.728644 -239.528354) (xy 194.774305 -239.551085) (xy 194.795394 -239.565434) (xy 194.801931 -239.569715)
			(xy 194.816797 -239.574506) (xy 194.824604 -239.574832) (xy 195.340732 -239.574832) (xy 195.346078 -239.575109)
			(xy 195.35362 -239.582692) (xy 195.35394 -239.58804) (xy 195.35394 -240.082578) (xy 195.353917 -240.082832)
			(xy 201.398124 -240.082832) (xy 201.398124 -240.082324) (xy 201.398124 -239.58804) (xy 201.398457 -239.582705)
			(xy 201.405998 -239.57516) (xy 201.411332 -239.574832) (xy 201.92746 -239.574832) (xy 201.93527 -239.574513)
			(xy 201.950142 -239.569732) (xy 201.95667 -239.565434) (xy 201.977759 -239.551085) (xy 202.02342 -239.528354)
			(xy 202.072026 -239.512895) (xy 202.122429 -239.505072) (xy 202.173435 -239.505072) (xy 202.223838 -239.512895)
			(xy 202.272444 -239.528354) (xy 202.318105 -239.551085) (xy 202.339194 -239.565434) (xy 202.345731 -239.569715)
			(xy 202.360597 -239.574506) (xy 202.368404 -239.574832) (xy 202.884532 -239.574832) (xy 202.889878 -239.575109)
			(xy 202.89742 -239.582692) (xy 202.89774 -239.58804) (xy 202.89774 -240.082324) (xy 264.798048 -240.082324)
			(xy 264.798048 -239.587786) (xy 264.798542 -239.582418) (xy 264.806141 -239.574833) (xy 264.81151 -239.574324)
			(xy 265.327638 -239.574324) (xy 265.335447 -239.573997) (xy 265.350319 -239.569222) (xy 265.356848 -239.564926)
			(xy 265.377937 -239.550577) (xy 265.423598 -239.527846) (xy 265.472204 -239.512387) (xy 265.522607 -239.504564)
			(xy 265.573613 -239.504564) (xy 265.624016 -239.512387) (xy 265.672622 -239.527846) (xy 265.718283 -239.550577)
			(xy 265.739372 -239.564926) (xy 265.745915 -239.569198) (xy 265.760776 -239.573994) (xy 265.768582 -239.574324)
			(xy 266.28471 -239.574324) (xy 266.290072 -239.574842) (xy 266.297656 -239.582424) (xy 266.298172 -239.587786)
			(xy 266.298172 -240.082324) (xy 272.342356 -240.082324) (xy 272.342356 -239.587786) (xy 272.342816 -239.582476)
			(xy 272.350263 -239.574905) (xy 272.355564 -239.574324) (xy 272.871692 -239.574324) (xy 272.879503 -239.57402)
			(xy 272.894375 -239.569229) (xy 272.900902 -239.564926) (xy 272.921991 -239.550577) (xy 272.967652 -239.527846)
			(xy 273.016258 -239.512387) (xy 273.066661 -239.504564) (xy 273.117667 -239.504564) (xy 273.16807 -239.512387)
			(xy 273.216676 -239.527846) (xy 273.262337 -239.550577) (xy 273.283426 -239.564926) (xy 273.289957 -239.569219)
			(xy 273.304827 -239.574002) (xy 273.312636 -239.574324) (xy 273.828764 -239.574324) (xy 273.834099 -239.574654)
			(xy 273.841644 -239.582197) (xy 273.841972 -239.587532) (xy 273.841972 -239.58804) (xy 273.841972 -240.082324)
			(xy 279.886156 -240.082324) (xy 279.886156 -239.587786) (xy 279.886616 -239.582476) (xy 279.894063 -239.574905)
			(xy 279.899364 -239.574324) (xy 280.415492 -239.574324) (xy 280.423303 -239.57402) (xy 280.438175 -239.569229)
			(xy 280.444702 -239.564926) (xy 280.465791 -239.550577) (xy 280.511452 -239.527846) (xy 280.560058 -239.512387)
			(xy 280.610461 -239.504564) (xy 280.661467 -239.504564) (xy 280.71187 -239.512387) (xy 280.760476 -239.527846)
			(xy 280.806137 -239.550577) (xy 280.827226 -239.564926) (xy 280.833757 -239.569219) (xy 280.848627 -239.574002)
			(xy 280.856436 -239.574324) (xy 281.372564 -239.574324) (xy 281.377899 -239.574654) (xy 281.385444 -239.582197)
			(xy 281.385772 -239.587532) (xy 281.385772 -239.58804) (xy 281.385772 -240.082324) (xy 287.429956 -240.082324)
			(xy 287.429956 -239.587786) (xy 287.430272 -239.582345) (xy 287.437976 -239.574659) (xy 287.443418 -239.574324)
			(xy 287.959546 -239.574324) (xy 287.967355 -239.574) (xy 287.982227 -239.569223) (xy 287.988756 -239.564926)
			(xy 288.009845 -239.550577) (xy 288.055506 -239.527846) (xy 288.104112 -239.512387) (xy 288.154515 -239.504564)
			(xy 288.205521 -239.504564) (xy 288.255924 -239.512387) (xy 288.30453 -239.527846) (xy 288.350191 -239.550577)
			(xy 288.37128 -239.564926) (xy 288.377821 -239.569201) (xy 288.392684 -239.573996) (xy 288.40049 -239.574324)
			(xy 288.916618 -239.574324) (xy 288.921981 -239.574837) (xy 288.929565 -239.582423) (xy 288.93008 -239.587786)
			(xy 288.93008 -240.082324) (xy 294.974264 -240.082324) (xy 294.974264 -239.587786) (xy 294.974717 -239.582475)
			(xy 294.982169 -239.574903) (xy 294.987472 -239.574324) (xy 295.5036 -239.574324) (xy 295.511411 -239.574023)
			(xy 295.526283 -239.56923) (xy 295.53281 -239.564926) (xy 295.553899 -239.550577) (xy 295.59956 -239.527846)
			(xy 295.648166 -239.512387) (xy 295.698569 -239.504564) (xy 295.749575 -239.504564) (xy 295.799978 -239.512387)
			(xy 295.848584 -239.527846) (xy 295.894245 -239.550577) (xy 295.915334 -239.564926) (xy 295.921863 -239.569222)
			(xy 295.936735 -239.574003) (xy 295.944544 -239.574324) (xy 296.460672 -239.574324) (xy 296.466008 -239.574649)
			(xy 296.473553 -239.582196) (xy 296.47388 -239.587532) (xy 296.47388 -239.58804) (xy 296.47388 -240.082324)
			(xy 302.518064 -240.082324) (xy 302.518064 -239.587786) (xy 302.518373 -239.582343) (xy 302.526082 -239.574656)
			(xy 302.531526 -239.574324) (xy 304.004726 -239.574324) (xy 304.01009 -239.574832) (xy 304.017673 -239.582422)
			(xy 304.018188 -239.587786) (xy 304.018188 -240.082324) (xy 411.618176 -240.082324) (xy 411.618176 -239.587786)
			(xy 411.618618 -239.582472) (xy 411.626078 -239.574899) (xy 411.631384 -239.574324) (xy 413.104584 -239.574324)
			(xy 413.109922 -239.574641) (xy 413.117466 -239.582194) (xy 413.117792 -239.587532) (xy 413.117792 -239.58804)
			(xy 413.117792 -240.082324) (xy 419.161976 -240.082324) (xy 419.161976 -239.587786) (xy 419.162274 -239.58234)
			(xy 419.169991 -239.574653) (xy 419.175438 -239.574324) (xy 419.691566 -239.574324) (xy 419.699376 -239.574009)
			(xy 419.714248 -239.569225) (xy 419.720776 -239.564926) (xy 419.741865 -239.550577) (xy 419.787526 -239.527846)
			(xy 419.836132 -239.512387) (xy 419.886535 -239.504564) (xy 419.937541 -239.504564) (xy 419.987944 -239.512387)
			(xy 420.03655 -239.527846) (xy 420.082211 -239.550577) (xy 420.1033 -239.564926) (xy 420.109837 -239.569209)
			(xy 420.124703 -239.573998) (xy 420.13251 -239.574324) (xy 420.648638 -239.574324) (xy 420.654003 -239.574824)
			(xy 420.661586 -239.58242) (xy 420.6621 -239.587786) (xy 420.6621 -240.082324) (xy 426.706284 -240.082324)
			(xy 426.706284 -239.587786) (xy 426.706719 -239.58247) (xy 426.714184 -239.574897) (xy 426.719492 -239.574324)
			(xy 427.23562 -239.574324) (xy 427.243432 -239.574031) (xy 427.258304 -239.569232) (xy 427.26483 -239.564926)
			(xy 427.285919 -239.550577) (xy 427.33158 -239.527846) (xy 427.380186 -239.512387) (xy 427.430589 -239.504564)
			(xy 427.481595 -239.504564) (xy 427.531998 -239.512387) (xy 427.580604 -239.527846) (xy 427.626265 -239.550577)
			(xy 427.647354 -239.564926) (xy 427.653879 -239.56923) (xy 427.668754 -239.574006) (xy 427.676564 -239.574324)
			(xy 428.192692 -239.574324) (xy 428.198031 -239.574635) (xy 428.205574 -239.582192) (xy 428.2059 -239.587532)
			(xy 428.2059 -239.58804) (xy 428.2059 -240.082324) (xy 434.250084 -240.082324) (xy 434.250084 -239.587786)
			(xy 434.250375 -239.582338) (xy 434.258097 -239.57465) (xy 434.263546 -239.574324) (xy 434.779674 -239.574324)
			(xy 434.787484 -239.574012) (xy 434.802356 -239.569226) (xy 434.808884 -239.564926) (xy 434.829973 -239.550577)
			(xy 434.875634 -239.527846) (xy 434.92424 -239.512387) (xy 434.974643 -239.504564) (xy 435.025649 -239.504564)
			(xy 435.076052 -239.512387) (xy 435.124658 -239.527846) (xy 435.170319 -239.550577) (xy 435.191408 -239.564926)
			(xy 435.197943 -239.569212) (xy 435.21281 -239.574) (xy 435.220618 -239.574324) (xy 435.736746 -239.574324)
			(xy 435.742112 -239.574819) (xy 435.749694 -239.582419) (xy 435.750208 -239.587786) (xy 435.750208 -240.082324)
			(xy 441.794392 -240.082324) (xy 441.794392 -239.587786) (xy 441.794908 -239.582491) (xy 441.802317 -239.574924)
			(xy 441.8076 -239.574324) (xy 442.323728 -239.574324) (xy 442.331541 -239.574035) (xy 442.346412 -239.569233)
			(xy 442.352938 -239.564926) (xy 442.374027 -239.550577) (xy 442.419688 -239.527846) (xy 442.468294 -239.512387)
			(xy 442.518697 -239.504564) (xy 442.569703 -239.504564) (xy 442.620106 -239.512387) (xy 442.668712 -239.527846)
			(xy 442.714373 -239.550577) (xy 442.735462 -239.564926) (xy 442.742007 -239.569194) (xy 442.756866 -239.573993)
			(xy 442.764672 -239.574324) (xy 443.2808 -239.574324) (xy 443.28614 -239.57463) (xy 443.293683 -239.582191)
			(xy 443.294008 -239.587532) (xy 443.294008 -239.58804) (xy 443.294008 -240.082324) (xy 449.338192 -240.082324)
			(xy 449.338192 -239.587786) (xy 449.338708 -239.582491) (xy 449.346117 -239.574924) (xy 449.3514 -239.574324)
			(xy 449.867528 -239.574324) (xy 449.875341 -239.574035) (xy 449.890212 -239.569233) (xy 449.896738 -239.564926)
			(xy 449.917827 -239.550577) (xy 449.963488 -239.527846) (xy 450.012094 -239.512387) (xy 450.062497 -239.504564)
			(xy 450.113503 -239.504564) (xy 450.163906 -239.512387) (xy 450.212512 -239.527846) (xy 450.258173 -239.550577)
			(xy 450.279262 -239.564926) (xy 450.285807 -239.569194) (xy 450.300666 -239.573993) (xy 450.308472 -239.574324)
			(xy 450.8246 -239.574324) (xy 450.82994 -239.57463) (xy 450.837483 -239.582191) (xy 450.837808 -239.587532)
			(xy 450.837808 -239.58804) (xy 450.837808 -240.082324) (xy 450.837321 -240.08759) (xy 450.829866 -240.095031)
			(xy 450.8246 -240.095532) (xy 450.308726 -240.095532) (xy 450.30085 -240.095798) (xy 450.285846 -240.100597)
			(xy 450.279262 -240.10493) (xy 450.258184 -240.119321) (xy 450.21254 -240.14215) (xy 450.163934 -240.157708)
			(xy 450.113517 -240.165627) (xy 450.088 -240.166144) (xy 450.06248 -240.165663) (xy 450.012053 -240.157765)
			(xy 449.963441 -240.142202) (xy 449.917803 -240.119346) (xy 449.896738 -240.10493) (xy 449.890138 -240.10063)
			(xy 449.875145 -240.095834) (xy 449.867274 -240.095532) (xy 449.3514 -240.095532) (xy 449.346143 -240.095008)
			(xy 449.338702 -240.08758) (xy 449.338192 -240.082324) (xy 443.294008 -240.082324) (xy 443.293521 -240.08759)
			(xy 443.286066 -240.095031) (xy 443.2808 -240.095532) (xy 442.764926 -240.095532) (xy 442.75705 -240.095798)
			(xy 442.742046 -240.100597) (xy 442.735462 -240.10493) (xy 442.714384 -240.119321) (xy 442.66874 -240.14215)
			(xy 442.620134 -240.157708) (xy 442.569717 -240.165627) (xy 442.5442 -240.166144) (xy 442.51868 -240.165663)
			(xy 442.468253 -240.157765) (xy 442.419641 -240.142202) (xy 442.374003 -240.119346) (xy 442.352938 -240.10493)
			(xy 442.346338 -240.10063) (xy 442.331345 -240.095834) (xy 442.323474 -240.095532) (xy 441.8076 -240.095532)
			(xy 441.802343 -240.095008) (xy 441.794902 -240.08758) (xy 441.794392 -240.082324) (xy 435.750208 -240.082324)
			(xy 435.749721 -240.08759) (xy 435.742266 -240.095031) (xy 435.737 -240.095532) (xy 435.736492 -240.095532)
			(xy 435.220872 -240.095532) (xy 435.212997 -240.095818) (xy 435.197993 -240.100603) (xy 435.191408 -240.10493)
			(xy 435.170345 -240.119344) (xy 435.124695 -240.142168) (xy 435.076085 -240.15772) (xy 435.025664 -240.165631)
			(xy 435.000146 -240.166144) (xy 434.974626 -240.16564) (xy 434.9242 -240.157749) (xy 434.875589 -240.142193)
			(xy 434.82995 -240.119343) (xy 434.808884 -240.10493) (xy 434.802296 -240.100609) (xy 434.787293 -240.095826)
			(xy 434.77942 -240.095532) (xy 434.263546 -240.095532) (xy 434.258241 -240.095043) (xy 434.250666 -240.087618)
			(xy 434.250084 -240.082324) (xy 428.2059 -240.082324) (xy 428.20542 -240.087592) (xy 428.197961 -240.095033)
			(xy 428.192692 -240.095532) (xy 427.676818 -240.095532) (xy 427.668945 -240.095838) (xy 427.653941 -240.10061)
			(xy 427.647354 -240.10493) (xy 427.626278 -240.119324) (xy 427.580633 -240.142153) (xy 427.532026 -240.15771)
			(xy 427.481609 -240.165628) (xy 427.456092 -240.166144) (xy 427.430573 -240.165617) (xy 427.380148 -240.157733)
			(xy 427.331537 -240.142183) (xy 427.285897 -240.11934) (xy 427.26483 -240.10493) (xy 427.258232 -240.100627)
			(xy 427.243237 -240.095832) (xy 427.235366 -240.095532) (xy 426.719492 -240.095532) (xy 426.714234 -240.095013)
			(xy 426.706793 -240.087581) (xy 426.706284 -240.082324) (xy 420.6621 -240.082324) (xy 420.66162 -240.087592)
			(xy 420.654161 -240.095033) (xy 420.648892 -240.095532) (xy 420.648384 -240.095532) (xy 420.132764 -240.095532)
			(xy 420.124889 -240.095815) (xy 420.109885 -240.100602) (xy 420.1033 -240.10493) (xy 420.082211 -240.119304)
			(xy 420.036571 -240.142137) (xy 419.987968 -240.1577) (xy 419.937554 -240.165624) (xy 419.912038 -240.166144)
			(xy 419.886518 -240.165644) (xy 419.836092 -240.157751) (xy 419.787481 -240.142194) (xy 419.741842 -240.119343)
			(xy 419.720776 -240.10493) (xy 419.71419 -240.100606) (xy 419.699186 -240.095824) (xy 419.691312 -240.095532)
			(xy 419.175438 -240.095532) (xy 419.170132 -240.095048) (xy 419.162557 -240.08762) (xy 419.161976 -240.082324)
			(xy 413.117792 -240.082324) (xy 413.117319 -240.087593) (xy 413.109855 -240.095035) (xy 413.104584 -240.095532)
			(xy 411.631384 -240.095532) (xy 411.626125 -240.095019) (xy 411.618685 -240.087583) (xy 411.618176 -240.082324)
			(xy 304.018188 -240.082324) (xy 304.017719 -240.087594) (xy 304.010252 -240.095037) (xy 304.00498 -240.095532)
			(xy 304.004472 -240.095532) (xy 302.531526 -240.095532) (xy 302.526218 -240.095056) (xy 302.518644 -240.087622)
			(xy 302.518064 -240.082324) (xy 296.47388 -240.082324) (xy 296.473586 -240.087666) (xy 296.466016 -240.095207)
			(xy 296.460672 -240.095532) (xy 295.944798 -240.095532) (xy 295.936924 -240.09583) (xy 295.921921 -240.100607)
			(xy 295.915334 -240.10493) (xy 295.894264 -240.119333) (xy 295.848617 -240.142159) (xy 295.800008 -240.157714)
			(xy 295.749589 -240.165629) (xy 295.724072 -240.166144) (xy 295.698553 -240.165627) (xy 295.648128 -240.15774)
			(xy 295.599516 -240.142187) (xy 295.553876 -240.119341) (xy 295.53281 -240.10493) (xy 295.526216 -240.100619)
			(xy 295.511218 -240.095829) (xy 295.503346 -240.095532) (xy 294.987472 -240.095532) (xy 294.982212 -240.095026)
			(xy 294.974772 -240.087585) (xy 294.974264 -240.082324) (xy 288.93008 -240.082324) (xy 288.929786 -240.087666)
			(xy 288.922216 -240.095207) (xy 288.916872 -240.095532) (xy 288.916364 -240.095532) (xy 288.400744 -240.095532)
			(xy 288.392868 -240.095806) (xy 288.377864 -240.100599) (xy 288.37128 -240.10493) (xy 288.350197 -240.119313)
			(xy 288.304554 -240.142144) (xy 288.25595 -240.157704) (xy 288.205534 -240.165626) (xy 288.180018 -240.166144)
			(xy 288.154498 -240.165654) (xy 288.104071 -240.157758) (xy 288.05546 -240.142198) (xy 288.009821 -240.119344)
			(xy 287.988756 -240.10493) (xy 287.982174 -240.100598) (xy 287.967167 -240.095821) (xy 287.959292 -240.095532)
			(xy 287.443418 -240.095532) (xy 287.438109 -240.095062) (xy 287.430536 -240.087623) (xy 287.429956 -240.082324)
			(xy 281.385772 -240.082324) (xy 281.385486 -240.087668) (xy 281.37791 -240.09521) (xy 281.372564 -240.095532)
			(xy 280.85669 -240.095532) (xy 280.848816 -240.095826) (xy 280.833812 -240.100606) (xy 280.827226 -240.10493)
			(xy 280.806158 -240.119336) (xy 280.76051 -240.142162) (xy 280.711901 -240.157716) (xy 280.661482 -240.16563)
			(xy 280.635964 -240.166144) (xy 280.610445 -240.165631) (xy 280.560019 -240.157742) (xy 280.511408 -240.142189)
			(xy 280.465768 -240.119341) (xy 280.444702 -240.10493) (xy 280.43811 -240.100616) (xy 280.42311 -240.095828)
			(xy 280.415238 -240.095532) (xy 279.899364 -240.095532) (xy 279.894103 -240.095031) (xy 279.886664 -240.087586)
			(xy 279.886156 -240.082324) (xy 273.841972 -240.082324) (xy 273.841686 -240.087668) (xy 273.83411 -240.09521)
			(xy 273.828764 -240.095532) (xy 273.31289 -240.095532) (xy 273.305016 -240.095826) (xy 273.290012 -240.100606)
			(xy 273.283426 -240.10493) (xy 273.262358 -240.119336) (xy 273.21671 -240.142162) (xy 273.168101 -240.157716)
			(xy 273.117682 -240.16563) (xy 273.092164 -240.166144) (xy 273.066645 -240.165631) (xy 273.016219 -240.157742)
			(xy 272.967608 -240.142189) (xy 272.921968 -240.119341) (xy 272.900902 -240.10493) (xy 272.89431 -240.100616)
			(xy 272.87931 -240.095828) (xy 272.871438 -240.095532) (xy 272.355564 -240.095532) (xy 272.350303 -240.095031)
			(xy 272.342864 -240.087586) (xy 272.342356 -240.082324) (xy 266.298172 -240.082324) (xy 266.297886 -240.087668)
			(xy 266.29031 -240.09521) (xy 266.284964 -240.095532) (xy 266.284456 -240.095532) (xy 265.768836 -240.095532)
			(xy 265.76096 -240.095803) (xy 265.745956 -240.100598) (xy 265.739372 -240.10493) (xy 265.718291 -240.119317)
			(xy 265.672648 -240.142147) (xy 265.624043 -240.157706) (xy 265.573626 -240.165626) (xy 265.54811 -240.166144)
			(xy 265.52259 -240.165658) (xy 265.472163 -240.157761) (xy 265.423552 -240.1422) (xy 265.377913 -240.119345)
			(xy 265.356848 -240.10493) (xy 265.350268 -240.100595) (xy 265.335259 -240.09582) (xy 265.327384 -240.095532)
			(xy 264.81151 -240.095532) (xy 264.806201 -240.095067) (xy 264.798627 -240.087624) (xy 264.798048 -240.082324)
			(xy 202.89774 -240.082324) (xy 202.89774 -240.082578) (xy 202.89726 -240.087884) (xy 202.889828 -240.095458)
			(xy 202.884532 -240.09604) (xy 202.368658 -240.09604) (xy 202.360849 -240.096372) (xy 202.345978 -240.101145)
			(xy 202.339448 -240.105438) (xy 202.318337 -240.119804) (xy 202.27261 -240.142528) (xy 202.223933 -240.157953)
			(xy 202.173464 -240.165714) (xy 202.147932 -240.166144) (xy 202.122402 -240.165695) (xy 202.071939 -240.157924)
			(xy 202.023266 -240.142498) (xy 201.977538 -240.119784) (xy 201.956416 -240.105438) (xy 201.949878 -240.101158)
			(xy 201.935013 -240.096367) (xy 201.927206 -240.09604) (xy 201.411332 -240.09604) (xy 201.406081 -240.095487)
			(xy 201.398638 -240.088081) (xy 201.398124 -240.082832) (xy 195.353917 -240.082832) (xy 195.35346 -240.087884)
			(xy 195.346028 -240.095458) (xy 195.340732 -240.09604) (xy 194.824858 -240.09604) (xy 194.817049 -240.096372)
			(xy 194.802178 -240.101145) (xy 194.795648 -240.105438) (xy 194.774537 -240.119804) (xy 194.72881 -240.142528)
			(xy 194.680133 -240.157953) (xy 194.629664 -240.165714) (xy 194.604132 -240.166144) (xy 194.578602 -240.165695)
			(xy 194.528139 -240.157924) (xy 194.479466 -240.142498) (xy 194.433738 -240.119784) (xy 194.412616 -240.105438)
			(xy 194.406078 -240.101158) (xy 194.391213 -240.096367) (xy 194.383406 -240.09604) (xy 193.867532 -240.09604)
			(xy 193.862281 -240.095487) (xy 193.854838 -240.088081) (xy 193.854324 -240.082832) (xy 187.810124 -240.082832)
			(xy 187.809804 -240.088015) (xy 187.802115 -240.095704) (xy 187.796678 -240.09604) (xy 187.280804 -240.09604)
			(xy 187.272993 -240.096348) (xy 187.258122 -240.101137) (xy 187.251594 -240.105438) (xy 187.230471 -240.119784)
			(xy 187.184747 -240.142512) (xy 187.136075 -240.157943) (xy 187.085609 -240.165711) (xy 187.060078 -240.166144)
			(xy 187.034547 -240.165722) (xy 186.984083 -240.157942) (xy 186.93541 -240.142509) (xy 186.889683 -240.119788)
			(xy 186.868562 -240.105438) (xy 186.862036 -240.101137) (xy 186.847162 -240.09636) (xy 186.839352 -240.09604)
			(xy 186.323478 -240.09604) (xy 186.318106 -240.095562) (xy 186.31052 -240.087952) (xy 186.310016 -240.082578)
			(xy 180.265832 -240.082578) (xy 180.265359 -240.087886) (xy 180.257922 -240.09546) (xy 180.252624 -240.09604)
			(xy 179.73675 -240.09604) (xy 179.728941 -240.096368) (xy 179.714069 -240.101144) (xy 179.70754 -240.105438)
			(xy 179.686432 -240.119808) (xy 179.640703 -240.14253) (xy 179.592026 -240.157955) (xy 179.541556 -240.165715)
			(xy 179.516024 -240.166144) (xy 179.490494 -240.165699) (xy 179.44003 -240.157926) (xy 179.391358 -240.1425)
			(xy 179.34563 -240.119785) (xy 179.324508 -240.105438) (xy 179.317972 -240.101155) (xy 179.303105 -240.096366)
			(xy 179.295298 -240.09604) (xy 178.779424 -240.09604) (xy 178.774172 -240.095492) (xy 178.76673 -240.088082)
			(xy 178.766216 -240.082832) (xy 172.722017 -240.082832) (xy 172.721703 -240.088017) (xy 172.714009 -240.095706)
			(xy 172.70857 -240.09604) (xy 172.192696 -240.09604) (xy 172.184885 -240.096345) (xy 172.170013 -240.101136)
			(xy 172.163486 -240.105438) (xy 172.142365 -240.119788) (xy 172.096641 -240.142515) (xy 172.047968 -240.157945)
			(xy 171.997501 -240.165711) (xy 171.97197 -240.166144) (xy 171.946439 -240.165726) (xy 171.895974 -240.157945)
			(xy 171.847302 -240.142511) (xy 171.801575 -240.119788) (xy 171.780454 -240.105438) (xy 171.77393 -240.101134)
			(xy 171.759054 -240.096358) (xy 171.751244 -240.09604) (xy 171.23537 -240.09604) (xy 171.229997 -240.095567)
			(xy 171.222412 -240.087953) (xy 171.221908 -240.082578) (xy 165.177724 -240.082578) (xy 165.177258 -240.087888)
			(xy 165.169816 -240.095462) (xy 165.164516 -240.09604) (xy 163.691316 -240.09604) (xy 163.686063 -240.095498)
			(xy 163.678621 -240.088083) (xy 163.678108 -240.082832) (xy 56.078105 -240.082832) (xy 56.077802 -240.08802)
			(xy 56.070101 -240.09571) (xy 56.064658 -240.09604) (xy 54.591458 -240.09604) (xy 54.586084 -240.095575)
			(xy 54.578499 -240.087955) (xy 54.577996 -240.082578) (xy 48.533812 -240.082578) (xy 48.533356 -240.087891)
			(xy 48.525908 -240.095466) (xy 48.520604 -240.09604) (xy 48.00473 -240.09604) (xy 47.99692 -240.09636)
			(xy 47.982049 -240.101141) (xy 47.97552 -240.105438) (xy 47.954389 -240.119773) (xy 47.908669 -240.142503)
			(xy 47.859998 -240.157938) (xy 47.809534 -240.165709) (xy 47.784004 -240.166144) (xy 47.758474 -240.165709)
			(xy 47.70801 -240.157933) (xy 47.659337 -240.142504) (xy 47.61361 -240.119786) (xy 47.592488 -240.105438)
			(xy 47.585956 -240.101147) (xy 47.571086 -240.096363) (xy 47.563278 -240.09604) (xy 47.047404 -240.09604)
			(xy 47.042149 -240.095506) (xy 47.034708 -240.088085) (xy 47.034196 -240.082832) (xy 40.989985 -240.082832)
			(xy 40.98944 -240.087927) (xy 40.981896 -240.095511) (xy 40.97655 -240.09604) (xy 40.460676 -240.09604)
			(xy 40.452864 -240.096337) (xy 40.437993 -240.101134) (xy 40.431466 -240.105438) (xy 40.41035 -240.119797)
			(xy 40.364624 -240.142522) (xy 40.315949 -240.157949) (xy 40.265482 -240.165713) (xy 40.23995 -240.166144)
			(xy 40.214421 -240.165686) (xy 40.163957 -240.157917) (xy 40.115285 -240.142494) (xy 40.069556 -240.119783)
			(xy 40.048434 -240.105438) (xy 40.041892 -240.101165) (xy 40.02703 -240.09637) (xy 40.019224 -240.09604)
			(xy 39.50335 -240.09604) (xy 39.497975 -240.09558) (xy 39.490391 -240.087956) (xy 39.489888 -240.082578)
			(xy 33.445704 -240.082578) (xy 33.445168 -240.087869) (xy 33.437775 -240.095439) (xy 33.432496 -240.09604)
			(xy 32.916622 -240.09604) (xy 32.908812 -240.096357) (xy 32.89394 -240.10114) (xy 32.887412 -240.105438)
			(xy 32.866283 -240.119777) (xy 32.820562 -240.142506) (xy 32.771891 -240.157939) (xy 32.721426 -240.165709)
			(xy 32.695896 -240.166144) (xy 32.670365 -240.165713) (xy 32.619901 -240.157936) (xy 32.571229 -240.142505)
			(xy 32.525502 -240.119787) (xy 32.50438 -240.105438) (xy 32.49785 -240.101144) (xy 32.482979 -240.096362)
			(xy 32.47517 -240.09604) (xy 31.959296 -240.09604) (xy 31.95404 -240.095511) (xy 31.9466 -240.088087)
			(xy 31.946088 -240.082832) (xy 25.901878 -240.082832) (xy 25.901368 -240.087869) (xy 25.893975 -240.095439)
			(xy 25.888696 -240.09604) (xy 25.372822 -240.09604) (xy 25.365012 -240.096357) (xy 25.35014 -240.10114)
			(xy 25.343612 -240.105438) (xy 25.322483 -240.119777) (xy 25.276762 -240.142506) (xy 25.228091 -240.157939)
			(xy 25.177626 -240.165709) (xy 25.152096 -240.166144) (xy 25.126565 -240.165713) (xy 25.076101 -240.157936)
			(xy 25.027429 -240.142505) (xy 24.981702 -240.119787) (xy 24.96058 -240.105438) (xy 24.95405 -240.101144)
			(xy 24.939179 -240.096362) (xy 24.93137 -240.09604) (xy 24.415496 -240.09604) (xy 24.41024 -240.095511)
			(xy 24.4028 -240.088087) (xy 24.402288 -240.082832) (xy 18.358077 -240.082832) (xy 18.357539 -240.087929)
			(xy 18.349991 -240.095514) (xy 18.344642 -240.09604) (xy 17.828768 -240.09604) (xy 17.82096 -240.096376)
			(xy 17.806088 -240.101146) (xy 17.799558 -240.105438) (xy 17.778445 -240.1198) (xy 17.732718 -240.142524)
			(xy 17.684042 -240.157951) (xy 17.633574 -240.165713) (xy 17.608042 -240.166144) (xy 17.582512 -240.16569)
			(xy 17.532049 -240.15792) (xy 17.483377 -240.142496) (xy 17.437648 -240.119784) (xy 17.416526 -240.105438)
			(xy 17.409986 -240.101162) (xy 17.395123 -240.096369) (xy 17.387316 -240.09604) (xy 16.871442 -240.09604)
			(xy 16.866007 -240.09569) (xy 16.858318 -240.088012) (xy 16.85798 -240.082578) (xy 2.509012 -240.082578)
			(xy 2.509012 -240.932462) (xy 20.958048 -240.932462) (xy 20.958048 -240.437924) (xy 20.958606 -240.432675)
			(xy 20.966009 -240.425233) (xy 20.971256 -240.424716) (xy 20.971764 -240.424716) (xy 21.487638 -240.424716)
			(xy 21.495447 -240.42439) (xy 21.510319 -240.419614) (xy 21.516848 -240.415318) (xy 21.537937 -240.400969)
			(xy 21.583598 -240.378238) (xy 21.632204 -240.362779) (xy 21.682607 -240.354956) (xy 21.733613 -240.354956)
			(xy 21.784016 -240.362779) (xy 21.832622 -240.378238) (xy 21.878283 -240.400969) (xy 21.899372 -240.415318)
			(xy 21.905915 -240.419589) (xy 21.920776 -240.424386) (xy 21.928582 -240.424716) (xy 22.44471 -240.424716)
			(xy 22.45001 -240.425214) (xy 22.457579 -240.432635) (xy 22.458172 -240.437924) (xy 22.458172 -240.932462)
			(xy 22.458154 -240.932716) (xy 28.502356 -240.932716) (xy 28.502356 -240.932208) (xy 28.502356 -240.437924)
			(xy 28.502907 -240.432673) (xy 28.510315 -240.425231) (xy 28.515564 -240.424716) (xy 29.031692 -240.424716)
			(xy 29.039503 -240.424413) (xy 29.054375 -240.419621) (xy 29.060902 -240.415318) (xy 29.081991 -240.400969)
			(xy 29.127652 -240.378238) (xy 29.176258 -240.362779) (xy 29.226661 -240.354956) (xy 29.277667 -240.354956)
			(xy 29.32807 -240.362779) (xy 29.376676 -240.378238) (xy 29.422337 -240.400969) (xy 29.443426 -240.415318)
			(xy 29.449957 -240.41961) (xy 29.464827 -240.424394) (xy 29.472636 -240.424716) (xy 29.988764 -240.424716)
			(xy 29.994097 -240.425053) (xy 30.001642 -240.432591) (xy 30.001972 -240.437924) (xy 30.001972 -240.932462)
			(xy 30.001947 -240.932716) (xy 36.046156 -240.932716) (xy 36.046156 -240.932208) (xy 36.046156 -240.437924)
			(xy 36.046707 -240.432673) (xy 36.054115 -240.425231) (xy 36.059364 -240.424716) (xy 36.575492 -240.424716)
			(xy 36.583303 -240.424413) (xy 36.598175 -240.419621) (xy 36.604702 -240.415318) (xy 36.625791 -240.400969)
			(xy 36.671452 -240.378238) (xy 36.720058 -240.362779) (xy 36.770461 -240.354956) (xy 36.821467 -240.354956)
			(xy 36.87187 -240.362779) (xy 36.920476 -240.378238) (xy 36.966137 -240.400969) (xy 36.987226 -240.415318)
			(xy 36.993757 -240.41961) (xy 37.008627 -240.424394) (xy 37.016436 -240.424716) (xy 37.532564 -240.424716)
			(xy 37.537897 -240.425053) (xy 37.545442 -240.432591) (xy 37.545772 -240.437924) (xy 37.545772 -240.932462)
			(xy 43.589956 -240.932462) (xy 43.589956 -240.437924) (xy 43.590507 -240.432673) (xy 43.597915 -240.425231)
			(xy 43.603164 -240.424716) (xy 43.603672 -240.424716) (xy 44.119546 -240.424716) (xy 44.127356 -240.424394)
			(xy 44.142228 -240.419615) (xy 44.148756 -240.415318) (xy 44.169845 -240.400969) (xy 44.215506 -240.378238)
			(xy 44.264112 -240.362779) (xy 44.314515 -240.354956) (xy 44.365521 -240.354956) (xy 44.415924 -240.362779)
			(xy 44.46453 -240.378238) (xy 44.510191 -240.400969) (xy 44.53128 -240.415318) (xy 44.537821 -240.419593)
			(xy 44.552684 -240.424387) (xy 44.56049 -240.424716) (xy 45.076618 -240.424716) (xy 45.081919 -240.425208)
			(xy 45.089488 -240.432634) (xy 45.09008 -240.437924) (xy 45.09008 -240.932462) (xy 45.090062 -240.932716)
			(xy 51.134264 -240.932716) (xy 51.134264 -240.932208) (xy 51.134264 -240.437924) (xy 51.134808 -240.432671)
			(xy 51.142221 -240.425229) (xy 51.147472 -240.424716) (xy 51.6636 -240.424716) (xy 51.671412 -240.424416)
			(xy 51.686283 -240.419622) (xy 51.69281 -240.415318) (xy 51.713899 -240.400969) (xy 51.75956 -240.378238)
			(xy 51.808166 -240.362779) (xy 51.858569 -240.354956) (xy 51.909575 -240.354956) (xy 51.959978 -240.362779)
			(xy 52.008584 -240.378238) (xy 52.054245 -240.400969) (xy 52.075334 -240.415318) (xy 52.081863 -240.419613)
			(xy 52.096735 -240.424395) (xy 52.104544 -240.424716) (xy 52.620672 -240.424716) (xy 52.626006 -240.425048)
			(xy 52.633551 -240.43259) (xy 52.63388 -240.437924) (xy 52.63388 -240.932462) (xy 58.678064 -240.932462)
			(xy 58.678064 -240.437924) (xy 58.678608 -240.432671) (xy 58.686021 -240.425229) (xy 58.691272 -240.424716)
			(xy 58.69178 -240.424716) (xy 60.164726 -240.424716) (xy 60.170028 -240.425203) (xy 60.177596 -240.432632)
			(xy 60.178188 -240.437924) (xy 60.178188 -240.932462) (xy 60.17817 -240.932716) (xy 167.778176 -240.932716)
			(xy 167.778176 -240.932208) (xy 167.778176 -240.437924) (xy 167.778541 -240.432599) (xy 167.78606 -240.425057)
			(xy 167.791384 -240.424716) (xy 169.264584 -240.424716) (xy 169.26992 -240.42504) (xy 169.277463 -240.432588)
			(xy 169.277792 -240.437924) (xy 169.277792 -240.932462) (xy 175.321976 -240.932462) (xy 175.321976 -240.437924)
			(xy 175.322341 -240.432599) (xy 175.32986 -240.425057) (xy 175.335184 -240.424716) (xy 175.335692 -240.424716)
			(xy 175.851566 -240.424716) (xy 175.859376 -240.424402) (xy 175.874248 -240.419618) (xy 175.880776 -240.415318)
			(xy 175.901865 -240.400969) (xy 175.947526 -240.378238) (xy 175.996132 -240.362779) (xy 176.046535 -240.354956)
			(xy 176.097541 -240.354956) (xy 176.147944 -240.362779) (xy 176.19655 -240.378238) (xy 176.242211 -240.400969)
			(xy 176.2633 -240.415318) (xy 176.269837 -240.4196) (xy 176.284703 -240.42439) (xy 176.29251 -240.424716)
			(xy 176.808638 -240.424716) (xy 176.813941 -240.425195) (xy 176.821509 -240.432631) (xy 176.8221 -240.437924)
			(xy 176.8221 -240.932462) (xy 176.822073 -240.932716) (xy 182.866284 -240.932716) (xy 182.866284 -240.932208)
			(xy 182.866284 -240.437924) (xy 182.866642 -240.432597) (xy 182.874166 -240.425055) (xy 182.879492 -240.424716)
			(xy 183.39562 -240.424716) (xy 183.403432 -240.424425) (xy 183.418304 -240.419625) (xy 183.42483 -240.415318)
			(xy 183.445919 -240.400969) (xy 183.49158 -240.378238) (xy 183.540186 -240.362779) (xy 183.590589 -240.354956)
			(xy 183.641595 -240.354956) (xy 183.691998 -240.362779) (xy 183.740604 -240.378238) (xy 183.786265 -240.400969)
			(xy 183.807354 -240.415318) (xy 183.813879 -240.419621) (xy 183.828754 -240.424398) (xy 183.836564 -240.424716)
			(xy 184.352692 -240.424716) (xy 184.358029 -240.425034) (xy 184.365572 -240.432587) (xy 184.3659 -240.437924)
			(xy 184.3659 -240.932462) (xy 190.410084 -240.932462) (xy 190.410084 -240.437924) (xy 190.410442 -240.432597)
			(xy 190.417966 -240.425055) (xy 190.423292 -240.424716) (xy 190.4238 -240.424716) (xy 190.939674 -240.424716)
			(xy 190.947485 -240.424405) (xy 190.962357 -240.419619) (xy 190.968884 -240.415318) (xy 190.989973 -240.400969)
			(xy 191.035634 -240.378238) (xy 191.08424 -240.362779) (xy 191.134643 -240.354956) (xy 191.185649 -240.354956)
			(xy 191.236052 -240.362779) (xy 191.284658 -240.378238) (xy 191.330319 -240.400969) (xy 191.351408 -240.415318)
			(xy 191.357943 -240.419603) (xy 191.37281 -240.424392) (xy 191.380618 -240.424716) (xy 191.896746 -240.424716)
			(xy 191.902038 -240.425256) (xy 191.909611 -240.432645) (xy 191.910208 -240.437924) (xy 191.910208 -240.932462)
			(xy 191.910181 -240.932716) (xy 197.954392 -240.932716) (xy 197.954392 -240.932208) (xy 197.954392 -240.437924)
			(xy 197.954743 -240.432595) (xy 197.962272 -240.425053) (xy 197.9676 -240.424716) (xy 198.483728 -240.424716)
			(xy 198.491541 -240.424428) (xy 198.506412 -240.419626) (xy 198.512938 -240.415318) (xy 198.534027 -240.400969)
			(xy 198.579688 -240.378238) (xy 198.628294 -240.362779) (xy 198.678697 -240.354956) (xy 198.729703 -240.354956)
			(xy 198.780106 -240.362779) (xy 198.828712 -240.378238) (xy 198.874373 -240.400969) (xy 198.895462 -240.415318)
			(xy 198.902008 -240.419586) (xy 198.916867 -240.424385) (xy 198.924672 -240.424716) (xy 199.4408 -240.424716)
			(xy 199.446138 -240.425029) (xy 199.453681 -240.432585) (xy 199.454008 -240.437924) (xy 199.454008 -240.932462)
			(xy 199.453982 -240.932716) (xy 205.498192 -240.932716) (xy 205.498192 -240.932208) (xy 205.498192 -240.437924)
			(xy 205.498543 -240.432595) (xy 205.506072 -240.425053) (xy 205.5114 -240.424716) (xy 206.027528 -240.424716)
			(xy 206.035341 -240.424428) (xy 206.050212 -240.419626) (xy 206.056738 -240.415318) (xy 206.077827 -240.400969)
			(xy 206.123488 -240.378238) (xy 206.172094 -240.362779) (xy 206.222497 -240.354956) (xy 206.273503 -240.354956)
			(xy 206.323906 -240.362779) (xy 206.372512 -240.378238) (xy 206.418173 -240.400969) (xy 206.439262 -240.415318)
			(xy 206.445808 -240.419586) (xy 206.460667 -240.424385) (xy 206.468472 -240.424716) (xy 206.9846 -240.424716)
			(xy 206.989938 -240.425029) (xy 206.997481 -240.432585) (xy 206.997808 -240.437924) (xy 206.997808 -240.932208)
			(xy 268.898116 -240.932208) (xy 268.898116 -240.43767) (xy 268.898628 -240.432308) (xy 268.906215 -240.424725)
			(xy 268.911578 -240.424208) (xy 269.427706 -240.424208) (xy 269.435516 -240.423896) (xy 269.450387 -240.419108)
			(xy 269.456916 -240.41481) (xy 269.478005 -240.400461) (xy 269.523666 -240.37773) (xy 269.572272 -240.362271)
			(xy 269.622675 -240.354448) (xy 269.673681 -240.354448) (xy 269.724084 -240.362271) (xy 269.77269 -240.37773)
			(xy 269.818351 -240.400461) (xy 269.83944 -240.41481) (xy 269.845963 -240.419116) (xy 269.86084 -240.42389)
			(xy 269.86865 -240.424208) (xy 270.384778 -240.424208) (xy 270.390132 -240.424762) (xy 270.397717 -240.432318)
			(xy 270.39824 -240.43767) (xy 270.39824 -240.932208) (xy 276.442424 -240.932208) (xy 276.442424 -240.43767)
			(xy 276.442901 -240.432366) (xy 276.450337 -240.424797) (xy 276.455632 -240.424208) (xy 276.97176 -240.424208)
			(xy 276.979568 -240.423876) (xy 276.99444 -240.419102) (xy 277.00097 -240.41481) (xy 277.022059 -240.400461)
			(xy 277.06772 -240.37773) (xy 277.116326 -240.362271) (xy 277.166729 -240.354448) (xy 277.217735 -240.354448)
			(xy 277.268138 -240.362271) (xy 277.316744 -240.37773) (xy 277.362405 -240.400461) (xy 277.383494 -240.41481)
			(xy 277.390027 -240.419099) (xy 277.404896 -240.423883) (xy 277.412704 -240.424208) (xy 277.928832 -240.424208)
			(xy 277.934102 -240.424675) (xy 277.941544 -240.432144) (xy 277.94204 -240.437416) (xy 277.94204 -240.437924)
			(xy 277.94204 -240.932208) (xy 283.986224 -240.932208) (xy 283.986224 -240.43767) (xy 283.986701 -240.432366)
			(xy 283.994137 -240.424797) (xy 283.999432 -240.424208) (xy 284.51556 -240.424208) (xy 284.523368 -240.423876)
			(xy 284.53824 -240.419102) (xy 284.54477 -240.41481) (xy 284.565859 -240.400461) (xy 284.61152 -240.37773)
			(xy 284.660126 -240.362271) (xy 284.710529 -240.354448) (xy 284.761535 -240.354448) (xy 284.811938 -240.362271)
			(xy 284.860544 -240.37773) (xy 284.906205 -240.400461) (xy 284.927294 -240.41481) (xy 284.933827 -240.419099)
			(xy 284.948696 -240.423883) (xy 284.956504 -240.424208) (xy 285.472632 -240.424208) (xy 285.477902 -240.424675)
			(xy 285.485344 -240.432144) (xy 285.48584 -240.437416) (xy 285.48584 -240.437924) (xy 285.48584 -240.932208)
			(xy 291.530024 -240.932208) (xy 291.530024 -240.43767) (xy 291.530529 -240.432306) (xy 291.538121 -240.424723)
			(xy 291.543486 -240.424208) (xy 292.059614 -240.424208) (xy 292.067424 -240.423899) (xy 292.082296 -240.41911)
			(xy 292.088824 -240.41481) (xy 292.109913 -240.400461) (xy 292.155574 -240.37773) (xy 292.20418 -240.362271)
			(xy 292.254583 -240.354448) (xy 292.305589 -240.354448) (xy 292.355992 -240.362271) (xy 292.404598 -240.37773)
			(xy 292.450259 -240.400461) (xy 292.471348 -240.41481) (xy 292.477869 -240.419119) (xy 292.492747 -240.423891)
			(xy 292.500558 -240.424208) (xy 293.016686 -240.424208) (xy 293.022041 -240.424757) (xy 293.029626 -240.432317)
			(xy 293.030148 -240.43767) (xy 293.030148 -240.932208) (xy 299.074332 -240.932208) (xy 299.074332 -240.43767)
			(xy 299.074802 -240.432364) (xy 299.082243 -240.424795) (xy 299.08754 -240.424208) (xy 299.603668 -240.424208)
			(xy 299.611477 -240.423879) (xy 299.626348 -240.419104) (xy 299.632878 -240.41481) (xy 299.653967 -240.400461)
			(xy 299.699628 -240.37773) (xy 299.748234 -240.362271) (xy 299.798637 -240.354448) (xy 299.849643 -240.354448)
			(xy 299.900046 -240.362271) (xy 299.948652 -240.37773) (xy 299.994313 -240.400461) (xy 300.015402 -240.41481)
			(xy 300.021933 -240.419102) (xy 300.036803 -240.423884) (xy 300.044612 -240.424208) (xy 300.56074 -240.424208)
			(xy 300.566012 -240.42467) (xy 300.573453 -240.432142) (xy 300.573948 -240.437416) (xy 300.573948 -240.437924)
			(xy 300.573948 -240.932208) (xy 306.618132 -240.932208) (xy 306.618132 -240.43767) (xy 306.61863 -240.432304)
			(xy 306.626227 -240.42472) (xy 306.631594 -240.424208) (xy 308.104794 -240.424208) (xy 308.11015 -240.424751)
			(xy 308.117734 -240.432315) (xy 308.118256 -240.43767) (xy 308.118256 -240.932208) (xy 415.718244 -240.932208)
			(xy 415.718244 -240.43767) (xy 415.718704 -240.432361) (xy 415.726152 -240.424791) (xy 415.731452 -240.424208)
			(xy 417.204652 -240.424208) (xy 417.209982 -240.424561) (xy 417.217526 -240.432087) (xy 417.21786 -240.437416)
			(xy 417.21786 -240.437924) (xy 417.21786 -240.932208) (xy 423.262044 -240.932208) (xy 423.262044 -240.43767)
			(xy 423.262531 -240.432301) (xy 423.270136 -240.424717) (xy 423.275506 -240.424208) (xy 423.791634 -240.424208)
			(xy 423.799441 -240.423865) (xy 423.814313 -240.419099) (xy 423.820844 -240.41481) (xy 423.841933 -240.400461)
			(xy 423.887594 -240.37773) (xy 423.9362 -240.362271) (xy 423.986603 -240.354448) (xy 424.037609 -240.354448)
			(xy 424.088012 -240.362271) (xy 424.136618 -240.37773) (xy 424.182279 -240.400461) (xy 424.203368 -240.41481)
			(xy 424.209907 -240.419089) (xy 424.224771 -240.423879) (xy 424.232578 -240.424208) (xy 424.748706 -240.424208)
			(xy 424.754063 -240.424743) (xy 424.761647 -240.432313) (xy 424.762168 -240.43767) (xy 424.762168 -240.932208)
			(xy 430.806352 -240.932208) (xy 430.806352 -240.43767) (xy 430.806805 -240.432359) (xy 430.814258 -240.424789)
			(xy 430.81956 -240.424208) (xy 431.335688 -240.424208) (xy 431.343497 -240.423888) (xy 431.358369 -240.419106)
			(xy 431.364898 -240.41481) (xy 431.385987 -240.400461) (xy 431.431648 -240.37773) (xy 431.480254 -240.362271)
			(xy 431.530657 -240.354448) (xy 431.581663 -240.354448) (xy 431.632066 -240.362271) (xy 431.680672 -240.37773)
			(xy 431.726333 -240.400461) (xy 431.747422 -240.41481) (xy 431.753949 -240.419109) (xy 431.768822 -240.423887)
			(xy 431.776632 -240.424208) (xy 432.29276 -240.424208) (xy 432.298091 -240.424555) (xy 432.305635 -240.432086)
			(xy 432.305968 -240.437416) (xy 432.305968 -240.437924) (xy 432.305968 -240.932208) (xy 438.350152 -240.932208)
			(xy 438.350152 -240.43767) (xy 438.350632 -240.432299) (xy 438.358241 -240.424714) (xy 438.363614 -240.424208)
			(xy 438.879742 -240.424208) (xy 438.88755 -240.423868) (xy 438.902421 -240.4191) (xy 438.908952 -240.41481)
			(xy 438.930041 -240.400461) (xy 438.975702 -240.37773) (xy 439.024308 -240.362271) (xy 439.074711 -240.354448)
			(xy 439.125717 -240.354448) (xy 439.17612 -240.362271) (xy 439.224726 -240.37773) (xy 439.270387 -240.400461)
			(xy 439.291476 -240.41481) (xy 439.298013 -240.419092) (xy 439.312879 -240.42388) (xy 439.320686 -240.424208)
			(xy 439.836814 -240.424208) (xy 439.842172 -240.424738) (xy 439.849755 -240.432312) (xy 439.850276 -240.43767)
			(xy 439.850276 -240.932208) (xy 445.89446 -240.932208) (xy 445.89446 -240.43767) (xy 445.894905 -240.432357)
			(xy 445.902364 -240.424787) (xy 445.907668 -240.424208) (xy 446.423796 -240.424208) (xy 446.431606 -240.423891)
			(xy 446.446477 -240.419107) (xy 446.453006 -240.41481) (xy 446.474095 -240.400461) (xy 446.519756 -240.37773)
			(xy 446.568362 -240.362271) (xy 446.618765 -240.354448) (xy 446.669771 -240.354448) (xy 446.720174 -240.362271)
			(xy 446.76878 -240.37773) (xy 446.814441 -240.400461) (xy 446.83553 -240.41481) (xy 446.842055 -240.419112)
			(xy 446.85693 -240.423888) (xy 446.86474 -240.424208) (xy 447.380868 -240.424208) (xy 447.3862 -240.42455)
			(xy 447.393744 -240.432085) (xy 447.394076 -240.437416) (xy 447.394076 -240.437924) (xy 447.394076 -240.932208)
			(xy 453.43826 -240.932208) (xy 453.43826 -240.43767) (xy 453.438705 -240.432357) (xy 453.446164 -240.424787)
			(xy 453.451468 -240.424208) (xy 453.967596 -240.424208) (xy 453.975406 -240.423891) (xy 453.990277 -240.419107)
			(xy 453.996806 -240.41481) (xy 454.017895 -240.400461) (xy 454.063556 -240.37773) (xy 454.112162 -240.362271)
			(xy 454.162565 -240.354448) (xy 454.213571 -240.354448) (xy 454.263974 -240.362271) (xy 454.31258 -240.37773)
			(xy 454.358241 -240.400461) (xy 454.37933 -240.41481) (xy 454.385855 -240.419112) (xy 454.40073 -240.423888)
			(xy 454.40854 -240.424208) (xy 454.924668 -240.424208) (xy 454.93 -240.42455) (xy 454.937544 -240.432085)
			(xy 454.937876 -240.437416) (xy 454.937876 -240.437924) (xy 454.937876 -240.932208) (xy 454.937576 -240.937549)
			(xy 454.93001 -240.945092) (xy 454.924668 -240.945416) (xy 454.408794 -240.945416) (xy 454.40092 -240.945714)
			(xy 454.385917 -240.950491) (xy 454.37933 -240.954814) (xy 454.35826 -240.969217) (xy 454.312613 -240.992044)
			(xy 454.264004 -241.007598) (xy 454.213585 -241.015513) (xy 454.188068 -241.016028) (xy 454.162549 -241.015516)
			(xy 454.112123 -241.007628) (xy 454.063511 -240.992074) (xy 454.017872 -240.969226) (xy 453.996806 -240.954814)
			(xy 453.990214 -240.9505) (xy 453.975214 -240.945712) (xy 453.967342 -240.945416) (xy 453.451468 -240.945416)
			(xy 453.446203 -240.944927) (xy 453.438763 -240.937474) (xy 453.43826 -240.932208) (xy 447.394076 -240.932208)
			(xy 447.393776 -240.937549) (xy 447.38621 -240.945092) (xy 447.380868 -240.945416) (xy 446.864994 -240.945416)
			(xy 446.85712 -240.945714) (xy 446.842117 -240.950491) (xy 446.83553 -240.954814) (xy 446.81446 -240.969217)
			(xy 446.768813 -240.992044) (xy 446.720204 -241.007598) (xy 446.669785 -241.015513) (xy 446.644268 -241.016028)
			(xy 446.618749 -241.015516) (xy 446.568323 -241.007628) (xy 446.519711 -240.992074) (xy 446.474072 -240.969226)
			(xy 446.453006 -240.954814) (xy 446.446414 -240.9505) (xy 446.431414 -240.945712) (xy 446.423542 -240.945416)
			(xy 445.907668 -240.945416) (xy 445.902403 -240.944927) (xy 445.894963 -240.937474) (xy 445.89446 -240.932208)
			(xy 439.850276 -240.932208) (xy 439.849976 -240.937549) (xy 439.84241 -240.945092) (xy 439.837068 -240.945416)
			(xy 439.83656 -240.945416) (xy 439.32094 -240.945416) (xy 439.313064 -240.945691) (xy 439.298061 -240.950484)
			(xy 439.291476 -240.954814) (xy 439.270393 -240.969197) (xy 439.22475 -240.992028) (xy 439.176146 -241.007589)
			(xy 439.12573 -241.01551) (xy 439.100214 -241.016028) (xy 439.074694 -241.015543) (xy 439.024267 -241.007646)
			(xy 438.975655 -240.992085) (xy 438.930017 -240.969229) (xy 438.908952 -240.954814) (xy 438.902372 -240.950479)
			(xy 438.887363 -240.945704) (xy 438.879488 -240.945416) (xy 438.363614 -240.945416) (xy 438.358301 -240.944962)
			(xy 438.350727 -240.937512) (xy 438.350152 -240.932208) (xy 432.305968 -240.932208) (xy 432.305675 -240.937551)
			(xy 432.298104 -240.945094) (xy 432.29276 -240.945416) (xy 431.776886 -240.945416) (xy 431.769012 -240.945711)
			(xy 431.754008 -240.95049) (xy 431.747422 -240.954814) (xy 431.726354 -240.96922) (xy 431.680706 -240.992046)
			(xy 431.632097 -241.0076) (xy 431.581678 -241.015514) (xy 431.55616 -241.016028) (xy 431.530641 -241.01552)
			(xy 431.480215 -241.00763) (xy 431.431603 -240.992076) (xy 431.385964 -240.969226) (xy 431.364898 -240.954814)
			(xy 431.358308 -240.950497) (xy 431.343307 -240.945711) (xy 431.335434 -240.945416) (xy 430.81956 -240.945416)
			(xy 430.814294 -240.944933) (xy 430.806854 -240.937475) (xy 430.806352 -240.932208) (xy 424.762168 -240.932208)
			(xy 424.761875 -240.937551) (xy 424.754304 -240.945094) (xy 424.74896 -240.945416) (xy 424.748452 -240.945416)
			(xy 424.232832 -240.945416) (xy 424.224956 -240.945688) (xy 424.209953 -240.950483) (xy 424.203368 -240.954814)
			(xy 424.182287 -240.9692) (xy 424.136644 -240.992031) (xy 424.088039 -241.00759) (xy 424.037622 -241.01551)
			(xy 424.012106 -241.016028) (xy 423.986586 -241.015547) (xy 423.936158 -241.007649) (xy 423.887547 -240.992086)
			(xy 423.841909 -240.96923) (xy 423.820844 -240.954814) (xy 423.814266 -240.950476) (xy 423.799256 -240.945703)
			(xy 423.79138 -240.945416) (xy 423.275506 -240.945416) (xy 423.270192 -240.944968) (xy 423.262618 -240.937513)
			(xy 423.262044 -240.932208) (xy 417.21786 -240.932208) (xy 417.217574 -240.937553) (xy 417.209999 -240.945097)
			(xy 417.204652 -240.945416) (xy 415.731452 -240.945416) (xy 415.726185 -240.944938) (xy 415.718746 -240.937476)
			(xy 415.718244 -240.932208) (xy 308.118256 -240.932208) (xy 308.117716 -240.93746) (xy 308.110299 -240.9449)
			(xy 308.105048 -240.945416) (xy 308.10454 -240.945416) (xy 306.631594 -240.945416) (xy 306.626279 -240.944976)
			(xy 306.618705 -240.937515) (xy 306.618132 -240.932208) (xy 300.573948 -240.932208) (xy 300.573415 -240.937462)
			(xy 300.565993 -240.944902) (xy 300.56074 -240.945416) (xy 300.044866 -240.945416) (xy 300.036991 -240.945702)
			(xy 300.021988 -240.950487) (xy 300.015402 -240.954814) (xy 299.994312 -240.969186) (xy 299.948672 -240.99202)
			(xy 299.90007 -241.007583) (xy 299.849656 -241.015508) (xy 299.82414 -241.016028) (xy 299.79862 -241.01553)
			(xy 299.748194 -241.007637) (xy 299.699582 -240.99208) (xy 299.653943 -240.969228) (xy 299.632878 -240.954814)
			(xy 299.626292 -240.950489) (xy 299.611288 -240.945708) (xy 299.603414 -240.945416) (xy 299.08754 -240.945416)
			(xy 299.082215 -240.945047) (xy 299.074672 -240.937532) (xy 299.074332 -240.932208) (xy 293.030148 -240.932208)
			(xy 293.029615 -240.937462) (xy 293.022193 -240.944902) (xy 293.01694 -240.945416) (xy 293.016432 -240.945416)
			(xy 292.500812 -240.945416) (xy 292.492939 -240.945722) (xy 292.477935 -240.950494) (xy 292.471348 -240.954814)
			(xy 292.450273 -240.969209) (xy 292.404627 -240.992038) (xy 292.356021 -241.007595) (xy 292.305603 -241.015512)
			(xy 292.280086 -241.016028) (xy 292.254567 -241.015507) (xy 292.204142 -241.007621) (xy 292.15553 -240.99207)
			(xy 292.10989 -240.969225) (xy 292.088824 -240.954814) (xy 292.082228 -240.950507) (xy 292.067231 -240.945715)
			(xy 292.05936 -240.945416) (xy 291.543486 -240.945416) (xy 291.53817 -240.944981) (xy 291.530597 -240.937516)
			(xy 291.530024 -240.932208) (xy 285.48584 -240.932208) (xy 285.485314 -240.937464) (xy 285.477887 -240.944904)
			(xy 285.472632 -240.945416) (xy 284.956758 -240.945416) (xy 284.948883 -240.945699) (xy 284.933879 -240.950486)
			(xy 284.927294 -240.954814) (xy 284.906206 -240.969189) (xy 284.860565 -240.992022) (xy 284.811962 -241.007585)
			(xy 284.761548 -241.015509) (xy 284.736032 -241.016028) (xy 284.710512 -241.015534) (xy 284.660085 -241.00764)
			(xy 284.611474 -240.992081) (xy 284.565835 -240.969228) (xy 284.54477 -240.954814) (xy 284.538186 -240.950486)
			(xy 284.52318 -240.945707) (xy 284.515306 -240.945416) (xy 283.999432 -240.945416) (xy 283.994106 -240.945052)
			(xy 283.986564 -240.937533) (xy 283.986224 -240.932208) (xy 277.94204 -240.932208) (xy 277.941514 -240.937464)
			(xy 277.934087 -240.944904) (xy 277.928832 -240.945416) (xy 277.412958 -240.945416) (xy 277.405083 -240.945699)
			(xy 277.390079 -240.950486) (xy 277.383494 -240.954814) (xy 277.362406 -240.969189) (xy 277.316765 -240.992022)
			(xy 277.268162 -241.007585) (xy 277.217748 -241.015509) (xy 277.192232 -241.016028) (xy 277.166712 -241.015534)
			(xy 277.116285 -241.00764) (xy 277.067674 -240.992081) (xy 277.022035 -240.969228) (xy 277.00097 -240.954814)
			(xy 276.994386 -240.950486) (xy 276.97938 -240.945707) (xy 276.971506 -240.945416) (xy 276.455632 -240.945416)
			(xy 276.450306 -240.945052) (xy 276.442764 -240.937533) (xy 276.442424 -240.932208) (xy 270.39824 -240.932208)
			(xy 270.397714 -240.937464) (xy 270.390287 -240.944904) (xy 270.385032 -240.945416) (xy 270.384524 -240.945416)
			(xy 269.868904 -240.945416) (xy 269.861031 -240.945719) (xy 269.846027 -240.950493) (xy 269.83944 -240.954814)
			(xy 269.818367 -240.969212) (xy 269.772721 -240.99204) (xy 269.724113 -241.007596) (xy 269.673695 -241.015513)
			(xy 269.648178 -241.016028) (xy 269.622659 -241.015511) (xy 269.572233 -241.007624) (xy 269.523622 -240.992072)
			(xy 269.477982 -240.969225) (xy 269.456916 -240.954814) (xy 269.450322 -240.950504) (xy 269.435324 -240.945714)
			(xy 269.427452 -240.945416) (xy 268.911578 -240.945416) (xy 268.906261 -240.944986) (xy 268.898688 -240.937518)
			(xy 268.898116 -240.932208) (xy 206.997808 -240.932208) (xy 206.997808 -240.932462) (xy 206.997257 -240.93775)
			(xy 206.989875 -240.945321) (xy 206.9846 -240.945924) (xy 206.468726 -240.945924) (xy 206.460916 -240.946244)
			(xy 206.446045 -240.951025) (xy 206.439516 -240.955322) (xy 206.418385 -240.969657) (xy 206.372665 -240.992388)
			(xy 206.323994 -241.007822) (xy 206.27353 -241.015593) (xy 206.248 -241.016028) (xy 206.222469 -241.015598)
			(xy 206.172005 -241.007821) (xy 206.123332 -240.99239) (xy 206.077605 -240.969671) (xy 206.056484 -240.955322)
			(xy 206.049954 -240.951028) (xy 206.035083 -240.946247) (xy 206.027274 -240.945924) (xy 205.5114 -240.945924)
			(xy 205.506141 -240.945407) (xy 205.4987 -240.937974) (xy 205.498192 -240.932716) (xy 199.453982 -240.932716)
			(xy 199.453457 -240.93775) (xy 199.446075 -240.945321) (xy 199.4408 -240.945924) (xy 198.924926 -240.945924)
			(xy 198.917116 -240.946244) (xy 198.902245 -240.951025) (xy 198.895716 -240.955322) (xy 198.874585 -240.969657)
			(xy 198.828865 -240.992388) (xy 198.780194 -241.007822) (xy 198.72973 -241.015593) (xy 198.7042 -241.016028)
			(xy 198.678669 -241.015598) (xy 198.628205 -241.007821) (xy 198.579532 -240.99239) (xy 198.533805 -240.969671)
			(xy 198.512684 -240.955322) (xy 198.506154 -240.951028) (xy 198.491283 -240.946247) (xy 198.483474 -240.945924)
			(xy 197.9676 -240.945924) (xy 197.962341 -240.945407) (xy 197.9549 -240.937974) (xy 197.954392 -240.932716)
			(xy 191.910181 -240.932716) (xy 191.909629 -240.93781) (xy 191.902091 -240.945396) (xy 191.896746 -240.945924)
			(xy 191.380872 -240.945924) (xy 191.37306 -240.946222) (xy 191.358189 -240.951018) (xy 191.351662 -240.955322)
			(xy 191.330546 -240.96968) (xy 191.284821 -240.992406) (xy 191.236145 -241.007834) (xy 191.185678 -241.015597)
			(xy 191.160146 -241.016028) (xy 191.134616 -241.015575) (xy 191.084153 -241.007805) (xy 191.03548 -240.992381)
			(xy 190.989752 -240.969668) (xy 190.96863 -240.955322) (xy 190.96209 -240.951046) (xy 190.947226 -240.946253)
			(xy 190.93942 -240.945924) (xy 190.423546 -240.945924) (xy 190.418108 -240.945586) (xy 190.410417 -240.9379)
			(xy 190.410084 -240.932462) (xy 184.3659 -240.932462) (xy 184.365356 -240.937752) (xy 184.357969 -240.945323)
			(xy 184.352692 -240.945924) (xy 183.836818 -240.945924) (xy 183.829008 -240.946241) (xy 183.814137 -240.951024)
			(xy 183.807608 -240.955322) (xy 183.786479 -240.96966) (xy 183.740758 -240.99239) (xy 183.692087 -241.007824)
			(xy 183.641622 -241.015593) (xy 183.616092 -241.016028) (xy 183.590561 -241.015602) (xy 183.540097 -241.007824)
			(xy 183.491424 -240.992392) (xy 183.445697 -240.969672) (xy 183.424576 -240.955322) (xy 183.418048 -240.951025)
			(xy 183.403175 -240.946245) (xy 183.395366 -240.945924) (xy 182.879492 -240.945924) (xy 182.874232 -240.945412)
			(xy 182.866791 -240.937976) (xy 182.866284 -240.932716) (xy 176.822073 -240.932716) (xy 176.821528 -240.937812)
			(xy 176.813985 -240.945398) (xy 176.808638 -240.945924) (xy 176.292764 -240.945924) (xy 176.284956 -240.946261)
			(xy 176.270084 -240.951031) (xy 176.263554 -240.955322) (xy 176.24244 -240.969684) (xy 176.196714 -240.992409)
			(xy 176.148038 -241.007835) (xy 176.09757 -241.015597) (xy 176.072038 -241.016028) (xy 176.046508 -241.015579)
			(xy 175.996045 -241.007808) (xy 175.947372 -240.992383) (xy 175.901644 -240.969669) (xy 175.880522 -240.955322)
			(xy 175.873983 -240.951043) (xy 175.859119 -240.946252) (xy 175.851312 -240.945924) (xy 175.335438 -240.945924)
			(xy 175.329999 -240.945592) (xy 175.322308 -240.937901) (xy 175.321976 -240.932462) (xy 169.277792 -240.932462)
			(xy 169.277255 -240.937754) (xy 169.269863 -240.945325) (xy 169.264584 -240.945924) (xy 167.791384 -240.945924)
			(xy 167.786123 -240.945418) (xy 167.778682 -240.937977) (xy 167.778176 -240.932716) (xy 60.17817 -240.932716)
			(xy 60.177798 -240.937886) (xy 60.170148 -240.945572) (xy 60.164726 -240.945924) (xy 58.691526 -240.945924)
			(xy 58.686085 -240.9456) (xy 58.678396 -240.937903) (xy 58.678064 -240.932462) (xy 52.63388 -240.932462)
			(xy 52.633354 -240.937757) (xy 52.625954 -240.945329) (xy 52.620672 -240.945924) (xy 52.104798 -240.945924)
			(xy 52.096987 -240.946233) (xy 52.082116 -240.951022) (xy 52.075588 -240.955322) (xy 52.054465 -240.969669)
			(xy 52.008742 -240.992397) (xy 51.960069 -241.007828) (xy 51.909603 -241.015595) (xy 51.884072 -241.016028)
			(xy 51.858541 -241.015612) (xy 51.808076 -241.007831) (xy 51.759403 -240.992396) (xy 51.713677 -240.969673)
			(xy 51.692556 -240.955322) (xy 51.686032 -240.951018) (xy 51.671156 -240.946243) (xy 51.663346 -240.945924)
			(xy 51.147472 -240.945924) (xy 51.14221 -240.945426) (xy 51.13477 -240.937979) (xy 51.134264 -240.932716)
			(xy 45.090062 -240.932716) (xy 45.089697 -240.937888) (xy 45.082042 -240.945575) (xy 45.076618 -240.945924)
			(xy 44.560744 -240.945924) (xy 44.552935 -240.946253) (xy 44.538064 -240.951028) (xy 44.531534 -240.955322)
			(xy 44.510426 -240.969692) (xy 44.464698 -240.992415) (xy 44.41602 -241.00784) (xy 44.36555 -241.015599)
			(xy 44.340018 -241.016028) (xy 44.314488 -241.015589) (xy 44.264024 -241.007815) (xy 44.215351 -240.992387)
			(xy 44.169624 -240.96967) (xy 44.148502 -240.955322) (xy 44.141968 -240.951035) (xy 44.1271 -240.946249)
			(xy 44.119292 -240.945924) (xy 43.603418 -240.945924) (xy 43.597976 -240.945605) (xy 43.590287 -240.937904)
			(xy 43.589956 -240.932462) (xy 37.545772 -240.932462) (xy 37.545253 -240.937759) (xy 37.537849 -240.945331)
			(xy 37.532564 -240.945924) (xy 37.01669 -240.945924) (xy 37.008879 -240.946229) (xy 36.994008 -240.951021)
			(xy 36.98748 -240.955322) (xy 36.966359 -240.969673) (xy 36.920635 -240.9924) (xy 36.871962 -241.00783)
			(xy 36.821495 -241.015596) (xy 36.795964 -241.016028) (xy 36.770433 -241.015616) (xy 36.719968 -241.007834)
			(xy 36.671295 -240.992398) (xy 36.625569 -240.969673) (xy 36.604448 -240.955322) (xy 36.597926 -240.951014)
			(xy 36.583049 -240.946241) (xy 36.575238 -240.945924) (xy 36.059364 -240.945924) (xy 36.054101 -240.945431)
			(xy 36.046661 -240.93798) (xy 36.046156 -240.932716) (xy 30.001947 -240.932716) (xy 30.001453 -240.937759)
			(xy 29.994049 -240.945331) (xy 29.988764 -240.945924) (xy 29.47289 -240.945924) (xy 29.465079 -240.946229)
			(xy 29.450208 -240.951021) (xy 29.44368 -240.955322) (xy 29.422559 -240.969673) (xy 29.376835 -240.9924)
			(xy 29.328162 -241.00783) (xy 29.277695 -241.015596) (xy 29.252164 -241.016028) (xy 29.226633 -241.015616)
			(xy 29.176168 -241.007834) (xy 29.127495 -240.992398) (xy 29.081769 -240.969673) (xy 29.060648 -240.955322)
			(xy 29.054126 -240.951014) (xy 29.039249 -240.946241) (xy 29.031438 -240.945924) (xy 28.515564 -240.945924)
			(xy 28.510301 -240.945431) (xy 28.502861 -240.93798) (xy 28.502356 -240.932716) (xy 22.458154 -240.932716)
			(xy 22.457796 -240.937889) (xy 22.450136 -240.945577) (xy 22.44471 -240.945924) (xy 21.928836 -240.945924)
			(xy 21.921027 -240.946249) (xy 21.906155 -240.951027) (xy 21.899626 -240.955322) (xy 21.878492 -240.969653)
			(xy 21.832773 -240.992384) (xy 21.784104 -241.00782) (xy 21.73364 -241.015592) (xy 21.70811 -241.016028)
			(xy 21.68258 -241.015593) (xy 21.632115 -241.007818) (xy 21.583443 -240.992388) (xy 21.537716 -240.96967)
			(xy 21.516594 -240.955322) (xy 21.510062 -240.951032) (xy 21.495192 -240.946248) (xy 21.487384 -240.945924)
			(xy 20.97151 -240.945924) (xy 20.966067 -240.94561) (xy 20.958378 -240.937906) (xy 20.958048 -240.932462)
			(xy 2.509012 -240.932462) (xy 2.509012 -241.782346) (xy 16.85798 -241.782346) (xy 16.85798 -241.287808)
			(xy 16.858499 -241.282549) (xy 16.86593 -241.275107) (xy 16.871188 -241.2746) (xy 16.871696 -241.2746)
			(xy 17.38757 -241.2746) (xy 17.395379 -241.274274) (xy 17.41025 -241.269496) (xy 17.41678 -241.265202)
			(xy 17.437869 -241.250853) (xy 17.48353 -241.228122) (xy 17.532136 -241.212663) (xy 17.582539 -241.20484)
			(xy 17.633545 -241.20484) (xy 17.683948 -241.212663) (xy 17.732554 -241.228122) (xy 17.778215 -241.250853)
			(xy 17.799304 -241.265202) (xy 17.805835 -241.269494) (xy 17.820705 -241.274276) (xy 17.828514 -241.2746)
			(xy 18.344642 -241.2746) (xy 18.349942 -241.27509) (xy 18.357508 -241.282518) (xy 18.358104 -241.287808)
			(xy 18.358104 -241.782346) (xy 18.358079 -241.7826) (xy 24.402288 -241.7826) (xy 24.402288 -241.782092)
			(xy 24.402288 -241.287808) (xy 24.402632 -241.282478) (xy 24.410166 -241.274937) (xy 24.415496 -241.2746)
			(xy 24.931624 -241.2746) (xy 24.939435 -241.274296) (xy 24.954306 -241.269503) (xy 24.960834 -241.265202)
			(xy 24.981923 -241.250853) (xy 25.027584 -241.228122) (xy 25.07619 -241.212663) (xy 25.126593 -241.20484)
			(xy 25.177599 -241.20484) (xy 25.228002 -241.212663) (xy 25.276608 -241.228122) (xy 25.322269 -241.250853)
			(xy 25.343358 -241.265202) (xy 25.349877 -241.269514) (xy 25.364757 -241.274284) (xy 25.372568 -241.2746)
			(xy 25.888696 -241.2746) (xy 25.89403 -241.27493) (xy 25.901571 -241.282474) (xy 25.901904 -241.287808)
			(xy 25.901904 -241.782346) (xy 25.901877 -241.7826) (xy 31.946088 -241.7826) (xy 31.946088 -241.782092)
			(xy 31.946088 -241.287808) (xy 31.946432 -241.282478) (xy 31.953966 -241.274937) (xy 31.959296 -241.2746)
			(xy 32.475424 -241.2746) (xy 32.483235 -241.274296) (xy 32.498106 -241.269503) (xy 32.504634 -241.265202)
			(xy 32.525723 -241.250853) (xy 32.571384 -241.228122) (xy 32.61999 -241.212663) (xy 32.670393 -241.20484)
			(xy 32.721399 -241.20484) (xy 32.771802 -241.212663) (xy 32.820408 -241.228122) (xy 32.866069 -241.250853)
			(xy 32.887158 -241.265202) (xy 32.893677 -241.269514) (xy 32.908557 -241.274284) (xy 32.916368 -241.2746)
			(xy 33.432496 -241.2746) (xy 33.43783 -241.27493) (xy 33.445371 -241.282474) (xy 33.445704 -241.287808)
			(xy 33.445704 -241.782346) (xy 39.489888 -241.782346) (xy 39.489888 -241.287808) (xy 39.490232 -241.282478)
			(xy 39.497766 -241.274937) (xy 39.503096 -241.2746) (xy 39.503604 -241.2746) (xy 40.019478 -241.2746)
			(xy 40.027287 -241.274277) (xy 40.042159 -241.269497) (xy 40.048688 -241.265202) (xy 40.069777 -241.250853)
			(xy 40.115438 -241.228122) (xy 40.164044 -241.212663) (xy 40.214447 -241.20484) (xy 40.265453 -241.20484)
			(xy 40.315856 -241.212663) (xy 40.364462 -241.228122) (xy 40.410123 -241.250853) (xy 40.431212 -241.265202)
			(xy 40.437741 -241.269497) (xy 40.452613 -241.274278) (xy 40.460422 -241.2746) (xy 40.97655 -241.2746)
			(xy 40.981839 -241.275152) (xy 40.98941 -241.282533) (xy 40.990012 -241.287808) (xy 40.990012 -241.782346)
			(xy 40.989987 -241.7826) (xy 47.034196 -241.7826) (xy 47.034196 -241.782092) (xy 47.034196 -241.287808)
			(xy 47.034532 -241.282476) (xy 47.042072 -241.274934) (xy 47.047404 -241.2746) (xy 47.563532 -241.2746)
			(xy 47.571339 -241.274258) (xy 47.586211 -241.269491) (xy 47.592742 -241.265202) (xy 47.613831 -241.250853)
			(xy 47.659492 -241.228122) (xy 47.708098 -241.212663) (xy 47.758501 -241.20484) (xy 47.809507 -241.20484)
			(xy 47.85991 -241.212663) (xy 47.908516 -241.228122) (xy 47.954177 -241.250853) (xy 47.975266 -241.265202)
			(xy 47.981806 -241.269479) (xy 47.996669 -241.274271) (xy 48.004476 -241.2746) (xy 48.520604 -241.2746)
			(xy 48.525939 -241.274925) (xy 48.53348 -241.282473) (xy 48.533812 -241.287808) (xy 48.533812 -241.782346)
			(xy 54.577996 -241.782346) (xy 54.577996 -241.287808) (xy 54.578332 -241.282476) (xy 54.585872 -241.274934)
			(xy 54.591204 -241.2746) (xy 54.591712 -241.2746) (xy 56.064658 -241.2746) (xy 56.069948 -241.275147)
			(xy 56.077519 -241.282532) (xy 56.07812 -241.287808) (xy 56.07812 -241.782346) (xy 56.078099 -241.7826)
			(xy 163.678108 -241.7826) (xy 163.678108 -241.782092) (xy 163.678108 -241.287808) (xy 163.678434 -241.282473)
			(xy 163.685981 -241.27493) (xy 163.691316 -241.2746) (xy 165.164516 -241.2746) (xy 165.169783 -241.275085)
			(xy 165.177225 -241.28254) (xy 165.177724 -241.287808) (xy 165.177724 -241.782346) (xy 171.221908 -241.782346)
			(xy 171.221908 -241.287808) (xy 171.222234 -241.282473) (xy 171.229781 -241.27493) (xy 171.235116 -241.2746)
			(xy 171.235624 -241.2746) (xy 171.751498 -241.2746) (xy 171.759308 -241.274286) (xy 171.774179 -241.2695)
			(xy 171.780708 -241.265202) (xy 171.801797 -241.250853) (xy 171.847458 -241.228122) (xy 171.896064 -241.212663)
			(xy 171.946467 -241.20484) (xy 171.997473 -241.20484) (xy 172.047876 -241.212663) (xy 172.096482 -241.228122)
			(xy 172.142143 -241.250853) (xy 172.163232 -241.265202) (xy 172.169757 -241.269504) (xy 172.184632 -241.27428)
			(xy 172.192442 -241.2746) (xy 172.70857 -241.2746) (xy 172.713861 -241.275138) (xy 172.721432 -241.28253)
			(xy 172.722032 -241.287808) (xy 172.722032 -241.782346) (xy 172.722011 -241.7826) (xy 178.766216 -241.7826)
			(xy 178.766216 -241.782092) (xy 178.766216 -241.287808) (xy 178.766534 -241.282471) (xy 178.774087 -241.274928)
			(xy 178.779424 -241.2746) (xy 179.295552 -241.2746) (xy 179.30336 -241.274266) (xy 179.318232 -241.269494)
			(xy 179.324762 -241.265202) (xy 179.345851 -241.250853) (xy 179.391512 -241.228122) (xy 179.440118 -241.212663)
			(xy 179.490521 -241.20484) (xy 179.541527 -241.20484) (xy 179.59193 -241.212663) (xy 179.640536 -241.228122)
			(xy 179.686197 -241.250853) (xy 179.707286 -241.265202) (xy 179.713821 -241.269487) (xy 179.728688 -241.274274)
			(xy 179.736496 -241.2746) (xy 180.252624 -241.2746) (xy 180.257892 -241.27508) (xy 180.265333 -241.282539)
			(xy 180.265832 -241.287808) (xy 180.265832 -241.782346) (xy 186.310016 -241.782346) (xy 186.310016 -241.287808)
			(xy 186.310334 -241.282471) (xy 186.317887 -241.274928) (xy 186.323224 -241.2746) (xy 186.323732 -241.2746)
			(xy 186.839606 -241.2746) (xy 186.847416 -241.274289) (xy 186.862288 -241.269501) (xy 186.868816 -241.265202)
			(xy 186.889905 -241.250853) (xy 186.935566 -241.228122) (xy 186.984172 -241.212663) (xy 187.034575 -241.20484)
			(xy 187.085581 -241.20484) (xy 187.135984 -241.212663) (xy 187.18459 -241.228122) (xy 187.230251 -241.250853)
			(xy 187.25134 -241.265202) (xy 187.257863 -241.269508) (xy 187.27274 -241.274282) (xy 187.28055 -241.2746)
			(xy 187.796678 -241.2746) (xy 187.80197 -241.275133) (xy 187.80954 -241.282528) (xy 187.81014 -241.287808)
			(xy 187.81014 -241.782346) (xy 187.810118 -241.7826) (xy 193.854324 -241.7826) (xy 193.854324 -241.782092)
			(xy 193.854324 -241.287808) (xy 193.854635 -241.282469) (xy 193.862192 -241.274926) (xy 193.867532 -241.2746)
			(xy 194.38366 -241.2746) (xy 194.391469 -241.274269) (xy 194.40634 -241.269495) (xy 194.41287 -241.265202)
			(xy 194.433959 -241.250853) (xy 194.47962 -241.228122) (xy 194.528226 -241.212663) (xy 194.578629 -241.20484)
			(xy 194.629635 -241.20484) (xy 194.680038 -241.212663) (xy 194.728644 -241.228122) (xy 194.774305 -241.250853)
			(xy 194.795394 -241.265202) (xy 194.801927 -241.26949) (xy 194.816796 -241.274275) (xy 194.824604 -241.2746)
			(xy 195.340732 -241.2746) (xy 195.346001 -241.275074) (xy 195.353442 -241.282538) (xy 195.35394 -241.287808)
			(xy 195.35394 -241.782346) (xy 195.353916 -241.7826) (xy 201.398124 -241.7826) (xy 201.398124 -241.782092)
			(xy 201.398124 -241.287808) (xy 201.398435 -241.282469) (xy 201.405992 -241.274926) (xy 201.411332 -241.2746)
			(xy 201.92746 -241.2746) (xy 201.935269 -241.274269) (xy 201.95014 -241.269495) (xy 201.95667 -241.265202)
			(xy 201.977759 -241.250853) (xy 202.02342 -241.228122) (xy 202.072026 -241.212663) (xy 202.122429 -241.20484)
			(xy 202.173435 -241.20484) (xy 202.223838 -241.212663) (xy 202.272444 -241.228122) (xy 202.318105 -241.250853)
			(xy 202.339194 -241.265202) (xy 202.345727 -241.26949) (xy 202.360596 -241.274275) (xy 202.368404 -241.2746)
			(xy 202.884532 -241.2746) (xy 202.889801 -241.275074) (xy 202.897242 -241.282538) (xy 202.89774 -241.287808)
			(xy 202.89774 -241.782092) (xy 264.798048 -241.782092) (xy 264.798048 -241.287554) (xy 264.798521 -241.282182)
			(xy 264.806136 -241.274599) (xy 264.81151 -241.274092) (xy 265.327638 -241.274092) (xy 265.335446 -241.273753)
			(xy 265.350317 -241.268984) (xy 265.356848 -241.264694) (xy 265.377937 -241.250345) (xy 265.423598 -241.227614)
			(xy 265.472204 -241.212155) (xy 265.522607 -241.204332) (xy 265.573613 -241.204332) (xy 265.624016 -241.212155)
			(xy 265.672622 -241.227614) (xy 265.718283 -241.250345) (xy 265.739372 -241.264694) (xy 265.745911 -241.268973)
			(xy 265.760775 -241.273764) (xy 265.768582 -241.274092) (xy 266.28471 -241.274092) (xy 266.290064 -241.274639)
			(xy 266.297647 -241.282201) (xy 266.298172 -241.287554) (xy 266.298172 -241.782092) (xy 272.342356 -241.782092)
			(xy 272.342356 -241.287554) (xy 272.342861 -241.282253) (xy 272.350274 -241.274677) (xy 272.355564 -241.274092)
			(xy 272.871692 -241.274092) (xy 272.879502 -241.273776) (xy 272.894373 -241.268992) (xy 272.900902 -241.264694)
			(xy 272.921991 -241.250345) (xy 272.967652 -241.227614) (xy 273.016258 -241.212155) (xy 273.066661 -241.204332)
			(xy 273.117667 -241.204332) (xy 273.16807 -241.212155) (xy 273.216676 -241.227614) (xy 273.262337 -241.250345)
			(xy 273.283426 -241.264694) (xy 273.289953 -241.268993) (xy 273.304826 -241.273772) (xy 273.312636 -241.274092)
			(xy 273.828764 -241.274092) (xy 273.834092 -241.274451) (xy 273.841635 -241.281973) (xy 273.841972 -241.2873)
			(xy 273.841972 -241.287808) (xy 273.841972 -241.782092) (xy 279.886156 -241.782092) (xy 279.886156 -241.287554)
			(xy 279.886661 -241.282253) (xy 279.894074 -241.274677) (xy 279.899364 -241.274092) (xy 280.415492 -241.274092)
			(xy 280.423302 -241.273776) (xy 280.438173 -241.268992) (xy 280.444702 -241.264694) (xy 280.465791 -241.250345)
			(xy 280.511452 -241.227614) (xy 280.560058 -241.212155) (xy 280.610461 -241.204332) (xy 280.661467 -241.204332)
			(xy 280.71187 -241.212155) (xy 280.760476 -241.227614) (xy 280.806137 -241.250345) (xy 280.827226 -241.264694)
			(xy 280.833753 -241.268993) (xy 280.848626 -241.273772) (xy 280.856436 -241.274092) (xy 281.372564 -241.274092)
			(xy 281.377892 -241.274451) (xy 281.385435 -241.281973) (xy 281.385772 -241.2873) (xy 281.385772 -241.287808)
			(xy 281.385772 -241.782092) (xy 287.429956 -241.782092) (xy 287.429956 -241.287554) (xy 287.430422 -241.28218)
			(xy 287.438042 -241.274596) (xy 287.443418 -241.274092) (xy 287.959546 -241.274092) (xy 287.967354 -241.273757)
			(xy 287.982226 -241.268986) (xy 287.988756 -241.264694) (xy 288.009845 -241.250345) (xy 288.055506 -241.227614)
			(xy 288.104112 -241.212155) (xy 288.154515 -241.204332) (xy 288.205521 -241.204332) (xy 288.255924 -241.212155)
			(xy 288.30453 -241.227614) (xy 288.350191 -241.250345) (xy 288.37128 -241.264694) (xy 288.377817 -241.268976)
			(xy 288.392683 -241.273765) (xy 288.40049 -241.274092) (xy 288.916618 -241.274092) (xy 288.921973 -241.274634)
			(xy 288.929555 -241.2822) (xy 288.93008 -241.287554) (xy 288.93008 -241.782092) (xy 294.974264 -241.782092)
			(xy 294.974264 -241.287554) (xy 294.974762 -241.282251) (xy 294.98218 -241.274675) (xy 294.987472 -241.274092)
			(xy 295.5036 -241.274092) (xy 295.51141 -241.27378) (xy 295.526282 -241.268993) (xy 295.53281 -241.264694)
			(xy 295.553899 -241.250345) (xy 295.59956 -241.227614) (xy 295.648166 -241.212155) (xy 295.698569 -241.204332)
			(xy 295.749575 -241.204332) (xy 295.799978 -241.212155) (xy 295.848584 -241.227614) (xy 295.894245 -241.250345)
			(xy 295.915334 -241.264694) (xy 295.921859 -241.268997) (xy 295.936734 -241.273773) (xy 295.944544 -241.274092)
			(xy 296.460672 -241.274092) (xy 296.466001 -241.274445) (xy 296.473543 -241.281972) (xy 296.47388 -241.2873)
			(xy 296.47388 -241.287808) (xy 296.47388 -241.782092) (xy 302.518064 -241.782092) (xy 302.518064 -241.287554)
			(xy 302.518523 -241.282178) (xy 302.526148 -241.274594) (xy 302.531526 -241.274092) (xy 304.004726 -241.274092)
			(xy 304.010082 -241.274629) (xy 304.017663 -241.282199) (xy 304.018188 -241.287554) (xy 304.018188 -241.782092)
			(xy 411.618176 -241.782092) (xy 411.618176 -241.287554) (xy 411.618663 -241.282248) (xy 411.626089 -241.274672)
			(xy 411.631384 -241.274092) (xy 413.104584 -241.274092) (xy 413.109914 -241.274438) (xy 413.117456 -241.28197)
			(xy 413.117792 -241.2873) (xy 413.117792 -241.287808) (xy 413.117792 -241.782092) (xy 419.161976 -241.782092)
			(xy 419.161976 -241.287554) (xy 419.162424 -241.282175) (xy 419.170056 -241.27459) (xy 419.175438 -241.274092)
			(xy 419.691566 -241.274092) (xy 419.699375 -241.273765) (xy 419.714246 -241.268988) (xy 419.720776 -241.264694)
			(xy 419.741865 -241.250345) (xy 419.787526 -241.227614) (xy 419.836132 -241.212155) (xy 419.886535 -241.204332)
			(xy 419.937541 -241.204332) (xy 419.987944 -241.212155) (xy 420.03655 -241.227614) (xy 420.082211 -241.250345)
			(xy 420.1033 -241.264694) (xy 420.109833 -241.268984) (xy 420.124702 -241.273768) (xy 420.13251 -241.274092)
			(xy 420.648638 -241.274092) (xy 420.653995 -241.274621) (xy 420.661576 -241.282197) (xy 420.6621 -241.287554)
			(xy 420.6621 -241.782092) (xy 426.706284 -241.782092) (xy 426.706284 -241.287554) (xy 426.706764 -241.282246)
			(xy 426.714194 -241.274669) (xy 426.719492 -241.274092) (xy 427.23562 -241.274092) (xy 427.243431 -241.273788)
			(xy 427.258302 -241.268995) (xy 427.26483 -241.264694) (xy 427.285919 -241.250345) (xy 427.33158 -241.227614)
			(xy 427.380186 -241.212155) (xy 427.430589 -241.204332) (xy 427.481595 -241.204332) (xy 427.531998 -241.212155)
			(xy 427.580604 -241.227614) (xy 427.626265 -241.250345) (xy 427.647354 -241.264694) (xy 427.653875 -241.269004)
			(xy 427.668753 -241.273776) (xy 427.676564 -241.274092) (xy 428.192692 -241.274092) (xy 428.198023 -241.274432)
			(xy 428.205565 -241.281969) (xy 428.2059 -241.2873) (xy 428.2059 -241.287808) (xy 428.2059 -241.782092)
			(xy 434.250084 -241.782092) (xy 434.250084 -241.287554) (xy 434.250525 -241.282173) (xy 434.258162 -241.274588)
			(xy 434.263546 -241.274092) (xy 434.779674 -241.274092) (xy 434.787483 -241.273769) (xy 434.802355 -241.26899)
			(xy 434.808884 -241.264694) (xy 434.829973 -241.250345) (xy 434.875634 -241.227614) (xy 434.92424 -241.212155)
			(xy 434.974643 -241.204332) (xy 435.025649 -241.204332) (xy 435.076052 -241.212155) (xy 435.124658 -241.227614)
			(xy 435.170319 -241.250345) (xy 435.191408 -241.264694) (xy 435.197939 -241.268987) (xy 435.212809 -241.273769)
			(xy 435.220618 -241.274092) (xy 435.736746 -241.274092) (xy 435.742104 -241.274615) (xy 435.749685 -241.282196)
			(xy 435.750208 -241.287554) (xy 435.750208 -241.782092) (xy 441.794392 -241.782092) (xy 441.794392 -241.287554)
			(xy 441.794954 -241.282267) (xy 441.802328 -241.274696) (xy 441.8076 -241.274092) (xy 442.323728 -241.274092)
			(xy 442.331539 -241.273792) (xy 442.346411 -241.268997) (xy 442.352938 -241.264694) (xy 442.374027 -241.250345)
			(xy 442.419688 -241.227614) (xy 442.468294 -241.212155) (xy 442.518697 -241.204332) (xy 442.569703 -241.204332)
			(xy 442.620106 -241.212155) (xy 442.668712 -241.227614) (xy 442.714373 -241.250345) (xy 442.735462 -241.264694)
			(xy 442.742003 -241.268969) (xy 442.756866 -241.273762) (xy 442.764672 -241.274092) (xy 443.2808 -241.274092)
			(xy 443.286063 -241.274595) (xy 443.293505 -241.282037) (xy 443.294008 -241.2873) (xy 443.294008 -241.287808)
			(xy 443.294008 -241.782092) (xy 449.338192 -241.782092) (xy 449.338192 -241.287554) (xy 449.338754 -241.282267)
			(xy 449.346128 -241.274696) (xy 449.3514 -241.274092) (xy 449.867528 -241.274092) (xy 449.875339 -241.273792)
			(xy 449.890211 -241.268997) (xy 449.896738 -241.264694) (xy 449.917827 -241.250345) (xy 449.963488 -241.227614)
			(xy 450.012094 -241.212155) (xy 450.062497 -241.204332) (xy 450.113503 -241.204332) (xy 450.163906 -241.212155)
			(xy 450.212512 -241.227614) (xy 450.258173 -241.250345) (xy 450.279262 -241.264694) (xy 450.285803 -241.268969)
			(xy 450.300666 -241.273762) (xy 450.308472 -241.274092) (xy 450.8246 -241.274092) (xy 450.829863 -241.274595)
			(xy 450.837305 -241.282037) (xy 450.837808 -241.2873) (xy 450.837808 -241.287808) (xy 450.837808 -241.782092)
			(xy 450.837468 -241.787423) (xy 450.829931 -241.794965) (xy 450.8246 -241.7953) (xy 450.308726 -241.7953)
			(xy 450.30085 -241.795572) (xy 450.285847 -241.800367) (xy 450.279262 -241.804698) (xy 450.258182 -241.819085)
			(xy 450.212538 -241.841916) (xy 450.163933 -241.857475) (xy 450.113517 -241.865395) (xy 450.088 -241.865912)
			(xy 450.062479 -241.865437) (xy 450.012052 -241.857538) (xy 449.96344 -241.841973) (xy 449.917802 -241.819115)
			(xy 449.896738 -241.804698) (xy 449.89014 -241.800395) (xy 449.875145 -241.795601) (xy 449.867274 -241.7953)
			(xy 449.3514 -241.7953) (xy 449.346066 -241.794973) (xy 449.338524 -241.787426) (xy 449.338192 -241.782092)
			(xy 443.294008 -241.782092) (xy 443.293668 -241.787423) (xy 443.286131 -241.794965) (xy 443.2808 -241.7953)
			(xy 442.764926 -241.7953) (xy 442.75705 -241.795572) (xy 442.742047 -241.800367) (xy 442.735462 -241.804698)
			(xy 442.714382 -241.819085) (xy 442.668738 -241.841916) (xy 442.620133 -241.857475) (xy 442.569717 -241.865395)
			(xy 442.5442 -241.865912) (xy 442.518679 -241.865437) (xy 442.468252 -241.857538) (xy 442.41964 -241.841973)
			(xy 442.374002 -241.819115) (xy 442.352938 -241.804698) (xy 442.34634 -241.800395) (xy 442.331345 -241.795601)
			(xy 442.323474 -241.7953) (xy 441.8076 -241.7953) (xy 441.802266 -241.794973) (xy 441.794724 -241.787426)
			(xy 441.794392 -241.782092) (xy 435.750208 -241.782092) (xy 435.749868 -241.787423) (xy 435.742331 -241.794965)
			(xy 435.737 -241.7953) (xy 435.736492 -241.7953) (xy 435.220872 -241.7953) (xy 435.212998 -241.795592)
			(xy 435.197994 -241.800373) (xy 435.191408 -241.804698) (xy 435.170343 -241.819108) (xy 435.124694 -241.841934)
			(xy 435.076084 -241.857487) (xy 435.025664 -241.865399) (xy 435.000146 -241.865912) (xy 434.974626 -241.865414)
			(xy 434.9242 -241.857522) (xy 434.875588 -241.841964) (xy 434.829949 -241.819112) (xy 434.808884 -241.804698)
			(xy 434.802298 -241.800374) (xy 434.787294 -241.795593) (xy 434.77942 -241.7953) (xy 434.263546 -241.7953)
			(xy 434.258256 -241.794751) (xy 434.250685 -241.787368) (xy 434.250084 -241.782092) (xy 428.2059 -241.782092)
			(xy 428.205567 -241.787425) (xy 428.198025 -241.794967) (xy 428.192692 -241.7953) (xy 427.676818 -241.7953)
			(xy 427.668946 -241.795611) (xy 427.653942 -241.800379) (xy 427.647354 -241.804698) (xy 427.626276 -241.819088)
			(xy 427.580632 -241.841919) (xy 427.532026 -241.857477) (xy 427.481609 -241.865395) (xy 427.456092 -241.865912)
			(xy 427.430573 -241.865391) (xy 427.380148 -241.857506) (xy 427.331536 -241.841955) (xy 427.285896 -241.819109)
			(xy 427.26483 -241.804698) (xy 427.258234 -241.800392) (xy 427.243237 -241.7956) (xy 427.235366 -241.7953)
			(xy 426.719492 -241.7953) (xy 426.714226 -241.79481) (xy 426.706784 -241.787358) (xy 426.706284 -241.782092)
			(xy 420.6621 -241.782092) (xy 420.661767 -241.787425) (xy 420.654225 -241.794967) (xy 420.648892 -241.7953)
			(xy 420.648384 -241.7953) (xy 420.132764 -241.7953) (xy 420.12489 -241.795588) (xy 420.109886 -241.800372)
			(xy 420.1033 -241.804698) (xy 420.082209 -241.819069) (xy 420.036569 -241.841903) (xy 419.987968 -241.857467)
			(xy 419.937554 -241.865392) (xy 419.912038 -241.865912) (xy 419.886518 -241.865418) (xy 419.836091 -241.857525)
			(xy 419.78748 -241.841966) (xy 419.741841 -241.819112) (xy 419.720776 -241.804698) (xy 419.714192 -241.800371)
			(xy 419.699186 -241.795592) (xy 419.691312 -241.7953) (xy 419.175438 -241.7953) (xy 419.170148 -241.794756)
			(xy 419.162577 -241.787369) (xy 419.161976 -241.782092) (xy 413.117792 -241.782092) (xy 413.117466 -241.787427)
			(xy 413.109919 -241.79497) (xy 413.104584 -241.7953) (xy 411.631384 -241.7953) (xy 411.626117 -241.794815)
			(xy 411.618675 -241.78736) (xy 411.618176 -241.782092) (xy 304.018188 -241.782092) (xy 304.017866 -241.787428)
			(xy 304.010316 -241.794971) (xy 304.00498 -241.7953) (xy 304.004472 -241.7953) (xy 302.531526 -241.7953)
			(xy 302.526234 -241.794764) (xy 302.518664 -241.787371) (xy 302.518064 -241.782092) (xy 296.47388 -241.782092)
			(xy 296.473565 -241.78743) (xy 296.466011 -241.794973) (xy 296.460672 -241.7953) (xy 295.944798 -241.7953)
			(xy 295.936925 -241.795603) (xy 295.921921 -241.800377) (xy 295.915334 -241.804698) (xy 295.894261 -241.819097)
			(xy 295.848615 -241.841925) (xy 295.800008 -241.857481) (xy 295.749589 -241.865397) (xy 295.724072 -241.865912)
			(xy 295.698553 -241.865401) (xy 295.648127 -241.857513) (xy 295.599515 -241.841959) (xy 295.553876 -241.81911)
			(xy 295.53281 -241.804698) (xy 295.526218 -241.800384) (xy 295.511218 -241.795597) (xy 295.503346 -241.7953)
			(xy 294.987472 -241.7953) (xy 294.982204 -241.794823) (xy 294.974762 -241.787361) (xy 294.974264 -241.782092)
			(xy 288.93008 -241.782092) (xy 288.929765 -241.78743) (xy 288.922211 -241.794973) (xy 288.916872 -241.7953)
			(xy 288.916364 -241.7953) (xy 288.400744 -241.7953) (xy 288.392869 -241.79558) (xy 288.377865 -241.80037)
			(xy 288.37128 -241.804698) (xy 288.350195 -241.819077) (xy 288.304553 -241.84191) (xy 288.255949 -241.857471)
			(xy 288.205534 -241.865394) (xy 288.180018 -241.865912) (xy 288.154498 -241.865428) (xy 288.104071 -241.857532)
			(xy 288.055459 -241.84197) (xy 288.009821 -241.819114) (xy 287.988756 -241.804698) (xy 287.982176 -241.800363)
			(xy 287.967167 -241.795589) (xy 287.959292 -241.7953) (xy 287.443418 -241.7953) (xy 287.438125 -241.79477)
			(xy 287.430555 -241.787372) (xy 287.429956 -241.782092) (xy 281.385772 -241.782092) (xy 281.385464 -241.787432)
			(xy 281.377905 -241.794976) (xy 281.372564 -241.7953) (xy 280.85669 -241.7953) (xy 280.848817 -241.795599)
			(xy 280.833813 -241.800376) (xy 280.827226 -241.804698) (xy 280.806156 -241.819101) (xy 280.760509 -241.841928)
			(xy 280.7119 -241.857483) (xy 280.661481 -241.865398) (xy 280.635964 -241.865912) (xy 280.610445 -241.865405)
			(xy 280.560018 -241.857515) (xy 280.511407 -241.84196) (xy 280.465768 -241.819111) (xy 280.444702 -241.804698)
			(xy 280.438112 -241.800381) (xy 280.423111 -241.795595) (xy 280.415238 -241.7953) (xy 279.899364 -241.7953)
			(xy 279.894095 -241.794828) (xy 279.886654 -241.787363) (xy 279.886156 -241.782092) (xy 273.841972 -241.782092)
			(xy 273.841664 -241.787432) (xy 273.834105 -241.794976) (xy 273.828764 -241.7953) (xy 273.31289 -241.7953)
			(xy 273.305017 -241.795599) (xy 273.290013 -241.800376) (xy 273.283426 -241.804698) (xy 273.262356 -241.819101)
			(xy 273.216709 -241.841928) (xy 273.1681 -241.857483) (xy 273.117681 -241.865398) (xy 273.092164 -241.865912)
			(xy 273.066645 -241.865405) (xy 273.016218 -241.857515) (xy 272.967607 -241.84196) (xy 272.921968 -241.819111)
			(xy 272.900902 -241.804698) (xy 272.894312 -241.800381) (xy 272.879311 -241.795595) (xy 272.871438 -241.7953)
			(xy 272.355564 -241.7953) (xy 272.350295 -241.794828) (xy 272.342854 -241.787363) (xy 272.342356 -241.782092)
			(xy 266.298172 -241.782092) (xy 266.297864 -241.787432) (xy 266.290305 -241.794976) (xy 266.284964 -241.7953)
			(xy 266.284456 -241.7953) (xy 265.768836 -241.7953) (xy 265.760961 -241.795576) (xy 265.745957 -241.800369)
			(xy 265.739372 -241.804698) (xy 265.718289 -241.819081) (xy 265.672646 -241.841913) (xy 265.624042 -241.857473)
			(xy 265.573626 -241.865394) (xy 265.54811 -241.865912) (xy 265.522589 -241.865432) (xy 265.472162 -241.857534)
			(xy 265.423551 -241.841971) (xy 265.377913 -241.819114) (xy 265.356848 -241.804698) (xy 265.35027 -241.80036)
			(xy 265.33526 -241.795587) (xy 265.327384 -241.7953) (xy 264.81151 -241.7953) (xy 264.806216 -241.794775)
			(xy 264.798647 -241.787374) (xy 264.798048 -241.782092) (xy 202.89774 -241.782092) (xy 202.89774 -241.782346)
			(xy 202.897239 -241.787648) (xy 202.889823 -241.795224) (xy 202.884532 -241.795808) (xy 202.368658 -241.795808)
			(xy 202.36085 -241.796145) (xy 202.345978 -241.800915) (xy 202.339448 -241.805206) (xy 202.318335 -241.819569)
			(xy 202.272608 -241.842294) (xy 202.223932 -241.85772) (xy 202.173464 -241.865482) (xy 202.147932 -241.865912)
			(xy 202.122403 -241.865451) (xy 202.07194 -241.857681) (xy 202.023268 -241.842259) (xy 201.977539 -241.81955)
			(xy 201.956416 -241.805206) (xy 201.94988 -241.800923) (xy 201.935013 -241.796135) (xy 201.927206 -241.795808)
			(xy 201.411332 -241.795808) (xy 201.406004 -241.795452) (xy 201.398461 -241.787927) (xy 201.398124 -241.7826)
			(xy 195.353916 -241.7826) (xy 195.353439 -241.787648) (xy 195.346023 -241.795224) (xy 195.340732 -241.795808)
			(xy 194.824858 -241.795808) (xy 194.81705 -241.796145) (xy 194.802178 -241.800915) (xy 194.795648 -241.805206)
			(xy 194.774535 -241.819569) (xy 194.728808 -241.842294) (xy 194.680132 -241.85772) (xy 194.629664 -241.865482)
			(xy 194.604132 -241.865912) (xy 194.578603 -241.865451) (xy 194.52814 -241.857681) (xy 194.479468 -241.842259)
			(xy 194.433739 -241.81955) (xy 194.412616 -241.805206) (xy 194.40608 -241.800923) (xy 194.391213 -241.796135)
			(xy 194.383406 -241.795808) (xy 193.867532 -241.795808) (xy 193.862204 -241.795452) (xy 193.854661 -241.787927)
			(xy 193.854324 -241.7826) (xy 187.810118 -241.7826) (xy 187.809678 -241.787721) (xy 187.802055 -241.795305)
			(xy 187.796678 -241.795808) (xy 187.280804 -241.795808) (xy 187.272994 -241.796122) (xy 187.258122 -241.800908)
			(xy 187.251594 -241.805206) (xy 187.230468 -241.819549) (xy 187.184746 -241.842278) (xy 187.136074 -241.85771)
			(xy 187.085609 -241.865478) (xy 187.060078 -241.865912) (xy 187.034548 -241.865478) (xy 186.984084 -241.8577)
			(xy 186.935412 -241.84227) (xy 186.889684 -241.819553) (xy 186.868562 -241.805206) (xy 186.862038 -241.800902)
			(xy 186.847162 -241.796127) (xy 186.839352 -241.795808) (xy 186.323478 -241.795808) (xy 186.318123 -241.795269)
			(xy 186.310541 -241.787701) (xy 186.310016 -241.782346) (xy 180.265832 -241.782346) (xy 180.265338 -241.78765)
			(xy 180.257917 -241.795226) (xy 180.252624 -241.795808) (xy 179.73675 -241.795808) (xy 179.728942 -241.796141)
			(xy 179.71407 -241.800914) (xy 179.70754 -241.805206) (xy 179.686429 -241.819572) (xy 179.640702 -241.842296)
			(xy 179.592025 -241.857722) (xy 179.541556 -241.865483) (xy 179.516024 -241.865912) (xy 179.490495 -241.865455)
			(xy 179.440032 -241.857684) (xy 179.39136 -241.84226) (xy 179.345631 -241.81955) (xy 179.324508 -241.805206)
			(xy 179.317974 -241.80092) (xy 179.303106 -241.796133) (xy 179.295298 -241.795808) (xy 178.779424 -241.795808)
			(xy 178.774095 -241.795457) (xy 178.766553 -241.787928) (xy 178.766216 -241.7826) (xy 172.722011 -241.7826)
			(xy 172.721577 -241.787723) (xy 172.713949 -241.795307) (xy 172.70857 -241.795808) (xy 172.192696 -241.795808)
			(xy 172.184886 -241.796119) (xy 172.170014 -241.800907) (xy 172.163486 -241.805206) (xy 172.142362 -241.819552)
			(xy 172.09664 -241.842281) (xy 172.047967 -241.857712) (xy 171.997501 -241.865479) (xy 171.97197 -241.865912)
			(xy 171.94644 -241.865482) (xy 171.895976 -241.857703) (xy 171.847304 -241.842271) (xy 171.801576 -241.819554)
			(xy 171.780454 -241.805206) (xy 171.773932 -241.800899) (xy 171.759055 -241.796126) (xy 171.751244 -241.795808)
			(xy 171.23537 -241.795808) (xy 171.230013 -241.795274) (xy 171.222432 -241.787702) (xy 171.221908 -241.782346)
			(xy 165.177724 -241.782346) (xy 165.177237 -241.787652) (xy 165.169811 -241.795228) (xy 165.164516 -241.795808)
			(xy 163.691316 -241.795808) (xy 163.685986 -241.795462) (xy 163.678444 -241.78793) (xy 163.678108 -241.7826)
			(xy 56.078099 -241.7826) (xy 56.077676 -241.787726) (xy 56.070041 -241.795311) (xy 56.064658 -241.795808)
			(xy 54.591458 -241.795808) (xy 54.5861 -241.795282) (xy 54.578519 -241.787704) (xy 54.577996 -241.782346)
			(xy 48.533812 -241.782346) (xy 48.533335 -241.787655) (xy 48.525903 -241.795232) (xy 48.520604 -241.795808)
			(xy 48.00473 -241.795808) (xy 47.996921 -241.796133) (xy 47.982049 -241.800911) (xy 47.97552 -241.805206)
			(xy 47.954387 -241.819537) (xy 47.908668 -241.842269) (xy 47.859998 -241.857705) (xy 47.809534 -241.865476)
			(xy 47.784004 -241.865912) (xy 47.758474 -241.865465) (xy 47.708011 -241.857691) (xy 47.659339 -241.842264)
			(xy 47.613611 -241.819551) (xy 47.592488 -241.805206) (xy 47.585958 -241.800912) (xy 47.571087 -241.796131)
			(xy 47.563278 -241.795808) (xy 47.047404 -241.795808) (xy 47.042072 -241.79547) (xy 47.034531 -241.787932)
			(xy 47.034196 -241.7826) (xy 40.989987 -241.7826) (xy 40.989485 -241.787703) (xy 40.981907 -241.795284)
			(xy 40.97655 -241.795808) (xy 40.460676 -241.795808) (xy 40.452865 -241.79611) (xy 40.437994 -241.800904)
			(xy 40.431466 -241.805206) (xy 40.410348 -241.819561) (xy 40.364623 -241.842288) (xy 40.315949 -241.857716)
			(xy 40.265481 -241.865481) (xy 40.23995 -241.865912) (xy 40.214421 -241.865442) (xy 40.163959 -241.857675)
			(xy 40.115287 -241.842255) (xy 40.069558 -241.819548) (xy 40.048434 -241.805206) (xy 40.041894 -241.80093)
			(xy 40.02703 -241.796137) (xy 40.019224 -241.795808) (xy 39.50335 -241.795808) (xy 39.497991 -241.795287)
			(xy 39.490411 -241.787705) (xy 39.489888 -241.782346) (xy 33.445704 -241.782346) (xy 33.445146 -241.787634)
			(xy 33.437769 -241.795205) (xy 33.432496 -241.795808) (xy 32.916622 -241.795808) (xy 32.908813 -241.79613)
			(xy 32.893941 -241.80091) (xy 32.887412 -241.805206) (xy 32.866281 -241.819541) (xy 32.820561 -241.842272)
			(xy 32.771891 -241.857706) (xy 32.721426 -241.865477) (xy 32.695896 -241.865912) (xy 32.670366 -241.865469)
			(xy 32.619903 -241.857694) (xy 32.571231 -241.842266) (xy 32.525503 -241.819552) (xy 32.50438 -241.805206)
			(xy 32.497852 -241.800909) (xy 32.482979 -241.796129) (xy 32.47517 -241.795808) (xy 31.959296 -241.795808)
			(xy 31.954033 -241.795308) (xy 31.94659 -241.787863) (xy 31.946088 -241.7826) (xy 25.901877 -241.7826)
			(xy 25.901346 -241.787634) (xy 25.893969 -241.795205) (xy 25.888696 -241.795808) (xy 25.372822 -241.795808)
			(xy 25.365013 -241.79613) (xy 25.350141 -241.80091) (xy 25.343612 -241.805206) (xy 25.322481 -241.819541)
			(xy 25.276761 -241.842272) (xy 25.228091 -241.857706) (xy 25.177626 -241.865477) (xy 25.152096 -241.865912)
			(xy 25.126566 -241.865469) (xy 25.076103 -241.857694) (xy 25.027431 -241.842266) (xy 24.981703 -241.819552)
			(xy 24.96058 -241.805206) (xy 24.954052 -241.800909) (xy 24.939179 -241.796129) (xy 24.93137 -241.795808)
			(xy 24.415496 -241.795808) (xy 24.410233 -241.795308) (xy 24.40279 -241.787863) (xy 24.402288 -241.7826)
			(xy 18.358079 -241.7826) (xy 18.357584 -241.787705) (xy 18.350002 -241.795286) (xy 18.344642 -241.795808)
			(xy 17.828768 -241.795808) (xy 17.82096 -241.796149) (xy 17.806089 -241.800916) (xy 17.799558 -241.805206)
			(xy 17.778442 -241.819564) (xy 17.732717 -241.84229) (xy 17.684042 -241.857718) (xy 17.633574 -241.865481)
			(xy 17.608042 -241.865912) (xy 17.582513 -241.865446) (xy 17.532051 -241.857678) (xy 17.483378 -241.842257)
			(xy 17.437649 -241.819549) (xy 17.416526 -241.805206) (xy 17.409988 -241.800926) (xy 17.395123 -241.796136)
			(xy 17.387316 -241.795808) (xy 16.871442 -241.795808) (xy 16.866094 -241.795226) (xy 16.858509 -241.78769)
			(xy 16.85798 -241.782346) (xy 2.509012 -241.782346) (xy 2.509012 -242.632484) (xy 20.958048 -242.632484)
			(xy 20.958048 -242.137946) (xy 20.958411 -242.132515) (xy 20.96608 -242.124825) (xy 20.97151 -242.124484)
			(xy 21.487638 -242.124484) (xy 21.495446 -242.124146) (xy 21.510318 -242.119377) (xy 21.516848 -242.115086)
			(xy 21.537937 -242.100737) (xy 21.583598 -242.078006) (xy 21.632204 -242.062547) (xy 21.682607 -242.054724)
			(xy 21.733613 -242.054724) (xy 21.784016 -242.062547) (xy 21.832622 -242.078006) (xy 21.878283 -242.100737)
			(xy 21.899372 -242.115086) (xy 21.905911 -242.119364) (xy 21.920775 -242.124156) (xy 21.928582 -242.124484)
			(xy 22.44471 -242.124484) (xy 22.450157 -242.124777) (xy 22.457846 -242.132497) (xy 22.458172 -242.137946)
			(xy 22.458172 -242.632484) (xy 28.502356 -242.632484) (xy 28.502356 -242.137946) (xy 28.502855 -242.132644)
			(xy 28.510273 -242.125069) (xy 28.515564 -242.124484) (xy 29.031692 -242.124484) (xy 29.039502 -242.12417)
			(xy 29.054374 -242.119384) (xy 29.060902 -242.115086) (xy 29.081991 -242.100737) (xy 29.127652 -242.078006)
			(xy 29.176258 -242.062547) (xy 29.226661 -242.054724) (xy 29.277667 -242.054724) (xy 29.32807 -242.062547)
			(xy 29.376676 -242.078006) (xy 29.422337 -242.100737) (xy 29.443426 -242.115086) (xy 29.449953 -242.119385)
			(xy 29.464827 -242.124163) (xy 29.472636 -242.124484) (xy 29.988764 -242.124484) (xy 29.99409 -242.12485)
			(xy 30.001632 -242.132368) (xy 30.001972 -242.137692) (xy 30.001972 -242.1382) (xy 30.001972 -242.632484)
			(xy 36.046156 -242.632484) (xy 36.046156 -242.137946) (xy 36.046655 -242.132644) (xy 36.054073 -242.125069)
			(xy 36.059364 -242.124484) (xy 36.575492 -242.124484) (xy 36.583302 -242.12417) (xy 36.598174 -242.119384)
			(xy 36.604702 -242.115086) (xy 36.625791 -242.100737) (xy 36.671452 -242.078006) (xy 36.720058 -242.062547)
			(xy 36.770461 -242.054724) (xy 36.821467 -242.054724) (xy 36.87187 -242.062547) (xy 36.920476 -242.078006)
			(xy 36.966137 -242.100737) (xy 36.987226 -242.115086) (xy 36.993753 -242.119385) (xy 37.008627 -242.124163)
			(xy 37.016436 -242.124484) (xy 37.532564 -242.124484) (xy 37.53789 -242.12485) (xy 37.545432 -242.132368)
			(xy 37.545772 -242.137692) (xy 37.545772 -242.1382) (xy 37.545772 -242.632484) (xy 43.589956 -242.632484)
			(xy 43.589956 -242.137946) (xy 43.590312 -242.132513) (xy 43.597986 -242.124823) (xy 43.603418 -242.124484)
			(xy 44.119546 -242.124484) (xy 44.127354 -242.12415) (xy 44.142226 -242.119378) (xy 44.148756 -242.115086)
			(xy 44.169845 -242.100737) (xy 44.215506 -242.078006) (xy 44.264112 -242.062547) (xy 44.314515 -242.054724)
			(xy 44.365521 -242.054724) (xy 44.415924 -242.062547) (xy 44.46453 -242.078006) (xy 44.510191 -242.100737)
			(xy 44.53128 -242.115086) (xy 44.537817 -242.119367) (xy 44.552683 -242.124157) (xy 44.56049 -242.124484)
			(xy 45.076618 -242.124484) (xy 45.082067 -242.124772) (xy 45.089754 -242.132496) (xy 45.09008 -242.137946)
			(xy 45.09008 -242.632484) (xy 51.134264 -242.632484) (xy 51.134264 -242.137946) (xy 51.134757 -242.132642)
			(xy 51.142179 -242.125067) (xy 51.147472 -242.124484) (xy 51.6636 -242.124484) (xy 51.67141 -242.124173)
			(xy 51.686282 -242.119385) (xy 51.69281 -242.115086) (xy 51.713899 -242.100737) (xy 51.75956 -242.078006)
			(xy 51.808166 -242.062547) (xy 51.858569 -242.054724) (xy 51.909575 -242.054724) (xy 51.959978 -242.062547)
			(xy 52.008584 -242.078006) (xy 52.054245 -242.100737) (xy 52.075334 -242.115086) (xy 52.081859 -242.119388)
			(xy 52.096734 -242.124165) (xy 52.104544 -242.124484) (xy 52.620672 -242.124484) (xy 52.625999 -242.124845)
			(xy 52.633541 -242.132366) (xy 52.63388 -242.137692) (xy 52.63388 -242.1382) (xy 52.63388 -242.632484)
			(xy 58.678064 -242.632484) (xy 58.678064 -242.137946) (xy 58.678413 -242.132511) (xy 58.686091 -242.124821)
			(xy 58.691526 -242.124484) (xy 60.164726 -242.124484) (xy 60.170176 -242.124766) (xy 60.177863 -242.132495)
			(xy 60.178188 -242.137946) (xy 60.178188 -242.632484) (xy 167.778176 -242.632484) (xy 167.778176 -242.137946)
			(xy 167.778658 -242.132639) (xy 167.786087 -242.125063) (xy 167.791384 -242.124484) (xy 169.264584 -242.124484)
			(xy 169.269912 -242.124837) (xy 169.277454 -242.132364) (xy 169.277792 -242.137692) (xy 169.277792 -242.1382)
			(xy 169.277792 -242.632484) (xy 175.321976 -242.632484) (xy 175.321976 -242.137946) (xy 175.322314 -242.132508)
			(xy 175.33 -242.124817) (xy 175.335438 -242.124484) (xy 175.851566 -242.124484) (xy 175.859375 -242.124159)
			(xy 175.874247 -242.119381) (xy 175.880776 -242.115086) (xy 175.901865 -242.100737) (xy 175.947526 -242.078006)
			(xy 175.996132 -242.062547) (xy 176.046535 -242.054724) (xy 176.097541 -242.054724) (xy 176.147944 -242.062547)
			(xy 176.19655 -242.078006) (xy 176.242211 -242.100737) (xy 176.2633 -242.115086) (xy 176.269833 -242.119375)
			(xy 176.284702 -242.12416) (xy 176.29251 -242.124484) (xy 176.808638 -242.124484) (xy 176.814089 -242.124758)
			(xy 176.821776 -242.132493) (xy 176.8221 -242.137946) (xy 176.8221 -242.632484) (xy 182.866284 -242.632484)
			(xy 182.866284 -242.137946) (xy 182.866759 -242.132637) (xy 182.874193 -242.125061) (xy 182.879492 -242.124484)
			(xy 183.39562 -242.124484) (xy 183.403431 -242.124182) (xy 183.418303 -242.119388) (xy 183.42483 -242.115086)
			(xy 183.445919 -242.100737) (xy 183.49158 -242.078006) (xy 183.540186 -242.062547) (xy 183.590589 -242.054724)
			(xy 183.641595 -242.054724) (xy 183.691998 -242.062547) (xy 183.740604 -242.078006) (xy 183.786265 -242.100737)
			(xy 183.807354 -242.115086) (xy 183.813875 -242.119395) (xy 183.828753 -242.124168) (xy 183.836564 -242.124484)
			(xy 184.352692 -242.124484) (xy 184.357952 -242.124999) (xy 184.365395 -242.132433) (xy 184.3659 -242.137692)
			(xy 184.3659 -242.1382) (xy 184.3659 -242.632484) (xy 190.410084 -242.632484) (xy 190.410084 -242.137946)
			(xy 190.410415 -242.132506) (xy 190.418106 -242.124815) (xy 190.423546 -242.124484) (xy 190.939674 -242.124484)
			(xy 190.947483 -242.124162) (xy 190.962355 -242.119382) (xy 190.968884 -242.115086) (xy 190.989973 -242.100737)
			(xy 191.035634 -242.078006) (xy 191.08424 -242.062547) (xy 191.134643 -242.054724) (xy 191.185649 -242.054724)
			(xy 191.236052 -242.062547) (xy 191.284658 -242.078006) (xy 191.330319 -242.100737) (xy 191.351408 -242.115086)
			(xy 191.357939 -242.119378) (xy 191.372809 -242.124161) (xy 191.380618 -242.124484) (xy 191.896746 -242.124484)
			(xy 191.902127 -242.124925) (xy 191.909712 -242.132562) (xy 191.910208 -242.137946) (xy 191.910208 -242.632484)
			(xy 197.954392 -242.632484) (xy 197.954392 -242.137946) (xy 197.954948 -242.132658) (xy 197.962326 -242.125087)
			(xy 197.9676 -242.124484) (xy 198.483728 -242.124484) (xy 198.491539 -242.124185) (xy 198.506411 -242.119389)
			(xy 198.512938 -242.115086) (xy 198.534027 -242.100737) (xy 198.579688 -242.078006) (xy 198.628294 -242.062547)
			(xy 198.678697 -242.054724) (xy 198.729703 -242.054724) (xy 198.780106 -242.062547) (xy 198.828712 -242.078006)
			(xy 198.874373 -242.100737) (xy 198.895462 -242.115086) (xy 198.902003 -242.11936) (xy 198.916866 -242.124154)
			(xy 198.924672 -242.124484) (xy 199.4408 -242.124484) (xy 199.446061 -242.124994) (xy 199.453503 -242.132432)
			(xy 199.454008 -242.137692) (xy 199.454008 -242.1382) (xy 199.454008 -242.632484) (xy 205.498192 -242.632484)
			(xy 205.498192 -242.137946) (xy 205.498748 -242.132658) (xy 205.506126 -242.125087) (xy 205.5114 -242.124484)
			(xy 206.027528 -242.124484) (xy 206.035339 -242.124185) (xy 206.050211 -242.119389) (xy 206.056738 -242.115086)
			(xy 206.077827 -242.100737) (xy 206.123488 -242.078006) (xy 206.172094 -242.062547) (xy 206.222497 -242.054724)
			(xy 206.273503 -242.054724) (xy 206.323906 -242.062547) (xy 206.372512 -242.078006) (xy 206.418173 -242.100737)
			(xy 206.439262 -242.115086) (xy 206.445803 -242.11936) (xy 206.460666 -242.124154) (xy 206.468472 -242.124484)
			(xy 206.9846 -242.124484) (xy 206.989861 -242.124994) (xy 206.997303 -242.132432) (xy 206.997808 -242.137692)
			(xy 206.997808 -242.1382) (xy 206.997808 -242.63223) (xy 268.898116 -242.63223) (xy 268.898116 -242.137692)
			(xy 268.898424 -242.132353) (xy 268.905984 -242.124811) (xy 268.911324 -242.124484) (xy 268.911832 -242.124484)
			(xy 269.427706 -242.124484) (xy 269.435517 -242.124176) (xy 269.450388 -242.119386) (xy 269.456916 -242.115086)
			(xy 269.478005 -242.100737) (xy 269.523666 -242.078006) (xy 269.572272 -242.062547) (xy 269.622675 -242.054724)
			(xy 269.673681 -242.054724) (xy 269.724084 -242.062547) (xy 269.77269 -242.078006) (xy 269.818351 -242.100737)
			(xy 269.83944 -242.115086) (xy 269.845964 -242.11939) (xy 269.86084 -242.124165) (xy 269.86865 -242.124484)
			(xy 270.384778 -242.124484) (xy 270.39009 -242.124943) (xy 270.397665 -242.132389) (xy 270.39824 -242.137692)
			(xy 270.39824 -242.63223) (xy 270.398218 -242.632484) (xy 276.442424 -242.632484) (xy 276.442424 -242.631976)
			(xy 276.442424 -242.137692) (xy 276.442724 -242.132351) (xy 276.45029 -242.124808) (xy 276.455632 -242.124484)
			(xy 276.97176 -242.124484) (xy 276.979569 -242.124156) (xy 276.99444 -242.11938) (xy 277.00097 -242.115086)
			(xy 277.022059 -242.100737) (xy 277.06772 -242.078006) (xy 277.116326 -242.062547) (xy 277.166729 -242.054724)
			(xy 277.217735 -242.054724) (xy 277.268138 -242.062547) (xy 277.316744 -242.078006) (xy 277.362405 -242.100737)
			(xy 277.383494 -242.115086) (xy 277.390028 -242.119372) (xy 277.404896 -242.124159) (xy 277.412704 -242.124484)
			(xy 277.928832 -242.124484) (xy 277.934097 -242.124973) (xy 277.941537 -242.132426) (xy 277.94204 -242.137692)
			(xy 277.94204 -242.63223) (xy 277.942019 -242.632484) (xy 283.986224 -242.632484) (xy 283.986224 -242.631976)
			(xy 283.986224 -242.137692) (xy 283.986524 -242.132351) (xy 283.99409 -242.124808) (xy 283.999432 -242.124484)
			(xy 284.51556 -242.124484) (xy 284.523369 -242.124156) (xy 284.53824 -242.11938) (xy 284.54477 -242.115086)
			(xy 284.565859 -242.100737) (xy 284.61152 -242.078006) (xy 284.660126 -242.062547) (xy 284.710529 -242.054724)
			(xy 284.761535 -242.054724) (xy 284.811938 -242.062547) (xy 284.860544 -242.078006) (xy 284.906205 -242.100737)
			(xy 284.927294 -242.115086) (xy 284.933828 -242.119372) (xy 284.948696 -242.124159) (xy 284.956504 -242.124484)
			(xy 285.472632 -242.124484) (xy 285.477897 -242.124973) (xy 285.485337 -242.132426) (xy 285.48584 -242.137692)
			(xy 285.48584 -242.63223) (xy 291.530024 -242.63223) (xy 291.530024 -242.137692) (xy 291.530324 -242.132351)
			(xy 291.53789 -242.124808) (xy 291.543232 -242.124484) (xy 291.54374 -242.124484) (xy 292.059614 -242.124484)
			(xy 292.067425 -242.124179) (xy 292.082296 -242.119387) (xy 292.088824 -242.115086) (xy 292.109913 -242.100737)
			(xy 292.155574 -242.078006) (xy 292.20418 -242.062547) (xy 292.254583 -242.054724) (xy 292.305589 -242.054724)
			(xy 292.355992 -242.062547) (xy 292.404598 -242.078006) (xy 292.450259 -242.100737) (xy 292.471348 -242.115086)
			(xy 292.47787 -242.119393) (xy 292.492747 -242.124167) (xy 292.500558 -242.124484) (xy 293.016686 -242.124484)
			(xy 293.021999 -242.124938) (xy 293.029573 -242.132388) (xy 293.030148 -242.137692) (xy 293.030148 -242.63223)
			(xy 293.030125 -242.632484) (xy 299.074332 -242.632484) (xy 299.074332 -242.631976) (xy 299.074332 -242.137692)
			(xy 299.074625 -242.132349) (xy 299.082196 -242.124806) (xy 299.08754 -242.124484) (xy 299.603668 -242.124484)
			(xy 299.611477 -242.12416) (xy 299.626349 -242.119381) (xy 299.632878 -242.115086) (xy 299.653967 -242.100737)
			(xy 299.699628 -242.078006) (xy 299.748234 -242.062547) (xy 299.798637 -242.054724) (xy 299.849643 -242.054724)
			(xy 299.900046 -242.062547) (xy 299.948652 -242.078006) (xy 299.994313 -242.100737) (xy 300.015402 -242.115086)
			(xy 300.021935 -242.119376) (xy 300.036804 -242.12416) (xy 300.044612 -242.124484) (xy 300.56074 -242.124484)
			(xy 300.566006 -242.124967) (xy 300.573446 -242.132425) (xy 300.573948 -242.137692) (xy 300.573948 -242.63223)
			(xy 306.618132 -242.63223) (xy 306.618132 -242.137692) (xy 306.618425 -242.132349) (xy 306.625996 -242.124806)
			(xy 306.63134 -242.124484) (xy 306.631848 -242.124484) (xy 308.104794 -242.124484) (xy 308.110108 -242.124932)
			(xy 308.117682 -242.132387) (xy 308.118256 -242.137692) (xy 308.118256 -242.63223) (xy 308.118233 -242.632484)
			(xy 415.718244 -242.632484) (xy 415.718244 -242.631976) (xy 415.718244 -242.137692) (xy 415.718784 -242.13244)
			(xy 415.726201 -242.125) (xy 415.731452 -242.124484) (xy 417.204652 -242.124484) (xy 417.209976 -242.124859)
			(xy 417.217519 -242.13237) (xy 417.21786 -242.137692) (xy 417.21786 -242.63223) (xy 423.262044 -242.63223)
			(xy 423.262044 -242.137692) (xy 423.262584 -242.13244) (xy 423.270001 -242.125) (xy 423.275252 -242.124484)
			(xy 423.27576 -242.124484) (xy 423.791634 -242.124484) (xy 423.799442 -242.124145) (xy 423.814313 -242.119376)
			(xy 423.820844 -242.115086) (xy 423.841933 -242.100737) (xy 423.887594 -242.078006) (xy 423.9362 -242.062547)
			(xy 423.986603 -242.054724) (xy 424.037609 -242.054724) (xy 424.088012 -242.062547) (xy 424.136618 -242.078006)
			(xy 424.182279 -242.100737) (xy 424.203368 -242.115086) (xy 424.209908 -242.119363) (xy 424.224771 -242.124155)
			(xy 424.232578 -242.124484) (xy 424.748706 -242.124484) (xy 424.754021 -242.124924) (xy 424.761595 -242.132385)
			(xy 424.762168 -242.137692) (xy 424.762168 -242.63223) (xy 424.762144 -242.632484) (xy 430.806352 -242.632484)
			(xy 430.806352 -242.631976) (xy 430.806352 -242.137692) (xy 430.806885 -242.132438) (xy 430.814307 -242.124998)
			(xy 430.81956 -242.124484) (xy 431.335688 -242.124484) (xy 431.343498 -242.124168) (xy 431.358369 -242.119384)
			(xy 431.364898 -242.115086) (xy 431.385987 -242.100737) (xy 431.431648 -242.078006) (xy 431.480254 -242.062547)
			(xy 431.530657 -242.054724) (xy 431.581663 -242.054724) (xy 431.632066 -242.062547) (xy 431.680672 -242.078006)
			(xy 431.726333 -242.100737) (xy 431.747422 -242.115086) (xy 431.75395 -242.119383) (xy 431.768823 -242.124163)
			(xy 431.776632 -242.124484) (xy 432.29276 -242.124484) (xy 432.298085 -242.124853) (xy 432.305628 -242.132368)
			(xy 432.305968 -242.137692) (xy 432.305968 -242.63223) (xy 438.350152 -242.63223) (xy 438.350152 -242.137692)
			(xy 438.350685 -242.132438) (xy 438.358107 -242.124998) (xy 438.36336 -242.124484) (xy 438.363868 -242.124484)
			(xy 438.879742 -242.124484) (xy 438.88755 -242.124148) (xy 438.902422 -242.119378) (xy 438.908952 -242.115086)
			(xy 438.930041 -242.100737) (xy 438.975702 -242.078006) (xy 439.024308 -242.062547) (xy 439.074711 -242.054724)
			(xy 439.125717 -242.054724) (xy 439.17612 -242.062547) (xy 439.224726 -242.078006) (xy 439.270387 -242.100737)
			(xy 439.291476 -242.115086) (xy 439.298014 -242.119366) (xy 439.312879 -242.124156) (xy 439.320686 -242.124484)
			(xy 439.836814 -242.124484) (xy 439.84213 -242.124919) (xy 439.849703 -242.132384) (xy 439.850276 -242.137692)
			(xy 439.850276 -242.63223) (xy 439.850252 -242.632484) (xy 445.89446 -242.632484) (xy 445.89446 -242.631976)
			(xy 445.89446 -242.137692) (xy 445.894986 -242.132436) (xy 445.902413 -242.124996) (xy 445.907668 -242.124484)
			(xy 446.423796 -242.124484) (xy 446.431606 -242.124171) (xy 446.446478 -242.119385) (xy 446.453006 -242.115086)
			(xy 446.474095 -242.100737) (xy 446.519756 -242.078006) (xy 446.568362 -242.062547) (xy 446.618765 -242.054724)
			(xy 446.669771 -242.054724) (xy 446.720174 -242.062547) (xy 446.76878 -242.078006) (xy 446.814441 -242.100737)
			(xy 446.83553 -242.115086) (xy 446.842056 -242.119386) (xy 446.85693 -242.124164) (xy 446.86474 -242.124484)
			(xy 447.380868 -242.124484) (xy 447.386194 -242.124848) (xy 447.393736 -242.132367) (xy 447.394076 -242.137692)
			(xy 447.394076 -242.63223) (xy 447.394053 -242.632484) (xy 453.43826 -242.632484) (xy 453.43826 -242.631976)
			(xy 453.43826 -242.137692) (xy 453.438786 -242.132436) (xy 453.446213 -242.124996) (xy 453.451468 -242.124484)
			(xy 453.967596 -242.124484) (xy 453.975406 -242.124171) (xy 453.990278 -242.119385) (xy 453.996806 -242.115086)
			(xy 454.017895 -242.100737) (xy 454.063556 -242.078006) (xy 454.112162 -242.062547) (xy 454.162565 -242.054724)
			(xy 454.213571 -242.054724) (xy 454.263974 -242.062547) (xy 454.31258 -242.078006) (xy 454.358241 -242.100737)
			(xy 454.37933 -242.115086) (xy 454.385856 -242.119386) (xy 454.40073 -242.124164) (xy 454.40854 -242.124484)
			(xy 454.924668 -242.124484) (xy 454.929994 -242.124848) (xy 454.937536 -242.132367) (xy 454.937876 -242.137692)
			(xy 454.937876 -242.63223) (xy 454.937399 -242.637534) (xy 454.929963 -242.645103) (xy 454.924668 -242.645692)
			(xy 454.408794 -242.645692) (xy 454.400984 -242.646004) (xy 454.386113 -242.650792) (xy 454.379584 -242.65509)
			(xy 454.358467 -242.669447) (xy 454.312741 -242.692171) (xy 454.264067 -242.707598) (xy 454.213599 -242.715363)
			(xy 454.188068 -242.715796) (xy 454.162537 -242.71537) (xy 454.112073 -242.70759) (xy 454.063401 -242.692158)
			(xy 454.017674 -242.669438) (xy 453.996552 -242.65509) (xy 453.990031 -242.650781) (xy 453.975153 -242.646009)
			(xy 453.967342 -242.645692) (xy 453.451468 -242.645692) (xy 453.446198 -242.645225) (xy 453.438756 -242.637756)
			(xy 453.43826 -242.632484) (xy 447.394053 -242.632484) (xy 447.393599 -242.637534) (xy 447.386163 -242.645103)
			(xy 447.380868 -242.645692) (xy 446.864994 -242.645692) (xy 446.857184 -242.646004) (xy 446.842313 -242.650792)
			(xy 446.835784 -242.65509) (xy 446.814667 -242.669447) (xy 446.768941 -242.692171) (xy 446.720267 -242.707598)
			(xy 446.669799 -242.715363) (xy 446.644268 -242.715796) (xy 446.618737 -242.71537) (xy 446.568273 -242.70759)
			(xy 446.519601 -242.692158) (xy 446.473874 -242.669438) (xy 446.452752 -242.65509) (xy 446.446231 -242.650781)
			(xy 446.431353 -242.646009) (xy 446.423542 -242.645692) (xy 445.907668 -242.645692) (xy 445.902398 -242.645225)
			(xy 445.894956 -242.637756) (xy 445.89446 -242.632484) (xy 439.850252 -242.632484) (xy 439.849771 -242.637594)
			(xy 439.842179 -242.645177) (xy 439.836814 -242.645692) (xy 439.32094 -242.645692) (xy 439.313132 -242.646024)
			(xy 439.29826 -242.650798) (xy 439.29173 -242.65509) (xy 439.270628 -242.66947) (xy 439.224897 -242.692189)
			(xy 439.176218 -242.70761) (xy 439.125747 -242.715367) (xy 439.100214 -242.715796) (xy 439.074684 -242.715347)
			(xy 439.024221 -242.707574) (xy 438.975549 -242.692148) (xy 438.929821 -242.669435) (xy 438.908698 -242.65509)
			(xy 438.902167 -242.650798) (xy 438.887297 -242.646016) (xy 438.879488 -242.645692) (xy 438.363614 -242.645692)
			(xy 438.358259 -242.645143) (xy 438.350674 -242.637583) (xy 438.350152 -242.63223) (xy 432.305968 -242.63223)
			(xy 432.305498 -242.637536) (xy 432.298057 -242.645105) (xy 432.29276 -242.645692) (xy 431.776886 -242.645692)
			(xy 431.769076 -242.646001) (xy 431.754204 -242.65079) (xy 431.747676 -242.65509) (xy 431.726562 -242.66945)
			(xy 431.680835 -242.692173) (xy 431.632159 -242.7076) (xy 431.581692 -242.715364) (xy 431.55616 -242.715796)
			(xy 431.530629 -242.715374) (xy 431.480165 -242.707593) (xy 431.431493 -242.692159) (xy 431.385766 -242.669439)
			(xy 431.364644 -242.65509) (xy 431.358125 -242.650778) (xy 431.343245 -242.646008) (xy 431.335434 -242.645692)
			(xy 430.81956 -242.645692) (xy 430.814288 -242.64523) (xy 430.806847 -242.637758) (xy 430.806352 -242.632484)
			(xy 424.762144 -242.632484) (xy 424.76167 -242.637596) (xy 424.754073 -242.64518) (xy 424.748706 -242.645692)
			(xy 424.232832 -242.645692) (xy 424.225023 -242.646021) (xy 424.210152 -242.650796) (xy 424.203622 -242.65509)
			(xy 424.182495 -242.66943) (xy 424.136773 -242.692158) (xy 424.088101 -242.70759) (xy 424.037636 -242.715361)
			(xy 424.012106 -242.715796) (xy 423.986576 -242.715351) (xy 423.936113 -242.707577) (xy 423.887441 -242.69215)
			(xy 423.841713 -242.669436) (xy 423.82059 -242.65509) (xy 423.814061 -242.650795) (xy 423.799189 -242.646015)
			(xy 423.79138 -242.645692) (xy 423.275506 -242.645692) (xy 423.27015 -242.645149) (xy 423.262566 -242.637585)
			(xy 423.262044 -242.63223) (xy 417.21786 -242.63223) (xy 417.217397 -242.637538) (xy 417.209951 -242.645107)
			(xy 417.204652 -242.645692) (xy 415.731452 -242.645692) (xy 415.72618 -242.645235) (xy 415.718739 -242.637759)
			(xy 415.718244 -242.632484) (xy 308.118233 -242.632484) (xy 308.117769 -242.637599) (xy 308.110164 -242.645183)
			(xy 308.104794 -242.645692) (xy 306.631594 -242.645692) (xy 306.626237 -242.645157) (xy 306.618653 -242.637587)
			(xy 306.618132 -242.63223) (xy 300.573948 -242.63223) (xy 300.573495 -242.637541) (xy 300.566042 -242.645111)
			(xy 300.56074 -242.645692) (xy 300.044866 -242.645692) (xy 300.037059 -242.646035) (xy 300.022187 -242.650801)
			(xy 300.015656 -242.65509) (xy 299.994547 -242.669459) (xy 299.948818 -242.69218) (xy 299.900141 -242.707604)
			(xy 299.849672 -242.715366) (xy 299.82414 -242.715796) (xy 299.798611 -242.715334) (xy 299.748148 -242.707565)
			(xy 299.699476 -242.692143) (xy 299.653747 -242.669434) (xy 299.632624 -242.65509) (xy 299.626087 -242.650808)
			(xy 299.611221 -242.64602) (xy 299.603414 -242.645692) (xy 299.08754 -242.645692) (xy 299.082209 -242.645345)
			(xy 299.074665 -242.637814) (xy 299.074332 -242.632484) (xy 293.030125 -242.632484) (xy 293.029668 -242.637601)
			(xy 293.022059 -242.645186) (xy 293.016686 -242.645692) (xy 292.500812 -242.645692) (xy 292.493003 -242.646012)
			(xy 292.478131 -242.650794) (xy 292.471602 -242.65509) (xy 292.45048 -242.669439) (xy 292.404756 -242.692165)
			(xy 292.356083 -242.707595) (xy 292.305617 -242.715362) (xy 292.280086 -242.715796) (xy 292.254556 -242.715361)
			(xy 292.204092 -242.707584) (xy 292.15542 -242.692154) (xy 292.109692 -242.669437) (xy 292.08857 -242.65509)
			(xy 292.082045 -242.650788) (xy 292.06717 -242.646012) (xy 292.05936 -242.645692) (xy 291.543486 -242.645692)
			(xy 291.538128 -242.645162) (xy 291.530545 -242.637588) (xy 291.530024 -242.63223) (xy 285.48584 -242.63223)
			(xy 285.485395 -242.637543) (xy 285.477936 -242.645113) (xy 285.472632 -242.645692) (xy 284.956758 -242.645692)
			(xy 284.94895 -242.646032) (xy 284.934079 -242.6508) (xy 284.927548 -242.65509) (xy 284.906441 -242.669462)
			(xy 284.860712 -242.692183) (xy 284.812034 -242.707606) (xy 284.761564 -242.715366) (xy 284.736032 -242.715796)
			(xy 284.710503 -242.715338) (xy 284.66004 -242.707567) (xy 284.611368 -242.692145) (xy 284.565639 -242.669434)
			(xy 284.544516 -242.65509) (xy 284.537981 -242.650805) (xy 284.523114 -242.646018) (xy 284.515306 -242.645692)
			(xy 283.999432 -242.645692) (xy 283.9941 -242.64535) (xy 283.986556 -242.637815) (xy 283.986224 -242.632484)
			(xy 277.942019 -242.632484) (xy 277.941595 -242.637543) (xy 277.934136 -242.645113) (xy 277.928832 -242.645692)
			(xy 277.412958 -242.645692) (xy 277.40515 -242.646032) (xy 277.390279 -242.6508) (xy 277.383748 -242.65509)
			(xy 277.362641 -242.669462) (xy 277.316912 -242.692183) (xy 277.268234 -242.707606) (xy 277.217764 -242.715366)
			(xy 277.192232 -242.715796) (xy 277.166703 -242.715338) (xy 277.11624 -242.707567) (xy 277.067568 -242.692145)
			(xy 277.021839 -242.669434) (xy 277.000716 -242.65509) (xy 276.994181 -242.650805) (xy 276.979314 -242.646018)
			(xy 276.971506 -242.645692) (xy 276.455632 -242.645692) (xy 276.4503 -242.64535) (xy 276.442756 -242.637815)
			(xy 276.442424 -242.632484) (xy 270.398218 -242.632484) (xy 270.397767 -242.637603) (xy 270.390153 -242.645188)
			(xy 270.384778 -242.645692) (xy 269.868904 -242.645692) (xy 269.861094 -242.646009) (xy 269.846223 -242.650793)
			(xy 269.839694 -242.65509) (xy 269.818575 -242.669443) (xy 269.77285 -242.692167) (xy 269.724176 -242.707596)
			(xy 269.673709 -242.715363) (xy 269.648178 -242.715796) (xy 269.622648 -242.715365) (xy 269.572184 -242.707586)
			(xy 269.523512 -242.692155) (xy 269.477784 -242.669438) (xy 269.456662 -242.65509) (xy 269.450139 -242.650784)
			(xy 269.435262 -242.646011) (xy 269.427452 -242.645692) (xy 268.911578 -242.645692) (xy 268.906219 -242.645167)
			(xy 268.898636 -242.637589) (xy 268.898116 -242.63223) (xy 206.997808 -242.63223) (xy 206.997808 -242.632484)
			(xy 206.997462 -242.637814) (xy 206.98993 -242.645356) (xy 206.9846 -242.645692) (xy 206.468726 -242.645692)
			(xy 206.460849 -242.645949) (xy 206.445844 -242.650753) (xy 206.439262 -242.65509) (xy 206.418189 -242.669488)
			(xy 206.372542 -242.692314) (xy 206.323935 -242.707869) (xy 206.273517 -242.715787) (xy 206.248 -242.716304)
			(xy 206.222479 -242.715831) (xy 206.172052 -242.707931) (xy 206.12344 -242.692366) (xy 206.077802 -242.669507)
			(xy 206.056738 -242.65509) (xy 206.05014 -242.650786) (xy 206.035145 -242.645993) (xy 206.027274 -242.645692)
			(xy 205.5114 -242.645692) (xy 205.506064 -242.645372) (xy 205.498522 -242.637821) (xy 205.498192 -242.632484)
			(xy 199.454008 -242.632484) (xy 199.453662 -242.637814) (xy 199.44613 -242.645356) (xy 199.4408 -242.645692)
			(xy 198.924926 -242.645692) (xy 198.917049 -242.645949) (xy 198.902044 -242.650753) (xy 198.895462 -242.65509)
			(xy 198.874389 -242.669488) (xy 198.828742 -242.692314) (xy 198.780135 -242.707869) (xy 198.729717 -242.715787)
			(xy 198.7042 -242.716304) (xy 198.678679 -242.715831) (xy 198.628252 -242.707931) (xy 198.57964 -242.692366)
			(xy 198.534002 -242.669507) (xy 198.512938 -242.65509) (xy 198.50634 -242.650786) (xy 198.491345 -242.645993)
			(xy 198.483474 -242.645692) (xy 197.9676 -242.645692) (xy 197.962264 -242.645372) (xy 197.954722 -242.637821)
			(xy 197.954392 -242.632484) (xy 191.910208 -242.632484) (xy 191.909862 -242.637814) (xy 191.90233 -242.645356)
			(xy 191.897 -242.645692) (xy 191.896492 -242.645692) (xy 191.380872 -242.645692) (xy 191.372996 -242.645968)
			(xy 191.357992 -242.650759) (xy 191.351408 -242.65509) (xy 191.33035 -242.669511) (xy 191.284698 -242.692332)
			(xy 191.236086 -242.707881) (xy 191.185664 -242.715791) (xy 191.160146 -242.716304) (xy 191.134626 -242.715808)
			(xy 191.084199 -242.707915) (xy 191.035588 -242.692357) (xy 190.989949 -242.669504) (xy 190.968884 -242.65509)
			(xy 190.962298 -242.650765) (xy 190.947294 -242.645985) (xy 190.93942 -242.645692) (xy 190.423546 -242.645692)
			(xy 190.418255 -242.64515) (xy 190.410683 -242.637762) (xy 190.410084 -242.632484) (xy 184.3659 -242.632484)
			(xy 184.365562 -242.637816) (xy 184.358024 -242.645358) (xy 184.352692 -242.645692) (xy 183.836818 -242.645692)
			(xy 183.828944 -242.645988) (xy 183.81394 -242.650765) (xy 183.807354 -242.65509) (xy 183.786283 -242.669491)
			(xy 183.740635 -242.692316) (xy 183.692028 -242.707871) (xy 183.641609 -242.715788) (xy 183.616092 -242.716304)
			(xy 183.590573 -242.715785) (xy 183.540147 -242.707899) (xy 183.491536 -242.692348) (xy 183.445896 -242.669501)
			(xy 183.42483 -242.65509) (xy 183.418234 -242.650783) (xy 183.403237 -242.645991) (xy 183.395366 -242.645692)
			(xy 182.879492 -242.645692) (xy 182.874155 -242.645377) (xy 182.866613 -242.637822) (xy 182.866284 -242.632484)
			(xy 176.8221 -242.632484) (xy 176.821762 -242.637816) (xy 176.814224 -242.645358) (xy 176.808892 -242.645692)
			(xy 176.808384 -242.645692) (xy 176.292764 -242.645692) (xy 176.284888 -242.645965) (xy 176.269884 -242.650758)
			(xy 176.2633 -242.65509) (xy 176.242216 -242.669472) (xy 176.196573 -242.692301) (xy 176.147969 -242.707861)
			(xy 176.097554 -242.715784) (xy 176.072038 -242.716304) (xy 176.046518 -242.715812) (xy 175.996091 -242.707918)
			(xy 175.94748 -242.692359) (xy 175.901841 -242.669505) (xy 175.880776 -242.65509) (xy 175.874192 -242.650762)
			(xy 175.859186 -242.645983) (xy 175.851312 -242.645692) (xy 175.335438 -242.645692) (xy 175.330146 -242.645155)
			(xy 175.322575 -242.637763) (xy 175.321976 -242.632484) (xy 169.277792 -242.632484) (xy 169.277461 -242.637818)
			(xy 169.269918 -242.645361) (xy 169.264584 -242.645692) (xy 167.791384 -242.645692) (xy 167.786115 -242.645215)
			(xy 167.778673 -242.637754) (xy 167.778176 -242.632484) (xy 60.178188 -242.632484) (xy 60.17786 -242.637819)
			(xy 60.170315 -242.645362) (xy 60.16498 -242.645692) (xy 60.164472 -242.645692) (xy 58.691526 -242.645692)
			(xy 58.686232 -242.645163) (xy 58.678662 -242.637765) (xy 58.678064 -242.632484) (xy 52.63388 -242.632484)
			(xy 52.63356 -242.637821) (xy 52.626009 -242.645365) (xy 52.620672 -242.645692) (xy 52.104798 -242.645692)
			(xy 52.096923 -242.645979) (xy 52.081919 -242.650762) (xy 52.075334 -242.65509) (xy 52.054269 -242.6695)
			(xy 52.008619 -242.692323) (xy 51.960009 -242.707875) (xy 51.90959 -242.715789) (xy 51.884072 -242.716304)
			(xy 51.858553 -242.715795) (xy 51.808127 -242.707906) (xy 51.759515 -242.692352) (xy 51.713876 -242.669502)
			(xy 51.69281 -242.65509) (xy 51.686219 -242.650775) (xy 51.671218 -242.645988) (xy 51.663346 -242.645692)
			(xy 51.147472 -242.645692) (xy 51.142202 -242.645222) (xy 51.13476 -242.637756) (xy 51.134264 -242.632484)
			(xy 45.09008 -242.632484) (xy 45.08976 -242.637821) (xy 45.082209 -242.645365) (xy 45.076872 -242.645692)
			(xy 45.076364 -242.645692) (xy 44.560744 -242.645692) (xy 44.552867 -242.645956) (xy 44.537863 -242.650755)
			(xy 44.53128 -242.65509) (xy 44.510202 -242.66948) (xy 44.464557 -242.692308) (xy 44.415951 -242.707866)
			(xy 44.365535 -242.715786) (xy 44.340018 -242.716304) (xy 44.314498 -242.715822) (xy 44.26407 -242.707925)
			(xy 44.215459 -242.692363) (xy 44.169821 -242.669506) (xy 44.148756 -242.65509) (xy 44.142177 -242.650754)
			(xy 44.127167 -242.645981) (xy 44.119292 -242.645692) (xy 43.603418 -242.645692) (xy 43.598123 -242.645169)
			(xy 43.590553 -242.637766) (xy 43.589956 -242.632484) (xy 37.545772 -242.632484) (xy 37.545459 -242.637823)
			(xy 37.537903 -242.645367) (xy 37.532564 -242.645692) (xy 37.01669 -242.645692) (xy 37.008815 -242.645976)
			(xy 36.993811 -242.650761) (xy 36.987226 -242.65509) (xy 36.966163 -242.669503) (xy 36.920512 -242.692326)
			(xy 36.871902 -242.707877) (xy 36.821482 -242.71579) (xy 36.795964 -242.716304) (xy 36.770444 -242.715799)
			(xy 36.720018 -242.707909) (xy 36.671407 -242.692353) (xy 36.625768 -242.669503) (xy 36.604702 -242.65509)
			(xy 36.598112 -242.650772) (xy 36.583111 -242.645987) (xy 36.575238 -242.645692) (xy 36.059364 -242.645692)
			(xy 36.054093 -242.645227) (xy 36.046652 -242.637757) (xy 36.046156 -242.632484) (xy 30.001972 -242.632484)
			(xy 30.001659 -242.637823) (xy 29.994103 -242.645367) (xy 29.988764 -242.645692) (xy 29.47289 -242.645692)
			(xy 29.465015 -242.645976) (xy 29.450011 -242.650761) (xy 29.443426 -242.65509) (xy 29.422363 -242.669503)
			(xy 29.376712 -242.692326) (xy 29.328102 -242.707877) (xy 29.277682 -242.71579) (xy 29.252164 -242.716304)
			(xy 29.226644 -242.715799) (xy 29.176218 -242.707909) (xy 29.127607 -242.692353) (xy 29.081968 -242.669503)
			(xy 29.060902 -242.65509) (xy 29.054312 -242.650772) (xy 29.039311 -242.645987) (xy 29.031438 -242.645692)
			(xy 28.515564 -242.645692) (xy 28.510293 -242.645227) (xy 28.502852 -242.637757) (xy 28.502356 -242.632484)
			(xy 22.458172 -242.632484) (xy 22.457859 -242.637823) (xy 22.450303 -242.645367) (xy 22.444964 -242.645692)
			(xy 22.444456 -242.645692) (xy 21.928836 -242.645692) (xy 21.920959 -242.645953) (xy 21.905955 -242.650754)
			(xy 21.899372 -242.65509) (xy 21.878296 -242.669484) (xy 21.83265 -242.69231) (xy 21.784044 -242.707867)
			(xy 21.733627 -242.715786) (xy 21.70811 -242.716304) (xy 21.682589 -242.715826) (xy 21.632162 -242.707928)
			(xy 21.58355 -242.692364) (xy 21.537913 -242.669506) (xy 21.516848 -242.65509) (xy 21.51027 -242.650751)
			(xy 21.49526 -242.645979) (xy 21.487384 -242.645692) (xy 20.97151 -242.645692) (xy 20.966214 -242.645174)
			(xy 20.958644 -242.637768) (xy 20.958048 -242.632484) (xy 2.509012 -242.632484) (xy 2.509012 -243.482368)
			(xy 16.85798 -243.482368) (xy 16.85798 -242.98783) (xy 16.858304 -242.982389) (xy 16.866001 -242.974699)
			(xy 16.871442 -242.974368) (xy 17.38757 -242.974368) (xy 17.395379 -242.974047) (xy 17.410251 -242.969266)
			(xy 17.41678 -242.96497) (xy 17.437869 -242.950621) (xy 17.48353 -242.92789) (xy 17.532136 -242.912431)
			(xy 17.582539 -242.904608) (xy 17.633545 -242.904608) (xy 17.683948 -242.912431) (xy 17.732554 -242.92789)
			(xy 17.778215 -242.950621) (xy 17.799304 -242.96497) (xy 17.805837 -242.969258) (xy 17.820706 -242.974044)
			(xy 17.828514 -242.974368) (xy 18.344642 -242.974368) (xy 18.350018 -242.974825) (xy 18.357603 -242.982451)
			(xy 18.358104 -242.98783) (xy 18.358104 -243.482368) (xy 24.402288 -243.482368) (xy 24.402288 -242.98783)
			(xy 24.402749 -242.982518) (xy 24.410193 -242.974943) (xy 24.415496 -242.974368) (xy 24.931624 -242.974368)
			(xy 24.939436 -242.97407) (xy 24.954307 -242.969274) (xy 24.960834 -242.96497) (xy 24.981923 -242.950621)
			(xy 25.027584 -242.92789) (xy 25.07619 -242.912431) (xy 25.126593 -242.904608) (xy 25.177599 -242.904608)
			(xy 25.228002 -242.912431) (xy 25.276608 -242.92789) (xy 25.322269 -242.950621) (xy 25.343358 -242.96497)
			(xy 25.349879 -242.969279) (xy 25.364757 -242.974051) (xy 25.372568 -242.974368) (xy 25.888696 -242.974368)
			(xy 25.893952 -242.974895) (xy 25.901394 -242.982321) (xy 25.901904 -242.987576) (xy 25.901904 -242.988084)
			(xy 25.901904 -243.482368) (xy 31.946088 -243.482368) (xy 31.946088 -242.98783) (xy 31.946549 -242.982518)
			(xy 31.953993 -242.974943) (xy 31.959296 -242.974368) (xy 32.475424 -242.974368) (xy 32.483236 -242.97407)
			(xy 32.498107 -242.969274) (xy 32.504634 -242.96497) (xy 32.525723 -242.950621) (xy 32.571384 -242.92789)
			(xy 32.61999 -242.912431) (xy 32.670393 -242.904608) (xy 32.721399 -242.904608) (xy 32.771802 -242.912431)
			(xy 32.820408 -242.92789) (xy 32.866069 -242.950621) (xy 32.887158 -242.96497) (xy 32.893679 -242.969279)
			(xy 32.908557 -242.974051) (xy 32.916368 -242.974368) (xy 33.432496 -242.974368) (xy 33.437752 -242.974895)
			(xy 33.445194 -242.982321) (xy 33.445704 -242.987576) (xy 33.445704 -242.988084) (xy 33.445704 -243.482368)
			(xy 39.489888 -243.482368) (xy 39.489888 -242.98783) (xy 39.490465 -242.982482) (xy 39.498005 -242.974897)
			(xy 39.50335 -242.974368) (xy 40.019478 -242.974368) (xy 40.027288 -242.974051) (xy 40.04216 -242.969268)
			(xy 40.048688 -242.96497) (xy 40.069777 -242.950621) (xy 40.115438 -242.92789) (xy 40.164044 -242.912431)
			(xy 40.214447 -242.904608) (xy 40.265453 -242.904608) (xy 40.315856 -242.912431) (xy 40.364462 -242.92789)
			(xy 40.410123 -242.950621) (xy 40.431212 -242.96497) (xy 40.437743 -242.969261) (xy 40.452613 -242.974045)
			(xy 40.460422 -242.974368) (xy 40.97655 -242.974368) (xy 40.981927 -242.97482) (xy 40.989512 -242.98245)
			(xy 40.990012 -242.98783) (xy 40.990012 -243.482368) (xy 47.034196 -243.482368) (xy 47.034196 -242.98783)
			(xy 47.034738 -242.98254) (xy 47.042127 -242.974969) (xy 47.047404 -242.974368) (xy 47.563532 -242.974368)
			(xy 47.57134 -242.974031) (xy 47.586212 -242.969261) (xy 47.592742 -242.96497) (xy 47.613831 -242.950621)
			(xy 47.659492 -242.92789) (xy 47.708098 -242.912431) (xy 47.758501 -242.904608) (xy 47.809507 -242.904608)
			(xy 47.85991 -242.912431) (xy 47.908516 -242.92789) (xy 47.954177 -242.950621) (xy 47.975266 -242.96497)
			(xy 47.981808 -242.969244) (xy 47.99667 -242.974038) (xy 48.004476 -242.974368) (xy 48.520604 -242.974368)
			(xy 48.525862 -242.974889) (xy 48.533303 -242.982319) (xy 48.533812 -242.987576) (xy 48.533812 -242.988084)
			(xy 48.533812 -243.482368) (xy 54.577996 -243.482368) (xy 54.577996 -242.98783) (xy 54.578566 -242.98248)
			(xy 54.586111 -242.974895) (xy 54.591458 -242.974368) (xy 56.064658 -242.974368) (xy 56.070094 -242.97471)
			(xy 56.077785 -242.982394) (xy 56.07812 -242.98783) (xy 56.07812 -243.482368) (xy 56.077753 -243.487693)
			(xy 56.070236 -243.495235) (xy 56.064912 -243.495576) (xy 56.064404 -243.495576) (xy 54.591458 -243.495576)
			(xy 54.586152 -243.495107) (xy 54.578585 -243.487664) (xy 54.577996 -243.482368) (xy 48.533812 -243.482368)
			(xy 48.533452 -243.487695) (xy 48.52593 -243.495237) (xy 48.520604 -243.495576) (xy 48.00473 -243.495576)
			(xy 47.996853 -243.495837) (xy 47.981849 -243.500639) (xy 47.975266 -243.504974) (xy 47.95419 -243.519368)
			(xy 47.908545 -243.542195) (xy 47.859938 -243.557752) (xy 47.809521 -243.565671) (xy 47.784004 -243.566188)
			(xy 47.758483 -243.565716) (xy 47.708055 -243.557816) (xy 47.659444 -243.542251) (xy 47.613806 -243.519392)
			(xy 47.592742 -243.504974) (xy 47.586161 -243.500641) (xy 47.571153 -243.495864) (xy 47.563278 -243.495576)
			(xy 47.047404 -243.495576) (xy 47.042065 -243.495267) (xy 47.034522 -243.487708) (xy 47.034196 -243.482368)
			(xy 40.990012 -243.482368) (xy 40.989652 -243.487695) (xy 40.98213 -243.495237) (xy 40.976804 -243.495576)
			(xy 40.976296 -243.495576) (xy 40.460676 -243.495576) (xy 40.452801 -243.495857) (xy 40.437797 -243.500645)
			(xy 40.431212 -243.504974) (xy 40.410152 -243.519392) (xy 40.3645 -243.542213) (xy 40.315889 -243.557764)
			(xy 40.265468 -243.565675) (xy 40.23995 -243.566188) (xy 40.21443 -243.565693) (xy 40.164003 -243.5578)
			(xy 40.115392 -243.542242) (xy 40.069753 -243.519389) (xy 40.048688 -243.504974) (xy 40.042097 -243.500659)
			(xy 40.027097 -243.495871) (xy 40.019224 -243.495576) (xy 39.50335 -243.495576) (xy 39.498056 -243.495045)
			(xy 39.490483 -243.48765) (xy 39.489888 -243.482368) (xy 33.445704 -243.482368) (xy 33.445351 -243.487697)
			(xy 33.437824 -243.49524) (xy 33.432496 -243.495576) (xy 32.916622 -243.495576) (xy 32.908748 -243.495876)
			(xy 32.893744 -243.500651) (xy 32.887158 -243.504974) (xy 32.866085 -243.519372) (xy 32.820438 -243.542198)
			(xy 32.771831 -243.557754) (xy 32.721413 -243.565671) (xy 32.695896 -243.566188) (xy 32.670375 -243.56572)
			(xy 32.619947 -243.557819) (xy 32.571335 -243.542253) (xy 32.525698 -243.519392) (xy 32.504634 -243.504974)
			(xy 32.498032 -243.500676) (xy 32.48304 -243.495877) (xy 32.47517 -243.495576) (xy 31.959296 -243.495576)
			(xy 31.953955 -243.495273) (xy 31.946413 -243.487709) (xy 31.946088 -243.482368) (xy 25.901904 -243.482368)
			(xy 25.901551 -243.487697) (xy 25.894024 -243.49524) (xy 25.888696 -243.495576) (xy 25.372822 -243.495576)
			(xy 25.364948 -243.495876) (xy 25.349944 -243.500651) (xy 25.343358 -243.504974) (xy 25.322285 -243.519372)
			(xy 25.276638 -243.542198) (xy 25.228031 -243.557754) (xy 25.177613 -243.565671) (xy 25.152096 -243.566188)
			(xy 25.126575 -243.56572) (xy 25.076147 -243.557819) (xy 25.027535 -243.542253) (xy 24.981898 -243.519392)
			(xy 24.960834 -243.504974) (xy 24.954232 -243.500676) (xy 24.93924 -243.495877) (xy 24.93137 -243.495576)
			(xy 24.415496 -243.495576) (xy 24.410155 -243.495273) (xy 24.402613 -243.487709) (xy 24.402288 -243.482368)
			(xy 18.358104 -243.482368) (xy 18.357751 -243.487697) (xy 18.350224 -243.49524) (xy 18.344896 -243.495576)
			(xy 18.344388 -243.495576) (xy 17.828768 -243.495576) (xy 17.820892 -243.495853) (xy 17.805888 -243.500644)
			(xy 17.799304 -243.504974) (xy 17.778218 -243.519352) (xy 17.732576 -243.542183) (xy 17.683973 -243.557744)
			(xy 17.633558 -243.565668) (xy 17.608042 -243.566188) (xy 17.582522 -243.565697) (xy 17.532095 -243.557803)
			(xy 17.483483 -243.542244) (xy 17.437845 -243.519389) (xy 17.41678 -243.504974) (xy 17.41019 -243.500655)
			(xy 17.395189 -243.495869) (xy 17.387316 -243.495576) (xy 16.871442 -243.495576) (xy 16.866147 -243.495051)
			(xy 16.858574 -243.487651) (xy 16.85798 -243.482368) (xy 2.509012 -243.482368) (xy 2.509012 -243.6744)
			(xy 108.185132 -243.6744) (xy 108.189304 -243.624054) (xy 108.201706 -243.575081) (xy 108.222 -243.528817)
			(xy 108.249632 -243.486525) (xy 108.283849 -243.449358) (xy 108.323717 -243.418331) (xy 108.368148 -243.394288)
			(xy 108.41593 -243.377887) (xy 108.465761 -243.369575) (xy 108.49102 -243.369084) (xy 109.431074 -243.369084)
			(xy 109.456332 -243.369591) (xy 109.506161 -243.377902) (xy 109.553942 -243.394301) (xy 109.598371 -243.418342)
			(xy 109.638238 -243.449368) (xy 109.668619 -243.482368) (xy 163.678108 -243.482368) (xy 163.678108 -242.98783)
			(xy 163.678639 -242.982537) (xy 163.686035 -242.974966) (xy 163.691316 -242.974368) (xy 165.164516 -242.974368)
			(xy 165.169775 -242.974881) (xy 165.177215 -242.982317) (xy 165.177724 -242.987576) (xy 165.177724 -242.988084)
			(xy 165.177724 -243.482368) (xy 171.221908 -243.482368) (xy 171.221908 -242.98783) (xy 171.222467 -242.982477)
			(xy 171.230019 -242.974891) (xy 171.23537 -242.974368) (xy 171.751498 -242.974368) (xy 171.759309 -242.974059)
			(xy 171.77418 -242.96927) (xy 171.780708 -242.96497) (xy 171.801797 -242.950621) (xy 171.847458 -242.92789)
			(xy 171.896064 -242.912431) (xy 171.946467 -242.904608) (xy 171.997473 -242.904608) (xy 172.047876 -242.912431)
			(xy 172.096482 -242.92789) (xy 172.142143 -242.950621) (xy 172.163232 -242.96497) (xy 172.169759 -242.969269)
			(xy 172.184632 -242.974048) (xy 172.192442 -242.974368) (xy 172.70857 -242.974368) (xy 172.714008 -242.974703)
			(xy 172.721697 -242.982392) (xy 172.722032 -242.98783) (xy 172.722032 -243.482368) (xy 178.766216 -243.482368)
			(xy 178.766216 -242.98783) (xy 178.76674 -242.982535) (xy 178.774141 -242.974964) (xy 178.779424 -242.974368)
			(xy 179.295552 -242.974368) (xy 179.303361 -242.974039) (xy 179.318232 -242.969264) (xy 179.324762 -242.96497)
			(xy 179.345851 -242.950621) (xy 179.391512 -242.92789) (xy 179.440118 -242.912431) (xy 179.490521 -242.904608)
			(xy 179.541527 -242.904608) (xy 179.59193 -242.912431) (xy 179.640536 -242.92789) (xy 179.686197 -242.950621)
			(xy 179.707286 -242.96497) (xy 179.713823 -242.969252) (xy 179.728689 -242.974041) (xy 179.736496 -242.974368)
			(xy 180.252624 -242.974368) (xy 180.257884 -242.974876) (xy 180.265324 -242.982316) (xy 180.265832 -242.987576)
			(xy 180.265832 -242.988084) (xy 180.265832 -243.482368) (xy 186.310016 -243.482368) (xy 186.310016 -242.98783)
			(xy 186.310397 -242.982405) (xy 186.318054 -242.974718) (xy 186.323478 -242.974368) (xy 186.839606 -242.974368)
			(xy 186.847417 -242.974062) (xy 186.862289 -242.969271) (xy 186.868816 -242.96497) (xy 186.889905 -242.950621)
			(xy 186.935566 -242.92789) (xy 186.984172 -242.912431) (xy 187.034575 -242.904608) (xy 187.085581 -242.904608)
			(xy 187.135984 -242.912431) (xy 187.18459 -242.92789) (xy 187.230251 -242.950621) (xy 187.25134 -242.96497)
			(xy 187.257865 -242.969272) (xy 187.27274 -242.974049) (xy 187.28055 -242.974368) (xy 187.796678 -242.974368)
			(xy 187.802117 -242.974697) (xy 187.809806 -242.982391) (xy 187.81014 -242.98783) (xy 187.81014 -243.482368)
			(xy 193.854324 -243.482368) (xy 193.854324 -242.98783) (xy 193.854841 -242.982533) (xy 193.862247 -242.974961)
			(xy 193.867532 -242.974368) (xy 194.38366 -242.974368) (xy 194.391469 -242.974042) (xy 194.406341 -242.969265)
			(xy 194.41287 -242.96497) (xy 194.433959 -242.950621) (xy 194.47962 -242.92789) (xy 194.528226 -242.912431)
			(xy 194.578629 -242.904608) (xy 194.629635 -242.904608) (xy 194.680038 -242.912431) (xy 194.728644 -242.92789)
			(xy 194.774305 -242.950621) (xy 194.795394 -242.96497) (xy 194.801929 -242.969255) (xy 194.816796 -242.974042)
			(xy 194.824604 -242.974368) (xy 195.340732 -242.974368) (xy 195.345993 -242.974871) (xy 195.353432 -242.982315)
			(xy 195.35394 -242.987576) (xy 195.35394 -242.988084) (xy 195.35394 -243.482368) (xy 201.398124 -243.482368)
			(xy 201.398124 -242.98783) (xy 201.398641 -242.982533) (xy 201.406047 -242.974961) (xy 201.411332 -242.974368)
			(xy 201.92746 -242.974368) (xy 201.935269 -242.974042) (xy 201.950141 -242.969265) (xy 201.95667 -242.96497)
			(xy 201.977759 -242.950621) (xy 202.02342 -242.92789) (xy 202.072026 -242.912431) (xy 202.122429 -242.904608)
			(xy 202.173435 -242.904608) (xy 202.223838 -242.912431) (xy 202.272444 -242.92789) (xy 202.318105 -242.950621)
			(xy 202.339194 -242.96497) (xy 202.345729 -242.969255) (xy 202.360596 -242.974042) (xy 202.368404 -242.974368)
			(xy 202.884532 -242.974368) (xy 202.889793 -242.974871) (xy 202.897232 -242.982315) (xy 202.89774 -242.987576)
			(xy 202.89774 -242.988084) (xy 202.89774 -243.482114) (xy 264.798048 -243.482114) (xy 264.798048 -242.987576)
			(xy 264.798574 -242.982321) (xy 264.806002 -242.974882) (xy 264.811256 -242.974368) (xy 264.811764 -242.974368)
			(xy 265.327638 -242.974368) (xy 265.335446 -242.974033) (xy 265.350318 -242.969262) (xy 265.356848 -242.96497)
			(xy 265.377937 -242.950621) (xy 265.423598 -242.92789) (xy 265.472204 -242.912431) (xy 265.522607 -242.904608)
			(xy 265.573613 -242.904608) (xy 265.624016 -242.912431) (xy 265.672622 -242.92789) (xy 265.718283 -242.950621)
			(xy 265.739372 -242.96497) (xy 265.745912 -242.969246) (xy 265.760776 -242.974039) (xy 265.768582 -242.974368)
			(xy 266.28471 -242.974368) (xy 266.290022 -242.97482) (xy 266.297594 -242.982273) (xy 266.298172 -242.987576)
			(xy 266.298172 -243.482114) (xy 266.298148 -243.482368) (xy 272.342356 -243.482368) (xy 272.342356 -243.48186)
			(xy 272.342356 -242.987576) (xy 272.342875 -242.982319) (xy 272.350308 -242.97488) (xy 272.355564 -242.974368)
			(xy 272.871692 -242.974368) (xy 272.879502 -242.974056) (xy 272.894374 -242.96927) (xy 272.900902 -242.96497)
			(xy 272.921991 -242.950621) (xy 272.967652 -242.92789) (xy 273.016258 -242.912431) (xy 273.066661 -242.904608)
			(xy 273.117667 -242.904608) (xy 273.16807 -242.912431) (xy 273.216676 -242.92789) (xy 273.262337 -242.950621)
			(xy 273.283426 -242.96497) (xy 273.289954 -242.969267) (xy 273.304827 -242.974047) (xy 273.312636 -242.974368)
			(xy 273.828764 -242.974368) (xy 273.834086 -242.974749) (xy 273.841627 -242.982256) (xy 273.841972 -242.987576)
			(xy 273.841972 -243.482114) (xy 273.841949 -243.482368) (xy 279.886156 -243.482368) (xy 279.886156 -243.48186)
			(xy 279.886156 -242.987576) (xy 279.886675 -242.982319) (xy 279.894108 -242.97488) (xy 279.899364 -242.974368)
			(xy 280.415492 -242.974368) (xy 280.423302 -242.974056) (xy 280.438174 -242.96927) (xy 280.444702 -242.96497)
			(xy 280.465791 -242.950621) (xy 280.511452 -242.92789) (xy 280.560058 -242.912431) (xy 280.610461 -242.904608)
			(xy 280.661467 -242.904608) (xy 280.71187 -242.912431) (xy 280.760476 -242.92789) (xy 280.806137 -242.950621)
			(xy 280.827226 -242.96497) (xy 280.833754 -242.969267) (xy 280.848627 -242.974047) (xy 280.856436 -242.974368)
			(xy 281.372564 -242.974368) (xy 281.377886 -242.974749) (xy 281.385427 -242.982256) (xy 281.385772 -242.987576)
			(xy 281.385772 -243.482114) (xy 287.429956 -243.482114) (xy 287.429956 -242.987576) (xy 287.430475 -242.982319)
			(xy 287.437908 -242.97488) (xy 287.443164 -242.974368) (xy 287.443672 -242.974368) (xy 287.959546 -242.974368)
			(xy 287.967355 -242.974037) (xy 287.982226 -242.969263) (xy 287.988756 -242.96497) (xy 288.009845 -242.950621)
			(xy 288.055506 -242.92789) (xy 288.104112 -242.912431) (xy 288.154515 -242.904608) (xy 288.205521 -242.904608)
			(xy 288.255924 -242.912431) (xy 288.30453 -242.92789) (xy 288.350191 -242.950621) (xy 288.37128 -242.96497)
			(xy 288.377819 -242.969249) (xy 288.392683 -242.97404) (xy 288.40049 -242.974368) (xy 288.916618 -242.974368)
			(xy 288.921931 -242.974814) (xy 288.929503 -242.982271) (xy 288.93008 -242.987576) (xy 288.93008 -243.482114)
			(xy 288.930055 -243.482368) (xy 294.974264 -243.482368) (xy 294.974264 -243.48186) (xy 294.974264 -242.987576)
			(xy 294.974776 -242.982317) (xy 294.982213 -242.974878) (xy 294.987472 -242.974368) (xy 295.5036 -242.974368)
			(xy 295.511411 -242.97406) (xy 295.526282 -242.969271) (xy 295.53281 -242.96497) (xy 295.553899 -242.950621)
			(xy 295.59956 -242.92789) (xy 295.648166 -242.912431) (xy 295.698569 -242.904608) (xy 295.749575 -242.904608)
			(xy 295.799978 -242.912431) (xy 295.848584 -242.92789) (xy 295.894245 -242.950621) (xy 295.915334 -242.96497)
			(xy 295.921861 -242.96927) (xy 295.936734 -242.974048) (xy 295.944544 -242.974368) (xy 296.460672 -242.974368)
			(xy 296.465995 -242.974743) (xy 296.473536 -242.982255) (xy 296.47388 -242.987576) (xy 296.47388 -243.482114)
			(xy 302.518064 -243.482114) (xy 302.518064 -242.987576) (xy 302.518576 -242.982317) (xy 302.526013 -242.974878)
			(xy 302.531272 -242.974368) (xy 302.53178 -242.974368) (xy 304.004726 -242.974368) (xy 304.01004 -242.974809)
			(xy 304.017611 -242.98227) (xy 304.018188 -242.987576) (xy 304.018188 -243.482114) (xy 304.017661 -243.487473)
			(xy 304.010085 -243.495057) (xy 304.004726 -243.495576) (xy 302.531526 -243.495576) (xy 302.526098 -243.495205)
			(xy 302.518411 -243.487541) (xy 302.518064 -243.482114) (xy 296.47388 -243.482114) (xy 296.473388 -243.487415)
			(xy 296.465963 -243.494984) (xy 296.460672 -243.495576) (xy 295.944798 -243.495576) (xy 295.936986 -243.495876)
			(xy 295.922115 -243.50067) (xy 295.915588 -243.504974) (xy 295.894469 -243.519327) (xy 295.848744 -243.542052)
			(xy 295.80007 -243.557481) (xy 295.749603 -243.565247) (xy 295.724072 -243.56568) (xy 295.698541 -243.565255)
			(xy 295.648077 -243.557475) (xy 295.599405 -243.542042) (xy 295.553678 -243.519323) (xy 295.532556 -243.504974)
			(xy 295.526029 -243.500674) (xy 295.511156 -243.495895) (xy 295.503346 -243.495576) (xy 294.987472 -243.495576)
			(xy 294.982128 -243.495289) (xy 294.974587 -243.487713) (xy 294.974264 -243.482368) (xy 288.930055 -243.482368)
			(xy 288.929561 -243.487475) (xy 288.921979 -243.495059) (xy 288.916618 -243.495576) (xy 288.400744 -243.495576)
			(xy 288.392934 -243.495896) (xy 288.378062 -243.500676) (xy 288.371534 -243.504974) (xy 288.35043 -243.519351)
			(xy 288.3047 -243.54207) (xy 288.256021 -243.557493) (xy 288.20555 -243.565251) (xy 288.180018 -243.56568)
			(xy 288.154488 -243.565232) (xy 288.104025 -243.557459) (xy 288.055353 -243.542033) (xy 288.009624 -243.51932)
			(xy 287.988502 -243.504974) (xy 287.981965 -243.500692) (xy 287.967099 -243.495902) (xy 287.959292 -243.495576)
			(xy 287.443418 -243.495576) (xy 287.437989 -243.49521) (xy 287.430303 -243.487542) (xy 287.429956 -243.482114)
			(xy 281.385772 -243.482114) (xy 281.385287 -243.487417) (xy 281.377857 -243.494986) (xy 281.372564 -243.495576)
			(xy 280.85669 -243.495576) (xy 280.848878 -243.495873) (xy 280.834006 -243.500669) (xy 280.82748 -243.504974)
			(xy 280.806363 -243.519331) (xy 280.760637 -243.542055) (xy 280.711963 -243.557483) (xy 280.661495 -243.565248)
			(xy 280.635964 -243.56568) (xy 280.610433 -243.565259) (xy 280.559969 -243.557478) (xy 280.511297 -243.542044)
			(xy 280.46557 -243.519323) (xy 280.444448 -243.504974) (xy 280.437923 -243.500671) (xy 280.423048 -243.495894)
			(xy 280.415238 -243.495576) (xy 279.899364 -243.495576) (xy 279.894089 -243.495126) (xy 279.886647 -243.487645)
			(xy 279.886156 -243.482368) (xy 273.841949 -243.482368) (xy 273.841487 -243.487417) (xy 273.834057 -243.494986)
			(xy 273.828764 -243.495576) (xy 273.31289 -243.495576) (xy 273.305078 -243.495873) (xy 273.290206 -243.500669)
			(xy 273.28368 -243.504974) (xy 273.262563 -243.519331) (xy 273.216837 -243.542055) (xy 273.168163 -243.557483)
			(xy 273.117695 -243.565248) (xy 273.092164 -243.56568) (xy 273.066633 -243.565259) (xy 273.016169 -243.557478)
			(xy 272.967497 -243.542044) (xy 272.92177 -243.519323) (xy 272.900648 -243.504974) (xy 272.894123 -243.500671)
			(xy 272.879248 -243.495894) (xy 272.871438 -243.495576) (xy 272.355564 -243.495576) (xy 272.350289 -243.495126)
			(xy 272.342847 -243.487645) (xy 272.342356 -243.482368) (xy 266.298148 -243.482368) (xy 266.29766 -243.487477)
			(xy 266.290073 -243.495061) (xy 266.28471 -243.495576) (xy 265.768836 -243.495576) (xy 265.761026 -243.495892)
			(xy 265.746154 -243.500675) (xy 265.739626 -243.504974) (xy 265.718496 -243.519311) (xy 265.672775 -243.54204)
			(xy 265.624104 -243.557473) (xy 265.57364 -243.565244) (xy 265.54811 -243.56568) (xy 265.52258 -243.565236)
			(xy 265.472117 -243.557462) (xy 265.423444 -243.542035) (xy 265.377716 -243.51932) (xy 265.356594 -243.504974)
			(xy 265.350059 -243.500689) (xy 265.335192 -243.495901) (xy 265.327384 -243.495576) (xy 264.81151 -243.495576)
			(xy 264.806151 -243.495044) (xy 264.798565 -243.487472) (xy 264.798048 -243.482114) (xy 202.89774 -243.482114)
			(xy 202.89774 -243.482368) (xy 202.897187 -243.487619) (xy 202.889781 -243.495062) (xy 202.884532 -243.495576)
			(xy 202.368658 -243.495576) (xy 202.360782 -243.495849) (xy 202.345778 -243.500642) (xy 202.339194 -243.504974)
			(xy 202.318111 -243.519356) (xy 202.272468 -243.542186) (xy 202.223864 -243.557746) (xy 202.173448 -243.565669)
			(xy 202.147932 -243.566188) (xy 202.122412 -243.565702) (xy 202.071985 -243.557806) (xy 202.023373 -243.542246)
			(xy 201.977735 -243.51939) (xy 201.95667 -243.504974) (xy 201.950083 -243.500652) (xy 201.93508 -243.495868)
			(xy 201.927206 -243.495576) (xy 201.411332 -243.495576) (xy 201.405996 -243.495248) (xy 201.398452 -243.487704)
			(xy 201.398124 -243.482368) (xy 195.35394 -243.482368) (xy 195.353387 -243.487619) (xy 195.345981 -243.495062)
			(xy 195.340732 -243.495576) (xy 194.824858 -243.495576) (xy 194.816982 -243.495849) (xy 194.801978 -243.500642)
			(xy 194.795394 -243.504974) (xy 194.774311 -243.519356) (xy 194.728668 -243.542186) (xy 194.680064 -243.557746)
			(xy 194.629648 -243.565669) (xy 194.604132 -243.566188) (xy 194.578612 -243.565702) (xy 194.528185 -243.557806)
			(xy 194.479573 -243.542246) (xy 194.433935 -243.51939) (xy 194.41287 -243.504974) (xy 194.406283 -243.500652)
			(xy 194.39128 -243.495868) (xy 194.383406 -243.495576) (xy 193.867532 -243.495576) (xy 193.862196 -243.495248)
			(xy 193.854652 -243.487704) (xy 193.854324 -243.482368) (xy 187.81014 -243.482368) (xy 187.809587 -243.487619)
			(xy 187.802181 -243.495062) (xy 187.796932 -243.495576) (xy 187.796424 -243.495576) (xy 187.280804 -243.495576)
			(xy 187.27293 -243.495869) (xy 187.257926 -243.500648) (xy 187.25134 -243.504974) (xy 187.230272 -243.51938)
			(xy 187.184623 -243.542204) (xy 187.136015 -243.557758) (xy 187.085595 -243.565673) (xy 187.060078 -243.566188)
			(xy 187.034559 -243.565678) (xy 186.984132 -243.55779) (xy 186.935521 -243.542236) (xy 186.889882 -243.519387)
			(xy 186.868816 -243.504974) (xy 186.862218 -243.500669) (xy 186.847223 -243.495875) (xy 186.839352 -243.495576)
			(xy 186.323478 -243.495576) (xy 186.318175 -243.495093) (xy 186.310606 -243.487661) (xy 186.310016 -243.482368)
			(xy 180.265832 -243.482368) (xy 180.265454 -243.48769) (xy 180.257945 -243.495231) (xy 180.252624 -243.495576)
			(xy 179.73675 -243.495576) (xy 179.728874 -243.495846) (xy 179.71387 -243.500641) (xy 179.707286 -243.504974)
			(xy 179.686205 -243.51936) (xy 179.640561 -243.542189) (xy 179.591956 -243.557748) (xy 179.54154 -243.565669)
			(xy 179.516024 -243.566188) (xy 179.490503 -243.565706) (xy 179.440076 -243.557809) (xy 179.391465 -243.542247)
			(xy 179.345827 -243.51939) (xy 179.324762 -243.504974) (xy 179.318176 -243.500649) (xy 179.303172 -243.495867)
			(xy 179.295298 -243.495576) (xy 178.779424 -243.495576) (xy 178.774087 -243.495254) (xy 178.766543 -243.487705)
			(xy 178.766216 -243.482368) (xy 172.722032 -243.482368) (xy 172.721654 -243.48769) (xy 172.714145 -243.495231)
			(xy 172.708824 -243.495576) (xy 172.708316 -243.495576) (xy 172.192696 -243.495576) (xy 172.184822 -243.495865)
			(xy 172.169817 -243.500647) (xy 172.163232 -243.504974) (xy 172.142166 -243.519383) (xy 172.096517 -243.542207)
			(xy 172.047907 -243.557759) (xy 171.997488 -243.565673) (xy 171.97197 -243.566188) (xy 171.94645 -243.565682)
			(xy 171.896024 -243.557793) (xy 171.847412 -243.542238) (xy 171.801773 -243.519387) (xy 171.780708 -243.504974)
			(xy 171.774112 -243.500666) (xy 171.759116 -243.495874) (xy 171.751244 -243.495576) (xy 171.23537 -243.495576)
			(xy 171.230066 -243.495099) (xy 171.222497 -243.487663) (xy 171.221908 -243.482368) (xy 165.177724 -243.482368)
			(xy 165.177353 -243.487692) (xy 165.169839 -243.495234) (xy 165.164516 -243.495576) (xy 163.691316 -243.495576)
			(xy 163.685978 -243.495259) (xy 163.678434 -243.487706) (xy 163.678108 -243.482368) (xy 109.668619 -243.482368)
			(xy 109.672453 -243.486533) (xy 109.700085 -243.528823) (xy 109.720378 -243.575085) (xy 109.73278 -243.624056)
			(xy 109.736927 -243.6741) (xy 361.758723 -243.6741) (xy 361.762898 -243.623721) (xy 361.775308 -243.574716)
			(xy 361.795615 -243.528421) (xy 361.823265 -243.486101) (xy 361.857503 -243.448909) (xy 361.897396 -243.41786)
			(xy 361.941856 -243.393801) (xy 361.989669 -243.377388) (xy 362.039532 -243.369068) (xy 362.064808 -243.368576)
			(xy 363.004862 -243.368576) (xy 363.030146 -243.36899) (xy 363.080025 -243.377308) (xy 363.127854 -243.393722)
			(xy 363.172329 -243.417786) (xy 363.212237 -243.448843) (xy 363.243102 -243.482368) (xy 411.618176 -243.482368)
			(xy 411.618176 -243.48186) (xy 411.618176 -242.987576) (xy 411.618677 -242.982314) (xy 411.626122 -242.974874)
			(xy 411.631384 -242.974368) (xy 413.104584 -242.974368) (xy 413.109839 -242.974903) (xy 413.117281 -242.982322)
			(xy 413.117792 -242.987576) (xy 413.117792 -243.482114) (xy 419.161976 -243.482114) (xy 419.161976 -242.987576)
			(xy 419.162477 -242.982314) (xy 419.169922 -242.974874) (xy 419.175184 -242.974368) (xy 419.175692 -242.974368)
			(xy 419.691566 -242.974368) (xy 419.699375 -242.974045) (xy 419.714247 -242.969266) (xy 419.720776 -242.96497)
			(xy 419.741865 -242.950621) (xy 419.787526 -242.92789) (xy 419.836132 -242.912431) (xy 419.886535 -242.904608)
			(xy 419.937541 -242.904608) (xy 419.987944 -242.912431) (xy 420.03655 -242.92789) (xy 420.082211 -242.950621)
			(xy 420.1033 -242.96497) (xy 420.109834 -242.969257) (xy 420.124702 -242.974043) (xy 420.13251 -242.974368)
			(xy 420.648638 -242.974368) (xy 420.653953 -242.974801) (xy 420.661524 -242.982268) (xy 420.6621 -242.987576)
			(xy 420.6621 -243.482114) (xy 420.662075 -243.482368) (xy 426.706284 -243.482368) (xy 426.706284 -243.48186)
			(xy 426.706284 -242.987576) (xy 426.706778 -242.982312) (xy 426.714228 -242.974872) (xy 426.719492 -242.974368)
			(xy 427.23562 -242.974368) (xy 427.243431 -242.974068) (xy 427.258303 -242.969273) (xy 427.26483 -242.96497)
			(xy 427.285919 -242.950621) (xy 427.33158 -242.92789) (xy 427.380186 -242.912431) (xy 427.430589 -242.904608)
			(xy 427.481595 -242.904608) (xy 427.531998 -242.912431) (xy 427.580604 -242.92789) (xy 427.626265 -242.950621)
			(xy 427.647354 -242.96497) (xy 427.653876 -242.969278) (xy 427.668753 -242.974051) (xy 427.676564 -242.974368)
			(xy 428.192692 -242.974368) (xy 428.197948 -242.974897) (xy 428.20539 -242.982321) (xy 428.2059 -242.987576)
			(xy 428.2059 -243.482114) (xy 434.250084 -243.482114) (xy 434.250084 -242.987576) (xy 434.250578 -242.982312)
			(xy 434.258028 -242.974872) (xy 434.263292 -242.974368) (xy 434.2638 -242.974368) (xy 434.779674 -242.974368)
			(xy 434.787484 -242.974048) (xy 434.802355 -242.969267) (xy 434.808884 -242.96497) (xy 434.829973 -242.950621)
			(xy 434.875634 -242.92789) (xy 434.92424 -242.912431) (xy 434.974643 -242.904608) (xy 435.025649 -242.904608)
			(xy 435.076052 -242.912431) (xy 435.124658 -242.92789) (xy 435.170319 -242.950621) (xy 435.191408 -242.96497)
			(xy 435.19794 -242.96926) (xy 435.21281 -242.974044) (xy 435.220618 -242.974368) (xy 435.736746 -242.974368)
			(xy 435.74205 -242.974862) (xy 435.749626 -242.982283) (xy 435.750208 -242.987576) (xy 435.750208 -243.482114)
			(xy 435.750182 -243.482368) (xy 441.794392 -243.482368) (xy 441.794392 -243.48186) (xy 441.794392 -242.987576)
			(xy 441.794879 -242.98231) (xy 441.802334 -242.974869) (xy 441.8076 -242.974368) (xy 442.323728 -242.974368)
			(xy 442.33154 -242.974072) (xy 442.346411 -242.969274) (xy 442.352938 -242.96497) (xy 442.374027 -242.950621)
			(xy 442.419688 -242.92789) (xy 442.468294 -242.912431) (xy 442.518697 -242.904608) (xy 442.569703 -242.904608)
			(xy 442.620106 -242.912431) (xy 442.668712 -242.92789) (xy 442.714373 -242.950621) (xy 442.735462 -242.96497)
			(xy 442.742005 -242.969242) (xy 442.756866 -242.974037) (xy 442.764672 -242.974368) (xy 443.2808 -242.974368)
			(xy 443.286057 -242.974892) (xy 443.293498 -242.98232) (xy 443.294008 -242.987576) (xy 443.294008 -243.482114)
			(xy 443.293983 -243.482368) (xy 449.338192 -243.482368) (xy 449.338192 -243.48186) (xy 449.338192 -242.987576)
			(xy 449.338679 -242.98231) (xy 449.346134 -242.974869) (xy 449.3514 -242.974368) (xy 449.867528 -242.974368)
			(xy 449.87534 -242.974072) (xy 449.890211 -242.969274) (xy 449.896738 -242.96497) (xy 449.917827 -242.950621)
			(xy 449.963488 -242.92789) (xy 450.012094 -242.912431) (xy 450.062497 -242.904608) (xy 450.113503 -242.904608)
			(xy 450.163906 -242.912431) (xy 450.212512 -242.92789) (xy 450.258173 -242.950621) (xy 450.279262 -242.96497)
			(xy 450.285805 -242.969242) (xy 450.300666 -242.974037) (xy 450.308472 -242.974368) (xy 450.8246 -242.974368)
			(xy 450.829857 -242.974892) (xy 450.837298 -242.98232) (xy 450.837808 -242.987576) (xy 450.837808 -243.482114)
			(xy 450.837292 -243.487409) (xy 450.829883 -243.494976) (xy 450.8246 -243.495576) (xy 450.308726 -243.495576)
			(xy 450.300916 -243.495888) (xy 450.286044 -243.500674) (xy 450.279516 -243.504974) (xy 450.258389 -243.519315)
			(xy 450.212667 -243.542043) (xy 450.163995 -243.557475) (xy 450.11353 -243.565245) (xy 450.088 -243.56568)
			(xy 450.06247 -243.565241) (xy 450.012006 -243.557465) (xy 449.963334 -243.542037) (xy 449.917606 -243.519321)
			(xy 449.896484 -243.504974) (xy 449.889951 -243.500685) (xy 449.875082 -243.495899) (xy 449.867274 -243.495576)
			(xy 449.3514 -243.495576) (xy 449.34606 -243.49527) (xy 449.338517 -243.487709) (xy 449.338192 -243.482368)
			(xy 443.293983 -243.482368) (xy 443.293492 -243.487409) (xy 443.286083 -243.494976) (xy 443.2808 -243.495576)
			(xy 442.764926 -243.495576) (xy 442.757116 -243.495888) (xy 442.742244 -243.500674) (xy 442.735716 -243.504974)
			(xy 442.714589 -243.519315) (xy 442.668867 -243.542043) (xy 442.620195 -243.557475) (xy 442.56973 -243.565245)
			(xy 442.5442 -243.56568) (xy 442.51867 -243.565241) (xy 442.468206 -243.557465) (xy 442.419534 -243.542037)
			(xy 442.373806 -243.519321) (xy 442.352684 -243.504974) (xy 442.346151 -243.500685) (xy 442.331282 -243.495899)
			(xy 442.323474 -243.495576) (xy 441.8076 -243.495576) (xy 441.80226 -243.49527) (xy 441.794717 -243.487709)
			(xy 441.794392 -243.482368) (xy 435.750182 -243.482368) (xy 435.749663 -243.487468) (xy 435.742099 -243.495051)
			(xy 435.736746 -243.495576) (xy 435.220872 -243.495576) (xy 435.213059 -243.495865) (xy 435.198188 -243.500667)
			(xy 435.191662 -243.504974) (xy 435.17055 -243.519338) (xy 435.124823 -243.542061) (xy 435.076146 -243.557487)
			(xy 435.025678 -243.565249) (xy 435.000146 -243.56568) (xy 434.974617 -243.565218) (xy 434.924154 -243.557449)
			(xy 434.875482 -243.542027) (xy 434.829753 -243.519318) (xy 434.80863 -243.504974) (xy 434.802087 -243.500703)
			(xy 434.787226 -243.495906) (xy 434.77942 -243.495576) (xy 434.263546 -243.495576) (xy 434.258121 -243.495191)
			(xy 434.250433 -243.487538) (xy 434.250084 -243.482114) (xy 428.2059 -243.482114) (xy 428.205391 -243.487411)
			(xy 428.197977 -243.494979) (xy 428.192692 -243.495576) (xy 427.676818 -243.495576) (xy 427.669007 -243.495885)
			(xy 427.654135 -243.500673) (xy 427.647608 -243.504974) (xy 427.626483 -243.519319) (xy 427.58076 -243.542046)
			(xy 427.532088 -243.557477) (xy 427.481623 -243.565246) (xy 427.456092 -243.56568) (xy 427.430562 -243.565245)
			(xy 427.380098 -243.557468) (xy 427.331426 -243.542038) (xy 427.285698 -243.519322) (xy 427.264576 -243.504974)
			(xy 427.258045 -243.500682) (xy 427.243175 -243.495898) (xy 427.235366 -243.495576) (xy 426.719492 -243.495576)
			(xy 426.714151 -243.495276) (xy 426.706608 -243.48771) (xy 426.706284 -243.482368) (xy 420.662075 -243.482368)
			(xy 420.661563 -243.48747) (xy 420.653993 -243.495053) (xy 420.648638 -243.495576) (xy 420.132764 -243.495576)
			(xy 420.124955 -243.495904) (xy 420.110083 -243.500679) (xy 420.103554 -243.504974) (xy 420.082444 -243.519342)
			(xy 420.036716 -243.542064) (xy 419.988039 -243.557488) (xy 419.93757 -243.56525) (xy 419.912038 -243.56568)
			(xy 419.886509 -243.565222) (xy 419.836046 -243.557452) (xy 419.787373 -243.542029) (xy 419.741645 -243.519319)
			(xy 419.720522 -243.504974) (xy 419.713981 -243.5007) (xy 419.699118 -243.495905) (xy 419.691312 -243.495576)
			(xy 419.175438 -243.495576) (xy 419.170012 -243.495197) (xy 419.162324 -243.487539) (xy 419.161976 -243.482114)
			(xy 413.117792 -243.482114) (xy 413.11729 -243.487412) (xy 413.109871 -243.494981) (xy 413.104584 -243.495576)
			(xy 411.631384 -243.495576) (xy 411.626042 -243.495281) (xy 411.6185 -243.487712) (xy 411.618176 -243.482368)
			(xy 363.243102 -243.482368) (xy 363.246487 -243.486045) (xy 363.274147 -243.528377) (xy 363.294462 -243.574685)
			(xy 363.306876 -243.623705) (xy 363.311053 -243.6741) (xy 363.306876 -243.724495) (xy 363.294462 -243.773515)
			(xy 363.274147 -243.819823) (xy 363.246487 -243.862155) (xy 363.212237 -243.899357) (xy 363.172329 -243.930414)
			(xy 363.127854 -243.954478) (xy 363.080025 -243.970892) (xy 363.030146 -243.97921) (xy 363.004862 -243.9797)
			(xy 362.064808 -243.9797) (xy 362.039532 -243.979132) (xy 361.989669 -243.970812) (xy 361.941856 -243.954399)
			(xy 361.897396 -243.93034) (xy 361.857503 -243.899291) (xy 361.823265 -243.862099) (xy 361.795615 -243.819779)
			(xy 361.775308 -243.773484) (xy 361.762898 -243.724479) (xy 361.758723 -243.6741) (xy 109.736927 -243.6741)
			(xy 109.736952 -243.6744) (xy 109.73278 -243.724744) (xy 109.720378 -243.773715) (xy 109.700085 -243.819977)
			(xy 109.672453 -243.862267) (xy 109.638238 -243.899432) (xy 109.598371 -243.930458) (xy 109.553942 -243.954499)
			(xy 109.506161 -243.970898) (xy 109.456332 -243.979209) (xy 109.431074 -243.9797) (xy 108.49102 -243.9797)
			(xy 108.465761 -243.979225) (xy 108.41593 -243.970913) (xy 108.368148 -243.954512) (xy 108.323717 -243.930469)
			(xy 108.283849 -243.899442) (xy 108.249632 -243.862275) (xy 108.222 -243.819983) (xy 108.201706 -243.773719)
			(xy 108.189304 -243.724746) (xy 108.185132 -243.6744) (xy 2.509012 -243.6744) (xy 2.509012 -244.332506)
			(xy 20.958048 -244.332506) (xy 20.958048 -243.837968) (xy 20.958569 -243.832712) (xy 20.966 -243.825274)
			(xy 20.971256 -243.82476) (xy 20.971764 -243.82476) (xy 21.487384 -243.82476) (xy 21.495257 -243.824456)
			(xy 21.510261 -243.819683) (xy 21.516848 -243.815362) (xy 21.537922 -243.800966) (xy 21.583568 -243.778138)
			(xy 21.632175 -243.762582) (xy 21.682593 -243.754664) (xy 21.70811 -243.754148) (xy 21.733629 -243.754675)
			(xy 21.784054 -243.76256) (xy 21.832665 -243.778109) (xy 21.878305 -243.800953) (xy 21.899372 -243.815362)
			(xy 21.90597 -243.819665) (xy 21.920965 -243.82446) (xy 21.928836 -243.82476) (xy 22.44471 -243.82476)
			(xy 22.45002 -243.825219) (xy 22.457592 -243.832667) (xy 22.458172 -243.837968) (xy 22.458172 -244.332506)
			(xy 22.458148 -244.33276) (xy 28.502356 -244.33276) (xy 28.502356 -244.332252) (xy 28.502356 -243.837968)
			(xy 28.50287 -243.83271) (xy 28.510306 -243.825271) (xy 28.515564 -243.82476) (xy 29.031184 -243.82476)
			(xy 29.039057 -243.824456) (xy 29.054061 -243.819683) (xy 29.060648 -243.815362) (xy 29.081722 -243.800966)
			(xy 29.127368 -243.778138) (xy 29.175975 -243.762582) (xy 29.226393 -243.754664) (xy 29.25191 -243.754148)
			(xy 29.277429 -243.754675) (xy 29.327854 -243.76256) (xy 29.376465 -243.778109) (xy 29.422105 -243.800953)
			(xy 29.443172 -243.815362) (xy 29.44977 -243.819665) (xy 29.464765 -243.82446) (xy 29.472636 -243.82476)
			(xy 29.988764 -243.82476) (xy 29.994084 -243.825148) (xy 30.001625 -243.83265) (xy 30.001972 -243.837968)
			(xy 30.001972 -244.332506) (xy 30.001949 -244.33276) (xy 36.046156 -244.33276) (xy 36.046156 -244.332252)
			(xy 36.046156 -243.837968) (xy 36.04667 -243.83271) (xy 36.054106 -243.825271) (xy 36.059364 -243.82476)
			(xy 36.575238 -243.82476) (xy 36.583113 -243.82448) (xy 36.598117 -243.819691) (xy 36.604702 -243.815362)
			(xy 36.625789 -243.800986) (xy 36.671431 -243.778154) (xy 36.720033 -243.762592) (xy 36.770448 -243.754668)
			(xy 36.795964 -243.754148) (xy 36.821484 -243.754648) (xy 36.87191 -243.762541) (xy 36.920521 -243.778098)
			(xy 36.96616 -243.800949) (xy 36.987226 -243.815362) (xy 36.993812 -243.819686) (xy 37.008816 -243.824468)
			(xy 37.01669 -243.82476) (xy 37.532564 -243.82476) (xy 37.537884 -243.825148) (xy 37.545425 -243.83265)
			(xy 37.545772 -243.837968) (xy 37.545772 -244.332506) (xy 43.589956 -244.332506) (xy 43.589956 -243.837968)
			(xy 43.59047 -243.83271) (xy 43.597906 -243.825271) (xy 43.603164 -243.82476) (xy 43.603672 -243.82476)
			(xy 44.119292 -243.82476) (xy 44.127165 -243.824459) (xy 44.142169 -243.819684) (xy 44.148756 -243.815362)
			(xy 44.169828 -243.800962) (xy 44.215475 -243.778136) (xy 44.264082 -243.76258) (xy 44.314501 -243.754664)
			(xy 44.340018 -243.754148) (xy 44.365537 -243.754671) (xy 44.415962 -243.762557) (xy 44.464573 -243.778108)
			(xy 44.510213 -243.800952) (xy 44.53128 -243.815362) (xy 44.537877 -243.819668) (xy 44.552873 -243.824461)
			(xy 44.560744 -243.82476) (xy 45.076618 -243.82476) (xy 45.081929 -243.825213) (xy 45.0895 -243.832665)
			(xy 45.09008 -243.837968) (xy 45.09008 -244.332506) (xy 45.090055 -244.33276) (xy 51.134264 -244.33276)
			(xy 51.134264 -244.332252) (xy 51.134264 -243.837968) (xy 51.134771 -243.832708) (xy 51.142212 -243.825269)
			(xy 51.147472 -243.82476) (xy 51.663346 -243.82476) (xy 51.671221 -243.824483) (xy 51.686225 -243.819692)
			(xy 51.69281 -243.815362) (xy 51.713895 -243.800982) (xy 51.759537 -243.778151) (xy 51.808141 -243.76259)
			(xy 51.858556 -243.754667) (xy 51.884072 -243.754148) (xy 51.909592 -243.754644) (xy 51.960018 -243.762538)
			(xy 52.008629 -243.778097) (xy 52.054268 -243.800949) (xy 52.075334 -243.815362) (xy 52.081918 -243.819689)
			(xy 52.096924 -243.824469) (xy 52.104798 -243.82476) (xy 52.620672 -243.82476) (xy 52.625924 -243.82531)
			(xy 52.633366 -243.832719) (xy 52.63388 -243.837968) (xy 52.63388 -244.332506) (xy 58.678064 -244.332506)
			(xy 58.678064 -243.837968) (xy 58.678571 -243.832708) (xy 58.686012 -243.825269) (xy 58.691272 -243.82476)
			(xy 58.69178 -243.82476) (xy 59.2074 -243.82476) (xy 59.215274 -243.824463) (xy 59.230278 -243.819685)
			(xy 59.236864 -243.815362) (xy 59.257934 -243.800959) (xy 59.303581 -243.778133) (xy 59.35219 -243.762578)
			(xy 59.402609 -243.754663) (xy 59.428126 -243.754148) (xy 59.453645 -243.754667) (xy 59.50407 -243.762554)
			(xy 59.552682 -243.778106) (xy 59.598322 -243.800952) (xy 59.619388 -243.815362) (xy 59.625983 -243.819671)
			(xy 59.64098 -243.824462) (xy 59.648852 -243.82476) (xy 60.164726 -243.82476) (xy 60.170038 -243.825208)
			(xy 60.177609 -243.832664) (xy 60.178188 -243.837968) (xy 60.178188 -244.332506) (xy 60.177656 -244.337864)
			(xy 60.170084 -244.345448) (xy 60.164726 -244.345968) (xy 59.648598 -244.345968) (xy 59.640787 -244.34627)
			(xy 59.625915 -244.351063) (xy 59.619388 -244.355366) (xy 59.598299 -244.369715) (xy 59.552638 -244.392446)
			(xy 59.504032 -244.407905) (xy 59.453629 -244.415728) (xy 59.402623 -244.415728) (xy 59.35222 -244.407905)
			(xy 59.303614 -244.392446) (xy 59.257953 -244.369715) (xy 59.236864 -244.355366) (xy 59.230336 -244.351069)
			(xy 59.215463 -244.346288) (xy 59.207654 -244.345968) (xy 58.691526 -244.345968) (xy 58.686096 -244.345604)
			(xy 58.678409 -244.337935) (xy 58.678064 -244.332506) (xy 52.63388 -244.332506) (xy 52.633383 -244.337806)
			(xy 52.625962 -244.345376) (xy 52.620672 -244.345968) (xy 52.104798 -244.345968) (xy 52.096987 -244.34627)
			(xy 52.082115 -244.351063) (xy 52.075588 -244.355366) (xy 52.054468 -244.369718) (xy 52.008744 -244.392444)
			(xy 51.96007 -244.407873) (xy 51.909603 -244.415639) (xy 51.884072 -244.416072) (xy 51.858541 -244.415648)
			(xy 51.808077 -244.407868) (xy 51.759405 -244.392435) (xy 51.713678 -244.369715) (xy 51.692556 -244.355366)
			(xy 51.68603 -244.351065) (xy 51.671156 -244.346287) (xy 51.663346 -244.345968) (xy 51.147472 -244.345968)
			(xy 51.142126 -244.345688) (xy 51.134584 -244.338108) (xy 51.134264 -244.33276) (xy 45.090055 -244.33276)
			(xy 45.089556 -244.337866) (xy 45.081978 -244.345451) (xy 45.076618 -244.345968) (xy 44.560744 -244.345968)
			(xy 44.552934 -244.346289) (xy 44.538062 -244.351069) (xy 44.531534 -244.355366) (xy 44.510429 -244.369742)
			(xy 44.464699 -244.392462) (xy 44.416021 -244.407885) (xy 44.36555 -244.415643) (xy 44.340018 -244.416072)
			(xy 44.314488 -244.415625) (xy 44.264025 -244.407852) (xy 44.215352 -244.392426) (xy 44.169624 -244.369712)
			(xy 44.148502 -244.355366) (xy 44.141965 -244.351083) (xy 44.127099 -244.346294) (xy 44.119292 -244.345968)
			(xy 43.603418 -244.345968) (xy 43.597987 -244.345609) (xy 43.5903 -244.337936) (xy 43.589956 -244.332506)
			(xy 37.545772 -244.332506) (xy 37.545282 -244.337808) (xy 37.537856 -244.345378) (xy 37.532564 -244.345968)
			(xy 37.01669 -244.345968) (xy 37.008878 -244.346266) (xy 36.994007 -244.351062) (xy 36.98748 -244.355366)
			(xy 36.966363 -244.369722) (xy 36.920637 -244.392447) (xy 36.871963 -244.407875) (xy 36.821495 -244.41564)
			(xy 36.795964 -244.416072) (xy 36.770433 -244.415652) (xy 36.719969 -244.407871) (xy 36.671296 -244.392437)
			(xy 36.625569 -244.369716) (xy 36.604448 -244.355366) (xy 36.597923 -244.351062) (xy 36.583048 -244.346286)
			(xy 36.575238 -244.345968) (xy 36.059364 -244.345968) (xy 36.054017 -244.345693) (xy 36.046476 -244.338109)
			(xy 36.046156 -244.33276) (xy 30.001949 -244.33276) (xy 30.001482 -244.337808) (xy 29.994056 -244.345378)
			(xy 29.988764 -244.345968) (xy 29.47289 -244.345968) (xy 29.465078 -244.346266) (xy 29.450207 -244.351062)
			(xy 29.44368 -244.355366) (xy 29.422563 -244.369722) (xy 29.376837 -244.392447) (xy 29.328163 -244.407875)
			(xy 29.277695 -244.41564) (xy 29.252164 -244.416072) (xy 29.226633 -244.415652) (xy 29.176169 -244.407871)
			(xy 29.127496 -244.392437) (xy 29.081769 -244.369716) (xy 29.060648 -244.355366) (xy 29.054123 -244.351062)
			(xy 29.039248 -244.346286) (xy 29.031438 -244.345968) (xy 28.515564 -244.345968) (xy 28.510217 -244.345693)
			(xy 28.502676 -244.338109) (xy 28.502356 -244.33276) (xy 22.458148 -244.33276) (xy 22.457655 -244.337868)
			(xy 22.450072 -244.345453) (xy 22.44471 -244.345968) (xy 21.928836 -244.345968) (xy 21.921026 -244.346286)
			(xy 21.906154 -244.351068) (xy 21.899626 -244.355366) (xy 21.878496 -244.369702) (xy 21.832775 -244.392431)
			(xy 21.784104 -244.407865) (xy 21.73364 -244.415636) (xy 21.70811 -244.416072) (xy 21.68258 -244.415629)
			(xy 21.632116 -244.407855) (xy 21.583444 -244.392428) (xy 21.537716 -244.369713) (xy 21.516594 -244.355366)
			(xy 21.510059 -244.35108) (xy 21.495192 -244.346293) (xy 21.487384 -244.345968) (xy 20.97151 -244.345968)
			(xy 20.966078 -244.345615) (xy 20.958392 -244.337938) (xy 20.958048 -244.332506) (xy 2.509012 -244.332506)
			(xy 2.509012 -244.4844) (xy 97.374883 -244.4844) (xy 97.379059 -244.434011) (xy 97.391472 -244.384997)
			(xy 97.411784 -244.338695) (xy 97.43944 -244.296368) (xy 97.473686 -244.259171) (xy 97.513588 -244.228118)
			(xy 97.558057 -244.204057) (xy 97.605881 -244.187644) (xy 97.655753 -244.179326) (xy 97.681034 -244.178836)
			(xy 98.621088 -244.178836) (xy 98.646367 -244.179332) (xy 98.696236 -244.187652) (xy 98.744056 -244.204067)
			(xy 98.788521 -244.228129) (xy 98.82842 -244.259181) (xy 98.862663 -244.296378) (xy 98.890316 -244.338703)
			(xy 98.910626 -244.385003) (xy 98.923037 -244.434014) (xy 98.927213 -244.4844) (xy 100.194783 -244.4844)
			(xy 100.198959 -244.434011) (xy 100.211373 -244.384996) (xy 100.231685 -244.338693) (xy 100.259342 -244.296365)
			(xy 100.293589 -244.259168) (xy 100.333492 -244.228115) (xy 100.377963 -244.204054) (xy 100.425787 -244.187642)
			(xy 100.475661 -244.179326) (xy 100.500942 -244.178836) (xy 101.440996 -244.178836) (xy 101.466275 -244.179333)
			(xy 101.516143 -244.187654) (xy 101.563961 -244.204069) (xy 101.608426 -244.228131) (xy 101.648323 -244.259184)
			(xy 101.682565 -244.29638) (xy 101.710217 -244.338705) (xy 101.730526 -244.385005) (xy 101.742937 -244.434015)
			(xy 101.747113 -244.4844) (xy 103.014983 -244.4844) (xy 103.019159 -244.434014) (xy 103.03157 -244.385003)
			(xy 103.051879 -244.338704) (xy 103.079532 -244.296378) (xy 103.113774 -244.259181) (xy 103.153672 -244.228128)
			(xy 103.198137 -244.204065) (xy 103.245956 -244.18765) (xy 103.295825 -244.179329) (xy 103.321104 -244.178836)
			(xy 104.261158 -244.178836) (xy 104.286439 -244.17933) (xy 104.336312 -244.187646) (xy 104.384136 -244.204058)
			(xy 104.428605 -244.228118) (xy 104.468508 -244.259171) (xy 104.502755 -244.296368) (xy 104.530412 -244.338695)
			(xy 104.550724 -244.384997) (xy 104.563137 -244.434011) (xy 104.567313 -244.4844) (xy 105.834883 -244.4844)
			(xy 105.839059 -244.434014) (xy 105.851471 -244.385002) (xy 105.87178 -244.338701) (xy 105.899434 -244.296375)
			(xy 105.933678 -244.259178) (xy 105.973577 -244.228125) (xy 106.018043 -244.204063) (xy 106.065863 -244.187648)
			(xy 106.115732 -244.179328) (xy 106.141012 -244.178836) (xy 107.081066 -244.178836) (xy 107.106346 -244.17933)
			(xy 107.156218 -244.187647) (xy 107.204041 -244.20406) (xy 107.24851 -244.228121) (xy 107.288411 -244.259174)
			(xy 107.322657 -244.29637) (xy 107.346434 -244.33276) (xy 167.778176 -244.33276) (xy 167.778176 -244.332252)
			(xy 167.778176 -243.837968) (xy 167.778672 -243.832705) (xy 167.786121 -243.825265) (xy 167.791384 -243.82476)
			(xy 168.307258 -243.82476) (xy 168.315134 -243.824488) (xy 168.330138 -243.819694) (xy 168.336722 -243.815362)
			(xy 168.357804 -243.800977) (xy 168.403447 -243.778147) (xy 168.452052 -243.762587) (xy 168.502468 -243.754666)
			(xy 168.527984 -243.754148) (xy 168.553504 -243.754638) (xy 168.603931 -243.762534) (xy 168.652542 -243.778094)
			(xy 168.698181 -243.800948) (xy 168.719246 -243.815362) (xy 168.725828 -243.819694) (xy 168.740835 -243.824471)
			(xy 168.74871 -243.82476) (xy 169.264584 -243.82476) (xy 169.269837 -243.825302) (xy 169.277279 -243.832717)
			(xy 169.277792 -243.837968) (xy 169.277792 -244.332506) (xy 175.321976 -244.332506) (xy 175.321976 -243.837968)
			(xy 175.322472 -243.832705) (xy 175.329921 -243.825265) (xy 175.335184 -243.82476) (xy 175.335692 -243.82476)
			(xy 175.851312 -243.82476) (xy 175.859186 -243.824468) (xy 175.87419 -243.819687) (xy 175.880776 -243.815362)
			(xy 175.901843 -243.800954) (xy 175.947491 -243.778129) (xy 175.996101 -243.762576) (xy 176.04652 -243.754662)
			(xy 176.072038 -243.754148) (xy 176.097557 -243.754661) (xy 176.147983 -243.76255) (xy 176.196594 -243.778103)
			(xy 176.242234 -243.800951) (xy 176.2633 -243.815362) (xy 176.269892 -243.819676) (xy 176.284892 -243.824464)
			(xy 176.292764 -243.82476) (xy 176.808638 -243.82476) (xy 176.813951 -243.8252) (xy 176.821521 -243.832662)
			(xy 176.8221 -243.837968) (xy 176.8221 -244.332506) (xy 176.822074 -244.33276) (xy 182.866284 -244.33276)
			(xy 182.866284 -244.332252) (xy 182.866284 -243.837968) (xy 182.866773 -243.832703) (xy 182.874226 -243.825263)
			(xy 182.879492 -243.82476) (xy 183.395366 -243.82476) (xy 183.403242 -243.824492) (xy 183.418246 -243.819695)
			(xy 183.42483 -243.815362) (xy 183.44591 -243.800974) (xy 183.491554 -243.778144) (xy 183.540159 -243.762586)
			(xy 183.590575 -243.754666) (xy 183.616092 -243.754148) (xy 183.641612 -243.754634) (xy 183.692039 -243.762531)
			(xy 183.74065 -243.778093) (xy 183.786289 -243.800947) (xy 183.807354 -243.815362) (xy 183.813934 -243.819697)
			(xy 183.828943 -243.824472) (xy 183.836818 -243.82476) (xy 184.352692 -243.82476) (xy 184.357946 -243.825297)
			(xy 184.365387 -243.832715) (xy 184.3659 -243.837968) (xy 184.3659 -244.332506) (xy 190.410084 -244.332506)
			(xy 190.410084 -243.837968) (xy 190.410573 -243.832703) (xy 190.418026 -243.825263) (xy 190.423292 -243.82476)
			(xy 190.4238 -243.82476) (xy 190.93942 -243.82476) (xy 190.947294 -243.824471) (xy 190.962298 -243.819688)
			(xy 190.968884 -243.815362) (xy 190.989948 -243.80095) (xy 191.035598 -243.778126) (xy 191.084208 -243.762574)
			(xy 191.134628 -243.754662) (xy 191.160146 -243.754148) (xy 191.185665 -243.754657) (xy 191.236091 -243.762547)
			(xy 191.284702 -243.778102) (xy 191.330342 -243.80095) (xy 191.351408 -243.815362) (xy 191.357998 -243.819679)
			(xy 191.372999 -243.824465) (xy 191.380872 -243.82476) (xy 191.896746 -243.82476) (xy 191.902048 -243.825261)
			(xy 191.909624 -243.832677) (xy 191.910208 -243.837968) (xy 191.910208 -244.332506) (xy 191.910182 -244.33276)
			(xy 197.954392 -244.33276) (xy 197.954392 -244.332252) (xy 197.954392 -243.837968) (xy 197.954873 -243.832701)
			(xy 197.962332 -243.825261) (xy 197.9676 -243.82476) (xy 198.48322 -243.82476) (xy 198.491094 -243.824471)
			(xy 198.506098 -243.819688) (xy 198.512684 -243.815362) (xy 198.533748 -243.80095) (xy 198.579398 -243.778126)
			(xy 198.628008 -243.762574) (xy 198.678428 -243.754662) (xy 198.703946 -243.754148) (xy 198.729465 -243.754657)
			(xy 198.779891 -243.762547) (xy 198.828502 -243.778102) (xy 198.874142 -243.80095) (xy 198.895208 -243.815362)
			(xy 198.901798 -243.819679) (xy 198.916799 -243.824465) (xy 198.924672 -243.82476) (xy 199.4408 -243.82476)
			(xy 199.446055 -243.825292) (xy 199.453496 -243.832714) (xy 199.454008 -243.837968) (xy 199.454008 -244.332506)
			(xy 199.453983 -244.33276) (xy 205.498192 -244.33276) (xy 205.498192 -244.332252) (xy 205.498192 -243.837968)
			(xy 205.498673 -243.832701) (xy 205.506132 -243.825261) (xy 205.5114 -243.82476) (xy 206.027528 -243.82476)
			(xy 206.03534 -243.824465) (xy 206.050211 -243.819667) (xy 206.056738 -243.815362) (xy 206.077827 -243.801013)
			(xy 206.123488 -243.778282) (xy 206.172094 -243.762823) (xy 206.222497 -243.755) (xy 206.273503 -243.755)
			(xy 206.323906 -243.762823) (xy 206.372512 -243.778282) (xy 206.418173 -243.801013) (xy 206.439262 -243.815362)
			(xy 206.445805 -243.819634) (xy 206.460666 -243.824429) (xy 206.468472 -243.82476) (xy 206.9846 -243.82476)
			(xy 206.989855 -243.825292) (xy 206.997296 -243.832714) (xy 206.997808 -243.837968) (xy 206.997808 -244.332252)
			(xy 268.898116 -244.332252) (xy 268.898116 -243.837714) (xy 268.898657 -243.832357) (xy 268.906222 -243.824772)
			(xy 268.911578 -243.824252) (xy 269.427706 -243.824252) (xy 269.435517 -243.823949) (xy 269.450389 -243.819157)
			(xy 269.456916 -243.814854) (xy 269.478005 -243.800505) (xy 269.523666 -243.777774) (xy 269.572272 -243.762315)
			(xy 269.622675 -243.754492) (xy 269.673681 -243.754492) (xy 269.724084 -243.762315) (xy 269.77269 -243.777774)
			(xy 269.818351 -243.800505) (xy 269.83944 -243.814854) (xy 269.845966 -243.819155) (xy 269.86084 -243.823933)
			(xy 269.86865 -243.824252) (xy 270.384778 -243.824252) (xy 270.390213 -243.824596) (xy 270.397901 -243.832279)
			(xy 270.39824 -243.837714) (xy 270.39824 -244.332252) (xy 276.442424 -244.332252) (xy 276.442424 -243.837714)
			(xy 276.442931 -243.832415) (xy 276.450345 -243.824844) (xy 276.455632 -243.824252) (xy 276.97176 -243.824252)
			(xy 276.979569 -243.823929) (xy 276.994441 -243.81915) (xy 277.00097 -243.814854) (xy 277.022059 -243.800505)
			(xy 277.06772 -243.777774) (xy 277.116326 -243.762315) (xy 277.166729 -243.754492) (xy 277.217735 -243.754492)
			(xy 277.268138 -243.762315) (xy 277.316744 -243.777774) (xy 277.362405 -243.800505) (xy 277.383494 -243.814854)
			(xy 277.39003 -243.819137) (xy 277.404897 -243.823926) (xy 277.412704 -243.824252) (xy 277.928832 -243.824252)
			(xy 277.934089 -243.824769) (xy 277.941527 -243.832203) (xy 277.94204 -243.83746) (xy 277.94204 -243.837968)
			(xy 277.94204 -244.332252) (xy 283.986224 -244.332252) (xy 283.986224 -243.837714) (xy 283.986731 -243.832415)
			(xy 283.994145 -243.824844) (xy 283.999432 -243.824252) (xy 284.51556 -243.824252) (xy 284.523369 -243.823929)
			(xy 284.538241 -243.81915) (xy 284.54477 -243.814854) (xy 284.565859 -243.800505) (xy 284.61152 -243.777774)
			(xy 284.660126 -243.762315) (xy 284.710529 -243.754492) (xy 284.761535 -243.754492) (xy 284.811938 -243.762315)
			(xy 284.860544 -243.777774) (xy 284.906205 -243.800505) (xy 284.927294 -243.814854) (xy 284.93383 -243.819137)
			(xy 284.948697 -243.823926) (xy 284.956504 -243.824252) (xy 285.472632 -243.824252) (xy 285.477889 -243.824769)
			(xy 285.485327 -243.832203) (xy 285.48584 -243.83746) (xy 285.48584 -243.837968) (xy 285.48584 -244.332252)
			(xy 291.530024 -244.332252) (xy 291.530024 -243.837714) (xy 291.530558 -243.832355) (xy 291.538128 -243.824769)
			(xy 291.543486 -243.824252) (xy 292.059614 -243.824252) (xy 292.067426 -243.823953) (xy 292.082297 -243.819158)
			(xy 292.088824 -243.814854) (xy 292.109913 -243.800505) (xy 292.155574 -243.777774) (xy 292.20418 -243.762315)
			(xy 292.254583 -243.754492) (xy 292.305589 -243.754492) (xy 292.355992 -243.762315) (xy 292.404598 -243.777774)
			(xy 292.450259 -243.800505) (xy 292.471348 -243.814854) (xy 292.477872 -243.819158) (xy 292.492748 -243.823934)
			(xy 292.500558 -243.824252) (xy 293.016686 -243.824252) (xy 293.022122 -243.82459) (xy 293.02981 -243.832278)
			(xy 293.030148 -243.837714) (xy 293.030148 -244.332252) (xy 299.074332 -244.332252) (xy 299.074332 -243.837714)
			(xy 299.074832 -243.832413) (xy 299.08225 -243.824842) (xy 299.08754 -243.824252) (xy 299.603668 -243.824252)
			(xy 299.611478 -243.823933) (xy 299.626349 -243.819151) (xy 299.632878 -243.814854) (xy 299.653967 -243.800505)
			(xy 299.699628 -243.777774) (xy 299.748234 -243.762315) (xy 299.798637 -243.754492) (xy 299.849643 -243.754492)
			(xy 299.900046 -243.762315) (xy 299.948652 -243.777774) (xy 299.994313 -243.800505) (xy 300.015402 -243.814854)
			(xy 300.021937 -243.81914) (xy 300.036804 -243.823927) (xy 300.044612 -243.824252) (xy 300.56074 -243.824252)
			(xy 300.565998 -243.824764) (xy 300.573436 -243.832202) (xy 300.573948 -243.83746) (xy 300.573948 -243.837968)
			(xy 300.573948 -244.332252) (xy 306.618132 -244.332252) (xy 306.618132 -243.837714) (xy 306.618488 -243.832283)
			(xy 306.626163 -243.824596) (xy 306.631594 -243.824252) (xy 307.147722 -243.824252) (xy 307.155534 -243.823956)
			(xy 307.170405 -243.819159) (xy 307.176932 -243.814854) (xy 307.198021 -243.800505) (xy 307.243682 -243.777774)
			(xy 307.292288 -243.762315) (xy 307.342691 -243.754492) (xy 307.393697 -243.754492) (xy 307.4441 -243.762315)
			(xy 307.492706 -243.777774) (xy 307.538367 -243.800505) (xy 307.559456 -243.814854) (xy 307.565979 -243.819161)
			(xy 307.580855 -243.823935) (xy 307.588666 -243.824252) (xy 308.104794 -243.824252) (xy 308.110231 -243.824585)
			(xy 308.117919 -243.832276) (xy 308.118256 -243.837714) (xy 308.118256 -244.332252) (xy 308.117678 -244.337498)
			(xy 308.11029 -244.34494) (xy 308.105048 -244.34546) (xy 308.10454 -244.34546) (xy 307.58892 -244.34546)
			(xy 307.581047 -244.345762) (xy 307.566043 -244.350536) (xy 307.559456 -244.354858) (xy 307.538382 -244.369255)
			(xy 307.492736 -244.392082) (xy 307.444129 -244.407638) (xy 307.393711 -244.415555) (xy 307.368194 -244.416072)
			(xy 307.342675 -244.415557) (xy 307.292249 -244.407671) (xy 307.243637 -244.392119) (xy 307.197998 -244.36927)
			(xy 307.176932 -244.354858) (xy 307.170332 -244.350558) (xy 307.155339 -244.345761) (xy 307.147468 -244.34546)
			(xy 306.631594 -244.34546) (xy 306.626289 -244.344981) (xy 306.618718 -244.337547) (xy 306.618132 -244.332252)
			(xy 300.573948 -244.332252) (xy 300.573545 -244.337568) (xy 300.566054 -244.345109) (xy 300.56074 -244.34546)
			(xy 300.044866 -244.34546) (xy 300.036991 -244.345739) (xy 300.021987 -244.350529) (xy 300.015402 -244.354858)
			(xy 299.994315 -244.369235) (xy 299.948674 -244.392066) (xy 299.90007 -244.407628) (xy 299.849656 -244.415552)
			(xy 299.82414 -244.416072) (xy 299.79862 -244.415584) (xy 299.748192 -244.40769) (xy 299.699581 -244.39213)
			(xy 299.653943 -244.369274) (xy 299.632878 -244.354858) (xy 299.62629 -244.350537) (xy 299.611287 -244.345753)
			(xy 299.603414 -244.34546) (xy 299.08754 -244.34546) (xy 299.082201 -244.345141) (xy 299.074655 -244.337591)
			(xy 299.074332 -244.332252) (xy 293.030148 -244.332252) (xy 293.029745 -244.337568) (xy 293.022254 -244.345109)
			(xy 293.01694 -244.34546) (xy 293.016432 -244.34546) (xy 292.500812 -244.34546) (xy 292.492938 -244.345759)
			(xy 292.477934 -244.350535) (xy 292.471348 -244.354858) (xy 292.450276 -244.369258) (xy 292.404629 -244.392084)
			(xy 292.356021 -244.40764) (xy 292.305603 -244.415556) (xy 292.280086 -244.416072) (xy 292.254567 -244.415561)
			(xy 292.20414 -244.407674) (xy 292.155528 -244.39212) (xy 292.109889 -244.369271) (xy 292.088824 -244.354858)
			(xy 292.082225 -244.350555) (xy 292.067231 -244.34576) (xy 292.05936 -244.34546) (xy 291.543486 -244.34546)
			(xy 291.53818 -244.344986) (xy 291.53061 -244.337548) (xy 291.530024 -244.332252) (xy 285.48584 -244.332252)
			(xy 285.485444 -244.33757) (xy 285.477948 -244.345112) (xy 285.472632 -244.34546) (xy 284.956758 -244.34546)
			(xy 284.948882 -244.345736) (xy 284.933878 -244.350528) (xy 284.927294 -244.354858) (xy 284.906209 -244.369238)
			(xy 284.860567 -244.392069) (xy 284.811963 -244.40763) (xy 284.761548 -244.415553) (xy 284.736032 -244.416072)
			(xy 284.710512 -244.415588) (xy 284.660084 -244.407693) (xy 284.611472 -244.392131) (xy 284.565834 -244.369274)
			(xy 284.54477 -244.354858) (xy 284.538184 -244.350534) (xy 284.52318 -244.345752) (xy 284.515306 -244.34546)
			(xy 283.999432 -244.34546) (xy 283.994092 -244.345147) (xy 283.986547 -244.337592) (xy 283.986224 -244.332252)
			(xy 277.94204 -244.332252) (xy 277.941644 -244.33757) (xy 277.934148 -244.345112) (xy 277.928832 -244.34546)
			(xy 277.412958 -244.34546) (xy 277.405082 -244.345736) (xy 277.390078 -244.350528) (xy 277.383494 -244.354858)
			(xy 277.362409 -244.369238) (xy 277.316767 -244.392069) (xy 277.268163 -244.40763) (xy 277.217748 -244.415553)
			(xy 277.192232 -244.416072) (xy 277.166712 -244.415588) (xy 277.116284 -244.407693) (xy 277.067672 -244.392131)
			(xy 277.022034 -244.369274) (xy 277.00097 -244.354858) (xy 276.994384 -244.350534) (xy 276.97938 -244.345752)
			(xy 276.971506 -244.34546) (xy 276.455632 -244.34546) (xy 276.450292 -244.345147) (xy 276.442747 -244.337592)
			(xy 276.442424 -244.332252) (xy 270.39824 -244.332252) (xy 270.397844 -244.33757) (xy 270.390348 -244.345112)
			(xy 270.385032 -244.34546) (xy 270.384524 -244.34546) (xy 269.868904 -244.34546) (xy 269.86103 -244.345755)
			(xy 269.846026 -244.350534) (xy 269.83944 -244.354858) (xy 269.81837 -244.369262) (xy 269.772723 -244.392087)
			(xy 269.724114 -244.407641) (xy 269.673695 -244.415557) (xy 269.648178 -244.416072) (xy 269.622658 -244.415565)
			(xy 269.572232 -244.407677) (xy 269.52362 -244.392122) (xy 269.477981 -244.369271) (xy 269.456916 -244.354858)
			(xy 269.450319 -244.350552) (xy 269.435323 -244.345759) (xy 269.427452 -244.34546) (xy 268.911578 -244.34546)
			(xy 268.906271 -244.344991) (xy 268.898701 -244.33755) (xy 268.898116 -244.332252) (xy 206.997808 -244.332252)
			(xy 206.997808 -244.332506) (xy 206.997287 -244.3378) (xy 206.989882 -244.345368) (xy 206.9846 -244.345968)
			(xy 206.468726 -244.345968) (xy 206.460916 -244.346281) (xy 206.446044 -244.351066) (xy 206.439516 -244.355366)
			(xy 206.418389 -244.369706) (xy 206.372667 -244.392435) (xy 206.323995 -244.407867) (xy 206.27353 -244.415637)
			(xy 206.248 -244.416072) (xy 206.22247 -244.415634) (xy 206.172006 -244.407858) (xy 206.123334 -244.39243)
			(xy 206.077606 -244.369713) (xy 206.056484 -244.355366) (xy 206.049951 -244.351076) (xy 206.035082 -244.346291)
			(xy 206.027274 -244.345968) (xy 205.5114 -244.345968) (xy 205.506058 -244.345669) (xy 205.498515 -244.338103)
			(xy 205.498192 -244.33276) (xy 199.453983 -244.33276) (xy 199.453487 -244.3378) (xy 199.446082 -244.345368)
			(xy 199.4408 -244.345968) (xy 198.924926 -244.345968) (xy 198.917116 -244.346281) (xy 198.902244 -244.351066)
			(xy 198.895716 -244.355366) (xy 198.874589 -244.369706) (xy 198.828867 -244.392435) (xy 198.780195 -244.407867)
			(xy 198.72973 -244.415637) (xy 198.7042 -244.416072) (xy 198.67867 -244.415634) (xy 198.628206 -244.407858)
			(xy 198.579534 -244.39243) (xy 198.533806 -244.369713) (xy 198.512684 -244.355366) (xy 198.506151 -244.351076)
			(xy 198.491282 -244.346291) (xy 198.483474 -244.345968) (xy 197.9676 -244.345968) (xy 197.962258 -244.345669)
			(xy 197.954715 -244.338103) (xy 197.954392 -244.33276) (xy 191.910182 -244.33276) (xy 191.909658 -244.33786)
			(xy 191.902098 -244.345442) (xy 191.896746 -244.345968) (xy 191.380872 -244.345968) (xy 191.37306 -244.346258)
			(xy 191.358188 -244.351059) (xy 191.351662 -244.355366) (xy 191.33055 -244.36973) (xy 191.284822 -244.392453)
			(xy 191.236146 -244.407879) (xy 191.185678 -244.415641) (xy 191.160146 -244.416072) (xy 191.134617 -244.415611)
			(xy 191.084154 -244.407842) (xy 191.035481 -244.39242) (xy 190.989753 -244.36971) (xy 190.96863 -244.355366)
			(xy 190.962087 -244.351094) (xy 190.947226 -244.346298) (xy 190.93942 -244.345968) (xy 190.423546 -244.345968)
			(xy 190.418119 -244.345591) (xy 190.41043 -244.337932) (xy 190.410084 -244.332506) (xy 184.3659 -244.332506)
			(xy 184.365386 -244.337802) (xy 184.357976 -244.34537) (xy 184.352692 -244.345968) (xy 183.836818 -244.345968)
			(xy 183.829007 -244.346278) (xy 183.814136 -244.351065) (xy 183.807608 -244.355366) (xy 183.786483 -244.36971)
			(xy 183.74076 -244.392437) (xy 183.692088 -244.407869) (xy 183.641623 -244.415638) (xy 183.616092 -244.416072)
			(xy 183.590562 -244.415638) (xy 183.540098 -244.407861) (xy 183.491425 -244.392431) (xy 183.445698 -244.369714)
			(xy 183.424576 -244.355366) (xy 183.418045 -244.351073) (xy 183.403175 -244.34629) (xy 183.395366 -244.345968)
			(xy 182.879492 -244.345968) (xy 182.874149 -244.345675) (xy 182.866606 -244.338104) (xy 182.866284 -244.33276)
			(xy 176.822074 -244.33276) (xy 176.821558 -244.337862) (xy 176.813992 -244.345445) (xy 176.808638 -244.345968)
			(xy 176.292764 -244.345968) (xy 176.284955 -244.346297) (xy 176.270083 -244.351071) (xy 176.263554 -244.355366)
			(xy 176.242444 -244.369733) (xy 176.196716 -244.392455) (xy 176.148039 -244.40788) (xy 176.09757 -244.415642)
			(xy 176.072038 -244.416072) (xy 176.046509 -244.415615) (xy 175.996046 -244.407845) (xy 175.947373 -244.392422)
			(xy 175.901645 -244.369711) (xy 175.880522 -244.355366) (xy 175.873981 -244.351091) (xy 175.859118 -244.346297)
			(xy 175.851312 -244.345968) (xy 175.335438 -244.345968) (xy 175.33001 -244.345596) (xy 175.322322 -244.337933)
			(xy 175.321976 -244.332506) (xy 169.277792 -244.332506) (xy 169.277285 -244.337803) (xy 169.26987 -244.345372)
			(xy 169.264584 -244.345968) (xy 168.748456 -244.345968) (xy 168.740647 -244.346294) (xy 168.725775 -244.35107)
			(xy 168.719246 -244.355366) (xy 168.698157 -244.369715) (xy 168.652496 -244.392446) (xy 168.60389 -244.407905)
			(xy 168.553487 -244.415728) (xy 168.502481 -244.415728) (xy 168.452078 -244.407905) (xy 168.403472 -244.392446)
			(xy 168.357811 -244.369715) (xy 168.336722 -244.355366) (xy 168.330181 -244.351091) (xy 168.315318 -244.346297)
			(xy 168.307512 -244.345968) (xy 167.791384 -244.345968) (xy 167.78604 -244.34568) (xy 167.778497 -244.338106)
			(xy 167.778176 -244.33276) (xy 107.346434 -244.33276) (xy 107.350313 -244.338697) (xy 107.370624 -244.384999)
			(xy 107.383037 -244.434012) (xy 107.387188 -244.4841) (xy 364.108984 -244.4841) (xy 364.113155 -244.433763)
			(xy 364.125555 -244.384799) (xy 364.145845 -244.338543) (xy 364.173472 -244.296259) (xy 364.207683 -244.259098)
			(xy 364.247543 -244.228076) (xy 364.291966 -244.204037) (xy 364.33974 -244.187639) (xy 364.389561 -244.179327)
			(xy 364.414816 -244.178836) (xy 365.35487 -244.178836) (xy 365.380133 -244.179238) (xy 365.42997 -244.18755)
			(xy 365.47776 -244.203952) (xy 365.522198 -244.227997) (xy 365.562072 -244.259028) (xy 365.596293 -244.2962)
			(xy 365.62393 -244.338497) (xy 365.644227 -244.384767) (xy 365.656631 -244.433747) (xy 365.660804 -244.4841)
			(xy 366.928884 -244.4841) (xy 366.933055 -244.433762) (xy 366.945456 -244.384797) (xy 366.965746 -244.338541)
			(xy 366.993374 -244.296256) (xy 367.027586 -244.259095) (xy 367.067447 -244.228073) (xy 367.111871 -244.204035)
			(xy 367.159646 -244.187637) (xy 367.209469 -244.179327) (xy 367.234724 -244.178836) (xy 368.174778 -244.178836)
			(xy 368.200041 -244.179239) (xy 368.249877 -244.187552) (xy 368.297665 -244.203955) (xy 368.342102 -244.228)
			(xy 368.381975 -244.259031) (xy 368.416196 -244.296203) (xy 368.443831 -244.3385) (xy 368.464128 -244.384769)
			(xy 368.476531 -244.433748) (xy 368.480704 -244.4841) (xy 369.749113 -244.4841) (xy 369.753283 -244.433771)
			(xy 369.76568 -244.384814) (xy 369.785966 -244.338565) (xy 369.813587 -244.296286) (xy 369.847791 -244.25913)
			(xy 369.887643 -244.22811) (xy 369.932057 -244.204073) (xy 369.979822 -244.187673) (xy 370.029635 -244.179359)
			(xy 370.054886 -244.178836) (xy 370.99494 -244.178836) (xy 371.020197 -244.179272) (xy 371.070021 -244.187592)
			(xy 371.117796 -244.203999) (xy 371.162219 -244.228045) (xy 371.202079 -244.259074) (xy 371.236289 -244.296241)
			(xy 371.263916 -244.33853) (xy 371.284205 -244.38479) (xy 371.296604 -244.433759) (xy 371.300776 -244.4841)
			(xy 372.569013 -244.4841) (xy 372.573183 -244.43377) (xy 372.585581 -244.384812) (xy 372.605867 -244.338563)
			(xy 372.63349 -244.296284) (xy 372.667694 -244.259127) (xy 372.707547 -244.228107) (xy 372.751963 -244.20407)
			(xy 372.799729 -244.187671) (xy 372.849543 -244.179358) (xy 372.874794 -244.178836) (xy 373.814848 -244.178836)
			(xy 373.840104 -244.179273) (xy 373.889927 -244.187594) (xy 373.937701 -244.204002) (xy 373.982123 -244.228048)
			(xy 374.021982 -244.259077) (xy 374.056191 -244.296243) (xy 374.079714 -244.332252) (xy 415.718244 -244.332252)
			(xy 415.718244 -243.837714) (xy 415.718733 -243.832411) (xy 415.726159 -243.824839) (xy 415.731452 -243.824252)
			(xy 416.24758 -243.824252) (xy 416.25539 -243.823938) (xy 416.270262 -243.819153) (xy 416.27679 -243.814854)
			(xy 416.297879 -243.800505) (xy 416.34354 -243.777774) (xy 416.392146 -243.762315) (xy 416.442549 -243.754492)
			(xy 416.493555 -243.754492) (xy 416.543958 -243.762315) (xy 416.592564 -243.777774) (xy 416.638225 -243.800505)
			(xy 416.659314 -243.814854) (xy 416.665846 -243.819145) (xy 416.680716 -243.823929) (xy 416.688524 -243.824252)
			(xy 417.204652 -243.824252) (xy 417.209968 -243.824655) (xy 417.217509 -243.832146) (xy 417.21786 -243.83746)
			(xy 417.21786 -243.837968) (xy 417.21786 -244.332252) (xy 423.262044 -244.332252) (xy 423.262044 -243.837714)
			(xy 423.262389 -243.83228) (xy 423.270072 -243.824593) (xy 423.275506 -243.824252) (xy 423.791634 -243.824252)
			(xy 423.799442 -243.823918) (xy 423.814314 -243.819147) (xy 423.820844 -243.814854) (xy 423.841933 -243.800505)
			(xy 423.887594 -243.777774) (xy 423.9362 -243.762315) (xy 423.986603 -243.754492) (xy 424.037609 -243.754492)
			(xy 424.088012 -243.762315) (xy 424.136618 -243.777774) (xy 424.182279 -243.800505) (xy 424.203368 -243.814854)
			(xy 424.20991 -243.819127) (xy 424.224772 -243.823922) (xy 424.232578 -243.824252) (xy 424.748706 -243.824252)
			(xy 424.754145 -243.824577) (xy 424.761831 -243.832275) (xy 424.762168 -243.837714) (xy 424.762168 -244.332252)
			(xy 430.806352 -244.332252) (xy 430.806352 -243.837714) (xy 430.806834 -243.832409) (xy 430.814265 -243.824836)
			(xy 430.81956 -243.824252) (xy 431.335688 -243.824252) (xy 431.343498 -243.823941) (xy 431.35837 -243.819154)
			(xy 431.364898 -243.814854) (xy 431.385987 -243.800505) (xy 431.431648 -243.777774) (xy 431.480254 -243.762315)
			(xy 431.530657 -243.754492) (xy 431.581663 -243.754492) (xy 431.632066 -243.762315) (xy 431.680672 -243.777774)
			(xy 431.726333 -243.800505) (xy 431.747422 -243.814854) (xy 431.753952 -243.819148) (xy 431.768823 -243.82393)
			(xy 431.776632 -243.824252) (xy 432.29276 -243.824252) (xy 432.298008 -243.824817) (xy 432.305451 -243.832215)
			(xy 432.305968 -243.83746) (xy 432.305968 -243.837968) (xy 432.305968 -244.332252) (xy 438.350152 -244.332252)
			(xy 438.350152 -243.837714) (xy 438.35049 -243.832278) (xy 438.358178 -243.82459) (xy 438.363614 -243.824252)
			(xy 438.879742 -243.824252) (xy 438.887551 -243.823922) (xy 438.902423 -243.819148) (xy 438.908952 -243.814854)
			(xy 438.930041 -243.800505) (xy 438.975702 -243.777774) (xy 439.024308 -243.762315) (xy 439.074711 -243.754492)
			(xy 439.125717 -243.754492) (xy 439.17612 -243.762315) (xy 439.224726 -243.777774) (xy 439.270387 -243.800505)
			(xy 439.291476 -243.814854) (xy 439.298016 -243.81913) (xy 439.312879 -243.823923) (xy 439.320686 -243.824252)
			(xy 439.836814 -243.824252) (xy 439.842183 -243.824743) (xy 439.849769 -243.832344) (xy 439.850276 -243.837714)
			(xy 439.850276 -244.332252) (xy 445.89446 -244.332252) (xy 445.89446 -243.837714) (xy 445.894935 -243.832407)
			(xy 445.902371 -243.824834) (xy 445.907668 -243.824252) (xy 446.423796 -243.824252) (xy 446.431607 -243.823944)
			(xy 446.446478 -243.819155) (xy 446.453006 -243.814854) (xy 446.474095 -243.800505) (xy 446.519756 -243.777774)
			(xy 446.568362 -243.762315) (xy 446.618765 -243.754492) (xy 446.669771 -243.754492) (xy 446.720174 -243.762315)
			(xy 446.76878 -243.777774) (xy 446.814441 -243.800505) (xy 446.83553 -243.814854) (xy 446.842058 -243.819151)
			(xy 446.856931 -243.823931) (xy 446.86474 -243.824252) (xy 447.380868 -243.824252) (xy 447.386117 -243.824812)
			(xy 447.39356 -243.832213) (xy 447.394076 -243.83746) (xy 447.394076 -243.837968) (xy 447.394076 -244.332252)
			(xy 453.43826 -244.332252) (xy 453.43826 -243.837714) (xy 453.438735 -243.832407) (xy 453.446171 -243.824834)
			(xy 453.451468 -243.824252) (xy 453.967596 -243.824252) (xy 453.975407 -243.823944) (xy 453.990278 -243.819155)
			(xy 453.996806 -243.814854) (xy 454.017895 -243.800505) (xy 454.063556 -243.777774) (xy 454.112162 -243.762315)
			(xy 454.162565 -243.754492) (xy 454.213571 -243.754492) (xy 454.263974 -243.762315) (xy 454.31258 -243.777774)
			(xy 454.358241 -243.800505) (xy 454.37933 -243.814854) (xy 454.385858 -243.819151) (xy 454.400731 -243.823931)
			(xy 454.40854 -243.824252) (xy 454.924668 -243.824252) (xy 454.929917 -243.824812) (xy 454.93736 -243.832213)
			(xy 454.937876 -243.83746) (xy 454.937876 -243.837968) (xy 454.937876 -244.332252) (xy 454.937538 -244.337586)
			(xy 454.930001 -244.345131) (xy 454.924668 -244.34546) (xy 454.408794 -244.34546) (xy 454.40092 -244.345751)
			(xy 454.385916 -244.350532) (xy 454.37933 -244.354858) (xy 454.358263 -244.369266) (xy 454.312614 -244.39209)
			(xy 454.264005 -244.407643) (xy 454.213586 -244.415557) (xy 454.188068 -244.416072) (xy 454.162548 -244.41557)
			(xy 454.112122 -244.40768) (xy 454.06351 -244.392124) (xy 454.017871 -244.369272) (xy 453.996806 -244.354858)
			(xy 453.990211 -244.350548) (xy 453.975214 -244.345757) (xy 453.967342 -244.34546) (xy 453.451468 -244.34546)
			(xy 453.44612 -244.34519) (xy 453.438578 -244.337602) (xy 453.43826 -244.332252) (xy 447.394076 -244.332252)
			(xy 447.393738 -244.337586) (xy 447.386201 -244.345131) (xy 447.380868 -244.34546) (xy 446.864994 -244.34546)
			(xy 446.85712 -244.345751) (xy 446.842116 -244.350532) (xy 446.83553 -244.354858) (xy 446.814463 -244.369266)
			(xy 446.768814 -244.39209) (xy 446.720205 -244.407643) (xy 446.669786 -244.415557) (xy 446.644268 -244.416072)
			(xy 446.618748 -244.41557) (xy 446.568322 -244.40768) (xy 446.51971 -244.392124) (xy 446.474071 -244.369272)
			(xy 446.453006 -244.354858) (xy 446.446411 -244.350548) (xy 446.431414 -244.345757) (xy 446.423542 -244.34546)
			(xy 445.907668 -244.34546) (xy 445.90232 -244.34519) (xy 445.894778 -244.337602) (xy 445.89446 -244.332252)
			(xy 439.850276 -244.332252) (xy 439.849938 -244.337586) (xy 439.842401 -244.345131) (xy 439.837068 -244.34546)
			(xy 439.83656 -244.34546) (xy 439.32094 -244.34546) (xy 439.313064 -244.345728) (xy 439.29806 -244.350525)
			(xy 439.291476 -244.354858) (xy 439.270396 -244.369246) (xy 439.224752 -244.392075) (xy 439.176147 -244.407634)
			(xy 439.12573 -244.415554) (xy 439.100214 -244.416072) (xy 439.074693 -244.415597) (xy 439.024265 -244.407699)
			(xy 438.975654 -244.392135) (xy 438.930016 -244.369276) (xy 438.908952 -244.354858) (xy 438.90237 -244.350527)
			(xy 438.887363 -244.345749) (xy 438.879488 -244.34546) (xy 438.363614 -244.34546) (xy 438.358312 -244.344967)
			(xy 438.35074 -244.337544) (xy 438.350152 -244.332252) (xy 432.305968 -244.332252) (xy 432.305637 -244.337587)
			(xy 432.298095 -244.345134) (xy 432.29276 -244.34546) (xy 431.776886 -244.34546) (xy 431.769011 -244.345748)
			(xy 431.754007 -244.350531) (xy 431.747422 -244.354858) (xy 431.726357 -244.369269) (xy 431.680708 -244.392093)
			(xy 431.632098 -244.407645) (xy 431.581678 -244.415558) (xy 431.55616 -244.416072) (xy 431.53064 -244.415574)
			(xy 431.480213 -244.407683) (xy 431.431601 -244.392126) (xy 431.385963 -244.369273) (xy 431.364898 -244.354858)
			(xy 431.358305 -244.350545) (xy 431.343306 -244.345756) (xy 431.335434 -244.34546) (xy 430.81956 -244.34546)
			(xy 430.81421 -244.345195) (xy 430.806669 -244.337603) (xy 430.806352 -244.332252) (xy 424.762168 -244.332252)
			(xy 424.761837 -244.337587) (xy 424.754295 -244.345134) (xy 424.74896 -244.34546) (xy 424.748452 -244.34546)
			(xy 424.232832 -244.34546) (xy 424.224955 -244.345724) (xy 424.209951 -244.350524) (xy 424.203368 -244.354858)
			(xy 424.182291 -244.36925) (xy 424.136646 -244.392078) (xy 424.08804 -244.407635) (xy 424.037623 -244.415555)
			(xy 424.012106 -244.416072) (xy 423.986585 -244.415602) (xy 423.936157 -244.407702) (xy 423.887545 -244.392137)
			(xy 423.841908 -244.369276) (xy 423.820844 -244.354858) (xy 423.814263 -244.350524) (xy 423.799255 -244.345748)
			(xy 423.79138 -244.34546) (xy 423.275506 -244.34546) (xy 423.270203 -244.344973) (xy 423.262631 -244.337545)
			(xy 423.262044 -244.332252) (xy 417.21786 -244.332252) (xy 417.217536 -244.337589) (xy 417.209989 -244.345136)
			(xy 417.204652 -244.34546) (xy 416.688778 -244.34546) (xy 416.680903 -244.345744) (xy 416.665899 -244.35053)
			(xy 416.659314 -244.354858) (xy 416.638252 -244.369273) (xy 416.592601 -244.392096) (xy 416.543991 -244.407647)
			(xy 416.49357 -244.415559) (xy 416.468052 -244.416072) (xy 416.442532 -244.415578) (xy 416.392105 -244.407686)
			(xy 416.343493 -244.392127) (xy 416.297855 -244.369273) (xy 416.27679 -244.354858) (xy 416.270199 -244.350542)
			(xy 416.255199 -244.345755) (xy 416.247326 -244.34546) (xy 415.731452 -244.34546) (xy 415.726172 -244.345032)
			(xy 415.718729 -244.337536) (xy 415.718244 -244.332252) (xy 374.079714 -244.332252) (xy 374.083817 -244.338533)
			(xy 374.104106 -244.384792) (xy 374.116505 -244.43376) (xy 374.120676 -244.4841) (xy 374.116505 -244.53444)
			(xy 374.104106 -244.583408) (xy 374.083817 -244.629667) (xy 374.056191 -244.671957) (xy 374.021982 -244.709123)
			(xy 373.982123 -244.740152) (xy 373.937701 -244.764198) (xy 373.889927 -244.780606) (xy 373.840104 -244.788927)
			(xy 373.814848 -244.789452) (xy 372.874794 -244.789452) (xy 372.849543 -244.788842) (xy 372.799729 -244.780529)
			(xy 372.751963 -244.76413) (xy 372.707547 -244.740093) (xy 372.667694 -244.709073) (xy 372.63349 -244.671916)
			(xy 372.605867 -244.629637) (xy 372.585581 -244.583388) (xy 372.573183 -244.53443) (xy 372.569013 -244.4841)
			(xy 371.300776 -244.4841) (xy 371.296604 -244.534441) (xy 371.284205 -244.58341) (xy 371.263915 -244.62967)
			(xy 371.236289 -244.671959) (xy 371.202079 -244.709126) (xy 371.162219 -244.740155) (xy 371.117796 -244.764201)
			(xy 371.070021 -244.780608) (xy 371.020197 -244.788928) (xy 370.99494 -244.789452) (xy 370.054886 -244.789452)
			(xy 370.029635 -244.788841) (xy 369.979822 -244.780527) (xy 369.932057 -244.764127) (xy 369.887643 -244.74009)
			(xy 369.847791 -244.70907) (xy 369.813587 -244.671914) (xy 369.785966 -244.629635) (xy 369.76568 -244.583386)
			(xy 369.753283 -244.534429) (xy 369.749113 -244.4841) (xy 368.480704 -244.4841) (xy 368.476531 -244.534452)
			(xy 368.464128 -244.583431) (xy 368.443831 -244.6297) (xy 368.416196 -244.671997) (xy 368.381975 -244.709169)
			(xy 368.342102 -244.7402) (xy 368.297665 -244.764245) (xy 368.249877 -244.780648) (xy 368.200041 -244.788961)
			(xy 368.174778 -244.789452) (xy 367.234724 -244.789452) (xy 367.209469 -244.788873) (xy 367.159646 -244.780563)
			(xy 367.111871 -244.764165) (xy 367.067447 -244.740127) (xy 367.027586 -244.709105) (xy 366.993374 -244.671944)
			(xy 366.965746 -244.629659) (xy 366.945456 -244.583403) (xy 366.933055 -244.534438) (xy 366.928884 -244.4841)
			(xy 365.660804 -244.4841) (xy 365.656631 -244.534453) (xy 365.644227 -244.583433) (xy 365.62393 -244.629703)
			(xy 365.596293 -244.672) (xy 365.562072 -244.709172) (xy 365.522198 -244.740203) (xy 365.47776 -244.764248)
			(xy 365.42997 -244.78065) (xy 365.380133 -244.788962) (xy 365.35487 -244.789452) (xy 364.414816 -244.789452)
			(xy 364.389561 -244.788873) (xy 364.33974 -244.780561) (xy 364.291966 -244.764163) (xy 364.247543 -244.740124)
			(xy 364.207683 -244.709102) (xy 364.173472 -244.671941) (xy 364.145845 -244.629657) (xy 364.125555 -244.583401)
			(xy 364.113155 -244.534437) (xy 364.108984 -244.4841) (xy 107.387188 -244.4841) (xy 107.387213 -244.4844)
			(xy 107.383037 -244.534788) (xy 107.370624 -244.583801) (xy 107.350313 -244.630103) (xy 107.322657 -244.67243)
			(xy 107.288411 -244.709626) (xy 107.24851 -244.740679) (xy 107.204041 -244.76474) (xy 107.156218 -244.781153)
			(xy 107.106346 -244.78947) (xy 107.081066 -244.78996) (xy 106.141012 -244.78996) (xy 106.115732 -244.789472)
			(xy 106.065863 -244.781152) (xy 106.018043 -244.764737) (xy 105.973577 -244.740675) (xy 105.933678 -244.709622)
			(xy 105.899434 -244.672425) (xy 105.87178 -244.630099) (xy 105.851471 -244.583798) (xy 105.839059 -244.534786)
			(xy 105.834883 -244.4844) (xy 104.567313 -244.4844) (xy 104.563137 -244.534789) (xy 104.550724 -244.583803)
			(xy 104.530412 -244.630105) (xy 104.502755 -244.672432) (xy 104.468508 -244.709629) (xy 104.428605 -244.740682)
			(xy 104.384136 -244.764742) (xy 104.336312 -244.781154) (xy 104.286439 -244.78947) (xy 104.261158 -244.78996)
			(xy 103.321104 -244.78996) (xy 103.295825 -244.789471) (xy 103.245956 -244.78115) (xy 103.198137 -244.764735)
			(xy 103.153672 -244.740672) (xy 103.113774 -244.709619) (xy 103.079532 -244.672422) (xy 103.051879 -244.630096)
			(xy 103.03157 -244.583797) (xy 103.019159 -244.534786) (xy 103.014983 -244.4844) (xy 101.747113 -244.4844)
			(xy 101.742937 -244.534785) (xy 101.730526 -244.583795) (xy 101.710217 -244.630095) (xy 101.682565 -244.67242)
			(xy 101.648323 -244.709616) (xy 101.608426 -244.740669) (xy 101.563961 -244.764731) (xy 101.516143 -244.781146)
			(xy 101.466275 -244.789467) (xy 101.440996 -244.78996) (xy 100.500942 -244.78996) (xy 100.475661 -244.789474)
			(xy 100.425787 -244.781158) (xy 100.377963 -244.764746) (xy 100.333492 -244.740685) (xy 100.293589 -244.709632)
			(xy 100.259342 -244.672435) (xy 100.231685 -244.630107) (xy 100.211373 -244.583804) (xy 100.198959 -244.534789)
			(xy 100.194783 -244.4844) (xy 98.927213 -244.4844) (xy 98.923037 -244.534786) (xy 98.910626 -244.583797)
			(xy 98.890316 -244.630097) (xy 98.862663 -244.672422) (xy 98.82842 -244.709619) (xy 98.788521 -244.740671)
			(xy 98.744056 -244.764733) (xy 98.696236 -244.781148) (xy 98.646367 -244.789468) (xy 98.621088 -244.78996)
			(xy 97.681034 -244.78996) (xy 97.655753 -244.789474) (xy 97.605881 -244.781156) (xy 97.558057 -244.764743)
			(xy 97.513588 -244.740682) (xy 97.473686 -244.709629) (xy 97.43944 -244.672432) (xy 97.411784 -244.630105)
			(xy 97.391472 -244.583803) (xy 97.379059 -244.534789) (xy 97.374883 -244.4844) (xy 2.509012 -244.4844)
			(xy 2.509012 -245.18239) (xy 16.85798 -245.18239) (xy 16.85798 -244.687852) (xy 16.858462 -244.682586)
			(xy 16.865921 -244.675147) (xy 16.871188 -244.674644) (xy 16.871696 -244.674644) (xy 17.38757 -244.674644)
			(xy 17.39538 -244.674327) (xy 17.410252 -244.669544) (xy 17.41678 -244.665246) (xy 17.437869 -244.650897)
			(xy 17.48353 -244.628166) (xy 17.532136 -244.612707) (xy 17.582539 -244.604884) (xy 17.633545 -244.604884)
			(xy 17.683948 -244.612707) (xy 17.732554 -244.628166) (xy 17.778215 -244.650897) (xy 17.799304 -244.665246)
			(xy 17.805839 -244.669532) (xy 17.820706 -244.674319) (xy 17.828514 -244.674644) (xy 18.344642 -244.674644)
			(xy 18.349952 -244.675096) (xy 18.357521 -244.68255) (xy 18.358104 -244.687852) (xy 18.358104 -245.18239)
			(xy 18.358078 -245.182644) (xy 24.402288 -245.182644) (xy 24.402288 -245.182136) (xy 24.402288 -244.687852)
			(xy 24.402763 -244.682584) (xy 24.410227 -244.675145) (xy 24.415496 -244.674644) (xy 24.931624 -244.674644)
			(xy 24.939436 -244.67435) (xy 24.954308 -244.669552) (xy 24.960834 -244.665246) (xy 24.981923 -244.650897)
			(xy 25.027584 -244.628166) (xy 25.07619 -244.612707) (xy 25.126593 -244.604884) (xy 25.177599 -244.604884)
			(xy 25.228002 -244.612707) (xy 25.276608 -244.628166) (xy 25.322269 -244.650897) (xy 25.343358 -244.665246)
			(xy 25.349881 -244.669553) (xy 25.364757 -244.674327) (xy 25.372568 -244.674644) (xy 25.888696 -244.674644)
			(xy 25.893947 -244.675192) (xy 25.901387 -244.682603) (xy 25.901904 -244.687852) (xy 25.901904 -245.18239)
			(xy 25.901879 -245.182644) (xy 31.946088 -245.182644) (xy 31.946088 -245.182136) (xy 31.946088 -244.687852)
			(xy 31.946563 -244.682584) (xy 31.954027 -244.675145) (xy 31.959296 -244.674644) (xy 32.475424 -244.674644)
			(xy 32.483236 -244.67435) (xy 32.498108 -244.669552) (xy 32.504634 -244.665246) (xy 32.525723 -244.650897)
			(xy 32.571384 -244.628166) (xy 32.61999 -244.612707) (xy 32.670393 -244.604884) (xy 32.721399 -244.604884)
			(xy 32.771802 -244.612707) (xy 32.820408 -244.628166) (xy 32.866069 -244.650897) (xy 32.887158 -244.665246)
			(xy 32.893681 -244.669553) (xy 32.908557 -244.674327) (xy 32.916368 -244.674644) (xy 33.432496 -244.674644)
			(xy 33.437747 -244.675192) (xy 33.445187 -244.682603) (xy 33.445704 -244.687852) (xy 33.445704 -245.18239)
			(xy 39.489888 -245.18239) (xy 39.489888 -244.687852) (xy 39.490363 -244.682584) (xy 39.497827 -244.675145)
			(xy 39.503096 -244.674644) (xy 39.503604 -244.674644) (xy 40.019478 -244.674644) (xy 40.027288 -244.67433)
			(xy 40.04216 -244.669545) (xy 40.048688 -244.665246) (xy 40.069777 -244.650897) (xy 40.115438 -244.628166)
			(xy 40.164044 -244.612707) (xy 40.214447 -244.604884) (xy 40.265453 -244.604884) (xy 40.315856 -244.612707)
			(xy 40.364462 -244.628166) (xy 40.410123 -244.650897) (xy 40.431212 -244.665246) (xy 40.437745 -244.669535)
			(xy 40.452614 -244.67432) (xy 40.460422 -244.674644) (xy 40.97655 -244.674644) (xy 40.981849 -244.675157)
			(xy 40.989423 -244.682565) (xy 40.990012 -244.687852) (xy 40.990012 -245.18239) (xy 40.989985 -245.182644)
			(xy 47.034196 -245.182644) (xy 47.034196 -245.182136) (xy 47.034196 -244.687852) (xy 47.034663 -244.682582)
			(xy 47.042133 -244.675143) (xy 47.047404 -244.674644) (xy 47.563532 -244.674644) (xy 47.57134 -244.674311)
			(xy 47.586212 -244.669539) (xy 47.592742 -244.665246) (xy 47.613831 -244.650897) (xy 47.659492 -244.628166)
			(xy 47.708098 -244.612707) (xy 47.758501 -244.604884) (xy 47.809507 -244.604884) (xy 47.85991 -244.612707)
			(xy 47.908516 -244.628166) (xy 47.954177 -244.650897) (xy 47.975266 -244.665246) (xy 47.981809 -244.669518)
			(xy 47.99667 -244.674314) (xy 48.004476 -244.674644) (xy 48.520604 -244.674644) (xy 48.525856 -244.675187)
			(xy 48.533295 -244.682602) (xy 48.533812 -244.687852) (xy 48.533812 -245.18239) (xy 54.577996 -245.18239)
			(xy 54.577996 -244.687852) (xy 54.578463 -244.682582) (xy 54.585933 -244.675143) (xy 54.591204 -244.674644)
			(xy 54.591712 -244.674644) (xy 56.064658 -244.674644) (xy 56.069958 -244.675152) (xy 56.077532 -244.682563)
			(xy 56.07812 -244.687852) (xy 56.07812 -245.18239) (xy 56.07781 -245.187834) (xy 56.070103 -245.195523)
			(xy 56.064658 -245.195852) (xy 54.591458 -245.195852) (xy 54.586086 -245.195377) (xy 54.578503 -245.187763)
			(xy 54.577996 -245.18239) (xy 48.533812 -245.18239) (xy 48.533364 -245.187704) (xy 48.52591 -245.195278)
			(xy 48.520604 -245.195852) (xy 48.00473 -245.195852) (xy 47.99692 -245.19617) (xy 47.982048 -245.200952)
			(xy 47.97552 -245.20525) (xy 47.95439 -245.219587) (xy 47.908669 -245.242316) (xy 47.859999 -245.25775)
			(xy 47.809534 -245.265521) (xy 47.784004 -245.265956) (xy 47.758474 -245.265519) (xy 47.70801 -245.257743)
			(xy 47.659337 -245.242315) (xy 47.61361 -245.219598) (xy 47.592488 -245.20525) (xy 47.585955 -245.20096)
			(xy 47.571086 -245.196175) (xy 47.563278 -245.195852) (xy 47.047404 -245.195852) (xy 47.042152 -245.195307)
			(xy 47.034712 -245.187894) (xy 47.034196 -245.182644) (xy 40.989985 -245.182644) (xy 40.989448 -245.187741)
			(xy 40.981898 -245.195324) (xy 40.97655 -245.195852) (xy 40.460676 -245.195852) (xy 40.452864 -245.196147)
			(xy 40.437992 -245.200945) (xy 40.431466 -245.20525) (xy 40.410351 -245.21961) (xy 40.364625 -245.242334)
			(xy 40.31595 -245.257761) (xy 40.265482 -245.265525) (xy 40.23995 -245.265956) (xy 40.214421 -245.265496)
			(xy 40.163958 -245.257727) (xy 40.115285 -245.242305) (xy 40.069557 -245.219595) (xy 40.048434 -245.20525)
			(xy 40.041891 -245.200978) (xy 40.02703 -245.196182) (xy 40.019224 -245.195852) (xy 39.50335 -245.195852)
			(xy 39.497978 -245.195382) (xy 39.490394 -245.187764) (xy 39.489888 -245.18239) (xy 33.445704 -245.18239)
			(xy 33.445176 -245.187683) (xy 33.437777 -245.195252) (xy 33.432496 -245.195852) (xy 32.916622 -245.195852)
			(xy 32.908812 -245.196166) (xy 32.89394 -245.200951) (xy 32.887412 -245.20525) (xy 32.866284 -245.21959)
			(xy 32.820563 -245.242319) (xy 32.771891 -245.257752) (xy 32.721426 -245.265521) (xy 32.695896 -245.265956)
			(xy 32.670366 -245.265523) (xy 32.619902 -245.257746) (xy 32.571229 -245.242316) (xy 32.525502 -245.219598)
			(xy 32.50438 -245.20525) (xy 32.497849 -245.200957) (xy 32.482979 -245.196174) (xy 32.47517 -245.195852)
			(xy 31.959296 -245.195852) (xy 31.954043 -245.195313) (xy 31.946603 -245.187895) (xy 31.946088 -245.182644)
			(xy 25.901879 -245.182644) (xy 25.901376 -245.187683) (xy 25.893977 -245.195252) (xy 25.888696 -245.195852)
			(xy 25.372822 -245.195852) (xy 25.365012 -245.196166) (xy 25.35014 -245.200951) (xy 25.343612 -245.20525)
			(xy 25.322484 -245.21959) (xy 25.276763 -245.242319) (xy 25.228091 -245.257752) (xy 25.177626 -245.265521)
			(xy 25.152096 -245.265956) (xy 25.126566 -245.265523) (xy 25.076102 -245.257746) (xy 25.027429 -245.242316)
			(xy 24.981702 -245.219598) (xy 24.96058 -245.20525) (xy 24.954049 -245.200957) (xy 24.939179 -245.196174)
			(xy 24.93137 -245.195852) (xy 24.415496 -245.195852) (xy 24.410243 -245.195313) (xy 24.402803 -245.187895)
			(xy 24.402288 -245.182644) (xy 18.358078 -245.182644) (xy 18.357547 -245.187743) (xy 18.349993 -245.195326)
			(xy 18.344642 -245.195852) (xy 17.828768 -245.195852) (xy 17.82096 -245.196186) (xy 17.806088 -245.200957)
			(xy 17.799558 -245.20525) (xy 17.778445 -245.219613) (xy 17.732718 -245.242337) (xy 17.684042 -245.257763)
			(xy 17.633574 -245.265525) (xy 17.608042 -245.265956) (xy 17.582512 -245.2655) (xy 17.532049 -245.25773)
			(xy 17.483377 -245.242307) (xy 17.437649 -245.219595) (xy 17.416526 -245.20525) (xy 17.409985 -245.200975)
			(xy 17.395122 -245.196181) (xy 17.387316 -245.195852) (xy 16.871442 -245.195852) (xy 16.86601 -245.195491)
			(xy 16.858321 -245.187821) (xy 16.85798 -245.18239) (xy 2.509012 -245.18239) (xy 2.509012 -245.2944)
			(xy 108.185144 -245.2944) (xy 108.189316 -245.244056) (xy 108.201717 -245.195085) (xy 108.222011 -245.148823)
			(xy 108.249642 -245.106533) (xy 108.283857 -245.069367) (xy 108.323723 -245.038341) (xy 108.368153 -245.014299)
			(xy 108.415933 -244.997899) (xy 108.465762 -244.989587) (xy 108.49102 -244.989096) (xy 109.431074 -244.989096)
			(xy 109.456333 -244.989579) (xy 109.506164 -244.99789) (xy 109.553947 -245.01429) (xy 109.598378 -245.038332)
			(xy 109.638246 -245.069359) (xy 109.672463 -245.106526) (xy 109.700095 -245.148818) (xy 109.714934 -245.182644)
			(xy 163.678108 -245.182644) (xy 163.678108 -245.182136) (xy 163.678108 -244.687852) (xy 163.678565 -244.68258)
			(xy 163.686041 -244.675139) (xy 163.691316 -244.674644) (xy 165.164516 -244.674644) (xy 165.169769 -244.675179)
			(xy 165.177208 -244.6826) (xy 165.177724 -244.687852) (xy 165.177724 -245.18239) (xy 171.221908 -245.18239)
			(xy 171.221908 -244.687852) (xy 171.222365 -244.68258) (xy 171.229841 -244.675139) (xy 171.235116 -244.674644)
			(xy 171.235624 -244.674644) (xy 171.751498 -244.674644) (xy 171.759309 -244.674339) (xy 171.774181 -244.669548)
			(xy 171.780708 -244.665246) (xy 171.801797 -244.650897) (xy 171.847458 -244.628166) (xy 171.896064 -244.612707)
			(xy 171.946467 -244.604884) (xy 171.997473 -244.604884) (xy 172.047876 -244.612707) (xy 172.096482 -244.628166)
			(xy 172.142143 -244.650897) (xy 172.163232 -244.665246) (xy 172.16976 -244.669543) (xy 172.184633 -244.674323)
			(xy 172.192442 -244.674644) (xy 172.70857 -244.674644) (xy 172.713872 -244.675144) (xy 172.721445 -244.682562)
			(xy 172.722032 -244.687852) (xy 172.722032 -245.18239) (xy 172.722017 -245.182644) (xy 178.766216 -245.182644)
			(xy 178.766216 -245.182136) (xy 178.766216 -244.687852) (xy 178.766665 -244.682578) (xy 178.774147 -244.675137)
			(xy 178.779424 -244.674644) (xy 179.295552 -244.674644) (xy 179.303361 -244.674319) (xy 179.318233 -244.669542)
			(xy 179.324762 -244.665246) (xy 179.345851 -244.650897) (xy 179.391512 -244.628166) (xy 179.440118 -244.612707)
			(xy 179.490521 -244.604884) (xy 179.541527 -244.604884) (xy 179.59193 -244.612707) (xy 179.640536 -244.628166)
			(xy 179.686197 -244.650897) (xy 179.707286 -244.665246) (xy 179.713825 -244.669525) (xy 179.728689 -244.674317)
			(xy 179.736496 -244.674644) (xy 180.252624 -244.674644) (xy 180.257878 -244.675174) (xy 180.265316 -244.682599)
			(xy 180.265832 -244.687852) (xy 180.265832 -245.18239) (xy 186.310016 -245.18239) (xy 186.310016 -244.687852)
			(xy 186.310465 -244.682578) (xy 186.317947 -244.675137) (xy 186.323224 -244.674644) (xy 186.323732 -244.674644)
			(xy 186.839606 -244.674644) (xy 186.847417 -244.674342) (xy 186.862289 -244.669549) (xy 186.868816 -244.665246)
			(xy 186.889905 -244.650897) (xy 186.935566 -244.628166) (xy 186.984172 -244.612707) (xy 187.034575 -244.604884)
			(xy 187.085581 -244.604884) (xy 187.135984 -244.612707) (xy 187.18459 -244.628166) (xy 187.230251 -244.650897)
			(xy 187.25134 -244.665246) (xy 187.257867 -244.669546) (xy 187.27274 -244.674325) (xy 187.28055 -244.674644)
			(xy 187.796678 -244.674644) (xy 187.801981 -244.675138) (xy 187.809553 -244.68256) (xy 187.81014 -244.687852)
			(xy 187.81014 -245.18239) (xy 187.810125 -245.182644) (xy 193.854324 -245.182644) (xy 193.854324 -245.182136)
			(xy 193.854324 -244.687852) (xy 193.854766 -244.682576) (xy 193.862253 -244.675134) (xy 193.867532 -244.674644)
			(xy 194.38366 -244.674644) (xy 194.39147 -244.674323) (xy 194.406341 -244.669543) (xy 194.41287 -244.665246)
			(xy 194.433959 -244.650897) (xy 194.47962 -244.628166) (xy 194.528226 -244.612707) (xy 194.578629 -244.604884)
			(xy 194.629635 -244.604884) (xy 194.680038 -244.612707) (xy 194.728644 -244.628166) (xy 194.774305 -244.650897)
			(xy 194.795394 -244.665246) (xy 194.801931 -244.669528) (xy 194.816797 -244.674318) (xy 194.824604 -244.674644)
			(xy 195.340732 -244.674644) (xy 195.345987 -244.675169) (xy 195.353425 -244.682598) (xy 195.35394 -244.687852)
			(xy 195.35394 -245.18239) (xy 195.353917 -245.182644) (xy 201.398124 -245.182644) (xy 201.398124 -245.182136)
			(xy 201.398124 -244.687852) (xy 201.398566 -244.682576) (xy 201.406053 -244.675134) (xy 201.411332 -244.674644)
			(xy 201.92746 -244.674644) (xy 201.93527 -244.674323) (xy 201.950141 -244.669543) (xy 201.95667 -244.665246)
			(xy 201.977759 -244.650897) (xy 202.02342 -244.628166) (xy 202.072026 -244.612707) (xy 202.122429 -244.604884)
			(xy 202.173435 -244.604884) (xy 202.223838 -244.612707) (xy 202.272444 -244.628166) (xy 202.318105 -244.650897)
			(xy 202.339194 -244.665246) (xy 202.345731 -244.669528) (xy 202.360597 -244.674318) (xy 202.368404 -244.674644)
			(xy 202.884532 -244.674644) (xy 202.889787 -244.675169) (xy 202.897225 -244.682598) (xy 202.89774 -244.687852)
			(xy 202.89774 -245.182136) (xy 264.798048 -245.182136) (xy 264.798048 -244.687598) (xy 264.798379 -244.68216)
			(xy 264.806072 -244.674474) (xy 264.81151 -244.674136) (xy 265.327638 -244.674136) (xy 265.335447 -244.673807)
			(xy 265.350319 -244.669033) (xy 265.356848 -244.664738) (xy 265.377937 -244.650389) (xy 265.423598 -244.627658)
			(xy 265.472204 -244.612199) (xy 265.522607 -244.604376) (xy 265.573613 -244.604376) (xy 265.624016 -244.612199)
			(xy 265.672622 -244.627658) (xy 265.718283 -244.650389) (xy 265.739372 -244.664738) (xy 265.745914 -244.669011)
			(xy 265.760776 -244.673807) (xy 265.768582 -244.674136) (xy 266.28471 -244.674136) (xy 266.290075 -244.674644)
			(xy 266.29766 -244.682233) (xy 266.298172 -244.687598) (xy 266.298172 -245.182136) (xy 272.342356 -245.182136)
			(xy 272.342356 -244.687598) (xy 272.342824 -244.68229) (xy 272.350265 -244.674718) (xy 272.355564 -244.674136)
			(xy 272.871692 -244.674136) (xy 272.879503 -244.67383) (xy 272.894375 -244.66904) (xy 272.900902 -244.664738)
			(xy 272.921991 -244.650389) (xy 272.967652 -244.627658) (xy 273.016258 -244.612199) (xy 273.066661 -244.604376)
			(xy 273.117667 -244.604376) (xy 273.16807 -244.612199) (xy 273.216676 -244.627658) (xy 273.262337 -244.650389)
			(xy 273.283426 -244.664738) (xy 273.289956 -244.669032) (xy 273.304827 -244.673814) (xy 273.312636 -244.674136)
			(xy 273.828764 -244.674136) (xy 273.834102 -244.674455) (xy 273.841648 -244.682006) (xy 273.841972 -244.687344)
			(xy 273.841972 -244.687852) (xy 273.841972 -245.182136) (xy 279.886156 -245.182136) (xy 279.886156 -244.687598)
			(xy 279.886624 -244.68229) (xy 279.894065 -244.674718) (xy 279.899364 -244.674136) (xy 280.415492 -244.674136)
			(xy 280.423303 -244.67383) (xy 280.438175 -244.66904) (xy 280.444702 -244.664738) (xy 280.465791 -244.650389)
			(xy 280.511452 -244.627658) (xy 280.560058 -244.612199) (xy 280.610461 -244.604376) (xy 280.661467 -244.604376)
			(xy 280.71187 -244.612199) (xy 280.760476 -244.627658) (xy 280.806137 -244.650389) (xy 280.827226 -244.664738)
			(xy 280.833756 -244.669032) (xy 280.848627 -244.673814) (xy 280.856436 -244.674136) (xy 281.372564 -244.674136)
			(xy 281.377902 -244.674455) (xy 281.385448 -244.682006) (xy 281.385772 -244.687344) (xy 281.385772 -244.687852)
			(xy 281.385772 -245.182136) (xy 287.429956 -245.182136) (xy 287.429956 -244.687598) (xy 287.43028 -244.682159)
			(xy 287.437978 -244.674472) (xy 287.443418 -244.674136) (xy 287.959546 -244.674136) (xy 287.967355 -244.67381)
			(xy 287.982227 -244.669034) (xy 287.988756 -244.664738) (xy 288.009845 -244.650389) (xy 288.055506 -244.627658)
			(xy 288.104112 -244.612199) (xy 288.154515 -244.604376) (xy 288.205521 -244.604376) (xy 288.255924 -244.612199)
			(xy 288.30453 -244.627658) (xy 288.350191 -244.650389) (xy 288.37128 -244.664738) (xy 288.37782 -244.669014)
			(xy 288.392683 -244.673808) (xy 288.40049 -244.674136) (xy 288.916618 -244.674136) (xy 288.921984 -244.674638)
			(xy 288.929568 -244.682232) (xy 288.93008 -244.687598) (xy 288.93008 -245.182136) (xy 294.974264 -245.182136)
			(xy 294.974264 -244.687598) (xy 294.974725 -244.682288) (xy 294.982171 -244.674716) (xy 294.987472 -244.674136)
			(xy 295.5036 -244.674136) (xy 295.511411 -244.673833) (xy 295.526283 -244.669041) (xy 295.53281 -244.664738)
			(xy 295.553899 -244.650389) (xy 295.59956 -244.627658) (xy 295.648166 -244.612199) (xy 295.698569 -244.604376)
			(xy 295.749575 -244.604376) (xy 295.799978 -244.612199) (xy 295.848584 -244.627658) (xy 295.894245 -244.650389)
			(xy 295.915334 -244.664738) (xy 295.921862 -244.669035) (xy 295.936735 -244.673816) (xy 295.944544 -244.674136)
			(xy 296.460672 -244.674136) (xy 296.466011 -244.67445) (xy 296.473557 -244.682004) (xy 296.47388 -244.687344)
			(xy 296.47388 -244.687852) (xy 296.47388 -245.182136) (xy 302.518064 -245.182136) (xy 302.518064 -244.687598)
			(xy 302.51838 -244.682157) (xy 302.526084 -244.674469) (xy 302.531526 -244.674136) (xy 304.004726 -244.674136)
			(xy 304.010093 -244.674633) (xy 304.017676 -244.682231) (xy 304.018188 -244.687598) (xy 304.018188 -245.182136)
			(xy 304.017727 -245.187408) (xy 304.010254 -245.194849) (xy 304.00498 -245.195344) (xy 304.004472 -245.195344)
			(xy 302.531526 -245.195344) (xy 302.526221 -245.194858) (xy 302.518648 -245.18743) (xy 302.518064 -245.182136)
			(xy 296.47388 -245.182136) (xy 296.473426 -245.18741) (xy 296.465948 -245.194852) (xy 296.460672 -245.195344)
			(xy 295.944798 -245.195344) (xy 295.936924 -245.19564) (xy 295.92192 -245.200418) (xy 295.915334 -245.204742)
			(xy 295.894265 -245.219146) (xy 295.848617 -245.241972) (xy 295.800009 -245.257526) (xy 295.749589 -245.265441)
			(xy 295.724072 -245.265956) (xy 295.698552 -245.265455) (xy 295.648125 -245.257565) (xy 295.599513 -245.242009)
			(xy 295.553875 -245.219156) (xy 295.53281 -245.204742) (xy 295.526215 -245.200432) (xy 295.511218 -245.195642)
			(xy 295.503346 -245.195344) (xy 294.987472 -245.195344) (xy 294.982215 -245.194828) (xy 294.974775 -245.187393)
			(xy 294.974264 -245.182136) (xy 288.93008 -245.182136) (xy 288.929626 -245.18741) (xy 288.922148 -245.194852)
			(xy 288.916872 -245.195344) (xy 288.916364 -245.195344) (xy 288.400744 -245.195344) (xy 288.392868 -245.195616)
			(xy 288.377864 -245.20041) (xy 288.37128 -245.204742) (xy 288.350198 -245.219126) (xy 288.304555 -245.241957)
			(xy 288.25595 -245.257516) (xy 288.205534 -245.265438) (xy 288.180018 -245.265956) (xy 288.154497 -245.265482)
			(xy 288.104069 -245.257584) (xy 288.055457 -245.24202) (xy 288.00982 -245.21916) (xy 287.988756 -245.204742)
			(xy 287.982174 -245.200411) (xy 287.967167 -245.195634) (xy 287.959292 -245.195344) (xy 287.443418 -245.195344)
			(xy 287.438112 -245.194863) (xy 287.430539 -245.187432) (xy 287.429956 -245.182136) (xy 281.385772 -245.182136)
			(xy 281.385325 -245.187412) (xy 281.377842 -245.194854) (xy 281.372564 -245.195344) (xy 280.85669 -245.195344)
			(xy 280.848816 -245.195636) (xy 280.833812 -245.200417) (xy 280.827226 -245.204742) (xy 280.806159 -245.21915)
			(xy 280.760511 -245.241975) (xy 280.711901 -245.257528) (xy 280.661482 -245.265442) (xy 280.635964 -245.265956)
			(xy 280.610444 -245.265459) (xy 280.560017 -245.257568) (xy 280.511405 -245.242011) (xy 280.465767 -245.219157)
			(xy 280.444702 -245.204742) (xy 280.438109 -245.200429) (xy 280.42311 -245.19564) (xy 280.415238 -245.195344)
			(xy 279.899364 -245.195344) (xy 279.894106 -245.194833) (xy 279.886667 -245.187394) (xy 279.886156 -245.182136)
			(xy 273.841972 -245.182136) (xy 273.841525 -245.187412) (xy 273.834042 -245.194854) (xy 273.828764 -245.195344)
			(xy 273.31289 -245.195344) (xy 273.305016 -245.195636) (xy 273.290012 -245.200417) (xy 273.283426 -245.204742)
			(xy 273.262359 -245.21915) (xy 273.216711 -245.241975) (xy 273.168101 -245.257528) (xy 273.117682 -245.265442)
			(xy 273.092164 -245.265956) (xy 273.066644 -245.265459) (xy 273.016217 -245.257568) (xy 272.967605 -245.242011)
			(xy 272.921967 -245.219157) (xy 272.900902 -245.204742) (xy 272.894309 -245.200429) (xy 272.87931 -245.19564)
			(xy 272.871438 -245.195344) (xy 272.355564 -245.195344) (xy 272.350306 -245.194833) (xy 272.342867 -245.187394)
			(xy 272.342356 -245.182136) (xy 266.298172 -245.182136) (xy 266.297725 -245.187412) (xy 266.290242 -245.194854)
			(xy 266.284964 -245.195344) (xy 266.284456 -245.195344) (xy 265.768836 -245.195344) (xy 265.76096 -245.195613)
			(xy 265.745956 -245.200409) (xy 265.739372 -245.204742) (xy 265.718292 -245.21913) (xy 265.672648 -245.241959)
			(xy 265.624043 -245.257518) (xy 265.573626 -245.265438) (xy 265.54811 -245.265956) (xy 265.522589 -245.265486)
			(xy 265.472161 -245.257587) (xy 265.423549 -245.242021) (xy 265.377912 -245.21916) (xy 265.356848 -245.204742)
			(xy 265.350267 -245.200408) (xy 265.335259 -245.195632) (xy 265.327384 -245.195344) (xy 264.81151 -245.195344)
			(xy 264.806203 -245.194869) (xy 264.79863 -245.187433) (xy 264.798048 -245.182136) (xy 202.89774 -245.182136)
			(xy 202.89774 -245.18239) (xy 202.897268 -245.187698) (xy 202.88983 -245.195271) (xy 202.884532 -245.195852)
			(xy 202.368658 -245.195852) (xy 202.360849 -245.196182) (xy 202.345977 -245.200956) (xy 202.339448 -245.20525)
			(xy 202.318338 -245.219618) (xy 202.27261 -245.24234) (xy 202.223933 -245.257765) (xy 202.173464 -245.265526)
			(xy 202.147932 -245.265956) (xy 202.122402 -245.265505) (xy 202.071939 -245.257734) (xy 202.023266 -245.242309)
			(xy 201.977538 -245.219596) (xy 201.956416 -245.20525) (xy 201.949877 -245.200971) (xy 201.935013 -245.19618)
			(xy 201.927206 -245.195852) (xy 201.411332 -245.195852) (xy 201.406083 -245.195289) (xy 201.398642 -245.187889)
			(xy 201.398124 -245.182644) (xy 195.353917 -245.182644) (xy 195.353468 -245.187698) (xy 195.34603 -245.195271)
			(xy 195.340732 -245.195852) (xy 194.824858 -245.195852) (xy 194.817049 -245.196182) (xy 194.802177 -245.200956)
			(xy 194.795648 -245.20525) (xy 194.774538 -245.219618) (xy 194.72881 -245.24234) (xy 194.680133 -245.257765)
			(xy 194.629664 -245.265526) (xy 194.604132 -245.265956) (xy 194.578602 -245.265505) (xy 194.528139 -245.257734)
			(xy 194.479466 -245.242309) (xy 194.433738 -245.219596) (xy 194.412616 -245.20525) (xy 194.406077 -245.200971)
			(xy 194.391213 -245.19618) (xy 194.383406 -245.195852) (xy 193.867532 -245.195852) (xy 193.862283 -245.195289)
			(xy 193.854842 -245.187889) (xy 193.854324 -245.182644) (xy 187.810125 -245.182644) (xy 187.809812 -245.187829)
			(xy 187.802117 -245.195517) (xy 187.796678 -245.195852) (xy 187.280804 -245.195852) (xy 187.272993 -245.196159)
			(xy 187.258122 -245.200949) (xy 187.251594 -245.20525) (xy 187.230471 -245.219598) (xy 187.184748 -245.242325)
			(xy 187.136075 -245.257755) (xy 187.085609 -245.265523) (xy 187.060078 -245.265956) (xy 187.034547 -245.265532)
			(xy 186.984083 -245.257753) (xy 186.93541 -245.24232) (xy 186.889683 -245.219599) (xy 186.868562 -245.20525)
			(xy 186.862035 -245.20095) (xy 186.847162 -245.196172) (xy 186.839352 -245.195852) (xy 186.323478 -245.195852)
			(xy 186.318109 -245.195363) (xy 186.310524 -245.18776) (xy 186.310016 -245.18239) (xy 180.265832 -245.18239)
			(xy 180.265367 -245.187699) (xy 180.257924 -245.195273) (xy 180.252624 -245.195852) (xy 179.73675 -245.195852)
			(xy 179.728941 -245.196178) (xy 179.714069 -245.200955) (xy 179.70754 -245.20525) (xy 179.686433 -245.219621)
			(xy 179.640704 -245.242343) (xy 179.592026 -245.257767) (xy 179.541556 -245.265527) (xy 179.516024 -245.265956)
			(xy 179.490494 -245.265509) (xy 179.440031 -245.257737) (xy 179.391358 -245.24231) (xy 179.34563 -245.219596)
			(xy 179.324508 -245.20525) (xy 179.317971 -245.200968) (xy 179.303105 -245.196178) (xy 179.295298 -245.195852)
			(xy 178.779424 -245.195852) (xy 178.774175 -245.195294) (xy 178.766733 -245.187891) (xy 178.766216 -245.182644)
			(xy 172.722017 -245.182644) (xy 172.721711 -245.187831) (xy 172.714011 -245.195519) (xy 172.70857 -245.195852)
			(xy 172.192696 -245.195852) (xy 172.184885 -245.196155) (xy 172.170013 -245.200947) (xy 172.163486 -245.20525)
			(xy 172.142366 -245.219601) (xy 172.096641 -245.242328) (xy 172.047968 -245.257757) (xy 171.997501 -245.265523)
			(xy 171.97197 -245.265956) (xy 171.946439 -245.265536) (xy 171.895975 -245.257755) (xy 171.847302 -245.242321)
			(xy 171.801575 -245.2196) (xy 171.780454 -245.20525) (xy 171.773929 -245.200947) (xy 171.759054 -245.196171)
			(xy 171.751244 -245.195852) (xy 171.23537 -245.195852) (xy 171.23 -245.195369) (xy 171.222415 -245.187761)
			(xy 171.221908 -245.18239) (xy 165.177724 -245.18239) (xy 165.177266 -245.187701) (xy 165.169818 -245.195275)
			(xy 165.164516 -245.195852) (xy 163.691316 -245.195852) (xy 163.686066 -245.195299) (xy 163.678625 -245.187892)
			(xy 163.678108 -245.182644) (xy 109.714934 -245.182644) (xy 109.72039 -245.195081) (xy 109.732792 -245.244054)
			(xy 109.736939 -245.2941) (xy 361.758735 -245.2941) (xy 361.76291 -245.243723) (xy 361.775319 -245.194719)
			(xy 361.795626 -245.148427) (xy 361.823274 -245.106109) (xy 361.857511 -245.068918) (xy 361.897403 -245.03787)
			(xy 361.941861 -245.013812) (xy 361.989672 -244.997399) (xy 362.039533 -244.98908) (xy 362.064808 -244.988588)
			(xy 363.004862 -244.988588) (xy 363.030147 -244.988978) (xy 363.080028 -244.997296) (xy 363.127859 -245.013711)
			(xy 363.172336 -245.037776) (xy 363.212245 -245.068834) (xy 363.246497 -245.106037) (xy 363.274158 -245.148371)
			(xy 363.28897 -245.182136) (xy 411.618176 -245.182136) (xy 411.618176 -244.687598) (xy 411.618626 -244.682285)
			(xy 411.62608 -244.674712) (xy 411.631384 -244.674136) (xy 413.104584 -244.674136) (xy 413.109925 -244.674442)
			(xy 413.117469 -244.682002) (xy 413.117792 -244.687344) (xy 413.117792 -244.687852) (xy 413.117792 -245.182136)
			(xy 419.161976 -245.182136) (xy 419.161976 -244.687598) (xy 419.162282 -244.682154) (xy 419.169993 -244.674465)
			(xy 419.175438 -244.674136) (xy 419.691566 -244.674136) (xy 419.699376 -244.673819) (xy 419.714248 -244.669036)
			(xy 419.720776 -244.664738) (xy 419.741865 -244.650389) (xy 419.787526 -244.627658) (xy 419.836132 -244.612199)
			(xy 419.886535 -244.604376) (xy 419.937541 -244.604376) (xy 419.987944 -244.612199) (xy 420.03655 -244.627658)
			(xy 420.082211 -244.650389) (xy 420.1033 -244.664738) (xy 420.109836 -244.669022) (xy 420.124702 -244.673811)
			(xy 420.13251 -244.674136) (xy 420.648638 -244.674136) (xy 420.654006 -244.674625) (xy 420.661589 -244.682229)
			(xy 420.6621 -244.687598) (xy 420.6621 -245.182136) (xy 426.706284 -245.182136) (xy 426.706284 -244.687598)
			(xy 426.706727 -244.682283) (xy 426.714186 -244.67471) (xy 426.719492 -244.674136) (xy 427.23562 -244.674136)
			(xy 427.243432 -244.673842) (xy 427.258304 -244.669044) (xy 427.26483 -244.664738) (xy 427.285919 -244.650389)
			(xy 427.33158 -244.627658) (xy 427.380186 -244.612199) (xy 427.430589 -244.604376) (xy 427.481595 -244.604376)
			(xy 427.531998 -244.612199) (xy 427.580604 -244.627658) (xy 427.626265 -244.650389) (xy 427.647354 -244.664738)
			(xy 427.653878 -244.669043) (xy 427.668754 -244.673819) (xy 427.676564 -244.674136) (xy 428.192692 -244.674136)
			(xy 428.198034 -244.674436) (xy 428.205578 -244.682001) (xy 428.2059 -244.687344) (xy 428.2059 -244.687852)
			(xy 428.2059 -245.182136) (xy 434.250084 -245.182136) (xy 434.250084 -244.687598) (xy 434.250382 -244.682152)
			(xy 434.258098 -244.674463) (xy 434.263546 -244.674136) (xy 434.779674 -244.674136) (xy 434.787484 -244.673822)
			(xy 434.802356 -244.669037) (xy 434.808884 -244.664738) (xy 434.829973 -244.650389) (xy 434.875634 -244.627658)
			(xy 434.92424 -244.612199) (xy 434.974643 -244.604376) (xy 435.025649 -244.604376) (xy 435.076052 -244.612199)
			(xy 435.124658 -244.627658) (xy 435.170319 -244.650389) (xy 435.191408 -244.664738) (xy 435.197942 -244.669025)
			(xy 435.21281 -244.673812) (xy 435.220618 -244.674136) (xy 435.736746 -244.674136) (xy 435.742115 -244.67462)
			(xy 435.749698 -244.682227) (xy 435.750208 -244.687598) (xy 435.750208 -245.182136) (xy 441.794392 -245.182136)
			(xy 441.794392 -244.687598) (xy 441.794916 -244.682305) (xy 441.802319 -244.674736) (xy 441.8076 -244.674136)
			(xy 442.323728 -244.674136) (xy 442.33154 -244.673845) (xy 442.346412 -244.669045) (xy 442.352938 -244.664738)
			(xy 442.374027 -244.650389) (xy 442.419688 -244.627658) (xy 442.468294 -244.612199) (xy 442.518697 -244.604376)
			(xy 442.569703 -244.604376) (xy 442.620106 -244.612199) (xy 442.668712 -244.627658) (xy 442.714373 -244.650389)
			(xy 442.735462 -244.664738) (xy 442.742006 -244.669007) (xy 442.756866 -244.673805) (xy 442.764672 -244.674136)
			(xy 443.2808 -244.674136) (xy 443.286143 -244.674431) (xy 443.293687 -244.682) (xy 443.294008 -244.687344)
			(xy 443.294008 -244.687852) (xy 443.294008 -245.182136) (xy 449.338192 -245.182136) (xy 449.338192 -244.687598)
			(xy 449.338716 -244.682305) (xy 449.346119 -244.674736) (xy 449.3514 -244.674136) (xy 449.867528 -244.674136)
			(xy 449.87534 -244.673845) (xy 449.890212 -244.669045) (xy 449.896738 -244.664738) (xy 449.917827 -244.650389)
			(xy 449.963488 -244.627658) (xy 450.012094 -244.612199) (xy 450.062497 -244.604376) (xy 450.113503 -244.604376)
			(xy 450.163906 -244.612199) (xy 450.212512 -244.627658) (xy 450.258173 -244.650389) (xy 450.279262 -244.664738)
			(xy 450.285806 -244.669007) (xy 450.300666 -244.673805) (xy 450.308472 -244.674136) (xy 450.8246 -244.674136)
			(xy 450.829943 -244.674431) (xy 450.837487 -244.682) (xy 450.837808 -244.687344) (xy 450.837808 -244.687852)
			(xy 450.837808 -245.182136) (xy 450.837329 -245.187403) (xy 450.829868 -245.194843) (xy 450.8246 -245.195344)
			(xy 450.308726 -245.195344) (xy 450.300849 -245.195608) (xy 450.285846 -245.200408) (xy 450.279262 -245.204742)
			(xy 450.258185 -245.219134) (xy 450.21254 -245.241963) (xy 450.163934 -245.25752) (xy 450.113517 -245.265439)
			(xy 450.088 -245.265956) (xy 450.062479 -245.265491) (xy 450.01205 -245.257591) (xy 449.963439 -245.242024)
			(xy 449.917802 -245.219161) (xy 449.896738 -245.204742) (xy 449.890137 -245.200443) (xy 449.875144 -245.195646)
			(xy 449.867274 -245.195344) (xy 449.3514 -245.195344) (xy 449.346146 -245.194809) (xy 449.338706 -245.187389)
			(xy 449.338192 -245.182136) (xy 443.294008 -245.182136) (xy 443.293529 -245.187403) (xy 443.286068 -245.194843)
			(xy 443.2808 -245.195344) (xy 442.764926 -245.195344) (xy 442.757049 -245.195608) (xy 442.742046 -245.200408)
			(xy 442.735462 -245.204742) (xy 442.714385 -245.219134) (xy 442.66874 -245.241963) (xy 442.620134 -245.25752)
			(xy 442.569717 -245.265439) (xy 442.5442 -245.265956) (xy 442.518679 -245.265491) (xy 442.46825 -245.257591)
			(xy 442.419639 -245.242024) (xy 442.374002 -245.219161) (xy 442.352938 -245.204742) (xy 442.346337 -245.200443)
			(xy 442.331344 -245.195646) (xy 442.323474 -245.195344) (xy 441.8076 -245.195344) (xy 441.802346 -245.194809)
			(xy 441.794906 -245.187389) (xy 441.794392 -245.182136) (xy 435.750208 -245.182136) (xy 435.749729 -245.187403)
			(xy 435.742268 -245.194843) (xy 435.737 -245.195344) (xy 435.736492 -245.195344) (xy 435.220872 -245.195344)
			(xy 435.212997 -245.195628) (xy 435.197993 -245.200415) (xy 435.191408 -245.204742) (xy 435.170346 -245.219158)
			(xy 435.124696 -245.241981) (xy 435.076085 -245.257532) (xy 435.025664 -245.265443) (xy 435.000146 -245.265956)
			(xy 434.974626 -245.265468) (xy 434.924198 -245.257575) (xy 434.875586 -245.242014) (xy 434.829948 -245.219158)
			(xy 434.808884 -245.204742) (xy 434.802295 -245.200422) (xy 434.787293 -245.195638) (xy 434.77942 -245.195344)
			(xy 434.263546 -245.195344) (xy 434.258244 -245.194845) (xy 434.250669 -245.187427) (xy 434.250084 -245.182136)
			(xy 428.2059 -245.182136) (xy 428.205428 -245.187405) (xy 428.197963 -245.194846) (xy 428.192692 -245.195344)
			(xy 427.676818 -245.195344) (xy 427.668945 -245.195648) (xy 427.653941 -245.200421) (xy 427.647354 -245.204742)
			(xy 427.626279 -245.219138) (xy 427.580634 -245.241965) (xy 427.532027 -245.257522) (xy 427.481609 -245.26544)
			(xy 427.456092 -245.265956) (xy 427.430573 -245.265445) (xy 427.380146 -245.257558) (xy 427.331534 -245.242005)
			(xy 427.285895 -245.219155) (xy 427.26483 -245.204742) (xy 427.258231 -245.20044) (xy 427.243237 -245.195644)
			(xy 427.235366 -245.195344) (xy 426.719492 -245.195344) (xy 426.714237 -245.194814) (xy 426.706797 -245.18739)
			(xy 426.706284 -245.182136) (xy 420.6621 -245.182136) (xy 420.661628 -245.187405) (xy 420.654163 -245.194846)
			(xy 420.648892 -245.195344) (xy 420.648384 -245.195344) (xy 420.132764 -245.195344) (xy 420.124889 -245.195625)
			(xy 420.109885 -245.200414) (xy 420.1033 -245.204742) (xy 420.082212 -245.219118) (xy 420.036571 -245.24195)
			(xy 419.987968 -245.257512) (xy 419.937554 -245.265436) (xy 419.912038 -245.265956) (xy 419.886517 -245.265472)
			(xy 419.83609 -245.257577) (xy 419.787478 -245.242016) (xy 419.74184 -245.219159) (xy 419.720776 -245.204742)
			(xy 419.714189 -245.200419) (xy 419.699186 -245.195637) (xy 419.691312 -245.195344) (xy 419.175438 -245.195344)
			(xy 419.170135 -245.19485) (xy 419.162561 -245.187428) (xy 419.161976 -245.182136) (xy 413.117792 -245.182136)
			(xy 413.117327 -245.187407) (xy 413.109857 -245.194848) (xy 413.104584 -245.195344) (xy 411.631384 -245.195344)
			(xy 411.626128 -245.19482) (xy 411.618688 -245.187391) (xy 411.618176 -245.182136) (xy 363.28897 -245.182136)
			(xy 363.294473 -245.194681) (xy 363.306888 -245.243703) (xy 363.311065 -245.2941) (xy 363.306888 -245.344497)
			(xy 363.294473 -245.393519) (xy 363.274158 -245.439829) (xy 363.246497 -245.482163) (xy 363.212245 -245.519366)
			(xy 363.172336 -245.550424) (xy 363.127859 -245.574489) (xy 363.080028 -245.590904) (xy 363.030147 -245.599222)
			(xy 363.004862 -245.599712) (xy 362.064808 -245.599712) (xy 362.039533 -245.59912) (xy 361.989672 -245.590801)
			(xy 361.941861 -245.574388) (xy 361.897403 -245.55033) (xy 361.857511 -245.519282) (xy 361.823274 -245.482091)
			(xy 361.795626 -245.439773) (xy 361.775319 -245.393481) (xy 361.76291 -245.344477) (xy 361.758735 -245.2941)
			(xy 109.736939 -245.2941) (xy 109.736964 -245.2944) (xy 109.732792 -245.344746) (xy 109.72039 -245.393719)
			(xy 109.700095 -245.439982) (xy 109.672463 -245.482274) (xy 109.638246 -245.519441) (xy 109.598378 -245.550468)
			(xy 109.553947 -245.57451) (xy 109.506164 -245.59091) (xy 109.456333 -245.599221) (xy 109.431074 -245.599712)
			(xy 108.49102 -245.599712) (xy 108.465762 -245.599213) (xy 108.415933 -245.590901) (xy 108.368153 -245.574501)
			(xy 108.323723 -245.550459) (xy 108.283857 -245.519433) (xy 108.249642 -245.482267) (xy 108.222011 -245.439977)
			(xy 108.201717 -245.393715) (xy 108.189316 -245.344744) (xy 108.185144 -245.2944) (xy 2.509012 -245.2944)
			(xy 2.509012 -246.032528) (xy 20.958048 -246.032528) (xy 20.958048 -245.53799) (xy 20.958545 -245.532622)
			(xy 20.966142 -245.525037) (xy 20.97151 -245.524528) (xy 21.487638 -245.524528) (xy 21.495447 -245.5242)
			(xy 21.510319 -245.519425) (xy 21.516848 -245.51513) (xy 21.537937 -245.500781) (xy 21.583598 -245.47805)
			(xy 21.632204 -245.462591) (xy 21.682607 -245.454768) (xy 21.733613 -245.454768) (xy 21.784016 -245.462591)
			(xy 21.832622 -245.47805) (xy 21.878283 -245.500781) (xy 21.899372 -245.51513) (xy 21.905915 -245.519403)
			(xy 21.920776 -245.524198) (xy 21.928582 -245.524528) (xy 22.44471 -245.524528) (xy 22.450073 -245.525043)
			(xy 22.457657 -245.532627) (xy 22.458172 -245.53799) (xy 22.458172 -246.032528) (xy 28.502356 -246.032528)
			(xy 28.502356 -245.53799) (xy 28.502818 -245.532681) (xy 28.510264 -245.525109) (xy 28.515564 -245.524528)
			(xy 29.031692 -245.524528) (xy 29.039503 -245.524223) (xy 29.054375 -245.519432) (xy 29.060902 -245.51513)
			(xy 29.081991 -245.500781) (xy 29.127652 -245.47805) (xy 29.176258 -245.462591) (xy 29.226661 -245.454768)
			(xy 29.277667 -245.454768) (xy 29.32807 -245.462591) (xy 29.376676 -245.47805) (xy 29.422337 -245.500781)
			(xy 29.443426 -245.51513) (xy 29.449957 -245.519423) (xy 29.464827 -245.524206) (xy 29.472636 -245.524528)
			(xy 29.988764 -245.524528) (xy 29.9941 -245.524854) (xy 30.001646 -245.5324) (xy 30.001972 -245.537736)
			(xy 30.001972 -245.538244) (xy 30.001972 -246.032528) (xy 36.046156 -246.032528) (xy 36.046156 -245.53799)
			(xy 36.046618 -245.532681) (xy 36.054064 -245.525109) (xy 36.059364 -245.524528) (xy 36.575492 -245.524528)
			(xy 36.583303 -245.524223) (xy 36.598175 -245.519432) (xy 36.604702 -245.51513) (xy 36.625791 -245.500781)
			(xy 36.671452 -245.47805) (xy 36.720058 -245.462591) (xy 36.770461 -245.454768) (xy 36.821467 -245.454768)
			(xy 36.87187 -245.462591) (xy 36.920476 -245.47805) (xy 36.966137 -245.500781) (xy 36.987226 -245.51513)
			(xy 36.993757 -245.519423) (xy 37.008627 -245.524206) (xy 37.016436 -245.524528) (xy 37.532564 -245.524528)
			(xy 37.5379 -245.524854) (xy 37.545446 -245.5324) (xy 37.545772 -245.537736) (xy 37.545772 -245.538244)
			(xy 37.545772 -246.032528) (xy 43.589956 -246.032528) (xy 43.589956 -245.53799) (xy 43.590274 -245.532549)
			(xy 43.597977 -245.524863) (xy 43.603418 -245.524528) (xy 44.119546 -245.524528) (xy 44.127355 -245.524203)
			(xy 44.142227 -245.519426) (xy 44.148756 -245.51513) (xy 44.169845 -245.500781) (xy 44.215506 -245.47805)
			(xy 44.264112 -245.462591) (xy 44.314515 -245.454768) (xy 44.365521 -245.454768) (xy 44.415924 -245.462591)
			(xy 44.46453 -245.47805) (xy 44.510191 -245.500781) (xy 44.53128 -245.51513) (xy 44.537821 -245.519406)
			(xy 44.552683 -245.5242) (xy 44.56049 -245.524528) (xy 45.076618 -245.524528) (xy 45.081982 -245.525037)
			(xy 45.089566 -245.532626) (xy 45.09008 -245.53799) (xy 45.09008 -246.032528) (xy 51.134264 -246.032528)
			(xy 51.134264 -245.53799) (xy 51.134719 -245.532679) (xy 51.14217 -245.525107) (xy 51.147472 -245.524528)
			(xy 51.6636 -245.524528) (xy 51.671411 -245.524226) (xy 51.686283 -245.519433) (xy 51.69281 -245.51513)
			(xy 51.713899 -245.500781) (xy 51.75956 -245.47805) (xy 51.808166 -245.462591) (xy 51.858569 -245.454768)
			(xy 51.909575 -245.454768) (xy 51.959978 -245.462591) (xy 52.008584 -245.47805) (xy 52.054245 -245.500781)
			(xy 52.075334 -245.51513) (xy 52.081863 -245.519426) (xy 52.096735 -245.524207) (xy 52.104544 -245.524528)
			(xy 52.620672 -245.524528) (xy 52.626009 -245.524849) (xy 52.633554 -245.532398) (xy 52.63388 -245.537736)
			(xy 52.63388 -245.538244) (xy 52.63388 -246.032528) (xy 58.678064 -246.032528) (xy 58.678064 -245.53799)
			(xy 58.678375 -245.532547) (xy 58.686083 -245.52486) (xy 58.691526 -245.524528) (xy 60.164726 -245.524528)
			(xy 60.170091 -245.525032) (xy 60.177674 -245.532625) (xy 60.178188 -245.53799) (xy 60.178188 -246.032528)
			(xy 60.177722 -246.037799) (xy 60.170253 -246.045241) (xy 60.16498 -246.045736) (xy 60.164472 -246.045736)
			(xy 58.691526 -246.045736) (xy 58.686219 -246.045257) (xy 58.678645 -246.037825) (xy 58.678064 -246.032528)
			(xy 52.63388 -246.032528) (xy 52.633421 -246.037801) (xy 52.625947 -246.045244) (xy 52.620672 -246.045736)
			(xy 52.104798 -246.045736) (xy 52.096924 -246.046033) (xy 52.08192 -246.050811) (xy 52.075334 -246.055134)
			(xy 52.054264 -246.069537) (xy 52.008617 -246.092363) (xy 51.971002 -246.1044) (xy 97.374895 -246.1044)
			(xy 97.379071 -246.054013) (xy 97.391483 -246.005001) (xy 97.411794 -245.958701) (xy 97.439449 -245.916375)
			(xy 97.473694 -245.879179) (xy 97.513595 -245.848128) (xy 97.558062 -245.824068) (xy 97.605884 -245.807655)
			(xy 97.655754 -245.799338) (xy 97.681034 -245.798848) (xy 98.621088 -245.798848) (xy 98.646368 -245.79932)
			(xy 98.696239 -245.80764) (xy 98.744061 -245.824056) (xy 98.788528 -245.848119) (xy 98.828428 -245.879173)
			(xy 98.862672 -245.91637) (xy 98.890327 -245.958698) (xy 98.910637 -246.004999) (xy 98.923049 -246.054012)
			(xy 98.927225 -246.1044) (xy 100.194795 -246.1044) (xy 100.198971 -246.054012) (xy 100.211384 -246.005)
			(xy 100.231695 -245.958699) (xy 100.259351 -245.916373) (xy 100.293597 -245.879177) (xy 100.333499 -245.848125)
			(xy 100.377968 -245.824065) (xy 100.42579 -245.807654) (xy 100.475662 -245.799338) (xy 100.500942 -245.798848)
			(xy 101.440996 -245.798848) (xy 101.466276 -245.799321) (xy 101.516146 -245.807642) (xy 101.563966 -245.824058)
			(xy 101.608432 -245.848121) (xy 101.648331 -245.879175) (xy 101.682574 -245.916373) (xy 101.710228 -245.9587)
			(xy 101.730538 -246.005001) (xy 101.742949 -246.054013) (xy 101.747125 -246.1044) (xy 103.014995 -246.1044)
			(xy 103.01917 -246.054016) (xy 103.031581 -246.005007) (xy 103.05189 -245.958709) (xy 103.079542 -245.916385)
			(xy 103.113783 -245.87919) (xy 103.153679 -245.848138) (xy 103.198142 -245.824076) (xy 103.245959 -245.807661)
			(xy 103.295826 -245.799341) (xy 103.321104 -245.798848) (xy 104.261158 -245.798848) (xy 104.28644 -245.799318)
			(xy 104.336315 -245.807634) (xy 104.38414 -245.824047) (xy 104.428612 -245.848108) (xy 104.468516 -245.879162)
			(xy 104.502764 -245.91636) (xy 104.530422 -245.958689) (xy 104.550735 -246.004993) (xy 104.563149 -246.054009)
			(xy 104.567325 -246.1044) (xy 105.834895 -246.1044) (xy 105.839071 -246.054016) (xy 105.851482 -246.005006)
			(xy 105.871791 -245.958707) (xy 105.899444 -245.916383) (xy 105.933686 -245.879187) (xy 105.973583 -245.848135)
			(xy 106.018047 -245.824074) (xy 106.065866 -245.80766) (xy 106.115733 -245.79934) (xy 106.141012 -245.798848)
			(xy 107.081066 -245.798848) (xy 107.106347 -245.799318) (xy 107.156221 -245.807636) (xy 107.204046 -245.824049)
			(xy 107.248516 -245.848111) (xy 107.288419 -245.879165) (xy 107.322666 -245.916363) (xy 107.350323 -245.958691)
			(xy 107.370636 -246.004995) (xy 107.377609 -246.032528) (xy 167.778176 -246.032528) (xy 167.778176 -245.53799)
			(xy 167.778621 -245.532676) (xy 167.786078 -245.525104) (xy 167.791384 -245.524528) (xy 169.264584 -245.524528)
			(xy 169.269923 -245.524841) (xy 169.277467 -245.532397) (xy 169.277792 -245.537736) (xy 169.277792 -245.538244)
			(xy 169.277792 -246.032528) (xy 175.321976 -246.032528) (xy 175.321976 -245.53799) (xy 175.322276 -245.532545)
			(xy 175.329991 -245.524857) (xy 175.335438 -245.524528) (xy 175.851566 -245.524528) (xy 175.859376 -245.524212)
			(xy 175.874248 -245.519429) (xy 175.880776 -245.51513) (xy 175.901865 -245.500781) (xy 175.947526 -245.47805)
			(xy 175.996132 -245.462591) (xy 176.046535 -245.454768) (xy 176.097541 -245.454768) (xy 176.147944 -245.462591)
			(xy 176.19655 -245.47805) (xy 176.242211 -245.500781) (xy 176.2633 -245.51513) (xy 176.269836 -245.519413)
			(xy 176.284702 -245.524203) (xy 176.29251 -245.524528) (xy 176.808638 -245.524528) (xy 176.814004 -245.525024)
			(xy 176.821587 -245.532623) (xy 176.8221 -245.53799) (xy 176.8221 -246.032528) (xy 182.866284 -246.032528)
			(xy 182.866284 -245.53799) (xy 182.866722 -245.532674) (xy 182.874184 -245.525101) (xy 182.879492 -245.524528)
			(xy 183.39562 -245.524528) (xy 183.403432 -245.524235) (xy 183.418304 -245.519436) (xy 183.42483 -245.51513)
			(xy 183.445919 -245.500781) (xy 183.49158 -245.47805) (xy 183.540186 -245.462591) (xy 183.590589 -245.454768)
			(xy 183.641595 -245.454768) (xy 183.691998 -245.462591) (xy 183.740604 -245.47805) (xy 183.786265 -245.500781)
			(xy 183.807354 -245.51513) (xy 183.813878 -245.519434) (xy 183.828754 -245.52421) (xy 183.836564 -245.524528)
			(xy 184.352692 -245.524528) (xy 184.358032 -245.524836) (xy 184.365576 -245.532395) (xy 184.3659 -245.537736)
			(xy 184.3659 -245.538244) (xy 184.3659 -246.032528) (xy 190.410084 -246.032528) (xy 190.410084 -245.53799)
			(xy 190.410377 -245.532543) (xy 190.418097 -245.524854) (xy 190.423546 -245.524528) (xy 190.939674 -245.524528)
			(xy 190.947484 -245.524215) (xy 190.962356 -245.51943) (xy 190.968884 -245.51513) (xy 190.989973 -245.500781)
			(xy 191.035634 -245.47805) (xy 191.08424 -245.462591) (xy 191.134643 -245.454768) (xy 191.185649 -245.454768)
			(xy 191.236052 -245.462591) (xy 191.284658 -245.47805) (xy 191.330319 -245.500781) (xy 191.351408 -245.51513)
			(xy 191.357943 -245.519416) (xy 191.37281 -245.524204) (xy 191.380618 -245.524528) (xy 191.896746 -245.524528)
			(xy 191.902113 -245.525019) (xy 191.909696 -245.532622) (xy 191.910208 -245.53799) (xy 191.910208 -246.032528)
			(xy 197.954392 -246.032528) (xy 197.954392 -245.53799) (xy 197.954911 -245.532696) (xy 197.962318 -245.525128)
			(xy 197.9676 -245.524528) (xy 198.483728 -245.524528) (xy 198.49154 -245.524238) (xy 198.506412 -245.519437)
			(xy 198.512938 -245.51513) (xy 198.534027 -245.500781) (xy 198.579688 -245.47805) (xy 198.628294 -245.462591)
			(xy 198.678697 -245.454768) (xy 198.729703 -245.454768) (xy 198.780106 -245.462591) (xy 198.828712 -245.47805)
			(xy 198.874373 -245.500781) (xy 198.895462 -245.51513) (xy 198.902007 -245.519399) (xy 198.916866 -245.524197)
			(xy 198.924672 -245.524528) (xy 199.4408 -245.524528) (xy 199.446141 -245.52483) (xy 199.453684 -245.532394)
			(xy 199.454008 -245.537736) (xy 199.454008 -245.538244) (xy 199.454008 -246.032528) (xy 205.498192 -246.032528)
			(xy 205.498192 -245.53799) (xy 205.498711 -245.532696) (xy 205.506118 -245.525128) (xy 205.5114 -245.524528)
			(xy 206.027528 -245.524528) (xy 206.03534 -245.524238) (xy 206.050212 -245.519437) (xy 206.056738 -245.51513)
			(xy 206.077827 -245.500781) (xy 206.123488 -245.47805) (xy 206.172094 -245.462591) (xy 206.222497 -245.454768)
			(xy 206.273503 -245.454768) (xy 206.323906 -245.462591) (xy 206.372512 -245.47805) (xy 206.418173 -245.500781)
			(xy 206.439262 -245.51513) (xy 206.445807 -245.519399) (xy 206.460666 -245.524197) (xy 206.468472 -245.524528)
			(xy 206.9846 -245.524528) (xy 206.989941 -245.52483) (xy 206.997484 -245.532394) (xy 206.997808 -245.537736)
			(xy 206.997808 -245.538244) (xy 206.997808 -246.032274) (xy 268.898116 -246.032274) (xy 268.898116 -245.537736)
			(xy 268.898453 -245.532403) (xy 268.905991 -245.524858) (xy 268.911324 -245.524528) (xy 268.911832 -245.524528)
			(xy 269.427706 -245.524528) (xy 269.435518 -245.524229) (xy 269.450389 -245.519434) (xy 269.456916 -245.51513)
			(xy 269.478005 -245.500781) (xy 269.523666 -245.47805) (xy 269.572272 -245.462591) (xy 269.622675 -245.454768)
			(xy 269.673681 -245.454768) (xy 269.724084 -245.462591) (xy 269.77269 -245.47805) (xy 269.818351 -245.500781)
			(xy 269.83944 -245.51513) (xy 269.845967 -245.519429) (xy 269.86084 -245.524208) (xy 269.86865 -245.524528)
			(xy 270.384778 -245.524528) (xy 270.390077 -245.525036) (xy 270.397649 -245.532449) (xy 270.39824 -245.537736)
			(xy 270.39824 -246.032274) (xy 270.398224 -246.032528) (xy 276.442424 -246.032528) (xy 276.442424 -246.03202)
			(xy 276.442424 -245.537736) (xy 276.442754 -245.532401) (xy 276.450297 -245.524856) (xy 276.455632 -245.524528)
			(xy 276.97176 -245.524528) (xy 276.97957 -245.524209) (xy 276.994442 -245.519428) (xy 277.00097 -245.51513)
			(xy 277.022059 -245.500781) (xy 277.06772 -245.47805) (xy 277.116326 -245.462591) (xy 277.166729 -245.454768)
			(xy 277.217735 -245.454768) (xy 277.268138 -245.462591) (xy 277.316744 -245.47805) (xy 277.362405 -245.500781)
			(xy 277.383494 -245.51513) (xy 277.390032 -245.519411) (xy 277.404897 -245.524202) (xy 277.412704 -245.524528)
			(xy 277.928832 -245.524528) (xy 277.934177 -245.524809) (xy 277.941718 -245.532389) (xy 277.94204 -245.537736)
			(xy 277.94204 -246.032274) (xy 277.942017 -246.032528) (xy 283.986224 -246.032528) (xy 283.986224 -246.03202)
			(xy 283.986224 -245.537736) (xy 283.986554 -245.532401) (xy 283.994097 -245.524856) (xy 283.999432 -245.524528)
			(xy 284.51556 -245.524528) (xy 284.52337 -245.524209) (xy 284.538242 -245.519428) (xy 284.54477 -245.51513)
			(xy 284.565859 -245.500781) (xy 284.61152 -245.47805) (xy 284.660126 -245.462591) (xy 284.710529 -245.454768)
			(xy 284.761535 -245.454768) (xy 284.811938 -245.462591) (xy 284.860544 -245.47805) (xy 284.906205 -245.500781)
			(xy 284.927294 -245.51513) (xy 284.933832 -245.519411) (xy 284.948697 -245.524202) (xy 284.956504 -245.524528)
			(xy 285.472632 -245.524528) (xy 285.477977 -245.524809) (xy 285.485518 -245.532389) (xy 285.48584 -245.537736)
			(xy 285.48584 -246.032274) (xy 291.530024 -246.032274) (xy 291.530024 -245.537736) (xy 291.530354 -245.532401)
			(xy 291.537897 -245.524856) (xy 291.543232 -245.524528) (xy 291.54374 -245.524528) (xy 292.059614 -245.524528)
			(xy 292.067426 -245.524232) (xy 292.082298 -245.519435) (xy 292.088824 -245.51513) (xy 292.109913 -245.500781)
			(xy 292.155574 -245.47805) (xy 292.20418 -245.462591) (xy 292.254583 -245.454768) (xy 292.305589 -245.454768)
			(xy 292.355992 -245.462591) (xy 292.404598 -245.47805) (xy 292.450259 -245.500781) (xy 292.471348 -245.51513)
			(xy 292.477874 -245.519432) (xy 292.492748 -245.52421) (xy 292.500558 -245.524528) (xy 293.016686 -245.524528)
			(xy 293.021986 -245.525031) (xy 293.029557 -245.532447) (xy 293.030148 -245.537736) (xy 293.030148 -246.032274)
			(xy 293.030132 -246.032528) (xy 299.074332 -246.032528) (xy 299.074332 -246.03202) (xy 299.074332 -245.537736)
			(xy 299.074655 -245.532399) (xy 299.082203 -245.524853) (xy 299.08754 -245.524528) (xy 299.603668 -245.524528)
			(xy 299.611478 -245.524213) (xy 299.62635 -245.519429) (xy 299.632878 -245.51513) (xy 299.653967 -245.500781)
			(xy 299.699628 -245.47805) (xy 299.748234 -245.462591) (xy 299.798637 -245.454768) (xy 299.849643 -245.454768)
			(xy 299.900046 -245.462591) (xy 299.948652 -245.47805) (xy 299.994313 -245.500781) (xy 300.015402 -245.51513)
			(xy 300.021938 -245.519414) (xy 300.036804 -245.524203) (xy 300.044612 -245.524528) (xy 300.56074 -245.524528)
			(xy 300.566016 -245.524972) (xy 300.573459 -245.532457) (xy 300.573948 -245.537736) (xy 300.573948 -246.032274)
			(xy 306.618132 -246.032274) (xy 306.618132 -245.537736) (xy 306.618455 -245.532399) (xy 306.626003 -245.524853)
			(xy 306.63134 -245.524528) (xy 306.631848 -245.524528) (xy 308.104794 -245.524528) (xy 308.110095 -245.525026)
			(xy 308.117665 -245.532446) (xy 308.118256 -245.537736) (xy 308.118256 -246.032274) (xy 308.117903 -246.037707)
			(xy 308.110226 -246.045395) (xy 308.104794 -246.045736) (xy 306.631594 -246.045736) (xy 306.626152 -246.045422)
			(xy 306.618465 -246.037717) (xy 306.618132 -246.032274) (xy 300.573948 -246.032274) (xy 300.573458 -246.037578)
			(xy 300.566033 -246.045151) (xy 300.56074 -246.045736) (xy 300.044866 -246.045736) (xy 300.037058 -246.046072)
			(xy 300.022186 -246.050842) (xy 300.015656 -246.055134) (xy 299.994543 -246.069496) (xy 299.948816 -246.092221)
			(xy 299.911017 -246.1042) (xy 364.108896 -246.1042) (xy 364.113068 -246.053848) (xy 364.125472 -246.00487)
			(xy 364.145768 -245.958601) (xy 364.173403 -245.916305) (xy 364.207623 -245.879133) (xy 364.247495 -245.848102)
			(xy 364.291931 -245.824057) (xy 364.339718 -245.807653) (xy 364.389554 -245.79934) (xy 364.414816 -245.798848)
			(xy 365.35487 -245.798848) (xy 365.380126 -245.799426) (xy 365.429949 -245.807736) (xy 365.477725 -245.824133)
			(xy 365.52215 -245.848171) (xy 365.562012 -245.879193) (xy 365.596224 -245.916354) (xy 365.623853 -245.958639)
			(xy 365.644144 -246.004896) (xy 365.656545 -246.053861) (xy 365.660716 -246.1042) (xy 366.928796 -246.1042)
			(xy 366.932969 -246.053847) (xy 366.945372 -246.004868) (xy 366.965669 -245.958599) (xy 366.993305 -245.916302)
			(xy 367.027526 -245.879131) (xy 367.067399 -245.848099) (xy 367.111836 -245.824054) (xy 367.159625 -245.807652)
			(xy 367.209461 -245.799339) (xy 367.234724 -245.798848) (xy 368.174778 -245.798848) (xy 368.200033 -245.799427)
			(xy 368.249855 -245.807737) (xy 368.29763 -245.824135) (xy 368.342054 -245.848173) (xy 368.381915 -245.879196)
			(xy 368.416126 -245.916357) (xy 368.443754 -245.958642) (xy 368.464045 -246.004897) (xy 368.476445 -246.053862)
			(xy 368.480616 -246.1042) (xy 369.749024 -246.1042) (xy 369.753196 -246.053856) (xy 369.765597 -246.004885)
			(xy 369.785888 -245.958623) (xy 369.813518 -245.916332) (xy 369.847731 -245.879165) (xy 369.887595 -245.848136)
			(xy 369.932022 -245.824092) (xy 369.979801 -245.807687) (xy 370.029628 -245.79937) (xy 370.054886 -245.798848)
			(xy 370.99494 -245.798848) (xy 371.02019 -245.799461) (xy 371.069999 -245.807778) (xy 371.11776 -245.82418)
			(xy 371.162171 -245.848219) (xy 371.202019 -245.879239) (xy 371.236219 -245.916395) (xy 371.263838 -245.958673)
			(xy 371.284121 -246.004919) (xy 371.296517 -246.053873) (xy 371.300687 -246.1042) (xy 372.568924 -246.1042)
			(xy 372.573096 -246.053855) (xy 372.585497 -246.004884) (xy 372.60579 -245.958621) (xy 372.63342 -245.916329)
			(xy 372.667634 -245.879162) (xy 372.707499 -245.848133) (xy 372.751927 -245.824089) (xy 372.799707 -245.807685)
			(xy 372.849535 -245.79937) (xy 372.874794 -245.798848) (xy 373.814848 -245.798848) (xy 373.840097 -245.799461)
			(xy 373.889906 -245.80778) (xy 373.937666 -245.824183) (xy 373.982075 -245.848222) (xy 374.021923 -245.879242)
			(xy 374.056121 -245.916398) (xy 374.083739 -245.958675) (xy 374.104022 -246.004921) (xy 374.111012 -246.032528)
			(xy 415.718244 -246.032528) (xy 415.718244 -246.03202) (xy 415.718244 -245.537736) (xy 415.718814 -245.532489)
			(xy 415.726208 -245.525047) (xy 415.731452 -245.524528) (xy 417.204652 -245.524528) (xy 417.209987 -245.524863)
			(xy 417.217532 -245.532402) (xy 417.21786 -245.537736) (xy 417.21786 -246.032274) (xy 423.262044 -246.032274)
			(xy 423.262044 -245.537736) (xy 423.262614 -245.532489) (xy 423.270008 -245.525047) (xy 423.275252 -245.524528)
			(xy 423.27576 -245.524528) (xy 423.791634 -245.524528) (xy 423.799443 -245.524198) (xy 423.814315 -245.519425)
			(xy 423.820844 -245.51513) (xy 423.841933 -245.500781) (xy 423.887594 -245.47805) (xy 423.9362 -245.462591)
			(xy 423.986603 -245.454768) (xy 424.037609 -245.454768) (xy 424.088012 -245.462591) (xy 424.136618 -245.47805)
			(xy 424.182279 -245.500781) (xy 424.203368 -245.51513) (xy 424.209911 -245.519401) (xy 424.224772 -245.524198)
			(xy 424.232578 -245.524528) (xy 424.748706 -245.524528) (xy 424.754008 -245.525018) (xy 424.761578 -245.532444)
			(xy 424.762168 -245.537736) (xy 424.762168 -246.032274) (xy 424.762151 -246.032528) (xy 430.806352 -246.032528)
			(xy 430.806352 -246.03202) (xy 430.806352 -245.537736) (xy 430.806915 -245.532487) (xy 430.814314 -245.525045)
			(xy 430.81956 -245.524528) (xy 431.335688 -245.524528) (xy 431.343499 -245.524221) (xy 431.358371 -245.519432)
			(xy 431.364898 -245.51513) (xy 431.385987 -245.500781) (xy 431.431648 -245.47805) (xy 431.480254 -245.462591)
			(xy 431.530657 -245.454768) (xy 431.581663 -245.454768) (xy 431.632066 -245.462591) (xy 431.680672 -245.47805)
			(xy 431.726333 -245.500781) (xy 431.747422 -245.51513) (xy 431.753953 -245.519422) (xy 431.768823 -245.524206)
			(xy 431.776632 -245.524528) (xy 432.29276 -245.524528) (xy 432.298096 -245.524857) (xy 432.305641 -245.532401)
			(xy 432.305968 -245.537736) (xy 432.305968 -246.032274) (xy 438.350152 -246.032274) (xy 438.350152 -245.537736)
			(xy 438.350715 -245.532487) (xy 438.358114 -245.525045) (xy 438.36336 -245.524528) (xy 438.363868 -245.524528)
			(xy 438.879742 -245.524528) (xy 438.887551 -245.524202) (xy 438.902423 -245.519426) (xy 438.908952 -245.51513)
			(xy 438.930041 -245.500781) (xy 438.975702 -245.47805) (xy 439.024308 -245.462591) (xy 439.074711 -245.454768)
			(xy 439.125717 -245.454768) (xy 439.17612 -245.462591) (xy 439.224726 -245.47805) (xy 439.270387 -245.500781)
			(xy 439.291476 -245.51513) (xy 439.298018 -245.519404) (xy 439.31288 -245.524199) (xy 439.320686 -245.524528)
			(xy 439.836814 -245.524528) (xy 439.842117 -245.525013) (xy 439.849686 -245.532443) (xy 439.850276 -245.537736)
			(xy 439.850276 -246.032274) (xy 439.850259 -246.032528) (xy 445.89446 -246.032528) (xy 445.89446 -246.03202)
			(xy 445.89446 -245.537736) (xy 445.894848 -245.532416) (xy 445.90235 -245.524875) (xy 445.907668 -245.524528)
			(xy 446.423796 -245.524528) (xy 446.431607 -245.524225) (xy 446.446479 -245.519433) (xy 446.453006 -245.51513)
			(xy 446.474095 -245.500781) (xy 446.519756 -245.47805) (xy 446.568362 -245.462591) (xy 446.618765 -245.454768)
			(xy 446.669771 -245.454768) (xy 446.720174 -245.462591) (xy 446.76878 -245.47805) (xy 446.814441 -245.500781)
			(xy 446.83553 -245.51513) (xy 446.84206 -245.519425) (xy 446.856931 -245.524207) (xy 446.86474 -245.524528)
			(xy 447.380868 -245.524528) (xy 447.386205 -245.524852) (xy 447.39375 -245.532399) (xy 447.394076 -245.537736)
			(xy 447.394076 -246.032274) (xy 447.394051 -246.032528) (xy 453.43826 -246.032528) (xy 453.43826 -246.03202)
			(xy 453.43826 -245.537736) (xy 453.438648 -245.532416) (xy 453.44615 -245.524875) (xy 453.451468 -245.524528)
			(xy 453.967596 -245.524528) (xy 453.975407 -245.524225) (xy 453.990279 -245.519433) (xy 453.996806 -245.51513)
			(xy 454.017895 -245.500781) (xy 454.063556 -245.47805) (xy 454.112162 -245.462591) (xy 454.162565 -245.454768)
			(xy 454.213571 -245.454768) (xy 454.263974 -245.462591) (xy 454.31258 -245.47805) (xy 454.358241 -245.500781)
			(xy 454.37933 -245.51513) (xy 454.38586 -245.519425) (xy 454.400731 -245.524207) (xy 454.40854 -245.524528)
			(xy 454.924668 -245.524528) (xy 454.930005 -245.524852) (xy 454.93755 -245.532399) (xy 454.937876 -245.537736)
			(xy 454.937876 -246.032274) (xy 454.937361 -246.037571) (xy 454.929954 -246.045143) (xy 454.924668 -246.045736)
			(xy 454.408794 -246.045736) (xy 454.400983 -246.046041) (xy 454.386111 -246.050832) (xy 454.379584 -246.055134)
			(xy 454.358463 -246.069484) (xy 454.312739 -246.092211) (xy 454.264066 -246.107641) (xy 454.213599 -246.115407)
			(xy 454.188068 -246.11584) (xy 454.162537 -246.115424) (xy 454.112072 -246.107643) (xy 454.0634 -246.092208)
			(xy 454.017673 -246.069485) (xy 453.996552 -246.055134) (xy 453.990028 -246.050829) (xy 453.975152 -246.046054)
			(xy 453.967342 -246.045736) (xy 453.451468 -246.045736) (xy 453.446208 -246.045229) (xy 453.438769 -246.037788)
			(xy 453.43826 -246.032528) (xy 447.394051 -246.032528) (xy 447.393561 -246.037571) (xy 447.386154 -246.045143)
			(xy 447.380868 -246.045736) (xy 446.864994 -246.045736) (xy 446.857183 -246.046041) (xy 446.842311 -246.050832)
			(xy 446.835784 -246.055134) (xy 446.814663 -246.069484) (xy 446.768939 -246.092211) (xy 446.720266 -246.107641)
			(xy 446.669799 -246.115407) (xy 446.644268 -246.11584) (xy 446.618737 -246.115424) (xy 446.568272 -246.107643)
			(xy 446.5196 -246.092208) (xy 446.473873 -246.069485) (xy 446.452752 -246.055134) (xy 446.446228 -246.050829)
			(xy 446.431352 -246.046054) (xy 446.423542 -246.045736) (xy 445.907668 -246.045736) (xy 445.902408 -246.045229)
			(xy 445.894969 -246.037788) (xy 445.89446 -246.032528) (xy 439.850259 -246.032528) (xy 439.849905 -246.037702)
			(xy 439.842241 -246.045389) (xy 439.836814 -246.045736) (xy 439.32094 -246.045736) (xy 439.313131 -246.046061)
			(xy 439.298259 -246.050839) (xy 439.29173 -246.055134) (xy 439.270624 -246.069508) (xy 439.224895 -246.092229)
			(xy 439.176217 -246.107653) (xy 439.125746 -246.115411) (xy 439.100214 -246.11584) (xy 439.074684 -246.115401)
			(xy 439.02422 -246.107626) (xy 438.975547 -246.092198) (xy 438.92982 -246.069482) (xy 438.908698 -246.055134)
			(xy 438.902164 -246.050847) (xy 438.887296 -246.046061) (xy 438.879488 -246.045736) (xy 438.363614 -246.045736)
			(xy 438.358175 -246.045409) (xy 438.350486 -246.037714) (xy 438.350152 -246.032274) (xy 432.305968 -246.032274)
			(xy 432.30546 -246.037573) (xy 432.298048 -246.045145) (xy 432.29276 -246.045736) (xy 431.776886 -246.045736)
			(xy 431.769075 -246.046038) (xy 431.754203 -246.050831) (xy 431.747676 -246.055134) (xy 431.726557 -246.069488)
			(xy 431.680833 -246.092214) (xy 431.632158 -246.107643) (xy 431.581691 -246.115408) (xy 431.55616 -246.11584)
			(xy 431.530629 -246.115428) (xy 431.480164 -246.107645) (xy 431.431491 -246.092209) (xy 431.385765 -246.069485)
			(xy 431.364644 -246.055134) (xy 431.358122 -246.050826) (xy 431.343245 -246.046053) (xy 431.335434 -246.045736)
			(xy 430.81956 -246.045736) (xy 430.814299 -246.045235) (xy 430.80686 -246.037789) (xy 430.806352 -246.032528)
			(xy 424.762151 -246.032528) (xy 424.761804 -246.037704) (xy 424.754135 -246.045391) (xy 424.748706 -246.045736)
			(xy 424.232832 -246.045736) (xy 424.225023 -246.046057) (xy 424.210151 -246.050838) (xy 424.203622 -246.055134)
			(xy 424.18249 -246.069468) (xy 424.13677 -246.092199) (xy 424.0881 -246.107633) (xy 424.037636 -246.115404)
			(xy 424.012106 -246.11584) (xy 423.986576 -246.115405) (xy 423.936112 -246.107629) (xy 423.887439 -246.0922)
			(xy 423.841712 -246.069482) (xy 423.82059 -246.055134) (xy 423.814058 -246.050844) (xy 423.799188 -246.04606)
			(xy 423.79138 -246.045736) (xy 423.275506 -246.045736) (xy 423.270066 -246.045414) (xy 423.262378 -246.037715)
			(xy 423.262044 -246.032274) (xy 417.21786 -246.032274) (xy 417.217359 -246.037575) (xy 417.209942 -246.045148)
			(xy 417.204652 -246.045736) (xy 415.731452 -246.045736) (xy 415.72619 -246.04524) (xy 415.718752 -246.03779)
			(xy 415.718244 -246.032528) (xy 374.111012 -246.032528) (xy 374.116417 -246.053874) (xy 374.120587 -246.1042)
			(xy 374.116417 -246.154526) (xy 374.104022 -246.203479) (xy 374.083739 -246.249725) (xy 374.056121 -246.292002)
			(xy 374.021923 -246.329158) (xy 373.982075 -246.360178) (xy 373.937666 -246.384217) (xy 373.889906 -246.40062)
			(xy 373.840097 -246.408939) (xy 373.814848 -246.409464) (xy 372.874794 -246.409464) (xy 372.849535 -246.40903)
			(xy 372.799707 -246.400715) (xy 372.751927 -246.384311) (xy 372.707499 -246.360267) (xy 372.667634 -246.329238)
			(xy 372.63342 -246.292071) (xy 372.60579 -246.249779) (xy 372.585497 -246.203516) (xy 372.573096 -246.154545)
			(xy 372.568924 -246.1042) (xy 371.300687 -246.1042) (xy 371.296517 -246.154527) (xy 371.284121 -246.203481)
			(xy 371.263838 -246.249727) (xy 371.236219 -246.292005) (xy 371.202019 -246.329161) (xy 371.162171 -246.360181)
			(xy 371.11776 -246.38422) (xy 371.069999 -246.400622) (xy 371.02019 -246.408939) (xy 370.99494 -246.409464)
			(xy 370.054886 -246.409464) (xy 370.029628 -246.40903) (xy 369.979801 -246.400713) (xy 369.932022 -246.384308)
			(xy 369.887595 -246.360264) (xy 369.847731 -246.329235) (xy 369.813518 -246.292068) (xy 369.785888 -246.249777)
			(xy 369.765597 -246.203515) (xy 369.753196 -246.154544) (xy 369.749024 -246.1042) (xy 368.480616 -246.1042)
			(xy 368.476445 -246.154538) (xy 368.464045 -246.203503) (xy 368.443754 -246.249758) (xy 368.416126 -246.292043)
			(xy 368.381915 -246.329204) (xy 368.342054 -246.360227) (xy 368.29763 -246.384265) (xy 368.249855 -246.400663)
			(xy 368.200033 -246.408973) (xy 368.174778 -246.409464) (xy 367.234724 -246.409464) (xy 367.209461 -246.409061)
			(xy 367.159625 -246.400748) (xy 367.111836 -246.384346) (xy 367.067399 -246.360301) (xy 367.027526 -246.329269)
			(xy 366.993305 -246.292098) (xy 366.965669 -246.249801) (xy 366.945372 -246.203532) (xy 366.932969 -246.154553)
			(xy 366.928796 -246.1042) (xy 365.660716 -246.1042) (xy 365.656545 -246.154539) (xy 365.644144 -246.203504)
			(xy 365.623853 -246.249761) (xy 365.596224 -246.292046) (xy 365.562012 -246.329207) (xy 365.52215 -246.360229)
			(xy 365.477725 -246.384267) (xy 365.429949 -246.400664) (xy 365.380126 -246.408974) (xy 365.35487 -246.409464)
			(xy 364.414816 -246.409464) (xy 364.389554 -246.40906) (xy 364.339718 -246.400747) (xy 364.291931 -246.384343)
			(xy 364.247495 -246.360298) (xy 364.207623 -246.329267) (xy 364.173403 -246.292095) (xy 364.145768 -246.249799)
			(xy 364.125472 -246.20353) (xy 364.113068 -246.154552) (xy 364.108896 -246.1042) (xy 299.911017 -246.1042)
			(xy 299.90014 -246.107647) (xy 299.849672 -246.115409) (xy 299.82414 -246.11584) (xy 299.79861 -246.115388)
			(xy 299.748147 -246.107617) (xy 299.699474 -246.092193) (xy 299.653746 -246.06948) (xy 299.632624 -246.055134)
			(xy 299.626084 -246.050857) (xy 299.611221 -246.046065) (xy 299.603414 -246.045736) (xy 299.08754 -246.045736)
			(xy 299.08222 -246.045349) (xy 299.074678 -246.037846) (xy 299.074332 -246.032528) (xy 293.030132 -246.032528)
			(xy 293.029802 -246.037709) (xy 293.02212 -246.045397) (xy 293.016686 -246.045736) (xy 292.500812 -246.045736)
			(xy 292.493002 -246.046049) (xy 292.47813 -246.050835) (xy 292.471602 -246.055134) (xy 292.450476 -246.069476)
			(xy 292.404754 -246.092205) (xy 292.356082 -246.107637) (xy 292.305617 -246.115406) (xy 292.280086 -246.11584)
			(xy 292.254555 -246.115415) (xy 292.204091 -246.107636) (xy 292.155418 -246.092204) (xy 292.109691 -246.069483)
			(xy 292.08857 -246.055134) (xy 292.082042 -246.050836) (xy 292.067169 -246.046057) (xy 292.05936 -246.045736)
			(xy 291.543486 -246.045736) (xy 291.538043 -246.045427) (xy 291.530356 -246.037718) (xy 291.530024 -246.032274)
			(xy 285.48584 -246.032274) (xy 285.485357 -246.03758) (xy 285.477927 -246.045153) (xy 285.472632 -246.045736)
			(xy 284.956758 -246.045736) (xy 284.94895 -246.046068) (xy 284.934078 -246.050841) (xy 284.927548 -246.055134)
			(xy 284.906437 -246.0695) (xy 284.86071 -246.092223) (xy 284.812033 -246.107649) (xy 284.761564 -246.11541)
			(xy 284.736032 -246.11584) (xy 284.710502 -246.115392) (xy 284.660039 -246.10762) (xy 284.611366 -246.092195)
			(xy 284.565638 -246.069481) (xy 284.544516 -246.055134) (xy 284.537978 -246.050854) (xy 284.523113 -246.046063)
			(xy 284.515306 -246.045736) (xy 283.999432 -246.045736) (xy 283.994111 -246.045354) (xy 283.98657 -246.037848)
			(xy 283.986224 -246.032528) (xy 277.942017 -246.032528) (xy 277.941557 -246.03758) (xy 277.934127 -246.045153)
			(xy 277.928832 -246.045736) (xy 277.412958 -246.045736) (xy 277.40515 -246.046068) (xy 277.390278 -246.050841)
			(xy 277.383748 -246.055134) (xy 277.362637 -246.0695) (xy 277.31691 -246.092223) (xy 277.268233 -246.107649)
			(xy 277.217764 -246.11541) (xy 277.192232 -246.11584) (xy 277.166702 -246.115392) (xy 277.116239 -246.10762)
			(xy 277.067566 -246.092195) (xy 277.021838 -246.069481) (xy 277.000716 -246.055134) (xy 276.994178 -246.050854)
			(xy 276.979313 -246.046063) (xy 276.971506 -246.045736) (xy 276.455632 -246.045736) (xy 276.450311 -246.045354)
			(xy 276.44277 -246.037848) (xy 276.442424 -246.032528) (xy 270.398224 -246.032528) (xy 270.397901 -246.037711)
			(xy 270.390215 -246.0454) (xy 270.384778 -246.045736) (xy 269.868904 -246.045736) (xy 269.861093 -246.046045)
			(xy 269.846222 -246.050834) (xy 269.839694 -246.055134) (xy 269.81857 -246.06948) (xy 269.772847 -246.092208)
			(xy 269.724175 -246.107639) (xy 269.673709 -246.115407) (xy 269.648178 -246.11584) (xy 269.622647 -246.115419)
			(xy 269.572182 -246.107639) (xy 269.52351 -246.092206) (xy 269.477783 -246.069484) (xy 269.456662 -246.055134)
			(xy 269.450136 -246.050833) (xy 269.435262 -246.046056) (xy 269.427452 -246.045736) (xy 268.911578 -246.045736)
			(xy 268.906134 -246.045433) (xy 268.898448 -246.037719) (xy 268.898116 -246.032274) (xy 206.997808 -246.032274)
			(xy 206.997808 -246.032528) (xy 206.997324 -246.037794) (xy 206.989867 -246.045235) (xy 206.9846 -246.045736)
			(xy 206.468726 -246.045736) (xy 206.46085 -246.046002) (xy 206.445846 -246.050801) (xy 206.439262 -246.055134)
			(xy 206.418184 -246.069525) (xy 206.37254 -246.092354) (xy 206.323934 -246.107912) (xy 206.273517 -246.115831)
			(xy 206.248 -246.116348) (xy 206.22248 -246.115867) (xy 206.172053 -246.107968) (xy 206.123441 -246.092406)
			(xy 206.077803 -246.069549) (xy 206.056738 -246.055134) (xy 206.050138 -246.050834) (xy 206.035144 -246.046038)
			(xy 206.027274 -246.045736) (xy 205.5114 -246.045736) (xy 205.506144 -246.045208) (xy 205.498703 -246.037783)
			(xy 205.498192 -246.032528) (xy 199.454008 -246.032528) (xy 199.453524 -246.037794) (xy 199.446067 -246.045235)
			(xy 199.4408 -246.045736) (xy 198.924926 -246.045736) (xy 198.91705 -246.046002) (xy 198.902046 -246.050801)
			(xy 198.895462 -246.055134) (xy 198.874384 -246.069525) (xy 198.82874 -246.092354) (xy 198.780134 -246.107912)
			(xy 198.729717 -246.115831) (xy 198.7042 -246.116348) (xy 198.67868 -246.115867) (xy 198.628253 -246.107968)
			(xy 198.579641 -246.092406) (xy 198.534003 -246.069549) (xy 198.512938 -246.055134) (xy 198.506338 -246.050834)
			(xy 198.491344 -246.046038) (xy 198.483474 -246.045736) (xy 197.9676 -246.045736) (xy 197.962344 -246.045208)
			(xy 197.954903 -246.037783) (xy 197.954392 -246.032528) (xy 191.910208 -246.032528) (xy 191.909724 -246.037794)
			(xy 191.902267 -246.045235) (xy 191.897 -246.045736) (xy 191.896492 -246.045736) (xy 191.380872 -246.045736)
			(xy 191.372997 -246.046021) (xy 191.357993 -246.050807) (xy 191.351408 -246.055134) (xy 191.330345 -246.069549)
			(xy 191.284695 -246.092372) (xy 191.236085 -246.107924) (xy 191.185664 -246.115835) (xy 191.160146 -246.116348)
			(xy 191.134627 -246.115844) (xy 191.084201 -246.107952) (xy 191.035589 -246.092396) (xy 190.98995 -246.069546)
			(xy 190.968884 -246.055134) (xy 190.962296 -246.050813) (xy 190.947293 -246.04603) (xy 190.93942 -246.045736)
			(xy 190.423546 -246.045736) (xy 190.418242 -246.045243) (xy 190.410667 -246.037821) (xy 190.410084 -246.032528)
			(xy 184.3659 -246.032528) (xy 184.365423 -246.037796) (xy 184.357961 -246.045238) (xy 184.352692 -246.045736)
			(xy 183.836818 -246.045736) (xy 183.828945 -246.046041) (xy 183.813941 -246.050813) (xy 183.807354 -246.055134)
			(xy 183.786279 -246.069529) (xy 183.740633 -246.092357) (xy 183.692027 -246.107914) (xy 183.641609 -246.115832)
			(xy 183.616092 -246.116348) (xy 183.590573 -246.11582) (xy 183.540148 -246.107936) (xy 183.491537 -246.092387)
			(xy 183.445897 -246.069543) (xy 183.42483 -246.055134) (xy 183.418231 -246.050831) (xy 183.403237 -246.046036)
			(xy 183.395366 -246.045736) (xy 182.879492 -246.045736) (xy 182.874235 -246.045213) (xy 182.866795 -246.037784)
			(xy 182.866284 -246.032528) (xy 176.8221 -246.032528) (xy 176.821623 -246.037796) (xy 176.814161 -246.045238)
			(xy 176.808892 -246.045736) (xy 176.808384 -246.045736) (xy 176.292764 -246.045736) (xy 176.284889 -246.046018)
			(xy 176.269885 -246.050806) (xy 176.2633 -246.055134) (xy 176.242212 -246.069509) (xy 176.196571 -246.092342)
			(xy 176.147968 -246.107904) (xy 176.097554 -246.115828) (xy 176.072038 -246.116348) (xy 176.046518 -246.115848)
			(xy 175.996092 -246.107955) (xy 175.947481 -246.092398) (xy 175.901842 -246.069547) (xy 175.880776 -246.055134)
			(xy 175.87419 -246.05081) (xy 175.859186 -246.046028) (xy 175.851312 -246.045736) (xy 175.335438 -246.045736)
			(xy 175.330133 -246.045249) (xy 175.322558 -246.037823) (xy 175.321976 -246.032528) (xy 169.277792 -246.032528)
			(xy 169.277322 -246.037798) (xy 169.269856 -246.04524) (xy 169.264584 -246.045736) (xy 167.791384 -246.045736)
			(xy 167.786126 -246.045219) (xy 167.778686 -246.037786) (xy 167.778176 -246.032528) (xy 107.377609 -246.032528)
			(xy 107.383049 -246.05401) (xy 107.387225 -246.1044) (xy 107.383049 -246.15479) (xy 107.370636 -246.203805)
			(xy 107.350323 -246.250109) (xy 107.322666 -246.292437) (xy 107.288419 -246.329635) (xy 107.248516 -246.360689)
			(xy 107.204046 -246.384751) (xy 107.156221 -246.401164) (xy 107.106347 -246.409482) (xy 107.081066 -246.409972)
			(xy 106.141012 -246.409972) (xy 106.115733 -246.40946) (xy 106.065866 -246.40114) (xy 106.018047 -246.384726)
			(xy 105.973583 -246.360665) (xy 105.933686 -246.329613) (xy 105.899444 -246.292417) (xy 105.871791 -246.250093)
			(xy 105.851482 -246.203794) (xy 105.839071 -246.154784) (xy 105.834895 -246.1044) (xy 104.567325 -246.1044)
			(xy 104.563149 -246.154791) (xy 104.550735 -246.203807) (xy 104.530422 -246.250111) (xy 104.502764 -246.29244)
			(xy 104.468516 -246.329638) (xy 104.428612 -246.360692) (xy 104.38414 -246.384753) (xy 104.336315 -246.401166)
			(xy 104.28644 -246.409482) (xy 104.261158 -246.409972) (xy 103.321104 -246.409972) (xy 103.295826 -246.409459)
			(xy 103.245959 -246.401139) (xy 103.198142 -246.384724) (xy 103.153679 -246.360662) (xy 103.113783 -246.32961)
			(xy 103.079542 -246.292415) (xy 103.05189 -246.250091) (xy 103.031581 -246.203793) (xy 103.01917 -246.154784)
			(xy 103.014995 -246.1044) (xy 101.747125 -246.1044) (xy 101.742949 -246.154787) (xy 101.730538 -246.203799)
			(xy 101.710228 -246.2501) (xy 101.682574 -246.292427) (xy 101.648331 -246.329625) (xy 101.608432 -246.360679)
			(xy 101.563966 -246.384742) (xy 101.516146 -246.401158) (xy 101.466276 -246.409479) (xy 101.440996 -246.409972)
			(xy 100.500942 -246.409972) (xy 100.475662 -246.409462) (xy 100.42579 -246.401146) (xy 100.377968 -246.384735)
			(xy 100.333499 -246.360675) (xy 100.293597 -246.329623) (xy 100.259351 -246.292427) (xy 100.231695 -246.250101)
			(xy 100.211384 -246.2038) (xy 100.198971 -246.154788) (xy 100.194795 -246.1044) (xy 98.927225 -246.1044)
			(xy 98.923049 -246.154788) (xy 98.910637 -246.203801) (xy 98.890327 -246.250102) (xy 98.862672 -246.29243)
			(xy 98.828428 -246.329627) (xy 98.788528 -246.360681) (xy 98.744061 -246.384744) (xy 98.696239 -246.40116)
			(xy 98.646368 -246.40948) (xy 98.621088 -246.409972) (xy 97.681034 -246.409972) (xy 97.655754 -246.409462)
			(xy 97.605884 -246.401145) (xy 97.558062 -246.384732) (xy 97.513595 -246.360672) (xy 97.473694 -246.329621)
			(xy 97.439449 -246.292425) (xy 97.411794 -246.250099) (xy 97.391483 -246.203799) (xy 97.379071 -246.154787)
			(xy 97.374895 -246.1044) (xy 51.971002 -246.1044) (xy 51.960008 -246.107918) (xy 51.909589 -246.115833)
			(xy 51.884072 -246.116348) (xy 51.858553 -246.115831) (xy 51.808128 -246.107943) (xy 51.759516 -246.092391)
			(xy 51.713876 -246.069545) (xy 51.69281 -246.055134) (xy 51.686216 -246.050823) (xy 51.671218 -246.046033)
			(xy 51.663346 -246.045736) (xy 51.147472 -246.045736) (xy 51.142213 -246.045227) (xy 51.134773 -246.037787)
			(xy 51.134264 -246.032528) (xy 45.09008 -246.032528) (xy 45.089621 -246.037801) (xy 45.082147 -246.045244)
			(xy 45.076872 -246.045736) (xy 45.076364 -246.045736) (xy 44.560744 -246.045736) (xy 44.552868 -246.046009)
			(xy 44.537864 -246.050803) (xy 44.53128 -246.055134) (xy 44.510197 -246.069518) (xy 44.464555 -246.092348)
			(xy 44.41595 -246.107908) (xy 44.365534 -246.11583) (xy 44.340018 -246.116348) (xy 44.314498 -246.115858)
			(xy 44.264071 -246.107962) (xy 44.21546 -246.092402) (xy 44.169821 -246.069548) (xy 44.148756 -246.055134)
			(xy 44.142174 -246.050803) (xy 44.127167 -246.046025) (xy 44.119292 -246.045736) (xy 43.603418 -246.045736)
			(xy 43.59811 -246.045262) (xy 43.590537 -246.037826) (xy 43.589956 -246.032528) (xy 37.545772 -246.032528)
			(xy 37.545488 -246.037873) (xy 37.53791 -246.045414) (xy 37.532564 -246.045736) (xy 37.01669 -246.045736)
			(xy 37.008816 -246.04603) (xy 36.993812 -246.05081) (xy 36.987226 -246.055134) (xy 36.966158 -246.069541)
			(xy 36.92051 -246.092366) (xy 36.871901 -246.10792) (xy 36.821482 -246.115834) (xy 36.795964 -246.116348)
			(xy 36.770445 -246.115835) (xy 36.720019 -246.107946) (xy 36.671408 -246.092393) (xy 36.625768 -246.069545)
			(xy 36.604702 -246.055134) (xy 36.59811 -246.05082) (xy 36.58311 -246.046032) (xy 36.575238 -246.045736)
			(xy 36.059364 -246.045736) (xy 36.054104 -246.045232) (xy 36.046665 -246.037789) (xy 36.046156 -246.032528)
			(xy 30.001972 -246.032528) (xy 30.001688 -246.037873) (xy 29.99411 -246.045414) (xy 29.988764 -246.045736)
			(xy 29.47289 -246.045736) (xy 29.465016 -246.04603) (xy 29.450012 -246.05081) (xy 29.443426 -246.055134)
			(xy 29.422358 -246.069541) (xy 29.37671 -246.092366) (xy 29.328101 -246.10792) (xy 29.277682 -246.115834)
			(xy 29.252164 -246.116348) (xy 29.226645 -246.115835) (xy 29.176219 -246.107946) (xy 29.127608 -246.092393)
			(xy 29.081968 -246.069545) (xy 29.060902 -246.055134) (xy 29.05431 -246.05082) (xy 29.03931 -246.046032)
			(xy 29.031438 -246.045736) (xy 28.515564 -246.045736) (xy 28.510304 -246.045232) (xy 28.502865 -246.037789)
			(xy 28.502356 -246.032528) (xy 22.458172 -246.032528) (xy 22.457888 -246.037873) (xy 22.45031 -246.045414)
			(xy 22.444964 -246.045736) (xy 22.444456 -246.045736) (xy 21.928836 -246.045736) (xy 21.92096 -246.046006)
			(xy 21.905956 -246.050802) (xy 21.899372 -246.055134) (xy 21.878292 -246.069521) (xy 21.832648 -246.092351)
			(xy 21.784043 -246.10791) (xy 21.733626 -246.11583) (xy 21.70811 -246.116348) (xy 21.68259 -246.115862)
			(xy 21.632163 -246.107965) (xy 21.583552 -246.092403) (xy 21.537913 -246.069549) (xy 21.516848 -246.055134)
			(xy 21.510268 -246.050799) (xy 21.495259 -246.046024) (xy 21.487384 -246.045736) (xy 20.97151 -246.045736)
			(xy 20.966202 -246.045267) (xy 20.958629 -246.037827) (xy 20.958048 -246.032528) (xy 2.509012 -246.032528)
			(xy 2.509012 -246.882412) (xy 16.85798 -246.882412) (xy 16.85798 -246.387874) (xy 16.858266 -246.382425)
			(xy 16.865992 -246.374738) (xy 16.871442 -246.374412) (xy 17.38757 -246.374412) (xy 17.395381 -246.3741)
			(xy 17.410253 -246.369315) (xy 17.41678 -246.365014) (xy 17.437869 -246.350665) (xy 17.48353 -246.327934)
			(xy 17.532136 -246.312475) (xy 17.582539 -246.304652) (xy 17.633545 -246.304652) (xy 17.683948 -246.312475)
			(xy 17.732554 -246.327934) (xy 17.778215 -246.350665) (xy 17.799304 -246.365014) (xy 17.80584 -246.369297)
			(xy 17.820706 -246.374087) (xy 17.828514 -246.374412) (xy 18.344642 -246.374412) (xy 18.350005 -246.37492)
			(xy 18.357587 -246.382511) (xy 18.358104 -246.387874) (xy 18.358104 -246.882412) (xy 24.402288 -246.882412)
			(xy 24.402288 -246.387874) (xy 24.402712 -246.382555) (xy 24.410185 -246.374983) (xy 24.415496 -246.374412)
			(xy 24.931624 -246.374412) (xy 24.939437 -246.374123) (xy 24.954308 -246.369322) (xy 24.960834 -246.365014)
			(xy 24.981923 -246.350665) (xy 25.027584 -246.327934) (xy 25.07619 -246.312475) (xy 25.126593 -246.304652)
			(xy 25.177599 -246.304652) (xy 25.228002 -246.312475) (xy 25.276608 -246.327934) (xy 25.322269 -246.350665)
			(xy 25.343358 -246.365014) (xy 25.349882 -246.369318) (xy 25.364758 -246.374095) (xy 25.372568 -246.374412)
			(xy 25.888696 -246.374412) (xy 25.894033 -246.374732) (xy 25.901575 -246.382283) (xy 25.901904 -246.38762)
			(xy 25.901904 -246.388128) (xy 25.901904 -246.882412) (xy 31.946088 -246.882412) (xy 31.946088 -246.387874)
			(xy 31.946512 -246.382555) (xy 31.953985 -246.374983) (xy 31.959296 -246.374412) (xy 32.475424 -246.374412)
			(xy 32.483237 -246.374123) (xy 32.498108 -246.369322) (xy 32.504634 -246.365014) (xy 32.525723 -246.350665)
			(xy 32.571384 -246.327934) (xy 32.61999 -246.312475) (xy 32.670393 -246.304652) (xy 32.721399 -246.304652)
			(xy 32.771802 -246.312475) (xy 32.820408 -246.327934) (xy 32.866069 -246.350665) (xy 32.887158 -246.365014)
			(xy 32.893682 -246.369318) (xy 32.908558 -246.374095) (xy 32.916368 -246.374412) (xy 33.432496 -246.374412)
			(xy 33.437833 -246.374732) (xy 33.445375 -246.382283) (xy 33.445704 -246.38762) (xy 33.445704 -246.388128)
			(xy 33.445704 -246.882412) (xy 39.489888 -246.882412) (xy 39.489888 -246.387874) (xy 39.490428 -246.382519)
			(xy 39.497996 -246.374938) (xy 39.50335 -246.374412) (xy 40.019478 -246.374412) (xy 40.027289 -246.374104)
			(xy 40.042161 -246.369316) (xy 40.048688 -246.365014) (xy 40.069777 -246.350665) (xy 40.115438 -246.327934)
			(xy 40.164044 -246.312475) (xy 40.214447 -246.304652) (xy 40.265453 -246.304652) (xy 40.315856 -246.312475)
			(xy 40.364462 -246.327934) (xy 40.410123 -246.350665) (xy 40.431212 -246.365014) (xy 40.437747 -246.3693)
			(xy 40.452614 -246.374088) (xy 40.460422 -246.374412) (xy 40.97655 -246.374412) (xy 40.981914 -246.374915)
			(xy 40.989495 -246.382509) (xy 40.990012 -246.387874) (xy 40.990012 -246.882412) (xy 47.034196 -246.882412)
			(xy 47.034196 -246.387874) (xy 47.0347 -246.382577) (xy 47.042118 -246.37501) (xy 47.047404 -246.374412)
			(xy 47.563532 -246.374412) (xy 47.571341 -246.374084) (xy 47.586213 -246.36931) (xy 47.592742 -246.365014)
			(xy 47.613831 -246.350665) (xy 47.659492 -246.327934) (xy 47.708098 -246.312475) (xy 47.758501 -246.304652)
			(xy 47.809507 -246.304652) (xy 47.85991 -246.312475) (xy 47.908516 -246.327934) (xy 47.954177 -246.350665)
			(xy 47.975266 -246.365014) (xy 47.981811 -246.369283) (xy 47.99667 -246.374081) (xy 48.004476 -246.374412)
			(xy 48.520604 -246.374412) (xy 48.525942 -246.374726) (xy 48.533483 -246.382282) (xy 48.533812 -246.38762)
			(xy 48.533812 -246.388128) (xy 48.533812 -246.882412) (xy 54.577996 -246.882412) (xy 54.577996 -246.387874)
			(xy 54.578529 -246.382517) (xy 54.586102 -246.374935) (xy 54.591458 -246.374412) (xy 56.064658 -246.374412)
			(xy 56.070081 -246.374805) (xy 56.077768 -246.382453) (xy 56.07812 -246.387874) (xy 56.07812 -246.882412)
			(xy 56.077614 -246.887673) (xy 56.070173 -246.895114) (xy 56.064912 -246.89562) (xy 56.064404 -246.89562)
			(xy 54.591458 -246.89562) (xy 54.586139 -246.8952) (xy 54.578568 -246.887724) (xy 54.577996 -246.882412)
			(xy 48.533812 -246.882412) (xy 48.533314 -246.887675) (xy 48.525867 -246.895117) (xy 48.520604 -246.89562)
			(xy 48.00473 -246.89562) (xy 47.996854 -246.89589) (xy 47.98185 -246.900686) (xy 47.975266 -246.905018)
			(xy 47.96152 -246.9144) (xy 108.185156 -246.9144) (xy 108.189328 -246.864058) (xy 108.201729 -246.815089)
			(xy 108.222021 -246.768829) (xy 108.249651 -246.72654) (xy 108.283865 -246.689376) (xy 108.32373 -246.658351)
			(xy 108.368157 -246.63431) (xy 108.415936 -246.617911) (xy 108.465763 -246.609599) (xy 108.49102 -246.609108)
			(xy 109.431074 -246.609108) (xy 109.456334 -246.609567) (xy 109.506167 -246.617878) (xy 109.553951 -246.634279)
			(xy 109.598385 -246.658322) (xy 109.638254 -246.68935) (xy 109.672472 -246.726518) (xy 109.700106 -246.768812)
			(xy 109.720401 -246.815077) (xy 109.732804 -246.864052) (xy 109.734325 -246.882412) (xy 163.678108 -246.882412)
			(xy 163.678108 -246.387874) (xy 163.678602 -246.382574) (xy 163.686027 -246.375007) (xy 163.691316 -246.374412)
			(xy 165.164516 -246.374412) (xy 165.169855 -246.374718) (xy 165.177397 -246.38228) (xy 165.177724 -246.38762)
			(xy 165.177724 -246.388128) (xy 165.177724 -246.882412) (xy 171.221908 -246.882412) (xy 171.221908 -246.387874)
			(xy 171.22243 -246.382514) (xy 171.23001 -246.374932) (xy 171.23537 -246.374412) (xy 171.751498 -246.374412)
			(xy 171.75931 -246.374112) (xy 171.774182 -246.369318) (xy 171.780708 -246.365014) (xy 171.801797 -246.350665)
			(xy 171.847458 -246.327934) (xy 171.896064 -246.312475) (xy 171.946467 -246.304652) (xy 171.997473 -246.304652)
			(xy 172.047876 -246.312475) (xy 172.096482 -246.327934) (xy 172.142143 -246.350665) (xy 172.163232 -246.365014)
			(xy 172.169762 -246.369308) (xy 172.184633 -246.374091) (xy 172.192442 -246.374412) (xy 172.70857 -246.374412)
			(xy 172.713994 -246.374797) (xy 172.72168 -246.382451) (xy 172.722032 -246.387874) (xy 172.722032 -246.882412)
			(xy 178.766216 -246.882412) (xy 178.766216 -246.387874) (xy 178.766703 -246.382572) (xy 178.774132 -246.375004)
			(xy 178.779424 -246.374412) (xy 179.295552 -246.374412) (xy 179.303362 -246.374093) (xy 179.318234 -246.369312)
			(xy 179.324762 -246.365014) (xy 179.345851 -246.350665) (xy 179.391512 -246.327934) (xy 179.440118 -246.312475)
			(xy 179.490521 -246.304652) (xy 179.541527 -246.304652) (xy 179.59193 -246.312475) (xy 179.640536 -246.327934)
			(xy 179.686197 -246.350665) (xy 179.707286 -246.365014) (xy 179.713826 -246.36929) (xy 179.728689 -246.374084)
			(xy 179.736496 -246.374412) (xy 180.252624 -246.374412) (xy 180.257894 -246.374881) (xy 180.265337 -246.382348)
			(xy 180.265832 -246.38762) (xy 180.265832 -246.388128) (xy 180.265832 -246.882412) (xy 186.310016 -246.882412)
			(xy 186.310016 -246.387874) (xy 186.310531 -246.382512) (xy 186.318116 -246.374929) (xy 186.323478 -246.374412)
			(xy 186.839606 -246.374412) (xy 186.847418 -246.374116) (xy 186.86229 -246.369319) (xy 186.868816 -246.365014)
			(xy 186.889905 -246.350665) (xy 186.935566 -246.327934) (xy 186.984172 -246.312475) (xy 187.034575 -246.304652)
			(xy 187.085581 -246.304652) (xy 187.135984 -246.312475) (xy 187.18459 -246.327934) (xy 187.230251 -246.350665)
			(xy 187.25134 -246.365014) (xy 187.257868 -246.369311) (xy 187.272741 -246.374092) (xy 187.28055 -246.374412)
			(xy 187.796678 -246.374412) (xy 187.802033 -246.374963) (xy 187.809618 -246.382521) (xy 187.81014 -246.387874)
			(xy 187.81014 -246.882412) (xy 193.854324 -246.882412) (xy 193.854324 -246.387874) (xy 193.854804 -246.38257)
			(xy 193.862238 -246.375002) (xy 193.867532 -246.374412) (xy 194.38366 -246.374412) (xy 194.39147 -246.374096)
			(xy 194.406342 -246.369313) (xy 194.41287 -246.365014) (xy 194.433959 -246.350665) (xy 194.47962 -246.327934)
			(xy 194.528226 -246.312475) (xy 194.578629 -246.304652) (xy 194.629635 -246.304652) (xy 194.680038 -246.312475)
			(xy 194.728644 -246.327934) (xy 194.774305 -246.350665) (xy 194.795394 -246.365014) (xy 194.801933 -246.369294)
			(xy 194.816797 -246.374085) (xy 194.824604 -246.374412) (xy 195.340732 -246.374412) (xy 195.346003 -246.374875)
			(xy 195.353445 -246.382347) (xy 195.35394 -246.38762) (xy 195.35394 -246.388128) (xy 195.35394 -246.882412)
			(xy 201.398124 -246.882412) (xy 201.398124 -246.387874) (xy 201.398604 -246.38257) (xy 201.406038 -246.375002)
			(xy 201.411332 -246.374412) (xy 201.92746 -246.374412) (xy 201.93527 -246.374096) (xy 201.950142 -246.369313)
			(xy 201.95667 -246.365014) (xy 201.977759 -246.350665) (xy 202.02342 -246.327934) (xy 202.072026 -246.312475)
			(xy 202.122429 -246.304652) (xy 202.173435 -246.304652) (xy 202.223838 -246.312475) (xy 202.272444 -246.327934)
			(xy 202.318105 -246.350665) (xy 202.339194 -246.365014) (xy 202.345733 -246.369294) (xy 202.360597 -246.374085)
			(xy 202.368404 -246.374412) (xy 202.884532 -246.374412) (xy 202.889803 -246.374875) (xy 202.897245 -246.382347)
			(xy 202.89774 -246.38762) (xy 202.89774 -246.388128) (xy 202.89774 -246.882158) (xy 264.798048 -246.882158)
			(xy 264.798048 -246.38762) (xy 264.798603 -246.38237) (xy 264.806009 -246.374929) (xy 264.811256 -246.374412)
			(xy 264.811764 -246.374412) (xy 265.327638 -246.374412) (xy 265.335447 -246.374087) (xy 265.350319 -246.36931)
			(xy 265.356848 -246.365014) (xy 265.377937 -246.350665) (xy 265.423598 -246.327934) (xy 265.472204 -246.312475)
			(xy 265.522607 -246.304652) (xy 265.573613 -246.304652) (xy 265.624016 -246.312475) (xy 265.672622 -246.327934)
			(xy 265.718283 -246.350665) (xy 265.739372 -246.365014) (xy 265.745916 -246.369285) (xy 265.760776 -246.374082)
			(xy 265.768582 -246.374412) (xy 266.28471 -246.374412) (xy 266.290009 -246.374913) (xy 266.297578 -246.382332)
			(xy 266.298172 -246.38762) (xy 266.298172 -246.882158) (xy 266.298154 -246.882412) (xy 272.342356 -246.882412)
			(xy 272.342356 -246.881904) (xy 272.342356 -246.38762) (xy 272.342904 -246.382368) (xy 272.350314 -246.374926)
			(xy 272.355564 -246.374412) (xy 272.871692 -246.374412) (xy 272.879503 -246.37411) (xy 272.894375 -246.369317)
			(xy 272.900902 -246.365014) (xy 272.921991 -246.350665) (xy 272.967652 -246.327934) (xy 273.016258 -246.312475)
			(xy 273.066661 -246.304652) (xy 273.117667 -246.304652) (xy 273.16807 -246.312475) (xy 273.216676 -246.327934)
			(xy 273.262337 -246.350665) (xy 273.283426 -246.365014) (xy 273.289957 -246.369306) (xy 273.304827 -246.37409)
			(xy 273.312636 -246.374412) (xy 273.828764 -246.374412) (xy 273.834096 -246.374753) (xy 273.841641 -246.382288)
			(xy 273.841972 -246.38762) (xy 273.841972 -246.882158) (xy 273.841947 -246.882412) (xy 279.886156 -246.882412)
			(xy 279.886156 -246.881904) (xy 279.886156 -246.38762) (xy 279.886704 -246.382368) (xy 279.894114 -246.374926)
			(xy 279.899364 -246.374412) (xy 280.415492 -246.374412) (xy 280.423303 -246.37411) (xy 280.438175 -246.369317)
			(xy 280.444702 -246.365014) (xy 280.465791 -246.350665) (xy 280.511452 -246.327934) (xy 280.560058 -246.312475)
			(xy 280.610461 -246.304652) (xy 280.661467 -246.304652) (xy 280.71187 -246.312475) (xy 280.760476 -246.327934)
			(xy 280.806137 -246.350665) (xy 280.827226 -246.365014) (xy 280.833757 -246.369306) (xy 280.848627 -246.37409)
			(xy 280.856436 -246.374412) (xy 281.372564 -246.374412) (xy 281.377896 -246.374753) (xy 281.385441 -246.382288)
			(xy 281.385772 -246.38762) (xy 281.385772 -246.882158) (xy 287.429956 -246.882158) (xy 287.429956 -246.38762)
			(xy 287.430504 -246.382368) (xy 287.437914 -246.374926) (xy 287.443164 -246.374412) (xy 287.443672 -246.374412)
			(xy 287.959546 -246.374412) (xy 287.967356 -246.37409) (xy 287.982228 -246.369311) (xy 287.988756 -246.365014)
			(xy 288.009845 -246.350665) (xy 288.055506 -246.327934) (xy 288.104112 -246.312475) (xy 288.154515 -246.304652)
			(xy 288.205521 -246.304652) (xy 288.255924 -246.312475) (xy 288.30453 -246.327934) (xy 288.350191 -246.350665)
			(xy 288.37128 -246.365014) (xy 288.377822 -246.369288) (xy 288.392684 -246.374083) (xy 288.40049 -246.374412)
			(xy 288.916618 -246.374412) (xy 288.921918 -246.374908) (xy 288.929486 -246.382331) (xy 288.93008 -246.38762)
			(xy 288.93008 -246.882158) (xy 288.930062 -246.882412) (xy 294.974264 -246.882412) (xy 294.974264 -246.881904)
			(xy 294.974264 -246.38762) (xy 294.974805 -246.382366) (xy 294.98222 -246.374924) (xy 294.987472 -246.374412)
			(xy 295.5036 -246.374412) (xy 295.511412 -246.374113) (xy 295.526284 -246.369318) (xy 295.53281 -246.365014)
			(xy 295.553899 -246.350665) (xy 295.59956 -246.327934) (xy 295.648166 -246.312475) (xy 295.698569 -246.304652)
			(xy 295.749575 -246.304652) (xy 295.799978 -246.312475) (xy 295.848584 -246.327934) (xy 295.894245 -246.350665)
			(xy 295.915334 -246.365014) (xy 295.921864 -246.369309) (xy 295.936735 -246.374091) (xy 295.944544 -246.374412)
			(xy 296.460672 -246.374412) (xy 296.466005 -246.374747) (xy 296.473549 -246.382287) (xy 296.47388 -246.38762)
			(xy 296.47388 -246.882158) (xy 302.518064 -246.882158) (xy 302.518064 -246.38762) (xy 302.518605 -246.382366)
			(xy 302.52602 -246.374924) (xy 302.531272 -246.374412) (xy 302.53178 -246.374412) (xy 304.004726 -246.374412)
			(xy 304.010027 -246.374903) (xy 304.017595 -246.38233) (xy 304.018188 -246.38762) (xy 304.018188 -246.882158)
			(xy 304.017795 -246.887581) (xy 304.010147 -246.895268) (xy 304.004726 -246.89562) (xy 302.531526 -246.89562)
			(xy 302.526084 -246.895299) (xy 302.518394 -246.8876) (xy 302.518064 -246.882158) (xy 296.47388 -246.882158)
			(xy 296.473351 -246.887453) (xy 296.465954 -246.895025) (xy 296.460672 -246.89562) (xy 295.944798 -246.89562)
			(xy 295.936987 -246.895929) (xy 295.922116 -246.900718) (xy 295.915588 -246.905018) (xy 295.902069 -246.9142)
			(xy 361.758647 -246.9142) (xy 361.762823 -246.863808) (xy 361.775236 -246.814791) (xy 361.795548 -246.768485)
			(xy 361.823205 -246.726155) (xy 361.857452 -246.688953) (xy 361.897355 -246.657897) (xy 361.941825 -246.633831)
			(xy 361.989651 -246.617414) (xy 362.039526 -246.609093) (xy 362.064808 -246.6086) (xy 363.004862 -246.6086)
			(xy 363.03014 -246.609166) (xy 363.080006 -246.617481) (xy 363.127824 -246.633892) (xy 363.172288 -246.65795)
			(xy 363.212185 -246.688999) (xy 363.246428 -246.726191) (xy 363.274081 -246.768513) (xy 363.29439 -246.81481)
			(xy 363.306801 -246.863818) (xy 363.308342 -246.882412) (xy 411.618176 -246.882412) (xy 411.618176 -246.881904)
			(xy 411.618176 -246.38762) (xy 411.618538 -246.382294) (xy 411.626059 -246.374753) (xy 411.631384 -246.374412)
			(xy 413.104584 -246.374412) (xy 413.109919 -246.37474) (xy 413.117462 -246.382285) (xy 413.117792 -246.38762)
			(xy 413.117792 -246.882158) (xy 419.161976 -246.882158) (xy 419.161976 -246.38762) (xy 419.162338 -246.382294)
			(xy 419.169859 -246.374753) (xy 419.175184 -246.374412) (xy 419.175692 -246.374412) (xy 419.691566 -246.374412)
			(xy 419.699376 -246.374099) (xy 419.714248 -246.369314) (xy 419.720776 -246.365014) (xy 419.741865 -246.350665)
			(xy 419.787526 -246.327934) (xy 419.836132 -246.312475) (xy 419.886535 -246.304652) (xy 419.937541 -246.304652)
			(xy 419.987944 -246.312475) (xy 420.03655 -246.327934) (xy 420.082211 -246.350665) (xy 420.1033 -246.365014)
			(xy 420.109837 -246.369296) (xy 420.124703 -246.374086) (xy 420.13251 -246.374412) (xy 420.648638 -246.374412)
			(xy 420.65394 -246.374895) (xy 420.661507 -246.382328) (xy 420.6621 -246.38762) (xy 420.6621 -246.882158)
			(xy 420.662081 -246.882412) (xy 426.706284 -246.882412) (xy 426.706284 -246.881904) (xy 426.706284 -246.38762)
			(xy 426.706639 -246.382292) (xy 426.714165 -246.374751) (xy 426.719492 -246.374412) (xy 427.23562 -246.374412)
			(xy 427.243432 -246.374121) (xy 427.258304 -246.369321) (xy 427.26483 -246.365014) (xy 427.285919 -246.350665)
			(xy 427.33158 -246.327934) (xy 427.380186 -246.312475) (xy 427.430589 -246.304652) (xy 427.481595 -246.304652)
			(xy 427.531998 -246.312475) (xy 427.580604 -246.327934) (xy 427.626265 -246.350665) (xy 427.647354 -246.365014)
			(xy 427.653879 -246.369317) (xy 427.668754 -246.374094) (xy 427.676564 -246.374412) (xy 428.192692 -246.374412)
			(xy 428.198028 -246.374734) (xy 428.205571 -246.382284) (xy 428.2059 -246.38762) (xy 428.2059 -246.882158)
			(xy 434.250084 -246.882158) (xy 434.250084 -246.38762) (xy 434.250439 -246.382292) (xy 434.257965 -246.374751)
			(xy 434.263292 -246.374412) (xy 434.2638 -246.374412) (xy 434.779674 -246.374412) (xy 434.787485 -246.374102)
			(xy 434.802357 -246.369315) (xy 434.808884 -246.365014) (xy 434.829973 -246.350665) (xy 434.875634 -246.327934)
			(xy 434.92424 -246.312475) (xy 434.974643 -246.304652) (xy 435.025649 -246.304652) (xy 435.076052 -246.312475)
			(xy 435.124658 -246.327934) (xy 435.170319 -246.350665) (xy 435.191408 -246.365014) (xy 435.197943 -246.369299)
			(xy 435.21281 -246.374088) (xy 435.220618 -246.374412) (xy 435.736746 -246.374412) (xy 435.742037 -246.374956)
			(xy 435.74961 -246.382342) (xy 435.750208 -246.38762) (xy 435.750208 -246.882158) (xy 435.75018 -246.882412)
			(xy 441.794392 -246.882412) (xy 441.794392 -246.881904) (xy 441.794392 -246.38762) (xy 441.79474 -246.38229)
			(xy 441.802271 -246.374748) (xy 441.8076 -246.374412) (xy 442.323728 -246.374412) (xy 442.331541 -246.374125)
			(xy 442.346413 -246.369322) (xy 442.352938 -246.365014) (xy 442.374027 -246.350665) (xy 442.419688 -246.327934)
			(xy 442.468294 -246.312475) (xy 442.518697 -246.304652) (xy 442.569703 -246.304652) (xy 442.620106 -246.312475)
			(xy 442.668712 -246.327934) (xy 442.714373 -246.350665) (xy 442.735462 -246.365014) (xy 442.742008 -246.369281)
			(xy 442.756867 -246.374081) (xy 442.764672 -246.374412) (xy 443.2808 -246.374412) (xy 443.286137 -246.374729)
			(xy 443.293679 -246.382282) (xy 443.294008 -246.38762) (xy 443.294008 -246.882158) (xy 443.293981 -246.882412)
			(xy 449.338192 -246.882412) (xy 449.338192 -246.881904) (xy 449.338192 -246.38762) (xy 449.33854 -246.38229)
			(xy 449.346071 -246.374748) (xy 449.3514 -246.374412) (xy 449.867528 -246.374412) (xy 449.875341 -246.374125)
			(xy 449.890213 -246.369322) (xy 449.896738 -246.365014) (xy 449.917827 -246.350665) (xy 449.963488 -246.327934)
			(xy 450.012094 -246.312475) (xy 450.062497 -246.304652) (xy 450.113503 -246.304652) (xy 450.163906 -246.312475)
			(xy 450.212512 -246.327934) (xy 450.258173 -246.350665) (xy 450.279262 -246.365014) (xy 450.285808 -246.369281)
			(xy 450.300667 -246.374081) (xy 450.308472 -246.374412) (xy 450.8246 -246.374412) (xy 450.829937 -246.374729)
			(xy 450.837479 -246.382282) (xy 450.837808 -246.38762) (xy 450.837808 -246.882158) (xy 450.837254 -246.887446)
			(xy 450.829874 -246.895017) (xy 450.8246 -246.89562) (xy 450.308726 -246.89562) (xy 450.300917 -246.895941)
			(xy 450.286045 -246.900722) (xy 450.279516 -246.905018) (xy 450.258385 -246.919353) (xy 450.212665 -246.942084)
			(xy 450.163994 -246.957518) (xy 450.11353 -246.965289) (xy 450.088 -246.965724) (xy 450.062469 -246.965295)
			(xy 450.012005 -246.957518) (xy 449.963332 -246.942087) (xy 449.917605 -246.919367) (xy 449.896484 -246.905018)
			(xy 449.889954 -246.900724) (xy 449.875083 -246.895943) (xy 449.867274 -246.89562) (xy 449.3514 -246.89562)
			(xy 449.34614 -246.895106) (xy 449.338698 -246.887671) (xy 449.338192 -246.882412) (xy 443.293981 -246.882412)
			(xy 443.293454 -246.887446) (xy 443.286074 -246.895017) (xy 443.2808 -246.89562) (xy 442.764926 -246.89562)
			(xy 442.757117 -246.895941) (xy 442.742245 -246.900722) (xy 442.735716 -246.905018) (xy 442.714585 -246.919353)
			(xy 442.668865 -246.942084) (xy 442.620194 -246.957518) (xy 442.56973 -246.965289) (xy 442.5442 -246.965724)
			(xy 442.518669 -246.965295) (xy 442.468205 -246.957518) (xy 442.419532 -246.942087) (xy 442.373805 -246.919367)
			(xy 442.352684 -246.905018) (xy 442.346154 -246.900724) (xy 442.331283 -246.895943) (xy 442.323474 -246.89562)
			(xy 441.8076 -246.89562) (xy 441.80234 -246.895106) (xy 441.794898 -246.887671) (xy 441.794392 -246.882412)
			(xy 435.75018 -246.882412) (xy 435.749626 -246.887506) (xy 435.74209 -246.895091) (xy 435.736746 -246.89562)
			(xy 435.220872 -246.89562) (xy 435.21306 -246.895918) (xy 435.198189 -246.900715) (xy 435.191662 -246.905018)
			(xy 435.170546 -246.919376) (xy 435.12482 -246.942102) (xy 435.076145 -246.957529) (xy 435.025678 -246.965293)
			(xy 435.000146 -246.965724) (xy 434.974616 -246.965272) (xy 434.924153 -246.957502) (xy 434.87548 -246.942077)
			(xy 434.829752 -246.919364) (xy 434.80863 -246.905018) (xy 434.80209 -246.900742) (xy 434.787227 -246.895949)
			(xy 434.77942 -246.89562) (xy 434.263546 -246.89562) (xy 434.258107 -246.895286) (xy 434.250416 -246.887597)
			(xy 434.250084 -246.882158) (xy 428.2059 -246.882158) (xy 428.205353 -246.887448) (xy 428.197968 -246.895019)
			(xy 428.192692 -246.89562) (xy 427.676818 -246.89562) (xy 427.669008 -246.895938) (xy 427.654137 -246.900721)
			(xy 427.647608 -246.905018) (xy 427.626479 -246.919356) (xy 427.580758 -246.942086) (xy 427.532087 -246.95752)
			(xy 427.481622 -246.965289) (xy 427.456092 -246.965724) (xy 427.430561 -246.965299) (xy 427.380097 -246.957521)
			(xy 427.331424 -246.942088) (xy 427.285697 -246.919368) (xy 427.264576 -246.905018) (xy 427.258048 -246.900721)
			(xy 427.243175 -246.895941) (xy 427.235366 -246.89562) (xy 426.719492 -246.89562) (xy 426.714231 -246.895112)
			(xy 426.70679 -246.887673) (xy 426.706284 -246.882412) (xy 420.662081 -246.882412) (xy 420.661696 -246.887578)
			(xy 420.654056 -246.895264) (xy 420.648638 -246.89562) (xy 420.132764 -246.89562) (xy 420.124956 -246.895958)
			(xy 420.110084 -246.900727) (xy 420.103554 -246.905018) (xy 420.08244 -246.919379) (xy 420.036714 -246.942104)
			(xy 419.988038 -246.957531) (xy 419.93757 -246.965293) (xy 419.912038 -246.965724) (xy 419.886508 -246.965276)
			(xy 419.836044 -246.957505) (xy 419.787372 -246.942079) (xy 419.741644 -246.919365) (xy 419.720522 -246.905018)
			(xy 419.713984 -246.900738) (xy 419.699119 -246.895948) (xy 419.691312 -246.89562) (xy 419.175438 -246.89562)
			(xy 419.169998 -246.895291) (xy 419.162307 -246.887598) (xy 419.161976 -246.882158) (xy 413.117792 -246.882158)
			(xy 413.117253 -246.88745) (xy 413.109863 -246.895021) (xy 413.104584 -246.89562) (xy 411.631384 -246.89562)
			(xy 411.626122 -246.895117) (xy 411.618681 -246.887674) (xy 411.618176 -246.882412) (xy 363.308342 -246.882412)
			(xy 363.310977 -246.9142) (xy 363.306801 -246.964582) (xy 363.29439 -247.01359) (xy 363.274081 -247.059887)
			(xy 363.246428 -247.102209) (xy 363.212185 -247.139401) (xy 363.172288 -247.17045) (xy 363.127824 -247.194508)
			(xy 363.080006 -247.210919) (xy 363.03014 -247.219234) (xy 363.004862 -247.219724) (xy 362.064808 -247.219724)
			(xy 362.039526 -247.219307) (xy 361.989651 -247.210986) (xy 361.941825 -247.194569) (xy 361.897355 -247.170503)
			(xy 361.857452 -247.139447) (xy 361.823205 -247.102245) (xy 361.795548 -247.059915) (xy 361.775236 -247.013609)
			(xy 361.762823 -246.964592) (xy 361.758647 -246.9142) (xy 295.902069 -246.9142) (xy 295.894465 -246.919365)
			(xy 295.848742 -246.942093) (xy 295.800069 -246.957524) (xy 295.749603 -246.965291) (xy 295.724072 -246.965724)
			(xy 295.698541 -246.965309) (xy 295.648076 -246.957528) (xy 295.599403 -246.942092) (xy 295.553677 -246.919369)
			(xy 295.532556 -246.905018) (xy 295.526032 -246.900713) (xy 295.511156 -246.895938) (xy 295.503346 -246.89562)
			(xy 294.987472 -246.89562) (xy 294.982209 -246.895125) (xy 294.974768 -246.887676) (xy 294.974264 -246.882412)
			(xy 288.930062 -246.882412) (xy 288.929694 -246.887583) (xy 288.922041 -246.89527) (xy 288.916618 -246.89562)
			(xy 288.400744 -246.89562) (xy 288.392935 -246.895949) (xy 288.378064 -246.900724) (xy 288.371534 -246.905018)
			(xy 288.350426 -246.919388) (xy 288.304697 -246.942111) (xy 288.25602 -246.957535) (xy 288.20555 -246.965295)
			(xy 288.180018 -246.965724) (xy 288.154488 -246.965286) (xy 288.104024 -246.957512) (xy 288.055351 -246.942083)
			(xy 288.009624 -246.919366) (xy 287.988502 -246.905018) (xy 287.981968 -246.900731) (xy 287.9671 -246.895945)
			(xy 287.959292 -246.89562) (xy 287.443418 -246.89562) (xy 287.437975 -246.895305) (xy 287.430286 -246.887601)
			(xy 287.429956 -246.882158) (xy 281.385772 -246.882158) (xy 281.38525 -246.887454) (xy 281.377848 -246.895027)
			(xy 281.372564 -246.89562) (xy 280.85669 -246.89562) (xy 280.848879 -246.895926) (xy 280.834008 -246.900717)
			(xy 280.82748 -246.905018) (xy 280.806359 -246.919368) (xy 280.760635 -246.942096) (xy 280.711962 -246.957526)
			(xy 280.661495 -246.965292) (xy 280.635964 -246.965724) (xy 280.610433 -246.965313) (xy 280.559967 -246.95753)
			(xy 280.511295 -246.942094) (xy 280.465569 -246.91937) (xy 280.444448 -246.905018) (xy 280.437926 -246.90071)
			(xy 280.423049 -246.895937) (xy 280.415238 -246.89562) (xy 279.899364 -246.89562) (xy 279.8941 -246.89513)
			(xy 279.88666 -246.887677) (xy 279.886156 -246.882412) (xy 273.841947 -246.882412) (xy 273.84145 -246.887454)
			(xy 273.834048 -246.895027) (xy 273.828764 -246.89562) (xy 273.31289 -246.89562) (xy 273.305079 -246.895926)
			(xy 273.290208 -246.900717) (xy 273.28368 -246.905018) (xy 273.262559 -246.919368) (xy 273.216835 -246.942096)
			(xy 273.168162 -246.957526) (xy 273.117695 -246.965292) (xy 273.092164 -246.965724) (xy 273.066633 -246.965313)
			(xy 273.016167 -246.95753) (xy 272.967495 -246.942094) (xy 272.921769 -246.91937) (xy 272.900648 -246.905018)
			(xy 272.894126 -246.90071) (xy 272.879249 -246.895937) (xy 272.871438 -246.89562) (xy 272.355564 -246.89562)
			(xy 272.3503 -246.89513) (xy 272.34286 -246.887677) (xy 272.342356 -246.882412) (xy 266.298154 -246.882412)
			(xy 266.297793 -246.887585) (xy 266.290135 -246.895273) (xy 266.28471 -246.89562) (xy 265.768836 -246.89562)
			(xy 265.761027 -246.895945) (xy 265.746155 -246.900723) (xy 265.739626 -246.905018) (xy 265.718492 -246.919348)
			(xy 265.672773 -246.94208) (xy 265.624103 -246.957516) (xy 265.57364 -246.965288) (xy 265.54811 -246.965724)
			(xy 265.52258 -246.96529) (xy 265.472115 -246.957514) (xy 265.423443 -246.942085) (xy 265.377715 -246.919367)
			(xy 265.356594 -246.905018) (xy 265.350062 -246.900728) (xy 265.335192 -246.895944) (xy 265.327384 -246.89562)
			(xy 264.81151 -246.89562) (xy 264.806066 -246.89531) (xy 264.798377 -246.887603) (xy 264.798048 -246.882158)
			(xy 202.89774 -246.882158) (xy 202.89774 -246.882412) (xy 202.897216 -246.887668) (xy 202.889788 -246.895108)
			(xy 202.884532 -246.89562) (xy 202.368658 -246.89562) (xy 202.360783 -246.895902) (xy 202.345779 -246.90069)
			(xy 202.339194 -246.905018) (xy 202.318106 -246.919394) (xy 202.272465 -246.942226) (xy 202.223863 -246.957789)
			(xy 202.173448 -246.965713) (xy 202.147932 -246.966232) (xy 202.122412 -246.965738) (xy 202.071986 -246.957843)
			(xy 202.023374 -246.942285) (xy 201.977735 -246.919432) (xy 201.95667 -246.905018) (xy 201.950086 -246.900691)
			(xy 201.93508 -246.895911) (xy 201.927206 -246.89562) (xy 201.411332 -246.89562) (xy 201.406007 -246.895253)
			(xy 201.398465 -246.887736) (xy 201.398124 -246.882412) (xy 195.35394 -246.882412) (xy 195.353416 -246.887668)
			(xy 195.345988 -246.895108) (xy 195.340732 -246.89562) (xy 194.824858 -246.89562) (xy 194.816983 -246.895902)
			(xy 194.801979 -246.90069) (xy 194.795394 -246.905018) (xy 194.774306 -246.919394) (xy 194.728665 -246.942226)
			(xy 194.680063 -246.957789) (xy 194.629648 -246.965713) (xy 194.604132 -246.966232) (xy 194.578612 -246.965738)
			(xy 194.528186 -246.957843) (xy 194.479574 -246.942285) (xy 194.433935 -246.919432) (xy 194.41287 -246.905018)
			(xy 194.406286 -246.900691) (xy 194.39128 -246.895911) (xy 194.383406 -246.89562) (xy 193.867532 -246.89562)
			(xy 193.862207 -246.895253) (xy 193.854665 -246.887736) (xy 193.854324 -246.882412) (xy 187.81014 -246.882412)
			(xy 187.809616 -246.887668) (xy 187.802188 -246.895108) (xy 187.796932 -246.89562) (xy 187.796424 -246.89562)
			(xy 187.280804 -246.89562) (xy 187.272931 -246.895922) (xy 187.257927 -246.900697) (xy 187.25134 -246.905018)
			(xy 187.230267 -246.919417) (xy 187.184621 -246.942244) (xy 187.136014 -246.9578) (xy 187.085595 -246.965717)
			(xy 187.060078 -246.966232) (xy 187.034559 -246.965714) (xy 186.984133 -246.957827) (xy 186.935522 -246.942275)
			(xy 186.889882 -246.919429) (xy 186.868816 -246.905018) (xy 186.862221 -246.900708) (xy 186.847224 -246.895918)
			(xy 186.839352 -246.89562) (xy 186.323478 -246.89562) (xy 186.318162 -246.895187) (xy 186.31059 -246.887721)
			(xy 186.310016 -246.882412) (xy 180.265832 -246.882412) (xy 180.265316 -246.88767) (xy 180.257882 -246.895111)
			(xy 180.252624 -246.89562) (xy 179.73675 -246.89562) (xy 179.728875 -246.895899) (xy 179.713871 -246.900689)
			(xy 179.707286 -246.905018) (xy 179.6862 -246.919397) (xy 179.640559 -246.942229) (xy 179.591955 -246.957791)
			(xy 179.54154 -246.965713) (xy 179.516024 -246.966232) (xy 179.490504 -246.965742) (xy 179.440077 -246.957846)
			(xy 179.391466 -246.942286) (xy 179.345827 -246.919432) (xy 179.324762 -246.905018) (xy 179.31818 -246.900687)
			(xy 179.303173 -246.89591) (xy 179.295298 -246.89562) (xy 178.779424 -246.89562) (xy 178.774098 -246.895258)
			(xy 178.766556 -246.887737) (xy 178.766216 -246.882412) (xy 172.722032 -246.882412) (xy 172.721516 -246.88767)
			(xy 172.714082 -246.895111) (xy 172.708824 -246.89562) (xy 172.708316 -246.89562) (xy 172.192696 -246.89562)
			(xy 172.184822 -246.895918) (xy 172.169819 -246.900695) (xy 172.163232 -246.905018) (xy 172.142162 -246.91942)
			(xy 172.096514 -246.942247) (xy 172.047906 -246.957802) (xy 171.997487 -246.965717) (xy 171.97197 -246.966232)
			(xy 171.946451 -246.965718) (xy 171.896025 -246.95783) (xy 171.847414 -246.942277) (xy 171.801774 -246.919429)
			(xy 171.780708 -246.905018) (xy 171.774115 -246.900705) (xy 171.759116 -246.895917) (xy 171.751244 -246.89562)
			(xy 171.23537 -246.89562) (xy 171.230053 -246.895192) (xy 171.222481 -246.887722) (xy 171.221908 -246.882412)
			(xy 165.177724 -246.882412) (xy 165.177215 -246.887672) (xy 165.169776 -246.895113) (xy 165.164516 -246.89562)
			(xy 163.691316 -246.89562) (xy 163.685989 -246.895264) (xy 163.678448 -246.887738) (xy 163.678108 -246.882412)
			(xy 109.734325 -246.882412) (xy 109.736976 -246.9144) (xy 109.732804 -246.964748) (xy 109.720401 -247.013723)
			(xy 109.700106 -247.059988) (xy 109.672472 -247.102282) (xy 109.638254 -247.13945) (xy 109.598385 -247.170478)
			(xy 109.553951 -247.194521) (xy 109.506167 -247.210922) (xy 109.456334 -247.219233) (xy 109.431074 -247.219724)
			(xy 108.49102 -247.219724) (xy 108.465763 -247.219201) (xy 108.415936 -247.210889) (xy 108.368157 -247.19449)
			(xy 108.32373 -247.170449) (xy 108.283865 -247.139424) (xy 108.249651 -247.10226) (xy 108.222021 -247.059971)
			(xy 108.201729 -247.013711) (xy 108.189328 -246.964742) (xy 108.185156 -246.9144) (xy 47.96152 -246.9144)
			(xy 47.954186 -246.919406) (xy 47.908542 -246.942236) (xy 47.859937 -246.957795) (xy 47.809521 -246.965715)
			(xy 47.784004 -246.966232) (xy 47.758483 -246.965752) (xy 47.708056 -246.957853) (xy 47.659445 -246.94229)
			(xy 47.613807 -246.919434) (xy 47.592742 -246.905018) (xy 47.586164 -246.90068) (xy 47.571154 -246.895907)
			(xy 47.563278 -246.89562) (xy 47.047404 -246.89562) (xy 47.042145 -246.895104) (xy 47.034702 -246.887671)
			(xy 47.034196 -246.882412) (xy 40.990012 -246.882412) (xy 40.989514 -246.887675) (xy 40.982067 -246.895117)
			(xy 40.976804 -246.89562) (xy 40.976296 -246.89562) (xy 40.460676 -246.89562) (xy 40.452802 -246.89591)
			(xy 40.437798 -246.900692) (xy 40.431212 -246.905018) (xy 40.410147 -246.919429) (xy 40.364498 -246.942254)
			(xy 40.315888 -246.957806) (xy 40.265468 -246.965719) (xy 40.23995 -246.966232) (xy 40.21443 -246.965728)
			(xy 40.164004 -246.957837) (xy 40.115393 -246.942281) (xy 40.069754 -246.919431) (xy 40.048688 -246.905018)
			(xy 40.0421 -246.900698) (xy 40.027097 -246.895914) (xy 40.019224 -246.89562) (xy 39.50335 -246.89562)
			(xy 39.498043 -246.895139) (xy 39.490466 -246.887709) (xy 39.489888 -246.882412) (xy 33.445704 -246.882412)
			(xy 33.445213 -246.887677) (xy 33.437762 -246.895119) (xy 33.432496 -246.89562) (xy 32.916622 -246.89562)
			(xy 32.908749 -246.89593) (xy 32.893746 -246.900699) (xy 32.887158 -246.905018) (xy 32.86608 -246.919409)
			(xy 32.820436 -246.942238) (xy 32.77183 -246.957797) (xy 32.721413 -246.965715) (xy 32.695896 -246.966232)
			(xy 32.670375 -246.965756) (xy 32.619948 -246.957856) (xy 32.571337 -246.942292) (xy 32.525699 -246.919434)
			(xy 32.504634 -246.905018) (xy 32.498035 -246.900715) (xy 32.483041 -246.895921) (xy 32.47517 -246.89562)
			(xy 31.959296 -246.89562) (xy 31.954036 -246.895109) (xy 31.946594 -246.887672) (xy 31.946088 -246.882412)
			(xy 25.901904 -246.882412) (xy 25.901413 -246.887677) (xy 25.893962 -246.895119) (xy 25.888696 -246.89562)
			(xy 25.372822 -246.89562) (xy 25.364949 -246.89593) (xy 25.349946 -246.900699) (xy 25.343358 -246.905018)
			(xy 25.32228 -246.919409) (xy 25.276636 -246.942238) (xy 25.22803 -246.957797) (xy 25.177613 -246.965715)
			(xy 25.152096 -246.966232) (xy 25.126575 -246.965756) (xy 25.076148 -246.957856) (xy 25.027537 -246.942292)
			(xy 24.981899 -246.919434) (xy 24.960834 -246.905018) (xy 24.954235 -246.900715) (xy 24.939241 -246.895921)
			(xy 24.93137 -246.89562) (xy 24.415496 -246.89562) (xy 24.410236 -246.895109) (xy 24.402794 -246.887672)
			(xy 24.402288 -246.882412) (xy 18.358104 -246.882412) (xy 18.357613 -246.887677) (xy 18.350162 -246.895119)
			(xy 18.344896 -246.89562) (xy 18.344388 -246.89562) (xy 17.828768 -246.89562) (xy 17.820893 -246.895906)
			(xy 17.80589 -246.900691) (xy 17.799304 -246.905018) (xy 17.778213 -246.919389) (xy 17.732574 -246.942223)
			(xy 17.683972 -246.957787) (xy 17.633558 -246.965712) (xy 17.608042 -246.966232) (xy 17.582522 -246.965733)
			(xy 17.532096 -246.95784) (xy 17.483485 -246.942283) (xy 17.437846 -246.919431) (xy 17.41678 -246.905018)
			(xy 17.410194 -246.900694) (xy 17.39519 -246.895913) (xy 17.387316 -246.89562) (xy 16.871442 -246.89562)
			(xy 16.866134 -246.895144) (xy 16.858558 -246.887711) (xy 16.85798 -246.882412) (xy 2.509012 -246.882412)
			(xy 2.509012 -247.73255) (xy 20.958048 -247.73255) (xy 20.958048 -247.238012) (xy 20.958598 -247.232761)
			(xy 20.966007 -247.225321) (xy 20.971256 -247.224804) (xy 20.971764 -247.224804) (xy 21.487638 -247.224804)
			(xy 21.495446 -247.224463) (xy 21.510317 -247.219696) (xy 21.516848 -247.215406) (xy 21.537937 -247.201057)
			(xy 21.583598 -247.178326) (xy 21.632204 -247.162867) (xy 21.682607 -247.155044) (xy 21.733613 -247.155044)
			(xy 21.784016 -247.162867) (xy 21.832622 -247.178326) (xy 21.878283 -247.201057) (xy 21.899372 -247.215406)
			(xy 21.90591 -247.219686) (xy 21.920775 -247.224476) (xy 21.928582 -247.224804) (xy 22.44471 -247.224804)
			(xy 22.450007 -247.225312) (xy 22.457575 -247.232726) (xy 22.458172 -247.238012) (xy 22.458172 -247.73255)
			(xy 22.458149 -247.732804) (xy 28.502356 -247.732804) (xy 28.502356 -247.732296) (xy 28.502356 -247.238012)
			(xy 28.502899 -247.232759) (xy 28.510313 -247.225318) (xy 28.515564 -247.224804) (xy 29.031692 -247.224804)
			(xy 29.039502 -247.224486) (xy 29.054373 -247.219703) (xy 29.060902 -247.215406) (xy 29.081991 -247.201057)
			(xy 29.127652 -247.178326) (xy 29.176258 -247.162867) (xy 29.226661 -247.155044) (xy 29.277667 -247.155044)
			(xy 29.32807 -247.162867) (xy 29.376676 -247.178326) (xy 29.422337 -247.201057) (xy 29.443426 -247.215406)
			(xy 29.449952 -247.219707) (xy 29.464826 -247.224484) (xy 29.472636 -247.224804) (xy 29.988764 -247.224804)
			(xy 29.994094 -247.225152) (xy 30.001638 -247.232682) (xy 30.001972 -247.238012) (xy 30.001972 -247.73255)
			(xy 30.001947 -247.732804) (xy 36.046156 -247.732804) (xy 36.046156 -247.732296) (xy 36.046156 -247.238012)
			(xy 36.046699 -247.232759) (xy 36.054113 -247.225318) (xy 36.059364 -247.224804) (xy 36.575492 -247.224804)
			(xy 36.583302 -247.224486) (xy 36.598173 -247.219703) (xy 36.604702 -247.215406) (xy 36.625791 -247.201057)
			(xy 36.671452 -247.178326) (xy 36.720058 -247.162867) (xy 36.770461 -247.155044) (xy 36.821467 -247.155044)
			(xy 36.87187 -247.162867) (xy 36.920476 -247.178326) (xy 36.966137 -247.201057) (xy 36.987226 -247.215406)
			(xy 36.993752 -247.219707) (xy 37.008626 -247.224484) (xy 37.016436 -247.224804) (xy 37.532564 -247.224804)
			(xy 37.537894 -247.225152) (xy 37.545438 -247.232682) (xy 37.545772 -247.238012) (xy 37.545772 -247.73255)
			(xy 43.589956 -247.73255) (xy 43.589956 -247.238012) (xy 43.590499 -247.232759) (xy 43.597913 -247.225318)
			(xy 43.603164 -247.224804) (xy 43.603672 -247.224804) (xy 44.119546 -247.224804) (xy 44.127354 -247.224467)
			(xy 44.142225 -247.219697) (xy 44.148756 -247.215406) (xy 44.169845 -247.201057) (xy 44.215506 -247.178326)
			(xy 44.264112 -247.162867) (xy 44.314515 -247.155044) (xy 44.365521 -247.155044) (xy 44.415924 -247.162867)
			(xy 44.46453 -247.178326) (xy 44.510191 -247.201057) (xy 44.53128 -247.215406) (xy 44.537816 -247.219689)
			(xy 44.552683 -247.224477) (xy 44.56049 -247.224804) (xy 45.076618 -247.224804) (xy 45.081916 -247.225307)
			(xy 45.089484 -247.232725) (xy 45.09008 -247.238012) (xy 45.09008 -247.73255) (xy 45.090057 -247.732804)
			(xy 51.134264 -247.732804) (xy 51.134264 -247.732296) (xy 51.134264 -247.238012) (xy 51.1348 -247.232757)
			(xy 51.142219 -247.225316) (xy 51.147472 -247.224804) (xy 51.6636 -247.224804) (xy 51.67141 -247.22449)
			(xy 51.686281 -247.219704) (xy 51.69281 -247.215406) (xy 51.713899 -247.201057) (xy 51.75956 -247.178326)
			(xy 51.808166 -247.162867) (xy 51.858569 -247.155044) (xy 51.909575 -247.155044) (xy 51.959978 -247.162867)
			(xy 52.008584 -247.178326) (xy 52.054245 -247.201057) (xy 52.075334 -247.215406) (xy 52.081858 -247.21971)
			(xy 52.096734 -247.224485) (xy 52.104544 -247.224804) (xy 52.620672 -247.224804) (xy 52.626003 -247.225147)
			(xy 52.633547 -247.232681) (xy 52.63388 -247.238012) (xy 52.63388 -247.73255) (xy 58.678064 -247.73255)
			(xy 58.678064 -247.238012) (xy 58.6786 -247.232757) (xy 58.686019 -247.225316) (xy 58.691272 -247.224804)
			(xy 58.69178 -247.224804) (xy 60.164726 -247.224804) (xy 60.170025 -247.225301) (xy 60.177593 -247.232724)
			(xy 60.178188 -247.238012) (xy 60.178188 -247.7244) (xy 97.374907 -247.7244) (xy 97.379083 -247.674015)
			(xy 97.391495 -247.625005) (xy 97.411805 -247.578707) (xy 97.439459 -247.536383) (xy 97.473702 -247.499188)
			(xy 97.513601 -247.468138) (xy 97.558067 -247.444079) (xy 97.605887 -247.427667) (xy 97.655755 -247.41935)
			(xy 97.681034 -247.41886) (xy 98.621088 -247.41886) (xy 98.646369 -247.419308) (xy 98.696242 -247.427629)
			(xy 98.744066 -247.444045) (xy 98.788534 -247.468109) (xy 98.828436 -247.499164) (xy 98.862682 -247.536363)
			(xy 98.890337 -247.578692) (xy 98.910648 -247.624995) (xy 98.923061 -247.67401) (xy 98.927237 -247.7244)
			(xy 100.194807 -247.7244) (xy 100.198983 -247.674014) (xy 100.211395 -247.625004) (xy 100.231706 -247.578704)
			(xy 100.259361 -247.53638) (xy 100.293605 -247.499185) (xy 100.333506 -247.468135) (xy 100.377972 -247.444076)
			(xy 100.425793 -247.427665) (xy 100.475663 -247.41935) (xy 100.500942 -247.41886) (xy 101.440996 -247.41886)
			(xy 101.466277 -247.419309) (xy 101.516149 -247.42763) (xy 101.563971 -247.444047) (xy 101.608439 -247.468111)
			(xy 101.648339 -247.499167) (xy 101.682584 -247.536366) (xy 101.710238 -247.578694) (xy 101.730549 -247.624997)
			(xy 101.742961 -247.674011) (xy 101.747137 -247.7244) (xy 103.015007 -247.7244) (xy 103.019182 -247.674018)
			(xy 103.031593 -247.625011) (xy 103.0519 -247.578715) (xy 103.079551 -247.536393) (xy 103.113791 -247.499199)
			(xy 103.153685 -247.468148) (xy 103.198147 -247.444087) (xy 103.245962 -247.427673) (xy 103.295827 -247.419353)
			(xy 103.321104 -247.41886) (xy 104.261158 -247.41886) (xy 104.286441 -247.419306) (xy 104.336318 -247.427622)
			(xy 104.384145 -247.444036) (xy 104.428619 -247.468098) (xy 104.468524 -247.499153) (xy 104.502774 -247.536353)
			(xy 104.530433 -247.578683) (xy 104.550746 -247.624989) (xy 104.56316 -247.674007) (xy 104.567337 -247.7244)
			(xy 105.834907 -247.7244) (xy 105.839082 -247.674018) (xy 105.851493 -247.62501) (xy 105.871801 -247.578713)
			(xy 105.899453 -247.53639) (xy 105.933694 -247.499196) (xy 105.97359 -247.468145) (xy 106.018052 -247.444085)
			(xy 106.065869 -247.427671) (xy 106.115734 -247.419352) (xy 106.141012 -247.41886) (xy 107.081066 -247.41886)
			(xy 107.106348 -247.419306) (xy 107.156224 -247.427624) (xy 107.204051 -247.444038) (xy 107.248523 -247.468101)
			(xy 107.288427 -247.499156) (xy 107.322676 -247.536356) (xy 107.350334 -247.578686) (xy 107.370647 -247.624991)
			(xy 107.383061 -247.674008) (xy 107.387237 -247.7244) (xy 107.386541 -247.732804) (xy 167.778176 -247.732804)
			(xy 167.778176 -247.732296) (xy 167.778176 -247.238012) (xy 167.778701 -247.232755) (xy 167.786128 -247.225312)
			(xy 167.791384 -247.224804) (xy 169.264584 -247.224804) (xy 169.269917 -247.225139) (xy 169.27746 -247.232679)
			(xy 169.277792 -247.238012) (xy 169.277792 -247.73255) (xy 175.321976 -247.73255) (xy 175.321976 -247.238012)
			(xy 175.322501 -247.232755) (xy 175.329928 -247.225312) (xy 175.335184 -247.224804) (xy 175.335692 -247.224804)
			(xy 175.851566 -247.224804) (xy 175.859375 -247.224475) (xy 175.874246 -247.2197) (xy 175.880776 -247.215406)
			(xy 175.901865 -247.201057) (xy 175.947526 -247.178326) (xy 175.996132 -247.162867) (xy 176.046535 -247.155044)
			(xy 176.097541 -247.155044) (xy 176.147944 -247.162867) (xy 176.19655 -247.178326) (xy 176.242211 -247.201057)
			(xy 176.2633 -247.215406) (xy 176.269832 -247.219697) (xy 176.284702 -247.22448) (xy 176.29251 -247.224804)
			(xy 176.808638 -247.224804) (xy 176.813939 -247.225293) (xy 176.821506 -247.232722) (xy 176.8221 -247.238012)
			(xy 176.8221 -247.73255) (xy 176.822076 -247.732804) (xy 182.866284 -247.732804) (xy 182.866284 -247.732296)
			(xy 182.866284 -247.238012) (xy 182.866634 -247.232683) (xy 182.874164 -247.225142) (xy 182.879492 -247.224804)
			(xy 183.39562 -247.224804) (xy 183.403431 -247.224498) (xy 183.418302 -247.219707) (xy 183.42483 -247.215406)
			(xy 183.445919 -247.201057) (xy 183.49158 -247.178326) (xy 183.540186 -247.162867) (xy 183.590589 -247.155044)
			(xy 183.641595 -247.155044) (xy 183.691998 -247.162867) (xy 183.740604 -247.178326) (xy 183.786265 -247.201057)
			(xy 183.807354 -247.215406) (xy 183.813874 -247.219717) (xy 183.828753 -247.224488) (xy 183.836564 -247.224804)
			(xy 184.352692 -247.224804) (xy 184.358026 -247.225133) (xy 184.365568 -247.232678) (xy 184.3659 -247.238012)
			(xy 184.3659 -247.73255) (xy 190.410084 -247.73255) (xy 190.410084 -247.238012) (xy 190.410434 -247.232683)
			(xy 190.417964 -247.225142) (xy 190.423292 -247.224804) (xy 190.4238 -247.224804) (xy 190.939674 -247.224804)
			(xy 190.947483 -247.224479) (xy 190.962354 -247.219701) (xy 190.968884 -247.215406) (xy 190.989973 -247.201057)
			(xy 191.035634 -247.178326) (xy 191.08424 -247.162867) (xy 191.134643 -247.155044) (xy 191.185649 -247.155044)
			(xy 191.236052 -247.162867) (xy 191.284658 -247.178326) (xy 191.330319 -247.201057) (xy 191.351408 -247.215406)
			(xy 191.357938 -247.2197) (xy 191.372809 -247.224481) (xy 191.380618 -247.224804) (xy 191.896746 -247.224804)
			(xy 191.902035 -247.225355) (xy 191.909607 -247.232736) (xy 191.910208 -247.238012) (xy 191.910208 -247.73255)
			(xy 191.910183 -247.732804) (xy 197.954392 -247.732804) (xy 197.954392 -247.732296) (xy 197.954392 -247.238012)
			(xy 197.954735 -247.232681) (xy 197.96227 -247.22514) (xy 197.9676 -247.224804) (xy 198.483728 -247.224804)
			(xy 198.491539 -247.224501) (xy 198.50641 -247.219708) (xy 198.512938 -247.215406) (xy 198.534027 -247.201057)
			(xy 198.579688 -247.178326) (xy 198.628294 -247.162867) (xy 198.678697 -247.155044) (xy 198.729703 -247.155044)
			(xy 198.780106 -247.162867) (xy 198.828712 -247.178326) (xy 198.874373 -247.201057) (xy 198.895462 -247.215406)
			(xy 198.902002 -247.219682) (xy 198.916866 -247.224474) (xy 198.924672 -247.224804) (xy 199.4408 -247.224804)
			(xy 199.446135 -247.225128) (xy 199.453677 -247.232676) (xy 199.454008 -247.238012) (xy 199.454008 -247.73255)
			(xy 199.453981 -247.732804) (xy 205.498192 -247.732804) (xy 205.498192 -247.732296) (xy 205.498192 -247.238012)
			(xy 205.498535 -247.232681) (xy 205.50607 -247.22514) (xy 205.5114 -247.224804) (xy 206.027528 -247.224804)
			(xy 206.035339 -247.224501) (xy 206.05021 -247.219708) (xy 206.056738 -247.215406) (xy 206.077827 -247.201057)
			(xy 206.123488 -247.178326) (xy 206.172094 -247.162867) (xy 206.222497 -247.155044) (xy 206.273503 -247.155044)
			(xy 206.323906 -247.162867) (xy 206.372512 -247.178326) (xy 206.418173 -247.201057) (xy 206.439262 -247.215406)
			(xy 206.445802 -247.219682) (xy 206.460666 -247.224474) (xy 206.468472 -247.224804) (xy 206.9846 -247.224804)
			(xy 206.989935 -247.225128) (xy 206.997477 -247.232676) (xy 206.997808 -247.238012) (xy 206.997808 -247.732296)
			(xy 268.898116 -247.732296) (xy 268.898116 -247.237758) (xy 268.89862 -247.232394) (xy 268.906214 -247.224812)
			(xy 268.911578 -247.224296) (xy 269.427706 -247.224296) (xy 269.435516 -247.223986) (xy 269.450388 -247.219197)
			(xy 269.456916 -247.214898) (xy 269.478005 -247.200549) (xy 269.523666 -247.177818) (xy 269.572272 -247.162359)
			(xy 269.622675 -247.154536) (xy 269.673681 -247.154536) (xy 269.724084 -247.162359) (xy 269.77269 -247.177818)
			(xy 269.818351 -247.200549) (xy 269.83944 -247.214898) (xy 269.845963 -247.219203) (xy 269.86084 -247.223978)
			(xy 269.86865 -247.224296) (xy 270.384778 -247.224296) (xy 270.390129 -247.224861) (xy 270.397714 -247.232409)
			(xy 270.39824 -247.237758) (xy 270.39824 -247.732296) (xy 276.442424 -247.732296) (xy 276.442424 -247.237758)
			(xy 276.442893 -247.232452) (xy 276.450336 -247.224885) (xy 276.455632 -247.224296) (xy 276.97176 -247.224296)
			(xy 276.979569 -247.223966) (xy 276.99444 -247.219191) (xy 277.00097 -247.214898) (xy 277.022059 -247.200549)
			(xy 277.06772 -247.177818) (xy 277.116326 -247.162359) (xy 277.166729 -247.154536) (xy 277.217735 -247.154536)
			(xy 277.268138 -247.162359) (xy 277.316744 -247.177818) (xy 277.362405 -247.200549) (xy 277.383494 -247.214898)
			(xy 277.390028 -247.219186) (xy 277.404896 -247.223971) (xy 277.412704 -247.224296) (xy 277.928832 -247.224296)
			(xy 277.9341 -247.224774) (xy 277.941541 -247.232235) (xy 277.94204 -247.237504) (xy 277.94204 -247.238012)
			(xy 277.94204 -247.732296) (xy 283.986224 -247.732296) (xy 283.986224 -247.237758) (xy 283.986693 -247.232452)
			(xy 283.994136 -247.224885) (xy 283.999432 -247.224296) (xy 284.51556 -247.224296) (xy 284.523369 -247.223966)
			(xy 284.53824 -247.219191) (xy 284.54477 -247.214898) (xy 284.565859 -247.200549) (xy 284.61152 -247.177818)
			(xy 284.660126 -247.162359) (xy 284.710529 -247.154536) (xy 284.761535 -247.154536) (xy 284.811938 -247.162359)
			(xy 284.860544 -247.177818) (xy 284.906205 -247.200549) (xy 284.927294 -247.214898) (xy 284.933828 -247.219186)
			(xy 284.948696 -247.223971) (xy 284.956504 -247.224296) (xy 285.472632 -247.224296) (xy 285.4779 -247.224774)
			(xy 285.485341 -247.232235) (xy 285.48584 -247.237504) (xy 285.48584 -247.238012) (xy 285.48584 -247.732296)
			(xy 291.530024 -247.732296) (xy 291.530024 -247.237758) (xy 291.530521 -247.232392) (xy 291.538119 -247.22481)
			(xy 291.543486 -247.224296) (xy 292.059614 -247.224296) (xy 292.067425 -247.223989) (xy 292.082296 -247.219198)
			(xy 292.088824 -247.214898) (xy 292.109913 -247.200549) (xy 292.155574 -247.177818) (xy 292.20418 -247.162359)
			(xy 292.254583 -247.154536) (xy 292.305589 -247.154536) (xy 292.355992 -247.162359) (xy 292.404598 -247.177818)
			(xy 292.450259 -247.200549) (xy 292.471348 -247.214898) (xy 292.47787 -247.219206) (xy 292.492747 -247.223979)
			(xy 292.500558 -247.224296) (xy 293.016686 -247.224296) (xy 293.022038 -247.224855) (xy 293.029622 -247.232408)
			(xy 293.030148 -247.237758) (xy 293.030148 -247.732296) (xy 299.074332 -247.732296) (xy 299.074332 -247.237758)
			(xy 299.074794 -247.23245) (xy 299.082241 -247.224882) (xy 299.08754 -247.224296) (xy 299.603668 -247.224296)
			(xy 299.611477 -247.22397) (xy 299.626348 -247.219192) (xy 299.632878 -247.214898) (xy 299.653967 -247.200549)
			(xy 299.699628 -247.177818) (xy 299.748234 -247.162359) (xy 299.798637 -247.154536) (xy 299.849643 -247.154536)
			(xy 299.900046 -247.162359) (xy 299.948652 -247.177818) (xy 299.994313 -247.200549) (xy 300.015402 -247.214898)
			(xy 300.021934 -247.219189) (xy 300.036804 -247.223972) (xy 300.044612 -247.224296) (xy 300.56074 -247.224296)
			(xy 300.566009 -247.224768) (xy 300.573449 -247.232234) (xy 300.573948 -247.237504) (xy 300.573948 -247.238012)
			(xy 300.573948 -247.732296) (xy 306.618132 -247.732296) (xy 306.618132 -247.237758) (xy 306.618622 -247.23239)
			(xy 306.626225 -247.224807) (xy 306.631594 -247.224296) (xy 308.104794 -247.224296) (xy 308.110147 -247.22485)
			(xy 308.117731 -247.232407) (xy 308.118256 -247.237758) (xy 308.118256 -247.7242) (xy 364.108908 -247.7242)
			(xy 364.11308 -247.67385) (xy 364.125483 -247.624874) (xy 364.145778 -247.578607) (xy 364.173412 -247.536312)
			(xy 364.207631 -247.499142) (xy 364.247501 -247.468112) (xy 364.291935 -247.444068) (xy 364.339721 -247.427665)
			(xy 364.389555 -247.419352) (xy 364.414816 -247.41886) (xy 365.35487 -247.41886) (xy 365.380127 -247.419414)
			(xy 365.429952 -247.427724) (xy 365.477729 -247.444122) (xy 365.522156 -247.468161) (xy 365.56202 -247.499184)
			(xy 365.596233 -247.536347) (xy 365.623863 -247.578634) (xy 365.644155 -247.624892) (xy 365.656556 -247.673859)
			(xy 365.660728 -247.7242) (xy 366.928808 -247.7242) (xy 366.93298 -247.673849) (xy 366.945384 -247.624872)
			(xy 366.96568 -247.578605) (xy 366.993314 -247.536309) (xy 367.027534 -247.499139) (xy 367.067406 -247.468109)
			(xy 367.111841 -247.444065) (xy 367.159628 -247.427663) (xy 367.209462 -247.419351) (xy 367.234724 -247.41886)
			(xy 368.174778 -247.41886) (xy 368.200034 -247.419415) (xy 368.249858 -247.427726) (xy 368.297635 -247.444124)
			(xy 368.34206 -247.468163) (xy 368.381923 -247.499187) (xy 368.416136 -247.536349) (xy 368.443764 -247.578636)
			(xy 368.464056 -247.624893) (xy 368.476457 -247.67386) (xy 368.480628 -247.7242) (xy 369.749037 -247.7242)
			(xy 369.753208 -247.673858) (xy 369.765609 -247.624889) (xy 369.785899 -247.578629) (xy 369.813527 -247.53634)
			(xy 369.847739 -247.499174) (xy 369.887601 -247.468147) (xy 369.932027 -247.444103) (xy 369.979804 -247.427699)
			(xy 370.029629 -247.419383) (xy 370.054886 -247.41886) (xy 370.99494 -247.41886) (xy 371.020191 -247.419449)
			(xy 371.070002 -247.427767) (xy 371.117765 -247.444169) (xy 371.162177 -247.468209) (xy 371.202028 -247.499231)
			(xy 371.236229 -247.536388) (xy 371.263848 -247.578667) (xy 371.284133 -247.624915) (xy 371.296529 -247.673871)
			(xy 371.300699 -247.7242) (xy 372.568937 -247.7242) (xy 372.573108 -247.673857) (xy 372.585509 -247.624888)
			(xy 372.605801 -247.578627) (xy 372.63343 -247.536337) (xy 372.667642 -247.499171) (xy 372.707506 -247.468144)
			(xy 372.751932 -247.444101) (xy 372.79971 -247.427698) (xy 372.849536 -247.419382) (xy 372.874794 -247.41886)
			(xy 373.814848 -247.41886) (xy 373.840098 -247.419449) (xy 373.889908 -247.427768) (xy 373.93767 -247.444172)
			(xy 373.982082 -247.468212) (xy 374.021931 -247.499233) (xy 374.056131 -247.53639) (xy 374.083749 -247.578669)
			(xy 374.104033 -247.624917) (xy 374.116429 -247.673872) (xy 374.120599 -247.7242) (xy 374.119928 -247.732296)
			(xy 415.718244 -247.732296) (xy 415.718244 -247.237758) (xy 415.718696 -247.232448) (xy 415.72615 -247.224879)
			(xy 415.731452 -247.224296) (xy 417.204652 -247.224296) (xy 417.209979 -247.22466) (xy 417.217523 -247.232178)
			(xy 417.21786 -247.237504) (xy 417.21786 -247.238012) (xy 417.21786 -247.732296) (xy 423.262044 -247.732296)
			(xy 423.262044 -247.237758) (xy 423.262523 -247.232387) (xy 423.270134 -247.224804) (xy 423.275506 -247.224296)
			(xy 423.791634 -247.224296) (xy 423.799442 -247.223955) (xy 423.814313 -247.219188) (xy 423.820844 -247.214898)
			(xy 423.841933 -247.200549) (xy 423.887594 -247.177818) (xy 423.9362 -247.162359) (xy 423.986603 -247.154536)
			(xy 424.037609 -247.154536) (xy 424.088012 -247.162359) (xy 424.136618 -247.177818) (xy 424.182279 -247.200549)
			(xy 424.203368 -247.214898) (xy 424.209907 -247.219176) (xy 424.224771 -247.223967) (xy 424.232578 -247.224296)
			(xy 424.748706 -247.224296) (xy 424.754061 -247.224842) (xy 424.761644 -247.232405) (xy 424.762168 -247.237758)
			(xy 424.762168 -247.732296) (xy 430.806352 -247.732296) (xy 430.806352 -247.237758) (xy 430.806797 -247.232446)
			(xy 430.814256 -247.224876) (xy 430.81956 -247.224296) (xy 431.335688 -247.224296) (xy 431.343498 -247.223978)
			(xy 431.358369 -247.219195) (xy 431.364898 -247.214898) (xy 431.385987 -247.200549) (xy 431.431648 -247.177818)
			(xy 431.480254 -247.162359) (xy 431.530657 -247.154536) (xy 431.581663 -247.154536) (xy 431.632066 -247.162359)
			(xy 431.680672 -247.177818) (xy 431.726333 -247.200549) (xy 431.747422 -247.214898) (xy 431.753949 -247.219196)
			(xy 431.768823 -247.223975) (xy 431.776632 -247.224296) (xy 432.29276 -247.224296) (xy 432.298088 -247.224654)
			(xy 432.305631 -247.232177) (xy 432.305968 -247.237504) (xy 432.305968 -247.238012) (xy 432.305968 -247.732296)
			(xy 438.350152 -247.732296) (xy 438.350152 -247.237758) (xy 438.350624 -247.232386) (xy 438.35824 -247.224801)
			(xy 438.363614 -247.224296) (xy 438.879742 -247.224296) (xy 438.88755 -247.223959) (xy 438.902422 -247.219189)
			(xy 438.908952 -247.214898) (xy 438.930041 -247.200549) (xy 438.975702 -247.177818) (xy 439.024308 -247.162359)
			(xy 439.074711 -247.154536) (xy 439.125717 -247.154536) (xy 439.17612 -247.162359) (xy 439.224726 -247.177818)
			(xy 439.270387 -247.200549) (xy 439.291476 -247.214898) (xy 439.298014 -247.219179) (xy 439.312879 -247.223968)
			(xy 439.320686 -247.224296) (xy 439.836814 -247.224296) (xy 439.842169 -247.224837) (xy 439.849752 -247.232404)
			(xy 439.850276 -247.237758) (xy 439.850276 -247.732296) (xy 445.89446 -247.732296) (xy 445.89446 -247.237758)
			(xy 445.894897 -247.232444) (xy 445.902362 -247.224874) (xy 445.907668 -247.224296) (xy 446.423796 -247.224296)
			(xy 446.431606 -247.223981) (xy 446.446477 -247.219196) (xy 446.453006 -247.214898) (xy 446.474095 -247.200549)
			(xy 446.519756 -247.177818) (xy 446.568362 -247.162359) (xy 446.618765 -247.154536) (xy 446.669771 -247.154536)
			(xy 446.720174 -247.162359) (xy 446.76878 -247.177818) (xy 446.814441 -247.200549) (xy 446.83553 -247.214898)
			(xy 446.842056 -247.219199) (xy 446.85693 -247.223976) (xy 446.86474 -247.224296) (xy 447.380868 -247.224296)
			(xy 447.386197 -247.224649) (xy 447.39374 -247.232176) (xy 447.394076 -247.237504) (xy 447.394076 -247.238012)
			(xy 447.394076 -247.732296) (xy 453.43826 -247.732296) (xy 453.43826 -247.237758) (xy 453.438697 -247.232444)
			(xy 453.446162 -247.224874) (xy 453.451468 -247.224296) (xy 453.967596 -247.224296) (xy 453.975406 -247.223981)
			(xy 453.990277 -247.219196) (xy 453.996806 -247.214898) (xy 454.017895 -247.200549) (xy 454.063556 -247.177818)
			(xy 454.112162 -247.162359) (xy 454.162565 -247.154536) (xy 454.213571 -247.154536) (xy 454.263974 -247.162359)
			(xy 454.31258 -247.177818) (xy 454.358241 -247.200549) (xy 454.37933 -247.214898) (xy 454.385856 -247.219199)
			(xy 454.40073 -247.223976) (xy 454.40854 -247.224296) (xy 454.924668 -247.224296) (xy 454.929997 -247.224649)
			(xy 454.93754 -247.232176) (xy 454.937876 -247.237504) (xy 454.937876 -247.238012) (xy 454.937876 -247.732296)
			(xy 454.937567 -247.737635) (xy 454.930008 -247.745178) (xy 454.924668 -247.745504) (xy 454.408794 -247.745504)
			(xy 454.400921 -247.745804) (xy 454.385917 -247.75058) (xy 454.37933 -247.754902) (xy 454.358259 -247.769303)
			(xy 454.312612 -247.792131) (xy 454.264004 -247.807686) (xy 454.213585 -247.815601) (xy 454.188068 -247.816116)
			(xy 454.162549 -247.815606) (xy 454.112123 -247.807717) (xy 454.063511 -247.792163) (xy 454.017872 -247.769314)
			(xy 453.996806 -247.754902) (xy 453.990215 -247.750587) (xy 453.975215 -247.7458) (xy 453.967342 -247.745504)
			(xy 453.451468 -247.745504) (xy 453.4462 -247.745026) (xy 453.438759 -247.737565) (xy 453.43826 -247.732296)
			(xy 447.394076 -247.732296) (xy 447.393767 -247.737635) (xy 447.386208 -247.745178) (xy 447.380868 -247.745504)
			(xy 446.864994 -247.745504) (xy 446.857121 -247.745804) (xy 446.842117 -247.75058) (xy 446.83553 -247.754902)
			(xy 446.814459 -247.769303) (xy 446.768812 -247.792131) (xy 446.720204 -247.807686) (xy 446.669785 -247.815601)
			(xy 446.644268 -247.816116) (xy 446.618749 -247.815606) (xy 446.568323 -247.807717) (xy 446.519711 -247.792163)
			(xy 446.474072 -247.769314) (xy 446.453006 -247.754902) (xy 446.446415 -247.750587) (xy 446.431415 -247.7458)
			(xy 446.423542 -247.745504) (xy 445.907668 -247.745504) (xy 445.9024 -247.745026) (xy 445.894959 -247.737565)
			(xy 445.89446 -247.732296) (xy 439.850276 -247.732296) (xy 439.849967 -247.737635) (xy 439.842408 -247.745178)
			(xy 439.837068 -247.745504) (xy 439.83656 -247.745504) (xy 439.32094 -247.745504) (xy 439.313065 -247.745781)
			(xy 439.298061 -247.750573) (xy 439.291476 -247.754902) (xy 439.270392 -247.769283) (xy 439.22475 -247.792115)
			(xy 439.176146 -247.807676) (xy 439.12573 -247.815598) (xy 439.100214 -247.816116) (xy 439.074694 -247.815633)
			(xy 439.024266 -247.807736) (xy 438.975655 -247.792174) (xy 438.930017 -247.769318) (xy 438.908952 -247.754902)
			(xy 438.902373 -247.750566) (xy 438.887363 -247.745792) (xy 438.879488 -247.745504) (xy 438.363614 -247.745504)
			(xy 438.358322 -247.744973) (xy 438.350752 -247.737576) (xy 438.350152 -247.732296) (xy 432.305968 -247.732296)
			(xy 432.305666 -247.737637) (xy 432.298102 -247.745181) (xy 432.29276 -247.745504) (xy 431.776886 -247.745504)
			(xy 431.769012 -247.745801) (xy 431.754009 -247.750579) (xy 431.747422 -247.754902) (xy 431.726353 -247.769307)
			(xy 431.680706 -247.792133) (xy 431.632097 -247.807688) (xy 431.581678 -247.815602) (xy 431.55616 -247.816116)
			(xy 431.53064 -247.81561) (xy 431.480214 -247.80772) (xy 431.431603 -247.792165) (xy 431.385964 -247.769315)
			(xy 431.364898 -247.754902) (xy 431.358309 -247.750584) (xy 431.343307 -247.745799) (xy 431.335434 -247.745504)
			(xy 430.81956 -247.745504) (xy 430.814291 -247.745032) (xy 430.806851 -247.737566) (xy 430.806352 -247.732296)
			(xy 424.762168 -247.732296) (xy 424.761866 -247.737637) (xy 424.754302 -247.745181) (xy 424.74896 -247.745504)
			(xy 424.748452 -247.745504) (xy 424.232832 -247.745504) (xy 424.224956 -247.745778) (xy 424.209953 -247.750572)
			(xy 424.203368 -247.754902) (xy 424.182286 -247.769287) (xy 424.136643 -247.792118) (xy 424.088039 -247.807678)
			(xy 424.037622 -247.815598) (xy 424.012106 -247.816116) (xy 423.986585 -247.815637) (xy 423.936158 -247.807739)
			(xy 423.887547 -247.792176) (xy 423.841909 -247.769318) (xy 423.820844 -247.754902) (xy 423.814267 -247.750563)
			(xy 423.799256 -247.745791) (xy 423.79138 -247.745504) (xy 423.275506 -247.745504) (xy 423.270213 -247.744978)
			(xy 423.262644 -247.737577) (xy 423.262044 -247.732296) (xy 417.21786 -247.732296) (xy 417.217566 -247.737639)
			(xy 417.209996 -247.745183) (xy 417.204652 -247.745504) (xy 415.731452 -247.745504) (xy 415.726182 -247.745037)
			(xy 415.718743 -247.737567) (xy 415.718244 -247.732296) (xy 374.119928 -247.732296) (xy 374.116429 -247.774528)
			(xy 374.104033 -247.823483) (xy 374.083749 -247.869731) (xy 374.056131 -247.91201) (xy 374.021931 -247.949166)
			(xy 373.982082 -247.980188) (xy 373.937671 -248.004228) (xy 373.889908 -248.020632) (xy 373.840098 -248.028951)
			(xy 373.814848 -248.029476) (xy 372.874794 -248.029476) (xy 372.849536 -248.029018) (xy 372.79971 -248.020702)
			(xy 372.751932 -248.004299) (xy 372.707506 -247.980256) (xy 372.667642 -247.949229) (xy 372.63343 -247.912063)
			(xy 372.605801 -247.869773) (xy 372.585509 -247.823512) (xy 372.573108 -247.774543) (xy 372.568937 -247.7242)
			(xy 371.300699 -247.7242) (xy 371.296529 -247.774529) (xy 371.284133 -247.823485) (xy 371.263848 -247.869733)
			(xy 371.236229 -247.912012) (xy 371.202028 -247.949169) (xy 371.162177 -247.980191) (xy 371.117765 -248.004231)
			(xy 371.070002 -248.020633) (xy 371.020191 -248.028951) (xy 370.99494 -248.029476) (xy 370.054886 -248.029476)
			(xy 370.029629 -248.029017) (xy 369.979804 -248.020701) (xy 369.932027 -248.004297) (xy 369.887601 -247.980253)
			(xy 369.847739 -247.949226) (xy 369.813527 -247.91206) (xy 369.785899 -247.869771) (xy 369.765609 -247.823511)
			(xy 369.753208 -247.774542) (xy 369.749037 -247.7242) (xy 368.480628 -247.7242) (xy 368.476457 -247.77454)
			(xy 368.464056 -247.823507) (xy 368.443764 -247.869764) (xy 368.416136 -247.912051) (xy 368.381923 -247.949213)
			(xy 368.34206 -247.980237) (xy 368.297635 -248.004276) (xy 368.249858 -248.020674) (xy 368.200034 -248.028985)
			(xy 368.174778 -248.029476) (xy 367.234724 -248.029476) (xy 367.209462 -248.029049) (xy 367.159628 -248.020737)
			(xy 367.111841 -248.004335) (xy 367.067406 -247.980291) (xy 367.027534 -247.949261) (xy 366.993314 -247.912091)
			(xy 366.96568 -247.869795) (xy 366.945384 -247.823528) (xy 366.93298 -247.774551) (xy 366.928808 -247.7242)
			(xy 365.660728 -247.7242) (xy 365.656556 -247.774541) (xy 365.644155 -247.823508) (xy 365.623863 -247.869766)
			(xy 365.596233 -247.912053) (xy 365.56202 -247.949216) (xy 365.522156 -247.980239) (xy 365.477729 -248.004278)
			(xy 365.429952 -248.020676) (xy 365.380127 -248.028986) (xy 365.35487 -248.029476) (xy 364.414816 -248.029476)
			(xy 364.389555 -248.029048) (xy 364.339721 -248.020735) (xy 364.291935 -248.004332) (xy 364.247501 -247.980288)
			(xy 364.207631 -247.949258) (xy 364.173412 -247.912088) (xy 364.145778 -247.869793) (xy 364.125483 -247.823526)
			(xy 364.11308 -247.77455) (xy 364.108908 -247.7242) (xy 308.118256 -247.7242) (xy 308.118256 -247.732296)
			(xy 308.117708 -247.737547) (xy 308.110297 -247.744987) (xy 308.105048 -247.745504) (xy 308.10454 -247.745504)
			(xy 306.631594 -247.745504) (xy 306.626299 -247.744986) (xy 306.618731 -247.737579) (xy 306.618132 -247.732296)
			(xy 300.573948 -247.732296) (xy 300.573407 -247.737549) (xy 300.565991 -247.744989) (xy 300.56074 -247.745504)
			(xy 300.044866 -247.745504) (xy 300.036992 -247.745792) (xy 300.021988 -247.750576) (xy 300.015402 -247.754902)
			(xy 299.994311 -247.769272) (xy 299.948671 -247.792107) (xy 299.900069 -247.807671) (xy 299.849656 -247.815596)
			(xy 299.82414 -247.816116) (xy 299.79862 -247.81562) (xy 299.748194 -247.807727) (xy 299.699582 -247.792169)
			(xy 299.653943 -247.769316) (xy 299.632878 -247.754902) (xy 299.626293 -247.750576) (xy 299.611288 -247.745796)
			(xy 299.603414 -247.745504) (xy 299.08754 -247.745504) (xy 299.082212 -247.745146) (xy 299.074669 -247.737623)
			(xy 299.074332 -247.732296) (xy 293.030148 -247.732296) (xy 293.029607 -247.737549) (xy 293.022191 -247.744989)
			(xy 293.01694 -247.745504) (xy 293.016432 -247.745504) (xy 292.500812 -247.745504) (xy 292.492939 -247.745812)
			(xy 292.477936 -247.750582) (xy 292.471348 -247.754902) (xy 292.450272 -247.769296) (xy 292.404627 -247.792125)
			(xy 292.35602 -247.807682) (xy 292.305603 -247.8156) (xy 292.280086 -247.816116) (xy 292.254567 -247.815597)
			(xy 292.204141 -247.807711) (xy 292.15553 -247.79216) (xy 292.10989 -247.769313) (xy 292.088824 -247.754902)
			(xy 292.082229 -247.750594) (xy 292.067232 -247.745803) (xy 292.05936 -247.745504) (xy 291.543486 -247.745504)
			(xy 291.53819 -247.744992) (xy 291.530622 -247.73758) (xy 291.530024 -247.732296) (xy 285.48584 -247.732296)
			(xy 285.485306 -247.737551) (xy 285.477885 -247.744992) (xy 285.472632 -247.745504) (xy 284.956758 -247.745504)
			(xy 284.948883 -247.745789) (xy 284.93388 -247.750575) (xy 284.927294 -247.754902) (xy 284.906205 -247.769276)
			(xy 284.860565 -247.792109) (xy 284.811962 -247.807673) (xy 284.761548 -247.815596) (xy 284.736032 -247.816116)
			(xy 284.710512 -247.815624) (xy 284.660085 -247.80773) (xy 284.611474 -247.792171) (xy 284.565835 -247.769317)
			(xy 284.54477 -247.754902) (xy 284.538187 -247.750573) (xy 284.52318 -247.745795) (xy 284.515306 -247.745504)
			(xy 283.999432 -247.745504) (xy 283.994103 -247.745151) (xy 283.98656 -247.737624) (xy 283.986224 -247.732296)
			(xy 277.94204 -247.732296) (xy 277.941506 -247.737551) (xy 277.934085 -247.744992) (xy 277.928832 -247.745504)
			(xy 277.412958 -247.745504) (xy 277.405083 -247.745789) (xy 277.39008 -247.750575) (xy 277.383494 -247.754902)
			(xy 277.362405 -247.769276) (xy 277.316765 -247.792109) (xy 277.268162 -247.807673) (xy 277.217748 -247.815596)
			(xy 277.192232 -247.816116) (xy 277.166712 -247.815624) (xy 277.116285 -247.80773) (xy 277.067674 -247.792171)
			(xy 277.022035 -247.769317) (xy 277.00097 -247.754902) (xy 276.994387 -247.750573) (xy 276.97938 -247.745795)
			(xy 276.971506 -247.745504) (xy 276.455632 -247.745504) (xy 276.450303 -247.745151) (xy 276.44276 -247.737624)
			(xy 276.442424 -247.732296) (xy 270.39824 -247.732296) (xy 270.397706 -247.737551) (xy 270.390285 -247.744992)
			(xy 270.385032 -247.745504) (xy 270.384524 -247.745504) (xy 269.868904 -247.745504) (xy 269.861031 -247.745809)
			(xy 269.846027 -247.750581) (xy 269.83944 -247.754902) (xy 269.818366 -247.769299) (xy 269.77272 -247.792127)
			(xy 269.724113 -247.807684) (xy 269.673695 -247.815601) (xy 269.648178 -247.816116) (xy 269.622659 -247.815601)
			(xy 269.572233 -247.807714) (xy 269.523621 -247.792161) (xy 269.477982 -247.769314) (xy 269.456916 -247.754902)
			(xy 269.450323 -247.75059) (xy 269.435324 -247.745801) (xy 269.427452 -247.745504) (xy 268.911578 -247.745504)
			(xy 268.906281 -247.744997) (xy 268.898714 -247.737582) (xy 268.898116 -247.732296) (xy 206.997808 -247.732296)
			(xy 206.997808 -247.73255) (xy 206.997249 -247.737837) (xy 206.989873 -247.745408) (xy 206.9846 -247.746012)
			(xy 206.468726 -247.746012) (xy 206.460917 -247.746335) (xy 206.446045 -247.751114) (xy 206.439516 -247.75541)
			(xy 206.418384 -247.769744) (xy 206.372664 -247.792475) (xy 206.323994 -247.80791) (xy 206.27353 -247.815681)
			(xy 206.248 -247.816116) (xy 206.22247 -247.81567) (xy 206.172007 -247.807896) (xy 206.123335 -247.792469)
			(xy 206.077607 -247.769756) (xy 206.056484 -247.75541) (xy 206.049955 -247.751115) (xy 206.035083 -247.746334)
			(xy 206.027274 -247.746012) (xy 205.5114 -247.746012) (xy 205.506138 -247.745506) (xy 205.498696 -247.738066)
			(xy 205.498192 -247.732804) (xy 199.453981 -247.732804) (xy 199.453449 -247.737837) (xy 199.446073 -247.745408)
			(xy 199.4408 -247.746012) (xy 198.924926 -247.746012) (xy 198.917117 -247.746335) (xy 198.902245 -247.751114)
			(xy 198.895716 -247.75541) (xy 198.874584 -247.769744) (xy 198.828864 -247.792475) (xy 198.780194 -247.80791)
			(xy 198.72973 -247.815681) (xy 198.7042 -247.816116) (xy 198.67867 -247.81567) (xy 198.628207 -247.807896)
			(xy 198.579535 -247.792469) (xy 198.533807 -247.769756) (xy 198.512684 -247.75541) (xy 198.506155 -247.751115)
			(xy 198.491283 -247.746334) (xy 198.483474 -247.746012) (xy 197.9676 -247.746012) (xy 197.962338 -247.745506)
			(xy 197.954896 -247.738066) (xy 197.954392 -247.732804) (xy 191.910183 -247.732804) (xy 191.909687 -247.737909)
			(xy 191.902105 -247.745489) (xy 191.896746 -247.746012) (xy 191.380872 -247.746012) (xy 191.373061 -247.746312)
			(xy 191.358189 -247.751107) (xy 191.351662 -247.75541) (xy 191.330545 -247.769767) (xy 191.28482 -247.792493)
			(xy 191.236145 -247.807921) (xy 191.185677 -247.815685) (xy 191.160146 -247.816116) (xy 191.134617 -247.815647)
			(xy 191.084155 -247.807879) (xy 191.035483 -247.79246) (xy 190.989754 -247.769753) (xy 190.96863 -247.75541)
			(xy 190.962091 -247.751132) (xy 190.947227 -247.746341) (xy 190.93942 -247.746012) (xy 190.423546 -247.746012)
			(xy 190.418199 -247.745424) (xy 190.410614 -247.737893) (xy 190.410084 -247.73255) (xy 184.3659 -247.73255)
			(xy 184.365348 -247.737839) (xy 184.357967 -247.74541) (xy 184.352692 -247.746012) (xy 183.836818 -247.746012)
			(xy 183.829008 -247.746331) (xy 183.814137 -247.751113) (xy 183.807608 -247.75541) (xy 183.786478 -247.769747)
			(xy 183.740758 -247.792478) (xy 183.692087 -247.807911) (xy 183.641622 -247.815681) (xy 183.616092 -247.816116)
			(xy 183.590562 -247.815674) (xy 183.540099 -247.807898) (xy 183.491427 -247.79247) (xy 183.445699 -247.769756)
			(xy 183.424576 -247.75541) (xy 183.418049 -247.751112) (xy 183.403175 -247.746333) (xy 183.395366 -247.746012)
			(xy 182.879492 -247.746012) (xy 182.874229 -247.745511) (xy 182.866787 -247.738067) (xy 182.866284 -247.732804)
			(xy 176.822076 -247.732804) (xy 176.821586 -247.737911) (xy 176.813999 -247.745491) (xy 176.808638 -247.746012)
			(xy 176.292764 -247.746012) (xy 176.284956 -247.746351) (xy 176.270085 -247.75112) (xy 176.263554 -247.75541)
			(xy 176.242439 -247.76977) (xy 176.196714 -247.792496) (xy 176.148038 -247.807923) (xy 176.09757 -247.815685)
			(xy 176.072038 -247.816116) (xy 176.046509 -247.815651) (xy 175.996047 -247.807882) (xy 175.947374 -247.792461)
			(xy 175.901645 -247.769753) (xy 175.880522 -247.75541) (xy 175.873984 -247.751129) (xy 175.859119 -247.74634)
			(xy 175.851312 -247.746012) (xy 175.335438 -247.746012) (xy 175.33009 -247.745429) (xy 175.322506 -247.737894)
			(xy 175.321976 -247.73255) (xy 169.277792 -247.73255) (xy 169.277247 -247.737841) (xy 169.269861 -247.745413)
			(xy 169.264584 -247.746012) (xy 167.791384 -247.746012) (xy 167.78612 -247.745517) (xy 167.778679 -247.738068)
			(xy 167.778176 -247.732804) (xy 107.386541 -247.732804) (xy 107.383061 -247.774792) (xy 107.370647 -247.823809)
			(xy 107.350334 -247.870114) (xy 107.322676 -247.912444) (xy 107.288427 -247.949644) (xy 107.248523 -247.980699)
			(xy 107.204051 -248.004762) (xy 107.156224 -248.021176) (xy 107.106348 -248.029494) (xy 107.081066 -248.029984)
			(xy 106.141012 -248.029984) (xy 106.115734 -248.029448) (xy 106.065869 -248.021129) (xy 106.018052 -248.004715)
			(xy 105.97359 -247.980655) (xy 105.933694 -247.949604) (xy 105.899453 -247.91241) (xy 105.871801 -247.870087)
			(xy 105.851493 -247.82379) (xy 105.839082 -247.774782) (xy 105.834907 -247.7244) (xy 104.567337 -247.7244)
			(xy 104.56316 -247.774793) (xy 104.550746 -247.823811) (xy 104.530433 -247.870117) (xy 104.502774 -247.912447)
			(xy 104.468524 -247.949647) (xy 104.428619 -247.980702) (xy 104.384145 -248.004764) (xy 104.336318 -248.021178)
			(xy 104.286441 -248.029494) (xy 104.261158 -248.029984) (xy 103.321104 -248.029984) (xy 103.295827 -248.029447)
			(xy 103.245962 -248.021127) (xy 103.198147 -248.004713) (xy 103.153685 -247.980652) (xy 103.113791 -247.949601)
			(xy 103.079551 -247.912407) (xy 103.0519 -247.870085) (xy 103.031593 -247.823789) (xy 103.019182 -247.774782)
			(xy 103.015007 -247.7244) (xy 101.747137 -247.7244) (xy 101.742961 -247.774789) (xy 101.730549 -247.823803)
			(xy 101.710238 -247.870106) (xy 101.682584 -247.912434) (xy 101.648339 -247.949633) (xy 101.608439 -247.980689)
			(xy 101.563971 -248.004753) (xy 101.516149 -248.02117) (xy 101.466277 -248.029491) (xy 101.440996 -248.029984)
			(xy 100.500942 -248.029984) (xy 100.475663 -248.02945) (xy 100.425793 -248.021135) (xy 100.377972 -248.004724)
			(xy 100.333506 -247.980665) (xy 100.293605 -247.949615) (xy 100.259361 -247.91242) (xy 100.231706 -247.870096)
			(xy 100.211395 -247.823796) (xy 100.198983 -247.774786) (xy 100.194807 -247.7244) (xy 98.927237 -247.7244)
			(xy 98.923061 -247.77479) (xy 98.910648 -247.823805) (xy 98.890337 -247.870108) (xy 98.862682 -247.912437)
			(xy 98.828436 -247.949636) (xy 98.788534 -247.980691) (xy 98.744066 -248.004755) (xy 98.696242 -248.021171)
			(xy 98.646369 -248.029492) (xy 98.621088 -248.029984) (xy 97.681034 -248.029984) (xy 97.655755 -248.02945)
			(xy 97.605887 -248.021133) (xy 97.558067 -248.004721) (xy 97.513601 -247.980662) (xy 97.473702 -247.949612)
			(xy 97.439459 -247.912417) (xy 97.411805 -247.870093) (xy 97.391495 -247.823795) (xy 97.379083 -247.774785)
			(xy 97.374907 -247.7244) (xy 60.178188 -247.7244) (xy 60.178188 -247.73255) (xy 60.177685 -247.737914)
			(xy 60.170091 -247.745495) (xy 60.164726 -247.746012) (xy 58.691526 -247.746012) (xy 58.686177 -247.745437)
			(xy 58.678593 -247.737896) (xy 58.678064 -247.73255) (xy 52.63388 -247.73255) (xy 52.633346 -247.737844)
			(xy 52.625953 -247.745416) (xy 52.620672 -247.746012) (xy 52.104798 -247.746012) (xy 52.096988 -247.746323)
			(xy 52.082116 -247.751111) (xy 52.075588 -247.75541) (xy 52.054464 -247.769756) (xy 52.008741 -247.792484)
			(xy 51.960069 -247.807916) (xy 51.909603 -247.815683) (xy 51.884072 -247.816116) (xy 51.858542 -247.815684)
			(xy 51.808078 -247.807905) (xy 51.759406 -247.792475) (xy 51.713678 -247.769757) (xy 51.692556 -247.75541)
			(xy 51.686033 -247.751104) (xy 51.671156 -247.74633) (xy 51.663346 -247.746012) (xy 51.147472 -247.746012)
			(xy 51.142207 -247.745524) (xy 51.134766 -247.73807) (xy 51.134264 -247.732804) (xy 45.090057 -247.732804)
			(xy 45.089584 -247.737916) (xy 45.081985 -247.745497) (xy 45.076618 -247.746012) (xy 44.560744 -247.746012)
			(xy 44.552935 -247.746342) (xy 44.538064 -247.751117) (xy 44.531534 -247.75541) (xy 44.510425 -247.769779)
			(xy 44.464697 -247.792502) (xy 44.41602 -247.807927) (xy 44.36555 -247.815687) (xy 44.340018 -247.816116)
			(xy 44.314489 -247.815661) (xy 44.264026 -247.807889) (xy 44.215354 -247.792465) (xy 44.169625 -247.769754)
			(xy 44.148502 -247.75541) (xy 44.141969 -247.751122) (xy 44.1271 -247.746337) (xy 44.119292 -247.746012)
			(xy 43.603418 -247.746012) (xy 43.598068 -247.745443) (xy 43.590484 -247.737897) (xy 43.589956 -247.73255)
			(xy 37.545772 -247.73255) (xy 37.545245 -247.737845) (xy 37.537847 -247.745418) (xy 37.532564 -247.746012)
			(xy 37.01669 -247.746012) (xy 37.008879 -247.746319) (xy 36.994008 -247.75111) (xy 36.98748 -247.75541)
			(xy 36.966358 -247.769759) (xy 36.920635 -247.792487) (xy 36.871962 -247.807917) (xy 36.821495 -247.815684)
			(xy 36.795964 -247.816116) (xy 36.770434 -247.815688) (xy 36.71997 -247.807908) (xy 36.671298 -247.792476)
			(xy 36.62557 -247.769758) (xy 36.604448 -247.75541) (xy 36.597927 -247.751101) (xy 36.583049 -247.746329)
			(xy 36.575238 -247.746012) (xy 36.059364 -247.746012) (xy 36.054098 -247.745529) (xy 36.046658 -247.738071)
			(xy 36.046156 -247.732804) (xy 30.001947 -247.732804) (xy 30.001445 -247.737845) (xy 29.994047 -247.745418)
			(xy 29.988764 -247.746012) (xy 29.47289 -247.746012) (xy 29.465079 -247.746319) (xy 29.450208 -247.75111)
			(xy 29.44368 -247.75541) (xy 29.422558 -247.769759) (xy 29.376835 -247.792487) (xy 29.328162 -247.807917)
			(xy 29.277695 -247.815684) (xy 29.252164 -247.816116) (xy 29.226634 -247.815688) (xy 29.17617 -247.807908)
			(xy 29.127498 -247.792476) (xy 29.08177 -247.769758) (xy 29.060648 -247.75541) (xy 29.054127 -247.751101)
			(xy 29.039249 -247.746329) (xy 29.031438 -247.746012) (xy 28.515564 -247.746012) (xy 28.510298 -247.745529)
			(xy 28.502858 -247.738071) (xy 28.502356 -247.732804) (xy 22.458149 -247.732804) (xy 22.457684 -247.737918)
			(xy 22.450079 -247.7455) (xy 22.44471 -247.746012) (xy 21.928836 -247.746012) (xy 21.921027 -247.746339)
			(xy 21.906155 -247.751115) (xy 21.899626 -247.75541) (xy 21.878491 -247.769739) (xy 21.832773 -247.792472)
			(xy 21.784103 -247.807908) (xy 21.73364 -247.81568) (xy 21.70811 -247.816116) (xy 21.68258 -247.815665)
			(xy 21.632118 -247.807892) (xy 21.583445 -247.792467) (xy 21.537717 -247.769755) (xy 21.516594 -247.75541)
			(xy 21.510063 -247.751119) (xy 21.495193 -247.746335) (xy 21.487384 -247.746012) (xy 20.97151 -247.746012)
			(xy 20.966159 -247.745448) (xy 20.958576 -247.737898) (xy 20.958048 -247.73255) (xy 2.509012 -247.73255)
			(xy 2.509012 -248.582434) (xy 16.85798 -248.582434) (xy 16.85798 -248.087896) (xy 16.858491 -248.082636)
			(xy 16.865928 -248.075194) (xy 16.871188 -248.074688) (xy 16.871696 -248.074688) (xy 17.38757 -248.074688)
			(xy 17.395379 -248.074364) (xy 17.410251 -248.069585) (xy 17.41678 -248.06529) (xy 17.437869 -248.050941)
			(xy 17.48353 -248.02821) (xy 17.532136 -248.012751) (xy 17.582539 -248.004928) (xy 17.633545 -248.004928)
			(xy 17.683948 -248.012751) (xy 17.732554 -248.02821) (xy 17.778215 -248.050941) (xy 17.799304 -248.06529)
			(xy 17.805836 -248.069581) (xy 17.820706 -248.074364) (xy 17.828514 -248.074688) (xy 18.344642 -248.074688)
			(xy 18.349963 -248.075101) (xy 18.357534 -248.082582) (xy 18.358104 -248.087896) (xy 18.358104 -248.582434)
			(xy 18.358079 -248.582688) (xy 24.402288 -248.582688) (xy 24.402288 -248.58218) (xy 24.402288 -248.087896)
			(xy 24.402791 -248.082634) (xy 24.410234 -248.075191) (xy 24.415496 -248.074688) (xy 24.931624 -248.074688)
			(xy 24.939435 -248.074387) (xy 24.954307 -248.069592) (xy 24.960834 -248.06529) (xy 24.981923 -248.050941)
			(xy 25.027584 -248.02821) (xy 25.07619 -248.012751) (xy 25.126593 -248.004928) (xy 25.177599 -248.004928)
			(xy 25.228002 -248.012751) (xy 25.276608 -248.02821) (xy 25.322269 -248.050941) (xy 25.343358 -248.06529)
			(xy 25.349878 -248.069601) (xy 25.364757 -248.074372) (xy 25.372568 -248.074688) (xy 25.888696 -248.074688)
			(xy 25.893957 -248.075197) (xy 25.9014 -248.082635) (xy 25.901904 -248.087896) (xy 25.901904 -248.582434)
			(xy 25.90188 -248.582688) (xy 31.946088 -248.582688) (xy 31.946088 -248.58218) (xy 31.946088 -248.087896)
			(xy 31.946591 -248.082634) (xy 31.954034 -248.075191) (xy 31.959296 -248.074688) (xy 32.475424 -248.074688)
			(xy 32.483235 -248.074387) (xy 32.498107 -248.069592) (xy 32.504634 -248.06529) (xy 32.525723 -248.050941)
			(xy 32.571384 -248.02821) (xy 32.61999 -248.012751) (xy 32.670393 -248.004928) (xy 32.721399 -248.004928)
			(xy 32.771802 -248.012751) (xy 32.820408 -248.02821) (xy 32.866069 -248.050941) (xy 32.887158 -248.06529)
			(xy 32.893678 -248.069601) (xy 32.908557 -248.074372) (xy 32.916368 -248.074688) (xy 33.432496 -248.074688)
			(xy 33.437757 -248.075197) (xy 33.4452 -248.082635) (xy 33.445704 -248.087896) (xy 33.445704 -248.582434)
			(xy 39.489888 -248.582434) (xy 39.489888 -248.087896) (xy 39.490391 -248.082634) (xy 39.497834 -248.075191)
			(xy 39.503096 -248.074688) (xy 39.503604 -248.074688) (xy 40.019478 -248.074688) (xy 40.027287 -248.074367)
			(xy 40.042159 -248.069586) (xy 40.048688 -248.06529) (xy 40.069777 -248.050941) (xy 40.115438 -248.02821)
			(xy 40.164044 -248.012751) (xy 40.214447 -248.004928) (xy 40.265453 -248.004928) (xy 40.315856 -248.012751)
			(xy 40.364462 -248.02821) (xy 40.410123 -248.050941) (xy 40.431212 -248.06529) (xy 40.437742 -248.069584)
			(xy 40.452613 -248.074365) (xy 40.460422 -248.074688) (xy 40.97655 -248.074688) (xy 40.981859 -248.075162)
			(xy 40.989436 -248.082597) (xy 40.990012 -248.087896) (xy 40.990012 -248.582434) (xy 40.989987 -248.582688)
			(xy 47.034196 -248.582688) (xy 47.034196 -248.58218) (xy 47.034196 -248.087896) (xy 47.034692 -248.082632)
			(xy 47.042139 -248.075189) (xy 47.047404 -248.074688) (xy 47.563532 -248.074688) (xy 47.57134 -248.074347)
			(xy 47.586211 -248.06958) (xy 47.592742 -248.06529) (xy 47.613831 -248.050941) (xy 47.659492 -248.02821)
			(xy 47.708098 -248.012751) (xy 47.758501 -248.004928) (xy 47.809507 -248.004928) (xy 47.85991 -248.012751)
			(xy 47.908516 -248.02821) (xy 47.954177 -248.050941) (xy 47.975266 -248.06529) (xy 47.981806 -248.069566)
			(xy 47.99667 -248.074359) (xy 48.004476 -248.074688) (xy 48.520604 -248.074688) (xy 48.525866 -248.075191)
			(xy 48.533309 -248.082634) (xy 48.533812 -248.087896) (xy 48.533812 -248.582434) (xy 54.577996 -248.582434)
			(xy 54.577996 -248.087896) (xy 54.578492 -248.082632) (xy 54.585939 -248.075189) (xy 54.591204 -248.074688)
			(xy 54.591712 -248.074688) (xy 56.064658 -248.074688) (xy 56.069968 -248.075157) (xy 56.077545 -248.082595)
			(xy 56.07812 -248.087896) (xy 56.07812 -248.5344) (xy 108.185168 -248.5344) (xy 108.189339 -248.48406)
			(xy 108.20174 -248.435093) (xy 108.222032 -248.388834) (xy 108.249661 -248.346547) (xy 108.283873 -248.309385)
			(xy 108.323736 -248.278361) (xy 108.368162 -248.254321) (xy 108.415939 -248.237922) (xy 108.465764 -248.229611)
			(xy 108.49102 -248.22912) (xy 109.431074 -248.22912) (xy 109.456335 -248.229555) (xy 109.50617 -248.237867)
			(xy 109.553956 -248.254268) (xy 109.598391 -248.278312) (xy 109.638262 -248.309342) (xy 109.672482 -248.346511)
			(xy 109.700117 -248.388806) (xy 109.720412 -248.435073) (xy 109.732816 -248.48405) (xy 109.736988 -248.5344)
			(xy 109.732987 -248.582688) (xy 163.678108 -248.582688) (xy 163.678108 -248.58218) (xy 163.678108 -248.087896)
			(xy 163.678426 -248.082559) (xy 163.685979 -248.075018) (xy 163.691316 -248.074688) (xy 165.164516 -248.074688)
			(xy 165.16978 -248.075183) (xy 165.177221 -248.082632) (xy 165.177724 -248.087896) (xy 165.177724 -248.582434)
			(xy 171.221908 -248.582434) (xy 171.221908 -248.087896) (xy 171.222226 -248.082559) (xy 171.229779 -248.075018)
			(xy 171.235116 -248.074688) (xy 171.235624 -248.074688) (xy 171.751498 -248.074688) (xy 171.759308 -248.074376)
			(xy 171.77418 -248.069589) (xy 171.780708 -248.06529) (xy 171.801797 -248.050941) (xy 171.847458 -248.02821)
			(xy 171.896064 -248.012751) (xy 171.946467 -248.004928) (xy 171.997473 -248.004928) (xy 172.047876 -248.012751)
			(xy 172.096482 -248.02821) (xy 172.142143 -248.050941) (xy 172.163232 -248.06529) (xy 172.169758 -248.069591)
			(xy 172.184632 -248.074368) (xy 172.192442 -248.074688) (xy 172.70857 -248.074688) (xy 172.713882 -248.075149)
			(xy 172.721457 -248.082593) (xy 172.722032 -248.087896) (xy 172.722032 -248.582434) (xy 172.72201 -248.582688)
			(xy 178.766216 -248.582688) (xy 178.766216 -248.58218) (xy 178.766216 -248.087896) (xy 178.766527 -248.082557)
			(xy 178.774085 -248.075015) (xy 178.779424 -248.074688) (xy 179.295552 -248.074688) (xy 179.30336 -248.074356)
			(xy 179.318232 -248.069583) (xy 179.324762 -248.06529) (xy 179.345851 -248.050941) (xy 179.391512 -248.02821)
			(xy 179.440118 -248.012751) (xy 179.490521 -248.004928) (xy 179.541527 -248.004928) (xy 179.59193 -248.012751)
			(xy 179.640536 -248.02821) (xy 179.686197 -248.050941) (xy 179.707286 -248.06529) (xy 179.713822 -248.069574)
			(xy 179.728689 -248.074362) (xy 179.736496 -248.074688) (xy 180.252624 -248.074688) (xy 180.257889 -248.075179)
			(xy 180.265329 -248.082631) (xy 180.265832 -248.087896) (xy 180.265832 -248.582434) (xy 186.310016 -248.582434)
			(xy 186.310016 -248.087896) (xy 186.310327 -248.082557) (xy 186.317885 -248.075015) (xy 186.323224 -248.074688)
			(xy 186.323732 -248.074688) (xy 186.839606 -248.074688) (xy 186.847417 -248.074379) (xy 186.862288 -248.06959)
			(xy 186.868816 -248.06529) (xy 186.889905 -248.050941) (xy 186.935566 -248.02821) (xy 186.984172 -248.012751)
			(xy 187.034575 -248.004928) (xy 187.085581 -248.004928) (xy 187.135984 -248.012751) (xy 187.18459 -248.02821)
			(xy 187.230251 -248.050941) (xy 187.25134 -248.06529) (xy 187.257864 -248.069594) (xy 187.27274 -248.07437)
			(xy 187.28055 -248.074688) (xy 187.796678 -248.074688) (xy 187.801991 -248.075144) (xy 187.809566 -248.082592)
			(xy 187.81014 -248.087896) (xy 187.81014 -248.582434) (xy 187.810118 -248.582688) (xy 193.854324 -248.582688)
			(xy 193.854324 -248.58218) (xy 193.854324 -248.087896) (xy 193.854627 -248.082555) (xy 193.862191 -248.075013)
			(xy 193.867532 -248.074688) (xy 194.38366 -248.074688) (xy 194.391469 -248.07436) (xy 194.40634 -248.069584)
			(xy 194.41287 -248.06529) (xy 194.433959 -248.050941) (xy 194.47962 -248.02821) (xy 194.528226 -248.012751)
			(xy 194.578629 -248.004928) (xy 194.629635 -248.004928) (xy 194.680038 -248.012751) (xy 194.728644 -248.02821)
			(xy 194.774305 -248.050941) (xy 194.795394 -248.06529) (xy 194.801928 -248.069577) (xy 194.816796 -248.074363)
			(xy 194.824604 -248.074688) (xy 195.340732 -248.074688) (xy 195.345998 -248.075173) (xy 195.353438 -248.082629)
			(xy 195.35394 -248.087896) (xy 195.35394 -248.582434) (xy 195.353919 -248.582688) (xy 201.398124 -248.582688)
			(xy 201.398124 -248.58218) (xy 201.398124 -248.087896) (xy 201.398427 -248.082555) (xy 201.405991 -248.075013)
			(xy 201.411332 -248.074688) (xy 201.92746 -248.074688) (xy 201.935269 -248.07436) (xy 201.95014 -248.069584)
			(xy 201.95667 -248.06529) (xy 201.977759 -248.050941) (xy 202.02342 -248.02821) (xy 202.072026 -248.012751)
			(xy 202.122429 -248.004928) (xy 202.173435 -248.004928) (xy 202.223838 -248.012751) (xy 202.272444 -248.02821)
			(xy 202.318105 -248.050941) (xy 202.339194 -248.06529) (xy 202.345728 -248.069577) (xy 202.360596 -248.074363)
			(xy 202.368404 -248.074688) (xy 202.884532 -248.074688) (xy 202.889798 -248.075173) (xy 202.897238 -248.082629)
			(xy 202.89774 -248.087896) (xy 202.89774 -248.58218) (xy 264.798048 -248.58218) (xy 264.798048 -248.087642)
			(xy 264.798409 -248.08221) (xy 264.806079 -248.074521) (xy 264.81151 -248.07418) (xy 265.327638 -248.07418)
			(xy 265.335446 -248.073843) (xy 265.350318 -248.069073) (xy 265.356848 -248.064782) (xy 265.377937 -248.050433)
			(xy 265.423598 -248.027702) (xy 265.472204 -248.012243) (xy 265.522607 -248.00442) (xy 265.573613 -248.00442)
			(xy 265.624016 -248.012243) (xy 265.672622 -248.027702) (xy 265.718283 -248.050433) (xy 265.739372 -248.064782)
			(xy 265.745912 -248.069059) (xy 265.760775 -248.073851) (xy 265.768582 -248.07418) (xy 266.28471 -248.07418)
			(xy 266.290156 -248.074477) (xy 266.297844 -248.082194) (xy 266.298172 -248.087642) (xy 266.298172 -248.58218)
			(xy 272.342356 -248.58218) (xy 272.342356 -248.087642) (xy 272.342853 -248.082339) (xy 272.350272 -248.074765)
			(xy 272.355564 -248.07418) (xy 272.871692 -248.07418) (xy 272.879502 -248.073866) (xy 272.894374 -248.069081)
			(xy 272.900902 -248.064782) (xy 272.921991 -248.050433) (xy 272.967652 -248.027702) (xy 273.016258 -248.012243)
			(xy 273.066661 -248.00442) (xy 273.117667 -248.00442) (xy 273.16807 -248.012243) (xy 273.216676 -248.027702)
			(xy 273.262337 -248.050433) (xy 273.283426 -248.064782) (xy 273.289954 -248.06908) (xy 273.304827 -248.073859)
			(xy 273.312636 -248.07418) (xy 273.828764 -248.07418) (xy 273.834089 -248.07455) (xy 273.841631 -248.082065)
			(xy 273.841972 -248.087388) (xy 273.841972 -248.087896) (xy 273.841972 -248.58218) (xy 279.886156 -248.58218)
			(xy 279.886156 -248.087642) (xy 279.886653 -248.082339) (xy 279.894072 -248.074765) (xy 279.899364 -248.07418)
			(xy 280.415492 -248.07418) (xy 280.423302 -248.073866) (xy 280.438174 -248.069081) (xy 280.444702 -248.064782)
			(xy 280.465791 -248.050433) (xy 280.511452 -248.027702) (xy 280.560058 -248.012243) (xy 280.610461 -248.00442)
			(xy 280.661467 -248.00442) (xy 280.71187 -248.012243) (xy 280.760476 -248.027702) (xy 280.806137 -248.050433)
			(xy 280.827226 -248.064782) (xy 280.833754 -248.06908) (xy 280.848627 -248.073859) (xy 280.856436 -248.07418)
			(xy 281.372564 -248.07418) (xy 281.377889 -248.07455) (xy 281.385431 -248.082065) (xy 281.385772 -248.087388)
			(xy 281.385772 -248.087896) (xy 281.385772 -248.58218) (xy 287.429956 -248.58218) (xy 287.429956 -248.087642)
			(xy 287.430309 -248.082208) (xy 287.437985 -248.074519) (xy 287.443418 -248.07418) (xy 287.959546 -248.07418)
			(xy 287.967354 -248.073847) (xy 287.982226 -248.069074) (xy 287.988756 -248.064782) (xy 288.009845 -248.050433)
			(xy 288.055506 -248.027702) (xy 288.104112 -248.012243) (xy 288.154515 -248.00442) (xy 288.205521 -248.00442)
			(xy 288.255924 -248.012243) (xy 288.30453 -248.027702) (xy 288.350191 -248.050433) (xy 288.37128 -248.064782)
			(xy 288.377818 -248.069062) (xy 288.392683 -248.073852) (xy 288.40049 -248.07418) (xy 288.916618 -248.07418)
			(xy 288.922066 -248.074471) (xy 288.929753 -248.082193) (xy 288.93008 -248.087642) (xy 288.93008 -248.58218)
			(xy 294.974264 -248.58218) (xy 294.974264 -248.087642) (xy 294.974754 -248.082337) (xy 294.982178 -248.074762)
			(xy 294.987472 -248.07418) (xy 295.5036 -248.07418) (xy 295.51141 -248.07387) (xy 295.526282 -248.069082)
			(xy 295.53281 -248.064782) (xy 295.553899 -248.050433) (xy 295.59956 -248.027702) (xy 295.648166 -248.012243)
			(xy 295.698569 -248.00442) (xy 295.749575 -248.00442) (xy 295.799978 -248.012243) (xy 295.848584 -248.027702)
			(xy 295.894245 -248.050433) (xy 295.915334 -248.064782) (xy 295.92186 -248.069083) (xy 295.936734 -248.07386)
			(xy 295.944544 -248.07418) (xy 296.460672 -248.07418) (xy 296.465998 -248.074544) (xy 296.47354 -248.082063)
			(xy 296.47388 -248.087388) (xy 296.47388 -248.087896) (xy 296.47388 -248.58218) (xy 302.518064 -248.58218)
			(xy 302.518064 -248.087642) (xy 302.51841 -248.082206) (xy 302.526091 -248.074517) (xy 302.531526 -248.07418)
			(xy 304.004726 -248.07418) (xy 304.010175 -248.074466) (xy 304.017862 -248.082192) (xy 304.018188 -248.087642)
			(xy 304.018188 -248.5342) (xy 361.758659 -248.5342) (xy 361.762835 -248.48381) (xy 361.775248 -248.434795)
			(xy 361.795559 -248.388491) (xy 361.823214 -248.346162) (xy 361.85746 -248.308962) (xy 361.897361 -248.277907)
			(xy 361.94183 -248.253842) (xy 361.989653 -248.237426) (xy 362.039527 -248.229104) (xy 362.064808 -248.228612)
			(xy 363.004862 -248.228612) (xy 363.030141 -248.229154) (xy 363.080009 -248.23747) (xy 363.127829 -248.253881)
			(xy 363.172294 -248.27794) (xy 363.212193 -248.30899) (xy 363.246437 -248.346184) (xy 363.274091 -248.388507)
			(xy 363.294401 -248.434806) (xy 363.306813 -248.483816) (xy 363.310989 -248.5342) (xy 363.307012 -248.58218)
			(xy 411.618176 -248.58218) (xy 411.618176 -248.087642) (xy 411.618655 -248.082334) (xy 411.626087 -248.074759)
			(xy 411.631384 -248.07418) (xy 413.104584 -248.07418) (xy 413.109911 -248.074536) (xy 413.117452 -248.082062)
			(xy 413.117792 -248.087388) (xy 413.117792 -248.087896) (xy 413.117792 -248.58218) (xy 419.161976 -248.58218)
			(xy 419.161976 -248.087642) (xy 419.162311 -248.082204) (xy 419.17 -248.074513) (xy 419.175438 -248.07418)
			(xy 419.691566 -248.07418) (xy 419.699375 -248.073855) (xy 419.714247 -248.069077) (xy 419.720776 -248.064782)
			(xy 419.741865 -248.050433) (xy 419.787526 -248.027702) (xy 419.836132 -248.012243) (xy 419.886535 -248.00442)
			(xy 419.937541 -248.00442) (xy 419.987944 -248.012243) (xy 420.03655 -248.027702) (xy 420.082211 -248.050433)
			(xy 420.1033 -248.064782) (xy 420.109833 -248.06907) (xy 420.124702 -248.073855) (xy 420.13251 -248.07418)
			(xy 420.648638 -248.07418) (xy 420.654088 -248.074458) (xy 420.661774 -248.08219) (xy 420.6621 -248.087642)
			(xy 420.6621 -248.58218) (xy 426.706284 -248.58218) (xy 426.706284 -248.087642) (xy 426.706756 -248.082333)
			(xy 426.714192 -248.074756) (xy 426.719492 -248.07418) (xy 427.23562 -248.07418) (xy 427.243431 -248.073878)
			(xy 427.258303 -248.069084) (xy 427.26483 -248.064782) (xy 427.285919 -248.050433) (xy 427.33158 -248.027702)
			(xy 427.380186 -248.012243) (xy 427.430589 -248.00442) (xy 427.481595 -248.00442) (xy 427.531998 -248.012243)
			(xy 427.580604 -248.027702) (xy 427.626265 -248.050433) (xy 427.647354 -248.064782) (xy 427.653875 -248.069091)
			(xy 427.668753 -248.073863) (xy 427.676564 -248.07418) (xy 428.192692 -248.07418) (xy 428.197951 -248.074699)
			(xy 428.205393 -248.08213) (xy 428.2059 -248.087388) (xy 428.2059 -248.087896) (xy 428.2059 -248.58218)
			(xy 434.250084 -248.58218) (xy 434.250084 -248.087642) (xy 434.250412 -248.082202) (xy 434.258106 -248.07451)
			(xy 434.263546 -248.07418) (xy 434.779674 -248.07418) (xy 434.787483 -248.073859) (xy 434.802355 -248.069078)
			(xy 434.808884 -248.064782) (xy 434.829973 -248.050433) (xy 434.875634 -248.027702) (xy 434.92424 -248.012243)
			(xy 434.974643 -248.00442) (xy 435.025649 -248.00442) (xy 435.076052 -248.012243) (xy 435.124658 -248.027702)
			(xy 435.170319 -248.050433) (xy 435.191408 -248.064782) (xy 435.19794 -248.069073) (xy 435.21281 -248.073856)
			(xy 435.220618 -248.07418) (xy 435.736746 -248.07418) (xy 435.742126 -248.074624) (xy 435.749711 -248.082259)
			(xy 435.750208 -248.087642) (xy 435.750208 -248.58218) (xy 441.794392 -248.58218) (xy 441.794392 -248.087642)
			(xy 441.794946 -248.082354) (xy 441.802326 -248.074783) (xy 441.8076 -248.07418) (xy 442.323728 -248.07418)
			(xy 442.33154 -248.073882) (xy 442.346411 -248.069085) (xy 442.352938 -248.064782) (xy 442.374027 -248.050433)
			(xy 442.419688 -248.027702) (xy 442.468294 -248.012243) (xy 442.518697 -248.00442) (xy 442.569703 -248.00442)
			(xy 442.620106 -248.012243) (xy 442.668712 -248.027702) (xy 442.714373 -248.050433) (xy 442.735462 -248.064782)
			(xy 442.742004 -248.069055) (xy 442.756866 -248.07385) (xy 442.764672 -248.07418) (xy 443.2808 -248.07418)
			(xy 443.28606 -248.074694) (xy 443.293502 -248.082129) (xy 443.294008 -248.087388) (xy 443.294008 -248.087896)
			(xy 443.294008 -248.58218) (xy 449.338192 -248.58218) (xy 449.338192 -248.087642) (xy 449.338746 -248.082354)
			(xy 449.346126 -248.074783) (xy 449.3514 -248.07418) (xy 449.867528 -248.07418) (xy 449.87534 -248.073882)
			(xy 449.890211 -248.069085) (xy 449.896738 -248.064782) (xy 449.917827 -248.050433) (xy 449.963488 -248.027702)
			(xy 450.012094 -248.012243) (xy 450.062497 -248.00442) (xy 450.113503 -248.00442) (xy 450.163906 -248.012243)
			(xy 450.212512 -248.027702) (xy 450.258173 -248.050433) (xy 450.279262 -248.064782) (xy 450.285804 -248.069055)
			(xy 450.300666 -248.07385) (xy 450.308472 -248.07418) (xy 450.8246 -248.07418) (xy 450.82986 -248.074694)
			(xy 450.837302 -248.082129) (xy 450.837808 -248.087388) (xy 450.837808 -248.087896) (xy 450.837808 -248.58218)
			(xy 450.83746 -248.58751) (xy 450.829929 -248.595052) (xy 450.8246 -248.595388) (xy 450.308726 -248.595388)
			(xy 450.300849 -248.595645) (xy 450.285845 -248.600449) (xy 450.279262 -248.604786) (xy 450.258189 -248.619183)
			(xy 450.212542 -248.642009) (xy 450.163935 -248.657565) (xy 450.113517 -248.665483) (xy 450.088 -248.666)
			(xy 450.062479 -248.665527) (xy 450.012052 -248.657628) (xy 449.96344 -248.642063) (xy 449.917802 -248.619203)
			(xy 449.896738 -248.604786) (xy 449.890141 -248.600482) (xy 449.875145 -248.595689) (xy 449.867274 -248.595388)
			(xy 449.3514 -248.595388) (xy 449.346063 -248.595071) (xy 449.338521 -248.587518) (xy 449.338192 -248.58218)
			(xy 443.294008 -248.58218) (xy 443.29366 -248.58751) (xy 443.286129 -248.595052) (xy 443.2808 -248.595388)
			(xy 442.764926 -248.595388) (xy 442.757049 -248.595645) (xy 442.742045 -248.600449) (xy 442.735462 -248.604786)
			(xy 442.714389 -248.619183) (xy 442.668742 -248.642009) (xy 442.620135 -248.657565) (xy 442.569717 -248.665483)
			(xy 442.5442 -248.666) (xy 442.518679 -248.665527) (xy 442.468252 -248.657628) (xy 442.41964 -248.642063)
			(xy 442.374002 -248.619203) (xy 442.352938 -248.604786) (xy 442.346341 -248.600482) (xy 442.331345 -248.595689)
			(xy 442.323474 -248.595388) (xy 441.8076 -248.595388) (xy 441.802263 -248.595071) (xy 441.794721 -248.587518)
			(xy 441.794392 -248.58218) (xy 435.750208 -248.58218) (xy 435.74986 -248.58751) (xy 435.742329 -248.595052)
			(xy 435.737 -248.595388) (xy 435.736492 -248.595388) (xy 435.220872 -248.595388) (xy 435.212996 -248.595665)
			(xy 435.197992 -248.600455) (xy 435.191408 -248.604786) (xy 435.17035 -248.619207) (xy 435.124698 -248.642027)
			(xy 435.076086 -248.657577) (xy 435.025664 -248.665487) (xy 435.000146 -248.666) (xy 434.974626 -248.665504)
			(xy 434.924199 -248.657612) (xy 434.875588 -248.642053) (xy 434.829949 -248.6192) (xy 434.808884 -248.604786)
			(xy 434.802299 -248.600461) (xy 434.787294 -248.595681) (xy 434.77942 -248.595388) (xy 434.263546 -248.595388)
			(xy 434.258254 -248.59485) (xy 434.250682 -248.587459) (xy 434.250084 -248.58218) (xy 428.2059 -248.58218)
			(xy 428.205559 -248.587512) (xy 428.198023 -248.595054) (xy 428.192692 -248.595388) (xy 427.676818 -248.595388)
			(xy 427.668944 -248.595684) (xy 427.65394 -248.600461) (xy 427.647354 -248.604786) (xy 427.626283 -248.619187)
			(xy 427.580635 -248.642012) (xy 427.532027 -248.657567) (xy 427.481609 -248.665484) (xy 427.456092 -248.666)
			(xy 427.430573 -248.665481) (xy 427.380147 -248.657596) (xy 427.331536 -248.642044) (xy 427.285896 -248.619197)
			(xy 427.26483 -248.604786) (xy 427.258234 -248.600478) (xy 427.243237 -248.595687) (xy 427.235366 -248.595388)
			(xy 426.719492 -248.595388) (xy 426.714154 -248.595077) (xy 426.706612 -248.587519) (xy 426.706284 -248.58218)
			(xy 420.6621 -248.58218) (xy 420.661759 -248.587512) (xy 420.654223 -248.595054) (xy 420.648892 -248.595388)
			(xy 420.648384 -248.595388) (xy 420.132764 -248.595388) (xy 420.124888 -248.595661) (xy 420.109884 -248.600454)
			(xy 420.1033 -248.604786) (xy 420.082216 -248.619167) (xy 420.036573 -248.641997) (xy 419.987969 -248.657557)
			(xy 419.937554 -248.66548) (xy 419.912038 -248.666) (xy 419.886518 -248.665508) (xy 419.836091 -248.657614)
			(xy 419.787479 -248.642055) (xy 419.741841 -248.619201) (xy 419.720776 -248.604786) (xy 419.714192 -248.600458)
			(xy 419.699186 -248.595679) (xy 419.691312 -248.595388) (xy 419.175438 -248.595388) (xy 419.170145 -248.594855)
			(xy 419.162573 -248.58746) (xy 419.161976 -248.58218) (xy 413.117792 -248.58218) (xy 413.117458 -248.587514)
			(xy 413.109917 -248.595057) (xy 413.104584 -248.595388) (xy 411.631384 -248.595388) (xy 411.626045 -248.595082)
			(xy 411.618503 -248.58752) (xy 411.618176 -248.58218) (xy 363.307012 -248.58218) (xy 363.306813 -248.584584)
			(xy 363.294401 -248.633594) (xy 363.274091 -248.679893) (xy 363.246437 -248.722216) (xy 363.212193 -248.75941)
			(xy 363.172294 -248.79046) (xy 363.127829 -248.814519) (xy 363.080009 -248.83093) (xy 363.030141 -248.839246)
			(xy 363.004862 -248.839736) (xy 362.064808 -248.839736) (xy 362.039527 -248.839296) (xy 361.989653 -248.830974)
			(xy 361.94183 -248.814558) (xy 361.897361 -248.790493) (xy 361.85746 -248.759438) (xy 361.823214 -248.722238)
			(xy 361.795559 -248.679909) (xy 361.775248 -248.633605) (xy 361.762835 -248.58459) (xy 361.758659 -248.5342)
			(xy 304.018188 -248.5342) (xy 304.018188 -248.58218) (xy 304.017858 -248.587515) (xy 304.010315 -248.595058)
			(xy 304.00498 -248.595388) (xy 304.004472 -248.595388) (xy 302.531526 -248.595388) (xy 302.526231 -248.594863)
			(xy 302.518661 -248.587462) (xy 302.518064 -248.58218) (xy 296.47388 -248.58218) (xy 296.473557 -248.587516)
			(xy 296.466009 -248.59506) (xy 296.460672 -248.595388) (xy 295.944798 -248.595388) (xy 295.936923 -248.595676)
			(xy 295.921919 -248.600459) (xy 295.915334 -248.604786) (xy 295.894268 -248.619196) (xy 295.848619 -248.642019)
			(xy 295.800009 -248.657571) (xy 295.74959 -248.665485) (xy 295.724072 -248.666) (xy 295.698553 -248.665491)
			(xy 295.648126 -248.657603) (xy 295.599515 -248.642048) (xy 295.553876 -248.619199) (xy 295.53281 -248.604786)
			(xy 295.526219 -248.600471) (xy 295.511218 -248.595684) (xy 295.503346 -248.595388) (xy 294.987472 -248.595388)
			(xy 294.982201 -248.594922) (xy 294.974759 -248.587453) (xy 294.974264 -248.58218) (xy 288.93008 -248.58218)
			(xy 288.929757 -248.587516) (xy 288.922209 -248.59506) (xy 288.916872 -248.595388) (xy 288.916364 -248.595388)
			(xy 288.400744 -248.595388) (xy 288.392867 -248.595653) (xy 288.377863 -248.600452) (xy 288.37128 -248.604786)
			(xy 288.350202 -248.619176) (xy 288.304557 -248.642003) (xy 288.255951 -248.657561) (xy 288.205535 -248.665482)
			(xy 288.180018 -248.666) (xy 288.154497 -248.665518) (xy 288.10407 -248.657621) (xy 288.055459 -248.642059)
			(xy 288.009821 -248.619202) (xy 287.988756 -248.604786) (xy 287.982177 -248.60045) (xy 287.967167 -248.595676)
			(xy 287.959292 -248.595388) (xy 287.443418 -248.595388) (xy 287.438122 -248.594868) (xy 287.430552 -248.587464)
			(xy 287.429956 -248.58218) (xy 281.385772 -248.58218) (xy 281.385456 -248.587518) (xy 281.377903 -248.595063)
			(xy 281.372564 -248.595388) (xy 280.85669 -248.595388) (xy 280.848815 -248.595673) (xy 280.833811 -248.600458)
			(xy 280.827226 -248.604786) (xy 280.806163 -248.619199) (xy 280.760512 -248.642021) (xy 280.711902 -248.657573)
			(xy 280.661482 -248.665486) (xy 280.635964 -248.666) (xy 280.610444 -248.665495) (xy 280.560018 -248.657605)
			(xy 280.511406 -248.64205) (xy 280.465767 -248.619199) (xy 280.444702 -248.604786) (xy 280.438113 -248.600468)
			(xy 280.423111 -248.595683) (xy 280.415238 -248.595388) (xy 279.899364 -248.595388) (xy 279.894092 -248.594927)
			(xy 279.886651 -248.587454) (xy 279.886156 -248.58218) (xy 273.841972 -248.58218) (xy 273.841656 -248.587518)
			(xy 273.834103 -248.595063) (xy 273.828764 -248.595388) (xy 273.31289 -248.595388) (xy 273.305015 -248.595673)
			(xy 273.290011 -248.600458) (xy 273.283426 -248.604786) (xy 273.262363 -248.619199) (xy 273.216712 -248.642021)
			(xy 273.168102 -248.657573) (xy 273.117682 -248.665486) (xy 273.092164 -248.666) (xy 273.066644 -248.665495)
			(xy 273.016218 -248.657605) (xy 272.967606 -248.64205) (xy 272.921967 -248.619199) (xy 272.900902 -248.604786)
			(xy 272.894313 -248.600468) (xy 272.879311 -248.595683) (xy 272.871438 -248.595388) (xy 272.355564 -248.595388)
			(xy 272.350292 -248.594927) (xy 272.342851 -248.587454) (xy 272.342356 -248.58218) (xy 266.298172 -248.58218)
			(xy 266.297856 -248.587518) (xy 266.290303 -248.595063) (xy 266.284964 -248.595388) (xy 266.284456 -248.595388)
			(xy 265.768836 -248.595388) (xy 265.760959 -248.595649) (xy 265.745955 -248.60045) (xy 265.739372 -248.604786)
			(xy 265.718296 -248.619179) (xy 265.67265 -248.642006) (xy 265.624044 -248.657563) (xy 265.573627 -248.665482)
			(xy 265.54811 -248.666) (xy 265.522589 -248.665522) (xy 265.472162 -248.657624) (xy 265.42355 -248.642061)
			(xy 265.377912 -248.619203) (xy 265.356848 -248.604786) (xy 265.350271 -248.600447) (xy 265.33526 -248.595675)
			(xy 265.327384 -248.595388) (xy 264.81151 -248.595388) (xy 264.806213 -248.594874) (xy 264.798643 -248.587465)
			(xy 264.798048 -248.58218) (xy 202.89774 -248.58218) (xy 202.89774 -248.582434) (xy 202.897297 -248.587747)
			(xy 202.889837 -248.595317) (xy 202.884532 -248.595896) (xy 202.368658 -248.595896) (xy 202.36085 -248.596235)
			(xy 202.345979 -248.601004) (xy 202.339448 -248.605294) (xy 202.318334 -248.619655) (xy 202.272608 -248.642381)
			(xy 202.223932 -248.657808) (xy 202.173464 -248.66557) (xy 202.147932 -248.666) (xy 202.122403 -248.665541)
			(xy 202.07194 -248.657771) (xy 202.023268 -248.642348) (xy 201.977539 -248.619638) (xy 201.956416 -248.605294)
			(xy 201.949881 -248.60101) (xy 201.935014 -248.596222) (xy 201.927206 -248.595896) (xy 201.411332 -248.595896)
			(xy 201.406001 -248.59555) (xy 201.398458 -248.588018) (xy 201.398124 -248.582688) (xy 195.353919 -248.582688)
			(xy 195.353497 -248.587747) (xy 195.346037 -248.595317) (xy 195.340732 -248.595896) (xy 194.824858 -248.595896)
			(xy 194.81705 -248.596235) (xy 194.802179 -248.601004) (xy 194.795648 -248.605294) (xy 194.774534 -248.619655)
			(xy 194.728808 -248.642381) (xy 194.680132 -248.657808) (xy 194.629664 -248.66557) (xy 194.604132 -248.666)
			(xy 194.578603 -248.665541) (xy 194.52814 -248.657771) (xy 194.479468 -248.642348) (xy 194.433739 -248.619638)
			(xy 194.412616 -248.605294) (xy 194.406081 -248.60101) (xy 194.391214 -248.596222) (xy 194.383406 -248.595896)
			(xy 193.867532 -248.595896) (xy 193.862201 -248.59555) (xy 193.854658 -248.588018) (xy 193.854324 -248.582688)
			(xy 187.810118 -248.582688) (xy 187.80967 -248.587807) (xy 187.802053 -248.595392) (xy 187.796678 -248.595896)
			(xy 187.280804 -248.595896) (xy 187.272994 -248.596212) (xy 187.258123 -248.600997) (xy 187.251594 -248.605294)
			(xy 187.230467 -248.619635) (xy 187.184746 -248.642365) (xy 187.136074 -248.657798) (xy 187.085609 -248.665566)
			(xy 187.060078 -248.666) (xy 187.034548 -248.665568) (xy 186.984084 -248.65779) (xy 186.935412 -248.642359)
			(xy 186.889684 -248.619642) (xy 186.868562 -248.605294) (xy 186.862039 -248.600989) (xy 186.847162 -248.596215)
			(xy 186.839352 -248.595896) (xy 186.323478 -248.595896) (xy 186.31812 -248.595368) (xy 186.310537 -248.587792)
			(xy 186.310016 -248.582434) (xy 180.265832 -248.582434) (xy 180.265396 -248.587749) (xy 180.257931 -248.59532)
			(xy 180.252624 -248.595896) (xy 179.73675 -248.595896) (xy 179.728942 -248.596231) (xy 179.71407 -248.601003)
			(xy 179.70754 -248.605294) (xy 179.686428 -248.619659) (xy 179.640701 -248.642383) (xy 179.592025 -248.65781)
			(xy 179.541556 -248.66557) (xy 179.516024 -248.666) (xy 179.490495 -248.665545) (xy 179.440032 -248.657774)
			(xy 179.391359 -248.64235) (xy 179.345631 -248.619639) (xy 179.324508 -248.605294) (xy 179.317974 -248.601006)
			(xy 179.303106 -248.596221) (xy 179.295298 -248.595896) (xy 178.779424 -248.595896) (xy 178.774092 -248.595556)
			(xy 178.766549 -248.58802) (xy 178.766216 -248.582688) (xy 172.72201 -248.582688) (xy 172.721569 -248.587809)
			(xy 172.713948 -248.595395) (xy 172.70857 -248.595896) (xy 172.192696 -248.595896) (xy 172.184886 -248.596209)
			(xy 172.170015 -248.600995) (xy 172.163486 -248.605294) (xy 172.142361 -248.619639) (xy 172.096639 -248.642368)
			(xy 172.047967 -248.6578) (xy 171.997501 -248.665567) (xy 171.97197 -248.666) (xy 171.946439 -248.665572)
			(xy 171.895976 -248.657793) (xy 171.847303 -248.642361) (xy 171.801576 -248.619642) (xy 171.780454 -248.605294)
			(xy 171.773932 -248.600986) (xy 171.759055 -248.596213) (xy 171.751244 -248.595896) (xy 171.23537 -248.595896)
			(xy 171.230011 -248.595373) (xy 171.222428 -248.587793) (xy 171.221908 -248.582434) (xy 165.177724 -248.582434)
			(xy 165.177295 -248.587751) (xy 165.169825 -248.595322) (xy 165.164516 -248.595896) (xy 163.691316 -248.595896)
			(xy 163.685983 -248.595561) (xy 163.67844 -248.588021) (xy 163.678108 -248.582688) (xy 109.732987 -248.582688)
			(xy 109.732816 -248.58475) (xy 109.720412 -248.633727) (xy 109.700117 -248.679994) (xy 109.672482 -248.722289)
			(xy 109.638262 -248.759458) (xy 109.598391 -248.790488) (xy 109.553956 -248.814532) (xy 109.50617 -248.830933)
			(xy 109.456335 -248.839245) (xy 109.431074 -248.839736) (xy 108.49102 -248.839736) (xy 108.465764 -248.839189)
			(xy 108.415939 -248.830878) (xy 108.368162 -248.814479) (xy 108.323736 -248.790439) (xy 108.283873 -248.759415)
			(xy 108.249661 -248.722253) (xy 108.222032 -248.679966) (xy 108.20174 -248.633707) (xy 108.189339 -248.58474)
			(xy 108.185168 -248.5344) (xy 56.07812 -248.5344) (xy 56.07812 -248.582434) (xy 56.077839 -248.587884)
			(xy 56.070109 -248.59557) (xy 56.064658 -248.595896) (xy 54.591458 -248.595896) (xy 54.586097 -248.595381)
			(xy 54.578516 -248.587795) (xy 54.577996 -248.582434) (xy 48.533812 -248.582434) (xy 48.533394 -248.587754)
			(xy 48.525917 -248.595325) (xy 48.520604 -248.595896) (xy 48.00473 -248.595896) (xy 47.996921 -248.596223)
			(xy 47.98205 -248.601) (xy 47.97552 -248.605294) (xy 47.954386 -248.619624) (xy 47.908667 -248.642357)
			(xy 47.859998 -248.657793) (xy 47.809534 -248.665564) (xy 47.784004 -248.666) (xy 47.758474 -248.665555)
			(xy 47.708011 -248.657781) (xy 47.659339 -248.642354) (xy 47.613611 -248.61964) (xy 47.592488 -248.605294)
			(xy 47.585959 -248.600999) (xy 47.571087 -248.596218) (xy 47.563278 -248.595896) (xy 47.047404 -248.595896)
			(xy 47.042069 -248.595569) (xy 47.034528 -248.588023) (xy 47.034196 -248.582688) (xy 40.989987 -248.582688)
			(xy 40.989477 -248.58779) (xy 40.981905 -248.595371) (xy 40.97655 -248.595896) (xy 40.460676 -248.595896)
			(xy 40.452865 -248.5962) (xy 40.437994 -248.600993) (xy 40.431466 -248.605294) (xy 40.410347 -248.619647)
			(xy 40.364623 -248.642375) (xy 40.315949 -248.657804) (xy 40.265481 -248.665569) (xy 40.23995 -248.666)
			(xy 40.214421 -248.665532) (xy 40.163959 -248.657765) (xy 40.115286 -248.642344) (xy 40.069557 -248.619637)
			(xy 40.048434 -248.605294) (xy 40.041895 -248.601016) (xy 40.027031 -248.596225) (xy 40.019224 -248.595896)
			(xy 39.50335 -248.595896) (xy 39.497988 -248.595386) (xy 39.490408 -248.587796) (xy 39.489888 -248.582434)
			(xy 33.445704 -248.582434) (xy 33.445205 -248.587732) (xy 33.437783 -248.595299) (xy 33.432496 -248.595896)
			(xy 32.916622 -248.595896) (xy 32.908813 -248.59622) (xy 32.893941 -248.600999) (xy 32.887412 -248.605294)
			(xy 32.86628 -248.619627) (xy 32.82056 -248.642359) (xy 32.77189 -248.657794) (xy 32.721426 -248.665565)
			(xy 32.695896 -248.666) (xy 32.670366 -248.665559) (xy 32.619903 -248.657783) (xy 32.57123 -248.642355)
			(xy 32.525502 -248.61964) (xy 32.50438 -248.605294) (xy 32.497853 -248.600996) (xy 32.482979 -248.596217)
			(xy 32.47517 -248.595896) (xy 31.959296 -248.595896) (xy 31.95396 -248.595575) (xy 31.946419 -248.588024)
			(xy 31.946088 -248.582688) (xy 25.90188 -248.582688) (xy 25.901405 -248.587732) (xy 25.893983 -248.595299)
			(xy 25.888696 -248.595896) (xy 25.372822 -248.595896) (xy 25.365013 -248.59622) (xy 25.350141 -248.600999)
			(xy 25.343612 -248.605294) (xy 25.32248 -248.619627) (xy 25.27676 -248.642359) (xy 25.22809 -248.657794)
			(xy 25.177626 -248.665565) (xy 25.152096 -248.666) (xy 25.126566 -248.665559) (xy 25.076103 -248.657783)
			(xy 25.02743 -248.642355) (xy 24.981702 -248.61964) (xy 24.96058 -248.605294) (xy 24.954053 -248.600996)
			(xy 24.939179 -248.596217) (xy 24.93137 -248.595896) (xy 24.415496 -248.595896) (xy 24.41016 -248.595575)
			(xy 24.402619 -248.588024) (xy 24.402288 -248.582688) (xy 18.358079 -248.582688) (xy 18.357576 -248.587792)
			(xy 18.35 -248.595373) (xy 18.344642 -248.595896) (xy 17.828768 -248.595896) (xy 17.820961 -248.596239)
			(xy 17.806089 -248.601005) (xy 17.799558 -248.605294) (xy 17.778441 -248.619651) (xy 17.732716 -248.642377)
			(xy 17.684041 -248.657806) (xy 17.633573 -248.665569) (xy 17.608042 -248.666) (xy 17.582513 -248.665536)
			(xy 17.53205 -248.657767) (xy 17.483378 -248.642346) (xy 17.437649 -248.619637) (xy 17.416526 -248.605294)
			(xy 17.409988 -248.601013) (xy 17.395123 -248.596224) (xy 17.387316 -248.595896) (xy 16.871442 -248.595896)
			(xy 16.866021 -248.595496) (xy 16.858335 -248.587853) (xy 16.85798 -248.582434) (xy 2.509012 -248.582434)
			(xy 2.509012 -249.432572) (xy 20.958048 -249.432572) (xy 20.958048 -248.938034) (xy 20.958403 -248.932601)
			(xy 20.966078 -248.924913) (xy 20.97151 -248.924572) (xy 21.487638 -248.924572) (xy 21.495446 -248.924236)
			(xy 21.510318 -248.919466) (xy 21.516848 -248.915174) (xy 21.537937 -248.900825) (xy 21.583598 -248.878094)
			(xy 21.632204 -248.862635) (xy 21.682607 -248.854812) (xy 21.733613 -248.854812) (xy 21.784016 -248.862635)
			(xy 21.832622 -248.878094) (xy 21.878283 -248.900825) (xy 21.899372 -248.915174) (xy 21.905912 -248.919451)
			(xy 21.920775 -248.924243) (xy 21.928582 -248.924572) (xy 22.44471 -248.924572) (xy 22.450155 -248.924876)
			(xy 22.457842 -248.932588) (xy 22.458172 -248.938034) (xy 22.458172 -249.432572) (xy 28.502356 -249.432572)
			(xy 28.502356 -248.938034) (xy 28.502847 -248.93273) (xy 28.510271 -248.925156) (xy 28.515564 -248.924572)
			(xy 29.031692 -248.924572) (xy 29.039502 -248.92426) (xy 29.054374 -248.919473) (xy 29.060902 -248.915174)
			(xy 29.081991 -248.900825) (xy 29.127652 -248.878094) (xy 29.176258 -248.862635) (xy 29.226661 -248.854812)
			(xy 29.277667 -248.854812) (xy 29.32807 -248.862635) (xy 29.376676 -248.878094) (xy 29.422337 -248.900825)
			(xy 29.443426 -248.915174) (xy 29.449954 -248.919471) (xy 29.464827 -248.924251) (xy 29.472636 -248.924572)
			(xy 29.988764 -248.924572) (xy 29.994087 -248.924949) (xy 30.001629 -248.932459) (xy 30.001972 -248.93778)
			(xy 30.001972 -248.938288) (xy 30.001972 -249.432572) (xy 36.046156 -249.432572) (xy 36.046156 -248.938034)
			(xy 36.046647 -248.93273) (xy 36.054071 -248.925156) (xy 36.059364 -248.924572) (xy 36.575492 -248.924572)
			(xy 36.583302 -248.92426) (xy 36.598174 -248.919473) (xy 36.604702 -248.915174) (xy 36.625791 -248.900825)
			(xy 36.671452 -248.878094) (xy 36.720058 -248.862635) (xy 36.770461 -248.854812) (xy 36.821467 -248.854812)
			(xy 36.87187 -248.862635) (xy 36.920476 -248.878094) (xy 36.966137 -248.900825) (xy 36.987226 -248.915174)
			(xy 36.993754 -248.919471) (xy 37.008627 -248.924251) (xy 37.016436 -248.924572) (xy 37.532564 -248.924572)
			(xy 37.537887 -248.924949) (xy 37.545429 -248.932459) (xy 37.545772 -248.93778) (xy 37.545772 -248.938288)
			(xy 37.545772 -249.432572) (xy 43.589956 -249.432572) (xy 43.589956 -248.938034) (xy 43.590304 -248.932599)
			(xy 43.597984 -248.92491) (xy 43.603418 -248.924572) (xy 44.119546 -248.924572) (xy 44.127354 -248.92424)
			(xy 44.142226 -248.919467) (xy 44.148756 -248.915174) (xy 44.169845 -248.900825) (xy 44.215506 -248.878094)
			(xy 44.264112 -248.862635) (xy 44.314515 -248.854812) (xy 44.365521 -248.854812) (xy 44.415924 -248.862635)
			(xy 44.46453 -248.878094) (xy 44.510191 -248.900825) (xy 44.53128 -248.915174) (xy 44.537818 -248.919454)
			(xy 44.552683 -248.924244) (xy 44.56049 -248.924572) (xy 45.076618 -248.924572) (xy 45.082064 -248.92487)
			(xy 45.089751 -248.932587) (xy 45.09008 -248.938034) (xy 45.09008 -249.432572) (xy 51.134264 -249.432572)
			(xy 51.134264 -248.938034) (xy 51.134749 -248.932728) (xy 51.142177 -248.925154) (xy 51.147472 -248.924572)
			(xy 51.6636 -248.924572) (xy 51.671411 -248.924263) (xy 51.686282 -248.919474) (xy 51.69281 -248.915174)
			(xy 51.713899 -248.900825) (xy 51.75956 -248.878094) (xy 51.808166 -248.862635) (xy 51.858569 -248.854812)
			(xy 51.909575 -248.854812) (xy 51.959978 -248.862635) (xy 52.008584 -248.878094) (xy 52.054245 -248.900825)
			(xy 52.075334 -248.915174) (xy 52.08186 -248.919474) (xy 52.096734 -248.924252) (xy 52.104544 -248.924572)
			(xy 52.620672 -248.924572) (xy 52.625996 -248.924943) (xy 52.633537 -248.932458) (xy 52.63388 -248.93778)
			(xy 52.63388 -248.938288) (xy 52.63388 -249.432572) (xy 58.678064 -249.432572) (xy 58.678064 -248.938034)
			(xy 58.678405 -248.932597) (xy 58.68609 -248.924908) (xy 58.691526 -248.924572) (xy 60.164726 -248.924572)
			(xy 60.170173 -248.924865) (xy 60.177859 -248.932586) (xy 60.178188 -248.938034) (xy 60.178188 -249.432572)
			(xy 167.778176 -249.432572) (xy 167.778176 -248.938034) (xy 167.77865 -248.932726) (xy 167.786085 -248.925151)
			(xy 167.791384 -248.924572) (xy 169.264584 -248.924572) (xy 169.26984 -248.925103) (xy 169.277282 -248.932525)
			(xy 169.277792 -248.93778) (xy 169.277792 -248.938288) (xy 169.277792 -249.432572) (xy 175.321976 -249.432572)
			(xy 175.321976 -248.938034) (xy 175.322306 -248.932594) (xy 175.329998 -248.924904) (xy 175.335438 -248.924572)
			(xy 175.851566 -248.924572) (xy 175.859375 -248.924248) (xy 175.874247 -248.91947) (xy 175.880776 -248.915174)
			(xy 175.901865 -248.900825) (xy 175.947526 -248.878094) (xy 175.996132 -248.862635) (xy 176.046535 -248.854812)
			(xy 176.097541 -248.854812) (xy 176.147944 -248.862635) (xy 176.19655 -248.878094) (xy 176.242211 -248.900825)
			(xy 176.2633 -248.915174) (xy 176.269834 -248.919461) (xy 176.284702 -248.924247) (xy 176.29251 -248.924572)
			(xy 176.808638 -248.924572) (xy 176.814015 -248.925029) (xy 176.8216 -248.932655) (xy 176.8221 -248.938034)
			(xy 176.8221 -249.432572) (xy 182.866284 -249.432572) (xy 182.866284 -248.938034) (xy 182.866751 -248.932724)
			(xy 182.874191 -248.925148) (xy 182.879492 -248.924572) (xy 183.39562 -248.924572) (xy 183.403431 -248.924272)
			(xy 183.418303 -248.919477) (xy 183.42483 -248.915174) (xy 183.445919 -248.900825) (xy 183.49158 -248.878094)
			(xy 183.540186 -248.862635) (xy 183.590589 -248.854812) (xy 183.641595 -248.854812) (xy 183.691998 -248.862635)
			(xy 183.740604 -248.878094) (xy 183.786265 -248.900825) (xy 183.807354 -248.915174) (xy 183.813876 -248.919482)
			(xy 183.828753 -248.924255) (xy 183.836564 -248.924572) (xy 184.352692 -248.924572) (xy 184.357949 -248.925098)
			(xy 184.365391 -248.932524) (xy 184.3659 -248.93778) (xy 184.3659 -248.938288) (xy 184.3659 -249.432572)
			(xy 190.410084 -249.432572) (xy 190.410084 -248.938034) (xy 190.410407 -248.932593) (xy 190.418104 -248.924902)
			(xy 190.423546 -248.924572) (xy 190.939674 -248.924572) (xy 190.947484 -248.924252) (xy 190.962355 -248.919471)
			(xy 190.968884 -248.915174) (xy 190.989973 -248.900825) (xy 191.035634 -248.878094) (xy 191.08424 -248.862635)
			(xy 191.134643 -248.854812) (xy 191.185649 -248.854812) (xy 191.236052 -248.862635) (xy 191.284658 -248.878094)
			(xy 191.330319 -248.900825) (xy 191.351408 -248.915174) (xy 191.35794 -248.919464) (xy 191.37281 -248.924248)
			(xy 191.380618 -248.924572) (xy 191.896746 -248.924572) (xy 191.902124 -248.925023) (xy 191.909709 -248.932653)
			(xy 191.910208 -248.938034) (xy 191.910208 -249.432572) (xy 197.954392 -249.432572) (xy 197.954392 -248.938034)
			(xy 197.95494 -248.932745) (xy 197.962324 -248.925175) (xy 197.9676 -248.924572) (xy 198.483728 -248.924572)
			(xy 198.49154 -248.924275) (xy 198.506411 -248.919478) (xy 198.512938 -248.915174) (xy 198.534027 -248.900825)
			(xy 198.579688 -248.878094) (xy 198.628294 -248.862635) (xy 198.678697 -248.854812) (xy 198.729703 -248.854812)
			(xy 198.780106 -248.862635) (xy 198.828712 -248.878094) (xy 198.874373 -248.900825) (xy 198.895462 -248.915174)
			(xy 198.902004 -248.919447) (xy 198.916866 -248.924241) (xy 198.924672 -248.924572) (xy 199.4408 -248.924572)
			(xy 199.446058 -248.925093) (xy 199.453499 -248.932523) (xy 199.454008 -248.93778) (xy 199.454008 -248.938288)
			(xy 199.454008 -249.432572) (xy 205.498192 -249.432572) (xy 205.498192 -248.938034) (xy 205.49874 -248.932745)
			(xy 205.506124 -248.925175) (xy 205.5114 -248.924572) (xy 206.027528 -248.924572) (xy 206.03534 -248.924275)
			(xy 206.050211 -248.919478) (xy 206.056738 -248.915174) (xy 206.077827 -248.900825) (xy 206.123488 -248.878094)
			(xy 206.172094 -248.862635) (xy 206.222497 -248.854812) (xy 206.273503 -248.854812) (xy 206.323906 -248.862635)
			(xy 206.372512 -248.878094) (xy 206.418173 -248.900825) (xy 206.439262 -248.915174) (xy 206.445804 -248.919447)
			(xy 206.460666 -248.924241) (xy 206.468472 -248.924572) (xy 206.9846 -248.924572) (xy 206.989858 -248.925093)
			(xy 206.997299 -248.932523) (xy 206.997808 -248.93778) (xy 206.997808 -248.938288) (xy 206.997808 -249.432318)
			(xy 268.898116 -249.432318) (xy 268.898116 -248.93778) (xy 268.898416 -248.932439) (xy 268.905982 -248.924898)
			(xy 268.911324 -248.924572) (xy 268.911832 -248.924572) (xy 269.427706 -248.924572) (xy 269.435517 -248.924266)
			(xy 269.450388 -248.919475) (xy 269.456916 -248.915174) (xy 269.478005 -248.900825) (xy 269.523666 -248.878094)
			(xy 269.572272 -248.862635) (xy 269.622675 -248.854812) (xy 269.673681 -248.854812) (xy 269.724084 -248.862635)
			(xy 269.77269 -248.878094) (xy 269.818351 -248.900825) (xy 269.83944 -248.915174) (xy 269.845965 -248.919477)
			(xy 269.86084 -248.924253) (xy 269.86865 -248.924572) (xy 270.384778 -248.924572) (xy 270.390087 -248.925042)
			(xy 270.397661 -248.932481) (xy 270.39824 -248.93778) (xy 270.39824 -249.432318) (xy 270.398226 -249.432572)
			(xy 276.442424 -249.432572) (xy 276.442424 -249.432064) (xy 276.442424 -248.93778) (xy 276.442717 -248.932437)
			(xy 276.450288 -248.924896) (xy 276.455632 -248.924572) (xy 276.97176 -248.924572) (xy 276.979569 -248.924246)
			(xy 276.994441 -248.919469) (xy 277.00097 -248.915174) (xy 277.022059 -248.900825) (xy 277.06772 -248.878094)
			(xy 277.116326 -248.862635) (xy 277.166729 -248.854812) (xy 277.217735 -248.854812) (xy 277.268138 -248.862635)
			(xy 277.316744 -248.878094) (xy 277.362405 -248.900825) (xy 277.383494 -248.915174) (xy 277.390029 -248.919459)
			(xy 277.404896 -248.924246) (xy 277.412704 -248.924572) (xy 277.928832 -248.924572) (xy 277.934094 -248.925071)
			(xy 277.941533 -248.932518) (xy 277.94204 -248.93778) (xy 277.94204 -249.432318) (xy 277.942018 -249.432572)
			(xy 283.986224 -249.432572) (xy 283.986224 -249.432064) (xy 283.986224 -248.93778) (xy 283.986517 -248.932437)
			(xy 283.994088 -248.924896) (xy 283.999432 -248.924572) (xy 284.51556 -248.924572) (xy 284.523369 -248.924246)
			(xy 284.538241 -248.919469) (xy 284.54477 -248.915174) (xy 284.565859 -248.900825) (xy 284.61152 -248.878094)
			(xy 284.660126 -248.862635) (xy 284.710529 -248.854812) (xy 284.761535 -248.854812) (xy 284.811938 -248.862635)
			(xy 284.860544 -248.878094) (xy 284.906205 -248.900825) (xy 284.927294 -248.915174) (xy 284.933829 -248.919459)
			(xy 284.948696 -248.924246) (xy 284.956504 -248.924572) (xy 285.472632 -248.924572) (xy 285.477894 -248.925071)
			(xy 285.485333 -248.932518) (xy 285.48584 -248.93778) (xy 285.48584 -249.432318) (xy 291.530024 -249.432318)
			(xy 291.530024 -248.93778) (xy 291.530317 -248.932437) (xy 291.537888 -248.924896) (xy 291.543232 -248.924572)
			(xy 291.54374 -248.924572) (xy 292.059614 -248.924572) (xy 292.067425 -248.924269) (xy 292.082297 -248.919476)
			(xy 292.088824 -248.915174) (xy 292.109913 -248.900825) (xy 292.155574 -248.878094) (xy 292.20418 -248.862635)
			(xy 292.254583 -248.854812) (xy 292.305589 -248.854812) (xy 292.355992 -248.862635) (xy 292.404598 -248.878094)
			(xy 292.450259 -248.900825) (xy 292.471348 -248.915174) (xy 292.477871 -248.91948) (xy 292.492748 -248.924254)
			(xy 292.500558 -248.924572) (xy 293.016686 -248.924572) (xy 293.021996 -248.925036) (xy 293.02957 -248.932479)
			(xy 293.030148 -248.93778) (xy 293.030148 -249.432318) (xy 293.030125 -249.432572) (xy 299.074332 -249.432572)
			(xy 299.074332 -249.432064) (xy 299.074332 -248.93778) (xy 299.074617 -248.932435) (xy 299.082194 -248.924893)
			(xy 299.08754 -248.924572) (xy 299.603668 -248.924572) (xy 299.611477 -248.924249) (xy 299.626349 -248.91947)
			(xy 299.632878 -248.915174) (xy 299.653967 -248.900825) (xy 299.699628 -248.878094) (xy 299.748234 -248.862635)
			(xy 299.798637 -248.854812) (xy 299.849643 -248.854812) (xy 299.900046 -248.862635) (xy 299.948652 -248.878094)
			(xy 299.994313 -248.900825) (xy 300.015402 -248.915174) (xy 300.021935 -248.919462) (xy 300.036804 -248.924247)
			(xy 300.044612 -248.924572) (xy 300.56074 -248.924572) (xy 300.566003 -248.925066) (xy 300.573442 -248.932516)
			(xy 300.573948 -248.93778) (xy 300.573948 -249.432318) (xy 306.618132 -249.432318) (xy 306.618132 -248.93778)
			(xy 306.618417 -248.932435) (xy 306.625994 -248.924893) (xy 306.63134 -248.924572) (xy 306.631848 -248.924572)
			(xy 308.104794 -248.924572) (xy 308.110105 -248.925031) (xy 308.117678 -248.932478) (xy 308.118256 -248.93778)
			(xy 308.118256 -249.432318) (xy 308.118233 -249.432572) (xy 415.718244 -249.432572) (xy 415.718244 -249.432064)
			(xy 415.718244 -248.93778) (xy 415.718777 -248.932526) (xy 415.726199 -248.925088) (xy 415.731452 -248.924572)
			(xy 417.204652 -248.924572) (xy 417.209973 -248.924957) (xy 417.217515 -248.932461) (xy 417.21786 -248.93778)
			(xy 417.21786 -249.432318) (xy 423.262044 -249.432318) (xy 423.262044 -248.93778) (xy 423.262577 -248.932526)
			(xy 423.269999 -248.925088) (xy 423.275252 -248.924572) (xy 423.27576 -248.924572) (xy 423.791634 -248.924572)
			(xy 423.799442 -248.924235) (xy 423.814314 -248.919465) (xy 423.820844 -248.915174) (xy 423.841933 -248.900825)
			(xy 423.887594 -248.878094) (xy 423.9362 -248.862635) (xy 423.986603 -248.854812) (xy 424.037609 -248.854812)
			(xy 424.088012 -248.862635) (xy 424.136618 -248.878094) (xy 424.182279 -248.900825) (xy 424.203368 -248.915174)
			(xy 424.209909 -248.919449) (xy 424.224772 -248.924242) (xy 424.232578 -248.924572) (xy 424.748706 -248.924572)
			(xy 424.754018 -248.925023) (xy 424.761591 -248.932476) (xy 424.762168 -248.93778) (xy 424.762168 -249.432318)
			(xy 424.762144 -249.432572) (xy 430.806352 -249.432572) (xy 430.806352 -249.432064) (xy 430.806352 -248.93778)
			(xy 430.806877 -248.932524) (xy 430.814305 -248.925085) (xy 430.81956 -248.924572) (xy 431.335688 -248.924572)
			(xy 431.343498 -248.924258) (xy 431.35837 -248.919473) (xy 431.364898 -248.915174) (xy 431.385987 -248.900825)
			(xy 431.431648 -248.878094) (xy 431.480254 -248.862635) (xy 431.530657 -248.854812) (xy 431.581663 -248.854812)
			(xy 431.632066 -248.862635) (xy 431.680672 -248.878094) (xy 431.726333 -248.900825) (xy 431.747422 -248.915174)
			(xy 431.753951 -248.91947) (xy 431.768823 -248.92425) (xy 431.776632 -248.924572) (xy 432.29276 -248.924572)
			(xy 432.298082 -248.924952) (xy 432.305624 -248.93246) (xy 432.305968 -248.93778) (xy 432.305968 -249.432318)
			(xy 438.350152 -249.432318) (xy 438.350152 -248.93778) (xy 438.350677 -248.932524) (xy 438.358105 -248.925085)
			(xy 438.36336 -248.924572) (xy 438.363868 -248.924572) (xy 438.879742 -248.924572) (xy 438.88755 -248.924238)
			(xy 438.902422 -248.919466) (xy 438.908952 -248.915174) (xy 438.930041 -248.900825) (xy 438.975702 -248.878094)
			(xy 439.024308 -248.862635) (xy 439.074711 -248.854812) (xy 439.125717 -248.854812) (xy 439.17612 -248.862635)
			(xy 439.224726 -248.878094) (xy 439.270387 -248.900825) (xy 439.291476 -248.915174) (xy 439.298015 -248.919452)
			(xy 439.312879 -248.924244) (xy 439.320686 -248.924572) (xy 439.836814 -248.924572) (xy 439.842127 -248.925018)
			(xy 439.849699 -248.932475) (xy 439.850276 -248.93778) (xy 439.850276 -249.432318) (xy 439.850252 -249.432572)
			(xy 445.89446 -249.432572) (xy 445.89446 -249.432064) (xy 445.89446 -248.93778) (xy 445.894978 -248.932523)
			(xy 445.902411 -248.925083) (xy 445.907668 -248.924572) (xy 446.423796 -248.924572) (xy 446.431606 -248.924261)
			(xy 446.446478 -248.919474) (xy 446.453006 -248.915174) (xy 446.474095 -248.900825) (xy 446.519756 -248.878094)
			(xy 446.568362 -248.862635) (xy 446.618765 -248.854812) (xy 446.669771 -248.854812) (xy 446.720174 -248.862635)
			(xy 446.76878 -248.878094) (xy 446.814441 -248.900825) (xy 446.83553 -248.915174) (xy 446.842057 -248.919473)
			(xy 446.85693 -248.924251) (xy 446.86474 -248.924572) (xy 447.380868 -248.924572) (xy 447.386191 -248.924946)
			(xy 447.393733 -248.932458) (xy 447.394076 -248.93778) (xy 447.394076 -249.432318) (xy 447.394053 -249.432572)
			(xy 453.43826 -249.432572) (xy 453.43826 -249.432064) (xy 453.43826 -248.93778) (xy 453.438778 -248.932523)
			(xy 453.446211 -248.925083) (xy 453.451468 -248.924572) (xy 453.967596 -248.924572) (xy 453.975406 -248.924261)
			(xy 453.990278 -248.919474) (xy 453.996806 -248.915174) (xy 454.017895 -248.900825) (xy 454.063556 -248.878094)
			(xy 454.112162 -248.862635) (xy 454.162565 -248.854812) (xy 454.213571 -248.854812) (xy 454.263974 -248.862635)
			(xy 454.31258 -248.878094) (xy 454.358241 -248.900825) (xy 454.37933 -248.915174) (xy 454.385857 -248.919473)
			(xy 454.40073 -248.924251) (xy 454.40854 -248.924572) (xy 454.924668 -248.924572) (xy 454.929991 -248.924946)
			(xy 454.937533 -248.932458) (xy 454.937876 -248.93778) (xy 454.937876 -249.432318) (xy 454.937391 -249.437621)
			(xy 454.929961 -249.44519) (xy 454.924668 -249.44578) (xy 454.408794 -249.44578) (xy 454.400982 -249.446078)
			(xy 454.38611 -249.450873) (xy 454.379584 -249.455178) (xy 454.358466 -249.469533) (xy 454.312741 -249.492258)
			(xy 454.264066 -249.507686) (xy 454.213599 -249.515451) (xy 454.188068 -249.515884) (xy 454.162537 -249.51546)
			(xy 454.112073 -249.50768) (xy 454.063401 -249.492247) (xy 454.017674 -249.469527) (xy 453.996552 -249.455178)
			(xy 453.990026 -249.450877) (xy 453.975152 -249.446099) (xy 453.967342 -249.44578) (xy 453.451468 -249.44578)
			(xy 453.446195 -249.445324) (xy 453.438752 -249.437848) (xy 453.43826 -249.432572) (xy 447.394053 -249.432572)
			(xy 447.393591 -249.437621) (xy 447.386161 -249.44519) (xy 447.380868 -249.44578) (xy 446.864994 -249.44578)
			(xy 446.857182 -249.446078) (xy 446.84231 -249.450873) (xy 446.835784 -249.455178) (xy 446.814666 -249.469533)
			(xy 446.768941 -249.492258) (xy 446.720266 -249.507686) (xy 446.669799 -249.515451) (xy 446.644268 -249.515884)
			(xy 446.618737 -249.51546) (xy 446.568273 -249.50768) (xy 446.519601 -249.492247) (xy 446.473874 -249.469527)
			(xy 446.452752 -249.455178) (xy 446.446226 -249.450877) (xy 446.431352 -249.446099) (xy 446.423542 -249.44578)
			(xy 445.907668 -249.44578) (xy 445.902395 -249.445324) (xy 445.894952 -249.437848) (xy 445.89446 -249.432572)
			(xy 439.850252 -249.432572) (xy 439.849763 -249.437681) (xy 439.842177 -249.445265) (xy 439.836814 -249.44578)
			(xy 439.32094 -249.44578) (xy 439.31313 -249.446097) (xy 439.298258 -249.450879) (xy 439.29173 -249.455178)
			(xy 439.270627 -249.469557) (xy 439.224897 -249.492276) (xy 439.176217 -249.507698) (xy 439.125747 -249.515455)
			(xy 439.100214 -249.515884) (xy 439.074684 -249.515437) (xy 439.024221 -249.507664) (xy 438.975549 -249.492237)
			(xy 438.92982 -249.469524) (xy 438.908698 -249.455178) (xy 438.902162 -249.450895) (xy 438.887296 -249.446105)
			(xy 438.879488 -249.44578) (xy 438.363614 -249.44578) (xy 438.358256 -249.445242) (xy 438.350671 -249.437675)
			(xy 438.350152 -249.432318) (xy 432.305968 -249.432318) (xy 432.30549 -249.437623) (xy 432.298055 -249.445192)
			(xy 432.29276 -249.44578) (xy 431.776886 -249.44578) (xy 431.769074 -249.446074) (xy 431.754202 -249.450872)
			(xy 431.747676 -249.455178) (xy 431.726561 -249.469537) (xy 431.680834 -249.492261) (xy 431.632159 -249.507688)
			(xy 431.581691 -249.515452) (xy 431.55616 -249.515884) (xy 431.530629 -249.515464) (xy 431.480165 -249.507683)
			(xy 431.431492 -249.492248) (xy 431.385766 -249.469527) (xy 431.364644 -249.455178) (xy 431.35812 -249.450874)
			(xy 431.343244 -249.446097) (xy 431.335434 -249.44578) (xy 430.81956 -249.44578) (xy 430.814286 -249.445329)
			(xy 430.806844 -249.437849) (xy 430.806352 -249.432572) (xy 424.762144 -249.432572) (xy 424.761662 -249.437683)
			(xy 424.754071 -249.445267) (xy 424.748706 -249.44578) (xy 424.232832 -249.44578) (xy 424.225022 -249.446094)
			(xy 424.21015 -249.450878) (xy 424.203622 -249.455178) (xy 424.182494 -249.469517) (xy 424.136772 -249.492245)
			(xy 424.088101 -249.507678) (xy 424.037636 -249.515449) (xy 424.012106 -249.515884) (xy 423.986576 -249.515441)
			(xy 423.936113 -249.507666) (xy 423.88744 -249.492239) (xy 423.841712 -249.469524) (xy 423.82059 -249.455178)
			(xy 423.814055 -249.450892) (xy 423.799188 -249.446104) (xy 423.79138 -249.44578) (xy 423.275506 -249.44578)
			(xy 423.270147 -249.445248) (xy 423.262562 -249.437676) (xy 423.262044 -249.432318) (xy 417.21786 -249.432318)
			(xy 417.217389 -249.437624) (xy 417.209949 -249.445195) (xy 417.204652 -249.44578) (xy 415.731452 -249.44578)
			(xy 415.726177 -249.445334) (xy 415.718735 -249.43785) (xy 415.718244 -249.432572) (xy 308.118233 -249.432572)
			(xy 308.117761 -249.437686) (xy 308.110162 -249.445271) (xy 308.104794 -249.44578) (xy 306.631594 -249.44578)
			(xy 306.626234 -249.445256) (xy 306.618649 -249.437678) (xy 306.618132 -249.432318) (xy 300.573948 -249.432318)
			(xy 300.573488 -249.437627) (xy 300.56604 -249.445198) (xy 300.56074 -249.44578) (xy 300.044866 -249.44578)
			(xy 300.037057 -249.446108) (xy 300.022185 -249.450883) (xy 300.015656 -249.455178) (xy 299.994546 -249.469546)
			(xy 299.948818 -249.492267) (xy 299.900141 -249.507692) (xy 299.849672 -249.515453) (xy 299.82414 -249.515884)
			(xy 299.798611 -249.515424) (xy 299.748148 -249.507655) (xy 299.699476 -249.492232) (xy 299.653747 -249.469522)
			(xy 299.632624 -249.455178) (xy 299.626082 -249.450905) (xy 299.61122 -249.446109) (xy 299.603414 -249.44578)
			(xy 299.08754 -249.44578) (xy 299.082206 -249.445443) (xy 299.074661 -249.437905) (xy 299.074332 -249.432572)
			(xy 293.030125 -249.432572) (xy 293.02966 -249.437688) (xy 293.022057 -249.445273) (xy 293.016686 -249.44578)
			(xy 292.500812 -249.44578) (xy 292.493001 -249.446085) (xy 292.478129 -249.450876) (xy 292.471602 -249.455178)
			(xy 292.450479 -249.469526) (xy 292.404756 -249.492252) (xy 292.356083 -249.507682) (xy 292.305617 -249.51545)
			(xy 292.280086 -249.515884) (xy 292.254556 -249.515451) (xy 292.204092 -249.507673) (xy 292.155419 -249.492243)
			(xy 292.109692 -249.469526) (xy 292.08857 -249.455178) (xy 292.08204 -249.450884) (xy 292.067169 -249.446101)
			(xy 292.05936 -249.44578) (xy 291.543486 -249.44578) (xy 291.538125 -249.445261) (xy 291.530541 -249.437679)
			(xy 291.530024 -249.432318) (xy 285.48584 -249.432318) (xy 285.485387 -249.437629) (xy 285.477935 -249.4452)
			(xy 285.472632 -249.44578) (xy 284.956758 -249.44578) (xy 284.948949 -249.446105) (xy 284.934077 -249.450882)
			(xy 284.927548 -249.455178) (xy 284.90644 -249.469549) (xy 284.860711 -249.49227) (xy 284.812034 -249.507694)
			(xy 284.761564 -249.515454) (xy 284.736032 -249.515884) (xy 284.710503 -249.515428) (xy 284.66004 -249.507657)
			(xy 284.611367 -249.492234) (xy 284.565639 -249.469523) (xy 284.544516 -249.455178) (xy 284.537976 -249.450902)
			(xy 284.523113 -249.446108) (xy 284.515306 -249.44578) (xy 283.999432 -249.44578) (xy 283.994097 -249.445449)
			(xy 283.986553 -249.437907) (xy 283.986224 -249.432572) (xy 277.942018 -249.432572) (xy 277.941587 -249.437629)
			(xy 277.934135 -249.4452) (xy 277.928832 -249.44578) (xy 277.412958 -249.44578) (xy 277.405149 -249.446105)
			(xy 277.390277 -249.450882) (xy 277.383748 -249.455178) (xy 277.36264 -249.469549) (xy 277.316911 -249.49227)
			(xy 277.268234 -249.507694) (xy 277.217764 -249.515454) (xy 277.192232 -249.515884) (xy 277.166703 -249.515428)
			(xy 277.11624 -249.507657) (xy 277.067567 -249.492234) (xy 277.021839 -249.469523) (xy 277.000716 -249.455178)
			(xy 276.994176 -249.450902) (xy 276.979313 -249.446108) (xy 276.971506 -249.44578) (xy 276.455632 -249.44578)
			(xy 276.450297 -249.445449) (xy 276.442753 -249.437907) (xy 276.442424 -249.432572) (xy 270.398226 -249.432572)
			(xy 270.397931 -249.437761) (xy 270.390222 -249.445447) (xy 270.384778 -249.44578) (xy 269.868904 -249.44578)
			(xy 269.861093 -249.446082) (xy 269.846221 -249.450875) (xy 269.839694 -249.455178) (xy 269.818574 -249.469529)
			(xy 269.772849 -249.492255) (xy 269.724175 -249.507684) (xy 269.673709 -249.515451) (xy 269.648178 -249.515884)
			(xy 269.622647 -249.515455) (xy 269.572184 -249.507676) (xy 269.523511 -249.492245) (xy 269.477784 -249.469526)
			(xy 269.456662 -249.455178) (xy 269.450134 -249.450881) (xy 269.435261 -249.4461) (xy 269.427452 -249.44578)
			(xy 268.911578 -249.44578) (xy 268.906216 -249.445266) (xy 268.898632 -249.43768) (xy 268.898116 -249.432318)
			(xy 206.997808 -249.432318) (xy 206.997808 -249.432572) (xy 206.997455 -249.437901) (xy 206.989928 -249.445443)
			(xy 206.9846 -249.44578) (xy 206.468726 -249.44578) (xy 206.460849 -249.446039) (xy 206.445845 -249.450842)
			(xy 206.439262 -249.455178) (xy 206.418188 -249.469575) (xy 206.372542 -249.492401) (xy 206.323935 -249.507957)
			(xy 206.273517 -249.515875) (xy 206.248 -249.516392) (xy 206.222479 -249.515921) (xy 206.172051 -249.508021)
			(xy 206.12344 -249.492456) (xy 206.077802 -249.469596) (xy 206.056738 -249.455178) (xy 206.050135 -249.450882)
			(xy 206.035144 -249.446082) (xy 206.027274 -249.44578) (xy 205.5114 -249.44578) (xy 205.506061 -249.445471)
			(xy 205.498518 -249.437912) (xy 205.498192 -249.432572) (xy 199.454008 -249.432572) (xy 199.453655 -249.437901)
			(xy 199.446128 -249.445443) (xy 199.4408 -249.44578) (xy 198.924926 -249.44578) (xy 198.917049 -249.446039)
			(xy 198.902045 -249.450842) (xy 198.895462 -249.455178) (xy 198.874388 -249.469575) (xy 198.828742 -249.492401)
			(xy 198.780135 -249.507957) (xy 198.729717 -249.515875) (xy 198.7042 -249.516392) (xy 198.678679 -249.515921)
			(xy 198.628251 -249.508021) (xy 198.57964 -249.492456) (xy 198.534002 -249.469596) (xy 198.512938 -249.455178)
			(xy 198.506335 -249.450882) (xy 198.491344 -249.446082) (xy 198.483474 -249.44578) (xy 197.9676 -249.44578)
			(xy 197.962261 -249.445471) (xy 197.954718 -249.437912) (xy 197.954392 -249.432572) (xy 191.910208 -249.432572)
			(xy 191.909855 -249.437901) (xy 191.902328 -249.445443) (xy 191.897 -249.44578) (xy 191.896492 -249.44578)
			(xy 191.380872 -249.44578) (xy 191.372997 -249.446058) (xy 191.357992 -249.450848) (xy 191.351408 -249.455178)
			(xy 191.330349 -249.469598) (xy 191.284697 -249.492419) (xy 191.236086 -249.507969) (xy 191.185664 -249.515879)
			(xy 191.160146 -249.516392) (xy 191.134626 -249.515898) (xy 191.084199 -249.508005) (xy 191.035588 -249.492446)
			(xy 190.989949 -249.469593) (xy 190.968884 -249.455178) (xy 190.962293 -249.450861) (xy 190.947293 -249.446074)
			(xy 190.93942 -249.44578) (xy 190.423546 -249.44578) (xy 190.418252 -249.445249) (xy 190.410679 -249.437853)
			(xy 190.410084 -249.432572) (xy 184.3659 -249.432572) (xy 184.365554 -249.437903) (xy 184.358022 -249.445446)
			(xy 184.352692 -249.44578) (xy 183.836818 -249.44578) (xy 183.828944 -249.446078) (xy 183.81394 -249.450854)
			(xy 183.807354 -249.455178) (xy 183.786282 -249.469578) (xy 183.740635 -249.492404) (xy 183.692027 -249.507959)
			(xy 183.641609 -249.515876) (xy 183.616092 -249.516392) (xy 183.590573 -249.515875) (xy 183.540147 -249.507989)
			(xy 183.491535 -249.492437) (xy 183.445896 -249.46959) (xy 183.42483 -249.455178) (xy 183.418229 -249.450879)
			(xy 183.403236 -249.446081) (xy 183.395366 -249.44578) (xy 182.879492 -249.44578) (xy 182.874152 -249.445476)
			(xy 182.86661 -249.437913) (xy 182.866284 -249.432572) (xy 176.8221 -249.432572) (xy 176.821754 -249.437903)
			(xy 176.814222 -249.445446) (xy 176.808892 -249.44578) (xy 176.808384 -249.44578) (xy 176.292764 -249.44578)
			(xy 176.284888 -249.446055) (xy 176.269884 -249.450847) (xy 176.2633 -249.455178) (xy 176.242215 -249.469558)
			(xy 176.196573 -249.492388) (xy 176.147969 -249.507949) (xy 176.097554 -249.515872) (xy 176.072038 -249.516392)
			(xy 176.046518 -249.515902) (xy 175.996091 -249.508008) (xy 175.947479 -249.492448) (xy 175.901841 -249.469593)
			(xy 175.880776 -249.455178) (xy 175.874187 -249.450858) (xy 175.859185 -249.446073) (xy 175.851312 -249.44578)
			(xy 175.335438 -249.44578) (xy 175.330143 -249.445254) (xy 175.322571 -249.437854) (xy 175.321976 -249.432572)
			(xy 169.277792 -249.432572) (xy 169.277453 -249.437904) (xy 169.269916 -249.445448) (xy 169.264584 -249.44578)
			(xy 167.791384 -249.44578) (xy 167.786043 -249.445481) (xy 167.778501 -249.437914) (xy 167.778176 -249.432572)
			(xy 60.178188 -249.432572) (xy 60.177853 -249.437905) (xy 60.170313 -249.445449) (xy 60.16498 -249.44578)
			(xy 60.164472 -249.44578) (xy 58.691526 -249.44578) (xy 58.68623 -249.445262) (xy 58.678658 -249.437856)
			(xy 58.678064 -249.432572) (xy 52.63388 -249.432572) (xy 52.633552 -249.437907) (xy 52.626007 -249.445452)
			(xy 52.620672 -249.44578) (xy 52.104798 -249.44578) (xy 52.096924 -249.446069) (xy 52.081919 -249.450851)
			(xy 52.075334 -249.455178) (xy 52.054268 -249.469587) (xy 52.008619 -249.49241) (xy 51.960009 -249.507963)
			(xy 51.90959 -249.515877) (xy 51.884072 -249.516392) (xy 51.858553 -249.515885) (xy 51.808126 -249.507996)
			(xy 51.759515 -249.492441) (xy 51.713875 -249.469591) (xy 51.69281 -249.455178) (xy 51.686213 -249.450871)
			(xy 51.671217 -249.446078) (xy 51.663346 -249.44578) (xy 51.147472 -249.44578) (xy 51.142199 -249.445321)
			(xy 51.134756 -249.437847) (xy 51.134264 -249.432572) (xy 45.09008 -249.432572) (xy 45.089752 -249.437907)
			(xy 45.082207 -249.445452) (xy 45.076872 -249.44578) (xy 45.076364 -249.44578) (xy 44.560744 -249.44578)
			(xy 44.552868 -249.446046) (xy 44.537863 -249.450844) (xy 44.53128 -249.455178) (xy 44.510201 -249.469567)
			(xy 44.464556 -249.492395) (xy 44.415951 -249.507953) (xy 44.365534 -249.515874) (xy 44.340018 -249.516392)
			(xy 44.314497 -249.515912) (xy 44.26407 -249.508015) (xy 44.215458 -249.492452) (xy 44.169821 -249.469594)
			(xy 44.148756 -249.455178) (xy 44.142172 -249.450851) (xy 44.127166 -249.44607) (xy 44.119292 -249.44578)
			(xy 43.603418 -249.44578) (xy 43.598121 -249.445267) (xy 43.59055 -249.437858) (xy 43.589956 -249.432572)
			(xy 37.545772 -249.432572) (xy 37.545451 -249.437909) (xy 37.537902 -249.445454) (xy 37.532564 -249.44578)
			(xy 37.01669 -249.44578) (xy 37.008815 -249.446066) (xy 36.993811 -249.45085) (xy 36.987226 -249.455178)
			(xy 36.966162 -249.46959) (xy 36.920512 -249.492413) (xy 36.871902 -249.507965) (xy 36.821482 -249.515878)
			(xy 36.795964 -249.516392) (xy 36.770444 -249.515889) (xy 36.720018 -249.507999) (xy 36.671406 -249.492443)
			(xy 36.625767 -249.469591) (xy 36.604702 -249.455178) (xy 36.598107 -249.450868) (xy 36.58311 -249.446077)
			(xy 36.575238 -249.44578) (xy 36.059364 -249.44578) (xy 36.05409 -249.445326) (xy 36.046648 -249.437848)
			(xy 36.046156 -249.432572) (xy 30.001972 -249.432572) (xy 30.001651 -249.437909) (xy 29.994102 -249.445454)
			(xy 29.988764 -249.44578) (xy 29.47289 -249.44578) (xy 29.465015 -249.446066) (xy 29.450011 -249.45085)
			(xy 29.443426 -249.455178) (xy 29.422362 -249.46959) (xy 29.376712 -249.492413) (xy 29.328102 -249.507965)
			(xy 29.277682 -249.515878) (xy 29.252164 -249.516392) (xy 29.226644 -249.515889) (xy 29.176218 -249.507999)
			(xy 29.127606 -249.492443) (xy 29.081967 -249.469591) (xy 29.060902 -249.455178) (xy 29.054307 -249.450868)
			(xy 29.03931 -249.446077) (xy 29.031438 -249.44578) (xy 28.515564 -249.44578) (xy 28.51029 -249.445326)
			(xy 28.502848 -249.437848) (xy 28.502356 -249.432572) (xy 22.458172 -249.432572) (xy 22.457851 -249.437909)
			(xy 22.450302 -249.445454) (xy 22.444964 -249.44578) (xy 22.444456 -249.44578) (xy 21.928836 -249.44578)
			(xy 21.920959 -249.446043) (xy 21.905955 -249.450843) (xy 21.899372 -249.455178) (xy 21.878295 -249.46957)
			(xy 21.83265 -249.492398) (xy 21.784044 -249.507955) (xy 21.733627 -249.515874) (xy 21.70811 -249.516392)
			(xy 21.682589 -249.515916) (xy 21.632162 -249.508017) (xy 21.58355 -249.492454) (xy 21.537912 -249.469595)
			(xy 21.516848 -249.455178) (xy 21.510265 -249.450847) (xy 21.495259 -249.446069) (xy 21.487384 -249.44578)
			(xy 20.97151 -249.44578) (xy 20.966212 -249.445273) (xy 20.958641 -249.437859) (xy 20.958048 -249.432572)
			(xy 2.509012 -249.432572) (xy 2.509012 -250.282456) (xy 16.85798 -250.282456) (xy 16.85798 -249.787918)
			(xy 16.858295 -249.782475) (xy 16.865999 -249.774786) (xy 16.871442 -249.774456) (xy 17.38757 -249.774456)
			(xy 17.39538 -249.774137) (xy 17.410251 -249.769355) (xy 17.41678 -249.765058) (xy 17.437869 -249.750709)
			(xy 17.48353 -249.727978) (xy 17.532136 -249.712519) (xy 17.582539 -249.704696) (xy 17.633545 -249.704696)
			(xy 17.683948 -249.712519) (xy 17.732554 -249.727978) (xy 17.778215 -249.750709) (xy 17.799304 -249.765058)
			(xy 17.805838 -249.769345) (xy 17.820706 -249.774131) (xy 17.828514 -249.774456) (xy 18.344642 -249.774456)
			(xy 18.350015 -249.774924) (xy 18.3576 -249.782542) (xy 18.358104 -249.787918) (xy 18.358104 -250.282456)
			(xy 24.402288 -250.282456) (xy 24.402288 -249.787918) (xy 24.402741 -249.782605) (xy 24.410191 -249.77503)
			(xy 24.415496 -249.774456) (xy 24.931624 -249.774456) (xy 24.939436 -249.77416) (xy 24.954307 -249.769363)
			(xy 24.960834 -249.765058) (xy 24.981923 -249.750709) (xy 25.027584 -249.727978) (xy 25.07619 -249.712519)
			(xy 25.126593 -249.704696) (xy 25.177599 -249.704696) (xy 25.228002 -249.712519) (xy 25.276608 -249.727978)
			(xy 25.322269 -249.750709) (xy 25.343358 -249.765058) (xy 25.34988 -249.769366) (xy 25.364757 -249.774139)
			(xy 25.372568 -249.774456) (xy 25.888696 -249.774456) (xy 25.89395 -249.774994) (xy 25.90139 -249.782412)
			(xy 25.901904 -249.787664) (xy 25.901904 -249.788172) (xy 25.901904 -250.282456) (xy 31.946088 -250.282456)
			(xy 31.946088 -249.787918) (xy 31.946541 -249.782605) (xy 31.953991 -249.77503) (xy 31.959296 -249.774456)
			(xy 32.475424 -249.774456) (xy 32.483236 -249.77416) (xy 32.498107 -249.769363) (xy 32.504634 -249.765058)
			(xy 32.525723 -249.750709) (xy 32.571384 -249.727978) (xy 32.61999 -249.712519) (xy 32.670393 -249.704696)
			(xy 32.721399 -249.704696) (xy 32.771802 -249.712519) (xy 32.820408 -249.727978) (xy 32.866069 -249.750709)
			(xy 32.887158 -249.765058) (xy 32.89368 -249.769366) (xy 32.908557 -249.774139) (xy 32.916368 -249.774456)
			(xy 33.432496 -249.774456) (xy 33.43775 -249.774994) (xy 33.44519 -249.782412) (xy 33.445704 -249.787664)
			(xy 33.445704 -249.788172) (xy 33.445704 -250.282456) (xy 39.489888 -250.282456) (xy 39.489888 -249.787918)
			(xy 39.490457 -249.782568) (xy 39.498003 -249.774984) (xy 39.50335 -249.774456) (xy 40.019478 -249.774456)
			(xy 40.027288 -249.77414) (xy 40.04216 -249.769356) (xy 40.048688 -249.765058) (xy 40.069777 -249.750709)
			(xy 40.115438 -249.727978) (xy 40.164044 -249.712519) (xy 40.214447 -249.704696) (xy 40.265453 -249.704696)
			(xy 40.315856 -249.712519) (xy 40.364462 -249.727978) (xy 40.410123 -249.750709) (xy 40.431212 -249.765058)
			(xy 40.437744 -249.769348) (xy 40.452614 -249.774133) (xy 40.460422 -249.774456) (xy 40.97655 -249.774456)
			(xy 40.981924 -249.774919) (xy 40.989508 -249.782541) (xy 40.990012 -249.787918) (xy 40.990012 -250.282456)
			(xy 47.034196 -250.282456) (xy 47.034196 -249.787918) (xy 47.03473 -249.782626) (xy 47.042125 -249.775057)
			(xy 47.047404 -249.774456) (xy 47.563532 -249.774456) (xy 47.57134 -249.774121) (xy 47.586212 -249.76935)
			(xy 47.592742 -249.765058) (xy 47.613831 -249.750709) (xy 47.659492 -249.727978) (xy 47.708098 -249.712519)
			(xy 47.758501 -249.704696) (xy 47.809507 -249.704696) (xy 47.85991 -249.712519) (xy 47.908516 -249.727978)
			(xy 47.954177 -249.750709) (xy 47.975266 -249.765058) (xy 47.981808 -249.769331) (xy 47.99667 -249.774126)
			(xy 48.004476 -249.774456) (xy 48.520604 -249.774456) (xy 48.525859 -249.774988) (xy 48.533299 -249.782411)
			(xy 48.533812 -249.787664) (xy 48.533812 -249.788172) (xy 48.533812 -250.282456) (xy 54.577996 -250.282456)
			(xy 54.577996 -249.787918) (xy 54.578558 -249.782566) (xy 54.586109 -249.774982) (xy 54.591458 -249.774456)
			(xy 56.064658 -249.774456) (xy 56.070092 -249.774809) (xy 56.077781 -249.782485) (xy 56.07812 -249.787918)
			(xy 56.07812 -250.282456) (xy 163.678108 -250.282456) (xy 163.678108 -249.787918) (xy 163.678631 -249.782623)
			(xy 163.686034 -249.775053) (xy 163.691316 -249.774456) (xy 165.164516 -249.774456) (xy 165.169772 -249.77498)
			(xy 165.177212 -249.782409) (xy 165.177724 -249.787664) (xy 165.177724 -249.788172) (xy 165.177724 -250.282456)
			(xy 171.221908 -250.282456) (xy 171.221908 -249.787918) (xy 171.222459 -249.782563) (xy 171.230017 -249.774978)
			(xy 171.23537 -249.774456) (xy 171.751498 -249.774456) (xy 171.759309 -249.774149) (xy 171.774181 -249.769359)
			(xy 171.780708 -249.765058) (xy 171.801797 -249.750709) (xy 171.847458 -249.727978) (xy 171.896064 -249.712519)
			(xy 171.946467 -249.704696) (xy 171.997473 -249.704696) (xy 172.047876 -249.712519) (xy 172.096482 -249.727978)
			(xy 172.142143 -249.750709) (xy 172.163232 -249.765058) (xy 172.16976 -249.769356) (xy 172.184633 -249.774136)
			(xy 172.192442 -249.774456) (xy 172.70857 -249.774456) (xy 172.714005 -249.774801) (xy 172.721694 -249.782483)
			(xy 172.722032 -249.787918) (xy 172.722032 -250.282456) (xy 178.766216 -250.282456) (xy 178.766216 -249.787918)
			(xy 178.766732 -249.782622) (xy 178.774139 -249.775051) (xy 178.779424 -249.774456) (xy 179.295552 -249.774456)
			(xy 179.303361 -249.774129) (xy 179.318233 -249.769353) (xy 179.324762 -249.765058) (xy 179.345851 -249.750709)
			(xy 179.391512 -249.727978) (xy 179.440118 -249.712519) (xy 179.490521 -249.704696) (xy 179.541527 -249.704696)
			(xy 179.59193 -249.712519) (xy 179.640536 -249.727978) (xy 179.686197 -249.750709) (xy 179.707286 -249.765058)
			(xy 179.713824 -249.769338) (xy 179.728689 -249.774129) (xy 179.736496 -249.774456) (xy 180.252624 -249.774456)
			(xy 180.257881 -249.774975) (xy 180.26532 -249.782408) (xy 180.265832 -249.787664) (xy 180.265832 -249.788172)
			(xy 180.265832 -250.282456) (xy 186.310016 -250.282456) (xy 186.310016 -249.787918) (xy 186.31056 -249.782561)
			(xy 186.318123 -249.774976) (xy 186.323478 -249.774456) (xy 186.839606 -249.774456) (xy 186.847417 -249.774152)
			(xy 186.862289 -249.76936) (xy 186.868816 -249.765058) (xy 186.889905 -249.750709) (xy 186.935566 -249.727978)
			(xy 186.984172 -249.712519) (xy 187.034575 -249.704696) (xy 187.085581 -249.704696) (xy 187.135984 -249.712519)
			(xy 187.18459 -249.727978) (xy 187.230251 -249.750709) (xy 187.25134 -249.765058) (xy 187.257866 -249.769359)
			(xy 187.27274 -249.774137) (xy 187.28055 -249.774456) (xy 187.796678 -249.774456) (xy 187.802114 -249.774796)
			(xy 187.809802 -249.782482) (xy 187.81014 -249.787918) (xy 187.81014 -250.282456) (xy 193.854324 -250.282456)
			(xy 193.854324 -249.787918) (xy 193.854833 -249.78262) (xy 193.862245 -249.775048) (xy 193.867532 -249.774456)
			(xy 194.38366 -249.774456) (xy 194.391469 -249.774133) (xy 194.406341 -249.769354) (xy 194.41287 -249.765058)
			(xy 194.433959 -249.750709) (xy 194.47962 -249.727978) (xy 194.528226 -249.712519) (xy 194.578629 -249.704696)
			(xy 194.629635 -249.704696) (xy 194.680038 -249.712519) (xy 194.728644 -249.727978) (xy 194.774305 -249.750709)
			(xy 194.795394 -249.765058) (xy 194.80193 -249.769342) (xy 194.816796 -249.77413) (xy 194.824604 -249.774456)
			(xy 195.340732 -249.774456) (xy 195.34599 -249.77497) (xy 195.353429 -249.782406) (xy 195.35394 -249.787664)
			(xy 195.35394 -249.788172) (xy 195.35394 -250.282456) (xy 201.398124 -250.282456) (xy 201.398124 -249.787918)
			(xy 201.398633 -249.78262) (xy 201.406045 -249.775048) (xy 201.411332 -249.774456) (xy 201.92746 -249.774456)
			(xy 201.935269 -249.774133) (xy 201.950141 -249.769354) (xy 201.95667 -249.765058) (xy 201.977759 -249.750709)
			(xy 202.02342 -249.727978) (xy 202.072026 -249.712519) (xy 202.122429 -249.704696) (xy 202.173435 -249.704696)
			(xy 202.223838 -249.712519) (xy 202.272444 -249.727978) (xy 202.318105 -249.750709) (xy 202.339194 -249.765058)
			(xy 202.34573 -249.769342) (xy 202.360596 -249.77413) (xy 202.368404 -249.774456) (xy 202.884532 -249.774456)
			(xy 202.88979 -249.77497) (xy 202.897229 -249.782406) (xy 202.89774 -249.787664) (xy 202.89774 -249.788172)
			(xy 202.89774 -250.282202) (xy 264.798048 -250.282202) (xy 264.798048 -249.787664) (xy 264.798566 -249.782408)
			(xy 264.806 -249.77497) (xy 264.811256 -249.774456) (xy 264.811764 -249.774456) (xy 265.327638 -249.774456)
			(xy 265.335446 -249.774123) (xy 265.350318 -249.769351) (xy 265.356848 -249.765058) (xy 265.377937 -249.750709)
			(xy 265.423598 -249.727978) (xy 265.472204 -249.712519) (xy 265.522607 -249.704696) (xy 265.573613 -249.704696)
			(xy 265.624016 -249.712519) (xy 265.672622 -249.727978) (xy 265.718283 -249.750709) (xy 265.739372 -249.765058)
			(xy 265.745913 -249.769333) (xy 265.760776 -249.774127) (xy 265.768582 -249.774456) (xy 266.28471 -249.774456)
			(xy 266.290019 -249.774918) (xy 266.297591 -249.782364) (xy 266.298172 -249.787664) (xy 266.298172 -250.282202)
			(xy 266.298147 -250.282456) (xy 272.342356 -250.282456) (xy 272.342356 -250.281948) (xy 272.342356 -249.787664)
			(xy 272.342867 -249.782406) (xy 272.350306 -249.774967) (xy 272.355564 -249.774456) (xy 272.871692 -249.774456)
			(xy 272.879503 -249.774147) (xy 272.894374 -249.769359) (xy 272.900902 -249.765058) (xy 272.921991 -249.750709)
			(xy 272.967652 -249.727978) (xy 273.016258 -249.712519) (xy 273.066661 -249.704696) (xy 273.117667 -249.704696)
			(xy 273.16807 -249.712519) (xy 273.216676 -249.727978) (xy 273.262337 -249.750709) (xy 273.283426 -249.765058)
			(xy 273.289955 -249.769354) (xy 273.304827 -249.774135) (xy 273.312636 -249.774456) (xy 273.828764 -249.774456)
			(xy 273.834014 -249.775015) (xy 273.841456 -249.782417) (xy 273.841972 -249.787664) (xy 273.841972 -250.282202)
			(xy 273.841948 -250.282456) (xy 279.886156 -250.282456) (xy 279.886156 -250.281948) (xy 279.886156 -249.787664)
			(xy 279.886667 -249.782406) (xy 279.894106 -249.774967) (xy 279.899364 -249.774456) (xy 280.415492 -249.774456)
			(xy 280.423303 -249.774147) (xy 280.438174 -249.769359) (xy 280.444702 -249.765058) (xy 280.465791 -249.750709)
			(xy 280.511452 -249.727978) (xy 280.560058 -249.712519) (xy 280.610461 -249.704696) (xy 280.661467 -249.704696)
			(xy 280.71187 -249.712519) (xy 280.760476 -249.727978) (xy 280.806137 -249.750709) (xy 280.827226 -249.765058)
			(xy 280.833755 -249.769354) (xy 280.848627 -249.774135) (xy 280.856436 -249.774456) (xy 281.372564 -249.774456)
			(xy 281.377814 -249.775015) (xy 281.385256 -249.782417) (xy 281.385772 -249.787664) (xy 281.385772 -250.282202)
			(xy 287.429956 -250.282202) (xy 287.429956 -249.787664) (xy 287.430467 -249.782406) (xy 287.437906 -249.774967)
			(xy 287.443164 -249.774456) (xy 287.443672 -249.774456) (xy 287.959546 -249.774456) (xy 287.967355 -249.774127)
			(xy 287.982227 -249.769352) (xy 287.988756 -249.765058) (xy 288.009845 -249.750709) (xy 288.055506 -249.727978)
			(xy 288.104112 -249.712519) (xy 288.154515 -249.704696) (xy 288.205521 -249.704696) (xy 288.255924 -249.712519)
			(xy 288.30453 -249.727978) (xy 288.350191 -249.750709) (xy 288.37128 -249.765058) (xy 288.377819 -249.769336)
			(xy 288.392683 -249.774128) (xy 288.40049 -249.774456) (xy 288.916618 -249.774456) (xy 288.921928 -249.774913)
			(xy 288.929499 -249.782363) (xy 288.93008 -249.787664) (xy 288.93008 -250.282202) (xy 288.930055 -250.282456)
			(xy 294.974264 -250.282456) (xy 294.974264 -250.281948) (xy 294.974264 -249.787664) (xy 294.974768 -249.782404)
			(xy 294.982211 -249.774965) (xy 294.987472 -249.774456) (xy 295.5036 -249.774456) (xy 295.511411 -249.77415)
			(xy 295.526283 -249.76936) (xy 295.53281 -249.765058) (xy 295.553899 -249.750709) (xy 295.59956 -249.727978)
			(xy 295.648166 -249.712519) (xy 295.698569 -249.704696) (xy 295.749575 -249.704696) (xy 295.799978 -249.712519)
			(xy 295.848584 -249.727978) (xy 295.894245 -249.750709) (xy 295.915334 -249.765058) (xy 295.921861 -249.769357)
			(xy 295.936734 -249.774136) (xy 295.944544 -249.774456) (xy 296.460672 -249.774456) (xy 296.465923 -249.77501)
			(xy 296.473365 -249.782416) (xy 296.47388 -249.787664) (xy 296.47388 -250.282202) (xy 302.518064 -250.282202)
			(xy 302.518064 -249.787664) (xy 302.518568 -249.782404) (xy 302.526011 -249.774965) (xy 302.531272 -249.774456)
			(xy 302.53178 -249.774456) (xy 304.004726 -249.774456) (xy 304.010037 -249.774908) (xy 304.017607 -249.782361)
			(xy 304.018188 -249.787664) (xy 304.018188 -250.282202) (xy 304.018163 -250.282456) (xy 411.618176 -250.282456)
			(xy 411.618176 -250.281948) (xy 411.618176 -249.787664) (xy 411.618669 -249.782401) (xy 411.62612 -249.774961)
			(xy 411.631384 -249.774456) (xy 413.104584 -249.774456) (xy 413.109836 -249.775002) (xy 413.117278 -249.782414)
			(xy 413.117792 -249.787664) (xy 413.117792 -250.282202) (xy 419.161976 -250.282202) (xy 419.161976 -249.787664)
			(xy 419.162469 -249.782401) (xy 419.16992 -249.774961) (xy 419.175184 -249.774456) (xy 419.175692 -249.774456)
			(xy 419.691566 -249.774456) (xy 419.699376 -249.774135) (xy 419.714247 -249.769355) (xy 419.720776 -249.765058)
			(xy 419.741865 -249.750709) (xy 419.787526 -249.727978) (xy 419.836132 -249.712519) (xy 419.886535 -249.704696)
			(xy 419.937541 -249.704696) (xy 419.987944 -249.712519) (xy 420.03655 -249.727978) (xy 420.082211 -249.750709)
			(xy 420.1033 -249.765058) (xy 420.109835 -249.769344) (xy 420.124702 -249.774131) (xy 420.13251 -249.774456)
			(xy 420.648638 -249.774456) (xy 420.653951 -249.7749) (xy 420.66152 -249.78236) (xy 420.6621 -249.787664)
			(xy 420.6621 -250.282202) (xy 420.662074 -250.282456) (xy 426.706284 -250.282456) (xy 426.706284 -250.281948)
			(xy 426.706284 -249.787664) (xy 426.70677 -249.782399) (xy 426.714226 -249.774959) (xy 426.719492 -249.774456)
			(xy 427.23562 -249.774456) (xy 427.243432 -249.774158) (xy 427.258303 -249.769362) (xy 427.26483 -249.765058)
			(xy 427.285919 -249.750709) (xy 427.33158 -249.727978) (xy 427.380186 -249.712519) (xy 427.430589 -249.704696)
			(xy 427.481595 -249.704696) (xy 427.531998 -249.712519) (xy 427.580604 -249.727978) (xy 427.626265 -249.750709)
			(xy 427.647354 -249.765058) (xy 427.653877 -249.769365) (xy 427.668753 -249.774139) (xy 427.676564 -249.774456)
			(xy 428.192692 -249.774456) (xy 428.197945 -249.774996) (xy 428.205386 -249.782413) (xy 428.2059 -249.787664)
			(xy 428.2059 -250.282202) (xy 434.250084 -250.282202) (xy 434.250084 -249.787664) (xy 434.25057 -249.782399)
			(xy 434.258026 -249.774959) (xy 434.263292 -249.774456) (xy 434.2638 -249.774456) (xy 434.779674 -249.774456)
			(xy 434.787484 -249.774138) (xy 434.802356 -249.769356) (xy 434.808884 -249.765058) (xy 434.829973 -249.750709)
			(xy 434.875634 -249.727978) (xy 434.92424 -249.712519) (xy 434.974643 -249.704696) (xy 435.025649 -249.704696)
			(xy 435.076052 -249.712519) (xy 435.124658 -249.727978) (xy 435.170319 -249.750709) (xy 435.191408 -249.765058)
			(xy 435.197941 -249.769347) (xy 435.21281 -249.774132) (xy 435.220618 -249.774456) (xy 435.736746 -249.774456)
			(xy 435.742047 -249.774961) (xy 435.749623 -249.782374) (xy 435.750208 -249.787664) (xy 435.750208 -250.282202)
			(xy 435.750182 -250.282456) (xy 441.794392 -250.282456) (xy 441.794392 -250.281948) (xy 441.794392 -249.787664)
			(xy 441.794871 -249.782397) (xy 441.802332 -249.774957) (xy 441.8076 -249.774456) (xy 442.323728 -249.774456)
			(xy 442.33154 -249.774162) (xy 442.346412 -249.769363) (xy 442.352938 -249.765058) (xy 442.374027 -249.750709)
			(xy 442.419688 -249.727978) (xy 442.468294 -249.712519) (xy 442.518697 -249.704696) (xy 442.569703 -249.704696)
			(xy 442.620106 -249.712519) (xy 442.668712 -249.727978) (xy 442.714373 -249.750709) (xy 442.735462 -249.765058)
			(xy 442.742005 -249.769329) (xy 442.756866 -249.774125) (xy 442.764672 -249.774456) (xy 443.2808 -249.774456)
			(xy 443.286054 -249.774991) (xy 443.293494 -249.782411) (xy 443.294008 -249.787664) (xy 443.294008 -250.282202)
			(xy 443.293983 -250.282456) (xy 449.338192 -250.282456) (xy 449.338192 -250.281948) (xy 449.338192 -249.787664)
			(xy 449.338671 -249.782397) (xy 449.346132 -249.774957) (xy 449.3514 -249.774456) (xy 449.867528 -249.774456)
			(xy 449.87534 -249.774162) (xy 449.890212 -249.769363) (xy 449.896738 -249.765058) (xy 449.917827 -249.750709)
			(xy 449.963488 -249.727978) (xy 450.012094 -249.712519) (xy 450.062497 -249.704696) (xy 450.113503 -249.704696)
			(xy 450.163906 -249.712519) (xy 450.212512 -249.727978) (xy 450.258173 -249.750709) (xy 450.279262 -249.765058)
			(xy 450.285805 -249.769329) (xy 450.300666 -249.774125) (xy 450.308472 -249.774456) (xy 450.8246 -249.774456)
			(xy 450.829854 -249.774991) (xy 450.837294 -249.782411) (xy 450.837808 -249.787664) (xy 450.837808 -250.282202)
			(xy 450.837284 -250.287495) (xy 450.829881 -250.295064) (xy 450.8246 -250.295664) (xy 450.308726 -250.295664)
			(xy 450.300916 -250.295978) (xy 450.286044 -250.300763) (xy 450.279516 -250.305062) (xy 450.258388 -250.319402)
			(xy 450.212667 -250.34213) (xy 450.163995 -250.357563) (xy 450.11353 -250.365333) (xy 450.088 -250.365768)
			(xy 450.06247 -250.365331) (xy 450.012006 -250.357555) (xy 449.963334 -250.342126) (xy 449.917606 -250.319409)
			(xy 449.896484 -250.305062) (xy 449.889952 -250.300772) (xy 449.875082 -250.295987) (xy 449.867274 -250.295664)
			(xy 449.3514 -250.295664) (xy 449.346057 -250.295369) (xy 449.338513 -250.2878) (xy 449.338192 -250.282456)
			(xy 443.293983 -250.282456) (xy 443.293484 -250.287495) (xy 443.286081 -250.295064) (xy 443.2808 -250.295664)
			(xy 442.764926 -250.295664) (xy 442.757116 -250.295978) (xy 442.742244 -250.300763) (xy 442.735716 -250.305062)
			(xy 442.714588 -250.319402) (xy 442.668867 -250.34213) (xy 442.620195 -250.357563) (xy 442.56973 -250.365333)
			(xy 442.5442 -250.365768) (xy 442.51867 -250.365331) (xy 442.468206 -250.357555) (xy 442.419534 -250.342126)
			(xy 442.373806 -250.319409) (xy 442.352684 -250.305062) (xy 442.346152 -250.300772) (xy 442.331282 -250.295987)
			(xy 442.323474 -250.295664) (xy 441.8076 -250.295664) (xy 441.802257 -250.295369) (xy 441.794713 -250.2878)
			(xy 441.794392 -250.282456) (xy 435.750182 -250.282456) (xy 435.749655 -250.287555) (xy 435.742097 -250.295138)
			(xy 435.736746 -250.295664) (xy 435.220872 -250.295664) (xy 435.21306 -250.295955) (xy 435.198188 -250.300755)
			(xy 435.191662 -250.305062) (xy 435.170549 -250.319425) (xy 435.124822 -250.342148) (xy 435.076146 -250.357574)
			(xy 435.025678 -250.365337) (xy 435.000146 -250.365768) (xy 434.974617 -250.365308) (xy 434.924154 -250.357539)
			(xy 434.875481 -250.342117) (xy 434.829753 -250.319406) (xy 434.80863 -250.305062) (xy 434.802087 -250.300789)
			(xy 434.787226 -250.295994) (xy 434.77942 -250.295664) (xy 434.263546 -250.295664) (xy 434.258118 -250.29529)
			(xy 434.250429 -250.287629) (xy 434.250084 -250.282202) (xy 428.2059 -250.282202) (xy 428.205383 -250.287497)
			(xy 428.197976 -250.295066) (xy 428.192692 -250.295664) (xy 427.676818 -250.295664) (xy 427.669007 -250.295975)
			(xy 427.654136 -250.300762) (xy 427.647608 -250.305062) (xy 427.626482 -250.319405) (xy 427.58076 -250.342133)
			(xy 427.532088 -250.357565) (xy 427.481623 -250.365334) (xy 427.456092 -250.365768) (xy 427.430562 -250.365335)
			(xy 427.380098 -250.357558) (xy 427.331425 -250.342128) (xy 427.285698 -250.31941) (xy 427.264576 -250.305062)
			(xy 427.258045 -250.300769) (xy 427.243175 -250.295986) (xy 427.235366 -250.295664) (xy 426.719492 -250.295664)
			(xy 426.714148 -250.295374) (xy 426.706605 -250.287801) (xy 426.706284 -250.282456) (xy 420.662074 -250.282456)
			(xy 420.661555 -250.287557) (xy 420.653992 -250.29514) (xy 420.648638 -250.295664) (xy 420.132764 -250.295664)
			(xy 420.124955 -250.295994) (xy 420.110083 -250.300768) (xy 420.103554 -250.305062) (xy 420.082444 -250.319429)
			(xy 420.036716 -250.342151) (xy 419.988039 -250.357576) (xy 419.93757 -250.365338) (xy 419.912038 -250.365768)
			(xy 419.886509 -250.365312) (xy 419.836045 -250.357542) (xy 419.787373 -250.342118) (xy 419.741645 -250.319407)
			(xy 419.720522 -250.305062) (xy 419.713981 -250.300786) (xy 419.699118 -250.295993) (xy 419.691312 -250.295664)
			(xy 419.175438 -250.295664) (xy 419.170009 -250.295296) (xy 419.16232 -250.28763) (xy 419.161976 -250.282202)
			(xy 413.117792 -250.282202) (xy 413.117282 -250.287499) (xy 413.10987 -250.295068) (xy 413.104584 -250.295664)
			(xy 411.631384 -250.295664) (xy 411.626039 -250.29538) (xy 411.618496 -250.287803) (xy 411.618176 -250.282456)
			(xy 304.018163 -250.282456) (xy 304.017653 -250.28756) (xy 304.010083 -250.295144) (xy 304.004726 -250.295664)
			(xy 302.531526 -250.295664) (xy 302.526095 -250.295304) (xy 302.518408 -250.287632) (xy 302.518064 -250.282202)
			(xy 296.47388 -250.282202) (xy 296.47338 -250.287502) (xy 296.465961 -250.295071) (xy 296.460672 -250.295664)
			(xy 295.944798 -250.295664) (xy 295.936987 -250.295966) (xy 295.922115 -250.300759) (xy 295.915588 -250.305062)
			(xy 295.894468 -250.319414) (xy 295.848744 -250.34214) (xy 295.80007 -250.357569) (xy 295.749603 -250.365335)
			(xy 295.724072 -250.365768) (xy 295.698541 -250.365345) (xy 295.648077 -250.357565) (xy 295.599405 -250.342132)
			(xy 295.553677 -250.319411) (xy 295.532556 -250.305062) (xy 295.52603 -250.300761) (xy 295.511156 -250.295983)
			(xy 295.503346 -250.295664) (xy 294.987472 -250.295664) (xy 294.982125 -250.295388) (xy 294.974583 -250.287805)
			(xy 294.974264 -250.282456) (xy 288.930055 -250.282456) (xy 288.929553 -250.287562) (xy 288.921977 -250.295146)
			(xy 288.916618 -250.295664) (xy 288.400744 -250.295664) (xy 288.392934 -250.295986) (xy 288.378063 -250.300765)
			(xy 288.371534 -250.305062) (xy 288.350429 -250.319437) (xy 288.304699 -250.342158) (xy 288.256021 -250.35758)
			(xy 288.20555 -250.365339) (xy 288.180018 -250.365768) (xy 288.154488 -250.365322) (xy 288.104025 -250.357549)
			(xy 288.055352 -250.342122) (xy 288.009624 -250.319408) (xy 287.988502 -250.305062) (xy 287.981966 -250.300779)
			(xy 287.9671 -250.29599) (xy 287.959292 -250.295664) (xy 287.443418 -250.295664) (xy 287.437986 -250.295309)
			(xy 287.430299 -250.287633) (xy 287.429956 -250.282202) (xy 281.385772 -250.282202) (xy 281.385279 -250.287504)
			(xy 281.377855 -250.295074) (xy 281.372564 -250.295664) (xy 280.85669 -250.295664) (xy 280.848878 -250.295963)
			(xy 280.834007 -250.300758) (xy 280.82748 -250.305062) (xy 280.806362 -250.319417) (xy 280.760637 -250.342142)
			(xy 280.711962 -250.357571) (xy 280.661495 -250.365336) (xy 280.635964 -250.365768) (xy 280.610433 -250.365349)
			(xy 280.559969 -250.357568) (xy 280.511296 -250.342133) (xy 280.465569 -250.319412) (xy 280.444448 -250.305062)
			(xy 280.437924 -250.300758) (xy 280.423048 -250.295982) (xy 280.415238 -250.295664) (xy 279.899364 -250.295664)
			(xy 279.894016 -250.295393) (xy 279.886475 -250.287806) (xy 279.886156 -250.282456) (xy 273.841948 -250.282456)
			(xy 273.841479 -250.287504) (xy 273.834055 -250.295074) (xy 273.828764 -250.295664) (xy 273.31289 -250.295664)
			(xy 273.305078 -250.295963) (xy 273.290207 -250.300758) (xy 273.28368 -250.305062) (xy 273.262562 -250.319417)
			(xy 273.216837 -250.342142) (xy 273.168162 -250.357571) (xy 273.117695 -250.365336) (xy 273.092164 -250.365768)
			(xy 273.066633 -250.365349) (xy 273.016169 -250.357568) (xy 272.967496 -250.342133) (xy 272.921769 -250.319412)
			(xy 272.900648 -250.305062) (xy 272.894124 -250.300758) (xy 272.879248 -250.295982) (xy 272.871438 -250.295664)
			(xy 272.355564 -250.295664) (xy 272.350216 -250.295393) (xy 272.342675 -250.287806) (xy 272.342356 -250.282456)
			(xy 266.298147 -250.282456) (xy 266.297652 -250.287564) (xy 266.290071 -250.295149) (xy 266.28471 -250.295664)
			(xy 265.768836 -250.295664) (xy 265.761026 -250.295982) (xy 265.746154 -250.300764) (xy 265.739626 -250.305062)
			(xy 265.718495 -250.319397) (xy 265.672775 -250.342127) (xy 265.624104 -250.357561) (xy 265.57364 -250.365332)
			(xy 265.54811 -250.365768) (xy 265.52258 -250.365326) (xy 265.472116 -250.357552) (xy 265.423444 -250.342124)
			(xy 265.377716 -250.319409) (xy 265.356594 -250.305062) (xy 265.350059 -250.300776) (xy 265.335192 -250.295989)
			(xy 265.327384 -250.295664) (xy 264.81151 -250.295664) (xy 264.806077 -250.295314) (xy 264.79839 -250.287635)
			(xy 264.798048 -250.282202) (xy 202.89774 -250.282202) (xy 202.89774 -250.282456) (xy 202.897347 -250.287775)
			(xy 202.889849 -250.295316) (xy 202.884532 -250.295664) (xy 202.368658 -250.295664) (xy 202.360782 -250.295939)
			(xy 202.345778 -250.300731) (xy 202.339194 -250.305062) (xy 202.31811 -250.319443) (xy 202.272467 -250.342273)
			(xy 202.223863 -250.357834) (xy 202.173448 -250.365757) (xy 202.147932 -250.366276) (xy 202.122412 -250.365792)
			(xy 202.071984 -250.357896) (xy 202.023373 -250.342335) (xy 201.977735 -250.319478) (xy 201.95667 -250.305062)
			(xy 201.950083 -250.300739) (xy 201.93508 -250.295956) (xy 201.927206 -250.295664) (xy 201.411332 -250.295664)
			(xy 201.405993 -250.295347) (xy 201.398448 -250.287795) (xy 201.398124 -250.282456) (xy 195.35394 -250.282456)
			(xy 195.353547 -250.287775) (xy 195.346049 -250.295316) (xy 195.340732 -250.295664) (xy 194.824858 -250.295664)
			(xy 194.816982 -250.295939) (xy 194.801978 -250.300731) (xy 194.795394 -250.305062) (xy 194.77431 -250.319443)
			(xy 194.728667 -250.342273) (xy 194.680063 -250.357834) (xy 194.629648 -250.365757) (xy 194.604132 -250.366276)
			(xy 194.578612 -250.365792) (xy 194.528184 -250.357896) (xy 194.479573 -250.342335) (xy 194.433935 -250.319478)
			(xy 194.41287 -250.305062) (xy 194.406283 -250.300739) (xy 194.39128 -250.295956) (xy 194.383406 -250.295664)
			(xy 193.867532 -250.295664) (xy 193.862193 -250.295347) (xy 193.854648 -250.287795) (xy 193.854324 -250.282456)
			(xy 187.81014 -250.282456) (xy 187.809747 -250.287775) (xy 187.802249 -250.295316) (xy 187.796932 -250.295664)
			(xy 187.796424 -250.295664) (xy 187.280804 -250.295664) (xy 187.27293 -250.295959) (xy 187.257926 -250.300737)
			(xy 187.25134 -250.305062) (xy 187.230271 -250.319466) (xy 187.184623 -250.342291) (xy 187.136014 -250.357845)
			(xy 187.085595 -250.365761) (xy 187.060078 -250.366276) (xy 187.034558 -250.365769) (xy 186.984132 -250.35788)
			(xy 186.93552 -250.342326) (xy 186.889881 -250.319475) (xy 186.868816 -250.305062) (xy 186.862219 -250.300756)
			(xy 186.847223 -250.295963) (xy 186.839352 -250.295664) (xy 186.323478 -250.295664) (xy 186.318172 -250.295192)
			(xy 186.310602 -250.287752) (xy 186.310016 -250.282456) (xy 180.265832 -250.282456) (xy 180.265446 -250.287777)
			(xy 180.257943 -250.295319) (xy 180.252624 -250.295664) (xy 179.73675 -250.295664) (xy 179.728874 -250.295936)
			(xy 179.71387 -250.30073) (xy 179.707286 -250.305062) (xy 179.686204 -250.319446) (xy 179.640561 -250.342276)
			(xy 179.591956 -250.357836) (xy 179.54154 -250.365757) (xy 179.516024 -250.366276) (xy 179.490503 -250.365796)
			(xy 179.440076 -250.357899) (xy 179.391464 -250.342336) (xy 179.345826 -250.319479) (xy 179.324762 -250.305062)
			(xy 179.318177 -250.300735) (xy 179.303172 -250.295955) (xy 179.295298 -250.295664) (xy 178.779424 -250.295664)
			(xy 178.774084 -250.295353) (xy 178.766539 -250.287796) (xy 178.766216 -250.282456) (xy 172.722032 -250.282456)
			(xy 172.721646 -250.287777) (xy 172.714143 -250.295319) (xy 172.708824 -250.295664) (xy 172.708316 -250.295664)
			(xy 172.192696 -250.295664) (xy 172.184822 -250.295955) (xy 172.169818 -250.300736) (xy 172.163232 -250.305062)
			(xy 172.142165 -250.31947) (xy 172.096516 -250.342294) (xy 172.047907 -250.357847) (xy 171.997488 -250.365761)
			(xy 171.97197 -250.366276) (xy 171.94645 -250.365773) (xy 171.896024 -250.357883) (xy 171.847412 -250.342327)
			(xy 171.801773 -250.319476) (xy 171.780708 -250.305062) (xy 171.774113 -250.300753) (xy 171.759116 -250.295961)
			(xy 171.751244 -250.295664) (xy 171.23537 -250.295664) (xy 171.230063 -250.295197) (xy 171.222494 -250.287754)
			(xy 171.221908 -250.282456) (xy 165.177724 -250.282456) (xy 165.177345 -250.287779) (xy 165.169837 -250.295321)
			(xy 165.164516 -250.295664) (xy 163.691316 -250.295664) (xy 163.685975 -250.295358) (xy 163.678431 -250.287798)
			(xy 163.678108 -250.282456) (xy 56.07812 -250.282456) (xy 56.077745 -250.28778) (xy 56.070234 -250.295322)
			(xy 56.064912 -250.295664) (xy 56.064404 -250.295664) (xy 54.591458 -250.295664) (xy 54.58615 -250.295205)
			(xy 54.578581 -250.287756) (xy 54.577996 -250.282456) (xy 48.533812 -250.282456) (xy 48.533444 -250.287781)
			(xy 48.525928 -250.295325) (xy 48.520604 -250.295664) (xy 48.00473 -250.295664) (xy 47.996853 -250.295927)
			(xy 47.981849 -250.300727) (xy 47.975266 -250.305062) (xy 47.95419 -250.319455) (xy 47.908544 -250.342283)
			(xy 47.859938 -250.35784) (xy 47.809521 -250.365759) (xy 47.784004 -250.366276) (xy 47.758483 -250.365806)
			(xy 47.708055 -250.357906) (xy 47.659443 -250.342341) (xy 47.613806 -250.31948) (xy 47.592742 -250.305062)
			(xy 47.586162 -250.300728) (xy 47.571153 -250.295952) (xy 47.563278 -250.295664) (xy 47.047404 -250.295664)
			(xy 47.042062 -250.295366) (xy 47.034518 -250.287799) (xy 47.034196 -250.282456) (xy 40.990012 -250.282456)
			(xy 40.989644 -250.287781) (xy 40.982128 -250.295325) (xy 40.976804 -250.295664) (xy 40.976296 -250.295664)
			(xy 40.460676 -250.295664) (xy 40.452801 -250.295947) (xy 40.437797 -250.300734) (xy 40.431212 -250.305062)
			(xy 40.410151 -250.319478) (xy 40.3645 -250.342301) (xy 40.315889 -250.357851) (xy 40.265468 -250.365763)
			(xy 40.23995 -250.366276) (xy 40.21443 -250.365783) (xy 40.164003 -250.35789) (xy 40.115391 -250.342331)
			(xy 40.069753 -250.319477) (xy 40.048688 -250.305062) (xy 40.042097 -250.300745) (xy 40.027097 -250.295958)
			(xy 40.019224 -250.295664) (xy 39.50335 -250.295664) (xy 39.498053 -250.295144) (xy 39.490479 -250.287741)
			(xy 39.489888 -250.282456) (xy 33.445704 -250.282456) (xy 33.445343 -250.287783) (xy 33.437822 -250.295327)
			(xy 33.432496 -250.295664) (xy 32.916622 -250.295664) (xy 32.908749 -250.295966) (xy 32.893745 -250.30074)
			(xy 32.887158 -250.305062) (xy 32.866084 -250.319458) (xy 32.820438 -250.342285) (xy 32.771831 -250.357842)
			(xy 32.721413 -250.365759) (xy 32.695896 -250.366276) (xy 32.670375 -250.36581) (xy 32.619947 -250.357909)
			(xy 32.571335 -250.342342) (xy 32.525698 -250.319481) (xy 32.504634 -250.305062) (xy 32.498033 -250.300763)
			(xy 32.48304 -250.295965) (xy 32.47517 -250.295664) (xy 31.959296 -250.295664) (xy 31.953952 -250.295371)
			(xy 31.946409 -250.287801) (xy 31.946088 -250.282456) (xy 25.901904 -250.282456) (xy 25.901543 -250.287783)
			(xy 25.894022 -250.295327) (xy 25.888696 -250.295664) (xy 25.372822 -250.295664) (xy 25.364949 -250.295966)
			(xy 25.349945 -250.30074) (xy 25.343358 -250.305062) (xy 25.322284 -250.319458) (xy 25.276638 -250.342285)
			(xy 25.228031 -250.357842) (xy 25.177613 -250.365759) (xy 25.152096 -250.366276) (xy 25.126575 -250.36581)
			(xy 25.076147 -250.357909) (xy 25.027535 -250.342342) (xy 24.981898 -250.319481) (xy 24.960834 -250.305062)
			(xy 24.954233 -250.300763) (xy 24.93924 -250.295965) (xy 24.93137 -250.295664) (xy 24.415496 -250.295664)
			(xy 24.410152 -250.295371) (xy 24.402609 -250.287801) (xy 24.402288 -250.282456) (xy 18.358104 -250.282456)
			(xy 18.357743 -250.287783) (xy 18.350222 -250.295327) (xy 18.344896 -250.295664) (xy 18.344388 -250.295664)
			(xy 17.828768 -250.295664) (xy 17.820893 -250.295943) (xy 17.805889 -250.300733) (xy 17.799304 -250.305062)
			(xy 17.778217 -250.319439) (xy 17.732575 -250.34227) (xy 17.683972 -250.357832) (xy 17.633558 -250.365756)
			(xy 17.608042 -250.366276) (xy 17.582522 -250.365787) (xy 17.532095 -250.357893) (xy 17.483483 -250.342333)
			(xy 17.437845 -250.319478) (xy 17.41678 -250.305062) (xy 17.410191 -250.300742) (xy 17.395189 -250.295957)
			(xy 17.387316 -250.295664) (xy 16.871442 -250.295664) (xy 16.866144 -250.295149) (xy 16.858571 -250.287742)
			(xy 16.85798 -250.282456) (xy 2.509012 -250.282456) (xy 2.509012 -251.13234) (xy 20.958048 -251.13234)
			(xy 20.958048 -250.637802) (xy 20.958382 -250.632365) (xy 20.966073 -250.624679) (xy 20.97151 -250.62434)
			(xy 21.487638 -250.62434) (xy 21.495447 -250.62401) (xy 21.510319 -250.619236) (xy 21.516848 -250.614942)
			(xy 21.537937 -250.600593) (xy 21.583598 -250.577862) (xy 21.632204 -250.562403) (xy 21.682607 -250.55458)
			(xy 21.733613 -250.55458) (xy 21.784016 -250.562403) (xy 21.832622 -250.577862) (xy 21.878283 -250.600593)
			(xy 21.899372 -250.614942) (xy 21.905914 -250.619216) (xy 21.920776 -250.624011) (xy 21.928582 -250.62434)
			(xy 22.44471 -250.62434) (xy 22.450076 -250.624844) (xy 22.457661 -250.632436) (xy 22.458172 -250.637802)
			(xy 22.458172 -251.13234) (xy 28.502356 -251.13234) (xy 28.502356 -250.637802) (xy 28.502826 -250.632494)
			(xy 28.510266 -250.624922) (xy 28.515564 -250.62434) (xy 29.031692 -250.62434) (xy 29.039503 -250.624033)
			(xy 29.054375 -250.619243) (xy 29.060902 -250.614942) (xy 29.081991 -250.600593) (xy 29.127652 -250.577862)
			(xy 29.176258 -250.562403) (xy 29.226661 -250.55458) (xy 29.277667 -250.55458) (xy 29.32807 -250.562403)
			(xy 29.376676 -250.577862) (xy 29.422337 -250.600593) (xy 29.443426 -250.614942) (xy 29.449956 -250.619236)
			(xy 29.464827 -250.624018) (xy 29.472636 -250.62434) (xy 29.988764 -250.62434) (xy 29.994103 -250.624656)
			(xy 30.001649 -250.632209) (xy 30.001972 -250.637548) (xy 30.001972 -250.638056) (xy 30.001972 -251.13234)
			(xy 36.046156 -251.13234) (xy 36.046156 -250.637802) (xy 36.046626 -250.632494) (xy 36.054066 -250.624922)
			(xy 36.059364 -250.62434) (xy 36.575492 -250.62434) (xy 36.583303 -250.624033) (xy 36.598175 -250.619243)
			(xy 36.604702 -250.614942) (xy 36.625791 -250.600593) (xy 36.671452 -250.577862) (xy 36.720058 -250.562403)
			(xy 36.770461 -250.55458) (xy 36.821467 -250.55458) (xy 36.87187 -250.562403) (xy 36.920476 -250.577862)
			(xy 36.966137 -250.600593) (xy 36.987226 -250.614942) (xy 36.993756 -250.619236) (xy 37.008627 -250.624018)
			(xy 37.016436 -250.62434) (xy 37.532564 -250.62434) (xy 37.537903 -250.624656) (xy 37.545449 -250.632209)
			(xy 37.545772 -250.637548) (xy 37.545772 -250.638056) (xy 37.545772 -251.13234) (xy 43.589956 -251.13234)
			(xy 43.589956 -250.637802) (xy 43.590283 -250.632363) (xy 43.597979 -250.624676) (xy 43.603418 -250.62434)
			(xy 44.119546 -250.62434) (xy 44.127355 -250.624013) (xy 44.142227 -250.619237) (xy 44.148756 -250.614942)
			(xy 44.169845 -250.600593) (xy 44.215506 -250.577862) (xy 44.264112 -250.562403) (xy 44.314515 -250.55458)
			(xy 44.365521 -250.55458) (xy 44.415924 -250.562403) (xy 44.46453 -250.577862) (xy 44.510191 -250.600593)
			(xy 44.53128 -250.614942) (xy 44.53782 -250.619219) (xy 44.552683 -250.624012) (xy 44.56049 -250.62434)
			(xy 45.076618 -250.62434) (xy 45.081985 -250.624838) (xy 45.08957 -250.632435) (xy 45.09008 -250.637802)
			(xy 45.09008 -251.13234) (xy 51.134264 -251.13234) (xy 51.134264 -250.637802) (xy 51.134727 -250.632492)
			(xy 51.142172 -250.62492) (xy 51.147472 -250.62434) (xy 51.6636 -250.62434) (xy 51.671411 -250.624036)
			(xy 51.686283 -250.619244) (xy 51.69281 -250.614942) (xy 51.713899 -250.600593) (xy 51.75956 -250.577862)
			(xy 51.808166 -250.562403) (xy 51.858569 -250.55458) (xy 51.909575 -250.55458) (xy 51.959978 -250.562403)
			(xy 52.008584 -250.577862) (xy 52.054245 -250.600593) (xy 52.075334 -250.614942) (xy 52.081862 -250.619239)
			(xy 52.096735 -250.62402) (xy 52.104544 -250.62434) (xy 52.620672 -250.62434) (xy 52.626012 -250.62465)
			(xy 52.633558 -250.632207) (xy 52.63388 -250.637548) (xy 52.63388 -250.638056) (xy 52.63388 -251.13234)
			(xy 58.678064 -251.13234) (xy 58.678064 -250.637802) (xy 58.678383 -250.632361) (xy 58.686085 -250.624674)
			(xy 58.691526 -250.62434) (xy 60.164726 -250.62434) (xy 60.170093 -250.624833) (xy 60.177678 -250.632433)
			(xy 60.178188 -250.637802) (xy 60.178188 -251.13234) (xy 167.778176 -251.13234) (xy 167.778176 -250.637802)
			(xy 167.778629 -250.63249) (xy 167.78608 -250.624916) (xy 167.791384 -250.62434) (xy 169.264584 -250.62434)
			(xy 169.269926 -250.624642) (xy 169.277471 -250.632205) (xy 169.277792 -250.637548) (xy 169.277792 -250.638056)
			(xy 169.277792 -251.13234) (xy 175.321976 -251.13234) (xy 175.321976 -250.637802) (xy 175.322285 -250.632358)
			(xy 175.329993 -250.62467) (xy 175.335438 -250.62434) (xy 175.851566 -250.62434) (xy 175.859376 -250.624022)
			(xy 175.874248 -250.61924) (xy 175.880776 -250.614942) (xy 175.901865 -250.600593) (xy 175.947526 -250.577862)
			(xy 175.996132 -250.562403) (xy 176.046535 -250.55458) (xy 176.097541 -250.55458) (xy 176.147944 -250.562403)
			(xy 176.19655 -250.577862) (xy 176.242211 -250.600593) (xy 176.2633 -250.614942) (xy 176.269836 -250.619226)
			(xy 176.284702 -250.624015) (xy 176.29251 -250.62434) (xy 176.808638 -250.62434) (xy 176.814007 -250.624826)
			(xy 176.82159 -250.632432) (xy 176.8221 -250.637802) (xy 176.8221 -251.13234) (xy 182.866284 -251.13234)
			(xy 182.866284 -250.637802) (xy 182.86673 -250.632488) (xy 182.874186 -250.624914) (xy 182.879492 -250.62434)
			(xy 183.39562 -250.62434) (xy 183.403432 -250.624045) (xy 183.418304 -250.619247) (xy 183.42483 -250.614942)
			(xy 183.445919 -250.600593) (xy 183.49158 -250.577862) (xy 183.540186 -250.562403) (xy 183.590589 -250.55458)
			(xy 183.641595 -250.55458) (xy 183.691998 -250.562403) (xy 183.740604 -250.577862) (xy 183.786265 -250.600593)
			(xy 183.807354 -250.614942) (xy 183.813878 -250.619247) (xy 183.828754 -250.624023) (xy 183.836564 -250.62434)
			(xy 184.352692 -250.62434) (xy 184.358035 -250.624637) (xy 184.365579 -250.632204) (xy 184.3659 -250.637548)
			(xy 184.3659 -250.638056) (xy 184.3659 -251.13234) (xy 190.410084 -251.13234) (xy 190.410084 -250.637802)
			(xy 190.410385 -250.632356) (xy 190.418099 -250.624668) (xy 190.423546 -250.62434) (xy 190.939674 -250.62434)
			(xy 190.947484 -250.624025) (xy 190.962356 -250.619241) (xy 190.968884 -250.614942) (xy 190.989973 -250.600593)
			(xy 191.035634 -250.577862) (xy 191.08424 -250.562403) (xy 191.134643 -250.55458) (xy 191.185649 -250.55458)
			(xy 191.236052 -250.562403) (xy 191.284658 -250.577862) (xy 191.330319 -250.600593) (xy 191.351408 -250.614942)
			(xy 191.357942 -250.619229) (xy 191.37281 -250.624016) (xy 191.380618 -250.62434) (xy 191.896746 -250.62434)
			(xy 191.902116 -250.62482) (xy 191.909699 -250.63243) (xy 191.910208 -250.637802) (xy 191.910208 -251.13234)
			(xy 197.954392 -251.13234) (xy 197.954392 -250.637802) (xy 197.954919 -250.632509) (xy 197.962319 -250.624941)
			(xy 197.9676 -250.62434) (xy 198.483728 -250.62434) (xy 198.49154 -250.624049) (xy 198.506412 -250.619248)
			(xy 198.512938 -250.614942) (xy 198.534027 -250.600593) (xy 198.579688 -250.577862) (xy 198.628294 -250.562403)
			(xy 198.678697 -250.55458) (xy 198.729703 -250.55458) (xy 198.780106 -250.562403) (xy 198.828712 -250.577862)
			(xy 198.874373 -250.600593) (xy 198.895462 -250.614942) (xy 198.902006 -250.619212) (xy 198.916866 -250.624009)
			(xy 198.924672 -250.62434) (xy 199.4408 -250.62434) (xy 199.446144 -250.624631) (xy 199.453688 -250.632203)
			(xy 199.454008 -250.637548) (xy 199.454008 -250.638056) (xy 199.454008 -251.13234) (xy 205.498192 -251.13234)
			(xy 205.498192 -250.637802) (xy 205.498719 -250.632509) (xy 205.506119 -250.624941) (xy 205.5114 -250.62434)
			(xy 206.027528 -250.62434) (xy 206.03534 -250.624049) (xy 206.050212 -250.619248) (xy 206.056738 -250.614942)
			(xy 206.077827 -250.600593) (xy 206.123488 -250.577862) (xy 206.172094 -250.562403) (xy 206.222497 -250.55458)
			(xy 206.273503 -250.55458) (xy 206.323906 -250.562403) (xy 206.372512 -250.577862) (xy 206.418173 -250.600593)
			(xy 206.439262 -250.614942) (xy 206.445806 -250.619212) (xy 206.460666 -250.624009) (xy 206.468472 -250.62434)
			(xy 206.9846 -250.62434) (xy 206.989944 -250.624631) (xy 206.997488 -250.632203) (xy 206.997808 -250.637548)
			(xy 206.997808 -250.638056) (xy 206.997808 -251.132086) (xy 268.898116 -251.132086) (xy 268.898116 -250.637548)
			(xy 268.898462 -250.632216) (xy 268.905993 -250.624671) (xy 268.911324 -250.62434) (xy 268.911832 -250.62434)
			(xy 269.427706 -250.62434) (xy 269.435517 -250.624039) (xy 269.450389 -250.619245) (xy 269.456916 -250.614942)
			(xy 269.478005 -250.600593) (xy 269.523666 -250.577862) (xy 269.572272 -250.562403) (xy 269.622675 -250.55458)
			(xy 269.673681 -250.55458) (xy 269.724084 -250.562403) (xy 269.77269 -250.577862) (xy 269.818351 -250.600593)
			(xy 269.83944 -250.614942) (xy 269.845967 -250.619242) (xy 269.86084 -250.624021) (xy 269.86865 -250.62434)
			(xy 270.384778 -250.62434) (xy 270.39008 -250.624838) (xy 270.397652 -250.632257) (xy 270.39824 -250.637548)
			(xy 270.39824 -251.132086) (xy 270.398225 -251.13234) (xy 276.442424 -251.13234) (xy 276.442424 -251.131832)
			(xy 276.442424 -250.637548) (xy 276.442762 -250.632214) (xy 276.450299 -250.624669) (xy 276.455632 -250.62434)
			(xy 276.97176 -250.62434) (xy 276.97957 -250.624019) (xy 276.994441 -250.619239) (xy 277.00097 -250.614942)
			(xy 277.022059 -250.600593) (xy 277.06772 -250.577862) (xy 277.116326 -250.562403) (xy 277.166729 -250.55458)
			(xy 277.217735 -250.55458) (xy 277.268138 -250.562403) (xy 277.316744 -250.577862) (xy 277.362405 -250.600593)
			(xy 277.383494 -250.614942) (xy 277.390031 -250.619224) (xy 277.404897 -250.624014) (xy 277.412704 -250.62434)
			(xy 277.928832 -250.62434) (xy 277.93418 -250.62461) (xy 277.941722 -250.632198) (xy 277.94204 -250.637548)
			(xy 277.94204 -251.132086) (xy 277.942017 -251.13234) (xy 283.986224 -251.13234) (xy 283.986224 -251.131832)
			(xy 283.986224 -250.637548) (xy 283.986562 -250.632214) (xy 283.994099 -250.624669) (xy 283.999432 -250.62434)
			(xy 284.51556 -250.62434) (xy 284.52337 -250.624019) (xy 284.538241 -250.619239) (xy 284.54477 -250.614942)
			(xy 284.565859 -250.600593) (xy 284.61152 -250.577862) (xy 284.660126 -250.562403) (xy 284.710529 -250.55458)
			(xy 284.761535 -250.55458) (xy 284.811938 -250.562403) (xy 284.860544 -250.577862) (xy 284.906205 -250.600593)
			(xy 284.927294 -250.614942) (xy 284.933831 -250.619224) (xy 284.948697 -250.624014) (xy 284.956504 -250.62434)
			(xy 285.472632 -250.62434) (xy 285.47798 -250.62461) (xy 285.485522 -250.632198) (xy 285.48584 -250.637548)
			(xy 285.48584 -251.132086) (xy 291.530024 -251.132086) (xy 291.530024 -250.637548) (xy 291.530362 -250.632214)
			(xy 291.537899 -250.624669) (xy 291.543232 -250.62434) (xy 291.54374 -250.62434) (xy 292.059614 -250.62434)
			(xy 292.067426 -250.624043) (xy 292.082298 -250.619247) (xy 292.088824 -250.614942) (xy 292.109913 -250.600593)
			(xy 292.155574 -250.577862) (xy 292.20418 -250.562403) (xy 292.254583 -250.55458) (xy 292.305589 -250.55458)
			(xy 292.355992 -250.562403) (xy 292.404598 -250.577862) (xy 292.450259 -250.600593) (xy 292.471348 -250.614942)
			(xy 292.477873 -250.619245) (xy 292.492748 -250.624022) (xy 292.500558 -250.62434) (xy 293.016686 -250.62434)
			(xy 293.021988 -250.624833) (xy 293.02956 -250.632256) (xy 293.030148 -250.637548) (xy 293.030148 -251.132086)
			(xy 293.030132 -251.13234) (xy 299.074332 -251.13234) (xy 299.074332 -251.131832) (xy 299.074332 -250.637548)
			(xy 299.074663 -250.632213) (xy 299.082205 -250.624666) (xy 299.08754 -250.62434) (xy 299.603668 -250.62434)
			(xy 299.611478 -250.624023) (xy 299.62635 -250.61924) (xy 299.632878 -250.614942) (xy 299.653967 -250.600593)
			(xy 299.699628 -250.577862) (xy 299.748234 -250.562403) (xy 299.798637 -250.55458) (xy 299.849643 -250.55458)
			(xy 299.900046 -250.562403) (xy 299.948652 -250.577862) (xy 299.994313 -250.600593) (xy 300.015402 -250.614942)
			(xy 300.021937 -250.619227) (xy 300.036804 -250.624015) (xy 300.044612 -250.62434) (xy 300.56074 -250.62434)
			(xy 300.56609 -250.624605) (xy 300.573631 -250.632197) (xy 300.573948 -250.637548) (xy 300.573948 -251.132086)
			(xy 306.618132 -251.132086) (xy 306.618132 -250.637548) (xy 306.618463 -250.632213) (xy 306.626005 -250.624666)
			(xy 306.63134 -250.62434) (xy 306.631848 -250.62434) (xy 308.104794 -250.62434) (xy 308.110097 -250.624827)
			(xy 308.117669 -250.632255) (xy 308.118256 -250.637548) (xy 308.118256 -251.132086) (xy 308.11824 -251.13234)
			(xy 415.718244 -251.13234) (xy 415.718244 -251.131832) (xy 415.718244 -250.637548) (xy 415.718822 -250.632302)
			(xy 415.72621 -250.62486) (xy 415.731452 -250.62434) (xy 417.204652 -250.62434) (xy 417.209989 -250.624664)
			(xy 417.217536 -250.632211) (xy 417.21786 -250.637548) (xy 417.21786 -251.132086) (xy 423.262044 -251.132086)
			(xy 423.262044 -250.637548) (xy 423.262622 -250.632302) (xy 423.27001 -250.62486) (xy 423.275252 -250.62434)
			(xy 423.27576 -250.62434) (xy 423.791634 -250.62434) (xy 423.799443 -250.624008) (xy 423.814315 -250.619236)
			(xy 423.820844 -250.614942) (xy 423.841933 -250.600593) (xy 423.887594 -250.577862) (xy 423.9362 -250.562403)
			(xy 423.986603 -250.55458) (xy 424.037609 -250.55458) (xy 424.088012 -250.562403) (xy 424.136618 -250.577862)
			(xy 424.182279 -250.600593) (xy 424.203368 -250.614942) (xy 424.209911 -250.619214) (xy 424.224772 -250.62401)
			(xy 424.232578 -250.62434) (xy 424.748706 -250.62434) (xy 424.754011 -250.624819) (xy 424.761582 -250.632253)
			(xy 424.762168 -250.637548) (xy 424.762168 -251.132086) (xy 424.762151 -251.13234) (xy 430.806352 -251.13234)
			(xy 430.806352 -251.131832) (xy 430.806352 -250.637548) (xy 430.806755 -250.632232) (xy 430.814246 -250.624691)
			(xy 430.81956 -250.62434) (xy 431.335688 -250.62434) (xy 431.343499 -250.624031) (xy 431.35837 -250.619243)
			(xy 431.364898 -250.614942) (xy 431.385987 -250.600593) (xy 431.431648 -250.577862) (xy 431.480254 -250.562403)
			(xy 431.530657 -250.55458) (xy 431.581663 -250.55458) (xy 431.632066 -250.562403) (xy 431.680672 -250.577862)
			(xy 431.726333 -250.600593) (xy 431.747422 -250.614942) (xy 431.753953 -250.619235) (xy 431.768823 -250.624018)
			(xy 431.776632 -250.62434) (xy 432.29276 -250.62434) (xy 432.298099 -250.624659) (xy 432.305645 -250.632209)
			(xy 432.305968 -250.637548) (xy 432.305968 -251.132086) (xy 438.350152 -251.132086) (xy 438.350152 -250.637548)
			(xy 438.350555 -250.632232) (xy 438.358046 -250.624691) (xy 438.36336 -250.62434) (xy 438.363868 -250.62434)
			(xy 438.879742 -250.62434) (xy 438.887551 -250.624012) (xy 438.902423 -250.619237) (xy 438.908952 -250.614942)
			(xy 438.930041 -250.600593) (xy 438.975702 -250.577862) (xy 439.024308 -250.562403) (xy 439.074711 -250.55458)
			(xy 439.125717 -250.55458) (xy 439.17612 -250.562403) (xy 439.224726 -250.577862) (xy 439.270387 -250.600593)
			(xy 439.291476 -250.614942) (xy 439.298017 -250.619217) (xy 439.31288 -250.624011) (xy 439.320686 -250.62434)
			(xy 439.836814 -250.62434) (xy 439.84212 -250.624814) (xy 439.84969 -250.632252) (xy 439.850276 -250.637548)
			(xy 439.850276 -251.132086) (xy 439.850251 -251.13234) (xy 445.89446 -251.13234) (xy 445.89446 -251.131832)
			(xy 445.89446 -250.637548) (xy 445.894856 -250.63223) (xy 445.902352 -250.624688) (xy 445.907668 -250.62434)
			(xy 446.423796 -250.62434) (xy 446.431607 -250.624035) (xy 446.446479 -250.619244) (xy 446.453006 -250.614942)
			(xy 446.474095 -250.600593) (xy 446.519756 -250.577862) (xy 446.568362 -250.562403) (xy 446.618765 -250.55458)
			(xy 446.669771 -250.55458) (xy 446.720174 -250.562403) (xy 446.76878 -250.577862) (xy 446.814441 -250.600593)
			(xy 446.83553 -250.614942) (xy 446.842059 -250.619238) (xy 446.856931 -250.624019) (xy 446.86474 -250.62434)
			(xy 447.380868 -250.62434) (xy 447.386208 -250.624653) (xy 447.393753 -250.632208) (xy 447.394076 -250.637548)
			(xy 447.394076 -251.132086) (xy 447.394052 -251.13234) (xy 453.43826 -251.13234) (xy 453.43826 -251.131832)
			(xy 453.43826 -250.637548) (xy 453.438656 -250.63223) (xy 453.446152 -250.624688) (xy 453.451468 -250.62434)
			(xy 453.967596 -250.62434) (xy 453.975407 -250.624035) (xy 453.990279 -250.619244) (xy 453.996806 -250.614942)
			(xy 454.017895 -250.600593) (xy 454.063556 -250.577862) (xy 454.112162 -250.562403) (xy 454.162565 -250.55458)
			(xy 454.213571 -250.55458) (xy 454.263974 -250.562403) (xy 454.31258 -250.577862) (xy 454.358241 -250.600593)
			(xy 454.37933 -250.614942) (xy 454.385859 -250.619238) (xy 454.400731 -250.624019) (xy 454.40854 -250.62434)
			(xy 454.924668 -250.62434) (xy 454.930008 -250.624653) (xy 454.937553 -250.632208) (xy 454.937876 -250.637548)
			(xy 454.937876 -251.132086) (xy 454.937369 -251.137385) (xy 454.929955 -251.144956) (xy 454.924668 -251.145548)
			(xy 454.408794 -251.145548) (xy 454.400983 -251.145851) (xy 454.386111 -251.150643) (xy 454.379584 -251.154946)
			(xy 454.358464 -251.169298) (xy 454.31274 -251.192024) (xy 454.264066 -251.207453) (xy 454.213599 -251.215219)
			(xy 454.188068 -251.215652) (xy 454.162537 -251.215234) (xy 454.112072 -251.207453) (xy 454.0634 -251.192018)
			(xy 454.017673 -251.169296) (xy 453.996552 -251.154946) (xy 453.990028 -251.150642) (xy 453.975152 -251.145866)
			(xy 453.967342 -251.145548) (xy 453.451468 -251.145548) (xy 453.446211 -251.145031) (xy 453.438773 -251.137597)
			(xy 453.43826 -251.13234) (xy 447.394052 -251.13234) (xy 447.393569 -251.137385) (xy 447.386155 -251.144956)
			(xy 447.380868 -251.145548) (xy 446.864994 -251.145548) (xy 446.857183 -251.145851) (xy 446.842311 -251.150643)
			(xy 446.835784 -251.154946) (xy 446.814664 -251.169298) (xy 446.76894 -251.192024) (xy 446.720266 -251.207453)
			(xy 446.669799 -251.215219) (xy 446.644268 -251.215652) (xy 446.618737 -251.215234) (xy 446.568272 -251.207453)
			(xy 446.5196 -251.192018) (xy 446.473873 -251.169296) (xy 446.452752 -251.154946) (xy 446.446228 -251.150642)
			(xy 446.431352 -251.145866) (xy 446.423542 -251.145548) (xy 445.907668 -251.145548) (xy 445.902411 -251.145031)
			(xy 445.894973 -251.137597) (xy 445.89446 -251.13234) (xy 439.850251 -251.13234) (xy 439.849742 -251.137445)
			(xy 439.842172 -251.145031) (xy 439.836814 -251.145548) (xy 439.32094 -251.145548) (xy 439.313131 -251.145871)
			(xy 439.298259 -251.15065) (xy 439.29173 -251.154946) (xy 439.270625 -251.169321) (xy 439.224895 -251.192042)
			(xy 439.176217 -251.207465) (xy 439.125746 -251.215223) (xy 439.100214 -251.215652) (xy 439.074684 -251.215211)
			(xy 439.02422 -251.207437) (xy 438.975548 -251.192009) (xy 438.92982 -251.169293) (xy 438.908698 -251.154946)
			(xy 438.902163 -251.15066) (xy 438.887296 -251.145873) (xy 438.879488 -251.145548) (xy 438.363614 -251.145548)
			(xy 438.358178 -251.14521) (xy 438.35049 -251.137522) (xy 438.350152 -251.132086) (xy 432.305968 -251.132086)
			(xy 432.305468 -251.137387) (xy 432.29805 -251.144958) (xy 432.29276 -251.145548) (xy 431.776886 -251.145548)
			(xy 431.769074 -251.145847) (xy 431.754203 -251.150642) (xy 431.747676 -251.154946) (xy 431.726558 -251.169301)
			(xy 431.680833 -251.192027) (xy 431.632159 -251.207455) (xy 431.581691 -251.21522) (xy 431.55616 -251.215652)
			(xy 431.530629 -251.215238) (xy 431.480164 -251.207455) (xy 431.431492 -251.19202) (xy 431.385765 -251.169297)
			(xy 431.364644 -251.154946) (xy 431.358121 -251.150639) (xy 431.343245 -251.145865) (xy 431.335434 -251.145548)
			(xy 430.81956 -251.145548) (xy 430.814302 -251.145036) (xy 430.806864 -251.137598) (xy 430.806352 -251.13234)
			(xy 424.762151 -251.13234) (xy 424.761812 -251.137517) (xy 424.754137 -251.145204) (xy 424.748706 -251.145548)
			(xy 424.232832 -251.145548) (xy 424.225022 -251.145867) (xy 424.210151 -251.150649) (xy 424.203622 -251.154946)
			(xy 424.182491 -251.169281) (xy 424.136771 -251.192011) (xy 424.0881 -251.207445) (xy 424.037636 -251.215216)
			(xy 424.012106 -251.215652) (xy 423.986576 -251.215215) (xy 423.936112 -251.207439) (xy 423.887439 -251.192011)
			(xy 423.841712 -251.169294) (xy 423.82059 -251.154946) (xy 423.814057 -251.150657) (xy 423.799188 -251.145872)
			(xy 423.79138 -251.145548) (xy 423.275506 -251.145548) (xy 423.270069 -251.145215) (xy 423.262381 -251.137524)
			(xy 423.262044 -251.132086) (xy 417.21786 -251.132086) (xy 417.217367 -251.137388) (xy 417.209944 -251.14496)
			(xy 417.204652 -251.145548) (xy 415.731452 -251.145548) (xy 415.726193 -251.145041) (xy 415.718756 -251.137599)
			(xy 415.718244 -251.13234) (xy 308.11824 -251.13234) (xy 308.117911 -251.13752) (xy 308.110228 -251.145207)
			(xy 308.104794 -251.145548) (xy 306.631594 -251.145548) (xy 306.626155 -251.145223) (xy 306.618469 -251.137525)
			(xy 306.618132 -251.132086) (xy 300.573948 -251.132086) (xy 300.573466 -251.137391) (xy 300.566035 -251.144964)
			(xy 300.56074 -251.145548) (xy 300.044866 -251.145548) (xy 300.037058 -251.145882) (xy 300.022186 -251.150653)
			(xy 300.015656 -251.154946) (xy 299.994544 -251.16931) (xy 299.948817 -251.192033) (xy 299.90014 -251.207459)
			(xy 299.849672 -251.215221) (xy 299.82414 -251.215652) (xy 299.79861 -251.215198) (xy 299.748147 -251.207428)
			(xy 299.699475 -251.192004) (xy 299.653746 -251.169292) (xy 299.632624 -251.154946) (xy 299.626084 -251.15067)
			(xy 299.611221 -251.145877) (xy 299.603414 -251.145548) (xy 299.08754 -251.145548) (xy 299.082292 -251.144983)
			(xy 299.074849 -251.137585) (xy 299.074332 -251.13234) (xy 293.030132 -251.13234) (xy 293.02981 -251.137522)
			(xy 293.022122 -251.14521) (xy 293.016686 -251.145548) (xy 292.500812 -251.145548) (xy 292.493002 -251.145859)
			(xy 292.47813 -251.150646) (xy 292.471602 -251.154946) (xy 292.450477 -251.16929) (xy 292.404754 -251.192018)
			(xy 292.356082 -251.20745) (xy 292.305617 -251.215218) (xy 292.280086 -251.215652) (xy 292.254555 -251.215225)
			(xy 292.204091 -251.207446) (xy 292.155419 -251.192015) (xy 292.109691 -251.169295) (xy 292.08857 -251.154946)
			(xy 292.082042 -251.150649) (xy 292.067169 -251.145869) (xy 292.05936 -251.145548) (xy 291.543486 -251.145548)
			(xy 291.538117 -251.145057) (xy 291.530531 -251.137456) (xy 291.530024 -251.132086) (xy 285.48584 -251.132086)
			(xy 285.485365 -251.137393) (xy 285.477929 -251.144966) (xy 285.472632 -251.145548) (xy 284.956758 -251.145548)
			(xy 284.948949 -251.145878) (xy 284.934077 -251.150652) (xy 284.927548 -251.154946) (xy 284.906438 -251.169313)
			(xy 284.86071 -251.192036) (xy 284.812033 -251.207461) (xy 284.761564 -251.215222) (xy 284.736032 -251.215652)
			(xy 284.710502 -251.215202) (xy 284.660039 -251.20743) (xy 284.611366 -251.192005) (xy 284.565638 -251.169292)
			(xy 284.544516 -251.154946) (xy 284.537977 -251.150667) (xy 284.523113 -251.145876) (xy 284.515306 -251.145548)
			(xy 283.999432 -251.145548) (xy 283.994183 -251.144988) (xy 283.98674 -251.137587) (xy 283.986224 -251.13234)
			(xy 277.942017 -251.13234) (xy 277.941565 -251.137393) (xy 277.934129 -251.144966) (xy 277.928832 -251.145548)
			(xy 277.412958 -251.145548) (xy 277.405149 -251.145878) (xy 277.390277 -251.150652) (xy 277.383748 -251.154946)
			(xy 277.362638 -251.169313) (xy 277.31691 -251.192036) (xy 277.268233 -251.207461) (xy 277.217764 -251.215222)
			(xy 277.192232 -251.215652) (xy 277.166702 -251.215202) (xy 277.116239 -251.20743) (xy 277.067566 -251.192005)
			(xy 277.021838 -251.169292) (xy 277.000716 -251.154946) (xy 276.994177 -251.150667) (xy 276.979313 -251.145876)
			(xy 276.971506 -251.145548) (xy 276.455632 -251.145548) (xy 276.450383 -251.144988) (xy 276.44294 -251.137587)
			(xy 276.442424 -251.13234) (xy 270.398225 -251.13234) (xy 270.397909 -251.137524) (xy 270.390216 -251.145212)
			(xy 270.384778 -251.145548) (xy 269.868904 -251.145548) (xy 269.861093 -251.145856) (xy 269.846222 -251.150645)
			(xy 269.839694 -251.154946) (xy 269.818571 -251.169293) (xy 269.772848 -251.192021) (xy 269.724175 -251.207451)
			(xy 269.673709 -251.215219) (xy 269.648178 -251.215652) (xy 269.622647 -251.215229) (xy 269.572183 -251.207449)
			(xy 269.52351 -251.192016) (xy 269.477783 -251.169296) (xy 269.456662 -251.154946) (xy 269.450135 -251.150646)
			(xy 269.435262 -251.145868) (xy 269.427452 -251.145548) (xy 268.911578 -251.145548) (xy 268.906208 -251.145063)
			(xy 268.898623 -251.137457) (xy 268.898116 -251.132086) (xy 206.997808 -251.132086) (xy 206.997808 -251.13234)
			(xy 206.997332 -251.137608) (xy 206.989869 -251.145048) (xy 206.9846 -251.145548) (xy 206.468726 -251.145548)
			(xy 206.460849 -251.145812) (xy 206.445845 -251.150612) (xy 206.439262 -251.154946) (xy 206.418185 -251.169339)
			(xy 206.37254 -251.192167) (xy 206.323934 -251.207724) (xy 206.273517 -251.215643) (xy 206.248 -251.21616)
			(xy 206.222479 -251.215695) (xy 206.172051 -251.207794) (xy 206.123439 -251.192227) (xy 206.077802 -251.169365)
			(xy 206.056738 -251.154946) (xy 206.050137 -251.150647) (xy 206.035144 -251.14585) (xy 206.027274 -251.145548)
			(xy 205.5114 -251.145548) (xy 205.506147 -251.145009) (xy 205.498707 -251.137592) (xy 205.498192 -251.13234)
			(xy 199.454008 -251.13234) (xy 199.453532 -251.137608) (xy 199.446069 -251.145048) (xy 199.4408 -251.145548)
			(xy 198.924926 -251.145548) (xy 198.917049 -251.145812) (xy 198.902045 -251.150612) (xy 198.895462 -251.154946)
			(xy 198.874385 -251.169339) (xy 198.82874 -251.192167) (xy 198.780134 -251.207724) (xy 198.729717 -251.215643)
			(xy 198.7042 -251.21616) (xy 198.678679 -251.215695) (xy 198.628251 -251.207794) (xy 198.579639 -251.192227)
			(xy 198.534002 -251.169365) (xy 198.512938 -251.154946) (xy 198.506337 -251.150647) (xy 198.491344 -251.14585)
			(xy 198.483474 -251.145548) (xy 197.9676 -251.145548) (xy 197.962347 -251.145009) (xy 197.954907 -251.137592)
			(xy 197.954392 -251.13234) (xy 191.910208 -251.13234) (xy 191.909732 -251.137608) (xy 191.902269 -251.145048)
			(xy 191.897 -251.145548) (xy 191.896492 -251.145548) (xy 191.380872 -251.145548) (xy 191.372997 -251.145832)
			(xy 191.357993 -251.150618) (xy 191.351408 -251.154946) (xy 191.330346 -251.169362) (xy 191.284696 -251.192185)
			(xy 191.236085 -251.207736) (xy 191.185664 -251.215647) (xy 191.160146 -251.21616) (xy 191.134626 -251.215672)
			(xy 191.084198 -251.207778) (xy 191.035587 -251.192218) (xy 190.989949 -251.169362) (xy 190.968884 -251.154946)
			(xy 190.962295 -251.150627) (xy 190.947293 -251.145842) (xy 190.93942 -251.145548) (xy 190.423546 -251.145548)
			(xy 190.418244 -251.145045) (xy 190.41067 -251.13763) (xy 190.410084 -251.13234) (xy 184.3659 -251.13234)
			(xy 184.365431 -251.13761) (xy 184.357963 -251.14505) (xy 184.352692 -251.145548) (xy 183.836818 -251.145548)
			(xy 183.828945 -251.145851) (xy 183.813941 -251.150624) (xy 183.807354 -251.154946) (xy 183.78628 -251.169342)
			(xy 183.740634 -251.19217) (xy 183.692027 -251.207726) (xy 183.641609 -251.215644) (xy 183.616092 -251.21616)
			(xy 183.590573 -251.215649) (xy 183.540146 -251.207762) (xy 183.491534 -251.192208) (xy 183.445895 -251.169359)
			(xy 183.42483 -251.154946) (xy 183.418231 -251.150644) (xy 183.403237 -251.145849) (xy 183.395366 -251.145548)
			(xy 182.879492 -251.145548) (xy 182.874238 -251.145015) (xy 182.866798 -251.137593) (xy 182.866284 -251.13234)
			(xy 176.8221 -251.13234) (xy 176.821631 -251.13761) (xy 176.814163 -251.14505) (xy 176.808892 -251.145548)
			(xy 176.808384 -251.145548) (xy 176.292764 -251.145548) (xy 176.284889 -251.145828) (xy 176.269885 -251.150617)
			(xy 176.2633 -251.154946) (xy 176.242213 -251.169322) (xy 176.196571 -251.192154) (xy 176.147968 -251.207716)
			(xy 176.097554 -251.21564) (xy 176.072038 -251.21616) (xy 176.046518 -251.215676) (xy 175.99609 -251.207781)
			(xy 175.947478 -251.192219) (xy 175.90184 -251.169362) (xy 175.880776 -251.154946) (xy 175.874189 -251.150623)
			(xy 175.859186 -251.145841) (xy 175.851312 -251.145548) (xy 175.335438 -251.145548) (xy 175.330136 -251.14505)
			(xy 175.322562 -251.137631) (xy 175.321976 -251.13234) (xy 169.277792 -251.13234) (xy 169.27733 -251.137612)
			(xy 169.269858 -251.145053) (xy 169.264584 -251.145548) (xy 167.791384 -251.145548) (xy 167.786129 -251.14502)
			(xy 167.778689 -251.137594) (xy 167.778176 -251.13234) (xy 60.178188 -251.13234) (xy 60.17773 -251.137613)
			(xy 60.170255 -251.145054) (xy 60.16498 -251.145548) (xy 60.164472 -251.145548) (xy 58.691526 -251.145548)
			(xy 58.686222 -251.145058) (xy 58.678649 -251.137633) (xy 58.678064 -251.13234) (xy 52.63388 -251.13234)
			(xy 52.633429 -251.137614) (xy 52.625949 -251.145056) (xy 52.620672 -251.145548) (xy 52.104798 -251.145548)
			(xy 52.096924 -251.145843) (xy 52.08192 -251.150622) (xy 52.075334 -251.154946) (xy 52.054265 -251.169351)
			(xy 52.008617 -251.192176) (xy 51.960009 -251.20773) (xy 51.909589 -251.215645) (xy 51.884072 -251.21616)
			(xy 51.858552 -251.215659) (xy 51.808125 -251.207769) (xy 51.759514 -251.192212) (xy 51.713875 -251.16936)
			(xy 51.69281 -251.154946) (xy 51.686215 -251.150637) (xy 51.671218 -251.145846) (xy 51.663346 -251.145548)
			(xy 51.147472 -251.145548) (xy 51.142215 -251.145028) (xy 51.134777 -251.137596) (xy 51.134264 -251.13234)
			(xy 45.09008 -251.13234) (xy 45.089629 -251.137614) (xy 45.082149 -251.145056) (xy 45.076872 -251.145548)
			(xy 45.076364 -251.145548) (xy 44.560744 -251.145548) (xy 44.552868 -251.145819) (xy 44.537864 -251.150614)
			(xy 44.53128 -251.154946) (xy 44.510198 -251.169331) (xy 44.464555 -251.192161) (xy 44.41595 -251.207721)
			(xy 44.365534 -251.215642) (xy 44.340018 -251.21616) (xy 44.314497 -251.215686) (xy 44.264069 -251.207788)
			(xy 44.215458 -251.192223) (xy 44.16982 -251.169364) (xy 44.148756 -251.154946) (xy 44.142173 -251.150616)
			(xy 44.127167 -251.145838) (xy 44.119292 -251.145548) (xy 43.603418 -251.145548) (xy 43.598113 -251.145064)
			(xy 43.59054 -251.137635) (xy 43.589956 -251.13234) (xy 37.545772 -251.13234) (xy 37.545328 -251.137616)
			(xy 37.537843 -251.145059) (xy 37.532564 -251.145548) (xy 37.01669 -251.145548) (xy 37.008816 -251.145839)
			(xy 36.993812 -251.150621) (xy 36.987226 -251.154946) (xy 36.966159 -251.169354) (xy 36.920511 -251.192179)
			(xy 36.871901 -251.207732) (xy 36.821482 -251.215646) (xy 36.795964 -251.21616) (xy 36.770444 -251.215663)
			(xy 36.720017 -251.207772) (xy 36.671405 -251.192214) (xy 36.625767 -251.169361) (xy 36.604702 -251.154946)
			(xy 36.598109 -251.150633) (xy 36.58311 -251.145844) (xy 36.575238 -251.145548) (xy 36.059364 -251.145548)
			(xy 36.054107 -251.145033) (xy 36.046668 -251.137597) (xy 36.046156 -251.13234) (xy 30.001972 -251.13234)
			(xy 30.001528 -251.137616) (xy 29.994043 -251.145059) (xy 29.988764 -251.145548) (xy 29.47289 -251.145548)
			(xy 29.465016 -251.145839) (xy 29.450012 -251.150621) (xy 29.443426 -251.154946) (xy 29.422359 -251.169354)
			(xy 29.376711 -251.192179) (xy 29.328101 -251.207732) (xy 29.277682 -251.215646) (xy 29.252164 -251.21616)
			(xy 29.226644 -251.215663) (xy 29.176217 -251.207772) (xy 29.127605 -251.192214) (xy 29.081967 -251.169361)
			(xy 29.060902 -251.154946) (xy 29.054309 -251.150633) (xy 29.03931 -251.145844) (xy 29.031438 -251.145548)
			(xy 28.515564 -251.145548) (xy 28.510307 -251.145033) (xy 28.502868 -251.137597) (xy 28.502356 -251.13234)
			(xy 22.458172 -251.13234) (xy 22.457728 -251.137616) (xy 22.450243 -251.145059) (xy 22.444964 -251.145548)
			(xy 22.444456 -251.145548) (xy 21.928836 -251.145548) (xy 21.92096 -251.145816) (xy 21.905956 -251.150613)
			(xy 21.899372 -251.154946) (xy 21.878293 -251.169334) (xy 21.832648 -251.192164) (xy 21.784043 -251.207722)
			(xy 21.733627 -251.215642) (xy 21.70811 -251.21616) (xy 21.682589 -251.21569) (xy 21.632161 -251.20779)
			(xy 21.583549 -251.192225) (xy 21.537912 -251.169364) (xy 21.516848 -251.154946) (xy 21.510267 -251.150613)
			(xy 21.495259 -251.145836) (xy 21.487384 -251.145548) (xy 20.97151 -251.145548) (xy 20.966204 -251.145069)
			(xy 20.958632 -251.137636) (xy 20.958048 -251.13234) (xy 2.509012 -251.13234) (xy 2.509012 -251.982478)
			(xy 16.85798 -251.982478) (xy 16.85798 -251.48794) (xy 16.858353 -251.482616) (xy 16.865865 -251.475074)
			(xy 16.871188 -251.474732) (xy 16.871696 -251.474732) (xy 17.38757 -251.474732) (xy 17.39538 -251.474417)
			(xy 17.410252 -251.469633) (xy 17.41678 -251.465334) (xy 17.437869 -251.450985) (xy 17.48353 -251.428254)
			(xy 17.532136 -251.412795) (xy 17.582539 -251.404972) (xy 17.633545 -251.404972) (xy 17.683948 -251.412795)
			(xy 17.732554 -251.428254) (xy 17.778215 -251.450985) (xy 17.799304 -251.465334) (xy 17.805839 -251.469619)
			(xy 17.820706 -251.474407) (xy 17.828514 -251.474732) (xy 18.344642 -251.474732) (xy 18.34995 -251.475194)
			(xy 18.357518 -251.482641) (xy 18.358104 -251.48794) (xy 18.358104 -251.982478) (xy 18.358077 -251.982732)
			(xy 24.402288 -251.982732) (xy 24.402288 -251.982224) (xy 24.402288 -251.48794) (xy 24.402653 -251.482614)
			(xy 24.410171 -251.475071) (xy 24.415496 -251.474732) (xy 24.931624 -251.474732) (xy 24.939436 -251.47444)
			(xy 24.954308 -251.46964) (xy 24.960834 -251.465334) (xy 24.981923 -251.450985) (xy 25.027584 -251.428254)
			(xy 25.07619 -251.412795) (xy 25.126593 -251.404972) (xy 25.177599 -251.404972) (xy 25.228002 -251.412795)
			(xy 25.276608 -251.428254) (xy 25.322269 -251.450985) (xy 25.343358 -251.465334) (xy 25.349881 -251.46964)
			(xy 25.364757 -251.474415) (xy 25.372568 -251.474732) (xy 25.888696 -251.474732) (xy 25.894037 -251.475034)
			(xy 25.901581 -251.482598) (xy 25.901904 -251.48794) (xy 25.901904 -251.982478) (xy 25.901878 -251.982732)
			(xy 31.946088 -251.982732) (xy 31.946088 -251.982224) (xy 31.946088 -251.48794) (xy 31.946453 -251.482614)
			(xy 31.953971 -251.475071) (xy 31.959296 -251.474732) (xy 32.475424 -251.474732) (xy 32.483236 -251.47444)
			(xy 32.498108 -251.46964) (xy 32.504634 -251.465334) (xy 32.525723 -251.450985) (xy 32.571384 -251.428254)
			(xy 32.61999 -251.412795) (xy 32.670393 -251.404972) (xy 32.721399 -251.404972) (xy 32.771802 -251.412795)
			(xy 32.820408 -251.428254) (xy 32.866069 -251.450985) (xy 32.887158 -251.465334) (xy 32.893681 -251.46964)
			(xy 32.908557 -251.474415) (xy 32.916368 -251.474732) (xy 33.432496 -251.474732) (xy 33.437837 -251.475034)
			(xy 33.445381 -251.482598) (xy 33.445704 -251.48794) (xy 33.445704 -251.982478) (xy 39.489888 -251.982478)
			(xy 39.489888 -251.48794) (xy 39.490253 -251.482614) (xy 39.497771 -251.475071) (xy 39.503096 -251.474732)
			(xy 39.503604 -251.474732) (xy 40.019478 -251.474732) (xy 40.027288 -251.47442) (xy 40.04216 -251.469634)
			(xy 40.048688 -251.465334) (xy 40.069777 -251.450985) (xy 40.115438 -251.428254) (xy 40.164044 -251.412795)
			(xy 40.214447 -251.404972) (xy 40.265453 -251.404972) (xy 40.315856 -251.412795) (xy 40.364462 -251.428254)
			(xy 40.410123 -251.450985) (xy 40.431212 -251.465334) (xy 40.437745 -251.469622) (xy 40.452614 -251.474408)
			(xy 40.460422 -251.474732) (xy 40.97655 -251.474732) (xy 40.981846 -251.475256) (xy 40.98942 -251.482656)
			(xy 40.990012 -251.48794) (xy 40.990012 -251.982478) (xy 40.989985 -251.982732) (xy 47.034196 -251.982732)
			(xy 47.034196 -251.982224) (xy 47.034196 -251.48794) (xy 47.034554 -251.482612) (xy 47.042077 -251.475069)
			(xy 47.047404 -251.474732) (xy 47.563532 -251.474732) (xy 47.571341 -251.474401) (xy 47.586213 -251.469628)
			(xy 47.592742 -251.465334) (xy 47.613831 -251.450985) (xy 47.659492 -251.428254) (xy 47.708098 -251.412795)
			(xy 47.758501 -251.404972) (xy 47.809507 -251.404972) (xy 47.85991 -251.412795) (xy 47.908516 -251.428254)
			(xy 47.954177 -251.450985) (xy 47.975266 -251.465334) (xy 47.98181 -251.469605) (xy 47.99667 -251.474402)
			(xy 48.004476 -251.474732) (xy 48.520604 -251.474732) (xy 48.525947 -251.475028) (xy 48.53349 -251.482596)
			(xy 48.533812 -251.48794) (xy 48.533812 -251.982478) (xy 54.577996 -251.982478) (xy 54.577996 -251.48794)
			(xy 54.578354 -251.482612) (xy 54.585877 -251.475069) (xy 54.591204 -251.474732) (xy 54.591712 -251.474732)
			(xy 56.064658 -251.474732) (xy 56.069955 -251.47525) (xy 56.077528 -251.482655) (xy 56.07812 -251.48794)
			(xy 56.07812 -251.982478) (xy 56.078105 -251.982732) (xy 163.678108 -251.982732) (xy 163.678108 -251.982224)
			(xy 163.678108 -251.48794) (xy 163.678455 -251.482609) (xy 163.685986 -251.475065) (xy 163.691316 -251.474732)
			(xy 165.164516 -251.474732) (xy 165.16986 -251.47502) (xy 165.177403 -251.482594) (xy 165.177724 -251.48794)
			(xy 165.177724 -251.982478) (xy 171.221908 -251.982478) (xy 171.221908 -251.48794) (xy 171.222255 -251.482609)
			(xy 171.229786 -251.475065) (xy 171.235116 -251.474732) (xy 171.235624 -251.474732) (xy 171.751498 -251.474732)
			(xy 171.759309 -251.474429) (xy 171.774181 -251.469637) (xy 171.780708 -251.465334) (xy 171.801797 -251.450985)
			(xy 171.847458 -251.428254) (xy 171.896064 -251.412795) (xy 171.946467 -251.404972) (xy 171.997473 -251.404972)
			(xy 172.047876 -251.412795) (xy 172.096482 -251.428254) (xy 172.142143 -251.450985) (xy 172.163232 -251.465334)
			(xy 172.169761 -251.46963) (xy 172.184633 -251.474411) (xy 172.192442 -251.474732) (xy 172.70857 -251.474732)
			(xy 172.713869 -251.475242) (xy 172.721441 -251.482653) (xy 172.722032 -251.48794) (xy 172.722032 -251.982478)
			(xy 172.722017 -251.982732) (xy 178.766216 -251.982732) (xy 178.766216 -251.982224) (xy 178.766216 -251.48794)
			(xy 178.766556 -251.482607) (xy 178.774092 -251.475063) (xy 178.779424 -251.474732) (xy 179.295552 -251.474732)
			(xy 179.303361 -251.474409) (xy 179.318233 -251.469631) (xy 179.324762 -251.465334) (xy 179.345851 -251.450985)
			(xy 179.391512 -251.428254) (xy 179.440118 -251.412795) (xy 179.490521 -251.404972) (xy 179.541527 -251.404972)
			(xy 179.59193 -251.412795) (xy 179.640536 -251.428254) (xy 179.686197 -251.450985) (xy 179.707286 -251.465334)
			(xy 179.713825 -251.469612) (xy 179.728689 -251.474405) (xy 179.736496 -251.474732) (xy 180.252624 -251.474732)
			(xy 180.257969 -251.475015) (xy 180.265511 -251.482593) (xy 180.265832 -251.48794) (xy 180.265832 -251.982478)
			(xy 186.310016 -251.982478) (xy 186.310016 -251.48794) (xy 186.310356 -251.482607) (xy 186.317892 -251.475063)
			(xy 186.323224 -251.474732) (xy 186.323732 -251.474732) (xy 186.839606 -251.474732) (xy 186.847418 -251.474432)
			(xy 186.862289 -251.469638) (xy 186.868816 -251.465334) (xy 186.889905 -251.450985) (xy 186.935566 -251.428254)
			(xy 186.984172 -251.412795) (xy 187.034575 -251.404972) (xy 187.085581 -251.404972) (xy 187.135984 -251.412795)
			(xy 187.18459 -251.428254) (xy 187.230251 -251.450985) (xy 187.25134 -251.465334) (xy 187.257867 -251.469633)
			(xy 187.27274 -251.474412) (xy 187.28055 -251.474732) (xy 187.796678 -251.474732) (xy 187.801978 -251.475237)
			(xy 187.80955 -251.482651) (xy 187.81014 -251.48794) (xy 187.81014 -251.982478) (xy 187.810124 -251.982732)
			(xy 193.854324 -251.982732) (xy 193.854324 -251.982224) (xy 193.854324 -251.48794) (xy 193.854657 -251.482605)
			(xy 193.862198 -251.47506) (xy 193.867532 -251.474732) (xy 194.38366 -251.474732) (xy 194.39147 -251.474413)
			(xy 194.406342 -251.469632) (xy 194.41287 -251.465334) (xy 194.433959 -251.450985) (xy 194.47962 -251.428254)
			(xy 194.528226 -251.412795) (xy 194.578629 -251.404972) (xy 194.629635 -251.404972) (xy 194.680038 -251.412795)
			(xy 194.728644 -251.428254) (xy 194.774305 -251.450985) (xy 194.795394 -251.465334) (xy 194.801931 -251.469615)
			(xy 194.816797 -251.474406) (xy 194.824604 -251.474732) (xy 195.340732 -251.474732) (xy 195.346078 -251.475009)
			(xy 195.35362 -251.482592) (xy 195.35394 -251.48794) (xy 195.35394 -251.982478) (xy 195.353917 -251.982732)
			(xy 201.398124 -251.982732) (xy 201.398124 -251.982224) (xy 201.398124 -251.48794) (xy 201.398457 -251.482605)
			(xy 201.405998 -251.47506) (xy 201.411332 -251.474732) (xy 201.92746 -251.474732) (xy 201.93527 -251.474413)
			(xy 201.950142 -251.469632) (xy 201.95667 -251.465334) (xy 201.977759 -251.450985) (xy 202.02342 -251.428254)
			(xy 202.072026 -251.412795) (xy 202.122429 -251.404972) (xy 202.173435 -251.404972) (xy 202.223838 -251.412795)
			(xy 202.272444 -251.428254) (xy 202.318105 -251.450985) (xy 202.339194 -251.465334) (xy 202.345731 -251.469615)
			(xy 202.360597 -251.474406) (xy 202.368404 -251.474732) (xy 202.884532 -251.474732) (xy 202.889878 -251.475009)
			(xy 202.89742 -251.482592) (xy 202.89774 -251.48794) (xy 202.89774 -251.982224) (xy 264.798048 -251.982224)
			(xy 264.798048 -251.487686) (xy 264.798542 -251.482318) (xy 264.806141 -251.474733) (xy 264.81151 -251.474224)
			(xy 265.327638 -251.474224) (xy 265.335447 -251.473897) (xy 265.350319 -251.469122) (xy 265.356848 -251.464826)
			(xy 265.377937 -251.450477) (xy 265.423598 -251.427746) (xy 265.472204 -251.412287) (xy 265.522607 -251.404464)
			(xy 265.573613 -251.404464) (xy 265.624016 -251.412287) (xy 265.672622 -251.427746) (xy 265.718283 -251.450477)
			(xy 265.739372 -251.464826) (xy 265.745915 -251.469098) (xy 265.760776 -251.473894) (xy 265.768582 -251.474224)
			(xy 266.28471 -251.474224) (xy 266.290072 -251.474742) (xy 266.297656 -251.482324) (xy 266.298172 -251.487686)
			(xy 266.298172 -251.982224) (xy 272.342356 -251.982224) (xy 272.342356 -251.487686) (xy 272.342816 -251.482376)
			(xy 272.350263 -251.474805) (xy 272.355564 -251.474224) (xy 272.871692 -251.474224) (xy 272.879503 -251.47392)
			(xy 272.894375 -251.469129) (xy 272.900902 -251.464826) (xy 272.921991 -251.450477) (xy 272.967652 -251.427746)
			(xy 273.016258 -251.412287) (xy 273.066661 -251.404464) (xy 273.117667 -251.404464) (xy 273.16807 -251.412287)
			(xy 273.216676 -251.427746) (xy 273.262337 -251.450477) (xy 273.283426 -251.464826) (xy 273.289957 -251.469119)
			(xy 273.304827 -251.473902) (xy 273.312636 -251.474224) (xy 273.828764 -251.474224) (xy 273.834099 -251.474554)
			(xy 273.841644 -251.482097) (xy 273.841972 -251.487432) (xy 273.841972 -251.48794) (xy 273.841972 -251.982224)
			(xy 279.886156 -251.982224) (xy 279.886156 -251.487686) (xy 279.886616 -251.482376) (xy 279.894063 -251.474805)
			(xy 279.899364 -251.474224) (xy 280.415492 -251.474224) (xy 280.423303 -251.47392) (xy 280.438175 -251.469129)
			(xy 280.444702 -251.464826) (xy 280.465791 -251.450477) (xy 280.511452 -251.427746) (xy 280.560058 -251.412287)
			(xy 280.610461 -251.404464) (xy 280.661467 -251.404464) (xy 280.71187 -251.412287) (xy 280.760476 -251.427746)
			(xy 280.806137 -251.450477) (xy 280.827226 -251.464826) (xy 280.833757 -251.469119) (xy 280.848627 -251.473902)
			(xy 280.856436 -251.474224) (xy 281.372564 -251.474224) (xy 281.377899 -251.474554) (xy 281.385444 -251.482097)
			(xy 281.385772 -251.487432) (xy 281.385772 -251.48794) (xy 281.385772 -251.982224) (xy 287.429956 -251.982224)
			(xy 287.429956 -251.487686) (xy 287.430272 -251.482245) (xy 287.437976 -251.474559) (xy 287.443418 -251.474224)
			(xy 287.959546 -251.474224) (xy 287.967355 -251.4739) (xy 287.982227 -251.469123) (xy 287.988756 -251.464826)
			(xy 288.009845 -251.450477) (xy 288.055506 -251.427746) (xy 288.104112 -251.412287) (xy 288.154515 -251.404464)
			(xy 288.205521 -251.404464) (xy 288.255924 -251.412287) (xy 288.30453 -251.427746) (xy 288.350191 -251.450477)
			(xy 288.37128 -251.464826) (xy 288.377821 -251.469101) (xy 288.392684 -251.473896) (xy 288.40049 -251.474224)
			(xy 288.916618 -251.474224) (xy 288.921981 -251.474737) (xy 288.929565 -251.482323) (xy 288.93008 -251.487686)
			(xy 288.93008 -251.982224) (xy 294.974264 -251.982224) (xy 294.974264 -251.487686) (xy 294.974717 -251.482375)
			(xy 294.982169 -251.474803) (xy 294.987472 -251.474224) (xy 295.5036 -251.474224) (xy 295.511411 -251.473923)
			(xy 295.526283 -251.46913) (xy 295.53281 -251.464826) (xy 295.553899 -251.450477) (xy 295.59956 -251.427746)
			(xy 295.648166 -251.412287) (xy 295.698569 -251.404464) (xy 295.749575 -251.404464) (xy 295.799978 -251.412287)
			(xy 295.848584 -251.427746) (xy 295.894245 -251.450477) (xy 295.915334 -251.464826) (xy 295.921863 -251.469122)
			(xy 295.936735 -251.473903) (xy 295.944544 -251.474224) (xy 296.460672 -251.474224) (xy 296.466008 -251.474549)
			(xy 296.473553 -251.482096) (xy 296.47388 -251.487432) (xy 296.47388 -251.48794) (xy 296.47388 -251.982224)
			(xy 302.518064 -251.982224) (xy 302.518064 -251.487686) (xy 302.518373 -251.482243) (xy 302.526082 -251.474556)
			(xy 302.531526 -251.474224) (xy 304.004726 -251.474224) (xy 304.01009 -251.474732) (xy 304.017673 -251.482322)
			(xy 304.018188 -251.487686) (xy 304.018188 -251.982224) (xy 411.618176 -251.982224) (xy 411.618176 -251.487686)
			(xy 411.618618 -251.482372) (xy 411.626078 -251.474799) (xy 411.631384 -251.474224) (xy 413.104584 -251.474224)
			(xy 413.109922 -251.474541) (xy 413.117466 -251.482094) (xy 413.117792 -251.487432) (xy 413.117792 -251.48794)
			(xy 413.117792 -251.982224) (xy 419.161976 -251.982224) (xy 419.161976 -251.487686) (xy 419.162274 -251.48224)
			(xy 419.169991 -251.474553) (xy 419.175438 -251.474224) (xy 419.691566 -251.474224) (xy 419.699376 -251.473909)
			(xy 419.714248 -251.469125) (xy 419.720776 -251.464826) (xy 419.741865 -251.450477) (xy 419.787526 -251.427746)
			(xy 419.836132 -251.412287) (xy 419.886535 -251.404464) (xy 419.937541 -251.404464) (xy 419.987944 -251.412287)
			(xy 420.03655 -251.427746) (xy 420.082211 -251.450477) (xy 420.1033 -251.464826) (xy 420.109837 -251.469109)
			(xy 420.124703 -251.473898) (xy 420.13251 -251.474224) (xy 420.648638 -251.474224) (xy 420.654003 -251.474724)
			(xy 420.661586 -251.48232) (xy 420.6621 -251.487686) (xy 420.6621 -251.982224) (xy 426.706284 -251.982224)
			(xy 426.706284 -251.487686) (xy 426.706719 -251.48237) (xy 426.714184 -251.474797) (xy 426.719492 -251.474224)
			(xy 427.23562 -251.474224) (xy 427.243432 -251.473931) (xy 427.258304 -251.469132) (xy 427.26483 -251.464826)
			(xy 427.285919 -251.450477) (xy 427.33158 -251.427746) (xy 427.380186 -251.412287) (xy 427.430589 -251.404464)
			(xy 427.481595 -251.404464) (xy 427.531998 -251.412287) (xy 427.580604 -251.427746) (xy 427.626265 -251.450477)
			(xy 427.647354 -251.464826) (xy 427.653879 -251.46913) (xy 427.668754 -251.473906) (xy 427.676564 -251.474224)
			(xy 428.192692 -251.474224) (xy 428.198031 -251.474535) (xy 428.205574 -251.482092) (xy 428.2059 -251.487432)
			(xy 428.2059 -251.48794) (xy 428.2059 -251.982224) (xy 434.250084 -251.982224) (xy 434.250084 -251.487686)
			(xy 434.250375 -251.482238) (xy 434.258097 -251.47455) (xy 434.263546 -251.474224) (xy 434.779674 -251.474224)
			(xy 434.787484 -251.473912) (xy 434.802356 -251.469126) (xy 434.808884 -251.464826) (xy 434.829973 -251.450477)
			(xy 434.875634 -251.427746) (xy 434.92424 -251.412287) (xy 434.974643 -251.404464) (xy 435.025649 -251.404464)
			(xy 435.076052 -251.412287) (xy 435.124658 -251.427746) (xy 435.170319 -251.450477) (xy 435.191408 -251.464826)
			(xy 435.197943 -251.469112) (xy 435.21281 -251.4739) (xy 435.220618 -251.474224) (xy 435.736746 -251.474224)
			(xy 435.742112 -251.474719) (xy 435.749694 -251.482319) (xy 435.750208 -251.487686) (xy 435.750208 -251.982224)
			(xy 441.794392 -251.982224) (xy 441.794392 -251.487686) (xy 441.794908 -251.482391) (xy 441.802317 -251.474824)
			(xy 441.8076 -251.474224) (xy 442.323728 -251.474224) (xy 442.331541 -251.473935) (xy 442.346412 -251.469133)
			(xy 442.352938 -251.464826) (xy 442.374027 -251.450477) (xy 442.419688 -251.427746) (xy 442.468294 -251.412287)
			(xy 442.518697 -251.404464) (xy 442.569703 -251.404464) (xy 442.620106 -251.412287) (xy 442.668712 -251.427746)
			(xy 442.714373 -251.450477) (xy 442.735462 -251.464826) (xy 442.742007 -251.469094) (xy 442.756866 -251.473893)
			(xy 442.764672 -251.474224) (xy 443.2808 -251.474224) (xy 443.28614 -251.47453) (xy 443.293683 -251.482091)
			(xy 443.294008 -251.487432) (xy 443.294008 -251.48794) (xy 443.294008 -251.982224) (xy 449.338192 -251.982224)
			(xy 449.338192 -251.487686) (xy 449.338708 -251.482391) (xy 449.346117 -251.474824) (xy 449.3514 -251.474224)
			(xy 449.867528 -251.474224) (xy 449.875341 -251.473935) (xy 449.890212 -251.469133) (xy 449.896738 -251.464826)
			(xy 449.917827 -251.450477) (xy 449.963488 -251.427746) (xy 450.012094 -251.412287) (xy 450.062497 -251.404464)
			(xy 450.113503 -251.404464) (xy 450.163906 -251.412287) (xy 450.212512 -251.427746) (xy 450.258173 -251.450477)
			(xy 450.279262 -251.464826) (xy 450.285807 -251.469094) (xy 450.300666 -251.473893) (xy 450.308472 -251.474224)
			(xy 450.8246 -251.474224) (xy 450.82994 -251.47453) (xy 450.837483 -251.482091) (xy 450.837808 -251.487432)
			(xy 450.837808 -251.48794) (xy 450.837808 -251.982224) (xy 450.837321 -251.98749) (xy 450.829866 -251.994931)
			(xy 450.8246 -251.995432) (xy 450.308726 -251.995432) (xy 450.30085 -251.995698) (xy 450.285846 -252.000497)
			(xy 450.279262 -252.00483) (xy 450.258184 -252.019221) (xy 450.21254 -252.04205) (xy 450.163934 -252.057608)
			(xy 450.113517 -252.065527) (xy 450.088 -252.066044) (xy 450.06248 -252.065563) (xy 450.012053 -252.057665)
			(xy 449.963441 -252.042102) (xy 449.917803 -252.019246) (xy 449.896738 -252.00483) (xy 449.890138 -252.00053)
			(xy 449.875145 -251.995734) (xy 449.867274 -251.995432) (xy 449.3514 -251.995432) (xy 449.346143 -251.994908)
			(xy 449.338702 -251.98748) (xy 449.338192 -251.982224) (xy 443.294008 -251.982224) (xy 443.293521 -251.98749)
			(xy 443.286066 -251.994931) (xy 443.2808 -251.995432) (xy 442.764926 -251.995432) (xy 442.75705 -251.995698)
			(xy 442.742046 -252.000497) (xy 442.735462 -252.00483) (xy 442.714384 -252.019221) (xy 442.66874 -252.04205)
			(xy 442.620134 -252.057608) (xy 442.569717 -252.065527) (xy 442.5442 -252.066044) (xy 442.51868 -252.065563)
			(xy 442.468253 -252.057665) (xy 442.419641 -252.042102) (xy 442.374003 -252.019246) (xy 442.352938 -252.00483)
			(xy 442.346338 -252.00053) (xy 442.331345 -251.995734) (xy 442.323474 -251.995432) (xy 441.8076 -251.995432)
			(xy 441.802343 -251.994908) (xy 441.794902 -251.98748) (xy 441.794392 -251.982224) (xy 435.750208 -251.982224)
			(xy 435.749721 -251.98749) (xy 435.742266 -251.994931) (xy 435.737 -251.995432) (xy 435.736492 -251.995432)
			(xy 435.220872 -251.995432) (xy 435.212997 -251.995718) (xy 435.197993 -252.000503) (xy 435.191408 -252.00483)
			(xy 435.170345 -252.019244) (xy 435.124695 -252.042068) (xy 435.076085 -252.05762) (xy 435.025664 -252.065531)
			(xy 435.000146 -252.066044) (xy 434.974626 -252.06554) (xy 434.9242 -252.057649) (xy 434.875589 -252.042093)
			(xy 434.82995 -252.019243) (xy 434.808884 -252.00483) (xy 434.802296 -252.000509) (xy 434.787293 -251.995726)
			(xy 434.77942 -251.995432) (xy 434.263546 -251.995432) (xy 434.258241 -251.994943) (xy 434.250666 -251.987518)
			(xy 434.250084 -251.982224) (xy 428.2059 -251.982224) (xy 428.20542 -251.987492) (xy 428.197961 -251.994933)
			(xy 428.192692 -251.995432) (xy 427.676818 -251.995432) (xy 427.668945 -251.995738) (xy 427.653941 -252.00051)
			(xy 427.647354 -252.00483) (xy 427.626278 -252.019224) (xy 427.580633 -252.042053) (xy 427.532026 -252.05761)
			(xy 427.481609 -252.065528) (xy 427.456092 -252.066044) (xy 427.430573 -252.065517) (xy 427.380148 -252.057633)
			(xy 427.331537 -252.042083) (xy 427.285897 -252.01924) (xy 427.26483 -252.00483) (xy 427.258232 -252.000527)
			(xy 427.243237 -251.995732) (xy 427.235366 -251.995432) (xy 426.719492 -251.995432) (xy 426.714234 -251.994913)
			(xy 426.706793 -251.987481) (xy 426.706284 -251.982224) (xy 420.6621 -251.982224) (xy 420.66162 -251.987492)
			(xy 420.654161 -251.994933) (xy 420.648892 -251.995432) (xy 420.648384 -251.995432) (xy 420.132764 -251.995432)
			(xy 420.124889 -251.995715) (xy 420.109885 -252.000502) (xy 420.1033 -252.00483) (xy 420.082211 -252.019204)
			(xy 420.036571 -252.042037) (xy 419.987968 -252.0576) (xy 419.937554 -252.065524) (xy 419.912038 -252.066044)
			(xy 419.886518 -252.065544) (xy 419.836092 -252.057651) (xy 419.787481 -252.042094) (xy 419.741842 -252.019243)
			(xy 419.720776 -252.00483) (xy 419.71419 -252.000506) (xy 419.699186 -251.995724) (xy 419.691312 -251.995432)
			(xy 419.175438 -251.995432) (xy 419.170132 -251.994948) (xy 419.162557 -251.98752) (xy 419.161976 -251.982224)
			(xy 413.117792 -251.982224) (xy 413.117319 -251.987493) (xy 413.109855 -251.994935) (xy 413.104584 -251.995432)
			(xy 411.631384 -251.995432) (xy 411.626125 -251.994919) (xy 411.618685 -251.987483) (xy 411.618176 -251.982224)
			(xy 304.018188 -251.982224) (xy 304.017719 -251.987494) (xy 304.010252 -251.994937) (xy 304.00498 -251.995432)
			(xy 304.004472 -251.995432) (xy 302.531526 -251.995432) (xy 302.526218 -251.994956) (xy 302.518644 -251.987522)
			(xy 302.518064 -251.982224) (xy 296.47388 -251.982224) (xy 296.473586 -251.987566) (xy 296.466016 -251.995107)
			(xy 296.460672 -251.995432) (xy 295.944798 -251.995432) (xy 295.936924 -251.99573) (xy 295.921921 -252.000507)
			(xy 295.915334 -252.00483) (xy 295.894264 -252.019233) (xy 295.848617 -252.042059) (xy 295.800008 -252.057614)
			(xy 295.749589 -252.065529) (xy 295.724072 -252.066044) (xy 295.698553 -252.065527) (xy 295.648128 -252.05764)
			(xy 295.599516 -252.042087) (xy 295.553876 -252.019241) (xy 295.53281 -252.00483) (xy 295.526216 -252.000519)
			(xy 295.511218 -251.995729) (xy 295.503346 -251.995432) (xy 294.987472 -251.995432) (xy 294.982212 -251.994926)
			(xy 294.974772 -251.987485) (xy 294.974264 -251.982224) (xy 288.93008 -251.982224) (xy 288.929786 -251.987566)
			(xy 288.922216 -251.995107) (xy 288.916872 -251.995432) (xy 288.916364 -251.995432) (xy 288.400744 -251.995432)
			(xy 288.392868 -251.995706) (xy 288.377864 -252.000499) (xy 288.37128 -252.00483) (xy 288.350197 -252.019213)
			(xy 288.304554 -252.042044) (xy 288.25595 -252.057604) (xy 288.205534 -252.065526) (xy 288.180018 -252.066044)
			(xy 288.154498 -252.065554) (xy 288.104071 -252.057658) (xy 288.05546 -252.042098) (xy 288.009821 -252.019244)
			(xy 287.988756 -252.00483) (xy 287.982174 -252.000498) (xy 287.967167 -251.995721) (xy 287.959292 -251.995432)
			(xy 287.443418 -251.995432) (xy 287.438109 -251.994962) (xy 287.430536 -251.987523) (xy 287.429956 -251.982224)
			(xy 281.385772 -251.982224) (xy 281.385486 -251.987568) (xy 281.37791 -251.99511) (xy 281.372564 -251.995432)
			(xy 280.85669 -251.995432) (xy 280.848816 -251.995726) (xy 280.833812 -252.000506) (xy 280.827226 -252.00483)
			(xy 280.806158 -252.019236) (xy 280.76051 -252.042062) (xy 280.711901 -252.057616) (xy 280.661482 -252.06553)
			(xy 280.635964 -252.066044) (xy 280.610445 -252.065531) (xy 280.560019 -252.057642) (xy 280.511408 -252.042089)
			(xy 280.465768 -252.019241) (xy 280.444702 -252.00483) (xy 280.43811 -252.000516) (xy 280.42311 -251.995728)
			(xy 280.415238 -251.995432) (xy 279.899364 -251.995432) (xy 279.894103 -251.994931) (xy 279.886664 -251.987486)
			(xy 279.886156 -251.982224) (xy 273.841972 -251.982224) (xy 273.841686 -251.987568) (xy 273.83411 -251.99511)
			(xy 273.828764 -251.995432) (xy 273.31289 -251.995432) (xy 273.305016 -251.995726) (xy 273.290012 -252.000506)
			(xy 273.283426 -252.00483) (xy 273.262358 -252.019236) (xy 273.21671 -252.042062) (xy 273.168101 -252.057616)
			(xy 273.117682 -252.06553) (xy 273.092164 -252.066044) (xy 273.066645 -252.065531) (xy 273.016219 -252.057642)
			(xy 272.967608 -252.042089) (xy 272.921968 -252.019241) (xy 272.900902 -252.00483) (xy 272.89431 -252.000516)
			(xy 272.87931 -251.995728) (xy 272.871438 -251.995432) (xy 272.355564 -251.995432) (xy 272.350303 -251.994931)
			(xy 272.342864 -251.987486) (xy 272.342356 -251.982224) (xy 266.298172 -251.982224) (xy 266.297886 -251.987568)
			(xy 266.29031 -251.99511) (xy 266.284964 -251.995432) (xy 266.284456 -251.995432) (xy 265.768836 -251.995432)
			(xy 265.76096 -251.995703) (xy 265.745956 -252.000498) (xy 265.739372 -252.00483) (xy 265.718291 -252.019217)
			(xy 265.672648 -252.042047) (xy 265.624043 -252.057606) (xy 265.573626 -252.065526) (xy 265.54811 -252.066044)
			(xy 265.52259 -252.065558) (xy 265.472163 -252.057661) (xy 265.423552 -252.0421) (xy 265.377913 -252.019245)
			(xy 265.356848 -252.00483) (xy 265.350268 -252.000495) (xy 265.335259 -251.99572) (xy 265.327384 -251.995432)
			(xy 264.81151 -251.995432) (xy 264.806201 -251.994967) (xy 264.798627 -251.987524) (xy 264.798048 -251.982224)
			(xy 202.89774 -251.982224) (xy 202.89774 -251.982478) (xy 202.89726 -251.987784) (xy 202.889828 -251.995358)
			(xy 202.884532 -251.99594) (xy 202.368658 -251.99594) (xy 202.360849 -251.996272) (xy 202.345978 -252.001045)
			(xy 202.339448 -252.005338) (xy 202.318337 -252.019704) (xy 202.27261 -252.042428) (xy 202.223933 -252.057853)
			(xy 202.173464 -252.065614) (xy 202.147932 -252.066044) (xy 202.122402 -252.065595) (xy 202.071939 -252.057824)
			(xy 202.023266 -252.042398) (xy 201.977538 -252.019684) (xy 201.956416 -252.005338) (xy 201.949878 -252.001058)
			(xy 201.935013 -251.996267) (xy 201.927206 -251.99594) (xy 201.411332 -251.99594) (xy 201.406081 -251.995387)
			(xy 201.398638 -251.987981) (xy 201.398124 -251.982732) (xy 195.353917 -251.982732) (xy 195.35346 -251.987784)
			(xy 195.346028 -251.995358) (xy 195.340732 -251.99594) (xy 194.824858 -251.99594) (xy 194.817049 -251.996272)
			(xy 194.802178 -252.001045) (xy 194.795648 -252.005338) (xy 194.774537 -252.019704) (xy 194.72881 -252.042428)
			(xy 194.680133 -252.057853) (xy 194.629664 -252.065614) (xy 194.604132 -252.066044) (xy 194.578602 -252.065595)
			(xy 194.528139 -252.057824) (xy 194.479466 -252.042398) (xy 194.433738 -252.019684) (xy 194.412616 -252.005338)
			(xy 194.406078 -252.001058) (xy 194.391213 -251.996267) (xy 194.383406 -251.99594) (xy 193.867532 -251.99594)
			(xy 193.862281 -251.995387) (xy 193.854838 -251.987981) (xy 193.854324 -251.982732) (xy 187.810124 -251.982732)
			(xy 187.809804 -251.987915) (xy 187.802115 -251.995604) (xy 187.796678 -251.99594) (xy 187.280804 -251.99594)
			(xy 187.272993 -251.996248) (xy 187.258122 -252.001037) (xy 187.251594 -252.005338) (xy 187.230471 -252.019684)
			(xy 187.184747 -252.042412) (xy 187.136075 -252.057843) (xy 187.085609 -252.065611) (xy 187.060078 -252.066044)
			(xy 187.034547 -252.065622) (xy 186.984083 -252.057842) (xy 186.93541 -252.042409) (xy 186.889683 -252.019688)
			(xy 186.868562 -252.005338) (xy 186.862036 -252.001037) (xy 186.847162 -251.99626) (xy 186.839352 -251.99594)
			(xy 186.323478 -251.99594) (xy 186.318106 -251.995462) (xy 186.31052 -251.987852) (xy 186.310016 -251.982478)
			(xy 180.265832 -251.982478) (xy 180.265359 -251.987786) (xy 180.257922 -251.99536) (xy 180.252624 -251.99594)
			(xy 179.73675 -251.99594) (xy 179.728941 -251.996268) (xy 179.714069 -252.001044) (xy 179.70754 -252.005338)
			(xy 179.686432 -252.019708) (xy 179.640703 -252.04243) (xy 179.592026 -252.057855) (xy 179.541556 -252.065615)
			(xy 179.516024 -252.066044) (xy 179.490494 -252.065599) (xy 179.44003 -252.057826) (xy 179.391358 -252.0424)
			(xy 179.34563 -252.019685) (xy 179.324508 -252.005338) (xy 179.317972 -252.001055) (xy 179.303105 -251.996266)
			(xy 179.295298 -251.99594) (xy 178.779424 -251.99594) (xy 178.774172 -251.995392) (xy 178.76673 -251.987982)
			(xy 178.766216 -251.982732) (xy 172.722017 -251.982732) (xy 172.721703 -251.987917) (xy 172.714009 -251.995606)
			(xy 172.70857 -251.99594) (xy 172.192696 -251.99594) (xy 172.184885 -251.996245) (xy 172.170013 -252.001036)
			(xy 172.163486 -252.005338) (xy 172.142365 -252.019688) (xy 172.096641 -252.042415) (xy 172.047968 -252.057845)
			(xy 171.997501 -252.065611) (xy 171.97197 -252.066044) (xy 171.946439 -252.065626) (xy 171.895974 -252.057845)
			(xy 171.847302 -252.042411) (xy 171.801575 -252.019688) (xy 171.780454 -252.005338) (xy 171.77393 -252.001034)
			(xy 171.759054 -251.996258) (xy 171.751244 -251.99594) (xy 171.23537 -251.99594) (xy 171.229997 -251.995467)
			(xy 171.222412 -251.987853) (xy 171.221908 -251.982478) (xy 165.177724 -251.982478) (xy 165.177258 -251.987788)
			(xy 165.169816 -251.995362) (xy 165.164516 -251.99594) (xy 163.691316 -251.99594) (xy 163.686063 -251.995398)
			(xy 163.678621 -251.987983) (xy 163.678108 -251.982732) (xy 56.078105 -251.982732) (xy 56.077802 -251.98792)
			(xy 56.070101 -251.99561) (xy 56.064658 -251.99594) (xy 54.591458 -251.99594) (xy 54.586084 -251.995475)
			(xy 54.578499 -251.987855) (xy 54.577996 -251.982478) (xy 48.533812 -251.982478) (xy 48.533356 -251.987791)
			(xy 48.525908 -251.995366) (xy 48.520604 -251.99594) (xy 48.00473 -251.99594) (xy 47.99692 -251.99626)
			(xy 47.982049 -252.001041) (xy 47.97552 -252.005338) (xy 47.954389 -252.019673) (xy 47.908669 -252.042403)
			(xy 47.859998 -252.057838) (xy 47.809534 -252.065609) (xy 47.784004 -252.066044) (xy 47.758474 -252.065609)
			(xy 47.70801 -252.057833) (xy 47.659337 -252.042404) (xy 47.61361 -252.019686) (xy 47.592488 -252.005338)
			(xy 47.585956 -252.001047) (xy 47.571086 -251.996263) (xy 47.563278 -251.99594) (xy 47.047404 -251.99594)
			(xy 47.042149 -251.995406) (xy 47.034708 -251.987985) (xy 47.034196 -251.982732) (xy 40.989985 -251.982732)
			(xy 40.98944 -251.987827) (xy 40.981896 -251.995411) (xy 40.97655 -251.99594) (xy 40.460676 -251.99594)
			(xy 40.452864 -251.996237) (xy 40.437993 -252.001034) (xy 40.431466 -252.005338) (xy 40.41035 -252.019697)
			(xy 40.364624 -252.042422) (xy 40.315949 -252.057849) (xy 40.265482 -252.065613) (xy 40.23995 -252.066044)
			(xy 40.214421 -252.065586) (xy 40.163957 -252.057817) (xy 40.115285 -252.042394) (xy 40.069556 -252.019683)
			(xy 40.048434 -252.005338) (xy 40.041892 -252.001065) (xy 40.02703 -251.99627) (xy 40.019224 -251.99594)
			(xy 39.50335 -251.99594) (xy 39.497975 -251.99548) (xy 39.490391 -251.987856) (xy 39.489888 -251.982478)
			(xy 33.445704 -251.982478) (xy 33.445168 -251.987769) (xy 33.437775 -251.995339) (xy 33.432496 -251.99594)
			(xy 32.916622 -251.99594) (xy 32.908812 -251.996257) (xy 32.89394 -252.00104) (xy 32.887412 -252.005338)
			(xy 32.866283 -252.019677) (xy 32.820562 -252.042406) (xy 32.771891 -252.057839) (xy 32.721426 -252.065609)
			(xy 32.695896 -252.066044) (xy 32.670365 -252.065613) (xy 32.619901 -252.057836) (xy 32.571229 -252.042405)
			(xy 32.525502 -252.019687) (xy 32.50438 -252.005338) (xy 32.49785 -252.001044) (xy 32.482979 -251.996262)
			(xy 32.47517 -251.99594) (xy 31.959296 -251.99594) (xy 31.95404 -251.995411) (xy 31.9466 -251.987987)
			(xy 31.946088 -251.982732) (xy 25.901878 -251.982732) (xy 25.901368 -251.987769) (xy 25.893975 -251.995339)
			(xy 25.888696 -251.99594) (xy 25.372822 -251.99594) (xy 25.365012 -251.996257) (xy 25.35014 -252.00104)
			(xy 25.343612 -252.005338) (xy 25.322483 -252.019677) (xy 25.276762 -252.042406) (xy 25.228091 -252.057839)
			(xy 25.177626 -252.065609) (xy 25.152096 -252.066044) (xy 25.126565 -252.065613) (xy 25.076101 -252.057836)
			(xy 25.027429 -252.042405) (xy 24.981702 -252.019687) (xy 24.96058 -252.005338) (xy 24.95405 -252.001044)
			(xy 24.939179 -251.996262) (xy 24.93137 -251.99594) (xy 24.415496 -251.99594) (xy 24.41024 -251.995411)
			(xy 24.4028 -251.987987) (xy 24.402288 -251.982732) (xy 18.358077 -251.982732) (xy 18.357539 -251.987829)
			(xy 18.349991 -251.995414) (xy 18.344642 -251.99594) (xy 17.828768 -251.99594) (xy 17.82096 -251.996276)
			(xy 17.806088 -252.001046) (xy 17.799558 -252.005338) (xy 17.778445 -252.0197) (xy 17.732718 -252.042424)
			(xy 17.684042 -252.057851) (xy 17.633574 -252.065613) (xy 17.608042 -252.066044) (xy 17.582512 -252.06559)
			(xy 17.532049 -252.05782) (xy 17.483377 -252.042396) (xy 17.437648 -252.019684) (xy 17.416526 -252.005338)
			(xy 17.409986 -252.001062) (xy 17.395123 -251.996269) (xy 17.387316 -251.99594) (xy 16.871442 -251.99594)
			(xy 16.866007 -251.99559) (xy 16.858318 -251.987912) (xy 16.85798 -251.982478) (xy 2.509012 -251.982478)
			(xy 2.509012 -252.832362) (xy 20.958048 -252.832362) (xy 20.958048 -252.337824) (xy 20.958606 -252.332575)
			(xy 20.966009 -252.325133) (xy 20.971256 -252.324616) (xy 20.971764 -252.324616) (xy 21.487638 -252.324616)
			(xy 21.495447 -252.32429) (xy 21.510319 -252.319514) (xy 21.516848 -252.315218) (xy 21.537937 -252.300869)
			(xy 21.583598 -252.278138) (xy 21.632204 -252.262679) (xy 21.682607 -252.254856) (xy 21.733613 -252.254856)
			(xy 21.784016 -252.262679) (xy 21.832622 -252.278138) (xy 21.878283 -252.300869) (xy 21.899372 -252.315218)
			(xy 21.905915 -252.319489) (xy 21.920776 -252.324286) (xy 21.928582 -252.324616) (xy 22.44471 -252.324616)
			(xy 22.45001 -252.325114) (xy 22.457579 -252.332535) (xy 22.458172 -252.337824) (xy 22.458172 -252.832362)
			(xy 22.458154 -252.832616) (xy 28.502356 -252.832616) (xy 28.502356 -252.832108) (xy 28.502356 -252.337824)
			(xy 28.502907 -252.332573) (xy 28.510315 -252.325131) (xy 28.515564 -252.324616) (xy 29.031692 -252.324616)
			(xy 29.039503 -252.324313) (xy 29.054375 -252.319521) (xy 29.060902 -252.315218) (xy 29.081991 -252.300869)
			(xy 29.127652 -252.278138) (xy 29.176258 -252.262679) (xy 29.226661 -252.254856) (xy 29.277667 -252.254856)
			(xy 29.32807 -252.262679) (xy 29.376676 -252.278138) (xy 29.422337 -252.300869) (xy 29.443426 -252.315218)
			(xy 29.449957 -252.31951) (xy 29.464827 -252.324294) (xy 29.472636 -252.324616) (xy 29.988764 -252.324616)
			(xy 29.994097 -252.324953) (xy 30.001642 -252.332491) (xy 30.001972 -252.337824) (xy 30.001972 -252.832362)
			(xy 30.001947 -252.832616) (xy 36.046156 -252.832616) (xy 36.046156 -252.832108) (xy 36.046156 -252.337824)
			(xy 36.046707 -252.332573) (xy 36.054115 -252.325131) (xy 36.059364 -252.324616) (xy 36.575492 -252.324616)
			(xy 36.583303 -252.324313) (xy 36.598175 -252.319521) (xy 36.604702 -252.315218) (xy 36.625791 -252.300869)
			(xy 36.671452 -252.278138) (xy 36.720058 -252.262679) (xy 36.770461 -252.254856) (xy 36.821467 -252.254856)
			(xy 36.87187 -252.262679) (xy 36.920476 -252.278138) (xy 36.966137 -252.300869) (xy 36.987226 -252.315218)
			(xy 36.993757 -252.31951) (xy 37.008627 -252.324294) (xy 37.016436 -252.324616) (xy 37.532564 -252.324616)
			(xy 37.537897 -252.324953) (xy 37.545442 -252.332491) (xy 37.545772 -252.337824) (xy 37.545772 -252.832362)
			(xy 43.589956 -252.832362) (xy 43.589956 -252.337824) (xy 43.590507 -252.332573) (xy 43.597915 -252.325131)
			(xy 43.603164 -252.324616) (xy 43.603672 -252.324616) (xy 44.119546 -252.324616) (xy 44.127356 -252.324294)
			(xy 44.142228 -252.319515) (xy 44.148756 -252.315218) (xy 44.169845 -252.300869) (xy 44.215506 -252.278138)
			(xy 44.264112 -252.262679) (xy 44.314515 -252.254856) (xy 44.365521 -252.254856) (xy 44.415924 -252.262679)
			(xy 44.46453 -252.278138) (xy 44.510191 -252.300869) (xy 44.53128 -252.315218) (xy 44.537821 -252.319493)
			(xy 44.552684 -252.324287) (xy 44.56049 -252.324616) (xy 45.076618 -252.324616) (xy 45.081919 -252.325108)
			(xy 45.089488 -252.332534) (xy 45.09008 -252.337824) (xy 45.09008 -252.832362) (xy 45.090062 -252.832616)
			(xy 51.134264 -252.832616) (xy 51.134264 -252.832108) (xy 51.134264 -252.337824) (xy 51.134808 -252.332571)
			(xy 51.142221 -252.325129) (xy 51.147472 -252.324616) (xy 51.6636 -252.324616) (xy 51.671412 -252.324316)
			(xy 51.686283 -252.319522) (xy 51.69281 -252.315218) (xy 51.713899 -252.300869) (xy 51.75956 -252.278138)
			(xy 51.808166 -252.262679) (xy 51.858569 -252.254856) (xy 51.909575 -252.254856) (xy 51.959978 -252.262679)
			(xy 52.008584 -252.278138) (xy 52.054245 -252.300869) (xy 52.075334 -252.315218) (xy 52.081863 -252.319513)
			(xy 52.096735 -252.324295) (xy 52.104544 -252.324616) (xy 52.620672 -252.324616) (xy 52.626006 -252.324948)
			(xy 52.633551 -252.33249) (xy 52.63388 -252.337824) (xy 52.63388 -252.832362) (xy 58.678064 -252.832362)
			(xy 58.678064 -252.337824) (xy 58.678608 -252.332571) (xy 58.686021 -252.325129) (xy 58.691272 -252.324616)
			(xy 58.69178 -252.324616) (xy 60.164726 -252.324616) (xy 60.170028 -252.325103) (xy 60.177596 -252.332532)
			(xy 60.178188 -252.337824) (xy 60.178188 -252.832362) (xy 60.17817 -252.832616) (xy 167.778176 -252.832616)
			(xy 167.778176 -252.337824) (xy 167.778541 -252.332499) (xy 167.78606 -252.324957) (xy 167.791384 -252.324616)
			(xy 169.264584 -252.324616) (xy 169.26992 -252.32494) (xy 169.277463 -252.332488) (xy 169.277792 -252.337824)
			(xy 169.277792 -252.832362) (xy 175.321976 -252.832362) (xy 175.321976 -252.337824) (xy 175.322341 -252.332499)
			(xy 175.32986 -252.324957) (xy 175.335184 -252.324616) (xy 175.335692 -252.324616) (xy 175.851566 -252.324616)
			(xy 175.859376 -252.324302) (xy 175.874248 -252.319518) (xy 175.880776 -252.315218) (xy 175.901865 -252.300869)
			(xy 175.947526 -252.278138) (xy 175.996132 -252.262679) (xy 176.046535 -252.254856) (xy 176.097541 -252.254856)
			(xy 176.147944 -252.262679) (xy 176.19655 -252.278138) (xy 176.242211 -252.300869) (xy 176.2633 -252.315218)
			(xy 176.269837 -252.3195) (xy 176.284703 -252.32429) (xy 176.29251 -252.324616) (xy 176.808638 -252.324616)
			(xy 176.813941 -252.325095) (xy 176.821509 -252.332531) (xy 176.8221 -252.337824) (xy 176.8221 -252.832362)
			(xy 176.822073 -252.832616) (xy 182.866284 -252.832616) (xy 182.866284 -252.832108) (xy 182.866284 -252.337824)
			(xy 182.866642 -252.332497) (xy 182.874166 -252.324955) (xy 182.879492 -252.324616) (xy 183.39562 -252.324616)
			(xy 183.403432 -252.324325) (xy 183.418304 -252.319525) (xy 183.42483 -252.315218) (xy 183.445919 -252.300869)
			(xy 183.49158 -252.278138) (xy 183.540186 -252.262679) (xy 183.590589 -252.254856) (xy 183.641595 -252.254856)
			(xy 183.691998 -252.262679) (xy 183.740604 -252.278138) (xy 183.786265 -252.300869) (xy 183.807354 -252.315218)
			(xy 183.813879 -252.319521) (xy 183.828754 -252.324298) (xy 183.836564 -252.324616) (xy 184.352692 -252.324616)
			(xy 184.358029 -252.324934) (xy 184.365572 -252.332487) (xy 184.3659 -252.337824) (xy 184.3659 -252.832362)
			(xy 190.410084 -252.832362) (xy 190.410084 -252.337824) (xy 190.410442 -252.332497) (xy 190.417966 -252.324955)
			(xy 190.423292 -252.324616) (xy 190.4238 -252.324616) (xy 190.939674 -252.324616) (xy 190.947485 -252.324305)
			(xy 190.962357 -252.319519) (xy 190.968884 -252.315218) (xy 190.989973 -252.300869) (xy 191.035634 -252.278138)
			(xy 191.08424 -252.262679) (xy 191.134643 -252.254856) (xy 191.185649 -252.254856) (xy 191.236052 -252.262679)
			(xy 191.284658 -252.278138) (xy 191.330319 -252.300869) (xy 191.351408 -252.315218) (xy 191.357943 -252.319503)
			(xy 191.37281 -252.324292) (xy 191.380618 -252.324616) (xy 191.896746 -252.324616) (xy 191.902038 -252.325156)
			(xy 191.909611 -252.332545) (xy 191.910208 -252.337824) (xy 191.910208 -252.832362) (xy 191.910181 -252.832616)
			(xy 197.954392 -252.832616) (xy 197.954392 -252.832108) (xy 197.954392 -252.337824) (xy 197.954743 -252.332495)
			(xy 197.962272 -252.324953) (xy 197.9676 -252.324616) (xy 198.483728 -252.324616) (xy 198.491541 -252.324328)
			(xy 198.506412 -252.319526) (xy 198.512938 -252.315218) (xy 198.534027 -252.300869) (xy 198.579688 -252.278138)
			(xy 198.628294 -252.262679) (xy 198.678697 -252.254856) (xy 198.729703 -252.254856) (xy 198.780106 -252.262679)
			(xy 198.828712 -252.278138) (xy 198.874373 -252.300869) (xy 198.895462 -252.315218) (xy 198.902008 -252.319486)
			(xy 198.916867 -252.324285) (xy 198.924672 -252.324616) (xy 199.4408 -252.324616) (xy 199.446138 -252.324929)
			(xy 199.453681 -252.332485) (xy 199.454008 -252.337824) (xy 199.454008 -252.832362) (xy 199.453982 -252.832616)
			(xy 205.498192 -252.832616) (xy 205.498192 -252.832108) (xy 205.498192 -252.337824) (xy 205.498543 -252.332495)
			(xy 205.506072 -252.324953) (xy 205.5114 -252.324616) (xy 206.027528 -252.324616) (xy 206.035341 -252.324328)
			(xy 206.050212 -252.319526) (xy 206.056738 -252.315218) (xy 206.077827 -252.300869) (xy 206.123488 -252.278138)
			(xy 206.172094 -252.262679) (xy 206.222497 -252.254856) (xy 206.273503 -252.254856) (xy 206.323906 -252.262679)
			(xy 206.372512 -252.278138) (xy 206.418173 -252.300869) (xy 206.439262 -252.315218) (xy 206.445808 -252.319486)
			(xy 206.460667 -252.324285) (xy 206.468472 -252.324616) (xy 206.9846 -252.324616) (xy 206.989938 -252.324929)
			(xy 206.997481 -252.332485) (xy 206.997808 -252.337824) (xy 206.997808 -252.832108) (xy 268.898116 -252.832108)
			(xy 268.898116 -252.33757) (xy 268.898628 -252.332208) (xy 268.906215 -252.324625) (xy 268.911578 -252.324108)
			(xy 269.427706 -252.324108) (xy 269.435516 -252.323796) (xy 269.450387 -252.319008) (xy 269.456916 -252.31471)
			(xy 269.478005 -252.300361) (xy 269.523666 -252.27763) (xy 269.572272 -252.262171) (xy 269.622675 -252.254348)
			(xy 269.673681 -252.254348) (xy 269.724084 -252.262171) (xy 269.77269 -252.27763) (xy 269.818351 -252.300361)
			(xy 269.83944 -252.31471) (xy 269.845963 -252.319016) (xy 269.86084 -252.32379) (xy 269.86865 -252.324108)
			(xy 270.384778 -252.324108) (xy 270.390132 -252.324662) (xy 270.397717 -252.332218) (xy 270.39824 -252.33757)
			(xy 270.39824 -252.832108) (xy 276.442424 -252.832108) (xy 276.442424 -252.33757) (xy 276.442901 -252.332266)
			(xy 276.450337 -252.324697) (xy 276.455632 -252.324108) (xy 276.97176 -252.324108) (xy 276.979568 -252.323776)
			(xy 276.99444 -252.319002) (xy 277.00097 -252.31471) (xy 277.022059 -252.300361) (xy 277.06772 -252.27763)
			(xy 277.116326 -252.262171) (xy 277.166729 -252.254348) (xy 277.217735 -252.254348) (xy 277.268138 -252.262171)
			(xy 277.316744 -252.27763) (xy 277.362405 -252.300361) (xy 277.383494 -252.31471) (xy 277.390027 -252.318999)
			(xy 277.404896 -252.323783) (xy 277.412704 -252.324108) (xy 277.928832 -252.324108) (xy 277.934102 -252.324575)
			(xy 277.941544 -252.332044) (xy 277.94204 -252.337316) (xy 277.94204 -252.337824) (xy 277.94204 -252.832108)
			(xy 283.986224 -252.832108) (xy 283.986224 -252.33757) (xy 283.986701 -252.332266) (xy 283.994137 -252.324697)
			(xy 283.999432 -252.324108) (xy 284.51556 -252.324108) (xy 284.523368 -252.323776) (xy 284.53824 -252.319002)
			(xy 284.54477 -252.31471) (xy 284.565859 -252.300361) (xy 284.61152 -252.27763) (xy 284.660126 -252.262171)
			(xy 284.710529 -252.254348) (xy 284.761535 -252.254348) (xy 284.811938 -252.262171) (xy 284.860544 -252.27763)
			(xy 284.906205 -252.300361) (xy 284.927294 -252.31471) (xy 284.933827 -252.318999) (xy 284.948696 -252.323783)
			(xy 284.956504 -252.324108) (xy 285.472632 -252.324108) (xy 285.477902 -252.324575) (xy 285.485344 -252.332044)
			(xy 285.48584 -252.337316) (xy 285.48584 -252.337824) (xy 285.48584 -252.832108) (xy 291.530024 -252.832108)
			(xy 291.530024 -252.33757) (xy 291.530529 -252.332206) (xy 291.538121 -252.324623) (xy 291.543486 -252.324108)
			(xy 292.059614 -252.324108) (xy 292.067424 -252.323799) (xy 292.082296 -252.31901) (xy 292.088824 -252.31471)
			(xy 292.109913 -252.300361) (xy 292.155574 -252.27763) (xy 292.20418 -252.262171) (xy 292.254583 -252.254348)
			(xy 292.305589 -252.254348) (xy 292.355992 -252.262171) (xy 292.404598 -252.27763) (xy 292.450259 -252.300361)
			(xy 292.471348 -252.31471) (xy 292.477869 -252.319019) (xy 292.492747 -252.323791) (xy 292.500558 -252.324108)
			(xy 293.016686 -252.324108) (xy 293.022041 -252.324657) (xy 293.029626 -252.332217) (xy 293.030148 -252.33757)
			(xy 293.030148 -252.832108) (xy 299.074332 -252.832108) (xy 299.074332 -252.33757) (xy 299.074802 -252.332264)
			(xy 299.082243 -252.324695) (xy 299.08754 -252.324108) (xy 299.603668 -252.324108) (xy 299.611477 -252.323779)
			(xy 299.626348 -252.319004) (xy 299.632878 -252.31471) (xy 299.653967 -252.300361) (xy 299.699628 -252.27763)
			(xy 299.748234 -252.262171) (xy 299.798637 -252.254348) (xy 299.849643 -252.254348) (xy 299.900046 -252.262171)
			(xy 299.948652 -252.27763) (xy 299.994313 -252.300361) (xy 300.015402 -252.31471) (xy 300.021933 -252.319002)
			(xy 300.036803 -252.323784) (xy 300.044612 -252.324108) (xy 300.56074 -252.324108) (xy 300.566012 -252.32457)
			(xy 300.573453 -252.332042) (xy 300.573948 -252.337316) (xy 300.573948 -252.337824) (xy 300.573948 -252.832108)
			(xy 306.618132 -252.832108) (xy 306.618132 -252.33757) (xy 306.61863 -252.332204) (xy 306.626227 -252.32462)
			(xy 306.631594 -252.324108) (xy 308.104794 -252.324108) (xy 308.11015 -252.324651) (xy 308.117734 -252.332215)
			(xy 308.118256 -252.33757) (xy 308.118256 -252.832108) (xy 415.718244 -252.832108) (xy 415.718244 -252.33757)
			(xy 415.718704 -252.332261) (xy 415.726152 -252.324691) (xy 415.731452 -252.324108) (xy 417.204652 -252.324108)
			(xy 417.209982 -252.324461) (xy 417.217526 -252.331987) (xy 417.21786 -252.337316) (xy 417.21786 -252.832108)
			(xy 423.262044 -252.832108) (xy 423.262044 -252.33757) (xy 423.262531 -252.332201) (xy 423.270136 -252.324617)
			(xy 423.275506 -252.324108) (xy 423.791634 -252.324108) (xy 423.799441 -252.323765) (xy 423.814313 -252.318999)
			(xy 423.820844 -252.31471) (xy 423.841933 -252.300361) (xy 423.887594 -252.27763) (xy 423.9362 -252.262171)
			(xy 423.986603 -252.254348) (xy 424.037609 -252.254348) (xy 424.088012 -252.262171) (xy 424.136618 -252.27763)
			(xy 424.182279 -252.300361) (xy 424.203368 -252.31471) (xy 424.209907 -252.318989) (xy 424.224771 -252.323779)
			(xy 424.232578 -252.324108) (xy 424.748706 -252.324108) (xy 424.754063 -252.324643) (xy 424.761647 -252.332213)
			(xy 424.762168 -252.33757) (xy 424.762168 -252.832108) (xy 430.806352 -252.832108) (xy 430.806352 -252.33757)
			(xy 430.806805 -252.332259) (xy 430.814258 -252.324689) (xy 430.81956 -252.324108) (xy 431.335688 -252.324108)
			(xy 431.343497 -252.323788) (xy 431.358369 -252.319006) (xy 431.364898 -252.31471) (xy 431.385987 -252.300361)
			(xy 431.431648 -252.27763) (xy 431.480254 -252.262171) (xy 431.530657 -252.254348) (xy 431.581663 -252.254348)
			(xy 431.632066 -252.262171) (xy 431.680672 -252.27763) (xy 431.726333 -252.300361) (xy 431.747422 -252.31471)
			(xy 431.753949 -252.319009) (xy 431.768822 -252.323787) (xy 431.776632 -252.324108) (xy 432.29276 -252.324108)
			(xy 432.298091 -252.324455) (xy 432.305635 -252.331986) (xy 432.305968 -252.337316) (xy 432.305968 -252.337824)
			(xy 432.305968 -252.832108) (xy 438.350152 -252.832108) (xy 438.350152 -252.33757) (xy 438.350632 -252.332199)
			(xy 438.358241 -252.324614) (xy 438.363614 -252.324108) (xy 438.879742 -252.324108) (xy 438.88755 -252.323768)
			(xy 438.902421 -252.319) (xy 438.908952 -252.31471) (xy 438.930041 -252.300361) (xy 438.975702 -252.27763)
			(xy 439.024308 -252.262171) (xy 439.074711 -252.254348) (xy 439.125717 -252.254348) (xy 439.17612 -252.262171)
			(xy 439.224726 -252.27763) (xy 439.270387 -252.300361) (xy 439.291476 -252.31471) (xy 439.298013 -252.318992)
			(xy 439.312879 -252.32378) (xy 439.320686 -252.324108) (xy 439.836814 -252.324108) (xy 439.842172 -252.324638)
			(xy 439.849755 -252.332212) (xy 439.850276 -252.33757) (xy 439.850276 -252.832108) (xy 445.89446 -252.832108)
			(xy 445.89446 -252.33757) (xy 445.894905 -252.332257) (xy 445.902364 -252.324687) (xy 445.907668 -252.324108)
			(xy 446.423796 -252.324108) (xy 446.431606 -252.323791) (xy 446.446477 -252.319007) (xy 446.453006 -252.31471)
			(xy 446.474095 -252.300361) (xy 446.519756 -252.27763) (xy 446.568362 -252.262171) (xy 446.618765 -252.254348)
			(xy 446.669771 -252.254348) (xy 446.720174 -252.262171) (xy 446.76878 -252.27763) (xy 446.814441 -252.300361)
			(xy 446.83553 -252.31471) (xy 446.842055 -252.319012) (xy 446.85693 -252.323788) (xy 446.86474 -252.324108)
			(xy 447.380868 -252.324108) (xy 447.3862 -252.32445) (xy 447.393744 -252.331985) (xy 447.394076 -252.337316)
			(xy 447.394076 -252.337824) (xy 447.394076 -252.832108) (xy 453.43826 -252.832108) (xy 453.43826 -252.33757)
			(xy 453.438705 -252.332257) (xy 453.446164 -252.324687) (xy 453.451468 -252.324108) (xy 453.967596 -252.324108)
			(xy 453.975406 -252.323791) (xy 453.990277 -252.319007) (xy 453.996806 -252.31471) (xy 454.017895 -252.300361)
			(xy 454.063556 -252.27763) (xy 454.112162 -252.262171) (xy 454.162565 -252.254348) (xy 454.213571 -252.254348)
			(xy 454.263974 -252.262171) (xy 454.31258 -252.27763) (xy 454.358241 -252.300361) (xy 454.37933 -252.31471)
			(xy 454.385855 -252.319012) (xy 454.40073 -252.323788) (xy 454.40854 -252.324108) (xy 454.924668 -252.324108)
			(xy 454.93 -252.32445) (xy 454.937544 -252.331985) (xy 454.937876 -252.337316) (xy 454.937876 -252.337824)
			(xy 454.937876 -252.832108) (xy 454.937576 -252.837449) (xy 454.93001 -252.844992) (xy 454.924668 -252.845316)
			(xy 454.408794 -252.845316) (xy 454.40092 -252.845614) (xy 454.385917 -252.850391) (xy 454.37933 -252.854714)
			(xy 454.35826 -252.869117) (xy 454.312613 -252.891944) (xy 454.264004 -252.907498) (xy 454.213585 -252.915413)
			(xy 454.188068 -252.915928) (xy 454.162549 -252.915416) (xy 454.112123 -252.907528) (xy 454.063511 -252.891974)
			(xy 454.017872 -252.869126) (xy 453.996806 -252.854714) (xy 453.990214 -252.8504) (xy 453.975214 -252.845612)
			(xy 453.967342 -252.845316) (xy 453.451468 -252.845316) (xy 453.446203 -252.844827) (xy 453.438763 -252.837374)
			(xy 453.43826 -252.832108) (xy 447.394076 -252.832108) (xy 447.393776 -252.837449) (xy 447.38621 -252.844992)
			(xy 447.380868 -252.845316) (xy 446.864994 -252.845316) (xy 446.85712 -252.845614) (xy 446.842117 -252.850391)
			(xy 446.83553 -252.854714) (xy 446.81446 -252.869117) (xy 446.768813 -252.891944) (xy 446.720204 -252.907498)
			(xy 446.669785 -252.915413) (xy 446.644268 -252.915928) (xy 446.618749 -252.915416) (xy 446.568323 -252.907528)
			(xy 446.519711 -252.891974) (xy 446.474072 -252.869126) (xy 446.453006 -252.854714) (xy 446.446414 -252.8504)
			(xy 446.431414 -252.845612) (xy 446.423542 -252.845316) (xy 445.907668 -252.845316) (xy 445.902403 -252.844827)
			(xy 445.894963 -252.837374) (xy 445.89446 -252.832108) (xy 439.850276 -252.832108) (xy 439.849976 -252.837449)
			(xy 439.84241 -252.844992) (xy 439.837068 -252.845316) (xy 439.83656 -252.845316) (xy 439.32094 -252.845316)
			(xy 439.313064 -252.845591) (xy 439.298061 -252.850384) (xy 439.291476 -252.854714) (xy 439.270393 -252.869097)
			(xy 439.22475 -252.891928) (xy 439.176146 -252.907489) (xy 439.12573 -252.91541) (xy 439.100214 -252.915928)
			(xy 439.074694 -252.915443) (xy 439.024267 -252.907546) (xy 438.975655 -252.891985) (xy 438.930017 -252.869129)
			(xy 438.908952 -252.854714) (xy 438.902372 -252.850379) (xy 438.887363 -252.845604) (xy 438.879488 -252.845316)
			(xy 438.363614 -252.845316) (xy 438.358301 -252.844862) (xy 438.350727 -252.837412) (xy 438.350152 -252.832108)
			(xy 432.305968 -252.832108) (xy 432.305675 -252.837451) (xy 432.298104 -252.844994) (xy 432.29276 -252.845316)
			(xy 431.776886 -252.845316) (xy 431.769012 -252.845611) (xy 431.754008 -252.85039) (xy 431.747422 -252.854714)
			(xy 431.726354 -252.86912) (xy 431.680706 -252.891946) (xy 431.632097 -252.9075) (xy 431.581678 -252.915414)
			(xy 431.55616 -252.915928) (xy 431.530641 -252.91542) (xy 431.480215 -252.90753) (xy 431.431603 -252.891976)
			(xy 431.385964 -252.869126) (xy 431.364898 -252.854714) (xy 431.358308 -252.850397) (xy 431.343307 -252.845611)
			(xy 431.335434 -252.845316) (xy 430.81956 -252.845316) (xy 430.814294 -252.844833) (xy 430.806854 -252.837375)
			(xy 430.806352 -252.832108) (xy 424.762168 -252.832108) (xy 424.761875 -252.837451) (xy 424.754304 -252.844994)
			(xy 424.74896 -252.845316) (xy 424.748452 -252.845316) (xy 424.232832 -252.845316) (xy 424.224956 -252.845588)
			(xy 424.209953 -252.850383) (xy 424.203368 -252.854714) (xy 424.182287 -252.8691) (xy 424.136644 -252.891931)
			(xy 424.088039 -252.90749) (xy 424.037622 -252.91541) (xy 424.012106 -252.915928) (xy 423.986586 -252.915447)
			(xy 423.936158 -252.907549) (xy 423.887547 -252.891986) (xy 423.841909 -252.86913) (xy 423.820844 -252.854714)
			(xy 423.814266 -252.850376) (xy 423.799256 -252.845603) (xy 423.79138 -252.845316) (xy 423.275506 -252.845316)
			(xy 423.270192 -252.844868) (xy 423.262618 -252.837413) (xy 423.262044 -252.832108) (xy 417.21786 -252.832108)
			(xy 417.217574 -252.837453) (xy 417.209999 -252.844997) (xy 417.204652 -252.845316) (xy 415.731452 -252.845316)
			(xy 415.726185 -252.844838) (xy 415.718746 -252.837376) (xy 415.718244 -252.832108) (xy 308.118256 -252.832108)
			(xy 308.117716 -252.83736) (xy 308.110299 -252.8448) (xy 308.105048 -252.845316) (xy 308.10454 -252.845316)
			(xy 306.631594 -252.845316) (xy 306.626279 -252.844876) (xy 306.618705 -252.837415) (xy 306.618132 -252.832108)
			(xy 300.573948 -252.832108) (xy 300.573415 -252.837362) (xy 300.565993 -252.844802) (xy 300.56074 -252.845316)
			(xy 300.044866 -252.845316) (xy 300.036991 -252.845602) (xy 300.021988 -252.850387) (xy 300.015402 -252.854714)
			(xy 299.994312 -252.869086) (xy 299.948672 -252.89192) (xy 299.90007 -252.907483) (xy 299.849656 -252.915408)
			(xy 299.82414 -252.915928) (xy 299.79862 -252.91543) (xy 299.748194 -252.907537) (xy 299.699582 -252.89198)
			(xy 299.653943 -252.869128) (xy 299.632878 -252.854714) (xy 299.626292 -252.850389) (xy 299.611288 -252.845608)
			(xy 299.603414 -252.845316) (xy 299.08754 -252.845316) (xy 299.082215 -252.844947) (xy 299.074672 -252.837432)
			(xy 299.074332 -252.832108) (xy 293.030148 -252.832108) (xy 293.029615 -252.837362) (xy 293.022193 -252.844802)
			(xy 293.01694 -252.845316) (xy 293.016432 -252.845316) (xy 292.500812 -252.845316) (xy 292.492939 -252.845622)
			(xy 292.477935 -252.850394) (xy 292.471348 -252.854714) (xy 292.450273 -252.869109) (xy 292.404627 -252.891938)
			(xy 292.356021 -252.907495) (xy 292.305603 -252.915412) (xy 292.280086 -252.915928) (xy 292.254567 -252.915407)
			(xy 292.204142 -252.907521) (xy 292.15553 -252.89197) (xy 292.10989 -252.869125) (xy 292.088824 -252.854714)
			(xy 292.082228 -252.850407) (xy 292.067231 -252.845615) (xy 292.05936 -252.845316) (xy 291.543486 -252.845316)
			(xy 291.53817 -252.844881) (xy 291.530597 -252.837416) (xy 291.530024 -252.832108) (xy 285.48584 -252.832108)
			(xy 285.485314 -252.837364) (xy 285.477887 -252.844804) (xy 285.472632 -252.845316) (xy 284.956758 -252.845316)
			(xy 284.948883 -252.845599) (xy 284.933879 -252.850386) (xy 284.927294 -252.854714) (xy 284.906206 -252.869089)
			(xy 284.860565 -252.891922) (xy 284.811962 -252.907485) (xy 284.761548 -252.915409) (xy 284.736032 -252.915928)
			(xy 284.710512 -252.915434) (xy 284.660085 -252.90754) (xy 284.611474 -252.891981) (xy 284.565835 -252.869128)
			(xy 284.54477 -252.854714) (xy 284.538186 -252.850386) (xy 284.52318 -252.845607) (xy 284.515306 -252.845316)
			(xy 283.999432 -252.845316) (xy 283.994106 -252.844952) (xy 283.986564 -252.837433) (xy 283.986224 -252.832108)
			(xy 277.94204 -252.832108) (xy 277.941514 -252.837364) (xy 277.934087 -252.844804) (xy 277.928832 -252.845316)
			(xy 277.412958 -252.845316) (xy 277.405083 -252.845599) (xy 277.390079 -252.850386) (xy 277.383494 -252.854714)
			(xy 277.362406 -252.869089) (xy 277.316765 -252.891922) (xy 277.268162 -252.907485) (xy 277.217748 -252.915409)
			(xy 277.192232 -252.915928) (xy 277.166712 -252.915434) (xy 277.116285 -252.90754) (xy 277.067674 -252.891981)
			(xy 277.022035 -252.869128) (xy 277.00097 -252.854714) (xy 276.994386 -252.850386) (xy 276.97938 -252.845607)
			(xy 276.971506 -252.845316) (xy 276.455632 -252.845316) (xy 276.450306 -252.844952) (xy 276.442764 -252.837433)
			(xy 276.442424 -252.832108) (xy 270.39824 -252.832108) (xy 270.397714 -252.837364) (xy 270.390287 -252.844804)
			(xy 270.385032 -252.845316) (xy 270.384524 -252.845316) (xy 269.868904 -252.845316) (xy 269.861031 -252.845619)
			(xy 269.846027 -252.850393) (xy 269.83944 -252.854714) (xy 269.818367 -252.869112) (xy 269.772721 -252.89194)
			(xy 269.724113 -252.907496) (xy 269.673695 -252.915413) (xy 269.648178 -252.915928) (xy 269.622659 -252.915411)
			(xy 269.572233 -252.907524) (xy 269.523622 -252.891972) (xy 269.477982 -252.869125) (xy 269.456916 -252.854714)
			(xy 269.450322 -252.850404) (xy 269.435324 -252.845614) (xy 269.427452 -252.845316) (xy 268.911578 -252.845316)
			(xy 268.906261 -252.844886) (xy 268.898688 -252.837418) (xy 268.898116 -252.832108) (xy 206.997808 -252.832108)
			(xy 206.997808 -252.832362) (xy 206.997257 -252.83765) (xy 206.989875 -252.845221) (xy 206.9846 -252.845824)
			(xy 206.468726 -252.845824) (xy 206.460916 -252.846144) (xy 206.446045 -252.850925) (xy 206.439516 -252.855222)
			(xy 206.418385 -252.869557) (xy 206.372665 -252.892288) (xy 206.323994 -252.907722) (xy 206.27353 -252.915493)
			(xy 206.248 -252.915928) (xy 206.222469 -252.915498) (xy 206.172005 -252.907721) (xy 206.123332 -252.89229)
			(xy 206.077605 -252.869571) (xy 206.056484 -252.855222) (xy 206.049954 -252.850928) (xy 206.035083 -252.846147)
			(xy 206.027274 -252.845824) (xy 205.5114 -252.845824) (xy 205.506141 -252.845307) (xy 205.4987 -252.837874)
			(xy 205.498192 -252.832616) (xy 199.453982 -252.832616) (xy 199.453457 -252.83765) (xy 199.446075 -252.845221)
			(xy 199.4408 -252.845824) (xy 198.924926 -252.845824) (xy 198.917116 -252.846144) (xy 198.902245 -252.850925)
			(xy 198.895716 -252.855222) (xy 198.874585 -252.869557) (xy 198.828865 -252.892288) (xy 198.780194 -252.907722)
			(xy 198.72973 -252.915493) (xy 198.7042 -252.915928) (xy 198.678669 -252.915498) (xy 198.628205 -252.907721)
			(xy 198.579532 -252.89229) (xy 198.533805 -252.869571) (xy 198.512684 -252.855222) (xy 198.506154 -252.850928)
			(xy 198.491283 -252.846147) (xy 198.483474 -252.845824) (xy 197.9676 -252.845824) (xy 197.962341 -252.845307)
			(xy 197.9549 -252.837874) (xy 197.954392 -252.832616) (xy 191.910181 -252.832616) (xy 191.909629 -252.83771)
			(xy 191.902091 -252.845296) (xy 191.896746 -252.845824) (xy 191.380872 -252.845824) (xy 191.37306 -252.846122)
			(xy 191.358189 -252.850918) (xy 191.351662 -252.855222) (xy 191.330546 -252.86958) (xy 191.284821 -252.892306)
			(xy 191.236145 -252.907734) (xy 191.185678 -252.915497) (xy 191.160146 -252.915928) (xy 191.134616 -252.915475)
			(xy 191.084153 -252.907705) (xy 191.03548 -252.892281) (xy 190.989752 -252.869568) (xy 190.96863 -252.855222)
			(xy 190.96209 -252.850946) (xy 190.947226 -252.846153) (xy 190.93942 -252.845824) (xy 190.423546 -252.845824)
			(xy 190.418108 -252.845486) (xy 190.410417 -252.8378) (xy 190.410084 -252.832362) (xy 184.3659 -252.832362)
			(xy 184.365356 -252.837652) (xy 184.357969 -252.845223) (xy 184.352692 -252.845824) (xy 183.836818 -252.845824)
			(xy 183.829008 -252.846141) (xy 183.814137 -252.850924) (xy 183.807608 -252.855222) (xy 183.786479 -252.86956)
			(xy 183.740758 -252.89229) (xy 183.692087 -252.907724) (xy 183.641622 -252.915493) (xy 183.616092 -252.915928)
			(xy 183.590561 -252.915502) (xy 183.540097 -252.907724) (xy 183.491424 -252.892292) (xy 183.445697 -252.869572)
			(xy 183.424576 -252.855222) (xy 183.418048 -252.850925) (xy 183.403175 -252.846145) (xy 183.395366 -252.845824)
			(xy 182.879492 -252.845824) (xy 182.874232 -252.845312) (xy 182.866791 -252.837876) (xy 182.866284 -252.832616)
			(xy 176.822073 -252.832616) (xy 176.821528 -252.837712) (xy 176.813985 -252.845298) (xy 176.808638 -252.845824)
			(xy 176.292764 -252.845824) (xy 176.284956 -252.846161) (xy 176.270084 -252.850931) (xy 176.263554 -252.855222)
			(xy 176.24244 -252.869584) (xy 176.196714 -252.892309) (xy 176.148038 -252.907735) (xy 176.09757 -252.915497)
			(xy 176.072038 -252.915928) (xy 176.046508 -252.915479) (xy 175.996045 -252.907708) (xy 175.947372 -252.892283)
			(xy 175.901644 -252.869569) (xy 175.880522 -252.855222) (xy 175.873983 -252.850943) (xy 175.859119 -252.846152)
			(xy 175.851312 -252.845824) (xy 175.335438 -252.845824) (xy 175.329999 -252.845492) (xy 175.322308 -252.837801)
			(xy 175.321976 -252.832362) (xy 169.277792 -252.832362) (xy 169.277255 -252.837654) (xy 169.269863 -252.845225)
			(xy 169.264584 -252.845824) (xy 167.791384 -252.845824) (xy 167.786123 -252.845318) (xy 167.778682 -252.837877)
			(xy 167.778176 -252.832616) (xy 60.17817 -252.832616) (xy 60.177798 -252.837786) (xy 60.170148 -252.845472)
			(xy 60.164726 -252.845824) (xy 58.691526 -252.845824) (xy 58.686085 -252.8455) (xy 58.678396 -252.837803)
			(xy 58.678064 -252.832362) (xy 52.63388 -252.832362) (xy 52.633354 -252.837657) (xy 52.625954 -252.845229)
			(xy 52.620672 -252.845824) (xy 52.104798 -252.845824) (xy 52.096987 -252.846133) (xy 52.082116 -252.850922)
			(xy 52.075588 -252.855222) (xy 52.054465 -252.869569) (xy 52.008742 -252.892297) (xy 51.960069 -252.907728)
			(xy 51.909603 -252.915495) (xy 51.884072 -252.915928) (xy 51.858541 -252.915512) (xy 51.808076 -252.907731)
			(xy 51.759403 -252.892296) (xy 51.713677 -252.869573) (xy 51.692556 -252.855222) (xy 51.686032 -252.850918)
			(xy 51.671156 -252.846143) (xy 51.663346 -252.845824) (xy 51.147472 -252.845824) (xy 51.14221 -252.845326)
			(xy 51.13477 -252.837879) (xy 51.134264 -252.832616) (xy 45.090062 -252.832616) (xy 45.089697 -252.837788)
			(xy 45.082042 -252.845475) (xy 45.076618 -252.845824) (xy 44.560744 -252.845824) (xy 44.552935 -252.846153)
			(xy 44.538064 -252.850928) (xy 44.531534 -252.855222) (xy 44.510426 -252.869592) (xy 44.464698 -252.892315)
			(xy 44.41602 -252.90774) (xy 44.36555 -252.915499) (xy 44.340018 -252.915928) (xy 44.314488 -252.915489)
			(xy 44.264024 -252.907715) (xy 44.215351 -252.892287) (xy 44.169624 -252.86957) (xy 44.148502 -252.855222)
			(xy 44.141968 -252.850935) (xy 44.1271 -252.846149) (xy 44.119292 -252.845824) (xy 43.603418 -252.845824)
			(xy 43.597976 -252.845505) (xy 43.590287 -252.837804) (xy 43.589956 -252.832362) (xy 37.545772 -252.832362)
			(xy 37.545253 -252.837659) (xy 37.537849 -252.845231) (xy 37.532564 -252.845824) (xy 37.01669 -252.845824)
			(xy 37.008879 -252.846129) (xy 36.994008 -252.850921) (xy 36.98748 -252.855222) (xy 36.966359 -252.869573)
			(xy 36.920635 -252.8923) (xy 36.871962 -252.90773) (xy 36.821495 -252.915496) (xy 36.795964 -252.915928)
			(xy 36.770433 -252.915516) (xy 36.719968 -252.907734) (xy 36.671295 -252.892298) (xy 36.625569 -252.869573)
			(xy 36.604448 -252.855222) (xy 36.597926 -252.850914) (xy 36.583049 -252.846141) (xy 36.575238 -252.845824)
			(xy 36.059364 -252.845824) (xy 36.054101 -252.845331) (xy 36.046661 -252.83788) (xy 36.046156 -252.832616)
			(xy 30.001947 -252.832616) (xy 30.001453 -252.837659) (xy 29.994049 -252.845231) (xy 29.988764 -252.845824)
			(xy 29.47289 -252.845824) (xy 29.465079 -252.846129) (xy 29.450208 -252.850921) (xy 29.44368 -252.855222)
			(xy 29.422559 -252.869573) (xy 29.376835 -252.8923) (xy 29.328162 -252.90773) (xy 29.277695 -252.915496)
			(xy 29.252164 -252.915928) (xy 29.226633 -252.915516) (xy 29.176168 -252.907734) (xy 29.127495 -252.892298)
			(xy 29.081769 -252.869573) (xy 29.060648 -252.855222) (xy 29.054126 -252.850914) (xy 29.039249 -252.846141)
			(xy 29.031438 -252.845824) (xy 28.515564 -252.845824) (xy 28.510301 -252.845331) (xy 28.502861 -252.83788)
			(xy 28.502356 -252.832616) (xy 22.458154 -252.832616) (xy 22.457796 -252.837789) (xy 22.450136 -252.845477)
			(xy 22.44471 -252.845824) (xy 21.928836 -252.845824) (xy 21.921027 -252.846149) (xy 21.906155 -252.850927)
			(xy 21.899626 -252.855222) (xy 21.878492 -252.869553) (xy 21.832773 -252.892284) (xy 21.784104 -252.90772)
			(xy 21.73364 -252.915492) (xy 21.70811 -252.915928) (xy 21.68258 -252.915493) (xy 21.632115 -252.907718)
			(xy 21.583443 -252.892288) (xy 21.537716 -252.86957) (xy 21.516594 -252.855222) (xy 21.510062 -252.850932)
			(xy 21.495192 -252.846148) (xy 21.487384 -252.845824) (xy 20.97151 -252.845824) (xy 20.966067 -252.84551)
			(xy 20.958378 -252.837806) (xy 20.958048 -252.832362) (xy 2.509012 -252.832362) (xy 2.509012 -253.6825)
			(xy 16.85798 -253.6825) (xy 16.85798 -253.187962) (xy 16.858258 -253.182512) (xy 16.86599 -253.174826)
			(xy 16.871442 -253.1745) (xy 17.38757 -253.1745) (xy 17.395379 -253.174174) (xy 17.41025 -253.169396)
			(xy 17.41678 -253.165102) (xy 17.437869 -253.150753) (xy 17.48353 -253.128022) (xy 17.532136 -253.112563)
			(xy 17.582539 -253.10474) (xy 17.633545 -253.10474) (xy 17.683948 -253.112563) (xy 17.732554 -253.128022)
			(xy 17.778215 -253.150753) (xy 17.799304 -253.165102) (xy 17.805835 -253.169394) (xy 17.820705 -253.174176)
			(xy 17.828514 -253.1745) (xy 18.344642 -253.1745) (xy 18.350002 -253.175019) (xy 18.357583 -253.182602)
			(xy 18.358104 -253.187962) (xy 18.358104 -253.6825) (xy 24.402288 -253.6825) (xy 24.402288 -253.187962)
			(xy 24.402704 -253.182642) (xy 24.410183 -253.17507) (xy 24.415496 -253.1745) (xy 24.931624 -253.1745)
			(xy 24.939435 -253.174196) (xy 24.954306 -253.169403) (xy 24.960834 -253.165102) (xy 24.981923 -253.150753)
			(xy 25.027584 -253.128022) (xy 25.07619 -253.112563) (xy 25.126593 -253.10474) (xy 25.177599 -253.10474)
			(xy 25.228002 -253.112563) (xy 25.276608 -253.128022) (xy 25.322269 -253.150753) (xy 25.343358 -253.165102)
			(xy 25.349877 -253.169414) (xy 25.364757 -253.174184) (xy 25.372568 -253.1745) (xy 25.888696 -253.1745)
			(xy 25.89403 -253.17483) (xy 25.901571 -253.182374) (xy 25.901904 -253.187708) (xy 25.901904 -253.188216)
			(xy 25.901904 -253.6825) (xy 31.946088 -253.6825) (xy 31.946088 -253.187962) (xy 31.946504 -253.182642)
			(xy 31.953983 -253.17507) (xy 31.959296 -253.1745) (xy 32.475424 -253.1745) (xy 32.483235 -253.174196)
			(xy 32.498106 -253.169403) (xy 32.504634 -253.165102) (xy 32.525723 -253.150753) (xy 32.571384 -253.128022)
			(xy 32.61999 -253.112563) (xy 32.670393 -253.10474) (xy 32.721399 -253.10474) (xy 32.771802 -253.112563)
			(xy 32.820408 -253.128022) (xy 32.866069 -253.150753) (xy 32.887158 -253.165102) (xy 32.893677 -253.169414)
			(xy 32.908557 -253.174184) (xy 32.916368 -253.1745) (xy 33.432496 -253.1745) (xy 33.43783 -253.17483)
			(xy 33.445371 -253.182374) (xy 33.445704 -253.187708) (xy 33.445704 -253.188216) (xy 33.445704 -253.6825)
			(xy 39.489888 -253.6825) (xy 39.489888 -253.187962) (xy 39.49042 -253.182606) (xy 39.497994 -253.175025)
			(xy 39.50335 -253.1745) (xy 40.019478 -253.1745) (xy 40.027287 -253.174177) (xy 40.042159 -253.169397)
			(xy 40.048688 -253.165102) (xy 40.069777 -253.150753) (xy 40.115438 -253.128022) (xy 40.164044 -253.112563)
			(xy 40.214447 -253.10474) (xy 40.265453 -253.10474) (xy 40.315856 -253.112563) (xy 40.364462 -253.128022)
			(xy 40.410123 -253.150753) (xy 40.431212 -253.165102) (xy 40.437741 -253.169397) (xy 40.452613 -253.174178)
			(xy 40.460422 -253.1745) (xy 40.97655 -253.1745) (xy 40.981911 -253.175014) (xy 40.989491 -253.182601)
			(xy 40.990012 -253.187962) (xy 40.990012 -253.6825) (xy 47.034196 -253.6825) (xy 47.034196 -253.187962)
			(xy 47.034692 -253.182663) (xy 47.042116 -253.175097) (xy 47.047404 -253.1745) (xy 47.563532 -253.1745)
			(xy 47.571339 -253.174158) (xy 47.586211 -253.169391) (xy 47.592742 -253.165102) (xy 47.613831 -253.150753)
			(xy 47.659492 -253.128022) (xy 47.708098 -253.112563) (xy 47.758501 -253.10474) (xy 47.809507 -253.10474)
			(xy 47.85991 -253.112563) (xy 47.908516 -253.128022) (xy 47.954177 -253.150753) (xy 47.975266 -253.165102)
			(xy 47.981806 -253.169379) (xy 47.996669 -253.174171) (xy 48.004476 -253.1745) (xy 48.520604 -253.1745)
			(xy 48.525939 -253.174825) (xy 48.53348 -253.182373) (xy 48.533812 -253.187708) (xy 48.533812 -253.188216)
			(xy 48.533812 -253.6825) (xy 54.577996 -253.6825) (xy 54.577996 -253.187962) (xy 54.578521 -253.182604)
			(xy 54.5861 -253.175023) (xy 54.591458 -253.1745) (xy 56.064658 -253.1745) (xy 56.070078 -253.174904)
			(xy 56.077764 -253.182544) (xy 56.07812 -253.187962) (xy 56.07812 -253.6825) (xy 163.678108 -253.6825)
			(xy 163.678108 -253.187962) (xy 163.678594 -253.182661) (xy 163.686025 -253.175094) (xy 163.691316 -253.1745)
			(xy 165.164516 -253.1745) (xy 165.169783 -253.174985) (xy 165.177225 -253.18244) (xy 165.177724 -253.187708)
			(xy 165.177724 -253.188216) (xy 165.177724 -253.6825) (xy 171.221908 -253.6825) (xy 171.221908 -253.187962)
			(xy 171.222422 -253.182601) (xy 171.230008 -253.175019) (xy 171.23537 -253.1745) (xy 171.751498 -253.1745)
			(xy 171.759308 -253.174186) (xy 171.774179 -253.1694) (xy 171.780708 -253.165102) (xy 171.801797 -253.150753)
			(xy 171.847458 -253.128022) (xy 171.896064 -253.112563) (xy 171.946467 -253.10474) (xy 171.997473 -253.10474)
			(xy 172.047876 -253.112563) (xy 172.096482 -253.128022) (xy 172.142143 -253.150753) (xy 172.163232 -253.165102)
			(xy 172.169757 -253.169404) (xy 172.184632 -253.17418) (xy 172.192442 -253.1745) (xy 172.70857 -253.1745)
			(xy 172.713921 -253.175066) (xy 172.721507 -253.182613) (xy 172.722032 -253.187962) (xy 172.722032 -253.6825)
			(xy 178.766216 -253.6825) (xy 178.766216 -253.187962) (xy 178.766695 -253.182659) (xy 178.774131 -253.175091)
			(xy 178.779424 -253.1745) (xy 179.295552 -253.1745) (xy 179.30336 -253.174166) (xy 179.318232 -253.169394)
			(xy 179.324762 -253.165102) (xy 179.345851 -253.150753) (xy 179.391512 -253.128022) (xy 179.440118 -253.112563)
			(xy 179.490521 -253.10474) (xy 179.541527 -253.10474) (xy 179.59193 -253.112563) (xy 179.640536 -253.128022)
			(xy 179.686197 -253.150753) (xy 179.707286 -253.165102) (xy 179.713821 -253.169387) (xy 179.728688 -253.174174)
			(xy 179.736496 -253.1745) (xy 180.252624 -253.1745) (xy 180.257892 -253.17498) (xy 180.265333 -253.182439)
			(xy 180.265832 -253.187708) (xy 180.265832 -253.188216) (xy 180.265832 -253.6825) (xy 186.310016 -253.6825)
			(xy 186.310016 -253.187962) (xy 186.310523 -253.182599) (xy 186.318114 -253.175017) (xy 186.323478 -253.1745)
			(xy 186.839606 -253.1745) (xy 186.847416 -253.174189) (xy 186.862288 -253.169401) (xy 186.868816 -253.165102)
			(xy 186.889905 -253.150753) (xy 186.935566 -253.128022) (xy 186.984172 -253.112563) (xy 187.034575 -253.10474)
			(xy 187.085581 -253.10474) (xy 187.135984 -253.112563) (xy 187.18459 -253.128022) (xy 187.230251 -253.150753)
			(xy 187.25134 -253.165102) (xy 187.257863 -253.169408) (xy 187.27274 -253.174182) (xy 187.28055 -253.1745)
			(xy 187.796678 -253.1745) (xy 187.80203 -253.175061) (xy 187.809615 -253.182612) (xy 187.81014 -253.187962)
			(xy 187.81014 -253.6825) (xy 193.854324 -253.6825) (xy 193.854324 -253.187962) (xy 193.854796 -253.182657)
			(xy 193.862236 -253.175089) (xy 193.867532 -253.1745) (xy 194.38366 -253.1745) (xy 194.391469 -253.174169)
			(xy 194.40634 -253.169395) (xy 194.41287 -253.165102) (xy 194.433959 -253.150753) (xy 194.47962 -253.128022)
			(xy 194.528226 -253.112563) (xy 194.578629 -253.10474) (xy 194.629635 -253.10474) (xy 194.680038 -253.112563)
			(xy 194.728644 -253.128022) (xy 194.774305 -253.150753) (xy 194.795394 -253.165102) (xy 194.801927 -253.16939)
			(xy 194.816796 -253.174175) (xy 194.824604 -253.1745) (xy 195.340732 -253.1745) (xy 195.346001 -253.174974)
			(xy 195.353442 -253.182438) (xy 195.35394 -253.187708) (xy 195.35394 -253.188216) (xy 195.35394 -253.6825)
			(xy 201.398124 -253.6825) (xy 201.398124 -253.187962) (xy 201.398596 -253.182657) (xy 201.406036 -253.175089)
			(xy 201.411332 -253.1745) (xy 201.92746 -253.1745) (xy 201.935269 -253.174169) (xy 201.95014 -253.169395)
			(xy 201.95667 -253.165102) (xy 201.977759 -253.150753) (xy 202.02342 -253.128022) (xy 202.072026 -253.112563)
			(xy 202.122429 -253.10474) (xy 202.173435 -253.10474) (xy 202.223838 -253.112563) (xy 202.272444 -253.128022)
			(xy 202.318105 -253.150753) (xy 202.339194 -253.165102) (xy 202.345727 -253.16939) (xy 202.360596 -253.174175)
			(xy 202.368404 -253.1745) (xy 202.884532 -253.1745) (xy 202.889801 -253.174974) (xy 202.897242 -253.182438)
			(xy 202.89774 -253.187708) (xy 202.89774 -253.188216) (xy 202.89774 -253.682246) (xy 264.798048 -253.682246)
			(xy 264.798048 -253.187708) (xy 264.798595 -253.182457) (xy 264.806007 -253.175016) (xy 264.811256 -253.1745)
			(xy 264.811764 -253.1745) (xy 265.327638 -253.1745) (xy 265.335446 -253.17416) (xy 265.350317 -253.169392)
			(xy 265.356848 -253.165102) (xy 265.377937 -253.150753) (xy 265.423598 -253.128022) (xy 265.472204 -253.112563)
			(xy 265.522607 -253.10474) (xy 265.573613 -253.10474) (xy 265.624016 -253.112563) (xy 265.672622 -253.128022)
			(xy 265.718283 -253.150753) (xy 265.739372 -253.165102) (xy 265.74591 -253.169382) (xy 265.760775 -253.174172)
			(xy 265.768582 -253.1745) (xy 266.28471 -253.1745) (xy 266.290006 -253.175012) (xy 266.297574 -253.182423)
			(xy 266.298172 -253.187708) (xy 266.298172 -253.682246) (xy 266.298149 -253.6825) (xy 272.342356 -253.6825)
			(xy 272.342356 -253.681992) (xy 272.342356 -253.187708) (xy 272.342896 -253.182455) (xy 272.350313 -253.175014)
			(xy 272.355564 -253.1745) (xy 272.871692 -253.1745) (xy 272.879502 -253.174183) (xy 272.894373 -253.169399)
			(xy 272.900902 -253.165102) (xy 272.921991 -253.150753) (xy 272.967652 -253.128022) (xy 273.016258 -253.112563)
			(xy 273.066661 -253.10474) (xy 273.117667 -253.10474) (xy 273.16807 -253.112563) (xy 273.216676 -253.128022)
			(xy 273.262337 -253.150753) (xy 273.283426 -253.165102) (xy 273.289952 -253.169402) (xy 273.304826 -253.17418)
			(xy 273.312636 -253.1745) (xy 273.828764 -253.1745) (xy 273.834093 -253.174852) (xy 273.841637 -253.182379)
			(xy 273.841972 -253.187708) (xy 273.841972 -253.682246) (xy 273.841947 -253.6825) (xy 279.886156 -253.6825)
			(xy 279.886156 -253.681992) (xy 279.886156 -253.187708) (xy 279.886696 -253.182455) (xy 279.894113 -253.175014)
			(xy 279.899364 -253.1745) (xy 280.415492 -253.1745) (xy 280.423302 -253.174183) (xy 280.438173 -253.169399)
			(xy 280.444702 -253.165102) (xy 280.465791 -253.150753) (xy 280.511452 -253.128022) (xy 280.560058 -253.112563)
			(xy 280.610461 -253.10474) (xy 280.661467 -253.10474) (xy 280.71187 -253.112563) (xy 280.760476 -253.128022)
			(xy 280.806137 -253.150753) (xy 280.827226 -253.165102) (xy 280.833752 -253.169402) (xy 280.848626 -253.17418)
			(xy 280.856436 -253.1745) (xy 281.372564 -253.1745) (xy 281.377893 -253.174852) (xy 281.385437 -253.182379)
			(xy 281.385772 -253.187708) (xy 281.385772 -253.682246) (xy 287.429956 -253.682246) (xy 287.429956 -253.187708)
			(xy 287.430496 -253.182455) (xy 287.437913 -253.175014) (xy 287.443164 -253.1745) (xy 287.443672 -253.1745)
			(xy 287.959546 -253.1745) (xy 287.967354 -253.174164) (xy 287.982226 -253.169393) (xy 287.988756 -253.165102)
			(xy 288.009845 -253.150753) (xy 288.055506 -253.128022) (xy 288.104112 -253.112563) (xy 288.154515 -253.10474)
			(xy 288.205521 -253.10474) (xy 288.255924 -253.112563) (xy 288.30453 -253.128022) (xy 288.350191 -253.150753)
			(xy 288.37128 -253.165102) (xy 288.377817 -253.169385) (xy 288.392683 -253.174173) (xy 288.40049 -253.1745)
			(xy 288.916618 -253.1745) (xy 288.921915 -253.175006) (xy 288.929483 -253.182422) (xy 288.93008 -253.187708)
			(xy 288.93008 -253.682246) (xy 288.930056 -253.6825) (xy 294.974264 -253.6825) (xy 294.974264 -253.681992)
			(xy 294.974264 -253.187708) (xy 294.974797 -253.182453) (xy 294.982218 -253.175011) (xy 294.987472 -253.1745)
			(xy 295.5036 -253.1745) (xy 295.51141 -253.174186) (xy 295.526281 -253.1694) (xy 295.53281 -253.165102)
			(xy 295.553899 -253.150753) (xy 295.59956 -253.128022) (xy 295.648166 -253.112563) (xy 295.698569 -253.10474)
			(xy 295.749575 -253.10474) (xy 295.799978 -253.112563) (xy 295.848584 -253.128022) (xy 295.894245 -253.150753)
			(xy 295.915334 -253.165102) (xy 295.921859 -253.169405) (xy 295.936734 -253.174181) (xy 295.944544 -253.1745)
			(xy 296.460672 -253.1745) (xy 296.466003 -253.174846) (xy 296.473546 -253.182378) (xy 296.47388 -253.187708)
			(xy 296.47388 -253.682246) (xy 302.518064 -253.682246) (xy 302.518064 -253.187708) (xy 302.518597 -253.182453)
			(xy 302.526018 -253.175011) (xy 302.531272 -253.1745) (xy 304.004726 -253.1745) (xy 304.010024 -253.175001)
			(xy 304.017592 -253.182421) (xy 304.018188 -253.187708) (xy 304.018188 -253.682246) (xy 304.018164 -253.6825)
			(xy 411.618176 -253.6825) (xy 411.618176 -253.681992) (xy 411.618176 -253.187708) (xy 411.618698 -253.18245)
			(xy 411.626127 -253.175008) (xy 411.631384 -253.1745) (xy 413.104584 -253.1745) (xy 413.109916 -253.174838)
			(xy 413.117458 -253.182376) (xy 413.117792 -253.187708) (xy 413.117792 -253.682246) (xy 419.161976 -253.682246)
			(xy 419.161976 -253.187708) (xy 419.162498 -253.18245) (xy 419.169927 -253.175008) (xy 419.175184 -253.1745)
			(xy 419.175692 -253.1745) (xy 419.691566 -253.1745) (xy 419.699375 -253.174172) (xy 419.714246 -253.169396)
			(xy 419.720776 -253.165102) (xy 419.741865 -253.150753) (xy 419.787526 -253.128022) (xy 419.836132 -253.112563)
			(xy 419.886535 -253.10474) (xy 419.937541 -253.10474) (xy 419.987944 -253.112563) (xy 420.03655 -253.128022)
			(xy 420.082211 -253.150753) (xy 420.1033 -253.165102) (xy 420.109832 -253.169392) (xy 420.124702 -253.174176)
			(xy 420.13251 -253.1745) (xy 420.648638 -253.1745) (xy 420.653938 -253.174993) (xy 420.661504 -253.182419)
			(xy 420.6621 -253.187708) (xy 420.6621 -253.682246) (xy 420.662076 -253.6825) (xy 426.706284 -253.6825)
			(xy 426.706284 -253.681992) (xy 426.706284 -253.187708) (xy 426.706799 -253.182448) (xy 426.714233 -253.175005)
			(xy 426.719492 -253.1745) (xy 427.23562 -253.1745) (xy 427.243431 -253.174195) (xy 427.258302 -253.169403)
			(xy 427.26483 -253.165102) (xy 427.285919 -253.150753) (xy 427.33158 -253.128022) (xy 427.380186 -253.112563)
			(xy 427.430589 -253.10474) (xy 427.481595 -253.10474) (xy 427.531998 -253.112563) (xy 427.580604 -253.128022)
			(xy 427.626265 -253.150753) (xy 427.647354 -253.165102) (xy 427.653874 -253.169413) (xy 427.668753 -253.174184)
			(xy 427.676564 -253.1745) (xy 428.192692 -253.1745) (xy 428.198025 -253.174833) (xy 428.205567 -253.182375)
			(xy 428.2059 -253.187708) (xy 428.2059 -253.682246) (xy 434.250084 -253.682246) (xy 434.250084 -253.187708)
			(xy 434.250599 -253.182448) (xy 434.258033 -253.175005) (xy 434.263292 -253.1745) (xy 434.2638 -253.1745)
			(xy 434.779674 -253.1745) (xy 434.787483 -253.174175) (xy 434.802355 -253.169397) (xy 434.808884 -253.165102)
			(xy 434.829973 -253.150753) (xy 434.875634 -253.128022) (xy 434.92424 -253.112563) (xy 434.974643 -253.10474)
			(xy 435.025649 -253.10474) (xy 435.076052 -253.112563) (xy 435.124658 -253.128022) (xy 435.170319 -253.150753)
			(xy 435.191408 -253.165102) (xy 435.197938 -253.169395) (xy 435.212809 -253.174177) (xy 435.220618 -253.1745)
			(xy 435.736746 -253.1745) (xy 435.742035 -253.175055) (xy 435.749606 -253.182434) (xy 435.750208 -253.187708)
			(xy 435.750208 -253.682246) (xy 435.750183 -253.6825) (xy 441.794392 -253.6825) (xy 441.794392 -253.681992)
			(xy 441.794392 -253.187708) (xy 441.794732 -253.182377) (xy 441.802269 -253.174835) (xy 441.8076 -253.1745)
			(xy 442.323728 -253.1745) (xy 442.331539 -253.174198) (xy 442.34641 -253.169404) (xy 442.352938 -253.165102)
			(xy 442.374027 -253.150753) (xy 442.419688 -253.128022) (xy 442.468294 -253.112563) (xy 442.518697 -253.10474)
			(xy 442.569703 -253.10474) (xy 442.620106 -253.112563) (xy 442.668712 -253.128022) (xy 442.714373 -253.150753)
			(xy 442.735462 -253.165102) (xy 442.742003 -253.169378) (xy 442.756866 -253.17417) (xy 442.764672 -253.1745)
			(xy 443.2808 -253.1745) (xy 443.286134 -253.174827) (xy 443.293676 -253.182374) (xy 443.294008 -253.187708)
			(xy 443.294008 -253.682246) (xy 443.293981 -253.6825) (xy 449.338192 -253.6825) (xy 449.338192 -253.681992)
			(xy 449.338192 -253.187708) (xy 449.338532 -253.182377) (xy 449.346069 -253.174835) (xy 449.3514 -253.1745)
			(xy 449.867528 -253.1745) (xy 449.875339 -253.174198) (xy 449.89021 -253.169404) (xy 449.896738 -253.165102)
			(xy 449.917827 -253.150753) (xy 449.963488 -253.128022) (xy 450.012094 -253.112563) (xy 450.062497 -253.10474)
			(xy 450.113503 -253.10474) (xy 450.163906 -253.112563) (xy 450.212512 -253.128022) (xy 450.258173 -253.150753)
			(xy 450.279262 -253.165102) (xy 450.285803 -253.169378) (xy 450.300666 -253.17417) (xy 450.308472 -253.1745)
			(xy 450.8246 -253.1745) (xy 450.829934 -253.174827) (xy 450.837476 -253.182374) (xy 450.837808 -253.187708)
			(xy 450.837808 -253.682246) (xy 450.837246 -253.687533) (xy 450.829872 -253.695104) (xy 450.8246 -253.695708)
			(xy 450.308726 -253.695708) (xy 450.300917 -253.696031) (xy 450.286045 -253.70081) (xy 450.279516 -253.705106)
			(xy 450.258384 -253.719439) (xy 450.212664 -253.742171) (xy 450.163994 -253.757606) (xy 450.11353 -253.765377)
			(xy 450.088 -253.765812) (xy 450.06247 -253.765367) (xy 450.012007 -253.757592) (xy 449.963335 -253.742165)
			(xy 449.917607 -253.719452) (xy 449.896484 -253.705106) (xy 449.889955 -253.70081) (xy 449.875083 -253.69603)
			(xy 449.867274 -253.695708) (xy 449.3514 -253.695708) (xy 449.346137 -253.695205) (xy 449.338695 -253.687763)
			(xy 449.338192 -253.6825) (xy 443.293981 -253.6825) (xy 443.293446 -253.687533) (xy 443.286072 -253.695104)
			(xy 443.2808 -253.695708) (xy 442.764926 -253.695708) (xy 442.757117 -253.696031) (xy 442.742245 -253.70081)
			(xy 442.735716 -253.705106) (xy 442.714584 -253.719439) (xy 442.668864 -253.742171) (xy 442.620194 -253.757606)
			(xy 442.56973 -253.765377) (xy 442.5442 -253.765812) (xy 442.51867 -253.765367) (xy 442.468207 -253.757592)
			(xy 442.419535 -253.742165) (xy 442.373807 -253.719452) (xy 442.352684 -253.705106) (xy 442.346155 -253.70081)
			(xy 442.331283 -253.69603) (xy 442.323474 -253.695708) (xy 441.8076 -253.695708) (xy 441.802337 -253.695205)
			(xy 441.794895 -253.687763) (xy 441.794392 -253.6825) (xy 435.750183 -253.6825) (xy 435.749685 -253.687604)
			(xy 435.742104 -253.695185) (xy 435.736746 -253.695708) (xy 435.220872 -253.695708) (xy 435.213061 -253.696008)
			(xy 435.198189 -253.700803) (xy 435.191662 -253.705106) (xy 435.170545 -253.719462) (xy 435.12482 -253.742189)
			(xy 435.076145 -253.757617) (xy 435.025677 -253.765381) (xy 435.000146 -253.765812) (xy 434.974617 -253.765344)
			(xy 434.924155 -253.757576) (xy 434.875483 -253.742156) (xy 434.829753 -253.719449) (xy 434.80863 -253.705106)
			(xy 434.802091 -253.700828) (xy 434.787227 -253.696037) (xy 434.77942 -253.695708) (xy 434.263546 -253.695708)
			(xy 434.258199 -253.695123) (xy 434.250613 -253.68759) (xy 434.250084 -253.682246) (xy 428.2059 -253.682246)
			(xy 428.205345 -253.687535) (xy 428.197966 -253.695106) (xy 428.192692 -253.695708) (xy 427.676818 -253.695708)
			(xy 427.669008 -253.696028) (xy 427.654137 -253.700809) (xy 427.647608 -253.705106) (xy 427.626478 -253.719443)
			(xy 427.580758 -253.742173) (xy 427.532087 -253.757607) (xy 427.481622 -253.765377) (xy 427.456092 -253.765812)
			(xy 427.430562 -253.765371) (xy 427.380099 -253.757595) (xy 427.331427 -253.742167) (xy 427.285699 -253.719452)
			(xy 427.264576 -253.705106) (xy 427.258049 -253.700807) (xy 427.243175 -253.696029) (xy 427.235366 -253.695708)
			(xy 426.719492 -253.695708) (xy 426.714228 -253.695211) (xy 426.706786 -253.687764) (xy 426.706284 -253.6825)
			(xy 420.662076 -253.6825) (xy 420.661584 -253.687606) (xy 420.653999 -253.695187) (xy 420.648638 -253.695708)
			(xy 420.132764 -253.695708) (xy 420.124956 -253.696048) (xy 420.110085 -253.700816) (xy 420.103554 -253.705106)
			(xy 420.082439 -253.719466) (xy 420.036713 -253.742192) (xy 419.988038 -253.757619) (xy 419.93757 -253.765381)
			(xy 419.912038 -253.765812) (xy 419.886509 -253.765348) (xy 419.836047 -253.757579) (xy 419.787374 -253.742158)
			(xy 419.741645 -253.719449) (xy 419.720522 -253.705106) (xy 419.713985 -253.700825) (xy 419.699119 -253.696035)
			(xy 419.691312 -253.695708) (xy 419.175438 -253.695708) (xy 419.17009 -253.695129) (xy 419.162504 -253.687591)
			(xy 419.161976 -253.682246) (xy 413.117792 -253.682246) (xy 413.117244 -253.687536) (xy 413.109861 -253.695109)
			(xy 413.104584 -253.695708) (xy 411.631384 -253.695708) (xy 411.626119 -253.695216) (xy 411.618678 -253.687765)
			(xy 411.618176 -253.6825) (xy 304.018164 -253.6825) (xy 304.017683 -253.687609) (xy 304.01009 -253.695191)
			(xy 304.004726 -253.695708) (xy 302.531526 -253.695708) (xy 302.526176 -253.695137) (xy 302.518592 -253.687593)
			(xy 302.518064 -253.682246) (xy 296.47388 -253.682246) (xy 296.473343 -253.687539) (xy 296.465952 -253.695112)
			(xy 296.460672 -253.695708) (xy 295.944798 -253.695708) (xy 295.936988 -253.696019) (xy 295.922116 -253.700807)
			(xy 295.915588 -253.705106) (xy 295.894464 -253.719451) (xy 295.848741 -253.74218) (xy 295.800069 -253.757612)
			(xy 295.749603 -253.765379) (xy 295.724072 -253.765812) (xy 295.698542 -253.765381) (xy 295.648078 -253.757602)
			(xy 295.599406 -253.742171) (xy 295.553678 -253.719454) (xy 295.532556 -253.705106) (xy 295.526033 -253.7008)
			(xy 295.511156 -253.696026) (xy 295.503346 -253.695708) (xy 294.987472 -253.695708) (xy 294.982206 -253.695224)
			(xy 294.974765 -253.687767) (xy 294.974264 -253.6825) (xy 288.930056 -253.6825) (xy 288.929582 -253.687611)
			(xy 288.921984 -253.695193) (xy 288.916618 -253.695708) (xy 288.400744 -253.695708) (xy 288.392935 -253.696039)
			(xy 288.378064 -253.700813) (xy 288.371534 -253.705106) (xy 288.350425 -253.719475) (xy 288.304697 -253.742198)
			(xy 288.25602 -253.757623) (xy 288.20555 -253.765383) (xy 288.180018 -253.765812) (xy 288.154489 -253.765358)
			(xy 288.104026 -253.757586) (xy 288.055354 -253.742162) (xy 288.009625 -253.719451) (xy 287.988502 -253.705106)
			(xy 287.981969 -253.700817) (xy 287.9671 -253.696033) (xy 287.959292 -253.695708) (xy 287.443418 -253.695708)
			(xy 287.438067 -253.695142) (xy 287.430483 -253.687594) (xy 287.429956 -253.682246) (xy 281.385772 -253.682246)
			(xy 281.385242 -253.687541) (xy 281.377846 -253.695114) (xy 281.372564 -253.695708) (xy 280.85669 -253.695708)
			(xy 280.848879 -253.696016) (xy 280.834008 -253.700806) (xy 280.82748 -253.705106) (xy 280.806358 -253.719455)
			(xy 280.760635 -253.742183) (xy 280.711962 -253.757613) (xy 280.661495 -253.765379) (xy 280.635964 -253.765812)
			(xy 280.610433 -253.765385) (xy 280.55997 -253.757605) (xy 280.511297 -253.742173) (xy 280.46557 -253.719454)
			(xy 280.444448 -253.705106) (xy 280.437927 -253.700797) (xy 280.423049 -253.696025) (xy 280.415238 -253.695708)
			(xy 279.899364 -253.695708) (xy 279.894097 -253.695229) (xy 279.886657 -253.687768) (xy 279.886156 -253.6825)
			(xy 273.841947 -253.6825) (xy 273.841442 -253.687541) (xy 273.834046 -253.695114) (xy 273.828764 -253.695708)
			(xy 273.31289 -253.695708) (xy 273.305079 -253.696016) (xy 273.290208 -253.700806) (xy 273.28368 -253.705106)
			(xy 273.262558 -253.719455) (xy 273.216835 -253.742183) (xy 273.168162 -253.757613) (xy 273.117695 -253.765379)
			(xy 273.092164 -253.765812) (xy 273.066633 -253.765385) (xy 273.01617 -253.757605) (xy 272.967497 -253.742173)
			(xy 272.92177 -253.719454) (xy 272.900648 -253.705106) (xy 272.894127 -253.700797) (xy 272.879249 -253.696025)
			(xy 272.871438 -253.695708) (xy 272.355564 -253.695708) (xy 272.350297 -253.695229) (xy 272.342857 -253.687768)
			(xy 272.342356 -253.6825) (xy 266.298149 -253.6825) (xy 266.297681 -253.687613) (xy 266.290078 -253.695196)
			(xy 266.28471 -253.695708) (xy 265.768836 -253.695708) (xy 265.761027 -253.696035) (xy 265.746156 -253.700812)
			(xy 265.739626 -253.705106) (xy 265.718491 -253.719435) (xy 265.672772 -253.742167) (xy 265.624103 -253.757603)
			(xy 265.57364 -253.765376) (xy 265.54811 -253.765812) (xy 265.52258 -253.765362) (xy 265.472117 -253.757589)
			(xy 265.423445 -253.742163) (xy 265.377717 -253.719451) (xy 265.356594 -253.705106) (xy 265.350063 -253.700814)
			(xy 265.335193 -253.696031) (xy 265.327384 -253.695708) (xy 264.81151 -253.695708) (xy 264.806158 -253.695147)
			(xy 264.798575 -253.687595) (xy 264.798048 -253.682246) (xy 202.89774 -253.682246) (xy 202.89774 -253.6825)
			(xy 202.897208 -253.687755) (xy 202.889786 -253.695196) (xy 202.884532 -253.695708) (xy 202.368658 -253.695708)
			(xy 202.360783 -253.695992) (xy 202.34578 -253.700779) (xy 202.339194 -253.705106) (xy 202.318105 -253.71948)
			(xy 202.272465 -253.742314) (xy 202.223862 -253.757877) (xy 202.173448 -253.7658) (xy 202.147932 -253.76632)
			(xy 202.122412 -253.765828) (xy 202.071985 -253.757933) (xy 202.023374 -253.742374) (xy 201.977735 -253.71952)
			(xy 201.95667 -253.705106) (xy 201.950087 -253.700777) (xy 201.93508 -253.695999) (xy 201.927206 -253.695708)
			(xy 201.411332 -253.695708) (xy 201.406004 -253.695352) (xy 201.398461 -253.687827) (xy 201.398124 -253.6825)
			(xy 195.35394 -253.6825) (xy 195.353408 -253.687755) (xy 195.345986 -253.695196) (xy 195.340732 -253.695708)
			(xy 194.824858 -253.695708) (xy 194.816983 -253.695992) (xy 194.80198 -253.700779) (xy 194.795394 -253.705106)
			(xy 194.774305 -253.71948) (xy 194.728665 -253.742314) (xy 194.680062 -253.757877) (xy 194.629648 -253.7658)
			(xy 194.604132 -253.76632) (xy 194.578612 -253.765828) (xy 194.528185 -253.757933) (xy 194.479574 -253.742374)
			(xy 194.433935 -253.71952) (xy 194.41287 -253.705106) (xy 194.406287 -253.700777) (xy 194.39128 -253.695999)
			(xy 194.383406 -253.695708) (xy 193.867532 -253.695708) (xy 193.862204 -253.695352) (xy 193.854661 -253.687827)
			(xy 193.854324 -253.6825) (xy 187.81014 -253.6825) (xy 187.809608 -253.687755) (xy 187.802186 -253.695196)
			(xy 187.796932 -253.695708) (xy 187.796424 -253.695708) (xy 187.280804 -253.695708) (xy 187.272931 -253.696012)
			(xy 187.257927 -253.700785) (xy 187.25134 -253.705106) (xy 187.230266 -253.719503) (xy 187.184621 -253.742332)
			(xy 187.136013 -253.757888) (xy 187.085595 -253.765805) (xy 187.060078 -253.76632) (xy 187.034559 -253.765805)
			(xy 186.984133 -253.757917) (xy 186.935522 -253.742365) (xy 186.889882 -253.719517) (xy 186.868816 -253.705106)
			(xy 186.862222 -253.700795) (xy 186.847224 -253.696006) (xy 186.839352 -253.695708) (xy 186.323478 -253.695708)
			(xy 186.318182 -253.695197) (xy 186.310615 -253.687784) (xy 186.310016 -253.6825) (xy 180.265832 -253.6825)
			(xy 180.265308 -253.687757) (xy 180.25788 -253.695198) (xy 180.252624 -253.695708) (xy 179.73675 -253.695708)
			(xy 179.728875 -253.695989) (xy 179.713871 -253.700778) (xy 179.707286 -253.705106) (xy 179.686199 -253.719484)
			(xy 179.640558 -253.742316) (xy 179.591955 -253.757878) (xy 179.54154 -253.765801) (xy 179.516024 -253.76632)
			(xy 179.490504 -253.765832) (xy 179.440077 -253.757936) (xy 179.391465 -253.742376) (xy 179.345827 -253.719521)
			(xy 179.324762 -253.705106) (xy 179.31818 -253.700774) (xy 179.303173 -253.695998) (xy 179.295298 -253.695708)
			(xy 178.779424 -253.695708) (xy 178.774095 -253.695357) (xy 178.766553 -253.687828) (xy 178.766216 -253.6825)
			(xy 172.722032 -253.6825) (xy 172.721508 -253.687757) (xy 172.71408 -253.695198) (xy 172.708824 -253.695708)
			(xy 172.708316 -253.695708) (xy 172.192696 -253.695708) (xy 172.184823 -253.696008) (xy 172.169819 -253.700784)
			(xy 172.163232 -253.705106) (xy 172.142161 -253.719507) (xy 172.096514 -253.742334) (xy 172.047906 -253.75789)
			(xy 171.997487 -253.765805) (xy 171.97197 -253.76632) (xy 171.946451 -253.765809) (xy 171.896025 -253.75792)
			(xy 171.847413 -253.742366) (xy 171.801774 -253.719518) (xy 171.780708 -253.705106) (xy 171.774116 -253.700792)
			(xy 171.759116 -253.696004) (xy 171.751244 -253.695708) (xy 171.23537 -253.695708) (xy 171.230073 -253.695203)
			(xy 171.222507 -253.687786) (xy 171.221908 -253.6825) (xy 165.177724 -253.6825) (xy 165.177207 -253.687759)
			(xy 165.169774 -253.6952) (xy 165.164516 -253.695708) (xy 163.691316 -253.695708) (xy 163.685986 -253.695362)
			(xy 163.678444 -253.68783) (xy 163.678108 -253.6825) (xy 56.07812 -253.6825) (xy 56.077606 -253.68776)
			(xy 56.070171 -253.695202) (xy 56.064912 -253.695708) (xy 54.591458 -253.695708) (xy 54.58616 -253.695211)
			(xy 54.578594 -253.687788) (xy 54.577996 -253.6825) (xy 48.533812 -253.6825) (xy 48.533306 -253.687762)
			(xy 48.525866 -253.695204) (xy 48.520604 -253.695708) (xy 48.00473 -253.695708) (xy 47.996854 -253.69598)
			(xy 47.981851 -253.700775) (xy 47.975266 -253.705106) (xy 47.954185 -253.719492) (xy 47.908542 -253.742323)
			(xy 47.859937 -253.757883) (xy 47.80952 -253.765803) (xy 47.784004 -253.76632) (xy 47.758483 -253.765842)
			(xy 47.708056 -253.757943) (xy 47.659445 -253.74238) (xy 47.613807 -253.719522) (xy 47.592742 -253.705106)
			(xy 47.586165 -253.700766) (xy 47.571154 -253.695995) (xy 47.563278 -253.695708) (xy 47.047404 -253.695708)
			(xy 47.042072 -253.69537) (xy 47.034531 -253.687832) (xy 47.034196 -253.6825) (xy 40.990012 -253.6825)
			(xy 40.989506 -253.687762) (xy 40.982066 -253.695204) (xy 40.976804 -253.695708) (xy 40.976296 -253.695708)
			(xy 40.460676 -253.695708) (xy 40.452802 -253.696) (xy 40.437798 -253.700781) (xy 40.431212 -253.705106)
			(xy 40.410146 -253.719516) (xy 40.364498 -253.742341) (xy 40.315888 -253.757894) (xy 40.265468 -253.765807)
			(xy 40.23995 -253.76632) (xy 40.21443 -253.765819) (xy 40.164004 -253.757927) (xy 40.115392 -253.74237)
			(xy 40.069754 -253.719519) (xy 40.048688 -253.705106) (xy 40.042101 -253.700784) (xy 40.027097 -253.696001)
			(xy 40.019224 -253.695708) (xy 39.50335 -253.695708) (xy 39.498063 -253.695149) (xy 39.490492 -253.687773)
			(xy 39.489888 -253.6825) (xy 33.445704 -253.6825) (xy 33.445373 -253.687833) (xy 33.437829 -253.695375)
			(xy 33.432496 -253.695708) (xy 32.916622 -253.695708) (xy 32.90875 -253.69602) (xy 32.893746 -253.700788)
			(xy 32.887158 -253.705106) (xy 32.866079 -253.719496) (xy 32.820435 -253.742326) (xy 32.77183 -253.757884)
			(xy 32.721413 -253.765803) (xy 32.695896 -253.76632) (xy 32.670375 -253.765846) (xy 32.619948 -253.757946)
			(xy 32.571336 -253.742381) (xy 32.525699 -253.719523) (xy 32.504634 -253.705106) (xy 32.498036 -253.700802)
			(xy 32.483041 -253.696008) (xy 32.47517 -253.695708) (xy 31.959296 -253.695708) (xy 31.954033 -253.695208)
			(xy 31.94659 -253.687763) (xy 31.946088 -253.6825) (xy 25.901904 -253.6825) (xy 25.901573 -253.687833)
			(xy 25.894029 -253.695375) (xy 25.888696 -253.695708) (xy 25.372822 -253.695708) (xy 25.36495 -253.69602)
			(xy 25.349946 -253.700788) (xy 25.343358 -253.705106) (xy 25.322279 -253.719496) (xy 25.276635 -253.742326)
			(xy 25.22803 -253.757884) (xy 25.177613 -253.765803) (xy 25.152096 -253.76632) (xy 25.126575 -253.765846)
			(xy 25.076148 -253.757946) (xy 25.027536 -253.742381) (xy 24.981899 -253.719523) (xy 24.960834 -253.705106)
			(xy 24.954236 -253.700802) (xy 24.939241 -253.696008) (xy 24.93137 -253.695708) (xy 24.415496 -253.695708)
			(xy 24.410233 -253.695208) (xy 24.40279 -253.687763) (xy 24.402288 -253.6825) (xy 18.358104 -253.6825)
			(xy 18.357773 -253.687833) (xy 18.350229 -253.695375) (xy 18.344896 -253.695708) (xy 18.344388 -253.695708)
			(xy 17.828768 -253.695708) (xy 17.820894 -253.695996) (xy 17.80589 -253.70078) (xy 17.799304 -253.705106)
			(xy 17.778212 -253.719476) (xy 17.732573 -253.74231) (xy 17.683971 -253.757874) (xy 17.633558 -253.7658)
			(xy 17.608042 -253.76632) (xy 17.582522 -253.765823) (xy 17.532096 -253.75793) (xy 17.483484 -253.742372)
			(xy 17.437845 -253.71952) (xy 17.41678 -253.705106) (xy 17.410194 -253.700781) (xy 17.39519 -253.696)
			(xy 17.387316 -253.695708) (xy 16.871442 -253.695708) (xy 16.866154 -253.695154) (xy 16.858583 -253.687774)
			(xy 16.85798 -253.6825) (xy 2.509012 -253.6825) (xy 2.509012 -254.532384) (xy 16.85798 -254.532384)
			(xy 16.85798 -254.037846) (xy 16.858314 -254.032407) (xy 16.866003 -254.024716) (xy 16.871442 -254.024384)
			(xy 17.38757 -254.024384) (xy 17.395379 -254.02406) (xy 17.410251 -254.019282) (xy 17.41678 -254.014986)
			(xy 17.437869 -254.000637) (xy 17.48353 -253.977906) (xy 17.532136 -253.962447) (xy 17.582539 -253.954624)
			(xy 17.633545 -253.954624) (xy 17.683948 -253.962447) (xy 17.732554 -253.977906) (xy 17.778215 -254.000637)
			(xy 17.799304 -254.014986) (xy 17.805836 -254.019276) (xy 17.820706 -254.02406) (xy 17.828514 -254.024384)
			(xy 18.344642 -254.024384) (xy 18.350094 -254.024656) (xy 18.35778 -254.032392) (xy 18.358104 -254.037846)
			(xy 18.358104 -254.532384) (xy 20.958048 -254.532384) (xy 20.958048 -254.037846) (xy 20.958411 -254.032415)
			(xy 20.96608 -254.024725) (xy 20.97151 -254.024384) (xy 21.487638 -254.024384) (xy 21.495446 -254.024046)
			(xy 21.510318 -254.019277) (xy 21.516848 -254.014986) (xy 21.537937 -254.000637) (xy 21.583598 -253.977906)
			(xy 21.632204 -253.962447) (xy 21.682607 -253.954624) (xy 21.733613 -253.954624) (xy 21.784016 -253.962447)
			(xy 21.832622 -253.977906) (xy 21.878283 -254.000637) (xy 21.899372 -254.014986) (xy 21.905911 -254.019264)
			(xy 21.920775 -254.024056) (xy 21.928582 -254.024384) (xy 22.44471 -254.024384) (xy 22.450157 -254.024677)
			(xy 22.457846 -254.032397) (xy 22.458172 -254.037846) (xy 22.458172 -254.532384) (xy 24.402288 -254.532384)
			(xy 24.402288 -254.037846) (xy 24.40276 -254.032536) (xy 24.410196 -254.02496) (xy 24.415496 -254.024384)
			(xy 24.931624 -254.024384) (xy 24.939435 -254.024083) (xy 24.954307 -254.019289) (xy 24.960834 -254.014986)
			(xy 24.981923 -254.000637) (xy 25.027584 -253.977906) (xy 25.07619 -253.962447) (xy 25.126593 -253.954624)
			(xy 25.177599 -253.954624) (xy 25.228002 -253.962447) (xy 25.276608 -253.977906) (xy 25.322269 -254.000637)
			(xy 25.343358 -254.014986) (xy 25.349878 -254.019297) (xy 25.364757 -254.024068) (xy 25.372568 -254.024384)
			(xy 25.888696 -254.024384) (xy 25.893956 -254.024897) (xy 25.901399 -254.032332) (xy 25.901904 -254.037592)
			(xy 25.901904 -254.0381) (xy 25.901904 -254.532384) (xy 28.502356 -254.532384) (xy 28.502356 -254.037846)
			(xy 28.502855 -254.032544) (xy 28.510273 -254.024969) (xy 28.515564 -254.024384) (xy 29.031692 -254.024384)
			(xy 29.039502 -254.02407) (xy 29.054374 -254.019284) (xy 29.060902 -254.014986) (xy 29.081991 -254.000637)
			(xy 29.127652 -253.977906) (xy 29.176258 -253.962447) (xy 29.226661 -253.954624) (xy 29.277667 -253.954624)
			(xy 29.32807 -253.962447) (xy 29.376676 -253.977906) (xy 29.422337 -254.000637) (xy 29.443426 -254.014986)
			(xy 29.449953 -254.019285) (xy 29.464827 -254.024063) (xy 29.472636 -254.024384) (xy 29.988764 -254.024384)
			(xy 29.99409 -254.02475) (xy 30.001632 -254.032268) (xy 30.001972 -254.037592) (xy 30.001972 -254.0381)
			(xy 30.001972 -254.532384) (xy 31.946088 -254.532384) (xy 31.946088 -254.037846) (xy 31.94656 -254.032536)
			(xy 31.953996 -254.02496) (xy 31.959296 -254.024384) (xy 32.475424 -254.024384) (xy 32.483235 -254.024083)
			(xy 32.498107 -254.019289) (xy 32.504634 -254.014986) (xy 32.525723 -254.000637) (xy 32.571384 -253.977906)
			(xy 32.61999 -253.962447) (xy 32.670393 -253.954624) (xy 32.721399 -253.954624) (xy 32.771802 -253.962447)
			(xy 32.820408 -253.977906) (xy 32.866069 -254.000637) (xy 32.887158 -254.014986) (xy 32.893678 -254.019297)
			(xy 32.908557 -254.024068) (xy 32.916368 -254.024384) (xy 33.432496 -254.024384) (xy 33.437756 -254.024897)
			(xy 33.445199 -254.032332) (xy 33.445704 -254.037592) (xy 33.445704 -254.0381) (xy 33.445704 -254.532384)
			(xy 36.046156 -254.532384) (xy 36.046156 -254.037846) (xy 36.046655 -254.032544) (xy 36.054073 -254.024969)
			(xy 36.059364 -254.024384) (xy 36.575492 -254.024384) (xy 36.583302 -254.02407) (xy 36.598174 -254.019284)
			(xy 36.604702 -254.014986) (xy 36.625791 -254.000637) (xy 36.671452 -253.977906) (xy 36.720058 -253.962447)
			(xy 36.770461 -253.954624) (xy 36.821467 -253.954624) (xy 36.87187 -253.962447) (xy 36.920476 -253.977906)
			(xy 36.966137 -254.000637) (xy 36.987226 -254.014986) (xy 36.993753 -254.019285) (xy 37.008627 -254.024063)
			(xy 37.016436 -254.024384) (xy 37.532564 -254.024384) (xy 37.53789 -254.02475) (xy 37.545432 -254.032268)
			(xy 37.545772 -254.037592) (xy 37.545772 -254.0381) (xy 37.545772 -254.532384) (xy 39.489888 -254.532384)
			(xy 39.489888 -254.037846) (xy 39.490476 -254.032499) (xy 39.498007 -254.024914) (xy 39.50335 -254.024384)
			(xy 40.019478 -254.024384) (xy 40.027288 -254.024064) (xy 40.042159 -254.019283) (xy 40.048688 -254.014986)
			(xy 40.069777 -254.000637) (xy 40.115438 -253.977906) (xy 40.164044 -253.962447) (xy 40.214447 -253.954624)
			(xy 40.265453 -253.954624) (xy 40.315856 -253.962447) (xy 40.364462 -253.977906) (xy 40.410123 -254.000637)
			(xy 40.431212 -254.014986) (xy 40.437742 -254.019279) (xy 40.452613 -254.024061) (xy 40.460422 -254.024384)
			(xy 40.97655 -254.024384) (xy 40.981931 -254.024822) (xy 40.989516 -254.032462) (xy 40.990012 -254.037846)
			(xy 40.990012 -254.532384) (xy 43.589956 -254.532384) (xy 43.589956 -254.037846) (xy 43.590312 -254.032413)
			(xy 43.597986 -254.024723) (xy 43.603418 -254.024384) (xy 44.119546 -254.024384) (xy 44.127354 -254.02405)
			(xy 44.142226 -254.019278) (xy 44.148756 -254.014986) (xy 44.169845 -254.000637) (xy 44.215506 -253.977906)
			(xy 44.264112 -253.962447) (xy 44.314515 -253.954624) (xy 44.365521 -253.954624) (xy 44.415924 -253.962447)
			(xy 44.46453 -253.977906) (xy 44.510191 -254.000637) (xy 44.53128 -254.014986) (xy 44.537817 -254.019267)
			(xy 44.552683 -254.024057) (xy 44.56049 -254.024384) (xy 45.076618 -254.024384) (xy 45.082067 -254.024672)
			(xy 45.089754 -254.032396) (xy 45.09008 -254.037846) (xy 45.09008 -254.532384) (xy 47.034196 -254.532384)
			(xy 47.034196 -254.037846) (xy 47.034749 -254.032557) (xy 47.042129 -254.024986) (xy 47.047404 -254.024384)
			(xy 47.563532 -254.024384) (xy 47.57134 -254.024044) (xy 47.586211 -254.019276) (xy 47.592742 -254.014986)
			(xy 47.613831 -254.000637) (xy 47.659492 -253.977906) (xy 47.708098 -253.962447) (xy 47.758501 -253.954624)
			(xy 47.809507 -253.954624) (xy 47.85991 -253.962447) (xy 47.908516 -253.977906) (xy 47.954177 -254.000637)
			(xy 47.975266 -254.014986) (xy 47.981807 -254.019262) (xy 47.99667 -254.024055) (xy 48.004476 -254.024384)
			(xy 48.520604 -254.024384) (xy 48.525865 -254.024891) (xy 48.533307 -254.032331) (xy 48.533812 -254.037592)
			(xy 48.533812 -254.0381) (xy 48.533812 -254.532384) (xy 51.134264 -254.532384) (xy 51.134264 -254.037846)
			(xy 51.134757 -254.032542) (xy 51.142179 -254.024967) (xy 51.147472 -254.024384) (xy 51.6636 -254.024384)
			(xy 51.67141 -254.024073) (xy 51.686282 -254.019285) (xy 51.69281 -254.014986) (xy 51.713899 -254.000637)
			(xy 51.75956 -253.977906) (xy 51.808166 -253.962447) (xy 51.858569 -253.954624) (xy 51.909575 -253.954624)
			(xy 51.959978 -253.962447) (xy 52.008584 -253.977906) (xy 52.054245 -254.000637) (xy 52.075334 -254.014986)
			(xy 52.081859 -254.019288) (xy 52.096734 -254.024065) (xy 52.104544 -254.024384) (xy 52.620672 -254.024384)
			(xy 52.625999 -254.024745) (xy 52.633541 -254.032266) (xy 52.63388 -254.037592) (xy 52.63388 -254.0381)
			(xy 52.63388 -254.532384) (xy 54.577996 -254.532384) (xy 54.577996 -254.037846) (xy 54.578406 -254.032427)
			(xy 54.586042 -254.024741) (xy 54.591458 -254.024384) (xy 56.064658 -254.024384) (xy 56.070098 -254.024712)
			(xy 56.07779 -254.032406) (xy 56.07812 -254.037846) (xy 56.07812 -254.532384) (xy 58.678064 -254.532384)
			(xy 58.678064 -254.037846) (xy 58.678413 -254.032411) (xy 58.686091 -254.024721) (xy 58.691526 -254.024384)
			(xy 60.164726 -254.024384) (xy 60.170176 -254.024666) (xy 60.177863 -254.032395) (xy 60.178188 -254.037846)
			(xy 60.178188 -254.532384) (xy 163.678108 -254.532384) (xy 163.678108 -254.037846) (xy 163.67865 -254.032555)
			(xy 163.686038 -254.024983) (xy 163.691316 -254.024384) (xy 165.164516 -254.024384) (xy 165.169779 -254.024883)
			(xy 165.17722 -254.032329) (xy 165.177724 -254.037592) (xy 165.177724 -254.0381) (xy 165.177724 -254.532384)
			(xy 167.778176 -254.532384) (xy 167.778176 -254.037846) (xy 167.778658 -254.032539) (xy 167.786087 -254.024963)
			(xy 167.791384 -254.024384) (xy 169.264584 -254.024384) (xy 169.269912 -254.024737) (xy 169.277454 -254.032264)
			(xy 169.277792 -254.037592) (xy 169.277792 -254.532384) (xy 171.221908 -254.532384) (xy 171.221908 -254.037846)
			(xy 171.222307 -254.032424) (xy 171.229951 -254.024738) (xy 171.23537 -254.024384) (xy 171.751498 -254.024384)
			(xy 171.759308 -254.024072) (xy 171.77418 -254.019285) (xy 171.780708 -254.014986) (xy 171.801797 -254.000637)
			(xy 171.847458 -253.977906) (xy 171.896064 -253.962447) (xy 171.946467 -253.954624) (xy 171.997473 -253.954624)
			(xy 172.047876 -253.962447) (xy 172.096482 -253.977906) (xy 172.142143 -254.000637) (xy 172.163232 -254.014986)
			(xy 172.169758 -254.019287) (xy 172.184632 -254.024064) (xy 172.192442 -254.024384) (xy 172.70857 -254.024384)
			(xy 172.714012 -254.024704) (xy 172.721702 -254.032404) (xy 172.722032 -254.037846) (xy 172.722032 -254.532384)
			(xy 175.321976 -254.532384) (xy 175.321976 -254.037846) (xy 175.322314 -254.032408) (xy 175.33 -254.024717)
			(xy 175.335438 -254.024384) (xy 175.851566 -254.024384) (xy 175.859375 -254.024059) (xy 175.874247 -254.019281)
			(xy 175.880776 -254.014986) (xy 175.901865 -254.000637) (xy 175.947526 -253.977906) (xy 175.996132 -253.962447)
			(xy 176.046535 -253.954624) (xy 176.097541 -253.954624) (xy 176.147944 -253.962447) (xy 176.19655 -253.977906)
			(xy 176.242211 -254.000637) (xy 176.2633 -254.014986) (xy 176.269833 -254.019275) (xy 176.284702 -254.02406)
			(xy 176.29251 -254.024384) (xy 176.808638 -254.024384) (xy 176.814089 -254.024658) (xy 176.821776 -254.032393)
			(xy 176.8221 -254.037846) (xy 176.8221 -254.532384) (xy 178.766216 -254.532384) (xy 178.766216 -254.037846)
			(xy 178.766751 -254.032553) (xy 178.774144 -254.02498) (xy 178.779424 -254.024384) (xy 179.295552 -254.024384)
			(xy 179.303361 -254.024053) (xy 179.318232 -254.019279) (xy 179.324762 -254.014986) (xy 179.345851 -254.000637)
			(xy 179.391512 -253.977906) (xy 179.440118 -253.962447) (xy 179.490521 -253.954624) (xy 179.541527 -253.954624)
			(xy 179.59193 -253.962447) (xy 179.640536 -253.977906) (xy 179.686197 -254.000637) (xy 179.707286 -254.014986)
			(xy 179.713822 -254.019269) (xy 179.728689 -254.024058) (xy 179.736496 -254.024384) (xy 180.252624 -254.024384)
			(xy 180.257888 -254.024878) (xy 180.265328 -254.032328) (xy 180.265832 -254.037592) (xy 180.265832 -254.0381)
			(xy 180.265832 -254.532384) (xy 182.866284 -254.532384) (xy 182.866284 -254.037846) (xy 182.866759 -254.032537)
			(xy 182.874193 -254.024961) (xy 182.879492 -254.024384) (xy 183.39562 -254.024384) (xy 183.403431 -254.024082)
			(xy 183.418303 -254.019288) (xy 183.42483 -254.014986) (xy 183.445919 -254.000637) (xy 183.49158 -253.977906)
			(xy 183.540186 -253.962447) (xy 183.590589 -253.954624) (xy 183.641595 -253.954624) (xy 183.691998 -253.962447)
			(xy 183.740604 -253.977906) (xy 183.786265 -254.000637) (xy 183.807354 -254.014986) (xy 183.813875 -254.019295)
			(xy 183.828753 -254.024068) (xy 183.836564 -254.024384) (xy 184.352692 -254.024384) (xy 184.357952 -254.024899)
			(xy 184.365395 -254.032333) (xy 184.3659 -254.037592) (xy 184.3659 -254.0381) (xy 184.3659 -254.532384)
			(xy 186.310016 -254.532384) (xy 186.310016 -254.037846) (xy 186.310408 -254.032423) (xy 186.318056 -254.024735)
			(xy 186.323478 -254.024384) (xy 186.839606 -254.024384) (xy 186.847417 -254.024076) (xy 186.862288 -254.019286)
			(xy 186.868816 -254.014986) (xy 186.889905 -254.000637) (xy 186.935566 -253.977906) (xy 186.984172 -253.962447)
			(xy 187.034575 -253.954624) (xy 187.085581 -253.954624) (xy 187.135984 -253.962447) (xy 187.18459 -253.977906)
			(xy 187.230251 -254.000637) (xy 187.25134 -254.014986) (xy 187.257864 -254.01929) (xy 187.27274 -254.024065)
			(xy 187.28055 -254.024384) (xy 187.796678 -254.024384) (xy 187.802121 -254.024699) (xy 187.809811 -254.032402)
			(xy 187.81014 -254.037846) (xy 187.81014 -254.532384) (xy 190.410084 -254.532384) (xy 190.410084 -254.037846)
			(xy 190.410415 -254.032406) (xy 190.418106 -254.024715) (xy 190.423546 -254.024384) (xy 190.939674 -254.024384)
			(xy 190.947483 -254.024062) (xy 190.962355 -254.019282) (xy 190.968884 -254.014986) (xy 190.989973 -254.000637)
			(xy 191.035634 -253.977906) (xy 191.08424 -253.962447) (xy 191.134643 -253.954624) (xy 191.185649 -253.954624)
			(xy 191.236052 -253.962447) (xy 191.284658 -253.977906) (xy 191.330319 -254.000637) (xy 191.351408 -254.014986)
			(xy 191.357939 -254.019278) (xy 191.372809 -254.024061) (xy 191.380618 -254.024384) (xy 191.896746 -254.024384)
			(xy 191.902127 -254.024825) (xy 191.909712 -254.032462) (xy 191.910208 -254.037846) (xy 191.910208 -254.532384)
			(xy 193.854324 -254.532384) (xy 193.854324 -254.037846) (xy 193.854852 -254.032551) (xy 193.86225 -254.024978)
			(xy 193.867532 -254.024384) (xy 194.38366 -254.024384) (xy 194.391469 -254.024056) (xy 194.40634 -254.01928)
			(xy 194.41287 -254.014986) (xy 194.433959 -254.000637) (xy 194.47962 -253.977906) (xy 194.528226 -253.962447)
			(xy 194.578629 -253.954624) (xy 194.629635 -253.954624) (xy 194.680038 -253.962447) (xy 194.728644 -253.977906)
			(xy 194.774305 -254.000637) (xy 194.795394 -254.014986) (xy 194.801928 -254.019272) (xy 194.816796 -254.024059)
			(xy 194.824604 -254.024384) (xy 195.340732 -254.024384) (xy 195.345997 -254.024873) (xy 195.353437 -254.032326)
			(xy 195.35394 -254.037592) (xy 195.35394 -254.0381) (xy 195.35394 -254.532384) (xy 197.954392 -254.532384)
			(xy 197.954392 -254.037846) (xy 197.954948 -254.032558) (xy 197.962326 -254.024987) (xy 197.9676 -254.024384)
			(xy 198.483728 -254.024384) (xy 198.491539 -254.024085) (xy 198.506411 -254.019289) (xy 198.512938 -254.014986)
			(xy 198.534027 -254.000637) (xy 198.579688 -253.977906) (xy 198.628294 -253.962447) (xy 198.678697 -253.954624)
			(xy 198.729703 -253.954624) (xy 198.780106 -253.962447) (xy 198.828712 -253.977906) (xy 198.874373 -254.000637)
			(xy 198.895462 -254.014986) (xy 198.902003 -254.01926) (xy 198.916866 -254.024054) (xy 198.924672 -254.024384)
			(xy 199.4408 -254.024384) (xy 199.446061 -254.024894) (xy 199.453503 -254.032332) (xy 199.454008 -254.037592)
			(xy 199.454008 -254.0381) (xy 199.454008 -254.532384) (xy 201.398124 -254.532384) (xy 201.398124 -254.037846)
			(xy 201.398652 -254.032551) (xy 201.40605 -254.024978) (xy 201.411332 -254.024384) (xy 201.92746 -254.024384)
			(xy 201.935269 -254.024056) (xy 201.95014 -254.01928) (xy 201.95667 -254.014986) (xy 201.977759 -254.000637)
			(xy 202.02342 -253.977906) (xy 202.072026 -253.962447) (xy 202.122429 -253.954624) (xy 202.173435 -253.954624)
			(xy 202.223838 -253.962447) (xy 202.272444 -253.977906) (xy 202.318105 -254.000637) (xy 202.339194 -254.014986)
			(xy 202.345728 -254.019272) (xy 202.360596 -254.024059) (xy 202.368404 -254.024384) (xy 202.884532 -254.024384)
			(xy 202.889797 -254.024873) (xy 202.897237 -254.032326) (xy 202.89774 -254.037592) (xy 202.89774 -254.0381)
			(xy 202.89774 -254.532384) (xy 205.498192 -254.532384) (xy 205.498192 -254.037846) (xy 205.498748 -254.032558)
			(xy 205.506126 -254.024987) (xy 205.5114 -254.024384) (xy 206.027528 -254.024384) (xy 206.035339 -254.024085)
			(xy 206.050211 -254.019289) (xy 206.056738 -254.014986) (xy 206.077827 -254.000637) (xy 206.123488 -253.977906)
			(xy 206.172094 -253.962447) (xy 206.222497 -253.954624) (xy 206.273503 -253.954624) (xy 206.323906 -253.962447)
			(xy 206.372512 -253.977906) (xy 206.418173 -254.000637) (xy 206.439262 -254.014986) (xy 206.445803 -254.01926)
			(xy 206.460666 -254.024054) (xy 206.468472 -254.024384) (xy 206.9846 -254.024384) (xy 206.989861 -254.024894)
			(xy 206.997303 -254.032332) (xy 206.997808 -254.037592) (xy 206.997808 -254.0381) (xy 206.997808 -254.53213)
			(xy 264.798048 -254.53213) (xy 264.798048 -254.037592) (xy 264.798585 -254.032339) (xy 264.806004 -254.024899)
			(xy 264.811256 -254.024384) (xy 264.811764 -254.024384) (xy 265.327638 -254.024384) (xy 265.335446 -254.024046)
			(xy 265.350318 -254.019277) (xy 265.356848 -254.014986) (xy 265.377937 -254.000637) (xy 265.423598 -253.977906)
			(xy 265.472204 -253.962447) (xy 265.522607 -253.954624) (xy 265.573613 -253.954624) (xy 265.624016 -253.962447)
			(xy 265.672622 -253.977906) (xy 265.718283 -254.000637) (xy 265.739372 -254.014986) (xy 265.745911 -254.019264)
			(xy 265.760775 -254.024056) (xy 265.768582 -254.024384) (xy 266.28471 -254.024384) (xy 266.290026 -254.024822)
			(xy 266.297599 -254.032284) (xy 266.298172 -254.037592) (xy 266.298172 -254.53213) (xy 268.898116 -254.53213)
			(xy 268.898116 -254.037592) (xy 268.898424 -254.032253) (xy 268.905984 -254.024711) (xy 268.911324 -254.024384)
			(xy 268.911832 -254.024384) (xy 269.427706 -254.024384) (xy 269.435517 -254.024076) (xy 269.450388 -254.019286)
			(xy 269.456916 -254.014986) (xy 269.478005 -254.000637) (xy 269.523666 -253.977906) (xy 269.572272 -253.962447)
			(xy 269.622675 -253.954624) (xy 269.673681 -253.954624) (xy 269.724084 -253.962447) (xy 269.77269 -253.977906)
			(xy 269.818351 -254.000637) (xy 269.83944 -254.014986) (xy 269.845964 -254.01929) (xy 269.86084 -254.024065)
			(xy 269.86865 -254.024384) (xy 270.384778 -254.024384) (xy 270.39009 -254.024843) (xy 270.397665 -254.032289)
			(xy 270.39824 -254.037592) (xy 270.39824 -254.53213) (xy 270.398218 -254.532384) (xy 272.342356 -254.532384)
			(xy 272.342356 -254.531876) (xy 272.342356 -254.037592) (xy 272.342886 -254.032337) (xy 272.35031 -254.024897)
			(xy 272.355564 -254.024384) (xy 272.871692 -254.024384) (xy 272.879502 -254.02407) (xy 272.894374 -254.019284)
			(xy 272.900902 -254.014986) (xy 272.921991 -254.000637) (xy 272.967652 -253.977906) (xy 273.016258 -253.962447)
			(xy 273.066661 -253.954624) (xy 273.117667 -253.954624) (xy 273.16807 -253.962447) (xy 273.216676 -253.977906)
			(xy 273.262337 -254.000637) (xy 273.283426 -254.014986) (xy 273.289953 -254.019285) (xy 273.304827 -254.024063)
			(xy 273.312636 -254.024384) (xy 273.828764 -254.024384) (xy 273.83409 -254.02475) (xy 273.841632 -254.032268)
			(xy 273.841972 -254.037592) (xy 273.841972 -254.53213) (xy 273.841949 -254.532384) (xy 276.442424 -254.532384)
			(xy 276.442424 -254.531876) (xy 276.442424 -254.037592) (xy 276.442724 -254.032251) (xy 276.45029 -254.024708)
			(xy 276.455632 -254.024384) (xy 276.97176 -254.024384) (xy 276.979569 -254.024056) (xy 276.99444 -254.01928)
			(xy 277.00097 -254.014986) (xy 277.022059 -254.000637) (xy 277.06772 -253.977906) (xy 277.116326 -253.962447)
			(xy 277.166729 -253.954624) (xy 277.217735 -253.954624) (xy 277.268138 -253.962447) (xy 277.316744 -253.977906)
			(xy 277.362405 -254.000637) (xy 277.383494 -254.014986) (xy 277.390028 -254.019272) (xy 277.404896 -254.024059)
			(xy 277.412704 -254.024384) (xy 277.928832 -254.024384) (xy 277.934097 -254.024873) (xy 277.941537 -254.032326)
			(xy 277.94204 -254.037592) (xy 277.94204 -254.53213) (xy 277.942019 -254.532384) (xy 279.886156 -254.532384)
			(xy 279.886156 -254.531876) (xy 279.886156 -254.037592) (xy 279.886686 -254.032337) (xy 279.89411 -254.024897)
			(xy 279.899364 -254.024384) (xy 280.415492 -254.024384) (xy 280.423302 -254.02407) (xy 280.438174 -254.019284)
			(xy 280.444702 -254.014986) (xy 280.465791 -254.000637) (xy 280.511452 -253.977906) (xy 280.560058 -253.962447)
			(xy 280.610461 -253.954624) (xy 280.661467 -253.954624) (xy 280.71187 -253.962447) (xy 280.760476 -253.977906)
			(xy 280.806137 -254.000637) (xy 280.827226 -254.014986) (xy 280.833753 -254.019285) (xy 280.848627 -254.024063)
			(xy 280.856436 -254.024384) (xy 281.372564 -254.024384) (xy 281.37789 -254.02475) (xy 281.385432 -254.032268)
			(xy 281.385772 -254.037592) (xy 281.385772 -254.53213) (xy 281.385749 -254.532384) (xy 283.986224 -254.532384)
			(xy 283.986224 -254.531876) (xy 283.986224 -254.037592) (xy 283.986524 -254.032251) (xy 283.99409 -254.024708)
			(xy 283.999432 -254.024384) (xy 284.51556 -254.024384) (xy 284.523369 -254.024056) (xy 284.53824 -254.01928)
			(xy 284.54477 -254.014986) (xy 284.565859 -254.000637) (xy 284.61152 -253.977906) (xy 284.660126 -253.962447)
			(xy 284.710529 -253.954624) (xy 284.761535 -253.954624) (xy 284.811938 -253.962447) (xy 284.860544 -253.977906)
			(xy 284.906205 -254.000637) (xy 284.927294 -254.014986) (xy 284.933828 -254.019272) (xy 284.948696 -254.024059)
			(xy 284.956504 -254.024384) (xy 285.472632 -254.024384) (xy 285.477897 -254.024873) (xy 285.485337 -254.032326)
			(xy 285.48584 -254.037592) (xy 285.48584 -254.53213) (xy 287.429956 -254.53213) (xy 287.429956 -254.037592)
			(xy 287.430486 -254.032337) (xy 287.43791 -254.024897) (xy 287.443164 -254.024384) (xy 287.443672 -254.024384)
			(xy 287.959546 -254.024384) (xy 287.967354 -254.02405) (xy 287.982226 -254.019278) (xy 287.988756 -254.014986)
			(xy 288.009845 -254.000637) (xy 288.055506 -253.977906) (xy 288.104112 -253.962447) (xy 288.154515 -253.954624)
			(xy 288.205521 -253.954624) (xy 288.255924 -253.962447) (xy 288.30453 -253.977906) (xy 288.350191 -254.000637)
			(xy 288.37128 -254.014986) (xy 288.377817 -254.019267) (xy 288.392683 -254.024057) (xy 288.40049 -254.024384)
			(xy 288.916618 -254.024384) (xy 288.921935 -254.024816) (xy 288.929507 -254.032283) (xy 288.93008 -254.037592)
			(xy 288.93008 -254.53213) (xy 291.530024 -254.53213) (xy 291.530024 -254.037592) (xy 291.530324 -254.032251)
			(xy 291.53789 -254.024708) (xy 291.543232 -254.024384) (xy 291.54374 -254.024384) (xy 292.059614 -254.024384)
			(xy 292.067425 -254.024079) (xy 292.082296 -254.019287) (xy 292.088824 -254.014986) (xy 292.109913 -254.000637)
			(xy 292.155574 -253.977906) (xy 292.20418 -253.962447) (xy 292.254583 -253.954624) (xy 292.305589 -253.954624)
			(xy 292.355992 -253.962447) (xy 292.404598 -253.977906) (xy 292.450259 -254.000637) (xy 292.471348 -254.014986)
			(xy 292.47787 -254.019293) (xy 292.492747 -254.024067) (xy 292.500558 -254.024384) (xy 293.016686 -254.024384)
			(xy 293.021999 -254.024838) (xy 293.029573 -254.032288) (xy 293.030148 -254.037592) (xy 293.030148 -254.53213)
			(xy 293.030125 -254.532384) (xy 294.974264 -254.532384) (xy 294.974264 -254.531876) (xy 294.974264 -254.037592)
			(xy 294.974787 -254.032335) (xy 294.982216 -254.024895) (xy 294.987472 -254.024384) (xy 295.5036 -254.024384)
			(xy 295.51141 -254.024073) (xy 295.526282 -254.019285) (xy 295.53281 -254.014986) (xy 295.553899 -254.000637)
			(xy 295.59956 -253.977906) (xy 295.648166 -253.962447) (xy 295.698569 -253.954624) (xy 295.749575 -253.954624)
			(xy 295.799978 -253.962447) (xy 295.848584 -253.977906) (xy 295.894245 -254.000637) (xy 295.915334 -254.014986)
			(xy 295.921859 -254.019288) (xy 295.936734 -254.024065) (xy 295.944544 -254.024384) (xy 296.460672 -254.024384)
			(xy 296.465999 -254.024745) (xy 296.473541 -254.032266) (xy 296.47388 -254.037592) (xy 296.47388 -254.53213)
			(xy 296.473857 -254.532384) (xy 299.074332 -254.532384) (xy 299.074332 -254.531876) (xy 299.074332 -254.037592)
			(xy 299.074625 -254.032249) (xy 299.082196 -254.024706) (xy 299.08754 -254.024384) (xy 299.603668 -254.024384)
			(xy 299.611477 -254.02406) (xy 299.626349 -254.019281) (xy 299.632878 -254.014986) (xy 299.653967 -254.000637)
			(xy 299.699628 -253.977906) (xy 299.748234 -253.962447) (xy 299.798637 -253.954624) (xy 299.849643 -253.954624)
			(xy 299.900046 -253.962447) (xy 299.948652 -253.977906) (xy 299.994313 -254.000637) (xy 300.015402 -254.014986)
			(xy 300.021935 -254.019276) (xy 300.036804 -254.02406) (xy 300.044612 -254.024384) (xy 300.56074 -254.024384)
			(xy 300.566006 -254.024867) (xy 300.573446 -254.032325) (xy 300.573948 -254.037592) (xy 300.573948 -254.53213)
			(xy 302.518064 -254.53213) (xy 302.518064 -254.037592) (xy 302.518587 -254.032335) (xy 302.526016 -254.024895)
			(xy 302.531272 -254.024384) (xy 304.004726 -254.024384) (xy 304.010044 -254.024811) (xy 304.017616 -254.032282)
			(xy 304.018188 -254.037592) (xy 304.018188 -254.53213) (xy 306.618132 -254.53213) (xy 306.618132 -254.037592)
			(xy 306.618425 -254.032249) (xy 306.625996 -254.024706) (xy 306.63134 -254.024384) (xy 306.631848 -254.024384)
			(xy 308.104794 -254.024384) (xy 308.110108 -254.024832) (xy 308.117682 -254.032287) (xy 308.118256 -254.037592)
			(xy 308.118256 -254.53213) (xy 308.118233 -254.532384) (xy 411.618176 -254.532384) (xy 411.618176 -254.531876)
			(xy 411.618176 -254.037592) (xy 411.618688 -254.032332) (xy 411.626124 -254.024891) (xy 411.631384 -254.024384)
			(xy 413.104584 -254.024384) (xy 413.109912 -254.024737) (xy 413.117454 -254.032264) (xy 413.117792 -254.037592)
			(xy 413.117792 -254.53213) (xy 413.117768 -254.532384) (xy 415.718244 -254.532384) (xy 415.718244 -254.037592)
			(xy 415.718784 -254.03234) (xy 415.726201 -254.0249) (xy 415.731452 -254.024384) (xy 417.204652 -254.024384)
			(xy 417.209976 -254.024759) (xy 417.217519 -254.03227) (xy 417.21786 -254.037592) (xy 417.21786 -254.53213)
			(xy 419.161976 -254.53213) (xy 419.161976 -254.037592) (xy 419.162488 -254.032332) (xy 419.169924 -254.024891)
			(xy 419.175184 -254.024384) (xy 419.175692 -254.024384) (xy 419.691566 -254.024384) (xy 419.699375 -254.024059)
			(xy 419.714247 -254.019281) (xy 419.720776 -254.014986) (xy 419.741865 -254.000637) (xy 419.787526 -253.977906)
			(xy 419.836132 -253.962447) (xy 419.886535 -253.954624) (xy 419.937541 -253.954624) (xy 419.987944 -253.962447)
			(xy 420.03655 -253.977906) (xy 420.082211 -254.000637) (xy 420.1033 -254.014986) (xy 420.109833 -254.019275)
			(xy 420.124702 -254.02406) (xy 420.13251 -254.024384) (xy 420.648638 -254.024384) (xy 420.653957 -254.024803)
			(xy 420.661528 -254.03228) (xy 420.6621 -254.037592) (xy 420.6621 -254.53213) (xy 423.262044 -254.53213)
			(xy 423.262044 -254.037592) (xy 423.262584 -254.03234) (xy 423.270001 -254.0249) (xy 423.275252 -254.024384)
			(xy 423.27576 -254.024384) (xy 423.791634 -254.024384) (xy 423.799442 -254.024045) (xy 423.814313 -254.019276)
			(xy 423.820844 -254.014986) (xy 423.841933 -254.000637) (xy 423.887594 -253.977906) (xy 423.9362 -253.962447)
			(xy 423.986603 -253.954624) (xy 424.037609 -253.954624) (xy 424.088012 -253.962447) (xy 424.136618 -253.977906)
			(xy 424.182279 -254.000637) (xy 424.203368 -254.014986) (xy 424.209908 -254.019263) (xy 424.224771 -254.024055)
			(xy 424.232578 -254.024384) (xy 424.748706 -254.024384) (xy 424.754021 -254.024824) (xy 424.761595 -254.032285)
			(xy 424.762168 -254.037592) (xy 424.762168 -254.53213) (xy 424.762144 -254.532384) (xy 426.706284 -254.532384)
			(xy 426.706284 -254.531876) (xy 426.706284 -254.037592) (xy 426.706789 -254.03233) (xy 426.71423 -254.024889)
			(xy 426.719492 -254.024384) (xy 427.23562 -254.024384) (xy 427.243431 -254.024082) (xy 427.258303 -254.019288)
			(xy 427.26483 -254.014986) (xy 427.285919 -254.000637) (xy 427.33158 -253.977906) (xy 427.380186 -253.962447)
			(xy 427.430589 -253.954624) (xy 427.481595 -253.954624) (xy 427.531998 -253.962447) (xy 427.580604 -253.977906)
			(xy 427.626265 -254.000637) (xy 427.647354 -254.014986) (xy 427.653875 -254.019295) (xy 427.668753 -254.024068)
			(xy 427.676564 -254.024384) (xy 428.192692 -254.024384) (xy 428.197952 -254.024899) (xy 428.205395 -254.032333)
			(xy 428.2059 -254.037592) (xy 428.2059 -254.53213) (xy 428.205876 -254.532384) (xy 430.806352 -254.532384)
			(xy 430.806352 -254.531876) (xy 430.806352 -254.037592) (xy 430.806885 -254.032338) (xy 430.814307 -254.024898)
			(xy 430.81956 -254.024384) (xy 431.335688 -254.024384) (xy 431.343498 -254.024068) (xy 431.358369 -254.019284)
			(xy 431.364898 -254.014986) (xy 431.385987 -254.000637) (xy 431.431648 -253.977906) (xy 431.480254 -253.962447)
			(xy 431.530657 -253.954624) (xy 431.581663 -253.954624) (xy 431.632066 -253.962447) (xy 431.680672 -253.977906)
			(xy 431.726333 -254.000637) (xy 431.747422 -254.014986) (xy 431.75395 -254.019283) (xy 431.768823 -254.024063)
			(xy 431.776632 -254.024384) (xy 432.29276 -254.024384) (xy 432.298085 -254.024753) (xy 432.305628 -254.032268)
			(xy 432.305968 -254.037592) (xy 432.305968 -254.53213) (xy 434.250084 -254.53213) (xy 434.250084 -254.037592)
			(xy 434.250589 -254.03233) (xy 434.25803 -254.024889) (xy 434.263292 -254.024384) (xy 434.2638 -254.024384)
			(xy 434.779674 -254.024384) (xy 434.787483 -254.024062) (xy 434.802355 -254.019282) (xy 434.808884 -254.014986)
			(xy 434.829973 -254.000637) (xy 434.875634 -253.977906) (xy 434.92424 -253.962447) (xy 434.974643 -253.954624)
			(xy 435.025649 -253.954624) (xy 435.076052 -253.962447) (xy 435.124658 -253.977906) (xy 435.170319 -254.000637)
			(xy 435.191408 -254.014986) (xy 435.197939 -254.019278) (xy 435.212809 -254.024061) (xy 435.220618 -254.024384)
			(xy 435.736746 -254.024384) (xy 435.742054 -254.024864) (xy 435.749631 -254.032294) (xy 435.750208 -254.037592)
			(xy 435.750208 -254.53213) (xy 438.350152 -254.53213) (xy 438.350152 -254.037592) (xy 438.350685 -254.032338)
			(xy 438.358107 -254.024898) (xy 438.36336 -254.024384) (xy 438.363868 -254.024384) (xy 438.879742 -254.024384)
			(xy 438.88755 -254.024048) (xy 438.902422 -254.019278) (xy 438.908952 -254.014986) (xy 438.930041 -254.000637)
			(xy 438.975702 -253.977906) (xy 439.024308 -253.962447) (xy 439.074711 -253.954624) (xy 439.125717 -253.954624)
			(xy 439.17612 -253.962447) (xy 439.224726 -253.977906) (xy 439.270387 -254.000637) (xy 439.291476 -254.014986)
			(xy 439.298014 -254.019266) (xy 439.312879 -254.024056) (xy 439.320686 -254.024384) (xy 439.836814 -254.024384)
			(xy 439.84213 -254.024819) (xy 439.849703 -254.032284) (xy 439.850276 -254.037592) (xy 439.850276 -254.53213)
			(xy 439.850252 -254.532384) (xy 441.794392 -254.532384) (xy 441.794392 -254.531876) (xy 441.794392 -254.037592)
			(xy 441.794889 -254.032328) (xy 441.802336 -254.024886) (xy 441.8076 -254.024384) (xy 442.323728 -254.024384)
			(xy 442.331539 -254.024085) (xy 442.346411 -254.019289) (xy 442.352938 -254.014986) (xy 442.374027 -254.000637)
			(xy 442.419688 -253.977906) (xy 442.468294 -253.962447) (xy 442.518697 -253.954624) (xy 442.569703 -253.954624)
			(xy 442.620106 -253.962447) (xy 442.668712 -253.977906) (xy 442.714373 -254.000637) (xy 442.735462 -254.014986)
			(xy 442.742003 -254.01926) (xy 442.756866 -254.024054) (xy 442.764672 -254.024384) (xy 443.2808 -254.024384)
			(xy 443.286061 -254.024894) (xy 443.293503 -254.032332) (xy 443.294008 -254.037592) (xy 443.294008 -254.53213)
			(xy 443.293984 -254.532384) (xy 445.89446 -254.532384) (xy 445.89446 -254.531876) (xy 445.89446 -254.037592)
			(xy 445.894986 -254.032336) (xy 445.902413 -254.024896) (xy 445.907668 -254.024384) (xy 446.423796 -254.024384)
			(xy 446.431606 -254.024071) (xy 446.446478 -254.019285) (xy 446.453006 -254.014986) (xy 446.474095 -254.000637)
			(xy 446.519756 -253.977906) (xy 446.568362 -253.962447) (xy 446.618765 -253.954624) (xy 446.669771 -253.954624)
			(xy 446.720174 -253.962447) (xy 446.76878 -253.977906) (xy 446.814441 -254.000637) (xy 446.83553 -254.014986)
			(xy 446.842056 -254.019286) (xy 446.85693 -254.024064) (xy 446.86474 -254.024384) (xy 447.380868 -254.024384)
			(xy 447.386194 -254.024748) (xy 447.393736 -254.032267) (xy 447.394076 -254.037592) (xy 447.394076 -254.53213)
			(xy 447.394053 -254.532384) (xy 449.338192 -254.532384) (xy 449.338192 -254.531876) (xy 449.338192 -254.037592)
			(xy 449.338689 -254.032328) (xy 449.346136 -254.024886) (xy 449.3514 -254.024384) (xy 449.867528 -254.024384)
			(xy 449.875339 -254.024085) (xy 449.890211 -254.019289) (xy 449.896738 -254.014986) (xy 449.917827 -254.000637)
			(xy 449.963488 -253.977906) (xy 450.012094 -253.962447) (xy 450.062497 -253.954624) (xy 450.113503 -253.954624)
			(xy 450.163906 -253.962447) (xy 450.212512 -253.977906) (xy 450.258173 -254.000637) (xy 450.279262 -254.014986)
			(xy 450.285803 -254.01926) (xy 450.300666 -254.024054) (xy 450.308472 -254.024384) (xy 450.8246 -254.024384)
			(xy 450.829861 -254.024894) (xy 450.837303 -254.032332) (xy 450.837808 -254.037592) (xy 450.837808 -254.53213)
			(xy 450.837784 -254.532384) (xy 453.43826 -254.532384) (xy 453.43826 -254.531876) (xy 453.43826 -254.037592)
			(xy 453.438786 -254.032336) (xy 453.446213 -254.024896) (xy 453.451468 -254.024384) (xy 453.967596 -254.024384)
			(xy 453.975406 -254.024071) (xy 453.990278 -254.019285) (xy 453.996806 -254.014986) (xy 454.017895 -254.000637)
			(xy 454.063556 -253.977906) (xy 454.112162 -253.962447) (xy 454.162565 -253.954624) (xy 454.213571 -253.954624)
			(xy 454.263974 -253.962447) (xy 454.31258 -253.977906) (xy 454.358241 -254.000637) (xy 454.37933 -254.014986)
			(xy 454.385856 -254.019286) (xy 454.40073 -254.024064) (xy 454.40854 -254.024384) (xy 454.924668 -254.024384)
			(xy 454.929994 -254.024748) (xy 454.937536 -254.032267) (xy 454.937876 -254.037592) (xy 454.937876 -254.53213)
			(xy 454.937399 -254.537434) (xy 454.929963 -254.545003) (xy 454.924668 -254.545592) (xy 454.408794 -254.545592)
			(xy 454.400984 -254.545904) (xy 454.386113 -254.550692) (xy 454.379584 -254.55499) (xy 454.358467 -254.569347)
			(xy 454.312741 -254.592071) (xy 454.264067 -254.607498) (xy 454.213599 -254.615263) (xy 454.188068 -254.615696)
			(xy 454.162537 -254.61527) (xy 454.112073 -254.60749) (xy 454.063401 -254.592058) (xy 454.017674 -254.569338)
			(xy 453.996552 -254.55499) (xy 453.990031 -254.550681) (xy 453.975153 -254.545909) (xy 453.967342 -254.545592)
			(xy 453.451468 -254.545592) (xy 453.446198 -254.545125) (xy 453.438756 -254.537656) (xy 453.43826 -254.532384)
			(xy 450.837784 -254.532384) (xy 450.837303 -254.537427) (xy 450.829886 -254.544993) (xy 450.8246 -254.545592)
			(xy 450.308726 -254.545592) (xy 450.300917 -254.545918) (xy 450.286046 -254.550696) (xy 450.279516 -254.55499)
			(xy 450.25839 -254.569333) (xy 450.212668 -254.59206) (xy 450.163996 -254.607492) (xy 450.113531 -254.615261)
			(xy 450.088 -254.615696) (xy 450.06247 -254.615254) (xy 450.012007 -254.607479) (xy 449.963334 -254.592051)
			(xy 449.917606 -254.569336) (xy 449.896484 -254.55499) (xy 449.889956 -254.550693) (xy 449.875083 -254.545914)
			(xy 449.867274 -254.545592) (xy 449.3514 -254.545592) (xy 449.346064 -254.545272) (xy 449.338522 -254.537721)
			(xy 449.338192 -254.532384) (xy 447.394053 -254.532384) (xy 447.393599 -254.537434) (xy 447.386163 -254.545003)
			(xy 447.380868 -254.545592) (xy 446.864994 -254.545592) (xy 446.857184 -254.545904) (xy 446.842313 -254.550692)
			(xy 446.835784 -254.55499) (xy 446.814667 -254.569347) (xy 446.768941 -254.592071) (xy 446.720267 -254.607498)
			(xy 446.669799 -254.615263) (xy 446.644268 -254.615696) (xy 446.618737 -254.61527) (xy 446.568273 -254.60749)
			(xy 446.519601 -254.592058) (xy 446.473874 -254.569338) (xy 446.452752 -254.55499) (xy 446.446231 -254.550681)
			(xy 446.431353 -254.545909) (xy 446.423542 -254.545592) (xy 445.907668 -254.545592) (xy 445.902398 -254.545125)
			(xy 445.894956 -254.537656) (xy 445.89446 -254.532384) (xy 443.293984 -254.532384) (xy 443.293503 -254.537427)
			(xy 443.286086 -254.544993) (xy 443.2808 -254.545592) (xy 442.764926 -254.545592) (xy 442.757117 -254.545918)
			(xy 442.742246 -254.550696) (xy 442.735716 -254.55499) (xy 442.71459 -254.569333) (xy 442.668868 -254.59206)
			(xy 442.620196 -254.607492) (xy 442.569731 -254.615261) (xy 442.5442 -254.615696) (xy 442.51867 -254.615254)
			(xy 442.468207 -254.607479) (xy 442.419534 -254.592051) (xy 442.373806 -254.569336) (xy 442.352684 -254.55499)
			(xy 442.346156 -254.550693) (xy 442.331283 -254.545914) (xy 442.323474 -254.545592) (xy 441.8076 -254.545592)
			(xy 441.802264 -254.545272) (xy 441.794722 -254.537721) (xy 441.794392 -254.532384) (xy 439.850252 -254.532384)
			(xy 439.849771 -254.537494) (xy 439.842179 -254.545077) (xy 439.836814 -254.545592) (xy 439.32094 -254.545592)
			(xy 439.313132 -254.545924) (xy 439.29826 -254.550698) (xy 439.29173 -254.55499) (xy 439.270628 -254.56937)
			(xy 439.224897 -254.592089) (xy 439.176218 -254.60751) (xy 439.125747 -254.615267) (xy 439.100214 -254.615696)
			(xy 439.074684 -254.615247) (xy 439.024221 -254.607474) (xy 438.975549 -254.592048) (xy 438.929821 -254.569335)
			(xy 438.908698 -254.55499) (xy 438.902167 -254.550698) (xy 438.887297 -254.545916) (xy 438.879488 -254.545592)
			(xy 438.363614 -254.545592) (xy 438.358259 -254.545043) (xy 438.350674 -254.537483) (xy 438.350152 -254.53213)
			(xy 435.750208 -254.53213) (xy 435.749674 -254.537487) (xy 435.742102 -254.545068) (xy 435.736746 -254.545592)
			(xy 435.220872 -254.545592) (xy 435.213061 -254.545895) (xy 435.19819 -254.550689) (xy 435.191662 -254.55499)
			(xy 435.170552 -254.569356) (xy 435.124823 -254.592078) (xy 435.076147 -254.607503) (xy 435.025678 -254.615265)
			(xy 435.000146 -254.615696) (xy 434.974617 -254.615231) (xy 434.924154 -254.607463) (xy 434.875482 -254.592042)
			(xy 434.829753 -254.569333) (xy 434.80863 -254.55499) (xy 434.802092 -254.550711) (xy 434.787227 -254.54592)
			(xy 434.77942 -254.545592) (xy 434.263546 -254.545592) (xy 434.258124 -254.545193) (xy 434.250438 -254.537549)
			(xy 434.250084 -254.53213) (xy 432.305968 -254.53213) (xy 432.305498 -254.537436) (xy 432.298057 -254.545005)
			(xy 432.29276 -254.545592) (xy 431.776886 -254.545592) (xy 431.769076 -254.545901) (xy 431.754204 -254.55069)
			(xy 431.747676 -254.55499) (xy 431.726562 -254.56935) (xy 431.680835 -254.592073) (xy 431.632159 -254.6075)
			(xy 431.581692 -254.615264) (xy 431.55616 -254.615696) (xy 431.530629 -254.615274) (xy 431.480165 -254.607493)
			(xy 431.431493 -254.592059) (xy 431.385766 -254.569339) (xy 431.364644 -254.55499) (xy 431.358125 -254.550678)
			(xy 431.343245 -254.545908) (xy 431.335434 -254.545592) (xy 430.81956 -254.545592) (xy 430.814288 -254.54513)
			(xy 430.806847 -254.537658) (xy 430.806352 -254.532384) (xy 428.205876 -254.532384) (xy 428.205402 -254.537429)
			(xy 428.19798 -254.544996) (xy 428.192692 -254.545592) (xy 427.676818 -254.545592) (xy 427.669009 -254.545915)
			(xy 427.654137 -254.550695) (xy 427.647608 -254.55499) (xy 427.626485 -254.569336) (xy 427.580761 -254.592063)
			(xy 427.532088 -254.607493) (xy 427.481623 -254.615262) (xy 427.456092 -254.615696) (xy 427.430562 -254.615258)
			(xy 427.380098 -254.607481) (xy 427.331426 -254.592053) (xy 427.285698 -254.569337) (xy 427.264576 -254.55499)
			(xy 427.25805 -254.55069) (xy 427.243176 -254.545913) (xy 427.235366 -254.545592) (xy 426.719492 -254.545592)
			(xy 426.714155 -254.545277) (xy 426.706613 -254.537722) (xy 426.706284 -254.532384) (xy 424.762144 -254.532384)
			(xy 424.76167 -254.537496) (xy 424.754073 -254.54508) (xy 424.748706 -254.545592) (xy 424.232832 -254.545592)
			(xy 424.225023 -254.545921) (xy 424.210152 -254.550696) (xy 424.203622 -254.55499) (xy 424.182495 -254.56933)
			(xy 424.136773 -254.592058) (xy 424.088101 -254.60749) (xy 424.037636 -254.615261) (xy 424.012106 -254.615696)
			(xy 423.986576 -254.615251) (xy 423.936113 -254.607477) (xy 423.887441 -254.59205) (xy 423.841713 -254.569336)
			(xy 423.82059 -254.55499) (xy 423.814061 -254.550695) (xy 423.799189 -254.545915) (xy 423.79138 -254.545592)
			(xy 423.275506 -254.545592) (xy 423.27015 -254.545049) (xy 423.262566 -254.537485) (xy 423.262044 -254.53213)
			(xy 420.6621 -254.53213) (xy 420.661574 -254.537488) (xy 420.653996 -254.54507) (xy 420.648638 -254.545592)
			(xy 420.132764 -254.545592) (xy 420.124957 -254.545934) (xy 420.110085 -254.550701) (xy 420.103554 -254.55499)
			(xy 420.082446 -254.56936) (xy 420.036717 -254.592081) (xy 419.988039 -254.607505) (xy 419.93757 -254.615266)
			(xy 419.912038 -254.615696) (xy 419.886509 -254.615235) (xy 419.836046 -254.607465) (xy 419.787374 -254.592043)
			(xy 419.741645 -254.569334) (xy 419.720522 -254.55499) (xy 419.713985 -254.550707) (xy 419.699119 -254.545919)
			(xy 419.691312 -254.545592) (xy 419.175438 -254.545592) (xy 419.170015 -254.545198) (xy 419.162329 -254.537551)
			(xy 419.161976 -254.53213) (xy 417.21786 -254.53213) (xy 417.217397 -254.537438) (xy 417.209951 -254.545007)
			(xy 417.204652 -254.545592) (xy 415.731452 -254.545592) (xy 415.72618 -254.545135) (xy 415.718739 -254.537659)
			(xy 415.718244 -254.532384) (xy 413.117768 -254.532384) (xy 413.117301 -254.53743) (xy 413.109874 -254.544998)
			(xy 413.104584 -254.545592) (xy 411.631384 -254.545592) (xy 411.626115 -254.545115) (xy 411.618673 -254.537654)
			(xy 411.618176 -254.532384) (xy 308.118233 -254.532384) (xy 308.117769 -254.537499) (xy 308.110164 -254.545083)
			(xy 308.104794 -254.545592) (xy 306.631594 -254.545592) (xy 306.626237 -254.545057) (xy 306.618653 -254.537487)
			(xy 306.618132 -254.53213) (xy 304.018188 -254.53213) (xy 304.017672 -254.537491) (xy 304.010087 -254.545074)
			(xy 304.004726 -254.545592) (xy 302.531526 -254.545592) (xy 302.526172 -254.545035) (xy 302.518587 -254.537481)
			(xy 302.518064 -254.53213) (xy 300.573948 -254.53213) (xy 300.573495 -254.537441) (xy 300.566042 -254.545011)
			(xy 300.56074 -254.545592) (xy 300.044866 -254.545592) (xy 300.037059 -254.545935) (xy 300.022187 -254.550701)
			(xy 300.015656 -254.55499) (xy 299.994547 -254.569359) (xy 299.948818 -254.59208) (xy 299.900141 -254.607504)
			(xy 299.849672 -254.615266) (xy 299.82414 -254.615696) (xy 299.798611 -254.615234) (xy 299.748148 -254.607465)
			(xy 299.699476 -254.592043) (xy 299.653747 -254.569334) (xy 299.632624 -254.55499) (xy 299.626087 -254.550708)
			(xy 299.611221 -254.54592) (xy 299.603414 -254.545592) (xy 299.08754 -254.545592) (xy 299.082209 -254.545245)
			(xy 299.074665 -254.537714) (xy 299.074332 -254.532384) (xy 296.473857 -254.532384) (xy 296.473399 -254.537433)
			(xy 296.465965 -254.545002) (xy 296.460672 -254.545592) (xy 295.944798 -254.545592) (xy 295.936988 -254.545906)
			(xy 295.922117 -254.550692) (xy 295.915588 -254.55499) (xy 295.89447 -254.569345) (xy 295.848745 -254.592069)
			(xy 295.80007 -254.607498) (xy 295.749603 -254.615263) (xy 295.724072 -254.615696) (xy 295.698541 -254.615268)
			(xy 295.648078 -254.607488) (xy 295.599405 -254.592057) (xy 295.553678 -254.569338) (xy 295.532556 -254.55499)
			(xy 295.526034 -254.550682) (xy 295.511157 -254.54591) (xy 295.503346 -254.545592) (xy 294.987472 -254.545592)
			(xy 294.982202 -254.545122) (xy 294.97476 -254.537656) (xy 294.974264 -254.532384) (xy 293.030125 -254.532384)
			(xy 293.029668 -254.537501) (xy 293.022059 -254.545086) (xy 293.016686 -254.545592) (xy 292.500812 -254.545592)
			(xy 292.493003 -254.545912) (xy 292.478131 -254.550694) (xy 292.471602 -254.55499) (xy 292.45048 -254.569339)
			(xy 292.404756 -254.592065) (xy 292.356083 -254.607495) (xy 292.305617 -254.615262) (xy 292.280086 -254.615696)
			(xy 292.254556 -254.615261) (xy 292.204092 -254.607484) (xy 292.15542 -254.592054) (xy 292.109692 -254.569337)
			(xy 292.08857 -254.55499) (xy 292.082045 -254.550688) (xy 292.06717 -254.545912) (xy 292.05936 -254.545592)
			(xy 291.543486 -254.545592) (xy 291.538128 -254.545062) (xy 291.530545 -254.537488) (xy 291.530024 -254.53213)
			(xy 288.93008 -254.53213) (xy 288.929571 -254.537493) (xy 288.921982 -254.545076) (xy 288.916618 -254.545592)
			(xy 288.400744 -254.545592) (xy 288.392936 -254.545926) (xy 288.378064 -254.550698) (xy 288.371534 -254.55499)
			(xy 288.350431 -254.569368) (xy 288.3047 -254.592087) (xy 288.256021 -254.607509) (xy 288.205551 -254.615267)
			(xy 288.180018 -254.615696) (xy 288.154488 -254.615245) (xy 288.104025 -254.607472) (xy 288.055353 -254.592047)
			(xy 288.009625 -254.569335) (xy 287.988502 -254.55499) (xy 287.98197 -254.5507) (xy 287.9671 -254.545916)
			(xy 287.959292 -254.545592) (xy 287.443418 -254.545592) (xy 287.438063 -254.545041) (xy 287.430478 -254.537483)
			(xy 287.429956 -254.53213) (xy 285.48584 -254.53213) (xy 285.485395 -254.537443) (xy 285.477936 -254.545013)
			(xy 285.472632 -254.545592) (xy 284.956758 -254.545592) (xy 284.94895 -254.545932) (xy 284.934079 -254.5507)
			(xy 284.927548 -254.55499) (xy 284.906441 -254.569362) (xy 284.860712 -254.592083) (xy 284.812034 -254.607506)
			(xy 284.761564 -254.615266) (xy 284.736032 -254.615696) (xy 284.710503 -254.615238) (xy 284.66004 -254.607467)
			(xy 284.611368 -254.592045) (xy 284.565639 -254.569334) (xy 284.544516 -254.55499) (xy 284.537981 -254.550705)
			(xy 284.523114 -254.545918) (xy 284.515306 -254.545592) (xy 283.999432 -254.545592) (xy 283.9941 -254.54525)
			(xy 283.986556 -254.537715) (xy 283.986224 -254.532384) (xy 281.385749 -254.532384) (xy 281.385298 -254.537435)
			(xy 281.37786 -254.545004) (xy 281.372564 -254.545592) (xy 280.85669 -254.545592) (xy 280.84888 -254.545903)
			(xy 280.834008 -254.550691) (xy 280.82748 -254.55499) (xy 280.806364 -254.569349) (xy 280.760638 -254.592072)
			(xy 280.711963 -254.607499) (xy 280.661495 -254.615264) (xy 280.635964 -254.615696) (xy 280.610433 -254.615272)
			(xy 280.559969 -254.607491) (xy 280.511297 -254.592058) (xy 280.46557 -254.569339) (xy 280.444448 -254.55499)
			(xy 280.437928 -254.550679) (xy 280.423049 -254.545909) (xy 280.415238 -254.545592) (xy 279.899364 -254.545592)
			(xy 279.894093 -254.545127) (xy 279.886652 -254.537657) (xy 279.886156 -254.532384) (xy 277.942019 -254.532384)
			(xy 277.941595 -254.537443) (xy 277.934136 -254.545013) (xy 277.928832 -254.545592) (xy 277.412958 -254.545592)
			(xy 277.40515 -254.545932) (xy 277.390279 -254.5507) (xy 277.383748 -254.55499) (xy 277.362641 -254.569362)
			(xy 277.316912 -254.592083) (xy 277.268234 -254.607506) (xy 277.217764 -254.615266) (xy 277.192232 -254.615696)
			(xy 277.166703 -254.615238) (xy 277.11624 -254.607467) (xy 277.067568 -254.592045) (xy 277.021839 -254.569334)
			(xy 277.000716 -254.55499) (xy 276.994181 -254.550705) (xy 276.979314 -254.545918) (xy 276.971506 -254.545592)
			(xy 276.455632 -254.545592) (xy 276.4503 -254.54525) (xy 276.442756 -254.537715) (xy 276.442424 -254.532384)
			(xy 273.841949 -254.532384) (xy 273.841498 -254.537435) (xy 273.83406 -254.545004) (xy 273.828764 -254.545592)
			(xy 273.31289 -254.545592) (xy 273.30508 -254.545903) (xy 273.290208 -254.550691) (xy 273.28368 -254.55499)
			(xy 273.262564 -254.569349) (xy 273.216838 -254.592072) (xy 273.168163 -254.607499) (xy 273.117695 -254.615264)
			(xy 273.092164 -254.615696) (xy 273.066633 -254.615272) (xy 273.016169 -254.607491) (xy 272.967497 -254.592058)
			(xy 272.92177 -254.569339) (xy 272.900648 -254.55499) (xy 272.894128 -254.550679) (xy 272.879249 -254.545909)
			(xy 272.871438 -254.545592) (xy 272.355564 -254.545592) (xy 272.350293 -254.545127) (xy 272.342852 -254.537657)
			(xy 272.342356 -254.532384) (xy 270.398218 -254.532384) (xy 270.397767 -254.537503) (xy 270.390153 -254.545088)
			(xy 270.384778 -254.545592) (xy 269.868904 -254.545592) (xy 269.861094 -254.545909) (xy 269.846223 -254.550693)
			(xy 269.839694 -254.55499) (xy 269.818575 -254.569343) (xy 269.77285 -254.592067) (xy 269.724176 -254.607496)
			(xy 269.673709 -254.615263) (xy 269.648178 -254.615696) (xy 269.622648 -254.615265) (xy 269.572184 -254.607486)
			(xy 269.523512 -254.592055) (xy 269.477784 -254.569338) (xy 269.456662 -254.55499) (xy 269.450139 -254.550684)
			(xy 269.435262 -254.545911) (xy 269.427452 -254.545592) (xy 268.911578 -254.545592) (xy 268.906219 -254.545067)
			(xy 268.898636 -254.537489) (xy 268.898116 -254.53213) (xy 266.298172 -254.53213) (xy 266.297671 -254.537495)
			(xy 266.290076 -254.545079) (xy 266.28471 -254.545592) (xy 265.768836 -254.545592) (xy 265.761027 -254.545922)
			(xy 265.746156 -254.550697) (xy 265.739626 -254.55499) (xy 265.718498 -254.569329) (xy 265.672776 -254.592057)
			(xy 265.624105 -254.607489) (xy 265.57364 -254.61526) (xy 265.54811 -254.615696) (xy 265.52258 -254.615249)
			(xy 265.472117 -254.607475) (xy 265.423445 -254.592049) (xy 265.377717 -254.569336) (xy 265.356594 -254.55499)
			(xy 265.350064 -254.550697) (xy 265.335193 -254.545915) (xy 265.327384 -254.545592) (xy 264.81151 -254.545592)
			(xy 264.806155 -254.545046) (xy 264.79857 -254.537484) (xy 264.798048 -254.53213) (xy 206.997808 -254.53213)
			(xy 206.997808 -254.532384) (xy 206.997462 -254.537714) (xy 206.98993 -254.545256) (xy 206.9846 -254.545592)
			(xy 206.468726 -254.545592) (xy 206.460849 -254.545849) (xy 206.445844 -254.550653) (xy 206.439262 -254.55499)
			(xy 206.418189 -254.569388) (xy 206.372542 -254.592214) (xy 206.323935 -254.607769) (xy 206.273517 -254.615687)
			(xy 206.248 -254.616204) (xy 206.222479 -254.615731) (xy 206.172052 -254.607831) (xy 206.12344 -254.592266)
			(xy 206.077802 -254.569407) (xy 206.056738 -254.55499) (xy 206.05014 -254.550686) (xy 206.035145 -254.545893)
			(xy 206.027274 -254.545592) (xy 205.5114 -254.545592) (xy 205.506064 -254.545272) (xy 205.498522 -254.537721)
			(xy 205.498192 -254.532384) (xy 202.89774 -254.532384) (xy 202.897198 -254.537637) (xy 202.889783 -254.545079)
			(xy 202.884532 -254.545592) (xy 202.368658 -254.545592) (xy 202.360782 -254.545862) (xy 202.345778 -254.550657)
			(xy 202.339194 -254.55499) (xy 202.318112 -254.569374) (xy 202.272468 -254.592203) (xy 202.223864 -254.607763)
			(xy 202.173448 -254.615685) (xy 202.147932 -254.616204) (xy 202.122412 -254.615715) (xy 202.071985 -254.60782)
			(xy 202.023373 -254.59226) (xy 201.977735 -254.569405) (xy 201.95667 -254.55499) (xy 201.950088 -254.55066)
			(xy 201.93508 -254.545883) (xy 201.927206 -254.545592) (xy 201.411332 -254.545592) (xy 201.406 -254.54525)
			(xy 201.398456 -254.537715) (xy 201.398124 -254.532384) (xy 199.454008 -254.532384) (xy 199.453662 -254.537714)
			(xy 199.44613 -254.545256) (xy 199.4408 -254.545592) (xy 198.924926 -254.545592) (xy 198.917049 -254.545849)
			(xy 198.902044 -254.550653) (xy 198.895462 -254.55499) (xy 198.874389 -254.569388) (xy 198.828742 -254.592214)
			(xy 198.780135 -254.607769) (xy 198.729717 -254.615687) (xy 198.7042 -254.616204) (xy 198.678679 -254.615731)
			(xy 198.628252 -254.607831) (xy 198.57964 -254.592266) (xy 198.534002 -254.569407) (xy 198.512938 -254.55499)
			(xy 198.50634 -254.550686) (xy 198.491345 -254.545893) (xy 198.483474 -254.545592) (xy 197.9676 -254.545592)
			(xy 197.962264 -254.545272) (xy 197.954722 -254.537721) (xy 197.954392 -254.532384) (xy 195.35394 -254.532384)
			(xy 195.353398 -254.537637) (xy 195.345983 -254.545079) (xy 195.340732 -254.545592) (xy 194.824858 -254.545592)
			(xy 194.816982 -254.545862) (xy 194.801978 -254.550657) (xy 194.795394 -254.55499) (xy 194.774312 -254.569374)
			(xy 194.728668 -254.592203) (xy 194.680064 -254.607763) (xy 194.629648 -254.615685) (xy 194.604132 -254.616204)
			(xy 194.578612 -254.615715) (xy 194.528185 -254.60782) (xy 194.479573 -254.59226) (xy 194.433935 -254.569405)
			(xy 194.41287 -254.55499) (xy 194.406288 -254.55066) (xy 194.39128 -254.545883) (xy 194.383406 -254.545592)
			(xy 193.867532 -254.545592) (xy 193.8622 -254.54525) (xy 193.854656 -254.537715) (xy 193.854324 -254.532384)
			(xy 191.910208 -254.532384) (xy 191.909862 -254.537714) (xy 191.90233 -254.545256) (xy 191.897 -254.545592)
			(xy 191.896492 -254.545592) (xy 191.380872 -254.545592) (xy 191.372996 -254.545868) (xy 191.357992 -254.550659)
			(xy 191.351408 -254.55499) (xy 191.33035 -254.569411) (xy 191.284698 -254.592232) (xy 191.236086 -254.607781)
			(xy 191.185664 -254.615691) (xy 191.160146 -254.616204) (xy 191.134626 -254.615708) (xy 191.084199 -254.607815)
			(xy 191.035588 -254.592257) (xy 190.989949 -254.569404) (xy 190.968884 -254.55499) (xy 190.962298 -254.550665)
			(xy 190.947294 -254.545885) (xy 190.93942 -254.545592) (xy 190.423546 -254.545592) (xy 190.418255 -254.54505)
			(xy 190.410683 -254.537662) (xy 190.410084 -254.532384) (xy 187.81014 -254.532384) (xy 187.809598 -254.537637)
			(xy 187.802183 -254.545079) (xy 187.796932 -254.545592) (xy 187.796424 -254.545592) (xy 187.280804 -254.545592)
			(xy 187.27293 -254.545882) (xy 187.257925 -254.550663) (xy 187.25134 -254.55499) (xy 187.230273 -254.569397)
			(xy 187.184624 -254.592221) (xy 187.136015 -254.607774) (xy 187.085596 -254.615689) (xy 187.060078 -254.616204)
			(xy 187.034559 -254.615692) (xy 186.984133 -254.607804) (xy 186.935521 -254.59225) (xy 186.889882 -254.569402)
			(xy 186.868816 -254.55499) (xy 186.862223 -254.550677) (xy 186.847224 -254.545889) (xy 186.839352 -254.545592)
			(xy 186.323478 -254.545592) (xy 186.318179 -254.545095) (xy 186.310611 -254.537673) (xy 186.310016 -254.532384)
			(xy 184.3659 -254.532384) (xy 184.365562 -254.537716) (xy 184.358024 -254.545258) (xy 184.352692 -254.545592)
			(xy 183.836818 -254.545592) (xy 183.828944 -254.545888) (xy 183.81394 -254.550665) (xy 183.807354 -254.55499)
			(xy 183.786283 -254.569391) (xy 183.740635 -254.592216) (xy 183.692028 -254.607771) (xy 183.641609 -254.615688)
			(xy 183.616092 -254.616204) (xy 183.590573 -254.615685) (xy 183.540147 -254.607799) (xy 183.491536 -254.592248)
			(xy 183.445896 -254.569401) (xy 183.42483 -254.55499) (xy 183.418234 -254.550683) (xy 183.403237 -254.545891)
			(xy 183.395366 -254.545592) (xy 182.879492 -254.545592) (xy 182.874155 -254.545277) (xy 182.866613 -254.537722)
			(xy 182.866284 -254.532384) (xy 180.265832 -254.532384) (xy 180.265297 -254.537639) (xy 180.257878 -254.545081)
			(xy 180.252624 -254.545592) (xy 179.73675 -254.545592) (xy 179.728874 -254.545859) (xy 179.713869 -254.550656)
			(xy 179.707286 -254.55499) (xy 179.686206 -254.569378) (xy 179.640562 -254.592206) (xy 179.591957 -254.607764)
			(xy 179.54154 -254.615685) (xy 179.516024 -254.616204) (xy 179.490504 -254.615719) (xy 179.440077 -254.607823)
			(xy 179.391465 -254.592261) (xy 179.345827 -254.569406) (xy 179.324762 -254.55499) (xy 179.318181 -254.550657)
			(xy 179.303173 -254.545881) (xy 179.295298 -254.545592) (xy 178.779424 -254.545592) (xy 178.774091 -254.545255)
			(xy 178.766548 -254.537717) (xy 178.766216 -254.532384) (xy 176.8221 -254.532384) (xy 176.821762 -254.537716)
			(xy 176.814224 -254.545258) (xy 176.808892 -254.545592) (xy 176.808384 -254.545592) (xy 176.292764 -254.545592)
			(xy 176.284888 -254.545865) (xy 176.269884 -254.550658) (xy 176.2633 -254.55499) (xy 176.242216 -254.569372)
			(xy 176.196573 -254.592201) (xy 176.147969 -254.607761) (xy 176.097554 -254.615684) (xy 176.072038 -254.616204)
			(xy 176.046518 -254.615712) (xy 175.996091 -254.607818) (xy 175.94748 -254.592259) (xy 175.901841 -254.569405)
			(xy 175.880776 -254.55499) (xy 175.874192 -254.550662) (xy 175.859186 -254.545883) (xy 175.851312 -254.545592)
			(xy 175.335438 -254.545592) (xy 175.330146 -254.545055) (xy 175.322575 -254.537663) (xy 175.321976 -254.532384)
			(xy 172.722032 -254.532384) (xy 172.721497 -254.537639) (xy 172.714078 -254.545081) (xy 172.708824 -254.545592)
			(xy 172.708316 -254.545592) (xy 172.192696 -254.545592) (xy 172.184821 -254.545878) (xy 172.169817 -254.550662)
			(xy 172.163232 -254.55499) (xy 172.142167 -254.569401) (xy 172.096517 -254.592224) (xy 172.047908 -254.607776)
			(xy 171.997488 -254.615689) (xy 171.97197 -254.616204) (xy 171.946451 -254.615696) (xy 171.896024 -254.607807)
			(xy 171.847413 -254.592252) (xy 171.801774 -254.569403) (xy 171.780708 -254.55499) (xy 171.774117 -254.550674)
			(xy 171.759117 -254.545888) (xy 171.751244 -254.545592) (xy 171.23537 -254.545592) (xy 171.23007 -254.545101)
			(xy 171.222502 -254.537674) (xy 171.221908 -254.532384) (xy 169.277792 -254.532384) (xy 169.277461 -254.537718)
			(xy 169.269918 -254.545261) (xy 169.264584 -254.545592) (xy 167.791384 -254.545592) (xy 167.786115 -254.545115)
			(xy 167.778673 -254.537654) (xy 167.778176 -254.532384) (xy 165.177724 -254.532384) (xy 165.177196 -254.537641)
			(xy 165.169772 -254.545084) (xy 165.164516 -254.545592) (xy 163.691316 -254.545592) (xy 163.685982 -254.545261)
			(xy 163.678439 -254.537718) (xy 163.678108 -254.532384) (xy 60.178188 -254.532384) (xy 60.17786 -254.537719)
			(xy 60.170315 -254.545262) (xy 60.16498 -254.545592) (xy 60.164472 -254.545592) (xy 58.691526 -254.545592)
			(xy 58.686232 -254.545063) (xy 58.678662 -254.537665) (xy 58.678064 -254.532384) (xy 56.07812 -254.532384)
			(xy 56.077764 -254.537711) (xy 56.070238 -254.545252) (xy 56.064912 -254.545592) (xy 54.591458 -254.545592)
			(xy 54.586156 -254.545109) (xy 54.578589 -254.537676) (xy 54.577996 -254.532384) (xy 52.63388 -254.532384)
			(xy 52.63356 -254.537721) (xy 52.626009 -254.545265) (xy 52.620672 -254.545592) (xy 52.104798 -254.545592)
			(xy 52.096923 -254.545879) (xy 52.081919 -254.550662) (xy 52.075334 -254.55499) (xy 52.054269 -254.5694)
			(xy 52.008619 -254.592223) (xy 51.960009 -254.607775) (xy 51.90959 -254.615689) (xy 51.884072 -254.616204)
			(xy 51.858553 -254.615695) (xy 51.808127 -254.607806) (xy 51.759515 -254.592252) (xy 51.713876 -254.569402)
			(xy 51.69281 -254.55499) (xy 51.686219 -254.550675) (xy 51.671218 -254.545888) (xy 51.663346 -254.545592)
			(xy 51.147472 -254.545592) (xy 51.142202 -254.545122) (xy 51.13476 -254.537656) (xy 51.134264 -254.532384)
			(xy 48.533812 -254.532384) (xy 48.533463 -254.537713) (xy 48.525933 -254.545255) (xy 48.520604 -254.545592)
			(xy 48.00473 -254.545592) (xy 47.996853 -254.54585) (xy 47.981849 -254.550653) (xy 47.975266 -254.55499)
			(xy 47.954192 -254.569386) (xy 47.908545 -254.592212) (xy 47.859938 -254.607769) (xy 47.809521 -254.615687)
			(xy 47.784004 -254.616204) (xy 47.758483 -254.615729) (xy 47.708056 -254.60783) (xy 47.659444 -254.592265)
			(xy 47.613806 -254.569407) (xy 47.592742 -254.55499) (xy 47.586166 -254.550649) (xy 47.571154 -254.545878)
			(xy 47.563278 -254.545592) (xy 47.047404 -254.545592) (xy 47.042068 -254.545269) (xy 47.034526 -254.53772)
			(xy 47.034196 -254.532384) (xy 45.09008 -254.532384) (xy 45.08976 -254.537721) (xy 45.082209 -254.545265)
			(xy 45.076872 -254.545592) (xy 45.076364 -254.545592) (xy 44.560744 -254.545592) (xy 44.552867 -254.545856)
			(xy 44.537863 -254.550655) (xy 44.53128 -254.55499) (xy 44.510202 -254.56938) (xy 44.464557 -254.592208)
			(xy 44.415951 -254.607766) (xy 44.365535 -254.615686) (xy 44.340018 -254.616204) (xy 44.314498 -254.615722)
			(xy 44.26407 -254.607825) (xy 44.215459 -254.592263) (xy 44.169821 -254.569406) (xy 44.148756 -254.55499)
			(xy 44.142177 -254.550654) (xy 44.127167 -254.545881) (xy 44.119292 -254.545592) (xy 43.603418 -254.545592)
			(xy 43.598123 -254.545069) (xy 43.590553 -254.537666) (xy 43.589956 -254.532384) (xy 40.990012 -254.532384)
			(xy 40.989663 -254.537713) (xy 40.982133 -254.545255) (xy 40.976804 -254.545592) (xy 40.976296 -254.545592)
			(xy 40.460676 -254.545592) (xy 40.4528 -254.54587) (xy 40.437796 -254.550659) (xy 40.431212 -254.55499)
			(xy 40.410153 -254.569409) (xy 40.364501 -254.59223) (xy 40.315889 -254.60778) (xy 40.265468 -254.615691)
			(xy 40.23995 -254.616204) (xy 40.21443 -254.615706) (xy 40.164004 -254.607814) (xy 40.115392 -254.592256)
			(xy 40.069753 -254.569404) (xy 40.048688 -254.55499) (xy 40.042102 -254.550667) (xy 40.027098 -254.545885)
			(xy 40.019224 -254.545592) (xy 39.50335 -254.545592) (xy 39.498059 -254.545047) (xy 39.490487 -254.537661)
			(xy 39.489888 -254.532384) (xy 37.545772 -254.532384) (xy 37.545459 -254.537723) (xy 37.537903 -254.545267)
			(xy 37.532564 -254.545592) (xy 37.01669 -254.545592) (xy 37.008815 -254.545876) (xy 36.993811 -254.550661)
			(xy 36.987226 -254.55499) (xy 36.966163 -254.569403) (xy 36.920512 -254.592226) (xy 36.871902 -254.607777)
			(xy 36.821482 -254.61569) (xy 36.795964 -254.616204) (xy 36.770444 -254.615699) (xy 36.720018 -254.607809)
			(xy 36.671407 -254.592253) (xy 36.625768 -254.569403) (xy 36.604702 -254.55499) (xy 36.598112 -254.550672)
			(xy 36.583111 -254.545887) (xy 36.575238 -254.545592) (xy 36.059364 -254.545592) (xy 36.054093 -254.545127)
			(xy 36.046652 -254.537657) (xy 36.046156 -254.532384) (xy 33.445704 -254.532384) (xy 33.445362 -254.537715)
			(xy 33.437827 -254.545257) (xy 33.432496 -254.545592) (xy 32.916622 -254.545592) (xy 32.908748 -254.545889)
			(xy 32.893744 -254.550665) (xy 32.887158 -254.55499) (xy 32.866086 -254.56939) (xy 32.820439 -254.592215)
			(xy 32.771831 -254.60777) (xy 32.721413 -254.615687) (xy 32.695896 -254.616204) (xy 32.670375 -254.615733)
			(xy 32.619947 -254.607832) (xy 32.571336 -254.592267) (xy 32.525698 -254.569407) (xy 32.504634 -254.55499)
			(xy 32.498037 -254.550684) (xy 32.483041 -254.545892) (xy 32.47517 -254.545592) (xy 31.959296 -254.545592)
			(xy 31.953959 -254.545274) (xy 31.946418 -254.537721) (xy 31.946088 -254.532384) (xy 30.001972 -254.532384)
			(xy 30.001659 -254.537723) (xy 29.994103 -254.545267) (xy 29.988764 -254.545592) (xy 29.47289 -254.545592)
			(xy 29.465015 -254.545876) (xy 29.450011 -254.550661) (xy 29.443426 -254.55499) (xy 29.422363 -254.569403)
			(xy 29.376712 -254.592226) (xy 29.328102 -254.607777) (xy 29.277682 -254.61569) (xy 29.252164 -254.616204)
			(xy 29.226644 -254.615699) (xy 29.176218 -254.607809) (xy 29.127607 -254.592253) (xy 29.081968 -254.569403)
			(xy 29.060902 -254.55499) (xy 29.054312 -254.550672) (xy 29.039311 -254.545887) (xy 29.031438 -254.545592)
			(xy 28.515564 -254.545592) (xy 28.510293 -254.545127) (xy 28.502852 -254.537657) (xy 28.502356 -254.532384)
			(xy 25.901904 -254.532384) (xy 25.901562 -254.537715) (xy 25.894027 -254.545257) (xy 25.888696 -254.545592)
			(xy 25.372822 -254.545592) (xy 25.364948 -254.545889) (xy 25.349944 -254.550665) (xy 25.343358 -254.55499)
			(xy 25.322286 -254.56939) (xy 25.276639 -254.592215) (xy 25.228031 -254.60777) (xy 25.177613 -254.615687)
			(xy 25.152096 -254.616204) (xy 25.126575 -254.615733) (xy 25.076147 -254.607832) (xy 25.027536 -254.592267)
			(xy 24.981898 -254.569407) (xy 24.960834 -254.55499) (xy 24.954237 -254.550684) (xy 24.939241 -254.545892)
			(xy 24.93137 -254.545592) (xy 24.415496 -254.545592) (xy 24.410159 -254.545274) (xy 24.402618 -254.537721)
			(xy 24.402288 -254.532384) (xy 22.458172 -254.532384) (xy 22.457859 -254.537723) (xy 22.450303 -254.545267)
			(xy 22.444964 -254.545592) (xy 22.444456 -254.545592) (xy 21.928836 -254.545592) (xy 21.920959 -254.545853)
			(xy 21.905955 -254.550654) (xy 21.899372 -254.55499) (xy 21.878296 -254.569384) (xy 21.83265 -254.59221)
			(xy 21.784044 -254.607767) (xy 21.733627 -254.615686) (xy 21.70811 -254.616204) (xy 21.682589 -254.615726)
			(xy 21.632162 -254.607828) (xy 21.58355 -254.592264) (xy 21.537913 -254.569406) (xy 21.516848 -254.55499)
			(xy 21.51027 -254.550651) (xy 21.49526 -254.545879) (xy 21.487384 -254.545592) (xy 20.97151 -254.545592)
			(xy 20.966214 -254.545074) (xy 20.958644 -254.537668) (xy 20.958048 -254.532384) (xy 18.358104 -254.532384)
			(xy 18.357762 -254.537715) (xy 18.350227 -254.545257) (xy 18.344896 -254.545592) (xy 18.344388 -254.545592)
			(xy 17.828768 -254.545592) (xy 17.820892 -254.545866) (xy 17.805888 -254.550658) (xy 17.799304 -254.55499)
			(xy 17.778219 -254.56937) (xy 17.732577 -254.5922) (xy 17.683973 -254.60776) (xy 17.633558 -254.615684)
			(xy 17.608042 -254.616204) (xy 17.582522 -254.61571) (xy 17.532095 -254.607816) (xy 17.483484 -254.592258)
			(xy 17.437845 -254.569404) (xy 17.41678 -254.55499) (xy 17.410195 -254.550663) (xy 17.39519 -254.545884)
			(xy 17.387316 -254.545592) (xy 16.871442 -254.545592) (xy 16.86615 -254.545053) (xy 16.858579 -254.537663)
			(xy 16.85798 -254.532384) (xy 2.509012 -254.532384) (xy 2.509012 -258.880356) (xy 67.312036 -258.880356)
			(xy 67.316066 -258.738021) (xy 67.328141 -258.596141) (xy 67.348224 -258.455173) (xy 67.376251 -258.315566)
			(xy 67.412131 -258.177768) (xy 67.455749 -258.042221) (xy 67.506966 -257.909359) (xy 67.565617 -257.779607)
			(xy 67.631515 -257.653381) (xy 67.704449 -257.531085) (xy 67.784186 -257.413112) (xy 67.870468 -257.299839)
			(xy 67.963021 -257.191628) (xy 68.061548 -257.088827) (xy 68.165733 -256.991765) (xy 68.275242 -256.900753)
			(xy 68.389725 -256.816081) (xy 68.508815 -256.738023) (xy 68.63213 -256.666827) (xy 68.759276 -256.602721)
			(xy 68.889845 -256.545912) (xy 69.023419 -256.49658) (xy 69.15957 -256.454884) (xy 69.297861 -256.420958)
			(xy 69.437851 -256.39491) (xy 69.57909 -256.376824) (xy 69.721126 -256.366757) (xy 69.863504 -256.364742)
			(xy 70.005768 -256.370785) (xy 70.147462 -256.384867) (xy 70.288132 -256.406943) (xy 70.427329 -256.436943)
			(xy 70.564605 -256.474769) (xy 70.699521 -256.520301) (xy 70.831645 -256.573392) (xy 70.960554 -256.633874)
			(xy 71.085835 -256.701552) (xy 71.207086 -256.776209) (xy 71.323919 -256.857607) (xy 71.43596 -256.945484)
			(xy 71.54285 -257.039559) (xy 71.644247 -257.139531) (xy 71.739825 -257.245079) (xy 71.829279 -257.355865)
			(xy 71.912321 -257.471534) (xy 71.988687 -257.591717) (xy 72.058131 -257.716027) (xy 72.120431 -257.844068)
			(xy 72.175387 -257.975427) (xy 72.222824 -258.109686) (xy 72.262588 -258.246413) (xy 72.294554 -258.385171)
			(xy 72.318619 -258.525515) (xy 72.334705 -258.666996) (xy 72.34276 -258.80916) (xy 72.343264 -258.880356)
			(xy 151.51202 -258.880356) (xy 151.51605 -258.738021) (xy 151.528125 -258.596141) (xy 151.548208 -258.455173)
			(xy 151.576235 -258.315566) (xy 151.612115 -258.177768) (xy 151.655733 -258.042221) (xy 151.70695 -257.909359)
			(xy 151.765601 -257.779607) (xy 151.831499 -257.653381) (xy 151.904433 -257.531085) (xy 151.98417 -257.413112)
			(xy 152.070452 -257.299839) (xy 152.163005 -257.191628) (xy 152.261532 -257.088827) (xy 152.365717 -256.991765)
			(xy 152.475226 -256.900753) (xy 152.589709 -256.816081) (xy 152.708799 -256.738023) (xy 152.832114 -256.666827)
			(xy 152.95926 -256.602721) (xy 153.089829 -256.545912) (xy 153.223403 -256.49658) (xy 153.359554 -256.454884)
			(xy 153.497845 -256.420958) (xy 153.637835 -256.39491) (xy 153.779074 -256.376824) (xy 153.92111 -256.366757)
			(xy 154.063488 -256.364742) (xy 154.205752 -256.370785) (xy 154.347446 -256.384867) (xy 154.488116 -256.406943)
			(xy 154.627313 -256.436943) (xy 154.764589 -256.474769) (xy 154.899505 -256.520301) (xy 155.031629 -256.573392)
			(xy 155.160538 -256.633874) (xy 155.285819 -256.701552) (xy 155.40707 -256.776209) (xy 155.523903 -256.857607)
			(xy 155.635944 -256.945484) (xy 155.742834 -257.039559) (xy 155.844231 -257.139531) (xy 155.939809 -257.245079)
			(xy 156.029263 -257.355865) (xy 156.112305 -257.471534) (xy 156.188671 -257.591717) (xy 156.258115 -257.716027)
			(xy 156.320415 -257.844068) (xy 156.375371 -257.975427) (xy 156.422808 -258.109686) (xy 156.462572 -258.246413)
			(xy 156.494538 -258.385171) (xy 156.518603 -258.525515) (xy 156.534689 -258.666996) (xy 156.542744 -258.80916)
			(xy 156.543246 -258.880102) (xy 315.252104 -258.880102) (xy 315.256134 -258.737767) (xy 315.268209 -258.595887)
			(xy 315.288292 -258.454919) (xy 315.316319 -258.315312) (xy 315.352199 -258.177514) (xy 315.395817 -258.041967)
			(xy 315.447034 -257.909105) (xy 315.505685 -257.779353) (xy 315.571583 -257.653127) (xy 315.644517 -257.530831)
			(xy 315.724254 -257.412858) (xy 315.810536 -257.299585) (xy 315.903089 -257.191374) (xy 316.001616 -257.088573)
			(xy 316.105801 -256.991511) (xy 316.21531 -256.900499) (xy 316.329793 -256.815827) (xy 316.448883 -256.737769)
			(xy 316.572198 -256.666573) (xy 316.699344 -256.602467) (xy 316.829913 -256.545658) (xy 316.963487 -256.496326)
			(xy 317.099638 -256.45463) (xy 317.237929 -256.420704) (xy 317.377919 -256.394656) (xy 317.519158 -256.37657)
			(xy 317.661194 -256.366503) (xy 317.803572 -256.364488) (xy 317.945836 -256.370531) (xy 318.08753 -256.384613)
			(xy 318.2282 -256.406689) (xy 318.367397 -256.436689) (xy 318.504673 -256.474515) (xy 318.639589 -256.520047)
			(xy 318.771713 -256.573138) (xy 318.900622 -256.63362) (xy 319.025903 -256.701298) (xy 319.147154 -256.775955)
			(xy 319.263987 -256.857353) (xy 319.376028 -256.94523) (xy 319.482918 -257.039305) (xy 319.584315 -257.139277)
			(xy 319.679893 -257.244825) (xy 319.769347 -257.355611) (xy 319.852389 -257.47128) (xy 319.928755 -257.591463)
			(xy 319.998199 -257.715773) (xy 320.060499 -257.843814) (xy 320.115455 -257.975173) (xy 320.162892 -258.109432)
			(xy 320.202656 -258.246159) (xy 320.234622 -258.384917) (xy 320.258687 -258.525261) (xy 320.274773 -258.666742)
			(xy 320.282828 -258.808906) (xy 320.283332 -258.880102) (xy 399.452088 -258.880102) (xy 399.456118 -258.737767)
			(xy 399.468193 -258.595887) (xy 399.488276 -258.454919) (xy 399.516303 -258.315312) (xy 399.552183 -258.177514)
			(xy 399.595801 -258.041967) (xy 399.647018 -257.909105) (xy 399.705669 -257.779353) (xy 399.771567 -257.653127)
			(xy 399.844501 -257.530831) (xy 399.924238 -257.412858) (xy 400.01052 -257.299585) (xy 400.103073 -257.191374)
			(xy 400.2016 -257.088573) (xy 400.305785 -256.991511) (xy 400.415294 -256.900499) (xy 400.529777 -256.815827)
			(xy 400.648867 -256.737769) (xy 400.772182 -256.666573) (xy 400.899328 -256.602467) (xy 401.029897 -256.545658)
			(xy 401.163471 -256.496326) (xy 401.299622 -256.45463) (xy 401.437913 -256.420704) (xy 401.577903 -256.394656)
			(xy 401.719142 -256.37657) (xy 401.861178 -256.366503) (xy 402.003556 -256.364488) (xy 402.14582 -256.370531)
			(xy 402.287514 -256.384613) (xy 402.428184 -256.406689) (xy 402.567381 -256.436689) (xy 402.704657 -256.474515)
			(xy 402.839573 -256.520047) (xy 402.971697 -256.573138) (xy 403.100606 -256.63362) (xy 403.225887 -256.701298)
			(xy 403.347138 -256.775955) (xy 403.463971 -256.857353) (xy 403.576012 -256.94523) (xy 403.682902 -257.039305)
			(xy 403.784299 -257.139277) (xy 403.879877 -257.244825) (xy 403.969331 -257.355611) (xy 404.052373 -257.47128)
			(xy 404.128739 -257.591463) (xy 404.198183 -257.715773) (xy 404.260483 -257.843814) (xy 404.315439 -257.975173)
			(xy 404.362876 -258.109432) (xy 404.40264 -258.246159) (xy 404.434606 -258.384917) (xy 404.458671 -258.525261)
			(xy 404.474757 -258.666742) (xy 404.482812 -258.808906) (xy 404.483316 -258.880102) (xy 404.482812 -258.951298)
			(xy 404.474757 -259.093462) (xy 404.458671 -259.234943) (xy 404.434606 -259.375287) (xy 404.40264 -259.514045)
			(xy 404.362876 -259.650772) (xy 404.315439 -259.785031) (xy 404.260483 -259.91639) (xy 404.198183 -260.044431)
			(xy 404.128739 -260.168741) (xy 404.052373 -260.288924) (xy 403.969331 -260.404593) (xy 403.879877 -260.515379)
			(xy 403.784299 -260.620927) (xy 403.682902 -260.720899) (xy 403.576012 -260.814974) (xy 403.463971 -260.902851)
			(xy 403.347138 -260.984249) (xy 403.225887 -261.058906) (xy 403.100606 -261.126584) (xy 402.971697 -261.187066)
			(xy 402.839573 -261.240157) (xy 402.704657 -261.285689) (xy 402.567381 -261.323515) (xy 402.525821 -261.332472)
			(xy 415.718244 -261.332472) (xy 415.718244 -260.83768) (xy 415.718777 -260.832426) (xy 415.726199 -260.824988)
			(xy 415.731452 -260.824472) (xy 417.204652 -260.824472) (xy 417.209973 -260.824857) (xy 417.217515 -260.832361)
			(xy 417.21786 -260.83768) (xy 417.21786 -261.332218) (xy 423.262044 -261.332218) (xy 423.262044 -260.83768)
			(xy 423.262577 -260.832426) (xy 423.269999 -260.824988) (xy 423.275252 -260.824472) (xy 423.27576 -260.824472)
			(xy 423.791634 -260.824472) (xy 423.799442 -260.824135) (xy 423.814314 -260.819365) (xy 423.820844 -260.815074)
			(xy 423.841933 -260.800725) (xy 423.887594 -260.777994) (xy 423.9362 -260.762535) (xy 423.986603 -260.754712)
			(xy 424.037609 -260.754712) (xy 424.088012 -260.762535) (xy 424.136618 -260.777994) (xy 424.182279 -260.800725)
			(xy 424.203368 -260.815074) (xy 424.209909 -260.819349) (xy 424.224772 -260.824142) (xy 424.232578 -260.824472)
			(xy 424.748706 -260.824472) (xy 424.754018 -260.824923) (xy 424.761591 -260.832376) (xy 424.762168 -260.83768)
			(xy 424.762168 -261.332218) (xy 424.762144 -261.332472) (xy 430.806352 -261.332472) (xy 430.806352 -261.331964)
			(xy 430.806352 -260.83768) (xy 430.806877 -260.832424) (xy 430.814305 -260.824985) (xy 430.81956 -260.824472)
			(xy 431.335688 -260.824472) (xy 431.343498 -260.824158) (xy 431.35837 -260.819373) (xy 431.364898 -260.815074)
			(xy 431.385987 -260.800725) (xy 431.431648 -260.777994) (xy 431.480254 -260.762535) (xy 431.530657 -260.754712)
			(xy 431.581663 -260.754712) (xy 431.632066 -260.762535) (xy 431.680672 -260.777994) (xy 431.726333 -260.800725)
			(xy 431.747422 -260.815074) (xy 431.753951 -260.81937) (xy 431.768823 -260.82415) (xy 431.776632 -260.824472)
			(xy 432.29276 -260.824472) (xy 432.298082 -260.824852) (xy 432.305624 -260.83236) (xy 432.305968 -260.83768)
			(xy 432.305968 -261.332218) (xy 438.350152 -261.332218) (xy 438.350152 -260.83768) (xy 438.350677 -260.832424)
			(xy 438.358105 -260.824985) (xy 438.36336 -260.824472) (xy 438.363868 -260.824472) (xy 438.879742 -260.824472)
			(xy 438.88755 -260.824138) (xy 438.902422 -260.819366) (xy 438.908952 -260.815074) (xy 438.930041 -260.800725)
			(xy 438.975702 -260.777994) (xy 439.024308 -260.762535) (xy 439.074711 -260.754712) (xy 439.125717 -260.754712)
			(xy 439.17612 -260.762535) (xy 439.224726 -260.777994) (xy 439.270387 -260.800725) (xy 439.291476 -260.815074)
			(xy 439.298015 -260.819352) (xy 439.312879 -260.824144) (xy 439.320686 -260.824472) (xy 439.836814 -260.824472)
			(xy 439.842127 -260.824918) (xy 439.849699 -260.832375) (xy 439.850276 -260.83768) (xy 439.850276 -261.332218)
			(xy 439.850252 -261.332472) (xy 445.89446 -261.332472) (xy 445.89446 -261.331964) (xy 445.89446 -260.83768)
			(xy 445.894978 -260.832423) (xy 445.902411 -260.824983) (xy 445.907668 -260.824472) (xy 446.423796 -260.824472)
			(xy 446.431606 -260.824161) (xy 446.446478 -260.819374) (xy 446.453006 -260.815074) (xy 446.474095 -260.800725)
			(xy 446.519756 -260.777994) (xy 446.568362 -260.762535) (xy 446.618765 -260.754712) (xy 446.669771 -260.754712)
			(xy 446.720174 -260.762535) (xy 446.76878 -260.777994) (xy 446.814441 -260.800725) (xy 446.83553 -260.815074)
			(xy 446.842057 -260.819373) (xy 446.85693 -260.824151) (xy 446.86474 -260.824472) (xy 447.380868 -260.824472)
			(xy 447.386191 -260.824846) (xy 447.393733 -260.832358) (xy 447.394076 -260.83768) (xy 447.394076 -261.332218)
			(xy 447.394053 -261.332472) (xy 453.43826 -261.332472) (xy 453.43826 -261.331964) (xy 453.43826 -260.83768)
			(xy 453.438778 -260.832423) (xy 453.446211 -260.824983) (xy 453.451468 -260.824472) (xy 453.967596 -260.824472)
			(xy 453.975406 -260.824161) (xy 453.990278 -260.819374) (xy 453.996806 -260.815074) (xy 454.017895 -260.800725)
			(xy 454.063556 -260.777994) (xy 454.112162 -260.762535) (xy 454.162565 -260.754712) (xy 454.213571 -260.754712)
			(xy 454.263974 -260.762535) (xy 454.31258 -260.777994) (xy 454.358241 -260.800725) (xy 454.37933 -260.815074)
			(xy 454.385857 -260.819373) (xy 454.40073 -260.824151) (xy 454.40854 -260.824472) (xy 454.924668 -260.824472)
			(xy 454.929991 -260.824846) (xy 454.937533 -260.832358) (xy 454.937876 -260.83768) (xy 454.937876 -261.332218)
			(xy 454.937391 -261.337521) (xy 454.929961 -261.34509) (xy 454.924668 -261.34568) (xy 454.408794 -261.34568)
			(xy 454.400982 -261.345978) (xy 454.38611 -261.350773) (xy 454.379584 -261.355078) (xy 454.358466 -261.369433)
			(xy 454.312741 -261.392158) (xy 454.264066 -261.407586) (xy 454.213599 -261.415351) (xy 454.188068 -261.415784)
			(xy 454.162537 -261.41536) (xy 454.112073 -261.40758) (xy 454.063401 -261.392147) (xy 454.017674 -261.369427)
			(xy 453.996552 -261.355078) (xy 453.990026 -261.350777) (xy 453.975152 -261.345999) (xy 453.967342 -261.34568)
			(xy 453.451468 -261.34568) (xy 453.446195 -261.345224) (xy 453.438752 -261.337748) (xy 453.43826 -261.332472)
			(xy 447.394053 -261.332472) (xy 447.393591 -261.337521) (xy 447.386161 -261.34509) (xy 447.380868 -261.34568)
			(xy 446.864994 -261.34568) (xy 446.857182 -261.345978) (xy 446.84231 -261.350773) (xy 446.835784 -261.355078)
			(xy 446.814666 -261.369433) (xy 446.768941 -261.392158) (xy 446.720266 -261.407586) (xy 446.669799 -261.415351)
			(xy 446.644268 -261.415784) (xy 446.618737 -261.41536) (xy 446.568273 -261.40758) (xy 446.519601 -261.392147)
			(xy 446.473874 -261.369427) (xy 446.452752 -261.355078) (xy 446.446226 -261.350777) (xy 446.431352 -261.345999)
			(xy 446.423542 -261.34568) (xy 445.907668 -261.34568) (xy 445.902395 -261.345224) (xy 445.894952 -261.337748)
			(xy 445.89446 -261.332472) (xy 439.850252 -261.332472) (xy 439.849763 -261.337581) (xy 439.842177 -261.345165)
			(xy 439.836814 -261.34568) (xy 439.32094 -261.34568) (xy 439.31313 -261.345997) (xy 439.298258 -261.350779)
			(xy 439.29173 -261.355078) (xy 439.270627 -261.369457) (xy 439.224897 -261.392176) (xy 439.176217 -261.407598)
			(xy 439.125747 -261.415355) (xy 439.100214 -261.415784) (xy 439.074684 -261.415337) (xy 439.024221 -261.407564)
			(xy 438.975549 -261.392137) (xy 438.92982 -261.369424) (xy 438.908698 -261.355078) (xy 438.902162 -261.350795)
			(xy 438.887296 -261.346005) (xy 438.879488 -261.34568) (xy 438.363614 -261.34568) (xy 438.358256 -261.345142)
			(xy 438.350671 -261.337575) (xy 438.350152 -261.332218) (xy 432.305968 -261.332218) (xy 432.30549 -261.337523)
			(xy 432.298055 -261.345092) (xy 432.29276 -261.34568) (xy 431.776886 -261.34568) (xy 431.769074 -261.345974)
			(xy 431.754202 -261.350772) (xy 431.747676 -261.355078) (xy 431.726561 -261.369437) (xy 431.680834 -261.392161)
			(xy 431.632159 -261.407588) (xy 431.581691 -261.415352) (xy 431.55616 -261.415784) (xy 431.530629 -261.415364)
			(xy 431.480165 -261.407583) (xy 431.431492 -261.392148) (xy 431.385766 -261.369427) (xy 431.364644 -261.355078)
			(xy 431.35812 -261.350774) (xy 431.343244 -261.345997) (xy 431.335434 -261.34568) (xy 430.81956 -261.34568)
			(xy 430.814286 -261.345229) (xy 430.806844 -261.337749) (xy 430.806352 -261.332472) (xy 424.762144 -261.332472)
			(xy 424.761662 -261.337583) (xy 424.754071 -261.345167) (xy 424.748706 -261.34568) (xy 424.232832 -261.34568)
			(xy 424.225022 -261.345994) (xy 424.21015 -261.350778) (xy 424.203622 -261.355078) (xy 424.182494 -261.369417)
			(xy 424.136772 -261.392145) (xy 424.088101 -261.407578) (xy 424.037636 -261.415349) (xy 424.012106 -261.415784)
			(xy 423.986576 -261.415341) (xy 423.936113 -261.407566) (xy 423.88744 -261.392139) (xy 423.841712 -261.369424)
			(xy 423.82059 -261.355078) (xy 423.814055 -261.350792) (xy 423.799188 -261.346004) (xy 423.79138 -261.34568)
			(xy 423.275506 -261.34568) (xy 423.270147 -261.345148) (xy 423.262562 -261.337576) (xy 423.262044 -261.332218)
			(xy 417.21786 -261.332218) (xy 417.217389 -261.337524) (xy 417.209949 -261.345095) (xy 417.204652 -261.34568)
			(xy 415.731452 -261.34568) (xy 415.726177 -261.345234) (xy 415.718735 -261.33775) (xy 415.718244 -261.332472)
			(xy 402.525821 -261.332472) (xy 402.428184 -261.353515) (xy 402.287514 -261.375591) (xy 402.14582 -261.389673)
			(xy 402.003556 -261.395716) (xy 401.861178 -261.393701) (xy 401.719142 -261.383634) (xy 401.577903 -261.365548)
			(xy 401.437913 -261.3395) (xy 401.299622 -261.305574) (xy 401.163471 -261.263878) (xy 401.029897 -261.214546)
			(xy 400.899328 -261.157737) (xy 400.772182 -261.093631) (xy 400.648867 -261.022435) (xy 400.529777 -260.944377)
			(xy 400.415294 -260.859705) (xy 400.305785 -260.768693) (xy 400.2016 -260.671631) (xy 400.103073 -260.56883)
			(xy 400.01052 -260.460619) (xy 399.924238 -260.347346) (xy 399.844501 -260.229373) (xy 399.771567 -260.107077)
			(xy 399.705669 -259.980851) (xy 399.647018 -259.851099) (xy 399.595801 -259.718237) (xy 399.552183 -259.58269)
			(xy 399.516303 -259.444892) (xy 399.488276 -259.305285) (xy 399.468193 -259.164317) (xy 399.456118 -259.022437)
			(xy 399.452088 -258.880102) (xy 320.283332 -258.880102) (xy 320.282828 -258.951298) (xy 320.274773 -259.093462)
			(xy 320.258687 -259.234943) (xy 320.234622 -259.375287) (xy 320.202656 -259.514045) (xy 320.162892 -259.650772)
			(xy 320.115455 -259.785031) (xy 320.060499 -259.91639) (xy 319.998199 -260.044431) (xy 319.928755 -260.168741)
			(xy 319.852389 -260.288924) (xy 319.769347 -260.404593) (xy 319.679893 -260.515379) (xy 319.584315 -260.620927)
			(xy 319.482918 -260.720899) (xy 319.376028 -260.814974) (xy 319.263987 -260.902851) (xy 319.147154 -260.984249)
			(xy 319.025903 -261.058906) (xy 318.900622 -261.126584) (xy 318.771713 -261.187066) (xy 318.639589 -261.240157)
			(xy 318.504673 -261.285689) (xy 318.367397 -261.323515) (xy 318.2282 -261.353515) (xy 318.08753 -261.375591)
			(xy 317.945836 -261.389673) (xy 317.803572 -261.395716) (xy 317.661194 -261.393701) (xy 317.519158 -261.383634)
			(xy 317.377919 -261.365548) (xy 317.237929 -261.3395) (xy 317.099638 -261.305574) (xy 316.963487 -261.263878)
			(xy 316.829913 -261.214546) (xy 316.699344 -261.157737) (xy 316.572198 -261.093631) (xy 316.448883 -261.022435)
			(xy 316.329793 -260.944377) (xy 316.21531 -260.859705) (xy 316.105801 -260.768693) (xy 316.001616 -260.671631)
			(xy 315.903089 -260.56883) (xy 315.810536 -260.460619) (xy 315.724254 -260.347346) (xy 315.644517 -260.229373)
			(xy 315.571583 -260.107077) (xy 315.505685 -259.980851) (xy 315.447034 -259.851099) (xy 315.395817 -259.718237)
			(xy 315.352199 -259.58269) (xy 315.316319 -259.444892) (xy 315.288292 -259.305285) (xy 315.268209 -259.164317)
			(xy 315.256134 -259.022437) (xy 315.252104 -258.880102) (xy 156.543246 -258.880102) (xy 156.543248 -258.880356)
			(xy 156.542744 -258.951552) (xy 156.534689 -259.093716) (xy 156.518603 -259.235197) (xy 156.494538 -259.375541)
			(xy 156.462572 -259.514299) (xy 156.422808 -259.651026) (xy 156.375371 -259.785285) (xy 156.320415 -259.916644)
			(xy 156.258115 -260.044685) (xy 156.188671 -260.168995) (xy 156.112305 -260.289178) (xy 156.029263 -260.404847)
			(xy 155.939809 -260.515633) (xy 155.844231 -260.621181) (xy 155.742834 -260.721153) (xy 155.635944 -260.815228)
			(xy 155.523903 -260.903105) (xy 155.40707 -260.984503) (xy 155.285819 -261.05916) (xy 155.160538 -261.126838)
			(xy 155.031629 -261.18732) (xy 154.899505 -261.240411) (xy 154.764589 -261.285943) (xy 154.627313 -261.323769)
			(xy 154.586932 -261.332472) (xy 167.778176 -261.332472) (xy 167.778176 -260.837934) (xy 167.77865 -260.832626)
			(xy 167.786085 -260.825051) (xy 167.791384 -260.824472) (xy 169.264584 -260.824472) (xy 169.26984 -260.825003)
			(xy 169.277282 -260.832425) (xy 169.277792 -260.83768) (xy 169.277792 -261.332472) (xy 175.321976 -261.332472)
			(xy 175.321976 -260.837934) (xy 175.322306 -260.832494) (xy 175.329998 -260.824804) (xy 175.335438 -260.824472)
			(xy 175.851566 -260.824472) (xy 175.859375 -260.824148) (xy 175.874247 -260.81937) (xy 175.880776 -260.815074)
			(xy 175.901865 -260.800725) (xy 175.947526 -260.777994) (xy 175.996132 -260.762535) (xy 176.046535 -260.754712)
			(xy 176.097541 -260.754712) (xy 176.147944 -260.762535) (xy 176.19655 -260.777994) (xy 176.242211 -260.800725)
			(xy 176.2633 -260.815074) (xy 176.269834 -260.819361) (xy 176.284702 -260.824147) (xy 176.29251 -260.824472)
			(xy 176.808638 -260.824472) (xy 176.814015 -260.824929) (xy 176.8216 -260.832555) (xy 176.8221 -260.837934)
			(xy 176.8221 -261.332472) (xy 182.866284 -261.332472) (xy 182.866284 -260.837934) (xy 182.866751 -260.832624)
			(xy 182.874191 -260.825048) (xy 182.879492 -260.824472) (xy 183.39562 -260.824472) (xy 183.403431 -260.824172)
			(xy 183.418303 -260.819377) (xy 183.42483 -260.815074) (xy 183.445919 -260.800725) (xy 183.49158 -260.777994)
			(xy 183.540186 -260.762535) (xy 183.590589 -260.754712) (xy 183.641595 -260.754712) (xy 183.691998 -260.762535)
			(xy 183.740604 -260.777994) (xy 183.786265 -260.800725) (xy 183.807354 -260.815074) (xy 183.813876 -260.819382)
			(xy 183.828753 -260.824155) (xy 183.836564 -260.824472) (xy 184.352692 -260.824472) (xy 184.357949 -260.824998)
			(xy 184.365391 -260.832424) (xy 184.3659 -260.83768) (xy 184.3659 -260.838188) (xy 184.3659 -261.332472)
			(xy 190.410084 -261.332472) (xy 190.410084 -260.837934) (xy 190.410407 -260.832493) (xy 190.418104 -260.824802)
			(xy 190.423546 -260.824472) (xy 190.939674 -260.824472) (xy 190.947484 -260.824152) (xy 190.962355 -260.819371)
			(xy 190.968884 -260.815074) (xy 190.989973 -260.800725) (xy 191.035634 -260.777994) (xy 191.08424 -260.762535)
			(xy 191.134643 -260.754712) (xy 191.185649 -260.754712) (xy 191.236052 -260.762535) (xy 191.284658 -260.777994)
			(xy 191.330319 -260.800725) (xy 191.351408 -260.815074) (xy 191.35794 -260.819364) (xy 191.37281 -260.824148)
			(xy 191.380618 -260.824472) (xy 191.896746 -260.824472) (xy 191.902124 -260.824923) (xy 191.909709 -260.832553)
			(xy 191.910208 -260.837934) (xy 191.910208 -261.332472) (xy 197.954392 -261.332472) (xy 197.954392 -260.837934)
			(xy 197.95494 -260.832645) (xy 197.962324 -260.825075) (xy 197.9676 -260.824472) (xy 198.483728 -260.824472)
			(xy 198.49154 -260.824175) (xy 198.506411 -260.819378) (xy 198.512938 -260.815074) (xy 198.534027 -260.800725)
			(xy 198.579688 -260.777994) (xy 198.628294 -260.762535) (xy 198.678697 -260.754712) (xy 198.729703 -260.754712)
			(xy 198.780106 -260.762535) (xy 198.828712 -260.777994) (xy 198.874373 -260.800725) (xy 198.895462 -260.815074)
			(xy 198.902004 -260.819347) (xy 198.916866 -260.824141) (xy 198.924672 -260.824472) (xy 199.4408 -260.824472)
			(xy 199.446058 -260.824993) (xy 199.453499 -260.832423) (xy 199.454008 -260.83768) (xy 199.454008 -260.838188)
			(xy 199.454008 -261.332472) (xy 205.498192 -261.332472) (xy 205.498192 -260.837934) (xy 205.49874 -260.832645)
			(xy 205.506124 -260.825075) (xy 205.5114 -260.824472) (xy 206.027528 -260.824472) (xy 206.03534 -260.824175)
			(xy 206.050211 -260.819378) (xy 206.056738 -260.815074) (xy 206.077827 -260.800725) (xy 206.123488 -260.777994)
			(xy 206.172094 -260.762535) (xy 206.222497 -260.754712) (xy 206.273503 -260.754712) (xy 206.323906 -260.762535)
			(xy 206.372512 -260.777994) (xy 206.418173 -260.800725) (xy 206.439262 -260.815074) (xy 206.445804 -260.819347)
			(xy 206.460666 -260.824141) (xy 206.468472 -260.824472) (xy 206.9846 -260.824472) (xy 206.989858 -260.824993)
			(xy 206.997299 -260.832423) (xy 206.997808 -260.83768) (xy 206.997808 -260.838188) (xy 206.997808 -261.332218)
			(xy 268.898116 -261.332218) (xy 268.898116 -260.83768) (xy 268.898416 -260.832339) (xy 268.905982 -260.824798)
			(xy 268.911324 -260.824472) (xy 268.911832 -260.824472) (xy 269.427706 -260.824472) (xy 269.435517 -260.824166)
			(xy 269.450388 -260.819375) (xy 269.456916 -260.815074) (xy 269.478005 -260.800725) (xy 269.523666 -260.777994)
			(xy 269.572272 -260.762535) (xy 269.622675 -260.754712) (xy 269.673681 -260.754712) (xy 269.724084 -260.762535)
			(xy 269.77269 -260.777994) (xy 269.818351 -260.800725) (xy 269.83944 -260.815074) (xy 269.845965 -260.819377)
			(xy 269.86084 -260.824153) (xy 269.86865 -260.824472) (xy 270.384778 -260.824472) (xy 270.390087 -260.824942)
			(xy 270.397661 -260.832381) (xy 270.39824 -260.83768) (xy 270.39824 -261.332218) (xy 270.398226 -261.332472)
			(xy 276.442424 -261.332472) (xy 276.442424 -261.331964) (xy 276.442424 -260.83768) (xy 276.442717 -260.832337)
			(xy 276.450288 -260.824796) (xy 276.455632 -260.824472) (xy 276.97176 -260.824472) (xy 276.979569 -260.824146)
			(xy 276.994441 -260.819369) (xy 277.00097 -260.815074) (xy 277.022059 -260.800725) (xy 277.06772 -260.777994)
			(xy 277.116326 -260.762535) (xy 277.166729 -260.754712) (xy 277.217735 -260.754712) (xy 277.268138 -260.762535)
			(xy 277.316744 -260.777994) (xy 277.362405 -260.800725) (xy 277.383494 -260.815074) (xy 277.390029 -260.819359)
			(xy 277.404896 -260.824146) (xy 277.412704 -260.824472) (xy 277.928832 -260.824472) (xy 277.934094 -260.824971)
			(xy 277.941533 -260.832418) (xy 277.94204 -260.83768) (xy 277.94204 -261.332218) (xy 277.942018 -261.332472)
			(xy 283.986224 -261.332472) (xy 283.986224 -261.331964) (xy 283.986224 -260.83768) (xy 283.986517 -260.832337)
			(xy 283.994088 -260.824796) (xy 283.999432 -260.824472) (xy 284.51556 -260.824472) (xy 284.523369 -260.824146)
			(xy 284.538241 -260.819369) (xy 284.54477 -260.815074) (xy 284.565859 -260.800725) (xy 284.61152 -260.777994)
			(xy 284.660126 -260.762535) (xy 284.710529 -260.754712) (xy 284.761535 -260.754712) (xy 284.811938 -260.762535)
			(xy 284.860544 -260.777994) (xy 284.906205 -260.800725) (xy 284.927294 -260.815074) (xy 284.933829 -260.819359)
			(xy 284.948696 -260.824146) (xy 284.956504 -260.824472) (xy 285.472632 -260.824472) (xy 285.477894 -260.824971)
			(xy 285.485333 -260.832418) (xy 285.48584 -260.83768) (xy 285.48584 -261.332218) (xy 291.530024 -261.332218)
			(xy 291.530024 -260.83768) (xy 291.530317 -260.832337) (xy 291.537888 -260.824796) (xy 291.543232 -260.824472)
			(xy 291.54374 -260.824472) (xy 292.059614 -260.824472) (xy 292.067425 -260.824169) (xy 292.082297 -260.819376)
			(xy 292.088824 -260.815074) (xy 292.109913 -260.800725) (xy 292.155574 -260.777994) (xy 292.20418 -260.762535)
			(xy 292.254583 -260.754712) (xy 292.305589 -260.754712) (xy 292.355992 -260.762535) (xy 292.404598 -260.777994)
			(xy 292.450259 -260.800725) (xy 292.471348 -260.815074) (xy 292.477871 -260.81938) (xy 292.492748 -260.824154)
			(xy 292.500558 -260.824472) (xy 293.016686 -260.824472) (xy 293.021996 -260.824936) (xy 293.02957 -260.832379)
			(xy 293.030148 -260.83768) (xy 293.030148 -261.332218) (xy 293.030125 -261.332472) (xy 299.074332 -261.332472)
			(xy 299.074332 -261.331964) (xy 299.074332 -260.83768) (xy 299.074617 -260.832335) (xy 299.082194 -260.824793)
			(xy 299.08754 -260.824472) (xy 299.603668 -260.824472) (xy 299.611477 -260.824149) (xy 299.626349 -260.81937)
			(xy 299.632878 -260.815074) (xy 299.653967 -260.800725) (xy 299.699628 -260.777994) (xy 299.748234 -260.762535)
			(xy 299.798637 -260.754712) (xy 299.849643 -260.754712) (xy 299.900046 -260.762535) (xy 299.948652 -260.777994)
			(xy 299.994313 -260.800725) (xy 300.015402 -260.815074) (xy 300.021935 -260.819362) (xy 300.036804 -260.824147)
			(xy 300.044612 -260.824472) (xy 300.56074 -260.824472) (xy 300.566003 -260.824966) (xy 300.573442 -260.832416)
			(xy 300.573948 -260.83768) (xy 300.573948 -261.332218) (xy 306.618132 -261.332218) (xy 306.618132 -260.83768)
			(xy 306.618417 -260.832335) (xy 306.625994 -260.824793) (xy 306.63134 -260.824472) (xy 306.631848 -260.824472)
			(xy 308.104794 -260.824472) (xy 308.110105 -260.824931) (xy 308.117678 -260.832378) (xy 308.118256 -260.83768)
			(xy 308.118256 -261.332218) (xy 308.117761 -261.337586) (xy 308.110162 -261.345171) (xy 308.104794 -261.34568)
			(xy 306.631594 -261.34568) (xy 306.626234 -261.345156) (xy 306.618649 -261.337578) (xy 306.618132 -261.332218)
			(xy 300.573948 -261.332218) (xy 300.573488 -261.337527) (xy 300.56604 -261.345098) (xy 300.56074 -261.34568)
			(xy 300.044866 -261.34568) (xy 300.037057 -261.346008) (xy 300.022185 -261.350783) (xy 300.015656 -261.355078)
			(xy 299.994546 -261.369446) (xy 299.948818 -261.392167) (xy 299.900141 -261.407592) (xy 299.849672 -261.415353)
			(xy 299.82414 -261.415784) (xy 299.798611 -261.415324) (xy 299.748148 -261.407555) (xy 299.699476 -261.392132)
			(xy 299.653747 -261.369422) (xy 299.632624 -261.355078) (xy 299.626082 -261.350805) (xy 299.61122 -261.346009)
			(xy 299.603414 -261.34568) (xy 299.08754 -261.34568) (xy 299.082206 -261.345343) (xy 299.074661 -261.337805)
			(xy 299.074332 -261.332472) (xy 293.030125 -261.332472) (xy 293.02966 -261.337588) (xy 293.022057 -261.345173)
			(xy 293.016686 -261.34568) (xy 292.500812 -261.34568) (xy 292.493001 -261.345985) (xy 292.478129 -261.350776)
			(xy 292.471602 -261.355078) (xy 292.450479 -261.369426) (xy 292.404756 -261.392152) (xy 292.356083 -261.407582)
			(xy 292.305617 -261.41535) (xy 292.280086 -261.415784) (xy 292.254556 -261.415351) (xy 292.204092 -261.407573)
			(xy 292.155419 -261.392143) (xy 292.109692 -261.369426) (xy 292.08857 -261.355078) (xy 292.08204 -261.350784)
			(xy 292.067169 -261.346001) (xy 292.05936 -261.34568) (xy 291.543486 -261.34568) (xy 291.538125 -261.345161)
			(xy 291.530541 -261.337579) (xy 291.530024 -261.332218) (xy 285.48584 -261.332218) (xy 285.485387 -261.337529)
			(xy 285.477935 -261.3451) (xy 285.472632 -261.34568) (xy 284.956758 -261.34568) (xy 284.948949 -261.346005)
			(xy 284.934077 -261.350782) (xy 284.927548 -261.355078) (xy 284.90644 -261.369449) (xy 284.860711 -261.39217)
			(xy 284.812034 -261.407594) (xy 284.761564 -261.415354) (xy 284.736032 -261.415784) (xy 284.710503 -261.415328)
			(xy 284.66004 -261.407557) (xy 284.611367 -261.392134) (xy 284.565639 -261.369423) (xy 284.544516 -261.355078)
			(xy 284.537976 -261.350802) (xy 284.523113 -261.346008) (xy 284.515306 -261.34568) (xy 283.999432 -261.34568)
			(xy 283.994097 -261.345349) (xy 283.986553 -261.337807) (xy 283.986224 -261.332472) (xy 277.942018 -261.332472)
			(xy 277.941587 -261.337529) (xy 277.934135 -261.3451) (xy 277.928832 -261.34568) (xy 277.412958 -261.34568)
			(xy 277.405149 -261.346005) (xy 277.390277 -261.350782) (xy 277.383748 -261.355078) (xy 277.36264 -261.369449)
			(xy 277.316911 -261.39217) (xy 277.268234 -261.407594) (xy 277.217764 -261.415354) (xy 277.192232 -261.415784)
			(xy 277.166703 -261.415328) (xy 277.11624 -261.407557) (xy 277.067567 -261.392134) (xy 277.021839 -261.369423)
			(xy 277.000716 -261.355078) (xy 276.994176 -261.350802) (xy 276.979313 -261.346008) (xy 276.971506 -261.34568)
			(xy 276.455632 -261.34568) (xy 276.450297 -261.345349) (xy 276.442753 -261.337807) (xy 276.442424 -261.332472)
			(xy 270.398226 -261.332472) (xy 270.397931 -261.337661) (xy 270.390222 -261.345347) (xy 270.384778 -261.34568)
			(xy 269.868904 -261.34568) (xy 269.861093 -261.345982) (xy 269.846221 -261.350775) (xy 269.839694 -261.355078)
			(xy 269.818574 -261.369429) (xy 269.772849 -261.392155) (xy 269.724175 -261.407584) (xy 269.673709 -261.415351)
			(xy 269.648178 -261.415784) (xy 269.622647 -261.415355) (xy 269.572184 -261.407576) (xy 269.523511 -261.392145)
			(xy 269.477784 -261.369426) (xy 269.456662 -261.355078) (xy 269.450134 -261.350781) (xy 269.435261 -261.346)
			(xy 269.427452 -261.34568) (xy 268.911578 -261.34568) (xy 268.906216 -261.345166) (xy 268.898632 -261.33758)
			(xy 268.898116 -261.332218) (xy 206.997808 -261.332218) (xy 206.997808 -261.332472) (xy 206.997455 -261.337801)
			(xy 206.989928 -261.345343) (xy 206.9846 -261.34568) (xy 206.468726 -261.34568) (xy 206.460849 -261.345939)
			(xy 206.445845 -261.350742) (xy 206.439262 -261.355078) (xy 206.418188 -261.369475) (xy 206.372542 -261.392301)
			(xy 206.323935 -261.407857) (xy 206.273517 -261.415775) (xy 206.248 -261.416292) (xy 206.222479 -261.415821)
			(xy 206.172051 -261.407921) (xy 206.12344 -261.392356) (xy 206.077802 -261.369496) (xy 206.056738 -261.355078)
			(xy 206.050135 -261.350782) (xy 206.035144 -261.345982) (xy 206.027274 -261.34568) (xy 205.5114 -261.34568)
			(xy 205.506061 -261.345371) (xy 205.498518 -261.337812) (xy 205.498192 -261.332472) (xy 199.454008 -261.332472)
			(xy 199.453655 -261.337801) (xy 199.446128 -261.345343) (xy 199.4408 -261.34568) (xy 198.924926 -261.34568)
			(xy 198.917049 -261.345939) (xy 198.902045 -261.350742) (xy 198.895462 -261.355078) (xy 198.874388 -261.369475)
			(xy 198.828742 -261.392301) (xy 198.780135 -261.407857) (xy 198.729717 -261.415775) (xy 198.7042 -261.416292)
			(xy 198.678679 -261.415821) (xy 198.628251 -261.407921) (xy 198.57964 -261.392356) (xy 198.534002 -261.369496)
			(xy 198.512938 -261.355078) (xy 198.506335 -261.350782) (xy 198.491344 -261.345982) (xy 198.483474 -261.34568)
			(xy 197.9676 -261.34568) (xy 197.962261 -261.345371) (xy 197.954718 -261.337812) (xy 197.954392 -261.332472)
			(xy 191.910208 -261.332472) (xy 191.909855 -261.337801) (xy 191.902328 -261.345343) (xy 191.897 -261.34568)
			(xy 191.896492 -261.34568) (xy 191.380872 -261.34568) (xy 191.372997 -261.345958) (xy 191.357992 -261.350748)
			(xy 191.351408 -261.355078) (xy 191.330349 -261.369498) (xy 191.284697 -261.392319) (xy 191.236086 -261.407869)
			(xy 191.185664 -261.415779) (xy 191.160146 -261.416292) (xy 191.134626 -261.415798) (xy 191.084199 -261.407905)
			(xy 191.035588 -261.392346) (xy 190.989949 -261.369493) (xy 190.968884 -261.355078) (xy 190.962293 -261.350761)
			(xy 190.947293 -261.345974) (xy 190.93942 -261.34568) (xy 190.423546 -261.34568) (xy 190.418252 -261.345149)
			(xy 190.410679 -261.337753) (xy 190.410084 -261.332472) (xy 184.3659 -261.332472) (xy 184.365554 -261.337803)
			(xy 184.358022 -261.345346) (xy 184.352692 -261.34568) (xy 183.836818 -261.34568) (xy 183.828944 -261.345978)
			(xy 183.81394 -261.350754) (xy 183.807354 -261.355078) (xy 183.786282 -261.369478) (xy 183.740635 -261.392304)
			(xy 183.692027 -261.407859) (xy 183.641609 -261.415776) (xy 183.616092 -261.416292) (xy 183.590573 -261.415775)
			(xy 183.540147 -261.407889) (xy 183.491535 -261.392337) (xy 183.445896 -261.36949) (xy 183.42483 -261.355078)
			(xy 183.418229 -261.350779) (xy 183.403236 -261.345981) (xy 183.395366 -261.34568) (xy 182.879492 -261.34568)
			(xy 182.874152 -261.345376) (xy 182.86661 -261.337813) (xy 182.866284 -261.332472) (xy 176.8221 -261.332472)
			(xy 176.821754 -261.337803) (xy 176.814222 -261.345346) (xy 176.808892 -261.34568) (xy 176.808384 -261.34568)
			(xy 176.292764 -261.34568) (xy 176.284888 -261.345955) (xy 176.269884 -261.350747) (xy 176.2633 -261.355078)
			(xy 176.242215 -261.369458) (xy 176.196573 -261.392288) (xy 176.147969 -261.407849) (xy 176.097554 -261.415772)
			(xy 176.072038 -261.416292) (xy 176.046518 -261.415802) (xy 175.996091 -261.407908) (xy 175.947479 -261.392348)
			(xy 175.901841 -261.369493) (xy 175.880776 -261.355078) (xy 175.874187 -261.350758) (xy 175.859185 -261.345973)
			(xy 175.851312 -261.34568) (xy 175.335438 -261.34568) (xy 175.330143 -261.345154) (xy 175.322571 -261.337754)
			(xy 175.321976 -261.332472) (xy 169.277792 -261.332472) (xy 169.277453 -261.337804) (xy 169.269916 -261.345348)
			(xy 169.264584 -261.34568) (xy 167.791384 -261.34568) (xy 167.786043 -261.345381) (xy 167.778501 -261.337814)
			(xy 167.778176 -261.332472) (xy 154.586932 -261.332472) (xy 154.488116 -261.353769) (xy 154.347446 -261.375845)
			(xy 154.205752 -261.389927) (xy 154.063488 -261.39597) (xy 153.92111 -261.393955) (xy 153.779074 -261.383888)
			(xy 153.637835 -261.365802) (xy 153.497845 -261.339754) (xy 153.359554 -261.305828) (xy 153.223403 -261.264132)
			(xy 153.089829 -261.2148) (xy 152.95926 -261.157991) (xy 152.832114 -261.093885) (xy 152.708799 -261.022689)
			(xy 152.589709 -260.944631) (xy 152.475226 -260.859959) (xy 152.365717 -260.768947) (xy 152.261532 -260.671885)
			(xy 152.163005 -260.569084) (xy 152.070452 -260.460873) (xy 151.98417 -260.3476) (xy 151.904433 -260.229627)
			(xy 151.831499 -260.107331) (xy 151.765601 -259.981105) (xy 151.70695 -259.851353) (xy 151.655733 -259.718491)
			(xy 151.612115 -259.582944) (xy 151.576235 -259.445146) (xy 151.548208 -259.305539) (xy 151.528125 -259.164571)
			(xy 151.51605 -259.022691) (xy 151.51202 -258.880356) (xy 72.343264 -258.880356) (xy 72.34276 -258.951552)
			(xy 72.334705 -259.093716) (xy 72.318619 -259.235197) (xy 72.294554 -259.375541) (xy 72.262588 -259.514299)
			(xy 72.222824 -259.651026) (xy 72.175387 -259.785285) (xy 72.120431 -259.916644) (xy 72.058131 -260.044685)
			(xy 71.988687 -260.168995) (xy 71.912321 -260.289178) (xy 71.829279 -260.404847) (xy 71.739825 -260.515633)
			(xy 71.644247 -260.621181) (xy 71.54285 -260.721153) (xy 71.43596 -260.815228) (xy 71.323919 -260.903105)
			(xy 71.207086 -260.984503) (xy 71.085835 -261.05916) (xy 70.960554 -261.126838) (xy 70.831645 -261.18732)
			(xy 70.699521 -261.240411) (xy 70.564605 -261.285943) (xy 70.427329 -261.323769) (xy 70.288132 -261.353769)
			(xy 70.147462 -261.375845) (xy 70.005768 -261.389927) (xy 69.863504 -261.39597) (xy 69.721126 -261.393955)
			(xy 69.57909 -261.383888) (xy 69.437851 -261.365802) (xy 69.297861 -261.339754) (xy 69.15957 -261.305828)
			(xy 69.023419 -261.264132) (xy 68.889845 -261.2148) (xy 68.759276 -261.157991) (xy 68.63213 -261.093885)
			(xy 68.508815 -261.022689) (xy 68.389725 -260.944631) (xy 68.275242 -260.859959) (xy 68.165733 -260.768947)
			(xy 68.061548 -260.671885) (xy 67.963021 -260.569084) (xy 67.870468 -260.460873) (xy 67.784186 -260.3476)
			(xy 67.704449 -260.229627) (xy 67.631515 -260.107331) (xy 67.565617 -259.981105) (xy 67.506966 -259.851353)
			(xy 67.455749 -259.718491) (xy 67.412131 -259.582944) (xy 67.376251 -259.445146) (xy 67.348224 -259.305539)
			(xy 67.328141 -259.164571) (xy 67.316066 -259.022691) (xy 67.312036 -258.880356) (xy 2.509012 -258.880356)
			(xy 2.509012 -261.332472) (xy 20.958048 -261.332472) (xy 20.958048 -260.837934) (xy 20.958403 -260.832501)
			(xy 20.966078 -260.824813) (xy 20.97151 -260.824472) (xy 21.487638 -260.824472) (xy 21.495446 -260.824136)
			(xy 21.510318 -260.819366) (xy 21.516848 -260.815074) (xy 21.537937 -260.800725) (xy 21.583598 -260.777994)
			(xy 21.632204 -260.762535) (xy 21.682607 -260.754712) (xy 21.733613 -260.754712) (xy 21.784016 -260.762535)
			(xy 21.832622 -260.777994) (xy 21.878283 -260.800725) (xy 21.899372 -260.815074) (xy 21.905912 -260.819351)
			(xy 21.920775 -260.824143) (xy 21.928582 -260.824472) (xy 22.44471 -260.824472) (xy 22.450155 -260.824776)
			(xy 22.457842 -260.832488) (xy 22.458172 -260.837934) (xy 22.458172 -261.332472) (xy 28.502356 -261.332472)
			(xy 28.502356 -260.837934) (xy 28.502847 -260.83263) (xy 28.510271 -260.825056) (xy 28.515564 -260.824472)
			(xy 29.031692 -260.824472) (xy 29.039502 -260.82416) (xy 29.054374 -260.819373) (xy 29.060902 -260.815074)
			(xy 29.081991 -260.800725) (xy 29.127652 -260.777994) (xy 29.176258 -260.762535) (xy 29.226661 -260.754712)
			(xy 29.277667 -260.754712) (xy 29.32807 -260.762535) (xy 29.376676 -260.777994) (xy 29.422337 -260.800725)
			(xy 29.443426 -260.815074) (xy 29.449954 -260.819371) (xy 29.464827 -260.824151) (xy 29.472636 -260.824472)
			(xy 29.988764 -260.824472) (xy 29.994087 -260.824849) (xy 30.001629 -260.832359) (xy 30.001972 -260.83768)
			(xy 30.001972 -260.838188) (xy 30.001972 -261.332472) (xy 36.046156 -261.332472) (xy 36.046156 -260.837934)
			(xy 36.046647 -260.83263) (xy 36.054071 -260.825056) (xy 36.059364 -260.824472) (xy 36.575492 -260.824472)
			(xy 36.583302 -260.82416) (xy 36.598174 -260.819373) (xy 36.604702 -260.815074) (xy 36.625791 -260.800725)
			(xy 36.671452 -260.777994) (xy 36.720058 -260.762535) (xy 36.770461 -260.754712) (xy 36.821467 -260.754712)
			(xy 36.87187 -260.762535) (xy 36.920476 -260.777994) (xy 36.966137 -260.800725) (xy 36.987226 -260.815074)
			(xy 36.993754 -260.819371) (xy 37.008627 -260.824151) (xy 37.016436 -260.824472) (xy 37.532564 -260.824472)
			(xy 37.537887 -260.824849) (xy 37.545429 -260.832359) (xy 37.545772 -260.83768) (xy 37.545772 -260.838188)
			(xy 37.545772 -261.332472) (xy 43.589956 -261.332472) (xy 43.589956 -260.837934) (xy 43.590304 -260.832499)
			(xy 43.597984 -260.82481) (xy 43.603418 -260.824472) (xy 44.119546 -260.824472) (xy 44.127354 -260.82414)
			(xy 44.142226 -260.819367) (xy 44.148756 -260.815074) (xy 44.169845 -260.800725) (xy 44.215506 -260.777994)
			(xy 44.264112 -260.762535) (xy 44.314515 -260.754712) (xy 44.365521 -260.754712) (xy 44.415924 -260.762535)
			(xy 44.46453 -260.777994) (xy 44.510191 -260.800725) (xy 44.53128 -260.815074) (xy 44.537818 -260.819354)
			(xy 44.552683 -260.824144) (xy 44.56049 -260.824472) (xy 45.076618 -260.824472) (xy 45.082064 -260.82477)
			(xy 45.089751 -260.832487) (xy 45.09008 -260.837934) (xy 45.09008 -261.332472) (xy 51.134264 -261.332472)
			(xy 51.134264 -260.837934) (xy 51.134749 -260.832628) (xy 51.142177 -260.825054) (xy 51.147472 -260.824472)
			(xy 51.6636 -260.824472) (xy 51.671411 -260.824163) (xy 51.686282 -260.819374) (xy 51.69281 -260.815074)
			(xy 51.713899 -260.800725) (xy 51.75956 -260.777994) (xy 51.808166 -260.762535) (xy 51.858569 -260.754712)
			(xy 51.909575 -260.754712) (xy 51.959978 -260.762535) (xy 52.008584 -260.777994) (xy 52.054245 -260.800725)
			(xy 52.075334 -260.815074) (xy 52.08186 -260.819374) (xy 52.096734 -260.824152) (xy 52.104544 -260.824472)
			(xy 52.620672 -260.824472) (xy 52.625996 -260.824843) (xy 52.633537 -260.832358) (xy 52.63388 -260.83768)
			(xy 52.63388 -260.838188) (xy 52.63388 -261.332472) (xy 58.678064 -261.332472) (xy 58.678064 -260.837934)
			(xy 58.678405 -260.832497) (xy 58.68609 -260.824808) (xy 58.691526 -260.824472) (xy 60.164726 -260.824472)
			(xy 60.170173 -260.824765) (xy 60.177859 -260.832486) (xy 60.178188 -260.837934) (xy 60.178188 -261.332472)
			(xy 60.177853 -261.337805) (xy 60.170313 -261.345349) (xy 60.16498 -261.34568) (xy 60.164472 -261.34568)
			(xy 58.691526 -261.34568) (xy 58.68623 -261.345162) (xy 58.678658 -261.337756) (xy 58.678064 -261.332472)
			(xy 52.63388 -261.332472) (xy 52.633552 -261.337807) (xy 52.626007 -261.345352) (xy 52.620672 -261.34568)
			(xy 52.104798 -261.34568) (xy 52.096924 -261.345969) (xy 52.081919 -261.350751) (xy 52.075334 -261.355078)
			(xy 52.054268 -261.369487) (xy 52.008619 -261.39231) (xy 51.960009 -261.407863) (xy 51.90959 -261.415777)
			(xy 51.884072 -261.416292) (xy 51.858553 -261.415785) (xy 51.808126 -261.407896) (xy 51.759515 -261.392341)
			(xy 51.713875 -261.369491) (xy 51.69281 -261.355078) (xy 51.686213 -261.350771) (xy 51.671217 -261.345978)
			(xy 51.663346 -261.34568) (xy 51.147472 -261.34568) (xy 51.142199 -261.345221) (xy 51.134756 -261.337747)
			(xy 51.134264 -261.332472) (xy 45.09008 -261.332472) (xy 45.089752 -261.337807) (xy 45.082207 -261.345352)
			(xy 45.076872 -261.34568) (xy 45.076364 -261.34568) (xy 44.560744 -261.34568) (xy 44.552868 -261.345946)
			(xy 44.537863 -261.350744) (xy 44.53128 -261.355078) (xy 44.510201 -261.369467) (xy 44.464556 -261.392295)
			(xy 44.415951 -261.407853) (xy 44.365534 -261.415774) (xy 44.340018 -261.416292) (xy 44.314497 -261.415812)
			(xy 44.26407 -261.407915) (xy 44.215458 -261.392352) (xy 44.169821 -261.369494) (xy 44.148756 -261.355078)
			(xy 44.142172 -261.350751) (xy 44.127166 -261.34597) (xy 44.119292 -261.34568) (xy 43.603418 -261.34568)
			(xy 43.598121 -261.345167) (xy 43.59055 -261.337758) (xy 43.589956 -261.332472) (xy 37.545772 -261.332472)
			(xy 37.545451 -261.337809) (xy 37.537902 -261.345354) (xy 37.532564 -261.34568) (xy 37.01669 -261.34568)
			(xy 37.008815 -261.345966) (xy 36.993811 -261.35075) (xy 36.987226 -261.355078) (xy 36.966162 -261.36949)
			(xy 36.920512 -261.392313) (xy 36.871902 -261.407865) (xy 36.821482 -261.415778) (xy 36.795964 -261.416292)
			(xy 36.770444 -261.415789) (xy 36.720018 -261.407899) (xy 36.671406 -261.392343) (xy 36.625767 -261.369491)
			(xy 36.604702 -261.355078) (xy 36.598107 -261.350768) (xy 36.58311 -261.345977) (xy 36.575238 -261.34568)
			(xy 36.059364 -261.34568) (xy 36.05409 -261.345226) (xy 36.046648 -261.337748) (xy 36.046156 -261.332472)
			(xy 30.001972 -261.332472) (xy 30.001651 -261.337809) (xy 29.994102 -261.345354) (xy 29.988764 -261.34568)
			(xy 29.47289 -261.34568) (xy 29.465015 -261.345966) (xy 29.450011 -261.35075) (xy 29.443426 -261.355078)
			(xy 29.422362 -261.36949) (xy 29.376712 -261.392313) (xy 29.328102 -261.407865) (xy 29.277682 -261.415778)
			(xy 29.252164 -261.416292) (xy 29.226644 -261.415789) (xy 29.176218 -261.407899) (xy 29.127606 -261.392343)
			(xy 29.081967 -261.369491) (xy 29.060902 -261.355078) (xy 29.054307 -261.350768) (xy 29.03931 -261.345977)
			(xy 29.031438 -261.34568) (xy 28.515564 -261.34568) (xy 28.51029 -261.345226) (xy 28.502848 -261.337748)
			(xy 28.502356 -261.332472) (xy 22.458172 -261.332472) (xy 22.457851 -261.337809) (xy 22.450302 -261.345354)
			(xy 22.444964 -261.34568) (xy 22.444456 -261.34568) (xy 21.928836 -261.34568) (xy 21.920959 -261.345943)
			(xy 21.905955 -261.350743) (xy 21.899372 -261.355078) (xy 21.878295 -261.36947) (xy 21.83265 -261.392298)
			(xy 21.784044 -261.407855) (xy 21.733627 -261.415774) (xy 21.70811 -261.416292) (xy 21.682589 -261.415816)
			(xy 21.632162 -261.407917) (xy 21.58355 -261.392354) (xy 21.537912 -261.369495) (xy 21.516848 -261.355078)
			(xy 21.510265 -261.350747) (xy 21.495259 -261.345969) (xy 21.487384 -261.34568) (xy 20.97151 -261.34568)
			(xy 20.966212 -261.345173) (xy 20.958641 -261.337759) (xy 20.958048 -261.332472) (xy 2.509012 -261.332472)
			(xy 2.509012 -262.182356) (xy 16.85798 -262.182356) (xy 16.85798 -261.687818) (xy 16.858295 -261.682375)
			(xy 16.865999 -261.674686) (xy 16.871442 -261.674356) (xy 17.38757 -261.674356) (xy 17.39538 -261.674037)
			(xy 17.410251 -261.669255) (xy 17.41678 -261.664958) (xy 17.437869 -261.650609) (xy 17.48353 -261.627878)
			(xy 17.532136 -261.612419) (xy 17.582539 -261.604596) (xy 17.633545 -261.604596) (xy 17.683948 -261.612419)
			(xy 17.732554 -261.627878) (xy 17.778215 -261.650609) (xy 17.799304 -261.664958) (xy 17.805838 -261.669245)
			(xy 17.820706 -261.674031) (xy 17.828514 -261.674356) (xy 18.344642 -261.674356) (xy 18.350015 -261.674824)
			(xy 18.3576 -261.682442) (xy 18.358104 -261.687818) (xy 18.358104 -262.182356) (xy 24.402288 -262.182356)
			(xy 24.402288 -261.687818) (xy 24.402741 -261.682505) (xy 24.410191 -261.67493) (xy 24.415496 -261.674356)
			(xy 24.931624 -261.674356) (xy 24.939436 -261.67406) (xy 24.954307 -261.669263) (xy 24.960834 -261.664958)
			(xy 24.981923 -261.650609) (xy 25.027584 -261.627878) (xy 25.07619 -261.612419) (xy 25.126593 -261.604596)
			(xy 25.177599 -261.604596) (xy 25.228002 -261.612419) (xy 25.276608 -261.627878) (xy 25.322269 -261.650609)
			(xy 25.343358 -261.664958) (xy 25.34988 -261.669266) (xy 25.364757 -261.674039) (xy 25.372568 -261.674356)
			(xy 25.888696 -261.674356) (xy 25.89395 -261.674894) (xy 25.90139 -261.682312) (xy 25.901904 -261.687564)
			(xy 25.901904 -261.688072) (xy 25.901904 -262.182356) (xy 31.946088 -262.182356) (xy 31.946088 -261.687818)
			(xy 31.946541 -261.682505) (xy 31.953991 -261.67493) (xy 31.959296 -261.674356) (xy 32.475424 -261.674356)
			(xy 32.483236 -261.67406) (xy 32.498107 -261.669263) (xy 32.504634 -261.664958) (xy 32.525723 -261.650609)
			(xy 32.571384 -261.627878) (xy 32.61999 -261.612419) (xy 32.670393 -261.604596) (xy 32.721399 -261.604596)
			(xy 32.771802 -261.612419) (xy 32.820408 -261.627878) (xy 32.866069 -261.650609) (xy 32.887158 -261.664958)
			(xy 32.89368 -261.669266) (xy 32.908557 -261.674039) (xy 32.916368 -261.674356) (xy 33.432496 -261.674356)
			(xy 33.43775 -261.674894) (xy 33.44519 -261.682312) (xy 33.445704 -261.687564) (xy 33.445704 -261.688072)
			(xy 33.445704 -262.182356) (xy 39.489888 -262.182356) (xy 39.489888 -261.687818) (xy 39.490457 -261.682468)
			(xy 39.498003 -261.674884) (xy 39.50335 -261.674356) (xy 40.019478 -261.674356) (xy 40.027288 -261.67404)
			(xy 40.04216 -261.669256) (xy 40.048688 -261.664958) (xy 40.069777 -261.650609) (xy 40.115438 -261.627878)
			(xy 40.164044 -261.612419) (xy 40.214447 -261.604596) (xy 40.265453 -261.604596) (xy 40.315856 -261.612419)
			(xy 40.364462 -261.627878) (xy 40.410123 -261.650609) (xy 40.431212 -261.664958) (xy 40.437744 -261.669248)
			(xy 40.452614 -261.674033) (xy 40.460422 -261.674356) (xy 40.97655 -261.674356) (xy 40.981924 -261.674819)
			(xy 40.989508 -261.682441) (xy 40.990012 -261.687818) (xy 40.990012 -262.182356) (xy 47.034196 -262.182356)
			(xy 47.034196 -261.687818) (xy 47.03473 -261.682526) (xy 47.042125 -261.674957) (xy 47.047404 -261.674356)
			(xy 47.563532 -261.674356) (xy 47.57134 -261.674021) (xy 47.586212 -261.66925) (xy 47.592742 -261.664958)
			(xy 47.613831 -261.650609) (xy 47.659492 -261.627878) (xy 47.708098 -261.612419) (xy 47.758501 -261.604596)
			(xy 47.809507 -261.604596) (xy 47.85991 -261.612419) (xy 47.908516 -261.627878) (xy 47.954177 -261.650609)
			(xy 47.975266 -261.664958) (xy 47.981808 -261.669231) (xy 47.99667 -261.674026) (xy 48.004476 -261.674356)
			(xy 48.520604 -261.674356) (xy 48.525859 -261.674888) (xy 48.533299 -261.682311) (xy 48.533812 -261.687564)
			(xy 48.533812 -261.688072) (xy 48.533812 -262.182356) (xy 54.577996 -262.182356) (xy 54.577996 -261.687818)
			(xy 54.578558 -261.682466) (xy 54.586109 -261.674882) (xy 54.591458 -261.674356) (xy 56.064658 -261.674356)
			(xy 56.070092 -261.674709) (xy 56.077781 -261.682385) (xy 56.07812 -261.687818) (xy 56.07812 -262.182356)
			(xy 163.678108 -262.182356) (xy 163.678108 -261.687818) (xy 163.678631 -261.682523) (xy 163.686034 -261.674953)
			(xy 163.691316 -261.674356) (xy 165.164516 -261.674356) (xy 165.169772 -261.67488) (xy 165.177212 -261.682309)
			(xy 165.177724 -261.687564) (xy 165.177724 -261.688072) (xy 165.177724 -262.182356) (xy 171.221908 -262.182356)
			(xy 171.221908 -261.687818) (xy 171.222459 -261.682463) (xy 171.230017 -261.674878) (xy 171.23537 -261.674356)
			(xy 171.751498 -261.674356) (xy 171.759309 -261.674049) (xy 171.774181 -261.669259) (xy 171.780708 -261.664958)
			(xy 171.801797 -261.650609) (xy 171.847458 -261.627878) (xy 171.896064 -261.612419) (xy 171.946467 -261.604596)
			(xy 171.997473 -261.604596) (xy 172.047876 -261.612419) (xy 172.096482 -261.627878) (xy 172.142143 -261.650609)
			(xy 172.163232 -261.664958) (xy 172.16976 -261.669256) (xy 172.184633 -261.674036) (xy 172.192442 -261.674356)
			(xy 172.70857 -261.674356) (xy 172.714005 -261.674701) (xy 172.721694 -261.682383) (xy 172.722032 -261.687818)
			(xy 172.722032 -262.182356) (xy 178.766216 -262.182356) (xy 178.766216 -261.687818) (xy 178.766732 -261.682522)
			(xy 178.774139 -261.674951) (xy 178.779424 -261.674356) (xy 179.295552 -261.674356) (xy 179.303361 -261.674029)
			(xy 179.318233 -261.669253) (xy 179.324762 -261.664958) (xy 179.345851 -261.650609) (xy 179.391512 -261.627878)
			(xy 179.440118 -261.612419) (xy 179.490521 -261.604596) (xy 179.541527 -261.604596) (xy 179.59193 -261.612419)
			(xy 179.640536 -261.627878) (xy 179.686197 -261.650609) (xy 179.707286 -261.664958) (xy 179.713824 -261.669238)
			(xy 179.728689 -261.674029) (xy 179.736496 -261.674356) (xy 180.252624 -261.674356) (xy 180.257881 -261.674875)
			(xy 180.26532 -261.682308) (xy 180.265832 -261.687564) (xy 180.265832 -261.688072) (xy 180.265832 -262.182356)
			(xy 186.310016 -262.182356) (xy 186.310016 -261.687818) (xy 186.31056 -261.682461) (xy 186.318123 -261.674876)
			(xy 186.323478 -261.674356) (xy 186.839606 -261.674356) (xy 186.847417 -261.674052) (xy 186.862289 -261.66926)
			(xy 186.868816 -261.664958) (xy 186.889905 -261.650609) (xy 186.935566 -261.627878) (xy 186.984172 -261.612419)
			(xy 187.034575 -261.604596) (xy 187.085581 -261.604596) (xy 187.135984 -261.612419) (xy 187.18459 -261.627878)
			(xy 187.230251 -261.650609) (xy 187.25134 -261.664958) (xy 187.257866 -261.669259) (xy 187.27274 -261.674037)
			(xy 187.28055 -261.674356) (xy 187.796678 -261.674356) (xy 187.802114 -261.674696) (xy 187.809802 -261.682382)
			(xy 187.81014 -261.687818) (xy 187.81014 -262.182356) (xy 193.854324 -262.182356) (xy 193.854324 -261.687818)
			(xy 193.854833 -261.68252) (xy 193.862245 -261.674948) (xy 193.867532 -261.674356) (xy 194.38366 -261.674356)
			(xy 194.391469 -261.674033) (xy 194.406341 -261.669254) (xy 194.41287 -261.664958) (xy 194.433959 -261.650609)
			(xy 194.47962 -261.627878) (xy 194.528226 -261.612419) (xy 194.578629 -261.604596) (xy 194.629635 -261.604596)
			(xy 194.680038 -261.612419) (xy 194.728644 -261.627878) (xy 194.774305 -261.650609) (xy 194.795394 -261.664958)
			(xy 194.80193 -261.669242) (xy 194.816796 -261.67403) (xy 194.824604 -261.674356) (xy 195.340732 -261.674356)
			(xy 195.34599 -261.67487) (xy 195.353429 -261.682306) (xy 195.35394 -261.687564) (xy 195.35394 -261.688072)
			(xy 195.35394 -262.182356) (xy 201.398124 -262.182356) (xy 201.398124 -261.687818) (xy 201.398633 -261.68252)
			(xy 201.406045 -261.674948) (xy 201.411332 -261.674356) (xy 201.92746 -261.674356) (xy 201.935269 -261.674033)
			(xy 201.950141 -261.669254) (xy 201.95667 -261.664958) (xy 201.977759 -261.650609) (xy 202.02342 -261.627878)
			(xy 202.072026 -261.612419) (xy 202.122429 -261.604596) (xy 202.173435 -261.604596) (xy 202.223838 -261.612419)
			(xy 202.272444 -261.627878) (xy 202.318105 -261.650609) (xy 202.339194 -261.664958) (xy 202.34573 -261.669242)
			(xy 202.360596 -261.67403) (xy 202.368404 -261.674356) (xy 202.884532 -261.674356) (xy 202.88979 -261.67487)
			(xy 202.897229 -261.682306) (xy 202.89774 -261.687564) (xy 202.89774 -261.688072) (xy 202.89774 -262.182102)
			(xy 264.798048 -262.182102) (xy 264.798048 -261.687564) (xy 264.798566 -261.682308) (xy 264.806 -261.67487)
			(xy 264.811256 -261.674356) (xy 264.811764 -261.674356) (xy 265.327638 -261.674356) (xy 265.335446 -261.674023)
			(xy 265.350318 -261.669251) (xy 265.356848 -261.664958) (xy 265.377937 -261.650609) (xy 265.423598 -261.627878)
			(xy 265.472204 -261.612419) (xy 265.522607 -261.604596) (xy 265.573613 -261.604596) (xy 265.624016 -261.612419)
			(xy 265.672622 -261.627878) (xy 265.718283 -261.650609) (xy 265.739372 -261.664958) (xy 265.745913 -261.669233)
			(xy 265.760776 -261.674027) (xy 265.768582 -261.674356) (xy 266.28471 -261.674356) (xy 266.290019 -261.674818)
			(xy 266.297591 -261.682264) (xy 266.298172 -261.687564) (xy 266.298172 -262.182102) (xy 266.298147 -262.182356)
			(xy 272.342356 -262.182356) (xy 272.342356 -262.181848) (xy 272.342356 -261.687564) (xy 272.342867 -261.682306)
			(xy 272.350306 -261.674867) (xy 272.355564 -261.674356) (xy 272.871692 -261.674356) (xy 272.879503 -261.674047)
			(xy 272.894374 -261.669259) (xy 272.900902 -261.664958) (xy 272.921991 -261.650609) (xy 272.967652 -261.627878)
			(xy 273.016258 -261.612419) (xy 273.066661 -261.604596) (xy 273.117667 -261.604596) (xy 273.16807 -261.612419)
			(xy 273.216676 -261.627878) (xy 273.262337 -261.650609) (xy 273.283426 -261.664958) (xy 273.289955 -261.669254)
			(xy 273.304827 -261.674035) (xy 273.312636 -261.674356) (xy 273.828764 -261.674356) (xy 273.834014 -261.674915)
			(xy 273.841456 -261.682317) (xy 273.841972 -261.687564) (xy 273.841972 -262.182102) (xy 273.841948 -262.182356)
			(xy 279.886156 -262.182356) (xy 279.886156 -262.181848) (xy 279.886156 -261.687564) (xy 279.886667 -261.682306)
			(xy 279.894106 -261.674867) (xy 279.899364 -261.674356) (xy 280.415492 -261.674356) (xy 280.423303 -261.674047)
			(xy 280.438174 -261.669259) (xy 280.444702 -261.664958) (xy 280.465791 -261.650609) (xy 280.511452 -261.627878)
			(xy 280.560058 -261.612419) (xy 280.610461 -261.604596) (xy 280.661467 -261.604596) (xy 280.71187 -261.612419)
			(xy 280.760476 -261.627878) (xy 280.806137 -261.650609) (xy 280.827226 -261.664958) (xy 280.833755 -261.669254)
			(xy 280.848627 -261.674035) (xy 280.856436 -261.674356) (xy 281.372564 -261.674356) (xy 281.377814 -261.674915)
			(xy 281.385256 -261.682317) (xy 281.385772 -261.687564) (xy 281.385772 -262.182102) (xy 287.429956 -262.182102)
			(xy 287.429956 -261.687564) (xy 287.430467 -261.682306) (xy 287.437906 -261.674867) (xy 287.443164 -261.674356)
			(xy 287.443672 -261.674356) (xy 287.959546 -261.674356) (xy 287.967355 -261.674027) (xy 287.982227 -261.669252)
			(xy 287.988756 -261.664958) (xy 288.009845 -261.650609) (xy 288.055506 -261.627878) (xy 288.104112 -261.612419)
			(xy 288.154515 -261.604596) (xy 288.205521 -261.604596) (xy 288.255924 -261.612419) (xy 288.30453 -261.627878)
			(xy 288.350191 -261.650609) (xy 288.37128 -261.664958) (xy 288.377819 -261.669236) (xy 288.392683 -261.674028)
			(xy 288.40049 -261.674356) (xy 288.916618 -261.674356) (xy 288.921928 -261.674813) (xy 288.929499 -261.682263)
			(xy 288.93008 -261.687564) (xy 288.93008 -262.182102) (xy 288.930055 -262.182356) (xy 294.974264 -262.182356)
			(xy 294.974264 -262.181848) (xy 294.974264 -261.687564) (xy 294.974768 -261.682304) (xy 294.982211 -261.674865)
			(xy 294.987472 -261.674356) (xy 295.5036 -261.674356) (xy 295.511411 -261.67405) (xy 295.526283 -261.66926)
			(xy 295.53281 -261.664958) (xy 295.553899 -261.650609) (xy 295.59956 -261.627878) (xy 295.648166 -261.612419)
			(xy 295.698569 -261.604596) (xy 295.749575 -261.604596) (xy 295.799978 -261.612419) (xy 295.848584 -261.627878)
			(xy 295.894245 -261.650609) (xy 295.915334 -261.664958) (xy 295.921861 -261.669257) (xy 295.936734 -261.674036)
			(xy 295.944544 -261.674356) (xy 296.460672 -261.674356) (xy 296.465923 -261.67491) (xy 296.473365 -261.682316)
			(xy 296.47388 -261.687564) (xy 296.47388 -262.182102) (xy 302.518064 -262.182102) (xy 302.518064 -261.687564)
			(xy 302.518568 -261.682304) (xy 302.526011 -261.674865) (xy 302.531272 -261.674356) (xy 304.004726 -261.674356)
			(xy 304.010037 -261.674808) (xy 304.017607 -261.682261) (xy 304.018188 -261.687564) (xy 304.018188 -262.182102)
			(xy 304.018163 -262.182356) (xy 411.618176 -262.182356) (xy 411.618176 -262.181848) (xy 411.618176 -261.687564)
			(xy 411.618669 -261.682301) (xy 411.62612 -261.674861) (xy 411.631384 -261.674356) (xy 413.104584 -261.674356)
			(xy 413.109836 -261.674902) (xy 413.117278 -261.682314) (xy 413.117792 -261.687564) (xy 413.117792 -262.182102)
			(xy 419.161976 -262.182102) (xy 419.161976 -261.687564) (xy 419.162469 -261.682301) (xy 419.16992 -261.674861)
			(xy 419.175184 -261.674356) (xy 419.175692 -261.674356) (xy 419.691566 -261.674356) (xy 419.699376 -261.674035)
			(xy 419.714247 -261.669255) (xy 419.720776 -261.664958) (xy 419.741865 -261.650609) (xy 419.787526 -261.627878)
			(xy 419.836132 -261.612419) (xy 419.886535 -261.604596) (xy 419.937541 -261.604596) (xy 419.987944 -261.612419)
			(xy 420.03655 -261.627878) (xy 420.082211 -261.650609) (xy 420.1033 -261.664958) (xy 420.109835 -261.669244)
			(xy 420.124702 -261.674031) (xy 420.13251 -261.674356) (xy 420.648638 -261.674356) (xy 420.653951 -261.6748)
			(xy 420.66152 -261.68226) (xy 420.6621 -261.687564) (xy 420.6621 -262.182102) (xy 420.662074 -262.182356)
			(xy 426.706284 -262.182356) (xy 426.706284 -262.181848) (xy 426.706284 -261.687564) (xy 426.70677 -261.682299)
			(xy 426.714226 -261.674859) (xy 426.719492 -261.674356) (xy 427.23562 -261.674356) (xy 427.243432 -261.674058)
			(xy 427.258303 -261.669262) (xy 427.26483 -261.664958) (xy 427.285919 -261.650609) (xy 427.33158 -261.627878)
			(xy 427.380186 -261.612419) (xy 427.430589 -261.604596) (xy 427.481595 -261.604596) (xy 427.531998 -261.612419)
			(xy 427.580604 -261.627878) (xy 427.626265 -261.650609) (xy 427.647354 -261.664958) (xy 427.653877 -261.669265)
			(xy 427.668753 -261.674039) (xy 427.676564 -261.674356) (xy 428.192692 -261.674356) (xy 428.197945 -261.674896)
			(xy 428.205386 -261.682313) (xy 428.2059 -261.687564) (xy 428.2059 -262.182102) (xy 434.250084 -262.182102)
			(xy 434.250084 -261.687564) (xy 434.25057 -261.682299) (xy 434.258026 -261.674859) (xy 434.263292 -261.674356)
			(xy 434.2638 -261.674356) (xy 434.779674 -261.674356) (xy 434.787484 -261.674038) (xy 434.802356 -261.669256)
			(xy 434.808884 -261.664958) (xy 434.829973 -261.650609) (xy 434.875634 -261.627878) (xy 434.92424 -261.612419)
			(xy 434.974643 -261.604596) (xy 435.025649 -261.604596) (xy 435.076052 -261.612419) (xy 435.124658 -261.627878)
			(xy 435.170319 -261.650609) (xy 435.191408 -261.664958) (xy 435.197941 -261.669247) (xy 435.21281 -261.674032)
			(xy 435.220618 -261.674356) (xy 435.736746 -261.674356) (xy 435.742047 -261.674861) (xy 435.749623 -261.682274)
			(xy 435.750208 -261.687564) (xy 435.750208 -262.182102) (xy 435.750182 -262.182356) (xy 441.794392 -262.182356)
			(xy 441.794392 -262.181848) (xy 441.794392 -261.687564) (xy 441.794871 -261.682297) (xy 441.802332 -261.674857)
			(xy 441.8076 -261.674356) (xy 442.323728 -261.674356) (xy 442.33154 -261.674062) (xy 442.346412 -261.669263)
			(xy 442.352938 -261.664958) (xy 442.374027 -261.650609) (xy 442.419688 -261.627878) (xy 442.468294 -261.612419)
			(xy 442.518697 -261.604596) (xy 442.569703 -261.604596) (xy 442.620106 -261.612419) (xy 442.668712 -261.627878)
			(xy 442.714373 -261.650609) (xy 442.735462 -261.664958) (xy 442.742005 -261.669229) (xy 442.756866 -261.674025)
			(xy 442.764672 -261.674356) (xy 443.2808 -261.674356) (xy 443.286054 -261.674891) (xy 443.293494 -261.682311)
			(xy 443.294008 -261.687564) (xy 443.294008 -262.182102) (xy 443.293983 -262.182356) (xy 449.338192 -262.182356)
			(xy 449.338192 -262.181848) (xy 449.338192 -261.687564) (xy 449.338671 -261.682297) (xy 449.346132 -261.674857)
			(xy 449.3514 -261.674356) (xy 449.867528 -261.674356) (xy 449.87534 -261.674062) (xy 449.890212 -261.669263)
			(xy 449.896738 -261.664958) (xy 449.917827 -261.650609) (xy 449.963488 -261.627878) (xy 450.012094 -261.612419)
			(xy 450.062497 -261.604596) (xy 450.113503 -261.604596) (xy 450.163906 -261.612419) (xy 450.212512 -261.627878)
			(xy 450.258173 -261.650609) (xy 450.279262 -261.664958) (xy 450.285805 -261.669229) (xy 450.300666 -261.674025)
			(xy 450.308472 -261.674356) (xy 450.8246 -261.674356) (xy 450.829854 -261.674891) (xy 450.837294 -261.682311)
			(xy 450.837808 -261.687564) (xy 450.837808 -262.182102) (xy 450.837284 -262.187395) (xy 450.829881 -262.194964)
			(xy 450.8246 -262.195564) (xy 450.308726 -262.195564) (xy 450.300916 -262.195878) (xy 450.286044 -262.200663)
			(xy 450.279516 -262.204962) (xy 450.258388 -262.219302) (xy 450.212667 -262.24203) (xy 450.163995 -262.257463)
			(xy 450.11353 -262.265233) (xy 450.088 -262.265668) (xy 450.06247 -262.265231) (xy 450.012006 -262.257455)
			(xy 449.963334 -262.242026) (xy 449.917606 -262.219309) (xy 449.896484 -262.204962) (xy 449.889952 -262.200672)
			(xy 449.875082 -262.195887) (xy 449.867274 -262.195564) (xy 449.3514 -262.195564) (xy 449.346057 -262.195269)
			(xy 449.338513 -262.1877) (xy 449.338192 -262.182356) (xy 443.293983 -262.182356) (xy 443.293484 -262.187395)
			(xy 443.286081 -262.194964) (xy 443.2808 -262.195564) (xy 442.764926 -262.195564) (xy 442.757116 -262.195878)
			(xy 442.742244 -262.200663) (xy 442.735716 -262.204962) (xy 442.714588 -262.219302) (xy 442.668867 -262.24203)
			(xy 442.620195 -262.257463) (xy 442.56973 -262.265233) (xy 442.5442 -262.265668) (xy 442.51867 -262.265231)
			(xy 442.468206 -262.257455) (xy 442.419534 -262.242026) (xy 442.373806 -262.219309) (xy 442.352684 -262.204962)
			(xy 442.346152 -262.200672) (xy 442.331282 -262.195887) (xy 442.323474 -262.195564) (xy 441.8076 -262.195564)
			(xy 441.802257 -262.195269) (xy 441.794713 -262.1877) (xy 441.794392 -262.182356) (xy 435.750182 -262.182356)
			(xy 435.749655 -262.187455) (xy 435.742097 -262.195038) (xy 435.736746 -262.195564) (xy 435.220872 -262.195564)
			(xy 435.21306 -262.195855) (xy 435.198188 -262.200655) (xy 435.191662 -262.204962) (xy 435.170549 -262.219325)
			(xy 435.124822 -262.242048) (xy 435.076146 -262.257474) (xy 435.025678 -262.265237) (xy 435.000146 -262.265668)
			(xy 434.974617 -262.265208) (xy 434.924154 -262.257439) (xy 434.875481 -262.242017) (xy 434.829753 -262.219306)
			(xy 434.80863 -262.204962) (xy 434.802087 -262.200689) (xy 434.787226 -262.195894) (xy 434.77942 -262.195564)
			(xy 434.263546 -262.195564) (xy 434.258118 -262.19519) (xy 434.250429 -262.187529) (xy 434.250084 -262.182102)
			(xy 428.2059 -262.182102) (xy 428.205383 -262.187397) (xy 428.197976 -262.194966) (xy 428.192692 -262.195564)
			(xy 427.676818 -262.195564) (xy 427.669007 -262.195875) (xy 427.654136 -262.200662) (xy 427.647608 -262.204962)
			(xy 427.626482 -262.219305) (xy 427.58076 -262.242033) (xy 427.532088 -262.257465) (xy 427.481623 -262.265234)
			(xy 427.456092 -262.265668) (xy 427.430562 -262.265235) (xy 427.380098 -262.257458) (xy 427.331425 -262.242028)
			(xy 427.285698 -262.21931) (xy 427.264576 -262.204962) (xy 427.258045 -262.200669) (xy 427.243175 -262.195886)
			(xy 427.235366 -262.195564) (xy 426.719492 -262.195564) (xy 426.714148 -262.195274) (xy 426.706605 -262.187701)
			(xy 426.706284 -262.182356) (xy 420.662074 -262.182356) (xy 420.661555 -262.187457) (xy 420.653992 -262.19504)
			(xy 420.648638 -262.195564) (xy 420.132764 -262.195564) (xy 420.124955 -262.195894) (xy 420.110083 -262.200668)
			(xy 420.103554 -262.204962) (xy 420.082444 -262.219329) (xy 420.036716 -262.242051) (xy 419.988039 -262.257476)
			(xy 419.93757 -262.265238) (xy 419.912038 -262.265668) (xy 419.886509 -262.265212) (xy 419.836045 -262.257442)
			(xy 419.787373 -262.242018) (xy 419.741645 -262.219307) (xy 419.720522 -262.204962) (xy 419.713981 -262.200686)
			(xy 419.699118 -262.195893) (xy 419.691312 -262.195564) (xy 419.175438 -262.195564) (xy 419.170009 -262.195196)
			(xy 419.16232 -262.18753) (xy 419.161976 -262.182102) (xy 413.117792 -262.182102) (xy 413.117282 -262.187399)
			(xy 413.10987 -262.194968) (xy 413.104584 -262.195564) (xy 411.631384 -262.195564) (xy 411.626039 -262.19528)
			(xy 411.618496 -262.187703) (xy 411.618176 -262.182356) (xy 304.018163 -262.182356) (xy 304.017653 -262.18746)
			(xy 304.010083 -262.195044) (xy 304.004726 -262.195564) (xy 302.531526 -262.195564) (xy 302.526095 -262.195204)
			(xy 302.518408 -262.187532) (xy 302.518064 -262.182102) (xy 296.47388 -262.182102) (xy 296.47338 -262.187402)
			(xy 296.465961 -262.194971) (xy 296.460672 -262.195564) (xy 295.944798 -262.195564) (xy 295.936987 -262.195866)
			(xy 295.922115 -262.200659) (xy 295.915588 -262.204962) (xy 295.894468 -262.219314) (xy 295.848744 -262.24204)
			(xy 295.80007 -262.257469) (xy 295.749603 -262.265235) (xy 295.724072 -262.265668) (xy 295.698541 -262.265245)
			(xy 295.648077 -262.257465) (xy 295.599405 -262.242032) (xy 295.553677 -262.219311) (xy 295.532556 -262.204962)
			(xy 295.52603 -262.200661) (xy 295.511156 -262.195883) (xy 295.503346 -262.195564) (xy 294.987472 -262.195564)
			(xy 294.982125 -262.195288) (xy 294.974583 -262.187705) (xy 294.974264 -262.182356) (xy 288.930055 -262.182356)
			(xy 288.929553 -262.187462) (xy 288.921977 -262.195046) (xy 288.916618 -262.195564) (xy 288.400744 -262.195564)
			(xy 288.392934 -262.195886) (xy 288.378063 -262.200665) (xy 288.371534 -262.204962) (xy 288.350429 -262.219337)
			(xy 288.304699 -262.242058) (xy 288.256021 -262.25748) (xy 288.20555 -262.265239) (xy 288.180018 -262.265668)
			(xy 288.154488 -262.265222) (xy 288.104025 -262.257449) (xy 288.055352 -262.242022) (xy 288.009624 -262.219308)
			(xy 287.988502 -262.204962) (xy 287.981966 -262.200679) (xy 287.9671 -262.19589) (xy 287.959292 -262.195564)
			(xy 287.443418 -262.195564) (xy 287.437986 -262.195209) (xy 287.430299 -262.187533) (xy 287.429956 -262.182102)
			(xy 281.385772 -262.182102) (xy 281.385279 -262.187404) (xy 281.377855 -262.194974) (xy 281.372564 -262.195564)
			(xy 280.85669 -262.195564) (xy 280.848878 -262.195863) (xy 280.834007 -262.200658) (xy 280.82748 -262.204962)
			(xy 280.806362 -262.219317) (xy 280.760637 -262.242042) (xy 280.711962 -262.257471) (xy 280.661495 -262.265236)
			(xy 280.635964 -262.265668) (xy 280.610433 -262.265249) (xy 280.559969 -262.257468) (xy 280.511296 -262.242033)
			(xy 280.465569 -262.219312) (xy 280.444448 -262.204962) (xy 280.437924 -262.200658) (xy 280.423048 -262.195882)
			(xy 280.415238 -262.195564) (xy 279.899364 -262.195564) (xy 279.894016 -262.195293) (xy 279.886475 -262.187706)
			(xy 279.886156 -262.182356) (xy 273.841948 -262.182356) (xy 273.841479 -262.187404) (xy 273.834055 -262.194974)
			(xy 273.828764 -262.195564) (xy 273.31289 -262.195564) (xy 273.305078 -262.195863) (xy 273.290207 -262.200658)
			(xy 273.28368 -262.204962) (xy 273.262562 -262.219317) (xy 273.216837 -262.242042) (xy 273.168162 -262.257471)
			(xy 273.117695 -262.265236) (xy 273.092164 -262.265668) (xy 273.066633 -262.265249) (xy 273.016169 -262.257468)
			(xy 272.967496 -262.242033) (xy 272.921769 -262.219312) (xy 272.900648 -262.204962) (xy 272.894124 -262.200658)
			(xy 272.879248 -262.195882) (xy 272.871438 -262.195564) (xy 272.355564 -262.195564) (xy 272.350216 -262.195293)
			(xy 272.342675 -262.187706) (xy 272.342356 -262.182356) (xy 266.298147 -262.182356) (xy 266.297652 -262.187464)
			(xy 266.290071 -262.195049) (xy 266.28471 -262.195564) (xy 265.768836 -262.195564) (xy 265.761026 -262.195882)
			(xy 265.746154 -262.200664) (xy 265.739626 -262.204962) (xy 265.718495 -262.219297) (xy 265.672775 -262.242027)
			(xy 265.624104 -262.257461) (xy 265.57364 -262.265232) (xy 265.54811 -262.265668) (xy 265.52258 -262.265226)
			(xy 265.472116 -262.257452) (xy 265.423444 -262.242024) (xy 265.377716 -262.219309) (xy 265.356594 -262.204962)
			(xy 265.350059 -262.200676) (xy 265.335192 -262.195889) (xy 265.327384 -262.195564) (xy 264.81151 -262.195564)
			(xy 264.806077 -262.195214) (xy 264.79839 -262.187535) (xy 264.798048 -262.182102) (xy 202.89774 -262.182102)
			(xy 202.89774 -262.182356) (xy 202.897347 -262.187675) (xy 202.889849 -262.195216) (xy 202.884532 -262.195564)
			(xy 202.368658 -262.195564) (xy 202.360782 -262.195839) (xy 202.345778 -262.200631) (xy 202.339194 -262.204962)
			(xy 202.31811 -262.219343) (xy 202.272467 -262.242173) (xy 202.223863 -262.257734) (xy 202.173448 -262.265657)
			(xy 202.147932 -262.266176) (xy 202.122412 -262.265692) (xy 202.071984 -262.257796) (xy 202.023373 -262.242235)
			(xy 201.977735 -262.219378) (xy 201.95667 -262.204962) (xy 201.950083 -262.200639) (xy 201.93508 -262.195856)
			(xy 201.927206 -262.195564) (xy 201.411332 -262.195564) (xy 201.405993 -262.195247) (xy 201.398448 -262.187695)
			(xy 201.398124 -262.182356) (xy 195.35394 -262.182356) (xy 195.353547 -262.187675) (xy 195.346049 -262.195216)
			(xy 195.340732 -262.195564) (xy 194.824858 -262.195564) (xy 194.816982 -262.195839) (xy 194.801978 -262.200631)
			(xy 194.795394 -262.204962) (xy 194.77431 -262.219343) (xy 194.728667 -262.242173) (xy 194.680063 -262.257734)
			(xy 194.629648 -262.265657) (xy 194.604132 -262.266176) (xy 194.578612 -262.265692) (xy 194.528184 -262.257796)
			(xy 194.479573 -262.242235) (xy 194.433935 -262.219378) (xy 194.41287 -262.204962) (xy 194.406283 -262.200639)
			(xy 194.39128 -262.195856) (xy 194.383406 -262.195564) (xy 193.867532 -262.195564) (xy 193.862193 -262.195247)
			(xy 193.854648 -262.187695) (xy 193.854324 -262.182356) (xy 187.81014 -262.182356) (xy 187.809747 -262.187675)
			(xy 187.802249 -262.195216) (xy 187.796932 -262.195564) (xy 187.796424 -262.195564) (xy 187.280804 -262.195564)
			(xy 187.27293 -262.195859) (xy 187.257926 -262.200637) (xy 187.25134 -262.204962) (xy 187.230271 -262.219366)
			(xy 187.184623 -262.242191) (xy 187.136014 -262.257745) (xy 187.085595 -262.265661) (xy 187.060078 -262.266176)
			(xy 187.034558 -262.265669) (xy 186.984132 -262.25778) (xy 186.93552 -262.242226) (xy 186.889881 -262.219375)
			(xy 186.868816 -262.204962) (xy 186.862219 -262.200656) (xy 186.847223 -262.195863) (xy 186.839352 -262.195564)
			(xy 186.323478 -262.195564) (xy 186.318172 -262.195092) (xy 186.310602 -262.187652) (xy 186.310016 -262.182356)
			(xy 180.265832 -262.182356) (xy 180.265446 -262.187677) (xy 180.257943 -262.195219) (xy 180.252624 -262.195564)
			(xy 179.73675 -262.195564) (xy 179.728874 -262.195836) (xy 179.71387 -262.20063) (xy 179.707286 -262.204962)
			(xy 179.686204 -262.219346) (xy 179.640561 -262.242176) (xy 179.591956 -262.257736) (xy 179.54154 -262.265657)
			(xy 179.516024 -262.266176) (xy 179.490503 -262.265696) (xy 179.440076 -262.257799) (xy 179.391464 -262.242236)
			(xy 179.345826 -262.219379) (xy 179.324762 -262.204962) (xy 179.318177 -262.200635) (xy 179.303172 -262.195855)
			(xy 179.295298 -262.195564) (xy 178.779424 -262.195564) (xy 178.774084 -262.195253) (xy 178.766539 -262.187696)
			(xy 178.766216 -262.182356) (xy 172.722032 -262.182356) (xy 172.721646 -262.187677) (xy 172.714143 -262.195219)
			(xy 172.708824 -262.195564) (xy 172.708316 -262.195564) (xy 172.192696 -262.195564) (xy 172.184822 -262.195855)
			(xy 172.169818 -262.200636) (xy 172.163232 -262.204962) (xy 172.142165 -262.21937) (xy 172.096516 -262.242194)
			(xy 172.047907 -262.257747) (xy 171.997488 -262.265661) (xy 171.97197 -262.266176) (xy 171.94645 -262.265673)
			(xy 171.896024 -262.257783) (xy 171.847412 -262.242227) (xy 171.801773 -262.219376) (xy 171.780708 -262.204962)
			(xy 171.774113 -262.200653) (xy 171.759116 -262.195861) (xy 171.751244 -262.195564) (xy 171.23537 -262.195564)
			(xy 171.230063 -262.195097) (xy 171.222494 -262.187654) (xy 171.221908 -262.182356) (xy 165.177724 -262.182356)
			(xy 165.177345 -262.187679) (xy 165.169837 -262.195221) (xy 165.164516 -262.195564) (xy 163.691316 -262.195564)
			(xy 163.685975 -262.195258) (xy 163.678431 -262.187698) (xy 163.678108 -262.182356) (xy 56.07812 -262.182356)
			(xy 56.077745 -262.18768) (xy 56.070234 -262.195222) (xy 56.064912 -262.195564) (xy 54.591458 -262.195564)
			(xy 54.58615 -262.195105) (xy 54.578581 -262.187656) (xy 54.577996 -262.182356) (xy 48.533812 -262.182356)
			(xy 48.533444 -262.187681) (xy 48.525928 -262.195225) (xy 48.520604 -262.195564) (xy 48.00473 -262.195564)
			(xy 47.996853 -262.195827) (xy 47.981849 -262.200627) (xy 47.975266 -262.204962) (xy 47.95419 -262.219355)
			(xy 47.908544 -262.242183) (xy 47.859938 -262.25774) (xy 47.809521 -262.265659) (xy 47.784004 -262.266176)
			(xy 47.758483 -262.265706) (xy 47.708055 -262.257806) (xy 47.659443 -262.242241) (xy 47.613806 -262.21938)
			(xy 47.592742 -262.204962) (xy 47.586162 -262.200628) (xy 47.571153 -262.195852) (xy 47.563278 -262.195564)
			(xy 47.047404 -262.195564) (xy 47.042062 -262.195266) (xy 47.034518 -262.187699) (xy 47.034196 -262.182356)
			(xy 40.990012 -262.182356) (xy 40.989644 -262.187681) (xy 40.982128 -262.195225) (xy 40.976804 -262.195564)
			(xy 40.976296 -262.195564) (xy 40.460676 -262.195564) (xy 40.452801 -262.195847) (xy 40.437797 -262.200634)
			(xy 40.431212 -262.204962) (xy 40.410151 -262.219378) (xy 40.3645 -262.242201) (xy 40.315889 -262.257751)
			(xy 40.265468 -262.265663) (xy 40.23995 -262.266176) (xy 40.21443 -262.265683) (xy 40.164003 -262.25779)
			(xy 40.115391 -262.242231) (xy 40.069753 -262.219377) (xy 40.048688 -262.204962) (xy 40.042097 -262.200645)
			(xy 40.027097 -262.195858) (xy 40.019224 -262.195564) (xy 39.50335 -262.195564) (xy 39.498053 -262.195044)
			(xy 39.490479 -262.187641) (xy 39.489888 -262.182356) (xy 33.445704 -262.182356) (xy 33.445343 -262.187683)
			(xy 33.437822 -262.195227) (xy 33.432496 -262.195564) (xy 32.916622 -262.195564) (xy 32.908749 -262.195866)
			(xy 32.893745 -262.20064) (xy 32.887158 -262.204962) (xy 32.866084 -262.219358) (xy 32.820438 -262.242185)
			(xy 32.771831 -262.257742) (xy 32.721413 -262.265659) (xy 32.695896 -262.266176) (xy 32.670375 -262.26571)
			(xy 32.619947 -262.257809) (xy 32.571335 -262.242242) (xy 32.525698 -262.219381) (xy 32.504634 -262.204962)
			(xy 32.498033 -262.200663) (xy 32.48304 -262.195865) (xy 32.47517 -262.195564) (xy 31.959296 -262.195564)
			(xy 31.953952 -262.195271) (xy 31.946409 -262.187701) (xy 31.946088 -262.182356) (xy 25.901904 -262.182356)
			(xy 25.901543 -262.187683) (xy 25.894022 -262.195227) (xy 25.888696 -262.195564) (xy 25.372822 -262.195564)
			(xy 25.364949 -262.195866) (xy 25.349945 -262.20064) (xy 25.343358 -262.204962) (xy 25.322284 -262.219358)
			(xy 25.276638 -262.242185) (xy 25.228031 -262.257742) (xy 25.177613 -262.265659) (xy 25.152096 -262.266176)
			(xy 25.126575 -262.26571) (xy 25.076147 -262.257809) (xy 25.027535 -262.242242) (xy 24.981898 -262.219381)
			(xy 24.960834 -262.204962) (xy 24.954233 -262.200663) (xy 24.93924 -262.195865) (xy 24.93137 -262.195564)
			(xy 24.415496 -262.195564) (xy 24.410152 -262.195271) (xy 24.402609 -262.187701) (xy 24.402288 -262.182356)
			(xy 18.358104 -262.182356) (xy 18.357743 -262.187683) (xy 18.350222 -262.195227) (xy 18.344896 -262.195564)
			(xy 18.344388 -262.195564) (xy 17.828768 -262.195564) (xy 17.820893 -262.195843) (xy 17.805889 -262.200633)
			(xy 17.799304 -262.204962) (xy 17.778217 -262.219339) (xy 17.732575 -262.24217) (xy 17.683972 -262.257732)
			(xy 17.633558 -262.265656) (xy 17.608042 -262.266176) (xy 17.582522 -262.265687) (xy 17.532095 -262.257793)
			(xy 17.483483 -262.242233) (xy 17.437845 -262.219378) (xy 17.41678 -262.204962) (xy 17.410191 -262.200642)
			(xy 17.395189 -262.195857) (xy 17.387316 -262.195564) (xy 16.871442 -262.195564) (xy 16.866144 -262.195049)
			(xy 16.858571 -262.187642) (xy 16.85798 -262.182356) (xy 2.509012 -262.182356) (xy 2.509012 -263.032494)
			(xy 20.958048 -263.032494) (xy 20.958048 -262.537956) (xy 20.958561 -262.532699) (xy 20.965999 -262.525261)
			(xy 20.971256 -262.524748) (xy 20.971764 -262.524748) (xy 21.487638 -262.524748) (xy 21.495447 -262.524417)
			(xy 21.510318 -262.519644) (xy 21.516848 -262.51535) (xy 21.537937 -262.501001) (xy 21.583598 -262.47827)
			(xy 21.632204 -262.462811) (xy 21.682607 -262.454988) (xy 21.733613 -262.454988) (xy 21.784016 -262.462811)
			(xy 21.832622 -262.47827) (xy 21.878283 -262.501001) (xy 21.899372 -262.51535) (xy 21.905913 -262.519624)
			(xy 21.920776 -262.524419) (xy 21.928582 -262.524748) (xy 22.44471 -262.524748) (xy 22.450017 -262.525217)
			(xy 22.457588 -262.532658) (xy 22.458172 -262.537956) (xy 22.458172 -263.032494) (xy 22.458147 -263.032748)
			(xy 28.502356 -263.032748) (xy 28.502356 -263.03224) (xy 28.502356 -262.537956) (xy 28.502862 -262.532697)
			(xy 28.510304 -262.525259) (xy 28.515564 -262.524748) (xy 29.031692 -262.524748) (xy 29.039503 -262.524439)
			(xy 29.054374 -262.519651) (xy 29.060902 -262.51535) (xy 29.081991 -262.501001) (xy 29.127652 -262.47827)
			(xy 29.176258 -262.462811) (xy 29.226661 -262.454988) (xy 29.277667 -262.454988) (xy 29.32807 -262.462811)
			(xy 29.376676 -262.47827) (xy 29.422337 -262.501001) (xy 29.443426 -262.51535) (xy 29.449955 -262.519645)
			(xy 29.464827 -262.524427) (xy 29.472636 -262.524748) (xy 29.988764 -262.524748) (xy 29.994012 -262.525314)
			(xy 30.001454 -262.532711) (xy 30.001972 -262.537956) (xy 30.001972 -263.032494) (xy 30.001948 -263.032748)
			(xy 36.046156 -263.032748) (xy 36.046156 -263.03224) (xy 36.046156 -262.537956) (xy 36.046662 -262.532697)
			(xy 36.054104 -262.525259) (xy 36.059364 -262.524748) (xy 36.575492 -262.524748) (xy 36.583303 -262.524439)
			(xy 36.598174 -262.519651) (xy 36.604702 -262.51535) (xy 36.625791 -262.501001) (xy 36.671452 -262.47827)
			(xy 36.720058 -262.462811) (xy 36.770461 -262.454988) (xy 36.821467 -262.454988) (xy 36.87187 -262.462811)
			(xy 36.920476 -262.47827) (xy 36.966137 -262.501001) (xy 36.987226 -262.51535) (xy 36.993755 -262.519645)
			(xy 37.008627 -262.524427) (xy 37.016436 -262.524748) (xy 37.532564 -262.524748) (xy 37.537812 -262.525314)
			(xy 37.545254 -262.532711) (xy 37.545772 -262.537956) (xy 37.545772 -263.032494) (xy 43.589956 -263.032494)
			(xy 43.589956 -262.537956) (xy 43.590462 -262.532697) (xy 43.597904 -262.525259) (xy 43.603164 -262.524748)
			(xy 43.603672 -262.524748) (xy 44.119546 -262.524748) (xy 44.127355 -262.52442) (xy 44.142227 -262.519645)
			(xy 44.148756 -262.51535) (xy 44.169845 -262.501001) (xy 44.215506 -262.47827) (xy 44.264112 -262.462811)
			(xy 44.314515 -262.454988) (xy 44.365521 -262.454988) (xy 44.415924 -262.462811) (xy 44.46453 -262.47827)
			(xy 44.510191 -262.501001) (xy 44.53128 -262.51535) (xy 44.53782 -262.519627) (xy 44.552683 -262.52442)
			(xy 44.56049 -262.524748) (xy 45.076618 -262.524748) (xy 45.081926 -262.525212) (xy 45.089497 -262.532657)
			(xy 45.09008 -262.537956) (xy 45.09008 -263.032494) (xy 45.090055 -263.032748) (xy 51.134264 -263.032748)
			(xy 51.134264 -263.03224) (xy 51.134264 -262.537956) (xy 51.134763 -262.532695) (xy 51.14221 -262.525256)
			(xy 51.147472 -262.524748) (xy 51.6636 -262.524748) (xy 51.671411 -262.524443) (xy 51.686283 -262.519652)
			(xy 51.69281 -262.51535) (xy 51.713899 -262.501001) (xy 51.75956 -262.47827) (xy 51.808166 -262.462811)
			(xy 51.858569 -262.454988) (xy 51.909575 -262.454988) (xy 51.959978 -262.462811) (xy 52.008584 -262.47827)
			(xy 52.054245 -262.501001) (xy 52.075334 -262.51535) (xy 52.081862 -262.519648) (xy 52.096735 -262.524428)
			(xy 52.104544 -262.524748) (xy 52.620672 -262.524748) (xy 52.625921 -262.525309) (xy 52.633362 -262.53271)
			(xy 52.63388 -262.537956) (xy 52.63388 -263.032494) (xy 58.678064 -263.032494) (xy 58.678064 -262.537956)
			(xy 58.678563 -262.532695) (xy 58.68601 -262.525256) (xy 58.691272 -262.524748) (xy 58.69178 -262.524748)
			(xy 60.164726 -262.524748) (xy 60.170035 -262.525207) (xy 60.177605 -262.532656) (xy 60.178188 -262.537956)
			(xy 60.178188 -263.032494) (xy 60.178162 -263.032748) (xy 167.778176 -263.032748) (xy 167.778176 -262.537956)
			(xy 167.778664 -262.532692) (xy 167.786119 -262.525253) (xy 167.791384 -262.524748) (xy 169.264584 -262.524748)
			(xy 169.269834 -262.525301) (xy 169.277275 -262.532708) (xy 169.277792 -262.537956) (xy 169.277792 -263.032494)
			(xy 175.321976 -263.032494) (xy 175.321976 -262.537956) (xy 175.322464 -262.532692) (xy 175.329919 -262.525253)
			(xy 175.335184 -262.524748) (xy 175.335692 -262.524748) (xy 175.851566 -262.524748) (xy 175.859376 -262.524428)
			(xy 175.874247 -262.519647) (xy 175.880776 -262.51535) (xy 175.901865 -262.501001) (xy 175.947526 -262.47827)
			(xy 175.996132 -262.462811) (xy 176.046535 -262.454988) (xy 176.097541 -262.454988) (xy 176.147944 -262.462811)
			(xy 176.19655 -262.47827) (xy 176.242211 -262.501001) (xy 176.2633 -262.51535) (xy 176.269835 -262.519635)
			(xy 176.284702 -262.524423) (xy 176.29251 -262.524748) (xy 176.808638 -262.524748) (xy 176.813949 -262.525199)
			(xy 176.821518 -262.532654) (xy 176.8221 -262.537956) (xy 176.8221 -263.032494) (xy 176.822074 -263.032748)
			(xy 182.866284 -263.032748) (xy 182.866284 -263.03224) (xy 182.866284 -262.537956) (xy 182.866765 -262.53269)
			(xy 182.874225 -262.52525) (xy 182.879492 -262.524748) (xy 183.39562 -262.524748) (xy 183.403432 -262.524452)
			(xy 183.418304 -262.519655) (xy 183.42483 -262.51535) (xy 183.445919 -262.501001) (xy 183.49158 -262.47827)
			(xy 183.540186 -262.462811) (xy 183.590589 -262.454988) (xy 183.641595 -262.454988) (xy 183.691998 -262.462811)
			(xy 183.740604 -262.47827) (xy 183.786265 -262.501001) (xy 183.807354 -262.51535) (xy 183.813877 -262.519656)
			(xy 183.828753 -262.524431) (xy 183.836564 -262.524748) (xy 184.352692 -262.524748) (xy 184.357943 -262.525295)
			(xy 184.365384 -262.532707) (xy 184.3659 -262.537956) (xy 184.3659 -263.032494) (xy 190.410084 -263.032494)
			(xy 190.410084 -262.537956) (xy 190.410565 -262.53269) (xy 190.418025 -262.52525) (xy 190.423292 -262.524748)
			(xy 190.4238 -262.524748) (xy 190.939674 -262.524748) (xy 190.947484 -262.524432) (xy 190.962356 -262.519648)
			(xy 190.968884 -262.51535) (xy 190.989973 -262.501001) (xy 191.035634 -262.47827) (xy 191.08424 -262.462811)
			(xy 191.134643 -262.454988) (xy 191.185649 -262.454988) (xy 191.236052 -262.462811) (xy 191.284658 -262.47827)
			(xy 191.330319 -262.501001) (xy 191.351408 -262.51535) (xy 191.357941 -262.519638) (xy 191.37281 -262.524424)
			(xy 191.380618 -262.524748) (xy 191.896746 -262.524748) (xy 191.902046 -262.52526) (xy 191.90962 -262.532668)
			(xy 191.910208 -262.537956) (xy 191.910208 -263.032494) (xy 191.910182 -263.032748) (xy 197.954392 -263.032748)
			(xy 197.954392 -263.03224) (xy 197.954392 -262.537956) (xy 197.954866 -262.532688) (xy 197.96233 -262.525248)
			(xy 197.9676 -262.524748) (xy 198.483728 -262.524748) (xy 198.49154 -262.524455) (xy 198.506412 -262.519656)
			(xy 198.512938 -262.51535) (xy 198.534027 -262.501001) (xy 198.579688 -262.47827) (xy 198.628294 -262.462811)
			(xy 198.678697 -262.454988) (xy 198.729703 -262.454988) (xy 198.780106 -262.462811) (xy 198.828712 -262.47827)
			(xy 198.874373 -262.501001) (xy 198.895462 -262.51535) (xy 198.902006 -262.519621) (xy 198.916866 -262.524417)
			(xy 198.924672 -262.524748) (xy 199.4408 -262.524748) (xy 199.446052 -262.52529) (xy 199.453492 -262.532706)
			(xy 199.454008 -262.537956) (xy 199.454008 -263.032494) (xy 199.453983 -263.032748) (xy 205.498192 -263.032748)
			(xy 205.498192 -263.03224) (xy 205.498192 -262.537956) (xy 205.498666 -262.532688) (xy 205.50613 -262.525248)
			(xy 205.5114 -262.524748) (xy 206.027528 -262.524748) (xy 206.03534 -262.524455) (xy 206.050212 -262.519656)
			(xy 206.056738 -262.51535) (xy 206.077827 -262.501001) (xy 206.123488 -262.47827) (xy 206.172094 -262.462811)
			(xy 206.222497 -262.454988) (xy 206.273503 -262.454988) (xy 206.323906 -262.462811) (xy 206.372512 -262.47827)
			(xy 206.418173 -262.501001) (xy 206.439262 -262.51535) (xy 206.445806 -262.519621) (xy 206.460666 -262.524417)
			(xy 206.468472 -262.524748) (xy 206.9846 -262.524748) (xy 206.989852 -262.52529) (xy 206.997292 -262.532706)
			(xy 206.997808 -262.537956) (xy 206.997808 -263.03224) (xy 268.898116 -263.03224) (xy 268.898116 -262.537702)
			(xy 268.898649 -262.532344) (xy 268.906221 -262.524759) (xy 268.911578 -262.52424) (xy 269.427706 -262.52424)
			(xy 269.435517 -262.523939) (xy 269.450389 -262.519145) (xy 269.456916 -262.514842) (xy 269.478005 -262.500493)
			(xy 269.523666 -262.477762) (xy 269.572272 -262.462303) (xy 269.622675 -262.45448) (xy 269.673681 -262.45448)
			(xy 269.724084 -262.462303) (xy 269.77269 -262.477762) (xy 269.818351 -262.500493) (xy 269.83944 -262.514842)
			(xy 269.845967 -262.519142) (xy 269.86084 -262.523921) (xy 269.86865 -262.52424) (xy 270.384778 -262.52424)
			(xy 270.39021 -262.524594) (xy 270.397898 -262.53227) (xy 270.39824 -262.537702) (xy 270.39824 -263.03224)
			(xy 276.442424 -263.03224) (xy 276.442424 -262.537702) (xy 276.442923 -262.532402) (xy 276.450343 -262.524832)
			(xy 276.455632 -262.52424) (xy 276.97176 -262.52424) (xy 276.97957 -262.523919) (xy 276.994441 -262.519139)
			(xy 277.00097 -262.514842) (xy 277.022059 -262.500493) (xy 277.06772 -262.477762) (xy 277.116326 -262.462303)
			(xy 277.166729 -262.45448) (xy 277.217735 -262.45448) (xy 277.268138 -262.462303) (xy 277.316744 -262.477762)
			(xy 277.362405 -262.500493) (xy 277.383494 -262.514842) (xy 277.390031 -262.519124) (xy 277.404897 -262.523914)
			(xy 277.412704 -262.52424) (xy 277.928832 -262.52424) (xy 277.93418 -262.52451) (xy 277.941722 -262.532098)
			(xy 277.94204 -262.537448) (xy 277.94204 -262.537956) (xy 277.94204 -263.03224) (xy 283.986224 -263.03224)
			(xy 283.986224 -262.537702) (xy 283.986723 -262.532402) (xy 283.994143 -262.524832) (xy 283.999432 -262.52424)
			(xy 284.51556 -262.52424) (xy 284.52337 -262.523919) (xy 284.538241 -262.519139) (xy 284.54477 -262.514842)
			(xy 284.565859 -262.500493) (xy 284.61152 -262.477762) (xy 284.660126 -262.462303) (xy 284.710529 -262.45448)
			(xy 284.761535 -262.45448) (xy 284.811938 -262.462303) (xy 284.860544 -262.477762) (xy 284.906205 -262.500493)
			(xy 284.927294 -262.514842) (xy 284.933831 -262.519124) (xy 284.948697 -262.523914) (xy 284.956504 -262.52424)
			(xy 285.472632 -262.52424) (xy 285.47798 -262.52451) (xy 285.485522 -262.532098) (xy 285.48584 -262.537448)
			(xy 285.48584 -262.537956) (xy 285.48584 -263.03224) (xy 291.530024 -263.03224) (xy 291.530024 -262.537702)
			(xy 291.53055 -262.532342) (xy 291.538126 -262.524757) (xy 291.543486 -262.52424) (xy 292.059614 -262.52424)
			(xy 292.067426 -262.523943) (xy 292.082298 -262.519147) (xy 292.088824 -262.514842) (xy 292.109913 -262.500493)
			(xy 292.155574 -262.477762) (xy 292.20418 -262.462303) (xy 292.254583 -262.45448) (xy 292.305589 -262.45448)
			(xy 292.355992 -262.462303) (xy 292.404598 -262.477762) (xy 292.450259 -262.500493) (xy 292.471348 -262.514842)
			(xy 292.477873 -262.519145) (xy 292.492748 -262.523922) (xy 292.500558 -262.52424) (xy 293.016686 -262.52424)
			(xy 293.022119 -262.524589) (xy 293.029806 -262.532269) (xy 293.030148 -262.537702) (xy 293.030148 -263.03224)
			(xy 299.074332 -263.03224) (xy 299.074332 -262.537702) (xy 299.074824 -262.5324) (xy 299.082248 -262.524829)
			(xy 299.08754 -262.52424) (xy 299.603668 -262.52424) (xy 299.611478 -262.523923) (xy 299.62635 -262.51914)
			(xy 299.632878 -262.514842) (xy 299.653967 -262.500493) (xy 299.699628 -262.477762) (xy 299.748234 -262.462303)
			(xy 299.798637 -262.45448) (xy 299.849643 -262.45448) (xy 299.900046 -262.462303) (xy 299.948652 -262.477762)
			(xy 299.994313 -262.500493) (xy 300.015402 -262.514842) (xy 300.021937 -262.519127) (xy 300.036804 -262.523915)
			(xy 300.044612 -262.52424) (xy 300.56074 -262.52424) (xy 300.56609 -262.524505) (xy 300.573631 -262.532097)
			(xy 300.573948 -262.537448) (xy 300.573948 -262.537956) (xy 300.573948 -263.03224) (xy 306.618132 -263.03224)
			(xy 306.618132 -262.537702) (xy 306.618651 -262.53234) (xy 306.626232 -262.524754) (xy 306.631594 -262.52424)
			(xy 308.104794 -262.52424) (xy 308.110228 -262.524583) (xy 308.117915 -262.532268) (xy 308.118256 -262.537702)
			(xy 308.118256 -263.03224) (xy 415.718244 -263.03224) (xy 415.718244 -262.537702) (xy 415.718725 -262.532397)
			(xy 415.726157 -262.524826) (xy 415.731452 -262.52424) (xy 417.204652 -262.52424) (xy 417.209989 -262.524564)
			(xy 417.217536 -262.532111) (xy 417.21786 -262.537448) (xy 417.21786 -263.03224) (xy 423.262044 -263.03224)
			(xy 423.262044 -262.537702) (xy 423.262381 -262.532266) (xy 423.27007 -262.52458) (xy 423.275506 -262.52424)
			(xy 423.791634 -262.52424) (xy 423.799443 -262.523908) (xy 423.814315 -262.519136) (xy 423.820844 -262.514842)
			(xy 423.841933 -262.500493) (xy 423.887594 -262.477762) (xy 423.9362 -262.462303) (xy 423.986603 -262.45448)
			(xy 424.037609 -262.45448) (xy 424.088012 -262.462303) (xy 424.136618 -262.477762) (xy 424.182279 -262.500493)
			(xy 424.203368 -262.514842) (xy 424.209911 -262.519114) (xy 424.224772 -262.52391) (xy 424.232578 -262.52424)
			(xy 424.748706 -262.52424) (xy 424.754071 -262.524746) (xy 424.761657 -262.532337) (xy 424.762168 -262.537702)
			(xy 424.762168 -263.03224) (xy 430.806352 -263.03224) (xy 430.806352 -262.537702) (xy 430.806826 -262.532395)
			(xy 430.814263 -262.524823) (xy 430.81956 -262.52424) (xy 431.335688 -262.52424) (xy 431.343499 -262.523931)
			(xy 431.35837 -262.519143) (xy 431.364898 -262.514842) (xy 431.385987 -262.500493) (xy 431.431648 -262.477762)
			(xy 431.480254 -262.462303) (xy 431.530657 -262.45448) (xy 431.581663 -262.45448) (xy 431.632066 -262.462303)
			(xy 431.680672 -262.477762) (xy 431.726333 -262.500493) (xy 431.747422 -262.514842) (xy 431.753953 -262.519135)
			(xy 431.768823 -262.523918) (xy 431.776632 -262.52424) (xy 432.29276 -262.52424) (xy 432.298099 -262.524559)
			(xy 432.305645 -262.532109) (xy 432.305968 -262.537448) (xy 432.305968 -262.537956) (xy 432.305968 -263.03224)
			(xy 438.350152 -263.03224) (xy 438.350152 -262.537702) (xy 438.350482 -262.532264) (xy 438.358176 -262.524577)
			(xy 438.363614 -262.52424) (xy 438.879742 -262.52424) (xy 438.887551 -262.523912) (xy 438.902423 -262.519137)
			(xy 438.908952 -262.514842) (xy 438.930041 -262.500493) (xy 438.975702 -262.477762) (xy 439.024308 -262.462303)
			(xy 439.074711 -262.45448) (xy 439.125717 -262.45448) (xy 439.17612 -262.462303) (xy 439.224726 -262.477762)
			(xy 439.270387 -262.500493) (xy 439.291476 -262.514842) (xy 439.298017 -262.519117) (xy 439.31288 -262.523911)
			(xy 439.320686 -262.52424) (xy 439.836814 -262.52424) (xy 439.84218 -262.524741) (xy 439.849765 -262.532335)
			(xy 439.850276 -262.537702) (xy 439.850276 -263.03224) (xy 445.89446 -263.03224) (xy 445.89446 -262.537702)
			(xy 445.894927 -262.532393) (xy 445.902369 -262.524821) (xy 445.907668 -262.52424) (xy 446.423796 -262.52424)
			(xy 446.431607 -262.523935) (xy 446.446479 -262.519144) (xy 446.453006 -262.514842) (xy 446.474095 -262.500493)
			(xy 446.519756 -262.477762) (xy 446.568362 -262.462303) (xy 446.618765 -262.45448) (xy 446.669771 -262.45448)
			(xy 446.720174 -262.462303) (xy 446.76878 -262.477762) (xy 446.814441 -262.500493) (xy 446.83553 -262.514842)
			(xy 446.842059 -262.519138) (xy 446.856931 -262.523919) (xy 446.86474 -262.52424) (xy 447.380868 -262.52424)
			(xy 447.386208 -262.524553) (xy 447.393753 -262.532108) (xy 447.394076 -262.537448) (xy 447.394076 -262.537956)
			(xy 447.394076 -263.03224) (xy 453.43826 -263.03224) (xy 453.43826 -262.537702) (xy 453.438727 -262.532393)
			(xy 453.446169 -262.524821) (xy 453.451468 -262.52424) (xy 453.967596 -262.52424) (xy 453.975407 -262.523935)
			(xy 453.990279 -262.519144) (xy 453.996806 -262.514842) (xy 454.017895 -262.500493) (xy 454.063556 -262.477762)
			(xy 454.112162 -262.462303) (xy 454.162565 -262.45448) (xy 454.213571 -262.45448) (xy 454.263974 -262.462303)
			(xy 454.31258 -262.477762) (xy 454.358241 -262.500493) (xy 454.37933 -262.514842) (xy 454.385859 -262.519138)
			(xy 454.400731 -262.523919) (xy 454.40854 -262.52424) (xy 454.924668 -262.52424) (xy 454.930008 -262.524553)
			(xy 454.937553 -262.532108) (xy 454.937876 -262.537448) (xy 454.937876 -262.537956) (xy 454.937876 -263.03224)
			(xy 454.937429 -263.037515) (xy 454.929946 -263.044958) (xy 454.924668 -263.045448) (xy 454.408794 -263.045448)
			(xy 454.40092 -263.045741) (xy 454.385916 -263.050521) (xy 454.37933 -263.054846) (xy 454.358262 -263.069252)
			(xy 454.312614 -263.092078) (xy 454.264005 -263.107631) (xy 454.213586 -263.115545) (xy 454.188068 -263.11606)
			(xy 454.162548 -263.115561) (xy 454.112121 -263.10767) (xy 454.063509 -263.092113) (xy 454.017871 -263.069261)
			(xy 453.996806 -263.054846) (xy 453.990212 -263.050535) (xy 453.975214 -263.045745) (xy 453.967342 -263.045448)
			(xy 453.451468 -263.045448) (xy 453.446211 -263.044931) (xy 453.438773 -263.037497) (xy 453.43826 -263.03224)
			(xy 447.394076 -263.03224) (xy 447.393629 -263.037515) (xy 447.386146 -263.044958) (xy 447.380868 -263.045448)
			(xy 446.864994 -263.045448) (xy 446.85712 -263.045741) (xy 446.842116 -263.050521) (xy 446.83553 -263.054846)
			(xy 446.814462 -263.069252) (xy 446.768814 -263.092078) (xy 446.720205 -263.107631) (xy 446.669786 -263.115545)
			(xy 446.644268 -263.11606) (xy 446.618748 -263.115561) (xy 446.568321 -263.10767) (xy 446.519709 -263.092113)
			(xy 446.474071 -263.069261) (xy 446.453006 -263.054846) (xy 446.446412 -263.050535) (xy 446.431414 -263.045745)
			(xy 446.423542 -263.045448) (xy 445.907668 -263.045448) (xy 445.902411 -263.044931) (xy 445.894973 -263.037497)
			(xy 445.89446 -263.03224) (xy 439.850276 -263.03224) (xy 439.849829 -263.037515) (xy 439.842346 -263.044958)
			(xy 439.837068 -263.045448) (xy 439.83656 -263.045448) (xy 439.32094 -263.045448) (xy 439.313064 -263.045718)
			(xy 439.29806 -263.050514) (xy 439.291476 -263.054846) (xy 439.270395 -263.069233) (xy 439.224752 -263.092062)
			(xy 439.176147 -263.107621) (xy 439.12573 -263.115542) (xy 439.100214 -263.11606) (xy 439.074693 -263.115588)
			(xy 439.024265 -263.107689) (xy 438.975653 -263.092124) (xy 438.930016 -263.069264) (xy 438.908952 -263.054846)
			(xy 438.90237 -263.050514) (xy 438.887363 -263.045737) (xy 438.879488 -263.045448) (xy 438.363614 -263.045448)
			(xy 438.358309 -263.044966) (xy 438.350736 -263.037535) (xy 438.350152 -263.03224) (xy 432.305968 -263.03224)
			(xy 432.305528 -263.037517) (xy 432.29804 -263.04496) (xy 432.29276 -263.045448) (xy 431.776886 -263.045448)
			(xy 431.769012 -263.045738) (xy 431.754008 -263.05052) (xy 431.747422 -263.054846) (xy 431.726357 -263.069256)
			(xy 431.680707 -263.09208) (xy 431.632098 -263.107633) (xy 431.581678 -263.115546) (xy 431.55616 -263.11606)
			(xy 431.53064 -263.115565) (xy 431.480213 -263.107673) (xy 431.431601 -263.092115) (xy 431.385963 -263.069261)
			(xy 431.364898 -263.054846) (xy 431.358306 -263.050532) (xy 431.343306 -263.045744) (xy 431.335434 -263.045448)
			(xy 430.81956 -263.045448) (xy 430.814302 -263.044936) (xy 430.806864 -263.037498) (xy 430.806352 -263.03224)
			(xy 424.762168 -263.03224) (xy 424.761728 -263.037517) (xy 424.75424 -263.04496) (xy 424.74896 -263.045448)
			(xy 424.748452 -263.045448) (xy 424.232832 -263.045448) (xy 424.224956 -263.045714) (xy 424.209952 -263.050513)
			(xy 424.203368 -263.054846) (xy 424.18229 -263.069236) (xy 424.136645 -263.092065) (xy 424.088039 -263.107623)
			(xy 424.037623 -263.115543) (xy 424.012106 -263.11606) (xy 423.986585 -263.115592) (xy 423.936157 -263.107692)
			(xy 423.887545 -263.092126) (xy 423.841908 -263.069265) (xy 423.820844 -263.054846) (xy 423.814264 -263.050511)
			(xy 423.799255 -263.045736) (xy 423.79138 -263.045448) (xy 423.275506 -263.045448) (xy 423.2702 -263.044972)
			(xy 423.262628 -263.037537) (xy 423.262044 -263.03224) (xy 417.21786 -263.03224) (xy 417.217595 -263.03759)
			(xy 417.210003 -263.045131) (xy 417.204652 -263.045448) (xy 415.731452 -263.045448) (xy 415.726193 -263.044941)
			(xy 415.718756 -263.037499) (xy 415.718244 -263.03224) (xy 308.118256 -263.03224) (xy 308.117737 -263.037496)
			(xy 308.110304 -263.044934) (xy 308.105048 -263.045448) (xy 308.10454 -263.045448) (xy 306.631594 -263.045448)
			(xy 306.626286 -263.04498) (xy 306.618715 -263.037538) (xy 306.618132 -263.03224) (xy 300.573948 -263.03224)
			(xy 300.573436 -263.037498) (xy 300.565998 -263.044936) (xy 300.56074 -263.045448) (xy 300.044866 -263.045448)
			(xy 300.036991 -263.045729) (xy 300.021987 -263.050517) (xy 300.015402 -263.054846) (xy 299.994314 -263.069221)
			(xy 299.948673 -263.092054) (xy 299.90007 -263.107616) (xy 299.849656 -263.11554) (xy 299.82414 -263.11606)
			(xy 299.79862 -263.115575) (xy 299.748192 -263.10768) (xy 299.69958 -263.092119) (xy 299.653942 -263.069262)
			(xy 299.632878 -263.054846) (xy 299.62629 -263.050524) (xy 299.611287 -263.045741) (xy 299.603414 -263.045448)
			(xy 299.08754 -263.045448) (xy 299.082292 -263.044883) (xy 299.074849 -263.037485) (xy 299.074332 -263.03224)
			(xy 293.030148 -263.03224) (xy 293.029636 -263.037498) (xy 293.022198 -263.044936) (xy 293.01694 -263.045448)
			(xy 293.016432 -263.045448) (xy 292.500812 -263.045448) (xy 292.492939 -263.045749) (xy 292.477935 -263.050524)
			(xy 292.471348 -263.054846) (xy 292.450275 -263.069245) (xy 292.404629 -263.092072) (xy 292.356021 -263.107627)
			(xy 292.305603 -263.115544) (xy 292.280086 -263.11606) (xy 292.254566 -263.115552) (xy 292.20414 -263.107664)
			(xy 292.155528 -263.09211) (xy 292.109889 -263.069259) (xy 292.088824 -263.054846) (xy 292.082226 -263.050542)
			(xy 292.067231 -263.045748) (xy 292.05936 -263.045448) (xy 291.543486 -263.045448) (xy 291.538177 -263.044985)
			(xy 291.530607 -263.03754) (xy 291.530024 -263.03224) (xy 285.48584 -263.03224) (xy 285.485335 -263.0375)
			(xy 285.477892 -263.044938) (xy 285.472632 -263.045448) (xy 284.956758 -263.045448) (xy 284.948883 -263.045726)
			(xy 284.933879 -263.050516) (xy 284.927294 -263.054846) (xy 284.906208 -263.069225) (xy 284.860567 -263.092056)
			(xy 284.811963 -263.107618) (xy 284.761548 -263.115541) (xy 284.736032 -263.11606) (xy 284.710511 -263.115579)
			(xy 284.660084 -263.107683) (xy 284.611472 -263.092121) (xy 284.565834 -263.069263) (xy 284.54477 -263.054846)
			(xy 284.538184 -263.050521) (xy 284.52318 -263.04574) (xy 284.515306 -263.045448) (xy 283.999432 -263.045448)
			(xy 283.994183 -263.044888) (xy 283.98674 -263.037487) (xy 283.986224 -263.03224) (xy 277.94204 -263.03224)
			(xy 277.941535 -263.0375) (xy 277.934092 -263.044938) (xy 277.928832 -263.045448) (xy 277.412958 -263.045448)
			(xy 277.405083 -263.045726) (xy 277.390079 -263.050516) (xy 277.383494 -263.054846) (xy 277.362408 -263.069225)
			(xy 277.316767 -263.092056) (xy 277.268163 -263.107618) (xy 277.217748 -263.115541) (xy 277.192232 -263.11606)
			(xy 277.166711 -263.115579) (xy 277.116284 -263.107683) (xy 277.067672 -263.092121) (xy 277.022034 -263.069263)
			(xy 277.00097 -263.054846) (xy 276.994384 -263.050521) (xy 276.97938 -263.04574) (xy 276.971506 -263.045448)
			(xy 276.455632 -263.045448) (xy 276.450383 -263.044888) (xy 276.44294 -263.037487) (xy 276.442424 -263.03224)
			(xy 270.39824 -263.03224) (xy 270.397735 -263.0375) (xy 270.390292 -263.044938) (xy 270.385032 -263.045448)
			(xy 270.384524 -263.045448) (xy 269.868904 -263.045448) (xy 269.86103 -263.045745) (xy 269.846026 -263.050522)
			(xy 269.83944 -263.054846) (xy 269.818369 -263.069248) (xy 269.772722 -263.092074) (xy 269.724114 -263.107629)
			(xy 269.673695 -263.115545) (xy 269.648178 -263.11606) (xy 269.622658 -263.115556) (xy 269.572232 -263.107667)
			(xy 269.52362 -263.092111) (xy 269.477981 -263.06926) (xy 269.456916 -263.054846) (xy 269.45032 -263.050539)
			(xy 269.435323 -263.045746) (xy 269.427452 -263.045448) (xy 268.911578 -263.045448) (xy 268.906268 -263.04499)
			(xy 268.898698 -263.037541) (xy 268.898116 -263.03224) (xy 206.997808 -263.03224) (xy 206.997808 -263.032494)
			(xy 206.997279 -263.037786) (xy 206.98988 -263.045355) (xy 206.9846 -263.045956) (xy 206.468726 -263.045956)
			(xy 206.460916 -263.046271) (xy 206.446044 -263.051055) (xy 206.439516 -263.055354) (xy 206.418388 -263.069693)
			(xy 206.372666 -263.092422) (xy 206.323995 -263.107855) (xy 206.27353 -263.115625) (xy 206.248 -263.11606)
			(xy 206.22247 -263.115624) (xy 206.172006 -263.107848) (xy 206.123333 -263.092419) (xy 206.077606 -263.069702)
			(xy 206.056484 -263.055354) (xy 206.049952 -263.051063) (xy 206.035083 -263.046279) (xy 206.027274 -263.045956)
			(xy 205.5114 -263.045956) (xy 205.506149 -263.04541) (xy 205.498709 -263.037997) (xy 205.498192 -263.032748)
			(xy 199.453983 -263.032748) (xy 199.453479 -263.037786) (xy 199.44608 -263.045355) (xy 199.4408 -263.045956)
			(xy 198.924926 -263.045956) (xy 198.917116 -263.046271) (xy 198.902244 -263.051055) (xy 198.895716 -263.055354)
			(xy 198.874588 -263.069693) (xy 198.828866 -263.092422) (xy 198.780195 -263.107855) (xy 198.72973 -263.115625)
			(xy 198.7042 -263.11606) (xy 198.67867 -263.115624) (xy 198.628206 -263.107848) (xy 198.579533 -263.092419)
			(xy 198.533806 -263.069702) (xy 198.512684 -263.055354) (xy 198.506152 -263.051063) (xy 198.491283 -263.046279)
			(xy 198.483474 -263.045956) (xy 197.9676 -263.045956) (xy 197.962349 -263.04541) (xy 197.954909 -263.037997)
			(xy 197.954392 -263.032748) (xy 191.910182 -263.032748) (xy 191.90965 -263.037846) (xy 191.902096 -263.04543)
			(xy 191.896746 -263.045956) (xy 191.380872 -263.045956) (xy 191.37306 -263.046248) (xy 191.358188 -263.051048)
			(xy 191.351662 -263.055354) (xy 191.330549 -263.069716) (xy 191.284822 -263.09244) (xy 191.236146 -263.107866)
			(xy 191.185678 -263.115629) (xy 191.160146 -263.11606) (xy 191.134617 -263.115601) (xy 191.084154 -263.107832)
			(xy 191.035481 -263.09241) (xy 190.989753 -263.069699) (xy 190.96863 -263.055354) (xy 190.962088 -263.051081)
			(xy 190.947226 -263.046286) (xy 190.93942 -263.045956) (xy 190.423546 -263.045956) (xy 190.418116 -263.045589)
			(xy 190.410427 -263.037923) (xy 190.410084 -263.032494) (xy 184.3659 -263.032494) (xy 184.365378 -263.037788)
			(xy 184.357974 -263.045357) (xy 184.352692 -263.045956) (xy 183.836818 -263.045956) (xy 183.829008 -263.046268)
			(xy 183.814136 -263.051054) (xy 183.807608 -263.055354) (xy 183.786482 -263.069696) (xy 183.74076 -263.092424)
			(xy 183.692088 -263.107856) (xy 183.641623 -263.115626) (xy 183.616092 -263.11606) (xy 183.590562 -263.115628)
			(xy 183.540097 -263.107851) (xy 183.491425 -263.092421) (xy 183.445698 -263.069702) (xy 183.424576 -263.055354)
			(xy 183.418046 -263.05106) (xy 183.403175 -263.046278) (xy 183.395366 -263.045956) (xy 182.879492 -263.045956)
			(xy 182.87424 -263.045416) (xy 182.8668 -263.037999) (xy 182.866284 -263.032748) (xy 176.822074 -263.032748)
			(xy 176.82155 -263.037848) (xy 176.81399 -263.045432) (xy 176.808638 -263.045956) (xy 176.292764 -263.045956)
			(xy 176.284955 -263.046288) (xy 176.270083 -263.05106) (xy 176.263554 -263.055354) (xy 176.242443 -263.06972)
			(xy 176.196715 -263.092443) (xy 176.148039 -263.107868) (xy 176.09757 -263.11563) (xy 176.072038 -263.11606)
			(xy 176.046508 -263.115605) (xy 175.996045 -263.107835) (xy 175.947373 -263.092411) (xy 175.901645 -263.069699)
			(xy 175.880522 -263.055354) (xy 175.873982 -263.051078) (xy 175.859119 -263.046285) (xy 175.851312 -263.045956)
			(xy 175.335438 -263.045956) (xy 175.330007 -263.045595) (xy 175.322318 -263.037924) (xy 175.321976 -263.032494)
			(xy 169.277792 -263.032494) (xy 169.277277 -263.03779) (xy 169.269868 -263.04536) (xy 169.264584 -263.045956)
			(xy 167.791384 -263.045956) (xy 167.786131 -263.045421) (xy 167.778692 -263.038) (xy 167.778176 -263.032748)
			(xy 60.178162 -263.032748) (xy 60.177648 -263.037851) (xy 60.170082 -263.045436) (xy 60.164726 -263.045956)
			(xy 58.691526 -263.045956) (xy 58.686093 -263.045603) (xy 58.678405 -263.037926) (xy 58.678064 -263.032494)
			(xy 52.63388 -263.032494) (xy 52.633375 -263.037793) (xy 52.62596 -263.045363) (xy 52.620672 -263.045956)
			(xy 52.104798 -263.045956) (xy 52.096987 -263.04626) (xy 52.082115 -263.051052) (xy 52.075588 -263.055354)
			(xy 52.054467 -263.069705) (xy 52.008743 -263.092431) (xy 51.96007 -263.107861) (xy 51.909603 -263.115627)
			(xy 51.884072 -263.11606) (xy 51.858541 -263.115638) (xy 51.808077 -263.107858) (xy 51.759404 -263.092425)
			(xy 51.713677 -263.069704) (xy 51.692556 -263.055354) (xy 51.68603 -263.051052) (xy 51.671156 -263.046275)
			(xy 51.663346 -263.045956) (xy 51.147472 -263.045956) (xy 51.142217 -263.045429) (xy 51.134779 -263.038002)
			(xy 51.134264 -263.032748) (xy 45.090055 -263.032748) (xy 45.089548 -263.037853) (xy 45.081976 -263.045438)
			(xy 45.076618 -263.045956) (xy 44.560744 -263.045956) (xy 44.552935 -263.046279) (xy 44.538063 -263.051058)
			(xy 44.531534 -263.055354) (xy 44.510429 -263.069728) (xy 44.464699 -263.092449) (xy 44.416021 -263.107872)
			(xy 44.36555 -263.115631) (xy 44.340018 -263.11606) (xy 44.314488 -263.115615) (xy 44.264025 -263.107842)
			(xy 44.215352 -263.092415) (xy 44.169624 -263.069701) (xy 44.148502 -263.055354) (xy 44.141966 -263.05107)
			(xy 44.1271 -263.046282) (xy 44.119292 -263.045956) (xy 43.603418 -263.045956) (xy 43.597984 -263.045608)
			(xy 43.590297 -263.037928) (xy 43.589956 -263.032494) (xy 37.545772 -263.032494) (xy 37.545274 -263.037795)
			(xy 37.537854 -263.045365) (xy 37.532564 -263.045956) (xy 37.01669 -263.045956) (xy 37.008878 -263.046256)
			(xy 36.994007 -263.05105) (xy 36.98748 -263.055354) (xy 36.966362 -263.069708) (xy 36.920637 -263.092434)
			(xy 36.871962 -263.107862) (xy 36.821495 -263.115628) (xy 36.795964 -263.11606) (xy 36.770433 -263.115642)
			(xy 36.719968 -263.107861) (xy 36.671296 -263.092426) (xy 36.625569 -263.069704) (xy 36.604448 -263.055354)
			(xy 36.597924 -263.051049) (xy 36.583048 -263.046274) (xy 36.575238 -263.045956) (xy 36.059364 -263.045956)
			(xy 36.054109 -263.045434) (xy 36.046671 -263.038003) (xy 36.046156 -263.032748) (xy 30.001948 -263.032748)
			(xy 30.001474 -263.037795) (xy 29.994054 -263.045365) (xy 29.988764 -263.045956) (xy 29.47289 -263.045956)
			(xy 29.465078 -263.046256) (xy 29.450207 -263.05105) (xy 29.44368 -263.055354) (xy 29.422562 -263.069708)
			(xy 29.376837 -263.092434) (xy 29.328162 -263.107862) (xy 29.277695 -263.115628) (xy 29.252164 -263.11606)
			(xy 29.226633 -263.115642) (xy 29.176168 -263.107861) (xy 29.127496 -263.092426) (xy 29.081769 -263.069704)
			(xy 29.060648 -263.055354) (xy 29.054124 -263.051049) (xy 29.039248 -263.046274) (xy 29.031438 -263.045956)
			(xy 28.515564 -263.045956) (xy 28.510309 -263.045434) (xy 28.502871 -263.038003) (xy 28.502356 -263.032748)
			(xy 22.458147 -263.032748) (xy 22.457647 -263.037855) (xy 22.45007 -263.04544) (xy 22.44471 -263.045956)
			(xy 21.928836 -263.045956) (xy 21.921026 -263.046276) (xy 21.906155 -263.051057) (xy 21.899626 -263.055354)
			(xy 21.878495 -263.069688) (xy 21.832774 -263.092418) (xy 21.784104 -263.107853) (xy 21.73364 -263.115624)
			(xy 21.70811 -263.11606) (xy 21.68258 -263.115619) (xy 21.632116 -263.107845) (xy 21.583444 -263.092417)
			(xy 21.537716 -263.069701) (xy 21.516594 -263.055354) (xy 21.51006 -263.051067) (xy 21.495192 -263.04628)
			(xy 21.487384 -263.045956) (xy 20.97151 -263.045956) (xy 20.966075 -263.045614) (xy 20.958388 -263.037929)
			(xy 20.958048 -263.032494) (xy 2.509012 -263.032494) (xy 2.509012 -263.882378) (xy 16.85798 -263.882378)
			(xy 16.85798 -263.38784) (xy 16.858353 -263.382516) (xy 16.865865 -263.374974) (xy 16.871188 -263.374632)
			(xy 16.871696 -263.374632) (xy 17.38757 -263.374632) (xy 17.39538 -263.374317) (xy 17.410252 -263.369533)
			(xy 17.41678 -263.365234) (xy 17.437869 -263.350885) (xy 17.48353 -263.328154) (xy 17.532136 -263.312695)
			(xy 17.582539 -263.304872) (xy 17.633545 -263.304872) (xy 17.683948 -263.312695) (xy 17.732554 -263.328154)
			(xy 17.778215 -263.350885) (xy 17.799304 -263.365234) (xy 17.805839 -263.369519) (xy 17.820706 -263.374307)
			(xy 17.828514 -263.374632) (xy 18.344642 -263.374632) (xy 18.34995 -263.375094) (xy 18.357518 -263.382541)
			(xy 18.358104 -263.38784) (xy 18.358104 -263.882378) (xy 18.358077 -263.882632) (xy 24.402288 -263.882632)
			(xy 24.402288 -263.882124) (xy 24.402288 -263.38784) (xy 24.402653 -263.382514) (xy 24.410171 -263.374971)
			(xy 24.415496 -263.374632) (xy 24.931624 -263.374632) (xy 24.939436 -263.37434) (xy 24.954308 -263.36954)
			(xy 24.960834 -263.365234) (xy 24.981923 -263.350885) (xy 25.027584 -263.328154) (xy 25.07619 -263.312695)
			(xy 25.126593 -263.304872) (xy 25.177599 -263.304872) (xy 25.228002 -263.312695) (xy 25.276608 -263.328154)
			(xy 25.322269 -263.350885) (xy 25.343358 -263.365234) (xy 25.349881 -263.36954) (xy 25.364757 -263.374315)
			(xy 25.372568 -263.374632) (xy 25.888696 -263.374632) (xy 25.894037 -263.374934) (xy 25.901581 -263.382498)
			(xy 25.901904 -263.38784) (xy 25.901904 -263.882378) (xy 25.901878 -263.882632) (xy 31.946088 -263.882632)
			(xy 31.946088 -263.882124) (xy 31.946088 -263.38784) (xy 31.946453 -263.382514) (xy 31.953971 -263.374971)
			(xy 31.959296 -263.374632) (xy 32.475424 -263.374632) (xy 32.483236 -263.37434) (xy 32.498108 -263.36954)
			(xy 32.504634 -263.365234) (xy 32.525723 -263.350885) (xy 32.571384 -263.328154) (xy 32.61999 -263.312695)
			(xy 32.670393 -263.304872) (xy 32.721399 -263.304872) (xy 32.771802 -263.312695) (xy 32.820408 -263.328154)
			(xy 32.866069 -263.350885) (xy 32.887158 -263.365234) (xy 32.893681 -263.36954) (xy 32.908557 -263.374315)
			(xy 32.916368 -263.374632) (xy 33.432496 -263.374632) (xy 33.437837 -263.374934) (xy 33.445381 -263.382498)
			(xy 33.445704 -263.38784) (xy 33.445704 -263.882378) (xy 39.489888 -263.882378) (xy 39.489888 -263.38784)
			(xy 39.490253 -263.382514) (xy 39.497771 -263.374971) (xy 39.503096 -263.374632) (xy 39.503604 -263.374632)
			(xy 40.019478 -263.374632) (xy 40.027288 -263.37432) (xy 40.04216 -263.369534) (xy 40.048688 -263.365234)
			(xy 40.069777 -263.350885) (xy 40.115438 -263.328154) (xy 40.164044 -263.312695) (xy 40.214447 -263.304872)
			(xy 40.265453 -263.304872) (xy 40.315856 -263.312695) (xy 40.364462 -263.328154) (xy 40.410123 -263.350885)
			(xy 40.431212 -263.365234) (xy 40.437745 -263.369522) (xy 40.452614 -263.374308) (xy 40.460422 -263.374632)
			(xy 40.97655 -263.374632) (xy 40.981846 -263.375156) (xy 40.98942 -263.382556) (xy 40.990012 -263.38784)
			(xy 40.990012 -263.882378) (xy 40.989985 -263.882632) (xy 47.034196 -263.882632) (xy 47.034196 -263.882124)
			(xy 47.034196 -263.38784) (xy 47.034554 -263.382512) (xy 47.042077 -263.374969) (xy 47.047404 -263.374632)
			(xy 47.563532 -263.374632) (xy 47.571341 -263.374301) (xy 47.586213 -263.369528) (xy 47.592742 -263.365234)
			(xy 47.613831 -263.350885) (xy 47.659492 -263.328154) (xy 47.708098 -263.312695) (xy 47.758501 -263.304872)
			(xy 47.809507 -263.304872) (xy 47.85991 -263.312695) (xy 47.908516 -263.328154) (xy 47.954177 -263.350885)
			(xy 47.975266 -263.365234) (xy 47.98181 -263.369505) (xy 47.99667 -263.374302) (xy 48.004476 -263.374632)
			(xy 48.520604 -263.374632) (xy 48.525947 -263.374928) (xy 48.53349 -263.382496) (xy 48.533812 -263.38784)
			(xy 48.533812 -263.882378) (xy 54.577996 -263.882378) (xy 54.577996 -263.38784) (xy 54.578354 -263.382512)
			(xy 54.585877 -263.374969) (xy 54.591204 -263.374632) (xy 56.064658 -263.374632) (xy 56.069955 -263.37515)
			(xy 56.077528 -263.382555) (xy 56.07812 -263.38784) (xy 56.07812 -263.882378) (xy 56.078105 -263.882632)
			(xy 163.678108 -263.882632) (xy 163.678108 -263.882124) (xy 163.678108 -263.38784) (xy 163.678455 -263.382509)
			(xy 163.685986 -263.374965) (xy 163.691316 -263.374632) (xy 165.164516 -263.374632) (xy 165.16986 -263.37492)
			(xy 165.177403 -263.382494) (xy 165.177724 -263.38784) (xy 165.177724 -263.882378) (xy 171.221908 -263.882378)
			(xy 171.221908 -263.38784) (xy 171.222255 -263.382509) (xy 171.229786 -263.374965) (xy 171.235116 -263.374632)
			(xy 171.235624 -263.374632) (xy 171.751498 -263.374632) (xy 171.759309 -263.374329) (xy 171.774181 -263.369537)
			(xy 171.780708 -263.365234) (xy 171.801797 -263.350885) (xy 171.847458 -263.328154) (xy 171.896064 -263.312695)
			(xy 171.946467 -263.304872) (xy 171.997473 -263.304872) (xy 172.047876 -263.312695) (xy 172.096482 -263.328154)
			(xy 172.142143 -263.350885) (xy 172.163232 -263.365234) (xy 172.169761 -263.36953) (xy 172.184633 -263.374311)
			(xy 172.192442 -263.374632) (xy 172.70857 -263.374632) (xy 172.713869 -263.375142) (xy 172.721441 -263.382553)
			(xy 172.722032 -263.38784) (xy 172.722032 -263.882378) (xy 172.722017 -263.882632) (xy 178.766216 -263.882632)
			(xy 178.766216 -263.882124) (xy 178.766216 -263.38784) (xy 178.766556 -263.382507) (xy 178.774092 -263.374963)
			(xy 178.779424 -263.374632) (xy 179.295552 -263.374632) (xy 179.303361 -263.374309) (xy 179.318233 -263.369531)
			(xy 179.324762 -263.365234) (xy 179.345851 -263.350885) (xy 179.391512 -263.328154) (xy 179.440118 -263.312695)
			(xy 179.490521 -263.304872) (xy 179.541527 -263.304872) (xy 179.59193 -263.312695) (xy 179.640536 -263.328154)
			(xy 179.686197 -263.350885) (xy 179.707286 -263.365234) (xy 179.713825 -263.369512) (xy 179.728689 -263.374305)
			(xy 179.736496 -263.374632) (xy 180.252624 -263.374632) (xy 180.257969 -263.374915) (xy 180.265511 -263.382493)
			(xy 180.265832 -263.38784) (xy 180.265832 -263.882378) (xy 186.310016 -263.882378) (xy 186.310016 -263.38784)
			(xy 186.310356 -263.382507) (xy 186.317892 -263.374963) (xy 186.323224 -263.374632) (xy 186.323732 -263.374632)
			(xy 186.839606 -263.374632) (xy 186.847418 -263.374332) (xy 186.862289 -263.369538) (xy 186.868816 -263.365234)
			(xy 186.889905 -263.350885) (xy 186.935566 -263.328154) (xy 186.984172 -263.312695) (xy 187.034575 -263.304872)
			(xy 187.085581 -263.304872) (xy 187.135984 -263.312695) (xy 187.18459 -263.328154) (xy 187.230251 -263.350885)
			(xy 187.25134 -263.365234) (xy 187.257867 -263.369533) (xy 187.27274 -263.374312) (xy 187.28055 -263.374632)
			(xy 187.796678 -263.374632) (xy 187.801978 -263.375137) (xy 187.80955 -263.382551) (xy 187.81014 -263.38784)
			(xy 187.81014 -263.882378) (xy 187.810124 -263.882632) (xy 193.854324 -263.882632) (xy 193.854324 -263.882124)
			(xy 193.854324 -263.38784) (xy 193.854657 -263.382505) (xy 193.862198 -263.37496) (xy 193.867532 -263.374632)
			(xy 194.38366 -263.374632) (xy 194.39147 -263.374313) (xy 194.406342 -263.369532) (xy 194.41287 -263.365234)
			(xy 194.433959 -263.350885) (xy 194.47962 -263.328154) (xy 194.528226 -263.312695) (xy 194.578629 -263.304872)
			(xy 194.629635 -263.304872) (xy 194.680038 -263.312695) (xy 194.728644 -263.328154) (xy 194.774305 -263.350885)
			(xy 194.795394 -263.365234) (xy 194.801931 -263.369515) (xy 194.816797 -263.374306) (xy 194.824604 -263.374632)
			(xy 195.340732 -263.374632) (xy 195.346078 -263.374909) (xy 195.35362 -263.382492) (xy 195.35394 -263.38784)
			(xy 195.35394 -263.882378) (xy 195.353917 -263.882632) (xy 201.398124 -263.882632) (xy 201.398124 -263.882124)
			(xy 201.398124 -263.38784) (xy 201.398457 -263.382505) (xy 201.405998 -263.37496) (xy 201.411332 -263.374632)
			(xy 201.92746 -263.374632) (xy 201.93527 -263.374313) (xy 201.950142 -263.369532) (xy 201.95667 -263.365234)
			(xy 201.977759 -263.350885) (xy 202.02342 -263.328154) (xy 202.072026 -263.312695) (xy 202.122429 -263.304872)
			(xy 202.173435 -263.304872) (xy 202.223838 -263.312695) (xy 202.272444 -263.328154) (xy 202.318105 -263.350885)
			(xy 202.339194 -263.365234) (xy 202.345731 -263.369515) (xy 202.360597 -263.374306) (xy 202.368404 -263.374632)
			(xy 202.884532 -263.374632) (xy 202.889878 -263.374909) (xy 202.89742 -263.382492) (xy 202.89774 -263.38784)
			(xy 202.89774 -263.882124) (xy 264.798048 -263.882124) (xy 264.798048 -263.387586) (xy 264.798542 -263.382218)
			(xy 264.806141 -263.374633) (xy 264.81151 -263.374124) (xy 265.327638 -263.374124) (xy 265.335447 -263.373797)
			(xy 265.350319 -263.369022) (xy 265.356848 -263.364726) (xy 265.377937 -263.350377) (xy 265.423598 -263.327646)
			(xy 265.472204 -263.312187) (xy 265.522607 -263.304364) (xy 265.573613 -263.304364) (xy 265.624016 -263.312187)
			(xy 265.672622 -263.327646) (xy 265.718283 -263.350377) (xy 265.739372 -263.364726) (xy 265.745915 -263.368998)
			(xy 265.760776 -263.373794) (xy 265.768582 -263.374124) (xy 266.28471 -263.374124) (xy 266.290072 -263.374642)
			(xy 266.297656 -263.382224) (xy 266.298172 -263.387586) (xy 266.298172 -263.882124) (xy 272.342356 -263.882124)
			(xy 272.342356 -263.387586) (xy 272.342816 -263.382276) (xy 272.350263 -263.374705) (xy 272.355564 -263.374124)
			(xy 272.871692 -263.374124) (xy 272.879503 -263.37382) (xy 272.894375 -263.369029) (xy 272.900902 -263.364726)
			(xy 272.921991 -263.350377) (xy 272.967652 -263.327646) (xy 273.016258 -263.312187) (xy 273.066661 -263.304364)
			(xy 273.117667 -263.304364) (xy 273.16807 -263.312187) (xy 273.216676 -263.327646) (xy 273.262337 -263.350377)
			(xy 273.283426 -263.364726) (xy 273.289957 -263.369019) (xy 273.304827 -263.373802) (xy 273.312636 -263.374124)
			(xy 273.828764 -263.374124) (xy 273.834099 -263.374454) (xy 273.841644 -263.381997) (xy 273.841972 -263.387332)
			(xy 273.841972 -263.38784) (xy 273.841972 -263.882124) (xy 279.886156 -263.882124) (xy 279.886156 -263.387586)
			(xy 279.886616 -263.382276) (xy 279.894063 -263.374705) (xy 279.899364 -263.374124) (xy 280.415492 -263.374124)
			(xy 280.423303 -263.37382) (xy 280.438175 -263.369029) (xy 280.444702 -263.364726) (xy 280.465791 -263.350377)
			(xy 280.511452 -263.327646) (xy 280.560058 -263.312187) (xy 280.610461 -263.304364) (xy 280.661467 -263.304364)
			(xy 280.71187 -263.312187) (xy 280.760476 -263.327646) (xy 280.806137 -263.350377) (xy 280.827226 -263.364726)
			(xy 280.833757 -263.369019) (xy 280.848627 -263.373802) (xy 280.856436 -263.374124) (xy 281.372564 -263.374124)
			(xy 281.377899 -263.374454) (xy 281.385444 -263.381997) (xy 281.385772 -263.387332) (xy 281.385772 -263.38784)
			(xy 281.385772 -263.882124) (xy 287.429956 -263.882124) (xy 287.429956 -263.387586) (xy 287.430272 -263.382145)
			(xy 287.437976 -263.374459) (xy 287.443418 -263.374124) (xy 287.959546 -263.374124) (xy 287.967355 -263.3738)
			(xy 287.982227 -263.369023) (xy 287.988756 -263.364726) (xy 288.009845 -263.350377) (xy 288.055506 -263.327646)
			(xy 288.104112 -263.312187) (xy 288.154515 -263.304364) (xy 288.205521 -263.304364) (xy 288.255924 -263.312187)
			(xy 288.30453 -263.327646) (xy 288.350191 -263.350377) (xy 288.37128 -263.364726) (xy 288.377821 -263.369001)
			(xy 288.392684 -263.373796) (xy 288.40049 -263.374124) (xy 288.916618 -263.374124) (xy 288.921981 -263.374637)
			(xy 288.929565 -263.382223) (xy 288.93008 -263.387586) (xy 288.93008 -263.882124) (xy 294.974264 -263.882124)
			(xy 294.974264 -263.387586) (xy 294.974717 -263.382275) (xy 294.982169 -263.374703) (xy 294.987472 -263.374124)
			(xy 295.5036 -263.374124) (xy 295.511411 -263.373823) (xy 295.526283 -263.36903) (xy 295.53281 -263.364726)
			(xy 295.553899 -263.350377) (xy 295.59956 -263.327646) (xy 295.648166 -263.312187) (xy 295.698569 -263.304364)
			(xy 295.749575 -263.304364) (xy 295.799978 -263.312187) (xy 295.848584 -263.327646) (xy 295.894245 -263.350377)
			(xy 295.915334 -263.364726) (xy 295.921863 -263.369022) (xy 295.936735 -263.373803) (xy 295.944544 -263.374124)
			(xy 296.460672 -263.374124) (xy 296.466008 -263.374449) (xy 296.473553 -263.381996) (xy 296.47388 -263.387332)
			(xy 296.47388 -263.38784) (xy 296.47388 -263.882124) (xy 302.518064 -263.882124) (xy 302.518064 -263.387586)
			(xy 302.518373 -263.382143) (xy 302.526082 -263.374456) (xy 302.531526 -263.374124) (xy 304.004726 -263.374124)
			(xy 304.01009 -263.374632) (xy 304.017673 -263.382222) (xy 304.018188 -263.387586) (xy 304.018188 -263.882124)
			(xy 411.618176 -263.882124) (xy 411.618176 -263.387586) (xy 411.618618 -263.382272) (xy 411.626078 -263.374699)
			(xy 411.631384 -263.374124) (xy 413.104584 -263.374124) (xy 413.109922 -263.374441) (xy 413.117466 -263.381994)
			(xy 413.117792 -263.387332) (xy 413.117792 -263.38784) (xy 413.117792 -263.882124) (xy 419.161976 -263.882124)
			(xy 419.161976 -263.387586) (xy 419.162274 -263.38214) (xy 419.169991 -263.374453) (xy 419.175438 -263.374124)
			(xy 419.691566 -263.374124) (xy 419.699376 -263.373809) (xy 419.714248 -263.369025) (xy 419.720776 -263.364726)
			(xy 419.741865 -263.350377) (xy 419.787526 -263.327646) (xy 419.836132 -263.312187) (xy 419.886535 -263.304364)
			(xy 419.937541 -263.304364) (xy 419.987944 -263.312187) (xy 420.03655 -263.327646) (xy 420.082211 -263.350377)
			(xy 420.1033 -263.364726) (xy 420.109837 -263.369009) (xy 420.124703 -263.373798) (xy 420.13251 -263.374124)
			(xy 420.648638 -263.374124) (xy 420.654003 -263.374624) (xy 420.661586 -263.38222) (xy 420.6621 -263.387586)
			(xy 420.6621 -263.882124) (xy 426.706284 -263.882124) (xy 426.706284 -263.387586) (xy 426.706719 -263.38227)
			(xy 426.714184 -263.374697) (xy 426.719492 -263.374124) (xy 427.23562 -263.374124) (xy 427.243432 -263.373831)
			(xy 427.258304 -263.369032) (xy 427.26483 -263.364726) (xy 427.285919 -263.350377) (xy 427.33158 -263.327646)
			(xy 427.380186 -263.312187) (xy 427.430589 -263.304364) (xy 427.481595 -263.304364) (xy 427.531998 -263.312187)
			(xy 427.580604 -263.327646) (xy 427.626265 -263.350377) (xy 427.647354 -263.364726) (xy 427.653879 -263.36903)
			(xy 427.668754 -263.373806) (xy 427.676564 -263.374124) (xy 428.192692 -263.374124) (xy 428.198031 -263.374435)
			(xy 428.205574 -263.381992) (xy 428.2059 -263.387332) (xy 428.2059 -263.38784) (xy 428.2059 -263.882124)
			(xy 434.250084 -263.882124) (xy 434.250084 -263.387586) (xy 434.250375 -263.382138) (xy 434.258097 -263.37445)
			(xy 434.263546 -263.374124) (xy 434.779674 -263.374124) (xy 434.787484 -263.373812) (xy 434.802356 -263.369026)
			(xy 434.808884 -263.364726) (xy 434.829973 -263.350377) (xy 434.875634 -263.327646) (xy 434.92424 -263.312187)
			(xy 434.974643 -263.304364) (xy 435.025649 -263.304364) (xy 435.076052 -263.312187) (xy 435.124658 -263.327646)
			(xy 435.170319 -263.350377) (xy 435.191408 -263.364726) (xy 435.197943 -263.369012) (xy 435.21281 -263.3738)
			(xy 435.220618 -263.374124) (xy 435.736746 -263.374124) (xy 435.742112 -263.374619) (xy 435.749694 -263.382219)
			(xy 435.750208 -263.387586) (xy 435.750208 -263.882124) (xy 441.794392 -263.882124) (xy 441.794392 -263.387586)
			(xy 441.794908 -263.382291) (xy 441.802317 -263.374724) (xy 441.8076 -263.374124) (xy 442.323728 -263.374124)
			(xy 442.331541 -263.373835) (xy 442.346412 -263.369033) (xy 442.352938 -263.364726) (xy 442.374027 -263.350377)
			(xy 442.419688 -263.327646) (xy 442.468294 -263.312187) (xy 442.518697 -263.304364) (xy 442.569703 -263.304364)
			(xy 442.620106 -263.312187) (xy 442.668712 -263.327646) (xy 442.714373 -263.350377) (xy 442.735462 -263.364726)
			(xy 442.742007 -263.368994) (xy 442.756866 -263.373793) (xy 442.764672 -263.374124) (xy 443.2808 -263.374124)
			(xy 443.28614 -263.37443) (xy 443.293683 -263.381991) (xy 443.294008 -263.387332) (xy 443.294008 -263.38784)
			(xy 443.294008 -263.882124) (xy 449.338192 -263.882124) (xy 449.338192 -263.387586) (xy 449.338708 -263.382291)
			(xy 449.346117 -263.374724) (xy 449.3514 -263.374124) (xy 449.867528 -263.374124) (xy 449.875341 -263.373835)
			(xy 449.890212 -263.369033) (xy 449.896738 -263.364726) (xy 449.917827 -263.350377) (xy 449.963488 -263.327646)
			(xy 450.012094 -263.312187) (xy 450.062497 -263.304364) (xy 450.113503 -263.304364) (xy 450.163906 -263.312187)
			(xy 450.212512 -263.327646) (xy 450.258173 -263.350377) (xy 450.279262 -263.364726) (xy 450.285807 -263.368994)
			(xy 450.300666 -263.373793) (xy 450.308472 -263.374124) (xy 450.8246 -263.374124) (xy 450.82994 -263.37443)
			(xy 450.837483 -263.381991) (xy 450.837808 -263.387332) (xy 450.837808 -263.38784) (xy 450.837808 -263.882124)
			(xy 450.837321 -263.88739) (xy 450.829866 -263.894831) (xy 450.8246 -263.895332) (xy 450.308726 -263.895332)
			(xy 450.30085 -263.895598) (xy 450.285846 -263.900397) (xy 450.279262 -263.90473) (xy 450.258184 -263.919121)
			(xy 450.21254 -263.94195) (xy 450.163934 -263.957508) (xy 450.113517 -263.965427) (xy 450.088 -263.965944)
			(xy 450.06248 -263.965463) (xy 450.012053 -263.957565) (xy 449.963441 -263.942002) (xy 449.917803 -263.919146)
			(xy 449.896738 -263.90473) (xy 449.890138 -263.90043) (xy 449.875145 -263.895634) (xy 449.867274 -263.895332)
			(xy 449.3514 -263.895332) (xy 449.346143 -263.894808) (xy 449.338702 -263.88738) (xy 449.338192 -263.882124)
			(xy 443.294008 -263.882124) (xy 443.293521 -263.88739) (xy 443.286066 -263.894831) (xy 443.2808 -263.895332)
			(xy 442.764926 -263.895332) (xy 442.75705 -263.895598) (xy 442.742046 -263.900397) (xy 442.735462 -263.90473)
			(xy 442.714384 -263.919121) (xy 442.66874 -263.94195) (xy 442.620134 -263.957508) (xy 442.569717 -263.965427)
			(xy 442.5442 -263.965944) (xy 442.51868 -263.965463) (xy 442.468253 -263.957565) (xy 442.419641 -263.942002)
			(xy 442.374003 -263.919146) (xy 442.352938 -263.90473) (xy 442.346338 -263.90043) (xy 442.331345 -263.895634)
			(xy 442.323474 -263.895332) (xy 441.8076 -263.895332) (xy 441.802343 -263.894808) (xy 441.794902 -263.88738)
			(xy 441.794392 -263.882124) (xy 435.750208 -263.882124) (xy 435.749721 -263.88739) (xy 435.742266 -263.894831)
			(xy 435.737 -263.895332) (xy 435.736492 -263.895332) (xy 435.220872 -263.895332) (xy 435.212997 -263.895618)
			(xy 435.197993 -263.900403) (xy 435.191408 -263.90473) (xy 435.170345 -263.919144) (xy 435.124695 -263.941968)
			(xy 435.076085 -263.95752) (xy 435.025664 -263.965431) (xy 435.000146 -263.965944) (xy 434.974626 -263.96544)
			(xy 434.9242 -263.957549) (xy 434.875589 -263.941993) (xy 434.82995 -263.919143) (xy 434.808884 -263.90473)
			(xy 434.802296 -263.900409) (xy 434.787293 -263.895626) (xy 434.77942 -263.895332) (xy 434.263546 -263.895332)
			(xy 434.258241 -263.894843) (xy 434.250666 -263.887418) (xy 434.250084 -263.882124) (xy 428.2059 -263.882124)
			(xy 428.20542 -263.887392) (xy 428.197961 -263.894833) (xy 428.192692 -263.895332) (xy 427.676818 -263.895332)
			(xy 427.668945 -263.895638) (xy 427.653941 -263.90041) (xy 427.647354 -263.90473) (xy 427.626278 -263.919124)
			(xy 427.580633 -263.941953) (xy 427.532026 -263.95751) (xy 427.481609 -263.965428) (xy 427.456092 -263.965944)
			(xy 427.430573 -263.965417) (xy 427.380148 -263.957533) (xy 427.331537 -263.941983) (xy 427.285897 -263.91914)
			(xy 427.26483 -263.90473) (xy 427.258232 -263.900427) (xy 427.243237 -263.895632) (xy 427.235366 -263.895332)
			(xy 426.719492 -263.895332) (xy 426.714234 -263.894813) (xy 426.706793 -263.887381) (xy 426.706284 -263.882124)
			(xy 420.6621 -263.882124) (xy 420.66162 -263.887392) (xy 420.654161 -263.894833) (xy 420.648892 -263.895332)
			(xy 420.648384 -263.895332) (xy 420.132764 -263.895332) (xy 420.124889 -263.895615) (xy 420.109885 -263.900402)
			(xy 420.1033 -263.90473) (xy 420.082211 -263.919104) (xy 420.036571 -263.941937) (xy 419.987968 -263.9575)
			(xy 419.937554 -263.965424) (xy 419.912038 -263.965944) (xy 419.886518 -263.965444) (xy 419.836092 -263.957551)
			(xy 419.787481 -263.941994) (xy 419.741842 -263.919143) (xy 419.720776 -263.90473) (xy 419.71419 -263.900406)
			(xy 419.699186 -263.895624) (xy 419.691312 -263.895332) (xy 419.175438 -263.895332) (xy 419.170132 -263.894848)
			(xy 419.162557 -263.88742) (xy 419.161976 -263.882124) (xy 413.117792 -263.882124) (xy 413.117319 -263.887393)
			(xy 413.109855 -263.894835) (xy 413.104584 -263.895332) (xy 411.631384 -263.895332) (xy 411.626125 -263.894819)
			(xy 411.618685 -263.887383) (xy 411.618176 -263.882124) (xy 304.018188 -263.882124) (xy 304.017719 -263.887394)
			(xy 304.010252 -263.894837) (xy 304.00498 -263.895332) (xy 302.531526 -263.895332) (xy 302.526218 -263.894856)
			(xy 302.518644 -263.887422) (xy 302.518064 -263.882124) (xy 296.47388 -263.882124) (xy 296.473586 -263.887466)
			(xy 296.466016 -263.895007) (xy 296.460672 -263.895332) (xy 295.944798 -263.895332) (xy 295.936924 -263.89563)
			(xy 295.921921 -263.900407) (xy 295.915334 -263.90473) (xy 295.894264 -263.919133) (xy 295.848617 -263.941959)
			(xy 295.800008 -263.957514) (xy 295.749589 -263.965429) (xy 295.724072 -263.965944) (xy 295.698553 -263.965427)
			(xy 295.648128 -263.95754) (xy 295.599516 -263.941987) (xy 295.553876 -263.919141) (xy 295.53281 -263.90473)
			(xy 295.526216 -263.900419) (xy 295.511218 -263.895629) (xy 295.503346 -263.895332) (xy 294.987472 -263.895332)
			(xy 294.982212 -263.894826) (xy 294.974772 -263.887385) (xy 294.974264 -263.882124) (xy 288.93008 -263.882124)
			(xy 288.929786 -263.887466) (xy 288.922216 -263.895007) (xy 288.916872 -263.895332) (xy 288.916364 -263.895332)
			(xy 288.400744 -263.895332) (xy 288.392868 -263.895606) (xy 288.377864 -263.900399) (xy 288.37128 -263.90473)
			(xy 288.350197 -263.919113) (xy 288.304554 -263.941944) (xy 288.25595 -263.957504) (xy 288.205534 -263.965426)
			(xy 288.180018 -263.965944) (xy 288.154498 -263.965454) (xy 288.104071 -263.957558) (xy 288.05546 -263.941998)
			(xy 288.009821 -263.919144) (xy 287.988756 -263.90473) (xy 287.982174 -263.900398) (xy 287.967167 -263.895621)
			(xy 287.959292 -263.895332) (xy 287.443418 -263.895332) (xy 287.438109 -263.894862) (xy 287.430536 -263.887423)
			(xy 287.429956 -263.882124) (xy 281.385772 -263.882124) (xy 281.385486 -263.887468) (xy 281.37791 -263.89501)
			(xy 281.372564 -263.895332) (xy 280.85669 -263.895332) (xy 280.848816 -263.895626) (xy 280.833812 -263.900406)
			(xy 280.827226 -263.90473) (xy 280.806158 -263.919136) (xy 280.76051 -263.941962) (xy 280.711901 -263.957516)
			(xy 280.661482 -263.96543) (xy 280.635964 -263.965944) (xy 280.610445 -263.965431) (xy 280.560019 -263.957542)
			(xy 280.511408 -263.941989) (xy 280.465768 -263.919141) (xy 280.444702 -263.90473) (xy 280.43811 -263.900416)
			(xy 280.42311 -263.895628) (xy 280.415238 -263.895332) (xy 279.899364 -263.895332) (xy 279.894103 -263.894831)
			(xy 279.886664 -263.887386) (xy 279.886156 -263.882124) (xy 273.841972 -263.882124) (xy 273.841686 -263.887468)
			(xy 273.83411 -263.89501) (xy 273.828764 -263.895332) (xy 273.31289 -263.895332) (xy 273.305016 -263.895626)
			(xy 273.290012 -263.900406) (xy 273.283426 -263.90473) (xy 273.262358 -263.919136) (xy 273.21671 -263.941962)
			(xy 273.168101 -263.957516) (xy 273.117682 -263.96543) (xy 273.092164 -263.965944) (xy 273.066645 -263.965431)
			(xy 273.016219 -263.957542) (xy 272.967608 -263.941989) (xy 272.921968 -263.919141) (xy 272.900902 -263.90473)
			(xy 272.89431 -263.900416) (xy 272.87931 -263.895628) (xy 272.871438 -263.895332) (xy 272.355564 -263.895332)
			(xy 272.350303 -263.894831) (xy 272.342864 -263.887386) (xy 272.342356 -263.882124) (xy 266.298172 -263.882124)
			(xy 266.297886 -263.887468) (xy 266.29031 -263.89501) (xy 266.284964 -263.895332) (xy 266.284456 -263.895332)
			(xy 265.768836 -263.895332) (xy 265.76096 -263.895603) (xy 265.745956 -263.900398) (xy 265.739372 -263.90473)
			(xy 265.718291 -263.919117) (xy 265.672648 -263.941947) (xy 265.624043 -263.957506) (xy 265.573626 -263.965426)
			(xy 265.54811 -263.965944) (xy 265.52259 -263.965458) (xy 265.472163 -263.957561) (xy 265.423552 -263.942)
			(xy 265.377913 -263.919145) (xy 265.356848 -263.90473) (xy 265.350268 -263.900395) (xy 265.335259 -263.89562)
			(xy 265.327384 -263.895332) (xy 264.81151 -263.895332) (xy 264.806201 -263.894867) (xy 264.798627 -263.887424)
			(xy 264.798048 -263.882124) (xy 202.89774 -263.882124) (xy 202.89774 -263.882378) (xy 202.89726 -263.887684)
			(xy 202.889828 -263.895258) (xy 202.884532 -263.89584) (xy 202.368658 -263.89584) (xy 202.360849 -263.896172)
			(xy 202.345978 -263.900945) (xy 202.339448 -263.905238) (xy 202.318337 -263.919604) (xy 202.27261 -263.942328)
			(xy 202.223933 -263.957753) (xy 202.173464 -263.965514) (xy 202.147932 -263.965944) (xy 202.122402 -263.965495)
			(xy 202.071939 -263.957724) (xy 202.023266 -263.942298) (xy 201.977538 -263.919584) (xy 201.956416 -263.905238)
			(xy 201.949878 -263.900958) (xy 201.935013 -263.896167) (xy 201.927206 -263.89584) (xy 201.411332 -263.89584)
			(xy 201.406081 -263.895287) (xy 201.398638 -263.887881) (xy 201.398124 -263.882632) (xy 195.353917 -263.882632)
			(xy 195.35346 -263.887684) (xy 195.346028 -263.895258) (xy 195.340732 -263.89584) (xy 194.824858 -263.89584)
			(xy 194.817049 -263.896172) (xy 194.802178 -263.900945) (xy 194.795648 -263.905238) (xy 194.774537 -263.919604)
			(xy 194.72881 -263.942328) (xy 194.680133 -263.957753) (xy 194.629664 -263.965514) (xy 194.604132 -263.965944)
			(xy 194.578602 -263.965495) (xy 194.528139 -263.957724) (xy 194.479466 -263.942298) (xy 194.433738 -263.919584)
			(xy 194.412616 -263.905238) (xy 194.406078 -263.900958) (xy 194.391213 -263.896167) (xy 194.383406 -263.89584)
			(xy 193.867532 -263.89584) (xy 193.862281 -263.895287) (xy 193.854838 -263.887881) (xy 193.854324 -263.882632)
			(xy 187.810124 -263.882632) (xy 187.809804 -263.887815) (xy 187.802115 -263.895504) (xy 187.796678 -263.89584)
			(xy 187.280804 -263.89584) (xy 187.272993 -263.896148) (xy 187.258122 -263.900937) (xy 187.251594 -263.905238)
			(xy 187.230471 -263.919584) (xy 187.184747 -263.942312) (xy 187.136075 -263.957743) (xy 187.085609 -263.965511)
			(xy 187.060078 -263.965944) (xy 187.034547 -263.965522) (xy 186.984083 -263.957742) (xy 186.93541 -263.942309)
			(xy 186.889683 -263.919588) (xy 186.868562 -263.905238) (xy 186.862036 -263.900937) (xy 186.847162 -263.89616)
			(xy 186.839352 -263.89584) (xy 186.323478 -263.89584) (xy 186.318106 -263.895362) (xy 186.31052 -263.887752)
			(xy 186.310016 -263.882378) (xy 180.265832 -263.882378) (xy 180.265359 -263.887686) (xy 180.257922 -263.89526)
			(xy 180.252624 -263.89584) (xy 179.73675 -263.89584) (xy 179.728941 -263.896168) (xy 179.714069 -263.900944)
			(xy 179.70754 -263.905238) (xy 179.686432 -263.919608) (xy 179.640703 -263.94233) (xy 179.592026 -263.957755)
			(xy 179.541556 -263.965515) (xy 179.516024 -263.965944) (xy 179.490494 -263.965499) (xy 179.44003 -263.957726)
			(xy 179.391358 -263.9423) (xy 179.34563 -263.919585) (xy 179.324508 -263.905238) (xy 179.317972 -263.900955)
			(xy 179.303105 -263.896166) (xy 179.295298 -263.89584) (xy 178.779424 -263.89584) (xy 178.774172 -263.895292)
			(xy 178.76673 -263.887882) (xy 178.766216 -263.882632) (xy 172.722017 -263.882632) (xy 172.721703 -263.887817)
			(xy 172.714009 -263.895506) (xy 172.70857 -263.89584) (xy 172.192696 -263.89584) (xy 172.184885 -263.896145)
			(xy 172.170013 -263.900936) (xy 172.163486 -263.905238) (xy 172.142365 -263.919588) (xy 172.096641 -263.942315)
			(xy 172.047968 -263.957745) (xy 171.997501 -263.965511) (xy 171.97197 -263.965944) (xy 171.946439 -263.965526)
			(xy 171.895974 -263.957745) (xy 171.847302 -263.942311) (xy 171.801575 -263.919588) (xy 171.780454 -263.905238)
			(xy 171.77393 -263.900934) (xy 171.759054 -263.896158) (xy 171.751244 -263.89584) (xy 171.23537 -263.89584)
			(xy 171.229997 -263.895367) (xy 171.222412 -263.887753) (xy 171.221908 -263.882378) (xy 165.177724 -263.882378)
			(xy 165.177258 -263.887688) (xy 165.169816 -263.895262) (xy 165.164516 -263.89584) (xy 163.691316 -263.89584)
			(xy 163.686063 -263.895298) (xy 163.678621 -263.887883) (xy 163.678108 -263.882632) (xy 56.078105 -263.882632)
			(xy 56.077802 -263.88782) (xy 56.070101 -263.89551) (xy 56.064658 -263.89584) (xy 54.591458 -263.89584)
			(xy 54.586084 -263.895375) (xy 54.578499 -263.887755) (xy 54.577996 -263.882378) (xy 48.533812 -263.882378)
			(xy 48.533356 -263.887691) (xy 48.525908 -263.895266) (xy 48.520604 -263.89584) (xy 48.00473 -263.89584)
			(xy 47.99692 -263.89616) (xy 47.982049 -263.900941) (xy 47.97552 -263.905238) (xy 47.954389 -263.919573)
			(xy 47.908669 -263.942303) (xy 47.859998 -263.957738) (xy 47.809534 -263.965509) (xy 47.784004 -263.965944)
			(xy 47.758474 -263.965509) (xy 47.70801 -263.957733) (xy 47.659337 -263.942304) (xy 47.61361 -263.919586)
			(xy 47.592488 -263.905238) (xy 47.585956 -263.900947) (xy 47.571086 -263.896163) (xy 47.563278 -263.89584)
			(xy 47.047404 -263.89584) (xy 47.042149 -263.895306) (xy 47.034708 -263.887885) (xy 47.034196 -263.882632)
			(xy 40.989985 -263.882632) (xy 40.98944 -263.887727) (xy 40.981896 -263.895311) (xy 40.97655 -263.89584)
			(xy 40.460676 -263.89584) (xy 40.452864 -263.896137) (xy 40.437993 -263.900934) (xy 40.431466 -263.905238)
			(xy 40.41035 -263.919597) (xy 40.364624 -263.942322) (xy 40.315949 -263.957749) (xy 40.265482 -263.965513)
			(xy 40.23995 -263.965944) (xy 40.214421 -263.965486) (xy 40.163957 -263.957717) (xy 40.115285 -263.942294)
			(xy 40.069556 -263.919583) (xy 40.048434 -263.905238) (xy 40.041892 -263.900965) (xy 40.02703 -263.89617)
			(xy 40.019224 -263.89584) (xy 39.50335 -263.89584) (xy 39.497975 -263.89538) (xy 39.490391 -263.887756)
			(xy 39.489888 -263.882378) (xy 33.445704 -263.882378) (xy 33.445168 -263.887669) (xy 33.437775 -263.895239)
			(xy 33.432496 -263.89584) (xy 32.916622 -263.89584) (xy 32.908812 -263.896157) (xy 32.89394 -263.90094)
			(xy 32.887412 -263.905238) (xy 32.866283 -263.919577) (xy 32.820562 -263.942306) (xy 32.771891 -263.957739)
			(xy 32.721426 -263.965509) (xy 32.695896 -263.965944) (xy 32.670365 -263.965513) (xy 32.619901 -263.957736)
			(xy 32.571229 -263.942305) (xy 32.525502 -263.919587) (xy 32.50438 -263.905238) (xy 32.49785 -263.900944)
			(xy 32.482979 -263.896162) (xy 32.47517 -263.89584) (xy 31.959296 -263.89584) (xy 31.95404 -263.895311)
			(xy 31.9466 -263.887887) (xy 31.946088 -263.882632) (xy 25.901878 -263.882632) (xy 25.901368 -263.887669)
			(xy 25.893975 -263.895239) (xy 25.888696 -263.89584) (xy 25.372822 -263.89584) (xy 25.365012 -263.896157)
			(xy 25.35014 -263.90094) (xy 25.343612 -263.905238) (xy 25.322483 -263.919577) (xy 25.276762 -263.942306)
			(xy 25.228091 -263.957739) (xy 25.177626 -263.965509) (xy 25.152096 -263.965944) (xy 25.126565 -263.965513)
			(xy 25.076101 -263.957736) (xy 25.027429 -263.942305) (xy 24.981702 -263.919587) (xy 24.96058 -263.905238)
			(xy 24.95405 -263.900944) (xy 24.939179 -263.896162) (xy 24.93137 -263.89584) (xy 24.415496 -263.89584)
			(xy 24.41024 -263.895311) (xy 24.4028 -263.887887) (xy 24.402288 -263.882632) (xy 18.358077 -263.882632)
			(xy 18.357539 -263.887729) (xy 18.349991 -263.895314) (xy 18.344642 -263.89584) (xy 17.828768 -263.89584)
			(xy 17.82096 -263.896176) (xy 17.806088 -263.900946) (xy 17.799558 -263.905238) (xy 17.778445 -263.9196)
			(xy 17.732718 -263.942324) (xy 17.684042 -263.957751) (xy 17.633574 -263.965513) (xy 17.608042 -263.965944)
			(xy 17.582512 -263.96549) (xy 17.532049 -263.95772) (xy 17.483377 -263.942296) (xy 17.437648 -263.919584)
			(xy 17.416526 -263.905238) (xy 17.409986 -263.900962) (xy 17.395123 -263.896169) (xy 17.387316 -263.89584)
			(xy 16.871442 -263.89584) (xy 16.866007 -263.89549) (xy 16.858318 -263.887812) (xy 16.85798 -263.882378)
			(xy 2.509012 -263.882378) (xy 2.509012 -264.732516) (xy 20.958048 -264.732516) (xy 20.958048 -264.237978)
			(xy 20.958537 -264.232609) (xy 20.96614 -264.225024) (xy 20.97151 -264.224516) (xy 21.487638 -264.224516)
			(xy 21.495447 -264.22419) (xy 21.510319 -264.219414) (xy 21.516848 -264.215118) (xy 21.537937 -264.200769)
			(xy 21.583598 -264.178038) (xy 21.632204 -264.162579) (xy 21.682607 -264.154756) (xy 21.733613 -264.154756)
			(xy 21.784016 -264.162579) (xy 21.832622 -264.178038) (xy 21.878283 -264.200769) (xy 21.899372 -264.215118)
			(xy 21.905915 -264.219389) (xy 21.920776 -264.224186) (xy 21.928582 -264.224516) (xy 22.44471 -264.224516)
			(xy 22.45007 -264.225042) (xy 22.457654 -264.232619) (xy 22.458172 -264.237978) (xy 22.458172 -264.732516)
			(xy 28.502356 -264.732516) (xy 28.502356 -264.237978) (xy 28.50281 -264.232667) (xy 28.510262 -264.225097)
			(xy 28.515564 -264.224516) (xy 29.031692 -264.224516) (xy 29.039503 -264.224213) (xy 29.054375 -264.219421)
			(xy 29.060902 -264.215118) (xy 29.081991 -264.200769) (xy 29.127652 -264.178038) (xy 29.176258 -264.162579)
			(xy 29.226661 -264.154756) (xy 29.277667 -264.154756) (xy 29.32807 -264.162579) (xy 29.376676 -264.178038)
			(xy 29.422337 -264.200769) (xy 29.443426 -264.215118) (xy 29.449957 -264.21941) (xy 29.464827 -264.224194)
			(xy 29.472636 -264.224516) (xy 29.988764 -264.224516) (xy 29.994097 -264.224853) (xy 30.001642 -264.232391)
			(xy 30.001972 -264.237724) (xy 30.001972 -264.238232) (xy 30.001972 -264.732516) (xy 36.046156 -264.732516)
			(xy 36.046156 -264.237978) (xy 36.04661 -264.232667) (xy 36.054062 -264.225097) (xy 36.059364 -264.224516)
			(xy 36.575492 -264.224516) (xy 36.583303 -264.224213) (xy 36.598175 -264.219421) (xy 36.604702 -264.215118)
			(xy 36.625791 -264.200769) (xy 36.671452 -264.178038) (xy 36.720058 -264.162579) (xy 36.770461 -264.154756)
			(xy 36.821467 -264.154756) (xy 36.87187 -264.162579) (xy 36.920476 -264.178038) (xy 36.966137 -264.200769)
			(xy 36.987226 -264.215118) (xy 36.993757 -264.21941) (xy 37.008627 -264.224194) (xy 37.016436 -264.224516)
			(xy 37.532564 -264.224516) (xy 37.537897 -264.224853) (xy 37.545442 -264.232391) (xy 37.545772 -264.237724)
			(xy 37.545772 -264.238232) (xy 37.545772 -264.732516) (xy 43.589956 -264.732516) (xy 43.589956 -264.237978)
			(xy 43.590438 -264.232607) (xy 43.598046 -264.225022) (xy 43.603418 -264.224516) (xy 44.119546 -264.224516)
			(xy 44.127356 -264.224194) (xy 44.142228 -264.219415) (xy 44.148756 -264.215118) (xy 44.169845 -264.200769)
			(xy 44.215506 -264.178038) (xy 44.264112 -264.162579) (xy 44.314515 -264.154756) (xy 44.365521 -264.154756)
			(xy 44.415924 -264.162579) (xy 44.46453 -264.178038) (xy 44.510191 -264.200769) (xy 44.53128 -264.215118)
			(xy 44.537821 -264.219393) (xy 44.552684 -264.224187) (xy 44.56049 -264.224516) (xy 45.076618 -264.224516)
			(xy 45.081979 -264.225036) (xy 45.089562 -264.232617) (xy 45.09008 -264.237978) (xy 45.09008 -264.732516)
			(xy 51.134264 -264.732516) (xy 51.134264 -264.237978) (xy 51.134711 -264.232666) (xy 51.142168 -264.225094)
			(xy 51.147472 -264.224516) (xy 51.6636 -264.224516) (xy 51.671412 -264.224216) (xy 51.686283 -264.219422)
			(xy 51.69281 -264.215118) (xy 51.713899 -264.200769) (xy 51.75956 -264.178038) (xy 51.808166 -264.162579)
			(xy 51.858569 -264.154756) (xy 51.909575 -264.154756) (xy 51.959978 -264.162579) (xy 52.008584 -264.178038)
			(xy 52.054245 -264.200769) (xy 52.075334 -264.215118) (xy 52.081863 -264.219413) (xy 52.096735 -264.224195)
			(xy 52.104544 -264.224516) (xy 52.620672 -264.224516) (xy 52.626006 -264.224848) (xy 52.633551 -264.23239)
			(xy 52.63388 -264.237724) (xy 52.63388 -264.238232) (xy 52.63388 -264.732516) (xy 58.678064 -264.732516)
			(xy 58.678064 -264.237978) (xy 58.678367 -264.232534) (xy 58.686081 -264.224848) (xy 58.691526 -264.224516)
			(xy 60.164726 -264.224516) (xy 60.170088 -264.225031) (xy 60.177671 -264.232616) (xy 60.178188 -264.237978)
			(xy 60.178188 -264.732516) (xy 167.778176 -264.732516) (xy 167.778176 -264.237978) (xy 167.778613 -264.232663)
			(xy 167.786076 -264.225091) (xy 167.791384 -264.224516) (xy 169.264584 -264.224516) (xy 169.26992 -264.22484)
			(xy 169.277463 -264.232388) (xy 169.277792 -264.237724) (xy 169.277792 -264.732516) (xy 175.321976 -264.732516)
			(xy 175.321976 -264.237978) (xy 175.322268 -264.232531) (xy 175.329989 -264.224844) (xy 175.335438 -264.224516)
			(xy 175.851566 -264.224516) (xy 175.859376 -264.224202) (xy 175.874248 -264.219418) (xy 175.880776 -264.215118)
			(xy 175.901865 -264.200769) (xy 175.947526 -264.178038) (xy 175.996132 -264.162579) (xy 176.046535 -264.154756)
			(xy 176.097541 -264.154756) (xy 176.147944 -264.162579) (xy 176.19655 -264.178038) (xy 176.242211 -264.200769)
			(xy 176.2633 -264.215118) (xy 176.269837 -264.2194) (xy 176.284703 -264.22419) (xy 176.29251 -264.224516)
			(xy 176.808638 -264.224516) (xy 176.814001 -264.225023) (xy 176.821583 -264.232614) (xy 176.8221 -264.237978)
			(xy 176.8221 -264.732516) (xy 182.866284 -264.732516) (xy 182.866284 -264.237978) (xy 182.866714 -264.232661)
			(xy 182.874182 -264.225088) (xy 182.879492 -264.224516) (xy 183.39562 -264.224516) (xy 183.403432 -264.224225)
			(xy 183.418304 -264.219425) (xy 183.42483 -264.215118) (xy 183.445919 -264.200769) (xy 183.49158 -264.178038)
			(xy 183.540186 -264.162579) (xy 183.590589 -264.154756) (xy 183.641595 -264.154756) (xy 183.691998 -264.162579)
			(xy 183.740604 -264.178038) (xy 183.786265 -264.200769) (xy 183.807354 -264.215118) (xy 183.813879 -264.219421)
			(xy 183.828754 -264.224198) (xy 183.836564 -264.224516) (xy 184.352692 -264.224516) (xy 184.358029 -264.224834)
			(xy 184.365572 -264.232387) (xy 184.3659 -264.237724) (xy 184.3659 -264.238232) (xy 184.3659 -264.732516)
			(xy 190.410084 -264.732516) (xy 190.410084 -264.237978) (xy 190.410369 -264.232529) (xy 190.418095 -264.224842)
			(xy 190.423546 -264.224516) (xy 190.939674 -264.224516) (xy 190.947485 -264.224205) (xy 190.962357 -264.219419)
			(xy 190.968884 -264.215118) (xy 190.989973 -264.200769) (xy 191.035634 -264.178038) (xy 191.08424 -264.162579)
			(xy 191.134643 -264.154756) (xy 191.185649 -264.154756) (xy 191.236052 -264.162579) (xy 191.284658 -264.178038)
			(xy 191.330319 -264.200769) (xy 191.351408 -264.215118) (xy 191.357943 -264.219403) (xy 191.37281 -264.224192)
			(xy 191.380618 -264.224516) (xy 191.896746 -264.224516) (xy 191.90211 -264.225018) (xy 191.909692 -264.232613)
			(xy 191.910208 -264.237978) (xy 191.910208 -264.732516) (xy 197.954392 -264.732516) (xy 197.954392 -264.237978)
			(xy 197.954903 -264.232682) (xy 197.962316 -264.225115) (xy 197.9676 -264.224516) (xy 198.483728 -264.224516)
			(xy 198.491541 -264.224228) (xy 198.506412 -264.219426) (xy 198.512938 -264.215118) (xy 198.534027 -264.200769)
			(xy 198.579688 -264.178038) (xy 198.628294 -264.162579) (xy 198.678697 -264.154756) (xy 198.729703 -264.154756)
			(xy 198.780106 -264.162579) (xy 198.828712 -264.178038) (xy 198.874373 -264.200769) (xy 198.895462 -264.215118)
			(xy 198.902008 -264.219386) (xy 198.916867 -264.224185) (xy 198.924672 -264.224516) (xy 199.4408 -264.224516)
			(xy 199.446138 -264.224829) (xy 199.453681 -264.232385) (xy 199.454008 -264.237724) (xy 199.454008 -264.238232)
			(xy 199.454008 -264.732516) (xy 205.498192 -264.732516) (xy 205.498192 -264.237978) (xy 205.498703 -264.232682)
			(xy 205.506116 -264.225115) (xy 205.5114 -264.224516) (xy 206.027528 -264.224516) (xy 206.035341 -264.224228)
			(xy 206.050212 -264.219426) (xy 206.056738 -264.215118) (xy 206.077827 -264.200769) (xy 206.123488 -264.178038)
			(xy 206.172094 -264.162579) (xy 206.222497 -264.154756) (xy 206.273503 -264.154756) (xy 206.323906 -264.162579)
			(xy 206.372512 -264.178038) (xy 206.418173 -264.200769) (xy 206.439262 -264.215118) (xy 206.445808 -264.219386)
			(xy 206.460667 -264.224185) (xy 206.468472 -264.224516) (xy 206.9846 -264.224516) (xy 206.989938 -264.224829)
			(xy 206.997481 -264.232385) (xy 206.997808 -264.237724) (xy 206.997808 -264.238232) (xy 206.997808 -264.732262)
			(xy 268.898116 -264.732262) (xy 268.898116 -264.237724) (xy 268.898445 -264.232389) (xy 268.905989 -264.224845)
			(xy 268.911324 -264.224516) (xy 268.911832 -264.224516) (xy 269.427706 -264.224516) (xy 269.435518 -264.224219)
			(xy 269.45039 -264.219423) (xy 269.456916 -264.215118) (xy 269.478005 -264.200769) (xy 269.523666 -264.178038)
			(xy 269.572272 -264.162579) (xy 269.622675 -264.154756) (xy 269.673681 -264.154756) (xy 269.724084 -264.162579)
			(xy 269.77269 -264.178038) (xy 269.818351 -264.200769) (xy 269.83944 -264.215118) (xy 269.845968 -264.219416)
			(xy 269.860841 -264.224196) (xy 269.86865 -264.224516) (xy 270.384778 -264.224516) (xy 270.390074 -264.225035)
			(xy 270.397645 -264.23244) (xy 270.39824 -264.237724) (xy 270.39824 -264.732262) (xy 270.398224 -264.732516)
			(xy 276.442424 -264.732516) (xy 276.442424 -264.732008) (xy 276.442424 -264.237724) (xy 276.442746 -264.232387)
			(xy 276.450295 -264.224843) (xy 276.455632 -264.224516) (xy 276.97176 -264.224516) (xy 276.97957 -264.224199)
			(xy 276.994442 -264.219417) (xy 277.00097 -264.215118) (xy 277.022059 -264.200769) (xy 277.06772 -264.178038)
			(xy 277.116326 -264.162579) (xy 277.166729 -264.154756) (xy 277.217735 -264.154756) (xy 277.268138 -264.162579)
			(xy 277.316744 -264.178038) (xy 277.362405 -264.200769) (xy 277.383494 -264.215118) (xy 277.390032 -264.219398)
			(xy 277.404897 -264.22419) (xy 277.412704 -264.224516) (xy 277.928832 -264.224516) (xy 277.934104 -264.224976)
			(xy 277.941547 -264.23245) (xy 277.94204 -264.237724) (xy 277.94204 -264.732262) (xy 277.942016 -264.732516)
			(xy 283.986224 -264.732516) (xy 283.986224 -264.732008) (xy 283.986224 -264.237724) (xy 283.986546 -264.232387)
			(xy 283.994095 -264.224843) (xy 283.999432 -264.224516) (xy 284.51556 -264.224516) (xy 284.52337 -264.224199)
			(xy 284.538242 -264.219417) (xy 284.54477 -264.215118) (xy 284.565859 -264.200769) (xy 284.61152 -264.178038)
			(xy 284.660126 -264.162579) (xy 284.710529 -264.154756) (xy 284.761535 -264.154756) (xy 284.811938 -264.162579)
			(xy 284.860544 -264.178038) (xy 284.906205 -264.200769) (xy 284.927294 -264.215118) (xy 284.933832 -264.219398)
			(xy 284.948697 -264.22419) (xy 284.956504 -264.224516) (xy 285.472632 -264.224516) (xy 285.477904 -264.224976)
			(xy 285.485347 -264.23245) (xy 285.48584 -264.237724) (xy 285.48584 -264.732262) (xy 291.530024 -264.732262)
			(xy 291.530024 -264.237724) (xy 291.530346 -264.232387) (xy 291.537895 -264.224843) (xy 291.543232 -264.224516)
			(xy 291.54374 -264.224516) (xy 292.059614 -264.224516) (xy 292.067426 -264.224222) (xy 292.082298 -264.219424)
			(xy 292.088824 -264.215118) (xy 292.109913 -264.200769) (xy 292.155574 -264.178038) (xy 292.20418 -264.162579)
			(xy 292.254583 -264.154756) (xy 292.305589 -264.154756) (xy 292.355992 -264.162579) (xy 292.404598 -264.178038)
			(xy 292.450259 -264.200769) (xy 292.471348 -264.215118) (xy 292.477874 -264.219419) (xy 292.492748 -264.224197)
			(xy 292.500558 -264.224516) (xy 293.016686 -264.224516) (xy 293.021983 -264.22503) (xy 293.029553 -264.232439)
			(xy 293.030148 -264.237724) (xy 293.030148 -264.732262) (xy 293.030131 -264.732516) (xy 299.074332 -264.732516)
			(xy 299.074332 -264.732008) (xy 299.074332 -264.237724) (xy 299.074647 -264.232385) (xy 299.082201 -264.224841)
			(xy 299.08754 -264.224516) (xy 299.603668 -264.224516) (xy 299.611478 -264.224203) (xy 299.62635 -264.219418)
			(xy 299.632878 -264.215118) (xy 299.653967 -264.200769) (xy 299.699628 -264.178038) (xy 299.748234 -264.162579)
			(xy 299.798637 -264.154756) (xy 299.849643 -264.154756) (xy 299.900046 -264.162579) (xy 299.948652 -264.178038)
			(xy 299.994313 -264.200769) (xy 300.015402 -264.215118) (xy 300.021939 -264.219401) (xy 300.036804 -264.224191)
			(xy 300.044612 -264.224516) (xy 300.56074 -264.224516) (xy 300.566013 -264.22497) (xy 300.573455 -264.232448)
			(xy 300.573948 -264.237724) (xy 300.573948 -264.732262) (xy 306.618132 -264.732262) (xy 306.618132 -264.237724)
			(xy 306.618447 -264.232385) (xy 306.626001 -264.224841) (xy 306.63134 -264.224516) (xy 306.631848 -264.224516)
			(xy 308.104794 -264.224516) (xy 308.110092 -264.225024) (xy 308.117662 -264.232437) (xy 308.118256 -264.237724)
			(xy 308.118256 -264.732262) (xy 308.118239 -264.732516) (xy 415.718244 -264.732516) (xy 415.718244 -264.237724)
			(xy 415.718806 -264.232476) (xy 415.726207 -264.225035) (xy 415.731452 -264.224516) (xy 417.204652 -264.224516)
			(xy 417.209984 -264.224862) (xy 417.217529 -264.232393) (xy 417.21786 -264.237724) (xy 417.21786 -264.732262)
			(xy 423.262044 -264.732262) (xy 423.262044 -264.237724) (xy 423.262606 -264.232476) (xy 423.270007 -264.225035)
			(xy 423.275252 -264.224516) (xy 423.27576 -264.224516) (xy 423.791634 -264.224516) (xy 423.799443 -264.224188)
			(xy 423.814315 -264.219414) (xy 423.820844 -264.215118) (xy 423.841933 -264.200769) (xy 423.887594 -264.178038)
			(xy 423.9362 -264.162579) (xy 423.986603 -264.154756) (xy 424.037609 -264.154756) (xy 424.088012 -264.162579)
			(xy 424.136618 -264.178038) (xy 424.182279 -264.200769) (xy 424.203368 -264.215118) (xy 424.209912 -264.219388)
			(xy 424.224772 -264.224186) (xy 424.232578 -264.224516) (xy 424.748706 -264.224516) (xy 424.754005 -264.225016)
			(xy 424.761575 -264.232435) (xy 424.762168 -264.237724) (xy 424.762168 -264.732262) (xy 424.762151 -264.732516)
			(xy 430.806352 -264.732516) (xy 430.806352 -264.732008) (xy 430.806352 -264.237724) (xy 430.806907 -264.232474)
			(xy 430.814312 -264.225032) (xy 430.81956 -264.224516) (xy 431.335688 -264.224516) (xy 431.343499 -264.224211)
			(xy 431.358371 -264.219421) (xy 431.364898 -264.215118) (xy 431.385987 -264.200769) (xy 431.431648 -264.178038)
			(xy 431.480254 -264.162579) (xy 431.530657 -264.154756) (xy 431.581663 -264.154756) (xy 431.632066 -264.162579)
			(xy 431.680672 -264.178038) (xy 431.726333 -264.200769) (xy 431.747422 -264.215118) (xy 431.753954 -264.219409)
			(xy 431.768823 -264.224194) (xy 431.776632 -264.224516) (xy 432.29276 -264.224516) (xy 432.298093 -264.224856)
			(xy 432.305637 -264.232392) (xy 432.305968 -264.237724) (xy 432.305968 -264.732262) (xy 438.350152 -264.732262)
			(xy 438.350152 -264.237724) (xy 438.350707 -264.232474) (xy 438.358112 -264.225032) (xy 438.36336 -264.224516)
			(xy 438.363868 -264.224516) (xy 438.879742 -264.224516) (xy 438.887551 -264.224192) (xy 438.902423 -264.219415)
			(xy 438.908952 -264.215118) (xy 438.930041 -264.200769) (xy 438.975702 -264.178038) (xy 439.024308 -264.162579)
			(xy 439.074711 -264.154756) (xy 439.125717 -264.154756) (xy 439.17612 -264.162579) (xy 439.224726 -264.178038)
			(xy 439.270387 -264.200769) (xy 439.291476 -264.215118) (xy 439.298018 -264.219391) (xy 439.31288 -264.224187)
			(xy 439.320686 -264.224516) (xy 439.836814 -264.224516) (xy 439.842114 -264.225011) (xy 439.849683 -264.232434)
			(xy 439.850276 -264.237724) (xy 439.850276 -264.732262) (xy 439.850258 -264.732516) (xy 445.89446 -264.732516)
			(xy 445.89446 -264.732008) (xy 445.89446 -264.237724) (xy 445.895008 -264.232472) (xy 445.902418 -264.22503)
			(xy 445.907668 -264.224516) (xy 446.423796 -264.224516) (xy 446.431607 -264.224215) (xy 446.446479 -264.219422)
			(xy 446.453006 -264.215118) (xy 446.474095 -264.200769) (xy 446.519756 -264.178038) (xy 446.568362 -264.162579)
			(xy 446.618765 -264.154756) (xy 446.669771 -264.154756) (xy 446.720174 -264.162579) (xy 446.76878 -264.178038)
			(xy 446.814441 -264.200769) (xy 446.83553 -264.215118) (xy 446.84206 -264.219412) (xy 446.856931 -264.224195)
			(xy 446.86474 -264.224516) (xy 447.380868 -264.224516) (xy 447.386202 -264.224851) (xy 447.393746 -264.23239)
			(xy 447.394076 -264.237724) (xy 447.394076 -264.732262) (xy 447.394051 -264.732516) (xy 453.43826 -264.732516)
			(xy 453.43826 -264.732008) (xy 453.43826 -264.237724) (xy 453.438808 -264.232472) (xy 453.446218 -264.22503)
			(xy 453.451468 -264.224516) (xy 453.967596 -264.224516) (xy 453.975407 -264.224215) (xy 453.990279 -264.219422)
			(xy 453.996806 -264.215118) (xy 454.017895 -264.200769) (xy 454.063556 -264.178038) (xy 454.112162 -264.162579)
			(xy 454.162565 -264.154756) (xy 454.213571 -264.154756) (xy 454.263974 -264.162579) (xy 454.31258 -264.178038)
			(xy 454.358241 -264.200769) (xy 454.37933 -264.215118) (xy 454.38586 -264.219412) (xy 454.400731 -264.224195)
			(xy 454.40854 -264.224516) (xy 454.924668 -264.224516) (xy 454.930002 -264.224851) (xy 454.937546 -264.23239)
			(xy 454.937876 -264.237724) (xy 454.937876 -264.732262) (xy 454.937353 -264.737558) (xy 454.929952 -264.74513)
			(xy 454.924668 -264.745724) (xy 454.408794 -264.745724) (xy 454.400983 -264.746031) (xy 454.386112 -264.750821)
			(xy 454.379584 -264.755122) (xy 454.358462 -264.769471) (xy 454.312739 -264.792199) (xy 454.264065 -264.807629)
			(xy 454.213599 -264.815395) (xy 454.188068 -264.815828) (xy 454.162537 -264.815414) (xy 454.112072 -264.807632)
			(xy 454.063399 -264.792197) (xy 454.017673 -264.769473) (xy 453.996552 -264.755122) (xy 453.990029 -264.750816)
			(xy 453.975152 -264.746042) (xy 453.967342 -264.745724) (xy 453.451468 -264.745724) (xy 453.446205 -264.745228)
			(xy 453.438765 -264.737779) (xy 453.43826 -264.732516) (xy 447.394051 -264.732516) (xy 447.393553 -264.737558)
			(xy 447.386152 -264.74513) (xy 447.380868 -264.745724) (xy 446.864994 -264.745724) (xy 446.857183 -264.746031)
			(xy 446.842312 -264.750821) (xy 446.835784 -264.755122) (xy 446.814662 -264.769471) (xy 446.768939 -264.792199)
			(xy 446.720265 -264.807629) (xy 446.669799 -264.815395) (xy 446.644268 -264.815828) (xy 446.618737 -264.815414)
			(xy 446.568272 -264.807632) (xy 446.519599 -264.792197) (xy 446.473873 -264.769473) (xy 446.452752 -264.755122)
			(xy 446.446229 -264.750816) (xy 446.431352 -264.746042) (xy 446.423542 -264.745724) (xy 445.907668 -264.745724)
			(xy 445.902405 -264.745228) (xy 445.894965 -264.737779) (xy 445.89446 -264.732516) (xy 439.850258 -264.732516)
			(xy 439.849897 -264.737688) (xy 439.842239 -264.745376) (xy 439.836814 -264.745724) (xy 439.32094 -264.745724)
			(xy 439.313131 -264.746051) (xy 439.29826 -264.750828) (xy 439.29173 -264.755122) (xy 439.270623 -264.769494)
			(xy 439.224894 -264.792217) (xy 439.176216 -264.80764) (xy 439.125746 -264.815399) (xy 439.100214 -264.815828)
			(xy 439.074684 -264.815391) (xy 439.02422 -264.807616) (xy 438.975547 -264.792187) (xy 438.92982 -264.76947)
			(xy 438.908698 -264.755122) (xy 438.902165 -264.750834) (xy 438.887296 -264.746049) (xy 438.879488 -264.745724)
			(xy 438.363614 -264.745724) (xy 438.358172 -264.745408) (xy 438.350483 -264.737705) (xy 438.350152 -264.732262)
			(xy 432.305968 -264.732262) (xy 432.305452 -264.73756) (xy 432.298046 -264.745132) (xy 432.29276 -264.745724)
			(xy 431.776886 -264.745724) (xy 431.769075 -264.746028) (xy 431.754203 -264.75082) (xy 431.747676 -264.755122)
			(xy 431.726556 -264.769474) (xy 431.680832 -264.792201) (xy 431.632158 -264.807631) (xy 431.581691 -264.815396)
			(xy 431.55616 -264.815828) (xy 431.530629 -264.815418) (xy 431.480163 -264.807635) (xy 431.431491 -264.792198)
			(xy 431.385765 -264.769474) (xy 431.364644 -264.755122) (xy 431.358123 -264.750813) (xy 431.343245 -264.746041)
			(xy 431.335434 -264.745724) (xy 430.81956 -264.745724) (xy 430.814296 -264.745234) (xy 430.806857 -264.737781)
			(xy 430.806352 -264.732516) (xy 424.762151 -264.732516) (xy 424.761796 -264.73769) (xy 424.754133 -264.745378)
			(xy 424.748706 -264.745724) (xy 424.232832 -264.745724) (xy 424.225023 -264.746047) (xy 424.210151 -264.750826)
			(xy 424.203622 -264.755122) (xy 424.182489 -264.769454) (xy 424.13677 -264.792186) (xy 424.0881 -264.807621)
			(xy 424.037636 -264.815392) (xy 424.012106 -264.815828) (xy 423.986576 -264.815395) (xy 423.936111 -264.807619)
			(xy 423.887439 -264.792189) (xy 423.841711 -264.769471) (xy 423.82059 -264.755122) (xy 423.814059 -264.750831)
			(xy 423.799189 -264.746047) (xy 423.79138 -264.745724) (xy 423.275506 -264.745724) (xy 423.270063 -264.745413)
			(xy 423.262374 -264.737706) (xy 423.262044 -264.732262) (xy 417.21786 -264.732262) (xy 417.217351 -264.737562)
			(xy 417.20994 -264.745135) (xy 417.204652 -264.745724) (xy 415.731452 -264.745724) (xy 415.726187 -264.745239)
			(xy 415.718749 -264.737782) (xy 415.718244 -264.732516) (xy 308.118239 -264.732516) (xy 308.117895 -264.737693)
			(xy 308.110224 -264.745382) (xy 308.104794 -264.745724) (xy 306.631594 -264.745724) (xy 306.626149 -264.745421)
			(xy 306.618461 -264.737708) (xy 306.618132 -264.732262) (xy 300.573948 -264.732262) (xy 300.57345 -264.737564)
			(xy 300.566031 -264.745138) (xy 300.56074 -264.745724) (xy 300.044866 -264.745724) (xy 300.037058 -264.746062)
			(xy 300.022186 -264.750831) (xy 300.015656 -264.755122) (xy 299.994542 -264.769483) (xy 299.948816 -264.792208)
			(xy 299.90014 -264.807635) (xy 299.849672 -264.815397) (xy 299.82414 -264.815828) (xy 299.79861 -264.815378)
			(xy 299.748147 -264.807607) (xy 299.699474 -264.792182) (xy 299.653746 -264.769468) (xy 299.632624 -264.755122)
			(xy 299.626085 -264.750844) (xy 299.611221 -264.746052) (xy 299.603414 -264.745724) (xy 299.08754 -264.745724)
			(xy 299.082217 -264.745348) (xy 299.074675 -264.737837) (xy 299.074332 -264.732516) (xy 293.030131 -264.732516)
			(xy 293.029794 -264.737695) (xy 293.022119 -264.745384) (xy 293.016686 -264.745724) (xy 292.500812 -264.745724)
			(xy 292.493002 -264.746039) (xy 292.47813 -264.750823) (xy 292.471602 -264.755122) (xy 292.450475 -264.769463)
			(xy 292.404753 -264.792192) (xy 292.356082 -264.807625) (xy 292.305617 -264.815394) (xy 292.280086 -264.815828)
			(xy 292.254555 -264.815405) (xy 292.20409 -264.807626) (xy 292.155418 -264.792193) (xy 292.109691 -264.769472)
			(xy 292.08857 -264.755122) (xy 292.082043 -264.750823) (xy 292.06717 -264.746045) (xy 292.05936 -264.745724)
			(xy 291.543486 -264.745724) (xy 291.53804 -264.745426) (xy 291.530353 -264.737709) (xy 291.530024 -264.732262)
			(xy 285.48584 -264.732262) (xy 285.485349 -264.737566) (xy 285.477926 -264.745141) (xy 285.472632 -264.745724)
			(xy 284.956758 -264.745724) (xy 284.94895 -264.746059) (xy 284.934078 -264.75083) (xy 284.927548 -264.755122)
			(xy 284.906436 -264.769486) (xy 284.860709 -264.792211) (xy 284.812033 -264.807637) (xy 284.761564 -264.815398)
			(xy 284.736032 -264.815828) (xy 284.710502 -264.815382) (xy 284.660038 -264.80761) (xy 284.611366 -264.792184)
			(xy 284.565638 -264.769469) (xy 284.544516 -264.755122) (xy 284.537979 -264.750841) (xy 284.523113 -264.746051)
			(xy 284.515306 -264.745724) (xy 283.999432 -264.745724) (xy 283.994108 -264.745353) (xy 283.986566 -264.737839)
			(xy 283.986224 -264.732516) (xy 277.942016 -264.732516) (xy 277.941549 -264.737566) (xy 277.934126 -264.745141)
			(xy 277.928832 -264.745724) (xy 277.412958 -264.745724) (xy 277.40515 -264.746059) (xy 277.390278 -264.75083)
			(xy 277.383748 -264.755122) (xy 277.362636 -264.769486) (xy 277.316909 -264.792211) (xy 277.268233 -264.807637)
			(xy 277.217764 -264.815398) (xy 277.192232 -264.815828) (xy 277.166702 -264.815382) (xy 277.116238 -264.80761)
			(xy 277.067566 -264.792184) (xy 277.021838 -264.769469) (xy 277.000716 -264.755122) (xy 276.994179 -264.750841)
			(xy 276.979313 -264.746051) (xy 276.971506 -264.745724) (xy 276.455632 -264.745724) (xy 276.450308 -264.745353)
			(xy 276.442766 -264.737839) (xy 276.442424 -264.732516) (xy 270.398224 -264.732516) (xy 270.397893 -264.737697)
			(xy 270.390213 -264.745387) (xy 270.384778 -264.745724) (xy 269.868904 -264.745724) (xy 269.861094 -264.746035)
			(xy 269.846222 -264.750822) (xy 269.839694 -264.755122) (xy 269.818569 -264.769467) (xy 269.772847 -264.792195)
			(xy 269.724174 -264.807627) (xy 269.673709 -264.815394) (xy 269.648178 -264.815828) (xy 269.622647 -264.815409)
			(xy 269.572182 -264.807629) (xy 269.52351 -264.792195) (xy 269.477783 -264.769472) (xy 269.456662 -264.755122)
			(xy 269.450137 -264.75082) (xy 269.435262 -264.746043) (xy 269.427452 -264.745724) (xy 268.911578 -264.745724)
			(xy 268.906131 -264.745432) (xy 268.898444 -264.737711) (xy 268.898116 -264.732262) (xy 206.997808 -264.732262)
			(xy 206.997808 -264.732516) (xy 206.997316 -264.737781) (xy 206.989865 -264.745222) (xy 206.9846 -264.745724)
			(xy 206.468726 -264.745724) (xy 206.46085 -264.745992) (xy 206.445846 -264.75079) (xy 206.439262 -264.755122)
			(xy 206.418183 -264.769512) (xy 206.372539 -264.792341) (xy 206.323934 -264.8079) (xy 206.273517 -264.815819)
			(xy 206.248 -264.816336) (xy 206.222479 -264.815857) (xy 206.172052 -264.807958) (xy 206.123441 -264.792395)
			(xy 206.077803 -264.769538) (xy 206.056738 -264.755122) (xy 206.050138 -264.750821) (xy 206.035145 -264.746025)
			(xy 206.027274 -264.745724) (xy 205.5114 -264.745724) (xy 205.506141 -264.745207) (xy 205.4987 -264.737774)
			(xy 205.498192 -264.732516) (xy 199.454008 -264.732516) (xy 199.453516 -264.737781) (xy 199.446065 -264.745222)
			(xy 199.4408 -264.745724) (xy 198.924926 -264.745724) (xy 198.91705 -264.745992) (xy 198.902046 -264.75079)
			(xy 198.895462 -264.755122) (xy 198.874383 -264.769512) (xy 198.828739 -264.792341) (xy 198.780134 -264.8079)
			(xy 198.729717 -264.815819) (xy 198.7042 -264.816336) (xy 198.678679 -264.815857) (xy 198.628252 -264.807958)
			(xy 198.579641 -264.792395) (xy 198.534003 -264.769538) (xy 198.512938 -264.755122) (xy 198.506338 -264.750821)
			(xy 198.491345 -264.746025) (xy 198.483474 -264.745724) (xy 197.9676 -264.745724) (xy 197.962341 -264.745207)
			(xy 197.9549 -264.737774) (xy 197.954392 -264.732516) (xy 191.910208 -264.732516) (xy 191.909716 -264.737781)
			(xy 191.902265 -264.745222) (xy 191.897 -264.745724) (xy 191.896492 -264.745724) (xy 191.380872 -264.745724)
			(xy 191.372998 -264.746011) (xy 191.357994 -264.750796) (xy 191.351408 -264.755122) (xy 191.330345 -264.769535)
			(xy 191.284695 -264.792359) (xy 191.236085 -264.807911) (xy 191.185664 -264.815823) (xy 191.160146 -264.816336)
			(xy 191.134626 -264.815834) (xy 191.0842 -264.807942) (xy 191.035589 -264.792385) (xy 190.98995 -264.769535)
			(xy 190.968884 -264.755122) (xy 190.962296 -264.7508) (xy 190.947293 -264.746017) (xy 190.93942 -264.745724)
			(xy 190.423546 -264.745724) (xy 190.418239 -264.745242) (xy 190.410663 -264.737813) (xy 190.410084 -264.732516)
			(xy 184.3659 -264.732516) (xy 184.365415 -264.737783) (xy 184.35796 -264.745225) (xy 184.352692 -264.745724)
			(xy 183.836818 -264.745724) (xy 183.828945 -264.746032) (xy 183.813941 -264.750802) (xy 183.807354 -264.755122)
			(xy 183.786278 -264.769515) (xy 183.740633 -264.792344) (xy 183.692026 -264.807902) (xy 183.641609 -264.81582)
			(xy 183.616092 -264.816336) (xy 183.590573 -264.815811) (xy 183.540148 -264.807926) (xy 183.491537 -264.792376)
			(xy 183.445897 -264.769532) (xy 183.42483 -264.755122) (xy 183.418232 -264.750818) (xy 183.403237 -264.746024)
			(xy 183.395366 -264.745724) (xy 182.879492 -264.745724) (xy 182.874232 -264.745212) (xy 182.866791 -264.737776)
			(xy 182.866284 -264.732516) (xy 176.8221 -264.732516) (xy 176.821615 -264.737783) (xy 176.81416 -264.745225)
			(xy 176.808892 -264.745724) (xy 176.808384 -264.745724) (xy 176.292764 -264.745724) (xy 176.284889 -264.746008)
			(xy 176.269885 -264.750795) (xy 176.2633 -264.755122) (xy 176.242211 -264.769496) (xy 176.19657 -264.792329)
			(xy 176.147968 -264.807892) (xy 176.097554 -264.815816) (xy 176.072038 -264.816336) (xy 176.046518 -264.815838)
			(xy 175.996092 -264.807945) (xy 175.94748 -264.792387) (xy 175.901842 -264.769535) (xy 175.880776 -264.755122)
			(xy 175.87419 -264.750797) (xy 175.859186 -264.746016) (xy 175.851312 -264.745724) (xy 175.335438 -264.745724)
			(xy 175.33013 -264.745247) (xy 175.322555 -264.737814) (xy 175.321976 -264.732516) (xy 169.277792 -264.732516)
			(xy 169.277315 -264.737785) (xy 169.269854 -264.745227) (xy 169.264584 -264.745724) (xy 167.791384 -264.745724)
			(xy 167.786123 -264.745218) (xy 167.778682 -264.737777) (xy 167.778176 -264.732516) (xy 60.178188 -264.732516)
			(xy 60.177882 -264.737855) (xy 60.17032 -264.745397) (xy 60.16498 -264.745724) (xy 60.164472 -264.745724)
			(xy 58.691526 -264.745724) (xy 58.686217 -264.745255) (xy 58.678642 -264.737816) (xy 58.678064 -264.732516)
			(xy 52.63388 -264.732516) (xy 52.633581 -264.737857) (xy 52.626014 -264.745399) (xy 52.620672 -264.745724)
			(xy 52.104798 -264.745724) (xy 52.096925 -264.746023) (xy 52.081921 -264.750799) (xy 52.075334 -264.755122)
			(xy 52.054263 -264.769524) (xy 52.008616 -264.792351) (xy 51.960008 -264.807906) (xy 51.909589 -264.815821)
			(xy 51.884072 -264.816336) (xy 51.858553 -264.815821) (xy 51.808127 -264.807933) (xy 51.759516 -264.79238)
			(xy 51.713876 -264.769533) (xy 51.69281 -264.755122) (xy 51.686217 -264.75081) (xy 51.671218 -264.746021)
			(xy 51.663346 -264.745724) (xy 51.147472 -264.745724) (xy 51.14221 -264.745226) (xy 51.13477 -264.737779)
			(xy 51.134264 -264.732516) (xy 45.09008 -264.732516) (xy 45.089781 -264.737857) (xy 45.082214 -264.745399)
			(xy 45.076872 -264.745724) (xy 45.076364 -264.745724) (xy 44.560744 -264.745724) (xy 44.552868 -264.745999)
			(xy 44.537865 -264.750792) (xy 44.53128 -264.755122) (xy 44.510196 -264.769504) (xy 44.464554 -264.792335)
			(xy 44.41595 -264.807896) (xy 44.365534 -264.815818) (xy 44.340018 -264.816336) (xy 44.314498 -264.815848)
			(xy 44.264071 -264.807952) (xy 44.21546 -264.792391) (xy 44.169821 -264.769537) (xy 44.148756 -264.755122)
			(xy 44.142175 -264.75079) (xy 44.127167 -264.746013) (xy 44.119292 -264.745724) (xy 43.603418 -264.745724)
			(xy 43.598108 -264.745261) (xy 43.590533 -264.737817) (xy 43.589956 -264.732516) (xy 37.545772 -264.732516)
			(xy 37.545481 -264.737859) (xy 37.537909 -264.745402) (xy 37.532564 -264.745724) (xy 37.01669 -264.745724)
			(xy 37.008816 -264.746019) (xy 36.993812 -264.750798) (xy 36.987226 -264.755122) (xy 36.966157 -264.769527)
			(xy 36.92051 -264.792353) (xy 36.871901 -264.807907) (xy 36.821482 -264.815822) (xy 36.795964 -264.816336)
			(xy 36.770445 -264.815825) (xy 36.720019 -264.807936) (xy 36.671408 -264.792382) (xy 36.625768 -264.769534)
			(xy 36.604702 -264.755122) (xy 36.59811 -264.750807) (xy 36.58311 -264.74602) (xy 36.575238 -264.745724)
			(xy 36.059364 -264.745724) (xy 36.054101 -264.745231) (xy 36.046661 -264.73778) (xy 36.046156 -264.732516)
			(xy 30.001972 -264.732516) (xy 30.001681 -264.737859) (xy 29.994109 -264.745402) (xy 29.988764 -264.745724)
			(xy 29.47289 -264.745724) (xy 29.465016 -264.746019) (xy 29.450012 -264.750798) (xy 29.443426 -264.755122)
			(xy 29.422357 -264.769527) (xy 29.37671 -264.792353) (xy 29.328101 -264.807907) (xy 29.277682 -264.815822)
			(xy 29.252164 -264.816336) (xy 29.226645 -264.815825) (xy 29.176219 -264.807936) (xy 29.127608 -264.792382)
			(xy 29.081968 -264.769534) (xy 29.060902 -264.755122) (xy 29.05431 -264.750807) (xy 29.03931 -264.74602)
			(xy 29.031438 -264.745724) (xy 28.515564 -264.745724) (xy 28.510301 -264.745231) (xy 28.502861 -264.73778)
			(xy 28.502356 -264.732516) (xy 22.458172 -264.732516) (xy 22.457881 -264.737859) (xy 22.450309 -264.745402)
			(xy 22.444964 -264.745724) (xy 22.444456 -264.745724) (xy 21.928836 -264.745724) (xy 21.92096 -264.745996)
			(xy 21.905956 -264.750791) (xy 21.899372 -264.755122) (xy 21.878291 -264.769508) (xy 21.832647 -264.792338)
			(xy 21.784043 -264.807898) (xy 21.733626 -264.815818) (xy 21.70811 -264.816336) (xy 21.68259 -264.815852)
			(xy 21.632163 -264.807955) (xy 21.583551 -264.792393) (xy 21.537913 -264.769537) (xy 21.516848 -264.755122)
			(xy 21.510268 -264.750786) (xy 21.495259 -264.746012) (xy 21.487384 -264.745724) (xy 20.97151 -264.745724)
			(xy 20.966199 -264.745266) (xy 20.958625 -264.737818) (xy 20.958048 -264.732516) (xy 2.509012 -264.732516)
			(xy 2.509012 -265.5824) (xy 16.85798 -265.5824) (xy 16.85798 -265.087862) (xy 16.858258 -265.082412)
			(xy 16.86599 -265.074726) (xy 16.871442 -265.0744) (xy 17.38757 -265.0744) (xy 17.395379 -265.074074)
			(xy 17.41025 -265.069296) (xy 17.41678 -265.065002) (xy 17.437869 -265.050653) (xy 17.48353 -265.027922)
			(xy 17.532136 -265.012463) (xy 17.582539 -265.00464) (xy 17.633545 -265.00464) (xy 17.683948 -265.012463)
			(xy 17.732554 -265.027922) (xy 17.778215 -265.050653) (xy 17.799304 -265.065002) (xy 17.805835 -265.069294)
			(xy 17.820705 -265.074076) (xy 17.828514 -265.0744) (xy 18.344642 -265.0744) (xy 18.350002 -265.074919)
			(xy 18.357583 -265.082502) (xy 18.358104 -265.087862) (xy 18.358104 -265.5824) (xy 24.402288 -265.5824)
			(xy 24.402288 -265.087862) (xy 24.402704 -265.082542) (xy 24.410183 -265.07497) (xy 24.415496 -265.0744)
			(xy 24.931624 -265.0744) (xy 24.939435 -265.074096) (xy 24.954306 -265.069303) (xy 24.960834 -265.065002)
			(xy 24.981923 -265.050653) (xy 25.027584 -265.027922) (xy 25.07619 -265.012463) (xy 25.126593 -265.00464)
			(xy 25.177599 -265.00464) (xy 25.228002 -265.012463) (xy 25.276608 -265.027922) (xy 25.322269 -265.050653)
			(xy 25.343358 -265.065002) (xy 25.349877 -265.069314) (xy 25.364757 -265.074084) (xy 25.372568 -265.0744)
			(xy 25.888696 -265.0744) (xy 25.89403 -265.07473) (xy 25.901571 -265.082274) (xy 25.901904 -265.087608)
			(xy 25.901904 -265.088116) (xy 25.901904 -265.5824) (xy 31.946088 -265.5824) (xy 31.946088 -265.087862)
			(xy 31.946504 -265.082542) (xy 31.953983 -265.07497) (xy 31.959296 -265.0744) (xy 32.475424 -265.0744)
			(xy 32.483235 -265.074096) (xy 32.498106 -265.069303) (xy 32.504634 -265.065002) (xy 32.525723 -265.050653)
			(xy 32.571384 -265.027922) (xy 32.61999 -265.012463) (xy 32.670393 -265.00464) (xy 32.721399 -265.00464)
			(xy 32.771802 -265.012463) (xy 32.820408 -265.027922) (xy 32.866069 -265.050653) (xy 32.887158 -265.065002)
			(xy 32.893677 -265.069314) (xy 32.908557 -265.074084) (xy 32.916368 -265.0744) (xy 33.432496 -265.0744)
			(xy 33.43783 -265.07473) (xy 33.445371 -265.082274) (xy 33.445704 -265.087608) (xy 33.445704 -265.088116)
			(xy 33.445704 -265.5824) (xy 39.489888 -265.5824) (xy 39.489888 -265.087862) (xy 39.49042 -265.082506)
			(xy 39.497994 -265.074925) (xy 39.50335 -265.0744) (xy 40.019478 -265.0744) (xy 40.027287 -265.074077)
			(xy 40.042159 -265.069297) (xy 40.048688 -265.065002) (xy 40.069777 -265.050653) (xy 40.115438 -265.027922)
			(xy 40.164044 -265.012463) (xy 40.214447 -265.00464) (xy 40.265453 -265.00464) (xy 40.315856 -265.012463)
			(xy 40.364462 -265.027922) (xy 40.410123 -265.050653) (xy 40.431212 -265.065002) (xy 40.437741 -265.069297)
			(xy 40.452613 -265.074078) (xy 40.460422 -265.0744) (xy 40.97655 -265.0744) (xy 40.981911 -265.074914)
			(xy 40.989491 -265.082501) (xy 40.990012 -265.087862) (xy 40.990012 -265.5824) (xy 47.034196 -265.5824)
			(xy 47.034196 -265.087862) (xy 47.034692 -265.082563) (xy 47.042116 -265.074997) (xy 47.047404 -265.0744)
			(xy 47.563532 -265.0744) (xy 47.571339 -265.074058) (xy 47.586211 -265.069291) (xy 47.592742 -265.065002)
			(xy 47.613831 -265.050653) (xy 47.659492 -265.027922) (xy 47.708098 -265.012463) (xy 47.758501 -265.00464)
			(xy 47.809507 -265.00464) (xy 47.85991 -265.012463) (xy 47.908516 -265.027922) (xy 47.954177 -265.050653)
			(xy 47.975266 -265.065002) (xy 47.981806 -265.069279) (xy 47.996669 -265.074071) (xy 48.004476 -265.0744)
			(xy 48.520604 -265.0744) (xy 48.525939 -265.074725) (xy 48.53348 -265.082273) (xy 48.533812 -265.087608)
			(xy 48.533812 -265.088116) (xy 48.533812 -265.5824) (xy 54.577996 -265.5824) (xy 54.577996 -265.087862)
			(xy 54.578521 -265.082504) (xy 54.5861 -265.074923) (xy 54.591458 -265.0744) (xy 56.064658 -265.0744)
			(xy 56.070078 -265.074804) (xy 56.077764 -265.082444) (xy 56.07812 -265.087862) (xy 56.07812 -265.5824)
			(xy 163.678108 -265.5824) (xy 163.678108 -265.087862) (xy 163.678594 -265.082561) (xy 163.686025 -265.074994)
			(xy 163.691316 -265.0744) (xy 165.164516 -265.0744) (xy 165.169783 -265.074885) (xy 165.177225 -265.08234)
			(xy 165.177724 -265.087608) (xy 165.177724 -265.088116) (xy 165.177724 -265.5824) (xy 171.221908 -265.5824)
			(xy 171.221908 -265.087862) (xy 171.222422 -265.082501) (xy 171.230008 -265.074919) (xy 171.23537 -265.0744)
			(xy 171.751498 -265.0744) (xy 171.759308 -265.074086) (xy 171.774179 -265.0693) (xy 171.780708 -265.065002)
			(xy 171.801797 -265.050653) (xy 171.847458 -265.027922) (xy 171.896064 -265.012463) (xy 171.946467 -265.00464)
			(xy 171.997473 -265.00464) (xy 172.047876 -265.012463) (xy 172.096482 -265.027922) (xy 172.142143 -265.050653)
			(xy 172.163232 -265.065002) (xy 172.169757 -265.069304) (xy 172.184632 -265.07408) (xy 172.192442 -265.0744)
			(xy 172.70857 -265.0744) (xy 172.713921 -265.074966) (xy 172.721507 -265.082513) (xy 172.722032 -265.087862)
			(xy 172.722032 -265.5824) (xy 178.766216 -265.5824) (xy 178.766216 -265.087862) (xy 178.766695 -265.082559)
			(xy 178.774131 -265.074991) (xy 178.779424 -265.0744) (xy 179.295552 -265.0744) (xy 179.30336 -265.074066)
			(xy 179.318232 -265.069294) (xy 179.324762 -265.065002) (xy 179.345851 -265.050653) (xy 179.391512 -265.027922)
			(xy 179.440118 -265.012463) (xy 179.490521 -265.00464) (xy 179.541527 -265.00464) (xy 179.59193 -265.012463)
			(xy 179.640536 -265.027922) (xy 179.686197 -265.050653) (xy 179.707286 -265.065002) (xy 179.713821 -265.069287)
			(xy 179.728688 -265.074074) (xy 179.736496 -265.0744) (xy 180.252624 -265.0744) (xy 180.257892 -265.07488)
			(xy 180.265333 -265.082339) (xy 180.265832 -265.087608) (xy 180.265832 -265.088116) (xy 180.265832 -265.5824)
			(xy 186.310016 -265.5824) (xy 186.310016 -265.087862) (xy 186.310523 -265.082499) (xy 186.318114 -265.074917)
			(xy 186.323478 -265.0744) (xy 186.839606 -265.0744) (xy 186.847416 -265.074089) (xy 186.862288 -265.069301)
			(xy 186.868816 -265.065002) (xy 186.889905 -265.050653) (xy 186.935566 -265.027922) (xy 186.984172 -265.012463)
			(xy 187.034575 -265.00464) (xy 187.085581 -265.00464) (xy 187.135984 -265.012463) (xy 187.18459 -265.027922)
			(xy 187.230251 -265.050653) (xy 187.25134 -265.065002) (xy 187.257863 -265.069308) (xy 187.27274 -265.074082)
			(xy 187.28055 -265.0744) (xy 187.796678 -265.0744) (xy 187.80203 -265.074961) (xy 187.809615 -265.082512)
			(xy 187.81014 -265.087862) (xy 187.81014 -265.5824) (xy 193.854324 -265.5824) (xy 193.854324 -265.087862)
			(xy 193.854796 -265.082557) (xy 193.862236 -265.074989) (xy 193.867532 -265.0744) (xy 194.38366 -265.0744)
			(xy 194.391469 -265.074069) (xy 194.40634 -265.069295) (xy 194.41287 -265.065002) (xy 194.433959 -265.050653)
			(xy 194.47962 -265.027922) (xy 194.528226 -265.012463) (xy 194.578629 -265.00464) (xy 194.629635 -265.00464)
			(xy 194.680038 -265.012463) (xy 194.728644 -265.027922) (xy 194.774305 -265.050653) (xy 194.795394 -265.065002)
			(xy 194.801927 -265.06929) (xy 194.816796 -265.074075) (xy 194.824604 -265.0744) (xy 195.340732 -265.0744)
			(xy 195.346001 -265.074874) (xy 195.353442 -265.082338) (xy 195.35394 -265.087608) (xy 195.35394 -265.088116)
			(xy 195.35394 -265.5824) (xy 201.398124 -265.5824) (xy 201.398124 -265.087862) (xy 201.398596 -265.082557)
			(xy 201.406036 -265.074989) (xy 201.411332 -265.0744) (xy 201.92746 -265.0744) (xy 201.935269 -265.074069)
			(xy 201.95014 -265.069295) (xy 201.95667 -265.065002) (xy 201.977759 -265.050653) (xy 202.02342 -265.027922)
			(xy 202.072026 -265.012463) (xy 202.122429 -265.00464) (xy 202.173435 -265.00464) (xy 202.223838 -265.012463)
			(xy 202.272444 -265.027922) (xy 202.318105 -265.050653) (xy 202.339194 -265.065002) (xy 202.345727 -265.06929)
			(xy 202.360596 -265.074075) (xy 202.368404 -265.0744) (xy 202.884532 -265.0744) (xy 202.889801 -265.074874)
			(xy 202.897242 -265.082338) (xy 202.89774 -265.087608) (xy 202.89774 -265.088116) (xy 202.89774 -265.582146)
			(xy 264.798048 -265.582146) (xy 264.798048 -265.087608) (xy 264.798595 -265.082357) (xy 264.806007 -265.074916)
			(xy 264.811256 -265.0744) (xy 264.811764 -265.0744) (xy 265.327638 -265.0744) (xy 265.335446 -265.07406)
			(xy 265.350317 -265.069292) (xy 265.356848 -265.065002) (xy 265.377937 -265.050653) (xy 265.423598 -265.027922)
			(xy 265.472204 -265.012463) (xy 265.522607 -265.00464) (xy 265.573613 -265.00464) (xy 265.624016 -265.012463)
			(xy 265.672622 -265.027922) (xy 265.718283 -265.050653) (xy 265.739372 -265.065002) (xy 265.74591 -265.069282)
			(xy 265.760775 -265.074072) (xy 265.768582 -265.0744) (xy 266.28471 -265.0744) (xy 266.290006 -265.074912)
			(xy 266.297574 -265.082323) (xy 266.298172 -265.087608) (xy 266.298172 -265.582146) (xy 266.298149 -265.5824)
			(xy 272.342356 -265.5824) (xy 272.342356 -265.581892) (xy 272.342356 -265.087608) (xy 272.342896 -265.082355)
			(xy 272.350313 -265.074914) (xy 272.355564 -265.0744) (xy 272.871692 -265.0744) (xy 272.879502 -265.074083)
			(xy 272.894373 -265.069299) (xy 272.900902 -265.065002) (xy 272.921991 -265.050653) (xy 272.967652 -265.027922)
			(xy 273.016258 -265.012463) (xy 273.066661 -265.00464) (xy 273.117667 -265.00464) (xy 273.16807 -265.012463)
			(xy 273.216676 -265.027922) (xy 273.262337 -265.050653) (xy 273.283426 -265.065002) (xy 273.289952 -265.069302)
			(xy 273.304826 -265.07408) (xy 273.312636 -265.0744) (xy 273.828764 -265.0744) (xy 273.834093 -265.074752)
			(xy 273.841637 -265.082279) (xy 273.841972 -265.087608) (xy 273.841972 -265.582146) (xy 273.841947 -265.5824)
			(xy 279.886156 -265.5824) (xy 279.886156 -265.581892) (xy 279.886156 -265.087608) (xy 279.886696 -265.082355)
			(xy 279.894113 -265.074914) (xy 279.899364 -265.0744) (xy 280.415492 -265.0744) (xy 280.423302 -265.074083)
			(xy 280.438173 -265.069299) (xy 280.444702 -265.065002) (xy 280.465791 -265.050653) (xy 280.511452 -265.027922)
			(xy 280.560058 -265.012463) (xy 280.610461 -265.00464) (xy 280.661467 -265.00464) (xy 280.71187 -265.012463)
			(xy 280.760476 -265.027922) (xy 280.806137 -265.050653) (xy 280.827226 -265.065002) (xy 280.833752 -265.069302)
			(xy 280.848626 -265.07408) (xy 280.856436 -265.0744) (xy 281.372564 -265.0744) (xy 281.377893 -265.074752)
			(xy 281.385437 -265.082279) (xy 281.385772 -265.087608) (xy 281.385772 -265.582146) (xy 287.429956 -265.582146)
			(xy 287.429956 -265.087608) (xy 287.430496 -265.082355) (xy 287.437913 -265.074914) (xy 287.443164 -265.0744)
			(xy 287.443672 -265.0744) (xy 287.959546 -265.0744) (xy 287.967354 -265.074064) (xy 287.982226 -265.069293)
			(xy 287.988756 -265.065002) (xy 288.009845 -265.050653) (xy 288.055506 -265.027922) (xy 288.104112 -265.012463)
			(xy 288.154515 -265.00464) (xy 288.205521 -265.00464) (xy 288.255924 -265.012463) (xy 288.30453 -265.027922)
			(xy 288.350191 -265.050653) (xy 288.37128 -265.065002) (xy 288.377817 -265.069285) (xy 288.392683 -265.074073)
			(xy 288.40049 -265.0744) (xy 288.916618 -265.0744) (xy 288.921915 -265.074906) (xy 288.929483 -265.082322)
			(xy 288.93008 -265.087608) (xy 288.93008 -265.582146) (xy 288.930056 -265.5824) (xy 294.974264 -265.5824)
			(xy 294.974264 -265.581892) (xy 294.974264 -265.087608) (xy 294.974797 -265.082353) (xy 294.982218 -265.074911)
			(xy 294.987472 -265.0744) (xy 295.5036 -265.0744) (xy 295.51141 -265.074086) (xy 295.526281 -265.0693)
			(xy 295.53281 -265.065002) (xy 295.553899 -265.050653) (xy 295.59956 -265.027922) (xy 295.648166 -265.012463)
			(xy 295.698569 -265.00464) (xy 295.749575 -265.00464) (xy 295.799978 -265.012463) (xy 295.848584 -265.027922)
			(xy 295.894245 -265.050653) (xy 295.915334 -265.065002) (xy 295.921859 -265.069305) (xy 295.936734 -265.074081)
			(xy 295.944544 -265.0744) (xy 296.460672 -265.0744) (xy 296.466003 -265.074746) (xy 296.473546 -265.082278)
			(xy 296.47388 -265.087608) (xy 296.47388 -265.582146) (xy 302.518064 -265.582146) (xy 302.518064 -265.087608)
			(xy 302.518597 -265.082353) (xy 302.526018 -265.074911) (xy 302.531272 -265.0744) (xy 304.004726 -265.0744)
			(xy 304.010024 -265.074901) (xy 304.017592 -265.082321) (xy 304.018188 -265.087608) (xy 304.018188 -265.582146)
			(xy 304.018164 -265.5824) (xy 411.618176 -265.5824) (xy 411.618176 -265.581892) (xy 411.618176 -265.087608)
			(xy 411.618698 -265.08235) (xy 411.626127 -265.074908) (xy 411.631384 -265.0744) (xy 413.104584 -265.0744)
			(xy 413.109916 -265.074738) (xy 413.117458 -265.082276) (xy 413.117792 -265.087608) (xy 413.117792 -265.582146)
			(xy 419.161976 -265.582146) (xy 419.161976 -265.087608) (xy 419.162498 -265.08235) (xy 419.169927 -265.074908)
			(xy 419.175184 -265.0744) (xy 419.175692 -265.0744) (xy 419.691566 -265.0744) (xy 419.699375 -265.074072)
			(xy 419.714246 -265.069296) (xy 419.720776 -265.065002) (xy 419.741865 -265.050653) (xy 419.787526 -265.027922)
			(xy 419.836132 -265.012463) (xy 419.886535 -265.00464) (xy 419.937541 -265.00464) (xy 419.987944 -265.012463)
			(xy 420.03655 -265.027922) (xy 420.082211 -265.050653) (xy 420.1033 -265.065002) (xy 420.109832 -265.069292)
			(xy 420.124702 -265.074076) (xy 420.13251 -265.0744) (xy 420.648638 -265.0744) (xy 420.653938 -265.074893)
			(xy 420.661504 -265.082319) (xy 420.6621 -265.087608) (xy 420.6621 -265.582146) (xy 420.662076 -265.5824)
			(xy 426.706284 -265.5824) (xy 426.706284 -265.581892) (xy 426.706284 -265.087608) (xy 426.706799 -265.082348)
			(xy 426.714233 -265.074905) (xy 426.719492 -265.0744) (xy 427.23562 -265.0744) (xy 427.243431 -265.074095)
			(xy 427.258302 -265.069303) (xy 427.26483 -265.065002) (xy 427.285919 -265.050653) (xy 427.33158 -265.027922)
			(xy 427.380186 -265.012463) (xy 427.430589 -265.00464) (xy 427.481595 -265.00464) (xy 427.531998 -265.012463)
			(xy 427.580604 -265.027922) (xy 427.626265 -265.050653) (xy 427.647354 -265.065002) (xy 427.653874 -265.069313)
			(xy 427.668753 -265.074084) (xy 427.676564 -265.0744) (xy 428.192692 -265.0744) (xy 428.198025 -265.074733)
			(xy 428.205567 -265.082275) (xy 428.2059 -265.087608) (xy 428.2059 -265.582146) (xy 434.250084 -265.582146)
			(xy 434.250084 -265.087608) (xy 434.250599 -265.082348) (xy 434.258033 -265.074905) (xy 434.263292 -265.0744)
			(xy 434.2638 -265.0744) (xy 434.779674 -265.0744) (xy 434.787483 -265.074075) (xy 434.802355 -265.069297)
			(xy 434.808884 -265.065002) (xy 434.829973 -265.050653) (xy 434.875634 -265.027922) (xy 434.92424 -265.012463)
			(xy 434.974643 -265.00464) (xy 435.025649 -265.00464) (xy 435.076052 -265.012463) (xy 435.124658 -265.027922)
			(xy 435.170319 -265.050653) (xy 435.191408 -265.065002) (xy 435.197938 -265.069295) (xy 435.212809 -265.074077)
			(xy 435.220618 -265.0744) (xy 435.736746 -265.0744) (xy 435.742035 -265.074955) (xy 435.749606 -265.082334)
			(xy 435.750208 -265.087608) (xy 435.750208 -265.582146) (xy 435.750183 -265.5824) (xy 441.794392 -265.5824)
			(xy 441.794392 -265.581892) (xy 441.794392 -265.087608) (xy 441.794732 -265.082277) (xy 441.802269 -265.074735)
			(xy 441.8076 -265.0744) (xy 442.323728 -265.0744) (xy 442.331539 -265.074098) (xy 442.34641 -265.069304)
			(xy 442.352938 -265.065002) (xy 442.374027 -265.050653) (xy 442.419688 -265.027922) (xy 442.468294 -265.012463)
			(xy 442.518697 -265.00464) (xy 442.569703 -265.00464) (xy 442.620106 -265.012463) (xy 442.668712 -265.027922)
			(xy 442.714373 -265.050653) (xy 442.735462 -265.065002) (xy 442.742003 -265.069278) (xy 442.756866 -265.07407)
			(xy 442.764672 -265.0744) (xy 443.2808 -265.0744) (xy 443.286134 -265.074727) (xy 443.293676 -265.082274)
			(xy 443.294008 -265.087608) (xy 443.294008 -265.582146) (xy 443.293981 -265.5824) (xy 449.338192 -265.5824)
			(xy 449.338192 -265.581892) (xy 449.338192 -265.087608) (xy 449.338532 -265.082277) (xy 449.346069 -265.074735)
			(xy 449.3514 -265.0744) (xy 449.867528 -265.0744) (xy 449.875339 -265.074098) (xy 449.89021 -265.069304)
			(xy 449.896738 -265.065002) (xy 449.917827 -265.050653) (xy 449.963488 -265.027922) (xy 450.012094 -265.012463)
			(xy 450.062497 -265.00464) (xy 450.113503 -265.00464) (xy 450.163906 -265.012463) (xy 450.212512 -265.027922)
			(xy 450.258173 -265.050653) (xy 450.279262 -265.065002) (xy 450.285803 -265.069278) (xy 450.300666 -265.07407)
			(xy 450.308472 -265.0744) (xy 450.8246 -265.0744) (xy 450.829934 -265.074727) (xy 450.837476 -265.082274)
			(xy 450.837808 -265.087608) (xy 450.837808 -265.582146) (xy 450.837246 -265.587433) (xy 450.829872 -265.595004)
			(xy 450.8246 -265.595608) (xy 450.308726 -265.595608) (xy 450.300917 -265.595931) (xy 450.286045 -265.60071)
			(xy 450.279516 -265.605006) (xy 450.258384 -265.619339) (xy 450.212664 -265.642071) (xy 450.163994 -265.657506)
			(xy 450.11353 -265.665277) (xy 450.088 -265.665712) (xy 450.06247 -265.665267) (xy 450.012007 -265.657492)
			(xy 449.963335 -265.642065) (xy 449.917607 -265.619352) (xy 449.896484 -265.605006) (xy 449.889955 -265.60071)
			(xy 449.875083 -265.59593) (xy 449.867274 -265.595608) (xy 449.3514 -265.595608) (xy 449.346137 -265.595105)
			(xy 449.338695 -265.587663) (xy 449.338192 -265.5824) (xy 443.293981 -265.5824) (xy 443.293446 -265.587433)
			(xy 443.286072 -265.595004) (xy 443.2808 -265.595608) (xy 442.764926 -265.595608) (xy 442.757117 -265.595931)
			(xy 442.742245 -265.60071) (xy 442.735716 -265.605006) (xy 442.714584 -265.619339) (xy 442.668864 -265.642071)
			(xy 442.620194 -265.657506) (xy 442.56973 -265.665277) (xy 442.5442 -265.665712) (xy 442.51867 -265.665267)
			(xy 442.468207 -265.657492) (xy 442.419535 -265.642065) (xy 442.373807 -265.619352) (xy 442.352684 -265.605006)
			(xy 442.346155 -265.60071) (xy 442.331283 -265.59593) (xy 442.323474 -265.595608) (xy 441.8076 -265.595608)
			(xy 441.802337 -265.595105) (xy 441.794895 -265.587663) (xy 441.794392 -265.5824) (xy 435.750183 -265.5824)
			(xy 435.749685 -265.587504) (xy 435.742104 -265.595085) (xy 435.736746 -265.595608) (xy 435.220872 -265.595608)
			(xy 435.213061 -265.595908) (xy 435.198189 -265.600703) (xy 435.191662 -265.605006) (xy 435.170545 -265.619362)
			(xy 435.12482 -265.642089) (xy 435.076145 -265.657517) (xy 435.025677 -265.665281) (xy 435.000146 -265.665712)
			(xy 434.974617 -265.665244) (xy 434.924155 -265.657476) (xy 434.875483 -265.642056) (xy 434.829753 -265.619349)
			(xy 434.80863 -265.605006) (xy 434.802091 -265.600728) (xy 434.787227 -265.595937) (xy 434.77942 -265.595608)
			(xy 434.263546 -265.595608) (xy 434.258199 -265.595023) (xy 434.250613 -265.58749) (xy 434.250084 -265.582146)
			(xy 428.2059 -265.582146) (xy 428.205345 -265.587435) (xy 428.197966 -265.595006) (xy 428.192692 -265.595608)
			(xy 427.676818 -265.595608) (xy 427.669008 -265.595928) (xy 427.654137 -265.600709) (xy 427.647608 -265.605006)
			(xy 427.626478 -265.619343) (xy 427.580758 -265.642073) (xy 427.532087 -265.657507) (xy 427.481622 -265.665277)
			(xy 427.456092 -265.665712) (xy 427.430562 -265.665271) (xy 427.380099 -265.657495) (xy 427.331427 -265.642067)
			(xy 427.285699 -265.619352) (xy 427.264576 -265.605006) (xy 427.258049 -265.600707) (xy 427.243175 -265.595929)
			(xy 427.235366 -265.595608) (xy 426.719492 -265.595608) (xy 426.714228 -265.595111) (xy 426.706786 -265.587664)
			(xy 426.706284 -265.5824) (xy 420.662076 -265.5824) (xy 420.661584 -265.587506) (xy 420.653999 -265.595087)
			(xy 420.648638 -265.595608) (xy 420.132764 -265.595608) (xy 420.124956 -265.595948) (xy 420.110085 -265.600716)
			(xy 420.103554 -265.605006) (xy 420.082439 -265.619366) (xy 420.036713 -265.642092) (xy 419.988038 -265.657519)
			(xy 419.93757 -265.665281) (xy 419.912038 -265.665712) (xy 419.886509 -265.665248) (xy 419.836047 -265.657479)
			(xy 419.787374 -265.642058) (xy 419.741645 -265.619349) (xy 419.720522 -265.605006) (xy 419.713985 -265.600725)
			(xy 419.699119 -265.595935) (xy 419.691312 -265.595608) (xy 419.175438 -265.595608) (xy 419.17009 -265.595029)
			(xy 419.162504 -265.587491) (xy 419.161976 -265.582146) (xy 413.117792 -265.582146) (xy 413.117244 -265.587436)
			(xy 413.109861 -265.595009) (xy 413.104584 -265.595608) (xy 411.631384 -265.595608) (xy 411.626119 -265.595116)
			(xy 411.618678 -265.587665) (xy 411.618176 -265.5824) (xy 304.018164 -265.5824) (xy 304.017683 -265.587509)
			(xy 304.01009 -265.595091) (xy 304.004726 -265.595608) (xy 302.531526 -265.595608) (xy 302.526176 -265.595037)
			(xy 302.518592 -265.587493) (xy 302.518064 -265.582146) (xy 296.47388 -265.582146) (xy 296.473343 -265.587439)
			(xy 296.465952 -265.595012) (xy 296.460672 -265.595608) (xy 295.944798 -265.595608) (xy 295.936988 -265.595919)
			(xy 295.922116 -265.600707) (xy 295.915588 -265.605006) (xy 295.894464 -265.619351) (xy 295.848741 -265.64208)
			(xy 295.800069 -265.657512) (xy 295.749603 -265.665279) (xy 295.724072 -265.665712) (xy 295.698542 -265.665281)
			(xy 295.648078 -265.657502) (xy 295.599406 -265.642071) (xy 295.553678 -265.619354) (xy 295.532556 -265.605006)
			(xy 295.526033 -265.6007) (xy 295.511156 -265.595926) (xy 295.503346 -265.595608) (xy 294.987472 -265.595608)
			(xy 294.982206 -265.595124) (xy 294.974765 -265.587667) (xy 294.974264 -265.5824) (xy 288.930056 -265.5824)
			(xy 288.929582 -265.587511) (xy 288.921984 -265.595093) (xy 288.916618 -265.595608) (xy 288.400744 -265.595608)
			(xy 288.392935 -265.595939) (xy 288.378064 -265.600713) (xy 288.371534 -265.605006) (xy 288.350425 -265.619375)
			(xy 288.304697 -265.642098) (xy 288.25602 -265.657523) (xy 288.20555 -265.665283) (xy 288.180018 -265.665712)
			(xy 288.154489 -265.665258) (xy 288.104026 -265.657486) (xy 288.055354 -265.642062) (xy 288.009625 -265.619351)
			(xy 287.988502 -265.605006) (xy 287.981969 -265.600717) (xy 287.9671 -265.595933) (xy 287.959292 -265.595608)
			(xy 287.443418 -265.595608) (xy 287.438067 -265.595042) (xy 287.430483 -265.587494) (xy 287.429956 -265.582146)
			(xy 281.385772 -265.582146) (xy 281.385242 -265.587441) (xy 281.377846 -265.595014) (xy 281.372564 -265.595608)
			(xy 280.85669 -265.595608) (xy 280.848879 -265.595916) (xy 280.834008 -265.600706) (xy 280.82748 -265.605006)
			(xy 280.806358 -265.619355) (xy 280.760635 -265.642083) (xy 280.711962 -265.657513) (xy 280.661495 -265.665279)
			(xy 280.635964 -265.665712) (xy 280.610433 -265.665285) (xy 280.55997 -265.657505) (xy 280.511297 -265.642073)
			(xy 280.46557 -265.619354) (xy 280.444448 -265.605006) (xy 280.437927 -265.600697) (xy 280.423049 -265.595925)
			(xy 280.415238 -265.595608) (xy 279.899364 -265.595608) (xy 279.894097 -265.595129) (xy 279.886657 -265.587668)
			(xy 279.886156 -265.5824) (xy 273.841947 -265.5824) (xy 273.841442 -265.587441) (xy 273.834046 -265.595014)
			(xy 273.828764 -265.595608) (xy 273.31289 -265.595608) (xy 273.305079 -265.595916) (xy 273.290208 -265.600706)
			(xy 273.28368 -265.605006) (xy 273.262558 -265.619355) (xy 273.216835 -265.642083) (xy 273.168162 -265.657513)
			(xy 273.117695 -265.665279) (xy 273.092164 -265.665712) (xy 273.066633 -265.665285) (xy 273.01617 -265.657505)
			(xy 272.967497 -265.642073) (xy 272.92177 -265.619354) (xy 272.900648 -265.605006) (xy 272.894127 -265.600697)
			(xy 272.879249 -265.595925) (xy 272.871438 -265.595608) (xy 272.355564 -265.595608) (xy 272.350297 -265.595129)
			(xy 272.342857 -265.587668) (xy 272.342356 -265.5824) (xy 266.298149 -265.5824) (xy 266.297681 -265.587513)
			(xy 266.290078 -265.595096) (xy 266.28471 -265.595608) (xy 265.768836 -265.595608) (xy 265.761027 -265.595935)
			(xy 265.746156 -265.600712) (xy 265.739626 -265.605006) (xy 265.718491 -265.619335) (xy 265.672772 -265.642067)
			(xy 265.624103 -265.657503) (xy 265.57364 -265.665276) (xy 265.54811 -265.665712) (xy 265.52258 -265.665262)
			(xy 265.472117 -265.657489) (xy 265.423445 -265.642063) (xy 265.377717 -265.619351) (xy 265.356594 -265.605006)
			(xy 265.350063 -265.600714) (xy 265.335193 -265.595931) (xy 265.327384 -265.595608) (xy 264.81151 -265.595608)
			(xy 264.806158 -265.595047) (xy 264.798575 -265.587495) (xy 264.798048 -265.582146) (xy 202.89774 -265.582146)
			(xy 202.89774 -265.5824) (xy 202.897208 -265.587655) (xy 202.889786 -265.595096) (xy 202.884532 -265.595608)
			(xy 202.368658 -265.595608) (xy 202.360783 -265.595892) (xy 202.34578 -265.600679) (xy 202.339194 -265.605006)
			(xy 202.318105 -265.61938) (xy 202.272465 -265.642214) (xy 202.223862 -265.657777) (xy 202.173448 -265.6657)
			(xy 202.147932 -265.66622) (xy 202.122412 -265.665728) (xy 202.071985 -265.657833) (xy 202.023374 -265.642274)
			(xy 201.977735 -265.61942) (xy 201.95667 -265.605006) (xy 201.950087 -265.600677) (xy 201.93508 -265.595899)
			(xy 201.927206 -265.595608) (xy 201.411332 -265.595608) (xy 201.406004 -265.595252) (xy 201.398461 -265.587727)
			(xy 201.398124 -265.5824) (xy 195.35394 -265.5824) (xy 195.353408 -265.587655) (xy 195.345986 -265.595096)
			(xy 195.340732 -265.595608) (xy 194.824858 -265.595608) (xy 194.816983 -265.595892) (xy 194.80198 -265.600679)
			(xy 194.795394 -265.605006) (xy 194.774305 -265.61938) (xy 194.728665 -265.642214) (xy 194.680062 -265.657777)
			(xy 194.629648 -265.6657) (xy 194.604132 -265.66622) (xy 194.578612 -265.665728) (xy 194.528185 -265.657833)
			(xy 194.479574 -265.642274) (xy 194.433935 -265.61942) (xy 194.41287 -265.605006) (xy 194.406287 -265.600677)
			(xy 194.39128 -265.595899) (xy 194.383406 -265.595608) (xy 193.867532 -265.595608) (xy 193.862204 -265.595252)
			(xy 193.854661 -265.587727) (xy 193.854324 -265.5824) (xy 187.81014 -265.5824) (xy 187.809608 -265.587655)
			(xy 187.802186 -265.595096) (xy 187.796932 -265.595608) (xy 187.796424 -265.595608) (xy 187.280804 -265.595608)
			(xy 187.272931 -265.595912) (xy 187.257927 -265.600685) (xy 187.25134 -265.605006) (xy 187.230266 -265.619403)
			(xy 187.184621 -265.642232) (xy 187.136013 -265.657788) (xy 187.085595 -265.665705) (xy 187.060078 -265.66622)
			(xy 187.034559 -265.665705) (xy 186.984133 -265.657817) (xy 186.935522 -265.642265) (xy 186.889882 -265.619417)
			(xy 186.868816 -265.605006) (xy 186.862222 -265.600695) (xy 186.847224 -265.595906) (xy 186.839352 -265.595608)
			(xy 186.323478 -265.595608) (xy 186.318182 -265.595097) (xy 186.310615 -265.587684) (xy 186.310016 -265.5824)
			(xy 180.265832 -265.5824) (xy 180.265308 -265.587657) (xy 180.25788 -265.595098) (xy 180.252624 -265.595608)
			(xy 179.73675 -265.595608) (xy 179.728875 -265.595889) (xy 179.713871 -265.600678) (xy 179.707286 -265.605006)
			(xy 179.686199 -265.619384) (xy 179.640558 -265.642216) (xy 179.591955 -265.657778) (xy 179.54154 -265.665701)
			(xy 179.516024 -265.66622) (xy 179.490504 -265.665732) (xy 179.440077 -265.657836) (xy 179.391465 -265.642276)
			(xy 179.345827 -265.619421) (xy 179.324762 -265.605006) (xy 179.31818 -265.600674) (xy 179.303173 -265.595898)
			(xy 179.295298 -265.595608) (xy 178.779424 -265.595608) (xy 178.774095 -265.595257) (xy 178.766553 -265.587728)
			(xy 178.766216 -265.5824) (xy 172.722032 -265.5824) (xy 172.721508 -265.587657) (xy 172.71408 -265.595098)
			(xy 172.708824 -265.595608) (xy 172.708316 -265.595608) (xy 172.192696 -265.595608) (xy 172.184823 -265.595908)
			(xy 172.169819 -265.600684) (xy 172.163232 -265.605006) (xy 172.142161 -265.619407) (xy 172.096514 -265.642234)
			(xy 172.047906 -265.65779) (xy 171.997487 -265.665705) (xy 171.97197 -265.66622) (xy 171.946451 -265.665709)
			(xy 171.896025 -265.65782) (xy 171.847413 -265.642266) (xy 171.801774 -265.619418) (xy 171.780708 -265.605006)
			(xy 171.774116 -265.600692) (xy 171.759116 -265.595904) (xy 171.751244 -265.595608) (xy 171.23537 -265.595608)
			(xy 171.230073 -265.595103) (xy 171.222507 -265.587686) (xy 171.221908 -265.5824) (xy 165.177724 -265.5824)
			(xy 165.177207 -265.587659) (xy 165.169774 -265.5951) (xy 165.164516 -265.595608) (xy 163.691316 -265.595608)
			(xy 163.685986 -265.595262) (xy 163.678444 -265.58773) (xy 163.678108 -265.5824) (xy 56.07812 -265.5824)
			(xy 56.077606 -265.58766) (xy 56.070171 -265.595102) (xy 56.064912 -265.595608) (xy 54.591458 -265.595608)
			(xy 54.58616 -265.595111) (xy 54.578594 -265.587688) (xy 54.577996 -265.5824) (xy 48.533812 -265.5824)
			(xy 48.533306 -265.587662) (xy 48.525866 -265.595104) (xy 48.520604 -265.595608) (xy 48.00473 -265.595608)
			(xy 47.996854 -265.59588) (xy 47.981851 -265.600675) (xy 47.975266 -265.605006) (xy 47.954185 -265.619392)
			(xy 47.908542 -265.642223) (xy 47.859937 -265.657783) (xy 47.80952 -265.665703) (xy 47.784004 -265.66622)
			(xy 47.758483 -265.665742) (xy 47.708056 -265.657843) (xy 47.659445 -265.64228) (xy 47.613807 -265.619422)
			(xy 47.592742 -265.605006) (xy 47.586165 -265.600666) (xy 47.571154 -265.595895) (xy 47.563278 -265.595608)
			(xy 47.047404 -265.595608) (xy 47.042072 -265.59527) (xy 47.034531 -265.587732) (xy 47.034196 -265.5824)
			(xy 40.990012 -265.5824) (xy 40.989506 -265.587662) (xy 40.982066 -265.595104) (xy 40.976804 -265.595608)
			(xy 40.976296 -265.595608) (xy 40.460676 -265.595608) (xy 40.452802 -265.5959) (xy 40.437798 -265.600681)
			(xy 40.431212 -265.605006) (xy 40.410146 -265.619416) (xy 40.364498 -265.642241) (xy 40.315888 -265.657794)
			(xy 40.265468 -265.665707) (xy 40.23995 -265.66622) (xy 40.21443 -265.665719) (xy 40.164004 -265.657827)
			(xy 40.115392 -265.64227) (xy 40.069754 -265.619419) (xy 40.048688 -265.605006) (xy 40.042101 -265.600684)
			(xy 40.027097 -265.595901) (xy 40.019224 -265.595608) (xy 39.50335 -265.595608) (xy 39.498063 -265.595049)
			(xy 39.490492 -265.587673) (xy 39.489888 -265.5824) (xy 33.445704 -265.5824) (xy 33.445373 -265.587733)
			(xy 33.437829 -265.595275) (xy 33.432496 -265.595608) (xy 32.916622 -265.595608) (xy 32.90875 -265.59592)
			(xy 32.893746 -265.600688) (xy 32.887158 -265.605006) (xy 32.866079 -265.619396) (xy 32.820435 -265.642226)
			(xy 32.77183 -265.657784) (xy 32.721413 -265.665703) (xy 32.695896 -265.66622) (xy 32.670375 -265.665746)
			(xy 32.619948 -265.657846) (xy 32.571336 -265.642281) (xy 32.525699 -265.619423) (xy 32.504634 -265.605006)
			(xy 32.498036 -265.600702) (xy 32.483041 -265.595908) (xy 32.47517 -265.595608) (xy 31.959296 -265.595608)
			(xy 31.954033 -265.595108) (xy 31.94659 -265.587663) (xy 31.946088 -265.5824) (xy 25.901904 -265.5824)
			(xy 25.901573 -265.587733) (xy 25.894029 -265.595275) (xy 25.888696 -265.595608) (xy 25.372822 -265.595608)
			(xy 25.36495 -265.59592) (xy 25.349946 -265.600688) (xy 25.343358 -265.605006) (xy 25.322279 -265.619396)
			(xy 25.276635 -265.642226) (xy 25.22803 -265.657784) (xy 25.177613 -265.665703) (xy 25.152096 -265.66622)
			(xy 25.126575 -265.665746) (xy 25.076148 -265.657846) (xy 25.027536 -265.642281) (xy 24.981899 -265.619423)
			(xy 24.960834 -265.605006) (xy 24.954236 -265.600702) (xy 24.939241 -265.595908) (xy 24.93137 -265.595608)
			(xy 24.415496 -265.595608) (xy 24.410233 -265.595108) (xy 24.40279 -265.587663) (xy 24.402288 -265.5824)
			(xy 18.358104 -265.5824) (xy 18.357773 -265.587733) (xy 18.350229 -265.595275) (xy 18.344896 -265.595608)
			(xy 18.344388 -265.595608) (xy 17.828768 -265.595608) (xy 17.820894 -265.595896) (xy 17.80589 -265.60068)
			(xy 17.799304 -265.605006) (xy 17.778212 -265.619376) (xy 17.732573 -265.64221) (xy 17.683971 -265.657774)
			(xy 17.633558 -265.6657) (xy 17.608042 -265.66622) (xy 17.582522 -265.665723) (xy 17.532096 -265.65783)
			(xy 17.483484 -265.642272) (xy 17.437845 -265.61942) (xy 17.41678 -265.605006) (xy 17.410194 -265.600681)
			(xy 17.39519 -265.5959) (xy 17.387316 -265.595608) (xy 16.871442 -265.595608) (xy 16.866154 -265.595054)
			(xy 16.858583 -265.587674) (xy 16.85798 -265.5824) (xy 2.509012 -265.5824) (xy 2.509012 -266.432538)
			(xy 20.958048 -266.432538) (xy 20.958048 -265.938) (xy 20.95859 -265.932748) (xy 20.966006 -265.925308)
			(xy 20.971256 -265.924792) (xy 20.971764 -265.924792) (xy 21.487638 -265.924792) (xy 21.495446 -265.924453)
			(xy 21.510317 -265.919684) (xy 21.516848 -265.915394) (xy 21.537937 -265.901045) (xy 21.583598 -265.878314)
			(xy 21.632204 -265.862855) (xy 21.682607 -265.855032) (xy 21.733613 -265.855032) (xy 21.784016 -265.862855)
			(xy 21.832622 -265.878314) (xy 21.878283 -265.901045) (xy 21.899372 -265.915394) (xy 21.905911 -265.919673)
			(xy 21.920775 -265.924464) (xy 21.928582 -265.924792) (xy 22.44471 -265.924792) (xy 22.450004 -265.925311)
			(xy 22.457572 -265.932718) (xy 22.458172 -265.938) (xy 22.458172 -266.432538) (xy 22.458149 -266.432792)
			(xy 28.502356 -266.432792) (xy 28.502356 -266.432284) (xy 28.502356 -265.938) (xy 28.502891 -265.932746)
			(xy 28.510311 -265.925306) (xy 28.515564 -265.924792) (xy 29.031692 -265.924792) (xy 29.039502 -265.924476)
			(xy 29.054373 -265.919692) (xy 29.060902 -265.915394) (xy 29.081991 -265.901045) (xy 29.127652 -265.878314)
			(xy 29.176258 -265.862855) (xy 29.226661 -265.855032) (xy 29.277667 -265.855032) (xy 29.32807 -265.862855)
			(xy 29.376676 -265.878314) (xy 29.422337 -265.901045) (xy 29.443426 -265.915394) (xy 29.449953 -265.919693)
			(xy 29.464826 -265.924472) (xy 29.472636 -265.924792) (xy 29.988764 -265.924792) (xy 29.994092 -265.925151)
			(xy 30.001635 -265.932673) (xy 30.001972 -265.938) (xy 30.001972 -266.432538) (xy 30.00195 -266.432792)
			(xy 36.046156 -266.432792) (xy 36.046156 -266.432284) (xy 36.046156 -265.938) (xy 36.046691 -265.932746)
			(xy 36.054111 -265.925306) (xy 36.059364 -265.924792) (xy 36.575492 -265.924792) (xy 36.583302 -265.924476)
			(xy 36.598173 -265.919692) (xy 36.604702 -265.915394) (xy 36.625791 -265.901045) (xy 36.671452 -265.878314)
			(xy 36.720058 -265.862855) (xy 36.770461 -265.855032) (xy 36.821467 -265.855032) (xy 36.87187 -265.862855)
			(xy 36.920476 -265.878314) (xy 36.966137 -265.901045) (xy 36.987226 -265.915394) (xy 36.993753 -265.919693)
			(xy 37.008626 -265.924472) (xy 37.016436 -265.924792) (xy 37.532564 -265.924792) (xy 37.537892 -265.925151)
			(xy 37.545435 -265.932673) (xy 37.545772 -265.938) (xy 37.545772 -266.432538) (xy 43.589956 -266.432538)
			(xy 43.589956 -265.938) (xy 43.590491 -265.932746) (xy 43.597911 -265.925306) (xy 43.603164 -265.924792)
			(xy 43.603672 -265.924792) (xy 44.119546 -265.924792) (xy 44.127354 -265.924457) (xy 44.142226 -265.919686)
			(xy 44.148756 -265.915394) (xy 44.169845 -265.901045) (xy 44.215506 -265.878314) (xy 44.264112 -265.862855)
			(xy 44.314515 -265.855032) (xy 44.365521 -265.855032) (xy 44.415924 -265.862855) (xy 44.46453 -265.878314)
			(xy 44.510191 -265.901045) (xy 44.53128 -265.915394) (xy 44.537817 -265.919676) (xy 44.552683 -265.924465)
			(xy 44.56049 -265.924792) (xy 45.076618 -265.924792) (xy 45.081913 -265.925305) (xy 45.089481 -265.932716)
			(xy 45.09008 -265.938) (xy 45.09008 -266.432538) (xy 45.090056 -266.432792) (xy 51.134264 -266.432792)
			(xy 51.134264 -266.432284) (xy 51.134264 -265.938) (xy 51.134792 -265.932744) (xy 51.142217 -265.925303)
			(xy 51.147472 -265.924792) (xy 51.6636 -265.924792) (xy 51.67141 -265.92448) (xy 51.686282 -265.919693)
			(xy 51.69281 -265.915394) (xy 51.713899 -265.901045) (xy 51.75956 -265.878314) (xy 51.808166 -265.862855)
			(xy 51.858569 -265.855032) (xy 51.909575 -265.855032) (xy 51.959978 -265.862855) (xy 52.008584 -265.878314)
			(xy 52.054245 -265.901045) (xy 52.075334 -265.915394) (xy 52.081859 -265.919697) (xy 52.096734 -265.924473)
			(xy 52.104544 -265.924792) (xy 52.620672 -265.924792) (xy 52.626001 -265.925145) (xy 52.633543 -265.932672)
			(xy 52.63388 -265.938) (xy 52.63388 -266.432538) (xy 58.678064 -266.432538) (xy 58.678064 -265.938)
			(xy 58.678592 -265.932744) (xy 58.686017 -265.925303) (xy 58.691272 -265.924792) (xy 58.69178 -265.924792)
			(xy 60.164726 -265.924792) (xy 60.170022 -265.9253) (xy 60.177589 -265.932715) (xy 60.178188 -265.938)
			(xy 60.178188 -266.432538) (xy 60.178164 -266.432792) (xy 167.778176 -266.432792) (xy 167.778176 -265.938)
			(xy 167.778693 -265.932741) (xy 167.786126 -265.9253) (xy 167.791384 -265.924792) (xy 169.264584 -265.924792)
			(xy 169.269914 -265.925138) (xy 169.277456 -265.93267) (xy 169.277792 -265.938) (xy 169.277792 -266.432538)
			(xy 175.321976 -266.432538) (xy 175.321976 -265.938) (xy 175.322493 -265.932741) (xy 175.329926 -265.9253)
			(xy 175.335184 -265.924792) (xy 175.335692 -265.924792) (xy 175.851566 -265.924792) (xy 175.859375 -265.924465)
			(xy 175.874246 -265.919688) (xy 175.880776 -265.915394) (xy 175.901865 -265.901045) (xy 175.947526 -265.878314)
			(xy 175.996132 -265.862855) (xy 176.046535 -265.855032) (xy 176.097541 -265.855032) (xy 176.147944 -265.862855)
			(xy 176.19655 -265.878314) (xy 176.242211 -265.901045) (xy 176.2633 -265.915394) (xy 176.269833 -265.919684)
			(xy 176.284702 -265.924468) (xy 176.29251 -265.924792) (xy 176.808638 -265.924792) (xy 176.813936 -265.925292)
			(xy 176.821502 -265.932713) (xy 176.8221 -265.938) (xy 176.8221 -266.432538) (xy 176.822075 -266.432792)
			(xy 182.866284 -266.432792) (xy 182.866284 -266.432284) (xy 182.866284 -265.938) (xy 182.866794 -265.932739)
			(xy 182.874232 -265.925297) (xy 182.879492 -265.924792) (xy 183.39562 -265.924792) (xy 183.403431 -265.924488)
			(xy 183.418302 -265.919695) (xy 183.42483 -265.915394) (xy 183.445919 -265.901045) (xy 183.49158 -265.878314)
			(xy 183.540186 -265.862855) (xy 183.590589 -265.855032) (xy 183.641595 -265.855032) (xy 183.691998 -265.862855)
			(xy 183.740604 -265.878314) (xy 183.786265 -265.901045) (xy 183.807354 -265.915394) (xy 183.813875 -265.919704)
			(xy 183.828753 -265.924476) (xy 183.836564 -265.924792) (xy 184.352692 -265.924792) (xy 184.358023 -265.925132)
			(xy 184.365565 -265.932669) (xy 184.3659 -265.938) (xy 184.3659 -266.432538) (xy 190.410084 -266.432538)
			(xy 190.410084 -265.938) (xy 190.410594 -265.932739) (xy 190.418032 -265.925297) (xy 190.423292 -265.924792)
			(xy 190.4238 -265.924792) (xy 190.939674 -265.924792) (xy 190.947483 -265.924469) (xy 190.962355 -265.91969)
			(xy 190.968884 -265.915394) (xy 190.989973 -265.901045) (xy 191.035634 -265.878314) (xy 191.08424 -265.862855)
			(xy 191.134643 -265.855032) (xy 191.185649 -265.855032) (xy 191.236052 -265.862855) (xy 191.284658 -265.878314)
			(xy 191.330319 -265.901045) (xy 191.351408 -265.915394) (xy 191.357939 -265.919687) (xy 191.372809 -265.924469)
			(xy 191.380618 -265.924792) (xy 191.896746 -265.924792) (xy 191.902033 -265.925354) (xy 191.909604 -265.932728)
			(xy 191.910208 -265.938) (xy 191.910208 -266.432538) (xy 191.910183 -266.432792) (xy 197.954392 -266.432792)
			(xy 197.954392 -266.432284) (xy 197.954392 -265.938) (xy 197.954895 -265.932737) (xy 197.962337 -265.925295)
			(xy 197.9676 -265.924792) (xy 198.483728 -265.924792) (xy 198.491539 -265.924492) (xy 198.506411 -265.919697)
			(xy 198.512938 -265.915394) (xy 198.534027 -265.901045) (xy 198.579688 -265.878314) (xy 198.628294 -265.862855)
			(xy 198.678697 -265.855032) (xy 198.729703 -265.855032) (xy 198.780106 -265.862855) (xy 198.828712 -265.878314)
			(xy 198.874373 -265.901045) (xy 198.895462 -265.915394) (xy 198.902003 -265.919669) (xy 198.916866 -265.924462)
			(xy 198.924672 -265.924792) (xy 199.4408 -265.924792) (xy 199.446063 -265.925295) (xy 199.453505 -265.932737)
			(xy 199.454008 -265.938) (xy 199.454008 -266.432538) (xy 199.453984 -266.432792) (xy 205.498192 -266.432792)
			(xy 205.498192 -266.432284) (xy 205.498192 -265.938) (xy 205.498695 -265.932737) (xy 205.506137 -265.925295)
			(xy 205.5114 -265.924792) (xy 206.027528 -265.924792) (xy 206.035339 -265.924492) (xy 206.050211 -265.919697)
			(xy 206.056738 -265.915394) (xy 206.077827 -265.901045) (xy 206.123488 -265.878314) (xy 206.172094 -265.862855)
			(xy 206.222497 -265.855032) (xy 206.273503 -265.855032) (xy 206.323906 -265.862855) (xy 206.372512 -265.878314)
			(xy 206.418173 -265.901045) (xy 206.439262 -265.915394) (xy 206.445803 -265.919669) (xy 206.460666 -265.924462)
			(xy 206.468472 -265.924792) (xy 206.9846 -265.924792) (xy 206.989863 -265.925295) (xy 206.997305 -265.932737)
			(xy 206.997808 -265.938) (xy 206.997808 -266.432284) (xy 268.898116 -266.432284) (xy 268.898116 -265.937746)
			(xy 268.898508 -265.932323) (xy 268.906156 -265.924635) (xy 268.911578 -265.924284) (xy 269.427706 -265.924284)
			(xy 269.435517 -265.923976) (xy 269.450388 -265.919186) (xy 269.456916 -265.914886) (xy 269.478005 -265.900537)
			(xy 269.523666 -265.877806) (xy 269.572272 -265.862347) (xy 269.622675 -265.854524) (xy 269.673681 -265.854524)
			(xy 269.724084 -265.862347) (xy 269.77269 -265.877806) (xy 269.818351 -265.900537) (xy 269.83944 -265.914886)
			(xy 269.845964 -265.91919) (xy 269.86084 -265.923965) (xy 269.86865 -265.924284) (xy 270.384778 -265.924284)
			(xy 270.390221 -265.924599) (xy 270.397911 -265.932302) (xy 270.39824 -265.937746) (xy 270.39824 -266.432284)
			(xy 276.442424 -266.432284) (xy 276.442424 -265.937746) (xy 276.442952 -265.932451) (xy 276.45035 -265.924878)
			(xy 276.455632 -265.924284) (xy 276.97176 -265.924284) (xy 276.979569 -265.923956) (xy 276.99444 -265.91918)
			(xy 277.00097 -265.914886) (xy 277.022059 -265.900537) (xy 277.06772 -265.877806) (xy 277.116326 -265.862347)
			(xy 277.166729 -265.854524) (xy 277.217735 -265.854524) (xy 277.268138 -265.862347) (xy 277.316744 -265.877806)
			(xy 277.362405 -265.900537) (xy 277.383494 -265.914886) (xy 277.390028 -265.919172) (xy 277.404896 -265.923959)
			(xy 277.412704 -265.924284) (xy 277.928832 -265.924284) (xy 277.934097 -265.924773) (xy 277.941537 -265.932226)
			(xy 277.94204 -265.937492) (xy 277.94204 -265.938) (xy 277.94204 -266.432284) (xy 283.986224 -266.432284)
			(xy 283.986224 -265.937746) (xy 283.986752 -265.932451) (xy 283.99415 -265.924878) (xy 283.999432 -265.924284)
			(xy 284.51556 -265.924284) (xy 284.523369 -265.923956) (xy 284.53824 -265.91918) (xy 284.54477 -265.914886)
			(xy 284.565859 -265.900537) (xy 284.61152 -265.877806) (xy 284.660126 -265.862347) (xy 284.710529 -265.854524)
			(xy 284.761535 -265.854524) (xy 284.811938 -265.862347) (xy 284.860544 -265.877806) (xy 284.906205 -265.900537)
			(xy 284.927294 -265.914886) (xy 284.933828 -265.919172) (xy 284.948696 -265.923959) (xy 284.956504 -265.924284)
			(xy 285.472632 -265.924284) (xy 285.477897 -265.924773) (xy 285.485337 -265.932226) (xy 285.48584 -265.937492)
			(xy 285.48584 -265.938) (xy 285.48584 -266.432284) (xy 291.530024 -266.432284) (xy 291.530024 -265.937746)
			(xy 291.530409 -265.932321) (xy 291.538062 -265.924633) (xy 291.543486 -265.924284) (xy 292.059614 -265.924284)
			(xy 292.067425 -265.923979) (xy 292.082296 -265.919187) (xy 292.088824 -265.914886) (xy 292.109913 -265.900537)
			(xy 292.155574 -265.877806) (xy 292.20418 -265.862347) (xy 292.254583 -265.854524) (xy 292.305589 -265.854524)
			(xy 292.355992 -265.862347) (xy 292.404598 -265.877806) (xy 292.450259 -265.900537) (xy 292.471348 -265.914886)
			(xy 292.47787 -265.919193) (xy 292.492747 -265.923967) (xy 292.500558 -265.924284) (xy 293.016686 -265.924284)
			(xy 293.02213 -265.924593) (xy 293.02982 -265.932301) (xy 293.030148 -265.937746) (xy 293.030148 -266.432284)
			(xy 299.074332 -266.432284) (xy 299.074332 -265.937746) (xy 299.074853 -265.932449) (xy 299.082255 -265.924876)
			(xy 299.08754 -265.924284) (xy 299.603668 -265.924284) (xy 299.611477 -265.92396) (xy 299.626349 -265.919181)
			(xy 299.632878 -265.914886) (xy 299.653967 -265.900537) (xy 299.699628 -265.877806) (xy 299.748234 -265.862347)
			(xy 299.798637 -265.854524) (xy 299.849643 -265.854524) (xy 299.900046 -265.862347) (xy 299.948652 -265.877806)
			(xy 299.994313 -265.900537) (xy 300.015402 -265.914886) (xy 300.021935 -265.919176) (xy 300.036804 -265.92396)
			(xy 300.044612 -265.924284) (xy 300.56074 -265.924284) (xy 300.566006 -265.924767) (xy 300.573446 -265.932225)
			(xy 300.573948 -265.937492) (xy 300.573948 -265.938) (xy 300.573948 -266.432284) (xy 306.618132 -266.432284)
			(xy 306.618132 -265.937746) (xy 306.618509 -265.932319) (xy 306.626168 -265.92463) (xy 306.631594 -265.924284)
			(xy 308.104794 -265.924284) (xy 308.110239 -265.924588) (xy 308.117928 -265.9323) (xy 308.118256 -265.937746)
			(xy 308.118256 -266.432284) (xy 415.718244 -266.432284) (xy 415.718244 -265.937746) (xy 415.718754 -265.932446)
			(xy 415.726164 -265.924872) (xy 415.731452 -265.924284) (xy 417.204652 -265.924284) (xy 417.209976 -265.924659)
			(xy 417.217519 -265.93217) (xy 417.21786 -265.937492) (xy 417.21786 -266.432284) (xy 423.262044 -266.432284)
			(xy 423.262044 -265.937746) (xy 423.262411 -265.932316) (xy 423.270077 -265.924627) (xy 423.275506 -265.924284)
			(xy 423.791634 -265.924284) (xy 423.799442 -265.923945) (xy 423.814313 -265.919176) (xy 423.820844 -265.914886)
			(xy 423.841933 -265.900537) (xy 423.887594 -265.877806) (xy 423.9362 -265.862347) (xy 423.986603 -265.854524)
			(xy 424.037609 -265.854524) (xy 424.088012 -265.862347) (xy 424.136618 -265.877806) (xy 424.182279 -265.900537)
			(xy 424.203368 -265.914886) (xy 424.209908 -265.919163) (xy 424.224771 -265.923955) (xy 424.232578 -265.924284)
			(xy 424.748706 -265.924284) (xy 424.754153 -265.92458) (xy 424.761841 -265.932298) (xy 424.762168 -265.937746)
			(xy 424.762168 -266.432284) (xy 430.806352 -266.432284) (xy 430.806352 -265.937746) (xy 430.806855 -265.932444)
			(xy 430.81427 -265.92487) (xy 430.81956 -265.924284) (xy 431.335688 -265.924284) (xy 431.343498 -265.923968)
			(xy 431.358369 -265.919184) (xy 431.364898 -265.914886) (xy 431.385987 -265.900537) (xy 431.431648 -265.877806)
			(xy 431.480254 -265.862347) (xy 431.530657 -265.854524) (xy 431.581663 -265.854524) (xy 431.632066 -265.862347)
			(xy 431.680672 -265.877806) (xy 431.726333 -265.900537) (xy 431.747422 -265.914886) (xy 431.75395 -265.919183)
			(xy 431.768823 -265.923963) (xy 431.776632 -265.924284) (xy 432.29276 -265.924284) (xy 432.298085 -265.924653)
			(xy 432.305628 -265.932168) (xy 432.305968 -265.937492) (xy 432.305968 -265.938) (xy 432.305968 -266.432284)
			(xy 438.350152 -266.432284) (xy 438.350152 -265.937746) (xy 438.350511 -265.932314) (xy 438.358183 -265.924624)
			(xy 438.363614 -265.924284) (xy 438.879742 -265.924284) (xy 438.88755 -265.923948) (xy 438.902422 -265.919178)
			(xy 438.908952 -265.914886) (xy 438.930041 -265.900537) (xy 438.975702 -265.877806) (xy 439.024308 -265.862347)
			(xy 439.074711 -265.854524) (xy 439.125717 -265.854524) (xy 439.17612 -265.862347) (xy 439.224726 -265.877806)
			(xy 439.270387 -265.900537) (xy 439.291476 -265.914886) (xy 439.298014 -265.919166) (xy 439.312879 -265.923956)
			(xy 439.320686 -265.924284) (xy 439.836814 -265.924284) (xy 439.842262 -265.924575) (xy 439.84995 -265.932297)
			(xy 439.850276 -265.937746) (xy 439.850276 -266.432284) (xy 445.89446 -266.432284) (xy 445.89446 -265.937746)
			(xy 445.894956 -265.932443) (xy 445.902376 -265.924868) (xy 445.907668 -265.924284) (xy 446.423796 -265.924284)
			(xy 446.431606 -265.923971) (xy 446.446478 -265.919185) (xy 446.453006 -265.914886) (xy 446.474095 -265.900537)
			(xy 446.519756 -265.877806) (xy 446.568362 -265.862347) (xy 446.618765 -265.854524) (xy 446.669771 -265.854524)
			(xy 446.720174 -265.862347) (xy 446.76878 -265.877806) (xy 446.814441 -265.900537) (xy 446.83553 -265.914886)
			(xy 446.842056 -265.919186) (xy 446.85693 -265.923964) (xy 446.86474 -265.924284) (xy 447.380868 -265.924284)
			(xy 447.386194 -265.924648) (xy 447.393736 -265.932167) (xy 447.394076 -265.937492) (xy 447.394076 -265.938)
			(xy 447.394076 -266.432284) (xy 453.43826 -266.432284) (xy 453.43826 -265.937746) (xy 453.438756 -265.932443)
			(xy 453.446176 -265.924868) (xy 453.451468 -265.924284) (xy 453.967596 -265.924284) (xy 453.975406 -265.923971)
			(xy 453.990278 -265.919185) (xy 453.996806 -265.914886) (xy 454.017895 -265.900537) (xy 454.063556 -265.877806)
			(xy 454.112162 -265.862347) (xy 454.162565 -265.854524) (xy 454.213571 -265.854524) (xy 454.263974 -265.862347)
			(xy 454.31258 -265.877806) (xy 454.358241 -265.900537) (xy 454.37933 -265.914886) (xy 454.385856 -265.919186)
			(xy 454.40073 -265.923964) (xy 454.40854 -265.924284) (xy 454.924668 -265.924284) (xy 454.929994 -265.924648)
			(xy 454.937536 -265.932167) (xy 454.937876 -265.937492) (xy 454.937876 -265.938) (xy 454.937876 -266.432284)
			(xy 454.937559 -266.437622) (xy 454.930006 -266.445166) (xy 454.924668 -266.445492) (xy 454.408794 -266.445492)
			(xy 454.400919 -266.445778) (xy 454.385915 -266.450562) (xy 454.37933 -266.45489) (xy 454.358266 -266.469302)
			(xy 454.312616 -266.492124) (xy 454.264006 -266.507676) (xy 454.213586 -266.51559) (xy 454.188068 -266.516104)
			(xy 454.162549 -266.515597) (xy 454.112122 -266.507707) (xy 454.063511 -266.492153) (xy 454.017872 -266.469303)
			(xy 453.996806 -266.45489) (xy 453.990215 -266.450574) (xy 453.975215 -266.445788) (xy 453.967342 -266.445492)
			(xy 453.451468 -266.445492) (xy 453.446198 -266.445025) (xy 453.438756 -266.437556) (xy 453.43826 -266.432284)
			(xy 447.394076 -266.432284) (xy 447.393759 -266.437622) (xy 447.386206 -266.445166) (xy 447.380868 -266.445492)
			(xy 446.864994 -266.445492) (xy 446.857119 -266.445778) (xy 446.842115 -266.450562) (xy 446.83553 -266.45489)
			(xy 446.814466 -266.469302) (xy 446.768816 -266.492124) (xy 446.720206 -266.507676) (xy 446.669786 -266.51559)
			(xy 446.644268 -266.516104) (xy 446.618749 -266.515597) (xy 446.568322 -266.507707) (xy 446.519711 -266.492153)
			(xy 446.474072 -266.469303) (xy 446.453006 -266.45489) (xy 446.446415 -266.450574) (xy 446.431415 -266.445788)
			(xy 446.423542 -266.445492) (xy 445.907668 -266.445492) (xy 445.902398 -266.445025) (xy 445.894956 -266.437556)
			(xy 445.89446 -266.432284) (xy 439.850276 -266.432284) (xy 439.849959 -266.437622) (xy 439.842406 -266.445166)
			(xy 439.837068 -266.445492) (xy 439.83656 -266.445492) (xy 439.32094 -266.445492) (xy 439.313063 -266.445754)
			(xy 439.298059 -266.450555) (xy 439.291476 -266.45489) (xy 439.270399 -266.469282) (xy 439.224754 -266.492109)
			(xy 439.176147 -266.507666) (xy 439.125731 -266.515586) (xy 439.100214 -266.516104) (xy 439.074693 -266.515624)
			(xy 439.024266 -266.507726) (xy 438.975655 -266.492163) (xy 438.930017 -266.469306) (xy 438.908952 -266.45489)
			(xy 438.902374 -266.450553) (xy 438.887363 -266.44578) (xy 438.879488 -266.445492) (xy 438.363614 -266.445492)
			(xy 438.358319 -266.444971) (xy 438.350749 -266.437567) (xy 438.350152 -266.432284) (xy 432.305968 -266.432284)
			(xy 432.305659 -266.437624) (xy 432.2981 -266.445168) (xy 432.29276 -266.445492) (xy 431.776886 -266.445492)
			(xy 431.769011 -266.445774) (xy 431.754007 -266.450561) (xy 431.747422 -266.45489) (xy 431.72636 -266.469305)
			(xy 431.680709 -266.492127) (xy 431.632098 -266.507678) (xy 431.581678 -266.51559) (xy 431.55616 -266.516104)
			(xy 431.53064 -266.515601) (xy 431.480214 -266.50771) (xy 431.431602 -266.492154) (xy 431.385963 -266.469303)
			(xy 431.364898 -266.45489) (xy 431.358309 -266.45057) (xy 431.343307 -266.445787) (xy 431.335434 -266.445492)
			(xy 430.81956 -266.445492) (xy 430.814288 -266.44503) (xy 430.806847 -266.437558) (xy 430.806352 -266.432284)
			(xy 424.762168 -266.432284) (xy 424.761859 -266.437624) (xy 424.7543 -266.445168) (xy 424.74896 -266.445492)
			(xy 424.748452 -266.445492) (xy 424.232832 -266.445492) (xy 424.224955 -266.445751) (xy 424.209951 -266.450554)
			(xy 424.203368 -266.45489) (xy 424.182293 -266.469285) (xy 424.136647 -266.492112) (xy 424.08804 -266.507668)
			(xy 424.037623 -266.515587) (xy 424.012106 -266.516104) (xy 423.986585 -266.515628) (xy 423.936158 -266.507729)
			(xy 423.887546 -266.492165) (xy 423.841908 -266.469307) (xy 423.820844 -266.45489) (xy 423.814267 -266.45055)
			(xy 423.799256 -266.445779) (xy 423.79138 -266.445492) (xy 423.275506 -266.445492) (xy 423.27021 -266.444977)
			(xy 423.26264 -266.437568) (xy 423.262044 -266.432284) (xy 417.21786 -266.432284) (xy 417.217558 -266.437626)
			(xy 417.209995 -266.445171) (xy 417.204652 -266.445492) (xy 415.731452 -266.445492) (xy 415.72618 -266.445035)
			(xy 415.718739 -266.437559) (xy 415.718244 -266.432284) (xy 308.118256 -266.432284) (xy 308.1177 -266.437533)
			(xy 308.110295 -266.444974) (xy 308.105048 -266.445492) (xy 308.10454 -266.445492) (xy 306.631594 -266.445492)
			(xy 306.626297 -266.444985) (xy 306.618728 -266.43757) (xy 306.618132 -266.432284) (xy 300.573948 -266.432284)
			(xy 300.573399 -266.437535) (xy 300.565989 -266.444976) (xy 300.56074 -266.445492) (xy 300.044866 -266.445492)
			(xy 300.03699 -266.445766) (xy 300.021986 -266.450558) (xy 300.015402 -266.45489) (xy 299.994318 -266.469271)
			(xy 299.948675 -266.4921) (xy 299.900071 -266.507661) (xy 299.849656 -266.515584) (xy 299.82414 -266.516104)
			(xy 299.79862 -266.515611) (xy 299.748193 -266.507717) (xy 299.699582 -266.492158) (xy 299.653943 -266.469305)
			(xy 299.632878 -266.45489) (xy 299.626294 -266.450563) (xy 299.611288 -266.445784) (xy 299.603414 -266.445492)
			(xy 299.08754 -266.445492) (xy 299.082209 -266.445145) (xy 299.074665 -266.437614) (xy 299.074332 -266.432284)
			(xy 293.030148 -266.432284) (xy 293.029599 -266.437535) (xy 293.022189 -266.444976) (xy 293.01694 -266.445492)
			(xy 293.016432 -266.445492) (xy 292.500812 -266.445492) (xy 292.492938 -266.445785) (xy 292.477933 -266.450564)
			(xy 292.471348 -266.45489) (xy 292.450279 -266.469294) (xy 292.404631 -266.492118) (xy 292.356022 -266.507672)
			(xy 292.305603 -266.515588) (xy 292.280086 -266.516104) (xy 292.254567 -266.515588) (xy 292.204141 -266.507701)
			(xy 292.155529 -266.492149) (xy 292.10989 -266.469302) (xy 292.088824 -266.45489) (xy 292.082229 -266.45058)
			(xy 292.067232 -266.445791) (xy 292.05936 -266.445492) (xy 291.543486 -266.445492) (xy 291.538188 -266.44499)
			(xy 291.530619 -266.437571) (xy 291.530024 -266.432284) (xy 285.48584 -266.432284) (xy 285.485298 -266.437537)
			(xy 285.477883 -266.444979) (xy 285.472632 -266.445492) (xy 284.956758 -266.445492) (xy 284.948882 -266.445762)
			(xy 284.933878 -266.450557) (xy 284.927294 -266.45489) (xy 284.906212 -266.469274) (xy 284.860568 -266.492103)
			(xy 284.811964 -266.507663) (xy 284.761548 -266.515585) (xy 284.736032 -266.516104) (xy 284.710512 -266.515615)
			(xy 284.660085 -266.50772) (xy 284.611473 -266.49216) (xy 284.565835 -266.469305) (xy 284.54477 -266.45489)
			(xy 284.538188 -266.45056) (xy 284.52318 -266.445783) (xy 284.515306 -266.445492) (xy 283.999432 -266.445492)
			(xy 283.9941 -266.44515) (xy 283.986556 -266.437615) (xy 283.986224 -266.432284) (xy 277.94204 -266.432284)
			(xy 277.941498 -266.437537) (xy 277.934083 -266.444979) (xy 277.928832 -266.445492) (xy 277.412958 -266.445492)
			(xy 277.405082 -266.445762) (xy 277.390078 -266.450557) (xy 277.383494 -266.45489) (xy 277.362412 -266.469274)
			(xy 277.316768 -266.492103) (xy 277.268164 -266.507663) (xy 277.217748 -266.515585) (xy 277.192232 -266.516104)
			(xy 277.166712 -266.515615) (xy 277.116285 -266.50772) (xy 277.067673 -266.49216) (xy 277.022035 -266.469305)
			(xy 277.00097 -266.45489) (xy 276.994388 -266.45056) (xy 276.97938 -266.445783) (xy 276.971506 -266.445492)
			(xy 276.455632 -266.445492) (xy 276.4503 -266.44515) (xy 276.442756 -266.437615) (xy 276.442424 -266.432284)
			(xy 270.39824 -266.432284) (xy 270.397698 -266.437537) (xy 270.390283 -266.444979) (xy 270.385032 -266.445492)
			(xy 270.384524 -266.445492) (xy 269.868904 -266.445492) (xy 269.86103 -266.445782) (xy 269.846025 -266.450563)
			(xy 269.83944 -266.45489) (xy 269.818373 -266.469297) (xy 269.772724 -266.492121) (xy 269.724115 -266.507674)
			(xy 269.673696 -266.515589) (xy 269.648178 -266.516104) (xy 269.622659 -266.515592) (xy 269.572233 -266.507704)
			(xy 269.523621 -266.49215) (xy 269.477982 -266.469302) (xy 269.456916 -266.45489) (xy 269.450323 -266.450577)
			(xy 269.435324 -266.445789) (xy 269.427452 -266.445492) (xy 268.911578 -266.445492) (xy 268.906279 -266.444995)
			(xy 268.898711 -266.437573) (xy 268.898116 -266.432284) (xy 206.997808 -266.432284) (xy 206.997808 -266.432538)
			(xy 206.997308 -266.437836) (xy 206.989887 -266.445402) (xy 206.9846 -266.446) (xy 206.468726 -266.446)
			(xy 206.460917 -266.446325) (xy 206.446045 -266.451103) (xy 206.439516 -266.455398) (xy 206.418383 -266.46973)
			(xy 206.372664 -266.492462) (xy 206.323994 -266.507897) (xy 206.27353 -266.515669) (xy 206.248 -266.516104)
			(xy 206.22247 -266.51566) (xy 206.172007 -266.507885) (xy 206.123335 -266.492458) (xy 206.077607 -266.469744)
			(xy 206.056484 -266.455398) (xy 206.049955 -266.451102) (xy 206.035083 -266.446322) (xy 206.027274 -266.446)
			(xy 205.5114 -266.446) (xy 205.506066 -266.445673) (xy 205.498524 -266.438126) (xy 205.498192 -266.432792)
			(xy 199.453984 -266.432792) (xy 199.453508 -266.437836) (xy 199.446087 -266.445402) (xy 199.4408 -266.446)
			(xy 198.924926 -266.446) (xy 198.917117 -266.446325) (xy 198.902245 -266.451103) (xy 198.895716 -266.455398)
			(xy 198.874583 -266.46973) (xy 198.828864 -266.492462) (xy 198.780194 -266.507897) (xy 198.72973 -266.515669)
			(xy 198.7042 -266.516104) (xy 198.67867 -266.51566) (xy 198.628207 -266.507885) (xy 198.579535 -266.492458)
			(xy 198.533807 -266.469744) (xy 198.512684 -266.455398) (xy 198.506155 -266.451102) (xy 198.491283 -266.446322)
			(xy 198.483474 -266.446) (xy 197.9676 -266.446) (xy 197.962266 -266.445673) (xy 197.954724 -266.438126)
			(xy 197.954392 -266.432792) (xy 191.910183 -266.432792) (xy 191.909679 -266.437895) (xy 191.902103 -266.445476)
			(xy 191.896746 -266.446) (xy 191.380872 -266.446) (xy 191.373061 -266.446302) (xy 191.35819 -266.451096)
			(xy 191.351662 -266.455398) (xy 191.330544 -266.469754) (xy 191.28482 -266.49248) (xy 191.236145 -266.507909)
			(xy 191.185677 -266.515673) (xy 191.160146 -266.516104) (xy 191.134617 -266.515637) (xy 191.084155 -266.507869)
			(xy 191.035482 -266.492449) (xy 190.989753 -266.469741) (xy 190.96863 -266.455398) (xy 190.962091 -266.451119)
			(xy 190.947227 -266.446329) (xy 190.93942 -266.446) (xy 190.423546 -266.446) (xy 190.418126 -266.445594)
			(xy 190.41044 -266.437955) (xy 190.410084 -266.432538) (xy 184.3659 -266.432538) (xy 184.365407 -266.437838)
			(xy 184.357981 -266.445404) (xy 184.352692 -266.446) (xy 183.836818 -266.446) (xy 183.829009 -266.446321)
			(xy 183.814137 -266.451102) (xy 183.807608 -266.455398) (xy 183.786477 -266.469734) (xy 183.740757 -266.492465)
			(xy 183.692087 -266.507899) (xy 183.641622 -266.515669) (xy 183.616092 -266.516104) (xy 183.590562 -266.515664)
			(xy 183.540099 -266.507888) (xy 183.491426 -266.49246) (xy 183.445698 -266.469745) (xy 183.424576 -266.455398)
			(xy 183.418049 -266.451099) (xy 183.403176 -266.446321) (xy 183.395366 -266.446) (xy 182.879492 -266.446)
			(xy 182.874226 -266.44551) (xy 182.866784 -266.438058) (xy 182.866284 -266.432792) (xy 176.822075 -266.432792)
			(xy 176.821579 -266.437897) (xy 176.813997 -266.445479) (xy 176.808638 -266.446) (xy 176.292764 -266.446)
			(xy 176.284956 -266.446341) (xy 176.270085 -266.451108) (xy 176.263554 -266.455398) (xy 176.242439 -266.469757)
			(xy 176.196713 -266.492483) (xy 176.148038 -266.507911) (xy 176.09757 -266.515673) (xy 176.072038 -266.516104)
			(xy 176.046509 -266.515641) (xy 175.996046 -266.507872) (xy 175.947374 -266.49245) (xy 175.901645 -266.469742)
			(xy 175.880522 -266.455398) (xy 175.873985 -266.451116) (xy 175.859119 -266.446327) (xy 175.851312 -266.446)
			(xy 175.335438 -266.446) (xy 175.330088 -266.445428) (xy 175.322502 -266.437885) (xy 175.321976 -266.432538)
			(xy 169.277792 -266.432538) (xy 169.277306 -266.437839) (xy 169.269875 -266.445406) (xy 169.264584 -266.446)
			(xy 167.791384 -266.446) (xy 167.786117 -266.445515) (xy 167.778675 -266.43806) (xy 167.778176 -266.432792)
			(xy 60.178164 -266.432792) (xy 60.177677 -266.4379) (xy 60.170089 -266.445482) (xy 60.164726 -266.446)
			(xy 58.691526 -266.446) (xy 58.686174 -266.445436) (xy 58.678589 -266.437887) (xy 58.678064 -266.432538)
			(xy 52.63388 -266.432538) (xy 52.633404 -266.437842) (xy 52.625967 -266.44541) (xy 52.620672 -266.446)
			(xy 52.104798 -266.446) (xy 52.096988 -266.446313) (xy 52.082116 -266.451099) (xy 52.075588 -266.455398)
			(xy 52.054463 -266.469742) (xy 52.008741 -266.492472) (xy 51.960069 -266.507903) (xy 51.909603 -266.515671)
			(xy 51.884072 -266.516104) (xy 51.858542 -266.515674) (xy 51.808078 -266.507895) (xy 51.759406 -266.492464)
			(xy 51.713678 -266.469746) (xy 51.692556 -266.455398) (xy 51.686034 -266.451091) (xy 51.671157 -266.446318)
			(xy 51.663346 -266.446) (xy 51.147472 -266.446) (xy 51.142204 -266.445523) (xy 51.134762 -266.438061)
			(xy 51.134264 -266.432792) (xy 45.090056 -266.432792) (xy 45.089576 -266.437902) (xy 45.081983 -266.445484)
			(xy 45.076618 -266.446) (xy 44.560744 -266.446) (xy 44.552936 -266.446332) (xy 44.538064 -266.451105)
			(xy 44.531534 -266.455398) (xy 44.510424 -266.469766) (xy 44.464697 -266.49249) (xy 44.41602 -266.507915)
			(xy 44.36555 -266.515675) (xy 44.340018 -266.516104) (xy 44.314488 -266.515651) (xy 44.264026 -266.507879)
			(xy 44.215353 -266.492455) (xy 44.169625 -266.469743) (xy 44.148502 -266.455398) (xy 44.141969 -266.451109)
			(xy 44.1271 -266.446324) (xy 44.119292 -266.446) (xy 43.603418 -266.446) (xy 43.598065 -266.445442)
			(xy 43.590481 -266.437889) (xy 43.589956 -266.432538) (xy 37.545772 -266.432538) (xy 37.545303 -266.437844)
			(xy 37.537861 -266.445412) (xy 37.532564 -266.446) (xy 37.01669 -266.446) (xy 37.00888 -266.446309)
			(xy 36.994008 -266.451098) (xy 36.98748 -266.455398) (xy 36.966357 -266.469746) (xy 36.920634 -266.492474)
			(xy 36.871961 -266.507905) (xy 36.821495 -266.515671) (xy 36.795964 -266.516104) (xy 36.770433 -266.515678)
			(xy 36.719969 -266.507898) (xy 36.671297 -266.492465) (xy 36.62557 -266.469746) (xy 36.604448 -266.455398)
			(xy 36.597927 -266.451088) (xy 36.583049 -266.446317) (xy 36.575238 -266.446) (xy 36.059364 -266.446)
			(xy 36.054095 -266.445528) (xy 36.046654 -266.438063) (xy 36.046156 -266.432792) (xy 30.00195 -266.432792)
			(xy 30.001503 -266.437844) (xy 29.994061 -266.445412) (xy 29.988764 -266.446) (xy 29.47289 -266.446)
			(xy 29.46508 -266.446309) (xy 29.450208 -266.451098) (xy 29.44368 -266.455398) (xy 29.422557 -266.469746)
			(xy 29.376834 -266.492474) (xy 29.328161 -266.507905) (xy 29.277695 -266.515671) (xy 29.252164 -266.516104)
			(xy 29.226633 -266.515678) (xy 29.176169 -266.507898) (xy 29.127497 -266.492465) (xy 29.08177 -266.469746)
			(xy 29.060648 -266.455398) (xy 29.054127 -266.451088) (xy 29.039249 -266.446317) (xy 29.031438 -266.446)
			(xy 28.515564 -266.446) (xy 28.510295 -266.445528) (xy 28.502854 -266.438063) (xy 28.502356 -266.432792)
			(xy 22.458149 -266.432792) (xy 22.457676 -266.437904) (xy 22.450077 -266.445487) (xy 22.44471 -266.446)
			(xy 21.928836 -266.446) (xy 21.921027 -266.446329) (xy 21.906156 -266.451104) (xy 21.899626 -266.455398)
			(xy 21.87849 -266.469726) (xy 21.832772 -266.492459) (xy 21.784103 -266.507895) (xy 21.73364 -266.515668)
			(xy 21.70811 -266.516104) (xy 21.68258 -266.515655) (xy 21.632117 -266.507882) (xy 21.583445 -266.492456)
			(xy 21.537717 -266.469743) (xy 21.516594 -266.455398) (xy 21.510063 -266.451105) (xy 21.495193 -266.446323)
			(xy 21.487384 -266.446) (xy 20.97151 -266.446) (xy 20.966156 -266.445447) (xy 20.958572 -266.43789)
			(xy 20.958048 -266.432538) (xy 2.509012 -266.432538) (xy 2.509012 -267.282422) (xy 16.85798 -267.282422)
			(xy 16.85798 -266.787884) (xy 16.858483 -266.782622) (xy 16.865926 -266.775181) (xy 16.871188 -266.774676)
			(xy 16.871696 -266.774676) (xy 17.38757 -266.774676) (xy 17.395379 -266.774354) (xy 17.410251 -266.769574)
			(xy 17.41678 -266.765278) (xy 17.437869 -266.750929) (xy 17.48353 -266.728198) (xy 17.532136 -266.712739)
			(xy 17.582539 -266.704916) (xy 17.633545 -266.704916) (xy 17.683948 -266.712739) (xy 17.732554 -266.728198)
			(xy 17.778215 -266.750929) (xy 17.799304 -266.765278) (xy 17.805837 -266.769567) (xy 17.820706 -266.774352)
			(xy 17.828514 -266.774676) (xy 18.344642 -266.774676) (xy 18.34996 -266.775099) (xy 18.357531 -266.782573)
			(xy 18.358104 -266.787884) (xy 18.358104 -267.282422) (xy 18.358079 -267.282676) (xy 24.402288 -267.282676)
			(xy 24.402288 -267.282168) (xy 24.402288 -266.787884) (xy 24.402783 -266.78262) (xy 24.410232 -266.775179)
			(xy 24.415496 -266.774676) (xy 24.931624 -266.774676) (xy 24.939435 -266.774377) (xy 24.954307 -266.769581)
			(xy 24.960834 -266.765278) (xy 24.981923 -266.750929) (xy 25.027584 -266.728198) (xy 25.07619 -266.712739)
			(xy 25.126593 -266.704916) (xy 25.177599 -266.704916) (xy 25.228002 -266.712739) (xy 25.276608 -266.728198)
			(xy 25.322269 -266.750929) (xy 25.343358 -266.765278) (xy 25.349879 -266.769588) (xy 25.364757 -266.77436)
			(xy 25.372568 -266.774676) (xy 25.888696 -266.774676) (xy 25.893954 -266.775196) (xy 25.901396 -266.782626)
			(xy 25.901904 -266.787884) (xy 25.901904 -267.282422) (xy 25.90188 -267.282676) (xy 31.946088 -267.282676)
			(xy 31.946088 -267.282168) (xy 31.946088 -266.787884) (xy 31.946583 -266.78262) (xy 31.954032 -266.775179)
			(xy 31.959296 -266.774676) (xy 32.475424 -266.774676) (xy 32.483235 -266.774377) (xy 32.498107 -266.769581)
			(xy 32.504634 -266.765278) (xy 32.525723 -266.750929) (xy 32.571384 -266.728198) (xy 32.61999 -266.712739)
			(xy 32.670393 -266.704916) (xy 32.721399 -266.704916) (xy 32.771802 -266.712739) (xy 32.820408 -266.728198)
			(xy 32.866069 -266.750929) (xy 32.887158 -266.765278) (xy 32.893679 -266.769588) (xy 32.908557 -266.77436)
			(xy 32.916368 -266.774676) (xy 33.432496 -266.774676) (xy 33.437754 -266.775196) (xy 33.445196 -266.782626)
			(xy 33.445704 -266.787884) (xy 33.445704 -267.282422) (xy 39.489888 -267.282422) (xy 39.489888 -266.787884)
			(xy 39.490383 -266.78262) (xy 39.497832 -266.775179) (xy 39.503096 -266.774676) (xy 39.503604 -266.774676)
			(xy 40.019478 -266.774676) (xy 40.027288 -266.774357) (xy 40.042159 -266.769575) (xy 40.048688 -266.765278)
			(xy 40.069777 -266.750929) (xy 40.115438 -266.728198) (xy 40.164044 -266.712739) (xy 40.214447 -266.704916)
			(xy 40.265453 -266.704916) (xy 40.315856 -266.712739) (xy 40.364462 -266.728198) (xy 40.410123 -266.750929)
			(xy 40.431212 -266.765278) (xy 40.437743 -266.76957) (xy 40.452613 -266.774353) (xy 40.460422 -266.774676)
			(xy 40.97655 -266.774676) (xy 40.981857 -266.775161) (xy 40.989433 -266.782588) (xy 40.990012 -266.787884)
			(xy 40.990012 -267.282422) (xy 40.989986 -267.282676) (xy 47.034196 -267.282676) (xy 47.034196 -267.282168)
			(xy 47.034196 -266.787884) (xy 47.034684 -266.782618) (xy 47.042138 -266.775176) (xy 47.047404 -266.774676)
			(xy 47.563532 -266.774676) (xy 47.57134 -266.774337) (xy 47.586212 -266.769569) (xy 47.592742 -266.765278)
			(xy 47.613831 -266.750929) (xy 47.659492 -266.728198) (xy 47.708098 -266.712739) (xy 47.758501 -266.704916)
			(xy 47.809507 -266.704916) (xy 47.85991 -266.712739) (xy 47.908516 -266.728198) (xy 47.954177 -266.750929)
			(xy 47.975266 -266.765278) (xy 47.981807 -266.769553) (xy 47.99667 -266.774346) (xy 48.004476 -266.774676)
			(xy 48.520604 -266.774676) (xy 48.525863 -266.77519) (xy 48.533305 -266.782625) (xy 48.533812 -266.787884)
			(xy 48.533812 -267.282422) (xy 54.577996 -267.282422) (xy 54.577996 -266.787884) (xy 54.578484 -266.782618)
			(xy 54.585938 -266.775176) (xy 54.591204 -266.774676) (xy 56.064658 -266.774676) (xy 56.069966 -266.775155)
			(xy 56.077541 -266.782587) (xy 56.07812 -266.787884) (xy 56.07812 -267.282422) (xy 56.078107 -267.282676)
			(xy 163.678108 -267.282676) (xy 163.678108 -267.282168) (xy 163.678108 -266.787884) (xy 163.678585 -266.782615)
			(xy 163.686046 -266.775173) (xy 163.691316 -266.774676) (xy 165.164516 -266.774676) (xy 165.169777 -266.775182)
			(xy 165.177218 -266.782623) (xy 165.177724 -266.787884) (xy 165.177724 -267.282422) (xy 171.221908 -267.282422)
			(xy 171.221908 -266.787884) (xy 171.222385 -266.782615) (xy 171.229846 -266.775173) (xy 171.235116 -266.774676)
			(xy 171.235624 -266.774676) (xy 171.751498 -266.774676) (xy 171.759308 -266.774366) (xy 171.77418 -266.769578)
			(xy 171.780708 -266.765278) (xy 171.801797 -266.750929) (xy 171.847458 -266.728198) (xy 171.896064 -266.712739)
			(xy 171.946467 -266.704916) (xy 171.997473 -266.704916) (xy 172.047876 -266.712739) (xy 172.096482 -266.728198)
			(xy 172.142143 -266.750929) (xy 172.163232 -266.765278) (xy 172.169759 -266.769578) (xy 172.184632 -266.774356)
			(xy 172.192442 -266.774676) (xy 172.70857 -266.774676) (xy 172.713879 -266.775147) (xy 172.721454 -266.782585)
			(xy 172.722032 -266.787884) (xy 172.722032 -267.282422) (xy 172.722018 -267.282676) (xy 178.766216 -267.282676)
			(xy 178.766216 -267.282168) (xy 178.766216 -266.787884) (xy 178.766518 -266.782544) (xy 178.774083 -266.775002)
			(xy 178.779424 -266.774676) (xy 179.295552 -266.774676) (xy 179.303361 -266.774346) (xy 179.318232 -266.769571)
			(xy 179.324762 -266.765278) (xy 179.345851 -266.750929) (xy 179.391512 -266.728198) (xy 179.440118 -266.712739)
			(xy 179.490521 -266.704916) (xy 179.541527 -266.704916) (xy 179.59193 -266.712739) (xy 179.640536 -266.728198)
			(xy 179.686197 -266.750929) (xy 179.707286 -266.765278) (xy 179.713823 -266.76956) (xy 179.728689 -266.774349)
			(xy 179.736496 -266.774676) (xy 180.252624 -266.774676) (xy 180.257886 -266.775177) (xy 180.265326 -266.782622)
			(xy 180.265832 -266.787884) (xy 180.265832 -267.282422) (xy 186.310016 -267.282422) (xy 186.310016 -266.787884)
			(xy 186.310318 -266.782544) (xy 186.317883 -266.775002) (xy 186.323224 -266.774676) (xy 186.323732 -266.774676)
			(xy 186.839606 -266.774676) (xy 186.847417 -266.774369) (xy 186.862288 -266.769579) (xy 186.868816 -266.765278)
			(xy 186.889905 -266.750929) (xy 186.935566 -266.728198) (xy 186.984172 -266.712739) (xy 187.034575 -266.704916)
			(xy 187.085581 -266.704916) (xy 187.135984 -266.712739) (xy 187.18459 -266.728198) (xy 187.230251 -266.750929)
			(xy 187.25134 -266.765278) (xy 187.257865 -266.769581) (xy 187.27274 -266.774357) (xy 187.28055 -266.774676)
			(xy 187.796678 -266.774676) (xy 187.801988 -266.775142) (xy 187.809562 -266.782584) (xy 187.81014 -266.787884)
			(xy 187.81014 -267.282422) (xy 187.810117 -267.282676) (xy 193.854324 -267.282676) (xy 193.854324 -267.282168)
			(xy 193.854324 -266.787884) (xy 193.854619 -266.782542) (xy 193.862188 -266.775) (xy 193.867532 -266.774676)
			(xy 194.38366 -266.774676) (xy 194.391469 -266.774349) (xy 194.40634 -266.769572) (xy 194.41287 -266.765278)
			(xy 194.433959 -266.750929) (xy 194.47962 -266.728198) (xy 194.528226 -266.712739) (xy 194.578629 -266.704916)
			(xy 194.629635 -266.704916) (xy 194.680038 -266.712739) (xy 194.728644 -266.728198) (xy 194.774305 -266.750929)
			(xy 194.795394 -266.765278) (xy 194.801929 -266.769563) (xy 194.816796 -266.77435) (xy 194.824604 -266.774676)
			(xy 195.340732 -266.774676) (xy 195.345995 -266.775172) (xy 195.353435 -266.782621) (xy 195.35394 -266.787884)
			(xy 195.35394 -267.282422) (xy 195.353918 -267.282676) (xy 201.398124 -267.282676) (xy 201.398124 -267.282168)
			(xy 201.398124 -266.787884) (xy 201.398419 -266.782542) (xy 201.405988 -266.775) (xy 201.411332 -266.774676)
			(xy 201.92746 -266.774676) (xy 201.935269 -266.774349) (xy 201.95014 -266.769572) (xy 201.95667 -266.765278)
			(xy 201.977759 -266.750929) (xy 202.02342 -266.728198) (xy 202.072026 -266.712739) (xy 202.122429 -266.704916)
			(xy 202.173435 -266.704916) (xy 202.223838 -266.712739) (xy 202.272444 -266.728198) (xy 202.318105 -266.750929)
			(xy 202.339194 -266.765278) (xy 202.345729 -266.769563) (xy 202.360596 -266.77435) (xy 202.368404 -266.774676)
			(xy 202.884532 -266.774676) (xy 202.889795 -266.775172) (xy 202.897235 -266.782621) (xy 202.89774 -266.787884)
			(xy 202.89774 -267.282168) (xy 264.798048 -267.282168) (xy 264.798048 -266.78763) (xy 264.798401 -266.782197)
			(xy 264.806077 -266.774509) (xy 264.81151 -266.774168) (xy 265.327638 -266.774168) (xy 265.335446 -266.773833)
			(xy 265.350318 -266.769062) (xy 265.356848 -266.76477) (xy 265.377937 -266.750421) (xy 265.423598 -266.72769)
			(xy 265.472204 -266.712231) (xy 265.522607 -266.704408) (xy 265.573613 -266.704408) (xy 265.624016 -266.712231)
			(xy 265.672622 -266.72769) (xy 265.718283 -266.750421) (xy 265.739372 -266.76477) (xy 265.745912 -266.769046)
			(xy 265.760776 -266.773839) (xy 265.768582 -266.774168) (xy 266.28471 -266.774168) (xy 266.290154 -266.774475)
			(xy 266.297841 -266.782185) (xy 266.298172 -266.78763) (xy 266.298172 -267.282168) (xy 272.342356 -267.282168)
			(xy 272.342356 -266.78763) (xy 272.342845 -266.782326) (xy 272.35027 -266.774752) (xy 272.355564 -266.774168)
			(xy 272.871692 -266.774168) (xy 272.879502 -266.773856) (xy 272.894374 -266.76907) (xy 272.900902 -266.76477)
			(xy 272.921991 -266.750421) (xy 272.967652 -266.72769) (xy 273.016258 -266.712231) (xy 273.066661 -266.704408)
			(xy 273.117667 -266.704408) (xy 273.16807 -266.712231) (xy 273.216676 -266.72769) (xy 273.262337 -266.750421)
			(xy 273.283426 -266.76477) (xy 273.289954 -266.769067) (xy 273.304827 -266.773847) (xy 273.312636 -266.774168)
			(xy 273.828764 -266.774168) (xy 273.834086 -266.774549) (xy 273.841627 -266.782056) (xy 273.841972 -266.787376)
			(xy 273.841972 -266.787884) (xy 273.841972 -267.282168) (xy 279.886156 -267.282168) (xy 279.886156 -266.78763)
			(xy 279.886645 -266.782326) (xy 279.89407 -266.774752) (xy 279.899364 -266.774168) (xy 280.415492 -266.774168)
			(xy 280.423302 -266.773856) (xy 280.438174 -266.76907) (xy 280.444702 -266.76477) (xy 280.465791 -266.750421)
			(xy 280.511452 -266.72769) (xy 280.560058 -266.712231) (xy 280.610461 -266.704408) (xy 280.661467 -266.704408)
			(xy 280.71187 -266.712231) (xy 280.760476 -266.72769) (xy 280.806137 -266.750421) (xy 280.827226 -266.76477)
			(xy 280.833754 -266.769067) (xy 280.848627 -266.773847) (xy 280.856436 -266.774168) (xy 281.372564 -266.774168)
			(xy 281.377886 -266.774549) (xy 281.385427 -266.782056) (xy 281.385772 -266.787376) (xy 281.385772 -266.787884)
			(xy 281.385772 -267.282168) (xy 287.429956 -267.282168) (xy 287.429956 -266.78763) (xy 287.430301 -266.782195)
			(xy 287.437983 -266.774506) (xy 287.443418 -266.774168) (xy 287.959546 -266.774168) (xy 287.967355 -266.773837)
			(xy 287.982226 -266.769063) (xy 287.988756 -266.76477) (xy 288.009845 -266.750421) (xy 288.055506 -266.72769)
			(xy 288.104112 -266.712231) (xy 288.154515 -266.704408) (xy 288.205521 -266.704408) (xy 288.255924 -266.712231)
			(xy 288.30453 -266.72769) (xy 288.350191 -266.750421) (xy 288.37128 -266.76477) (xy 288.377819 -266.769049)
			(xy 288.392683 -266.77384) (xy 288.40049 -266.774168) (xy 288.916618 -266.774168) (xy 288.922063 -266.77447)
			(xy 288.929749 -266.782184) (xy 288.93008 -266.78763) (xy 288.93008 -267.282168) (xy 294.974264 -267.282168)
			(xy 294.974264 -266.78763) (xy 294.974746 -266.782324) (xy 294.982176 -266.77475) (xy 294.987472 -266.774168)
			(xy 295.5036 -266.774168) (xy 295.511411 -266.77386) (xy 295.526282 -266.769071) (xy 295.53281 -266.76477)
			(xy 295.553899 -266.750421) (xy 295.59956 -266.72769) (xy 295.648166 -266.712231) (xy 295.698569 -266.704408)
			(xy 295.749575 -266.704408) (xy 295.799978 -266.712231) (xy 295.848584 -266.72769) (xy 295.894245 -266.750421)
			(xy 295.915334 -266.76477) (xy 295.921861 -266.76907) (xy 295.936734 -266.773848) (xy 295.944544 -266.774168)
			(xy 296.460672 -266.774168) (xy 296.465995 -266.774543) (xy 296.473536 -266.782055) (xy 296.47388 -266.787376)
			(xy 296.47388 -266.787884) (xy 296.47388 -267.282168) (xy 302.518064 -267.282168) (xy 302.518064 -266.78763)
			(xy 302.518402 -266.782193) (xy 302.526089 -266.774504) (xy 302.531526 -266.774168) (xy 304.004726 -266.774168)
			(xy 304.010172 -266.774465) (xy 304.017858 -266.782183) (xy 304.018188 -266.78763) (xy 304.018188 -267.282168)
			(xy 411.618176 -267.282168) (xy 411.618176 -266.78763) (xy 411.618647 -266.782321) (xy 411.626085 -266.774746)
			(xy 411.631384 -266.774168) (xy 413.104584 -266.774168) (xy 413.109839 -266.774703) (xy 413.117281 -266.782122)
			(xy 413.117792 -266.787376) (xy 413.117792 -266.787884) (xy 413.117792 -267.282168) (xy 419.161976 -267.282168)
			(xy 419.161976 -266.78763) (xy 419.162303 -266.78219) (xy 419.169998 -266.7745) (xy 419.175438 -266.774168)
			(xy 419.691566 -266.774168) (xy 419.699375 -266.773845) (xy 419.714247 -266.769066) (xy 419.720776 -266.76477)
			(xy 419.741865 -266.750421) (xy 419.787526 -266.72769) (xy 419.836132 -266.712231) (xy 419.886535 -266.704408)
			(xy 419.937541 -266.704408) (xy 419.987944 -266.712231) (xy 420.03655 -266.72769) (xy 420.082211 -266.750421)
			(xy 420.1033 -266.76477) (xy 420.109834 -266.769057) (xy 420.124702 -266.773843) (xy 420.13251 -266.774168)
			(xy 420.648638 -266.774168) (xy 420.654014 -266.774628) (xy 420.661599 -266.782252) (xy 420.6621 -266.78763)
			(xy 420.6621 -267.282168) (xy 426.706284 -267.282168) (xy 426.706284 -266.78763) (xy 426.706748 -266.782319)
			(xy 426.71419 -266.774744) (xy 426.719492 -266.774168) (xy 427.23562 -266.774168) (xy 427.243431 -266.773868)
			(xy 427.258303 -266.769073) (xy 427.26483 -266.76477) (xy 427.285919 -266.750421) (xy 427.33158 -266.72769)
			(xy 427.380186 -266.712231) (xy 427.430589 -266.704408) (xy 427.481595 -266.704408) (xy 427.531998 -266.712231)
			(xy 427.580604 -266.72769) (xy 427.626265 -266.750421) (xy 427.647354 -266.76477) (xy 427.653876 -266.769078)
			(xy 427.668753 -266.773851) (xy 427.676564 -266.774168) (xy 428.192692 -266.774168) (xy 428.197948 -266.774697)
			(xy 428.20539 -266.782121) (xy 428.2059 -266.787376) (xy 428.2059 -266.787884) (xy 428.2059 -267.282168)
			(xy 434.250084 -267.282168) (xy 434.250084 -266.78763) (xy 434.250404 -266.782188) (xy 434.258104 -266.774498)
			(xy 434.263546 -266.774168) (xy 434.779674 -266.774168) (xy 434.787484 -266.773848) (xy 434.802355 -266.769067)
			(xy 434.808884 -266.76477) (xy 434.829973 -266.750421) (xy 434.875634 -266.72769) (xy 434.92424 -266.712231)
			(xy 434.974643 -266.704408) (xy 435.025649 -266.704408) (xy 435.076052 -266.712231) (xy 435.124658 -266.72769)
			(xy 435.170319 -266.750421) (xy 435.191408 -266.76477) (xy 435.19794 -266.76906) (xy 435.21281 -266.773844)
			(xy 435.220618 -266.774168) (xy 435.736746 -266.774168) (xy 435.742123 -266.774623) (xy 435.749707 -266.782251)
			(xy 435.750208 -266.78763) (xy 435.750208 -267.282168) (xy 441.794392 -267.282168) (xy 441.794392 -266.78763)
			(xy 441.794938 -266.782341) (xy 441.802324 -266.774771) (xy 441.8076 -266.774168) (xy 442.323728 -266.774168)
			(xy 442.33154 -266.773872) (xy 442.346411 -266.769074) (xy 442.352938 -266.76477) (xy 442.374027 -266.750421)
			(xy 442.419688 -266.72769) (xy 442.468294 -266.712231) (xy 442.518697 -266.704408) (xy 442.569703 -266.704408)
			(xy 442.620106 -266.712231) (xy 442.668712 -266.72769) (xy 442.714373 -266.750421) (xy 442.735462 -266.76477)
			(xy 442.742005 -266.769042) (xy 442.756866 -266.773837) (xy 442.764672 -266.774168) (xy 443.2808 -266.774168)
			(xy 443.286057 -266.774692) (xy 443.293498 -266.78212) (xy 443.294008 -266.787376) (xy 443.294008 -266.787884)
			(xy 443.294008 -267.282168) (xy 449.338192 -267.282168) (xy 449.338192 -266.78763) (xy 449.338738 -266.782341)
			(xy 449.346124 -266.774771) (xy 449.3514 -266.774168) (xy 449.867528 -266.774168) (xy 449.87534 -266.773872)
			(xy 449.890211 -266.769074) (xy 449.896738 -266.76477) (xy 449.917827 -266.750421) (xy 449.963488 -266.72769)
			(xy 450.012094 -266.712231) (xy 450.062497 -266.704408) (xy 450.113503 -266.704408) (xy 450.163906 -266.712231)
			(xy 450.212512 -266.72769) (xy 450.258173 -266.750421) (xy 450.279262 -266.76477) (xy 450.285805 -266.769042)
			(xy 450.300666 -266.773837) (xy 450.308472 -266.774168) (xy 450.8246 -266.774168) (xy 450.829857 -266.774692)
			(xy 450.837298 -266.78212) (xy 450.837808 -266.787376) (xy 450.837808 -266.787884) (xy 450.837808 -267.282168)
			(xy 450.837452 -267.287496) (xy 450.829927 -267.295039) (xy 450.8246 -267.295376) (xy 450.308726 -267.295376)
			(xy 450.300849 -267.295635) (xy 450.285845 -267.300438) (xy 450.279262 -267.304774) (xy 450.258188 -267.31917)
			(xy 450.212541 -267.341997) (xy 450.163934 -267.357553) (xy 450.113517 -267.365471) (xy 450.088 -267.365988)
			(xy 450.062479 -267.365518) (xy 450.012051 -267.357618) (xy 449.96344 -267.342052) (xy 449.917802 -267.319192)
			(xy 449.896738 -267.304774) (xy 449.890135 -267.300478) (xy 449.875144 -267.295678) (xy 449.867274 -267.295376)
			(xy 449.3514 -267.295376) (xy 449.34606 -267.29507) (xy 449.338517 -267.287509) (xy 449.338192 -267.282168)
			(xy 443.294008 -267.282168) (xy 443.293652 -267.287496) (xy 443.286127 -267.295039) (xy 443.2808 -267.295376)
			(xy 442.764926 -267.295376) (xy 442.757049 -267.295635) (xy 442.742045 -267.300438) (xy 442.735462 -267.304774)
			(xy 442.714388 -267.31917) (xy 442.668741 -267.341997) (xy 442.620134 -267.357553) (xy 442.569717 -267.365471)
			(xy 442.5442 -267.365988) (xy 442.518679 -267.365518) (xy 442.468251 -267.357618) (xy 442.41964 -267.342052)
			(xy 442.374002 -267.319192) (xy 442.352938 -267.304774) (xy 442.346335 -267.300478) (xy 442.331344 -267.295678)
			(xy 442.323474 -267.295376) (xy 441.8076 -267.295376) (xy 441.80226 -267.29507) (xy 441.794717 -267.287509)
			(xy 441.794392 -267.282168) (xy 435.750208 -267.282168) (xy 435.749852 -267.287496) (xy 435.742327 -267.295039)
			(xy 435.737 -267.295376) (xy 435.736492 -267.295376) (xy 435.220872 -267.295376) (xy 435.212997 -267.295655)
			(xy 435.197992 -267.300444) (xy 435.191408 -267.304774) (xy 435.170349 -267.319193) (xy 435.124697 -267.342015)
			(xy 435.076085 -267.357565) (xy 435.025664 -267.365475) (xy 435.000146 -267.365988) (xy 434.974626 -267.365495)
			(xy 434.924199 -267.357601) (xy 434.875587 -267.342043) (xy 434.829949 -267.319189) (xy 434.808884 -267.304774)
			(xy 434.802294 -267.300457) (xy 434.787293 -267.29567) (xy 434.77942 -267.295376) (xy 434.263546 -267.295376)
			(xy 434.258251 -267.294848) (xy 434.250678 -267.28745) (xy 434.250084 -267.282168) (xy 428.2059 -267.282168)
			(xy 428.205551 -267.287498) (xy 428.198021 -267.295041) (xy 428.192692 -267.295376) (xy 427.676818 -267.295376)
			(xy 427.668944 -267.295675) (xy 427.65394 -267.30045) (xy 427.647354 -267.304774) (xy 427.626282 -267.319173)
			(xy 427.580635 -267.341999) (xy 427.532027 -267.357555) (xy 427.481609 -267.365472) (xy 427.456092 -267.365988)
			(xy 427.430573 -267.365471) (xy 427.380147 -267.357585) (xy 427.331535 -267.342033) (xy 427.285896 -267.319186)
			(xy 427.26483 -267.304774) (xy 427.258229 -267.300475) (xy 427.243236 -267.295677) (xy 427.235366 -267.295376)
			(xy 426.719492 -267.295376) (xy 426.714151 -267.295076) (xy 426.706608 -267.28751) (xy 426.706284 -267.282168)
			(xy 420.6621 -267.282168) (xy 420.661751 -267.287498) (xy 420.654221 -267.295041) (xy 420.648892 -267.295376)
			(xy 420.648384 -267.295376) (xy 420.132764 -267.295376) (xy 420.124888 -267.295652) (xy 420.109884 -267.300443)
			(xy 420.1033 -267.304774) (xy 420.082215 -267.319154) (xy 420.036573 -267.341984) (xy 419.987969 -267.357545)
			(xy 419.937554 -267.365468) (xy 419.912038 -267.365988) (xy 419.886518 -267.365499) (xy 419.836091 -267.357604)
			(xy 419.787479 -267.342044) (xy 419.741841 -267.319189) (xy 419.720776 -267.304774) (xy 419.714187 -267.300454)
			(xy 419.699185 -267.295669) (xy 419.691312 -267.295376) (xy 419.175438 -267.295376) (xy 419.170142 -267.294853)
			(xy 419.16257 -267.287452) (xy 419.161976 -267.282168) (xy 413.117792 -267.282168) (xy 413.11745 -267.2875)
			(xy 413.109915 -267.295044) (xy 413.104584 -267.295376) (xy 411.631384 -267.295376) (xy 411.626042 -267.295081)
			(xy 411.6185 -267.287512) (xy 411.618176 -267.282168) (xy 304.018188 -267.282168) (xy 304.01785 -267.287501)
			(xy 304.010312 -267.295045) (xy 304.00498 -267.295376) (xy 302.531526 -267.295376) (xy 302.526229 -267.294861)
			(xy 302.518657 -267.287454) (xy 302.518064 -267.282168) (xy 296.47388 -267.282168) (xy 296.473549 -267.287503)
			(xy 296.466007 -267.295047) (xy 296.460672 -267.295376) (xy 295.944798 -267.295376) (xy 295.936924 -267.295666)
			(xy 295.921919 -267.300448) (xy 295.915334 -267.304774) (xy 295.894267 -267.319182) (xy 295.848618 -267.342006)
			(xy 295.800009 -267.357559) (xy 295.74959 -267.365473) (xy 295.724072 -267.365988) (xy 295.698552 -267.365481)
			(xy 295.648126 -267.357592) (xy 295.599514 -267.342037) (xy 295.553875 -267.319187) (xy 295.53281 -267.304774)
			(xy 295.526214 -267.300467) (xy 295.511218 -267.295674) (xy 295.503346 -267.295376) (xy 294.987472 -267.295376)
			(xy 294.982128 -267.295089) (xy 294.974587 -267.287513) (xy 294.974264 -267.282168) (xy 288.93008 -267.282168)
			(xy 288.929749 -267.287503) (xy 288.922207 -267.295047) (xy 288.916872 -267.295376) (xy 288.916364 -267.295376)
			(xy 288.400744 -267.295376) (xy 288.392868 -267.295643) (xy 288.377864 -267.30044) (xy 288.37128 -267.304774)
			(xy 288.350201 -267.319162) (xy 288.304556 -267.341991) (xy 288.255951 -267.357549) (xy 288.205534 -267.36547)
			(xy 288.180018 -267.365988) (xy 288.154497 -267.365509) (xy 288.10407 -267.357611) (xy 288.055458 -267.342048)
			(xy 288.00982 -267.319191) (xy 287.988756 -267.304774) (xy 287.982172 -267.300446) (xy 287.967166 -267.295666)
			(xy 287.959292 -267.295376) (xy 287.443418 -267.295376) (xy 287.43812 -267.294867) (xy 287.430548 -267.287455)
			(xy 287.429956 -267.282168) (xy 281.385772 -267.282168) (xy 281.385448 -267.287505) (xy 281.377901 -267.29505)
			(xy 281.372564 -267.295376) (xy 280.85669 -267.295376) (xy 280.848815 -267.295663) (xy 280.833811 -267.300446)
			(xy 280.827226 -267.304774) (xy 280.806162 -267.319186) (xy 280.760512 -267.342009) (xy 280.711902 -267.357561)
			(xy 280.661482 -267.365474) (xy 280.635964 -267.365988) (xy 280.610444 -267.365485) (xy 280.560018 -267.357595)
			(xy 280.511406 -267.342039) (xy 280.465767 -267.319188) (xy 280.444702 -267.304774) (xy 280.438107 -267.300464)
			(xy 280.42311 -267.295673) (xy 280.415238 -267.295376) (xy 279.899364 -267.295376) (xy 279.894089 -267.294926)
			(xy 279.886647 -267.287445) (xy 279.886156 -267.282168) (xy 273.841972 -267.282168) (xy 273.841648 -267.287505)
			(xy 273.834101 -267.29505) (xy 273.828764 -267.295376) (xy 273.31289 -267.295376) (xy 273.305015 -267.295663)
			(xy 273.290011 -267.300446) (xy 273.283426 -267.304774) (xy 273.262362 -267.319186) (xy 273.216712 -267.342009)
			(xy 273.168102 -267.357561) (xy 273.117682 -267.365474) (xy 273.092164 -267.365988) (xy 273.066644 -267.365485)
			(xy 273.016218 -267.357595) (xy 272.967606 -267.342039) (xy 272.921967 -267.319188) (xy 272.900902 -267.304774)
			(xy 272.894307 -267.300464) (xy 272.87931 -267.295673) (xy 272.871438 -267.295376) (xy 272.355564 -267.295376)
			(xy 272.350289 -267.294926) (xy 272.342847 -267.287445) (xy 272.342356 -267.282168) (xy 266.298172 -267.282168)
			(xy 266.297848 -267.287505) (xy 266.290301 -267.29505) (xy 266.284964 -267.295376) (xy 266.284456 -267.295376)
			(xy 265.768836 -267.295376) (xy 265.760959 -267.29564) (xy 265.745955 -267.300439) (xy 265.739372 -267.304774)
			(xy 265.718295 -267.319166) (xy 265.67265 -267.341993) (xy 265.624044 -267.357551) (xy 265.573627 -267.36547)
			(xy 265.54811 -267.365988) (xy 265.522589 -267.365513) (xy 265.472162 -267.357614) (xy 265.42355 -267.34205)
			(xy 265.377912 -267.319191) (xy 265.356848 -267.304774) (xy 265.350266 -267.300443) (xy 265.335259 -267.295665)
			(xy 265.327384 -267.295376) (xy 264.81151 -267.295376) (xy 264.806211 -267.294872) (xy 264.79864 -267.287456)
			(xy 264.798048 -267.282168) (xy 202.89774 -267.282168) (xy 202.89774 -267.282422) (xy 202.897289 -267.287734)
			(xy 202.889835 -267.295305) (xy 202.884532 -267.295884) (xy 202.368658 -267.295884) (xy 202.360849 -267.296208)
			(xy 202.345977 -267.300985) (xy 202.339448 -267.305282) (xy 202.318341 -267.319653) (xy 202.272611 -267.342374)
			(xy 202.223934 -267.357798) (xy 202.173464 -267.365558) (xy 202.147932 -267.365988) (xy 202.122403 -267.365531)
			(xy 202.07194 -267.357761) (xy 202.023267 -267.342337) (xy 201.977539 -267.319627) (xy 201.956416 -267.305282)
			(xy 201.949875 -267.301006) (xy 201.935013 -267.296212) (xy 201.927206 -267.295884) (xy 201.411332 -267.295884)
			(xy 201.405998 -267.295549) (xy 201.398454 -267.28801) (xy 201.398124 -267.282676) (xy 195.353918 -267.282676)
			(xy 195.353489 -267.287734) (xy 195.346035 -267.295305) (xy 195.340732 -267.295884) (xy 194.824858 -267.295884)
			(xy 194.817049 -267.296208) (xy 194.802177 -267.300985) (xy 194.795648 -267.305282) (xy 194.774541 -267.319653)
			(xy 194.728811 -267.342374) (xy 194.680134 -267.357798) (xy 194.629664 -267.365558) (xy 194.604132 -267.365988)
			(xy 194.578603 -267.365531) (xy 194.52814 -267.357761) (xy 194.479467 -267.342337) (xy 194.433739 -267.319627)
			(xy 194.412616 -267.305282) (xy 194.406075 -267.301006) (xy 194.391213 -267.296212) (xy 194.383406 -267.295884)
			(xy 193.867532 -267.295884) (xy 193.862198 -267.295549) (xy 193.854654 -267.28801) (xy 193.854324 -267.282676)
			(xy 187.810117 -267.282676) (xy 187.809662 -267.287794) (xy 187.802052 -267.29538) (xy 187.796678 -267.295884)
			(xy 187.280804 -267.295884) (xy 187.272993 -267.296185) (xy 187.258121 -267.300978) (xy 187.251594 -267.305282)
			(xy 187.230474 -267.319634) (xy 187.184749 -267.342359) (xy 187.136076 -267.357788) (xy 187.085609 -267.365555)
			(xy 187.060078 -267.365988) (xy 187.034548 -267.365558) (xy 186.984084 -267.35778) (xy 186.935411 -267.342348)
			(xy 186.889684 -267.31963) (xy 186.868562 -267.305282) (xy 186.862033 -267.300985) (xy 186.847161 -267.296204)
			(xy 186.839352 -267.295884) (xy 186.323478 -267.295884) (xy 186.318117 -267.295366) (xy 186.310534 -267.287783)
			(xy 186.310016 -267.282422) (xy 180.265832 -267.282422) (xy 180.265388 -267.287735) (xy 180.257929 -267.295307)
			(xy 180.252624 -267.295884) (xy 179.73675 -267.295884) (xy 179.72894 -267.296205) (xy 179.714068 -267.300984)
			(xy 179.70754 -267.305282) (xy 179.686435 -267.319657) (xy 179.640705 -267.342377) (xy 179.592027 -267.3578)
			(xy 179.541556 -267.365559) (xy 179.516024 -267.365988) (xy 179.490494 -267.365535) (xy 179.440031 -267.357764)
			(xy 179.391359 -267.342339) (xy 179.345631 -267.319627) (xy 179.324508 -267.305282) (xy 179.317969 -267.301003)
			(xy 179.303105 -267.296211) (xy 179.295298 -267.295884) (xy 178.779424 -267.295884) (xy 178.774089 -267.295555)
			(xy 178.766545 -267.288011) (xy 178.766216 -267.282676) (xy 172.722018 -267.282676) (xy 172.721732 -267.287867)
			(xy 172.714016 -267.295554) (xy 172.70857 -267.295884) (xy 172.192696 -267.295884) (xy 172.184884 -267.296182)
			(xy 172.170012 -267.300977) (xy 172.163486 -267.305282) (xy 172.142368 -267.319637) (xy 172.096643 -267.342362)
			(xy 172.047968 -267.35779) (xy 171.997501 -267.365555) (xy 171.97197 -267.365988) (xy 171.946439 -267.365562)
			(xy 171.895975 -267.357782) (xy 171.847303 -267.34235) (xy 171.801576 -267.319631) (xy 171.780454 -267.305282)
			(xy 171.773927 -267.300982) (xy 171.759054 -267.296203) (xy 171.751244 -267.295884) (xy 171.23537 -267.295884)
			(xy 171.230008 -267.295372) (xy 171.222425 -267.287785) (xy 171.221908 -267.282422) (xy 165.177724 -267.282422)
			(xy 165.177287 -267.287737) (xy 165.169824 -267.295309) (xy 165.164516 -267.295884) (xy 163.691316 -267.295884)
			(xy 163.68598 -267.29556) (xy 163.678437 -267.288012) (xy 163.678108 -267.282676) (xy 56.078107 -267.282676)
			(xy 56.077831 -267.28787) (xy 56.070108 -267.295557) (xy 56.064658 -267.295884) (xy 54.591458 -267.295884)
			(xy 54.586094 -267.29538) (xy 54.578512 -267.287786) (xy 54.577996 -267.282422) (xy 48.533812 -267.282422)
			(xy 48.533386 -267.28774) (xy 48.525915 -267.295313) (xy 48.520604 -267.295884) (xy 48.00473 -267.295884)
			(xy 47.99692 -267.296196) (xy 47.982048 -267.300982) (xy 47.97552 -267.305282) (xy 47.954393 -267.319622)
			(xy 47.908671 -267.34235) (xy 47.859999 -267.357783) (xy 47.809534 -267.365553) (xy 47.784004 -267.365988)
			(xy 47.758474 -267.365545) (xy 47.708011 -267.357771) (xy 47.659338 -267.342343) (xy 47.61361 -267.319628)
			(xy 47.592488 -267.305282) (xy 47.585954 -267.300995) (xy 47.571086 -267.296208) (xy 47.563278 -267.295884)
			(xy 47.047404 -267.295884) (xy 47.042066 -267.295568) (xy 47.034524 -267.288014) (xy 47.034196 -267.282676)
			(xy 40.989986 -267.282676) (xy 40.989469 -267.287777) (xy 40.981903 -267.295358) (xy 40.97655 -267.295884)
			(xy 40.460676 -267.295884) (xy 40.452863 -267.296174) (xy 40.437992 -267.300975) (xy 40.431466 -267.305282)
			(xy 40.410354 -267.319646) (xy 40.364626 -267.342368) (xy 40.31595 -267.357794) (xy 40.265482 -267.365557)
			(xy 40.23995 -267.365988) (xy 40.214421 -267.365522) (xy 40.163958 -267.357754) (xy 40.115286 -267.342334)
			(xy 40.069557 -267.319625) (xy 40.048434 -267.305282) (xy 40.041889 -267.301013) (xy 40.02703 -267.296215)
			(xy 40.019224 -267.295884) (xy 39.50335 -267.295884) (xy 39.497985 -267.295385) (xy 39.490404 -267.287788)
			(xy 39.489888 -267.282422) (xy 33.445704 -267.282422) (xy 33.445197 -267.287719) (xy 33.437782 -267.295286)
			(xy 33.432496 -267.295884) (xy 32.916622 -267.295884) (xy 32.908811 -267.296193) (xy 32.893939 -267.300981)
			(xy 32.887412 -267.305282) (xy 32.866287 -267.319626) (xy 32.820564 -267.342353) (xy 32.771892 -267.357784)
			(xy 32.721427 -267.365553) (xy 32.695896 -267.365988) (xy 32.670366 -267.365549) (xy 32.619902 -267.357773)
			(xy 32.57123 -267.342345) (xy 32.525502 -267.319629) (xy 32.50438 -267.305282) (xy 32.497847 -267.300992)
			(xy 32.482978 -267.296207) (xy 32.47517 -267.295884) (xy 31.959296 -267.295884) (xy 31.953957 -267.295573)
			(xy 31.946415 -267.288015) (xy 31.946088 -267.282676) (xy 25.90188 -267.282676) (xy 25.901397 -267.287719)
			(xy 25.893982 -267.295286) (xy 25.888696 -267.295884) (xy 25.372822 -267.295884) (xy 25.365011 -267.296193)
			(xy 25.350139 -267.300981) (xy 25.343612 -267.305282) (xy 25.322487 -267.319626) (xy 25.276764 -267.342353)
			(xy 25.228092 -267.357784) (xy 25.177627 -267.365553) (xy 25.152096 -267.365988) (xy 25.126566 -267.365549)
			(xy 25.076102 -267.357773) (xy 25.02743 -267.342345) (xy 24.981702 -267.319629) (xy 24.96058 -267.305282)
			(xy 24.954047 -267.300992) (xy 24.939178 -267.296207) (xy 24.93137 -267.295884) (xy 24.415496 -267.295884)
			(xy 24.410157 -267.295573) (xy 24.402615 -267.288015) (xy 24.402288 -267.282676) (xy 18.358079 -267.282676)
			(xy 18.357568 -267.287778) (xy 18.349998 -267.29536) (xy 18.344642 -267.295884) (xy 17.828768 -267.295884)
			(xy 17.820959 -267.296212) (xy 17.806087 -267.300987) (xy 17.799558 -267.305282) (xy 17.778448 -267.319649)
			(xy 17.73272 -267.342371) (xy 17.684043 -267.357796) (xy 17.633574 -267.365557) (xy 17.608042 -267.365988)
			(xy 17.582513 -267.365526) (xy 17.53205 -267.357757) (xy 17.483378 -267.342335) (xy 17.437649 -267.319626)
			(xy 17.416526 -267.305282) (xy 17.409983 -267.30101) (xy 17.395122 -267.296213) (xy 17.387316 -267.295884)
			(xy 16.871442 -267.295884) (xy 16.866018 -267.295495) (xy 16.858331 -267.287844) (xy 16.85798 -267.282422)
			(xy 2.509012 -267.282422) (xy 2.509012 -268.13256) (xy 20.958048 -268.13256) (xy 20.958048 -267.638022)
			(xy 20.958395 -267.632588) (xy 20.966076 -267.6249) (xy 20.97151 -267.62456) (xy 21.487638 -267.62456)
			(xy 21.495446 -267.624227) (xy 21.510318 -267.619455) (xy 21.516848 -267.615162) (xy 21.537937 -267.600813)
			(xy 21.583598 -267.578082) (xy 21.632204 -267.562623) (xy 21.682607 -267.5548) (xy 21.733613 -267.5548)
			(xy 21.784016 -267.562623) (xy 21.832622 -267.578082) (xy 21.878283 -267.600813) (xy 21.899372 -267.615162)
			(xy 21.905913 -267.619437) (xy 21.920776 -267.624231) (xy 21.928582 -267.62456) (xy 22.44471 -267.62456)
			(xy 22.450152 -267.624875) (xy 22.457838 -267.63258) (xy 22.458172 -267.638022) (xy 22.458172 -268.13256)
			(xy 28.502356 -268.13256) (xy 28.502356 -267.638022) (xy 28.502839 -267.632717) (xy 28.510269 -267.625143)
			(xy 28.515564 -267.62456) (xy 29.031692 -267.62456) (xy 29.039503 -267.62425) (xy 29.054374 -267.619462)
			(xy 29.060902 -267.615162) (xy 29.081991 -267.600813) (xy 29.127652 -267.578082) (xy 29.176258 -267.562623)
			(xy 29.226661 -267.5548) (xy 29.277667 -267.5548) (xy 29.32807 -267.562623) (xy 29.376676 -267.578082)
			(xy 29.422337 -267.600813) (xy 29.443426 -267.615162) (xy 29.449955 -267.619458) (xy 29.464827 -267.624239)
			(xy 29.472636 -267.62456) (xy 29.988764 -267.62456) (xy 29.994084 -267.624948) (xy 30.001625 -267.63245)
			(xy 30.001972 -267.637768) (xy 30.001972 -267.638276) (xy 30.001972 -268.13256) (xy 36.046156 -268.13256)
			(xy 36.046156 -267.638022) (xy 36.046639 -267.632717) (xy 36.054069 -267.625143) (xy 36.059364 -267.62456)
			(xy 36.575492 -267.62456) (xy 36.583303 -267.62425) (xy 36.598174 -267.619462) (xy 36.604702 -267.615162)
			(xy 36.625791 -267.600813) (xy 36.671452 -267.578082) (xy 36.720058 -267.562623) (xy 36.770461 -267.5548)
			(xy 36.821467 -267.5548) (xy 36.87187 -267.562623) (xy 36.920476 -267.578082) (xy 36.966137 -267.600813)
			(xy 36.987226 -267.615162) (xy 36.993755 -267.619458) (xy 37.008627 -267.624239) (xy 37.016436 -267.62456)
			(xy 37.532564 -267.62456) (xy 37.537884 -267.624948) (xy 37.545425 -267.63245) (xy 37.545772 -267.637768)
			(xy 37.545772 -267.638276) (xy 37.545772 -268.13256) (xy 43.589956 -268.13256) (xy 43.589956 -267.638022)
			(xy 43.590296 -267.632586) (xy 43.597982 -267.624898) (xy 43.603418 -267.62456) (xy 44.119546 -267.62456)
			(xy 44.127355 -267.62423) (xy 44.142226 -267.619456) (xy 44.148756 -267.615162) (xy 44.169845 -267.600813)
			(xy 44.215506 -267.578082) (xy 44.264112 -267.562623) (xy 44.314515 -267.5548) (xy 44.365521 -267.5548)
			(xy 44.415924 -267.562623) (xy 44.46453 -267.578082) (xy 44.510191 -267.600813) (xy 44.53128 -267.615162)
			(xy 44.537819 -267.619441) (xy 44.552683 -267.624232) (xy 44.56049 -267.62456) (xy 45.076618 -267.62456)
			(xy 45.082061 -267.624869) (xy 45.089747 -267.632578) (xy 45.09008 -267.638022) (xy 45.09008 -268.13256)
			(xy 51.134264 -268.13256) (xy 51.134264 -267.638022) (xy 51.134741 -267.632715) (xy 51.142175 -267.625141)
			(xy 51.147472 -267.62456) (xy 51.6636 -267.62456) (xy 51.671411 -267.624253) (xy 51.686283 -267.619463)
			(xy 51.69281 -267.615162) (xy 51.713899 -267.600813) (xy 51.75956 -267.578082) (xy 51.808166 -267.562623)
			(xy 51.858569 -267.5548) (xy 51.909575 -267.5548) (xy 51.959978 -267.562623) (xy 52.008584 -267.578082)
			(xy 52.054245 -267.600813) (xy 52.075334 -267.615162) (xy 52.081861 -267.619461) (xy 52.096734 -267.62424)
			(xy 52.104544 -267.62456) (xy 52.620672 -267.62456) (xy 52.625924 -267.62511) (xy 52.633366 -267.632519)
			(xy 52.63388 -267.637768) (xy 52.63388 -267.638276) (xy 52.63388 -268.13256) (xy 58.678064 -268.13256)
			(xy 58.678064 -267.638022) (xy 58.678397 -267.632584) (xy 58.686088 -267.624895) (xy 58.691526 -267.62456)
			(xy 60.164726 -267.62456) (xy 60.170098 -267.625035) (xy 60.177684 -267.632648) (xy 60.178188 -267.638022)
			(xy 60.178188 -268.13256) (xy 167.778176 -268.13256) (xy 167.778176 -267.638022) (xy 167.778642 -267.632712)
			(xy 167.786084 -267.625138) (xy 167.791384 -267.62456) (xy 169.264584 -267.62456) (xy 169.269837 -267.625102)
			(xy 169.277279 -267.632517) (xy 169.277792 -267.637768) (xy 169.277792 -268.13256) (xy 175.321976 -268.13256)
			(xy 175.321976 -267.638022) (xy 175.322298 -267.632581) (xy 175.329997 -267.624891) (xy 175.335438 -267.62456)
			(xy 175.851566 -267.62456) (xy 175.859375 -267.624238) (xy 175.874247 -267.619458) (xy 175.880776 -267.615162)
			(xy 175.901865 -267.600813) (xy 175.947526 -267.578082) (xy 175.996132 -267.562623) (xy 176.046535 -267.5548)
			(xy 176.097541 -267.5548) (xy 176.147944 -267.562623) (xy 176.19655 -267.578082) (xy 176.242211 -267.600813)
			(xy 176.2633 -267.615162) (xy 176.269835 -267.619448) (xy 176.284702 -267.624235) (xy 176.29251 -267.62456)
			(xy 176.808638 -267.62456) (xy 176.814012 -267.625028) (xy 176.821596 -267.632646) (xy 176.8221 -267.638022)
			(xy 176.8221 -268.13256) (xy 182.866284 -268.13256) (xy 182.866284 -267.638022) (xy 182.866743 -267.63271)
			(xy 182.874189 -267.625135) (xy 182.879492 -267.62456) (xy 183.39562 -267.62456) (xy 183.403432 -267.624262)
			(xy 183.418303 -267.619466) (xy 183.42483 -267.615162) (xy 183.445919 -267.600813) (xy 183.49158 -267.578082)
			(xy 183.540186 -267.562623) (xy 183.590589 -267.5548) (xy 183.641595 -267.5548) (xy 183.691998 -267.562623)
			(xy 183.740604 -267.578082) (xy 183.786265 -267.600813) (xy 183.807354 -267.615162) (xy 183.813877 -267.619469)
			(xy 183.828753 -267.624243) (xy 183.836564 -267.62456) (xy 184.352692 -267.62456) (xy 184.357946 -267.625097)
			(xy 184.365387 -267.632515) (xy 184.3659 -267.637768) (xy 184.3659 -267.638276) (xy 184.3659 -268.13256)
			(xy 190.410084 -268.13256) (xy 190.410084 -267.638022) (xy 190.410399 -267.632579) (xy 190.418102 -267.624889)
			(xy 190.423546 -267.62456) (xy 190.939674 -267.62456) (xy 190.947484 -267.624242) (xy 190.962355 -267.619459)
			(xy 190.968884 -267.615162) (xy 190.989973 -267.600813) (xy 191.035634 -267.578082) (xy 191.08424 -267.562623)
			(xy 191.134643 -267.5548) (xy 191.185649 -267.5548) (xy 191.236052 -267.562623) (xy 191.284658 -267.578082)
			(xy 191.330319 -267.600813) (xy 191.351408 -267.615162) (xy 191.357941 -267.619451) (xy 191.37281 -267.624236)
			(xy 191.380618 -267.62456) (xy 191.896746 -267.62456) (xy 191.902121 -267.625022) (xy 191.909705 -267.632645)
			(xy 191.910208 -267.638022) (xy 191.910208 -268.13256) (xy 197.954392 -268.13256) (xy 197.954392 -267.638022)
			(xy 197.954932 -267.632732) (xy 197.962323 -267.625162) (xy 197.9676 -267.62456) (xy 198.483728 -267.62456)
			(xy 198.49154 -267.624265) (xy 198.506411 -267.619467) (xy 198.512938 -267.615162) (xy 198.534027 -267.600813)
			(xy 198.579688 -267.578082) (xy 198.628294 -267.562623) (xy 198.678697 -267.5548) (xy 198.729703 -267.5548)
			(xy 198.780106 -267.562623) (xy 198.828712 -267.578082) (xy 198.874373 -267.600813) (xy 198.895462 -267.615162)
			(xy 198.902005 -267.619434) (xy 198.916866 -267.624229) (xy 198.924672 -267.62456) (xy 199.4408 -267.62456)
			(xy 199.446055 -267.625092) (xy 199.453496 -267.632514) (xy 199.454008 -267.637768) (xy 199.454008 -267.638276)
			(xy 199.454008 -268.13256) (xy 205.498192 -268.13256) (xy 205.498192 -267.638022) (xy 205.498732 -267.632732)
			(xy 205.506123 -267.625162) (xy 205.5114 -267.62456) (xy 206.027528 -267.62456) (xy 206.03534 -267.624265)
			(xy 206.050211 -267.619467) (xy 206.056738 -267.615162) (xy 206.077827 -267.600813) (xy 206.123488 -267.578082)
			(xy 206.172094 -267.562623) (xy 206.222497 -267.5548) (xy 206.273503 -267.5548) (xy 206.323906 -267.562623)
			(xy 206.372512 -267.578082) (xy 206.418173 -267.600813) (xy 206.439262 -267.615162) (xy 206.445805 -267.619434)
			(xy 206.460666 -267.624229) (xy 206.468472 -267.62456) (xy 206.9846 -267.62456) (xy 206.989855 -267.625092)
			(xy 206.997296 -267.632514) (xy 206.997808 -267.637768) (xy 206.997808 -267.638276) (xy 206.997808 -268.132306)
			(xy 268.898116 -268.132306) (xy 268.898116 -267.637768) (xy 268.898576 -267.632496) (xy 268.90605 -267.625053)
			(xy 268.911324 -267.62456) (xy 268.911832 -267.62456) (xy 269.427706 -267.62456) (xy 269.435517 -267.624256)
			(xy 269.450389 -267.619464) (xy 269.456916 -267.615162) (xy 269.478005 -267.600813) (xy 269.523666 -267.578082)
			(xy 269.572272 -267.562623) (xy 269.622675 -267.5548) (xy 269.673681 -267.5548) (xy 269.724084 -267.562623)
			(xy 269.77269 -267.578082) (xy 269.818351 -267.600813) (xy 269.83944 -267.615162) (xy 269.845966 -267.619464)
			(xy 269.86084 -267.624241) (xy 269.86865 -267.62456) (xy 270.384778 -267.62456) (xy 270.390084 -267.62504)
			(xy 270.397658 -267.632472) (xy 270.39824 -267.637768) (xy 270.39824 -268.132306) (xy 270.398225 -268.13256)
			(xy 276.442424 -268.13256) (xy 276.442424 -268.132052) (xy 276.442424 -267.637768) (xy 276.442877 -267.632494)
			(xy 276.450355 -267.625051) (xy 276.455632 -267.62456) (xy 276.97176 -267.62456) (xy 276.979569 -267.624236)
			(xy 276.994441 -267.619458) (xy 277.00097 -267.615162) (xy 277.022059 -267.600813) (xy 277.06772 -267.578082)
			(xy 277.116326 -267.562623) (xy 277.166729 -267.5548) (xy 277.217735 -267.5548) (xy 277.268138 -267.562623)
			(xy 277.316744 -267.578082) (xy 277.362405 -267.600813) (xy 277.383494 -267.615162) (xy 277.39003 -267.619446)
			(xy 277.404896 -267.624234) (xy 277.412704 -267.62456) (xy 277.928832 -267.62456) (xy 277.934091 -267.62507)
			(xy 277.94153 -267.632509) (xy 277.94204 -267.637768) (xy 277.94204 -268.132306) (xy 277.942018 -268.13256)
			(xy 283.986224 -268.13256) (xy 283.986224 -268.132052) (xy 283.986224 -267.637768) (xy 283.986677 -267.632494)
			(xy 283.994155 -267.625051) (xy 283.999432 -267.62456) (xy 284.51556 -267.62456) (xy 284.523369 -267.624236)
			(xy 284.538241 -267.619458) (xy 284.54477 -267.615162) (xy 284.565859 -267.600813) (xy 284.61152 -267.578082)
			(xy 284.660126 -267.562623) (xy 284.710529 -267.5548) (xy 284.761535 -267.5548) (xy 284.811938 -267.562623)
			(xy 284.860544 -267.578082) (xy 284.906205 -267.600813) (xy 284.927294 -267.615162) (xy 284.93383 -267.619446)
			(xy 284.948696 -267.624234) (xy 284.956504 -267.62456) (xy 285.472632 -267.62456) (xy 285.477891 -267.62507)
			(xy 285.48533 -267.632509) (xy 285.48584 -267.637768) (xy 285.48584 -268.132306) (xy 291.530024 -268.132306)
			(xy 291.530024 -267.637768) (xy 291.530477 -267.632494) (xy 291.537955 -267.625051) (xy 291.543232 -267.62456)
			(xy 291.54374 -267.62456) (xy 292.059614 -267.62456) (xy 292.067425 -267.624259) (xy 292.082297 -267.619465)
			(xy 292.088824 -267.615162) (xy 292.109913 -267.600813) (xy 292.155574 -267.578082) (xy 292.20418 -267.562623)
			(xy 292.254583 -267.5548) (xy 292.305589 -267.5548) (xy 292.355992 -267.562623) (xy 292.404598 -267.578082)
			(xy 292.450259 -267.600813) (xy 292.471348 -267.615162) (xy 292.477872 -267.619467) (xy 292.492748 -267.624242)
			(xy 292.500558 -267.62456) (xy 293.016686 -267.62456) (xy 293.021993 -267.625035) (xy 293.029566 -267.632471)
			(xy 293.030148 -267.637768) (xy 293.030148 -268.132306) (xy 293.030133 -268.13256) (xy 299.074332 -268.13256)
			(xy 299.074332 -268.132052) (xy 299.074332 -267.637768) (xy 299.074609 -267.632422) (xy 299.082192 -267.62488)
			(xy 299.08754 -267.62456) (xy 299.603668 -267.62456) (xy 299.611478 -267.624239) (xy 299.626349 -267.619459)
			(xy 299.632878 -267.615162) (xy 299.653967 -267.600813) (xy 299.699628 -267.578082) (xy 299.748234 -267.562623)
			(xy 299.798637 -267.5548) (xy 299.849643 -267.5548) (xy 299.900046 -267.562623) (xy 299.948652 -267.578082)
			(xy 299.994313 -267.600813) (xy 300.015402 -267.615162) (xy 300.021936 -267.619449) (xy 300.036804 -267.624235)
			(xy 300.044612 -267.62456) (xy 300.56074 -267.62456) (xy 300.566 -267.625065) (xy 300.573438 -267.632508)
			(xy 300.573948 -267.637768) (xy 300.573948 -268.132306) (xy 306.618132 -268.132306) (xy 306.618132 -267.637768)
			(xy 306.618409 -267.632422) (xy 306.625992 -267.62488) (xy 306.63134 -267.62456) (xy 306.631848 -267.62456)
			(xy 308.104794 -267.62456) (xy 308.110102 -267.625029) (xy 308.117675 -267.632469) (xy 308.118256 -267.637768)
			(xy 308.118256 -268.132306) (xy 308.118232 -268.13256) (xy 415.718244 -268.13256) (xy 415.718244 -267.637768)
			(xy 415.718769 -267.632513) (xy 415.726198 -267.625075) (xy 415.731452 -267.62456) (xy 417.204652 -267.62456)
			(xy 417.20997 -267.624956) (xy 417.217512 -267.632452) (xy 417.21786 -267.637768) (xy 417.21786 -268.132306)
			(xy 423.262044 -268.132306) (xy 423.262044 -267.637768) (xy 423.262569 -267.632513) (xy 423.269998 -267.625075)
			(xy 423.275252 -267.62456) (xy 423.27576 -267.62456) (xy 423.791634 -267.62456) (xy 423.799442 -267.624225)
			(xy 423.814314 -267.619454) (xy 423.820844 -267.615162) (xy 423.841933 -267.600813) (xy 423.887594 -267.578082)
			(xy 423.9362 -267.562623) (xy 423.986603 -267.5548) (xy 424.037609 -267.5548) (xy 424.088012 -267.562623)
			(xy 424.136618 -267.578082) (xy 424.182279 -267.600813) (xy 424.203368 -267.615162) (xy 424.20991 -267.619436)
			(xy 424.224772 -267.62423) (xy 424.232578 -267.62456) (xy 424.748706 -267.62456) (xy 424.754016 -267.625021)
			(xy 424.761588 -267.632467) (xy 424.762168 -267.637768) (xy 424.762168 -268.132306) (xy 424.762144 -268.13256)
			(xy 430.806352 -268.13256) (xy 430.806352 -268.132052) (xy 430.806352 -267.637768) (xy 430.806869 -267.632511)
			(xy 430.814303 -267.625073) (xy 430.81956 -267.62456) (xy 431.335688 -267.62456) (xy 431.343498 -267.624248)
			(xy 431.35837 -267.619462) (xy 431.364898 -267.615162) (xy 431.385987 -267.600813) (xy 431.431648 -267.578082)
			(xy 431.480254 -267.562623) (xy 431.530657 -267.5548) (xy 431.581663 -267.5548) (xy 431.632066 -267.562623)
			(xy 431.680672 -267.578082) (xy 431.726333 -267.600813) (xy 431.747422 -267.615162) (xy 431.753952 -267.619457)
			(xy 431.768823 -267.624238) (xy 431.776632 -267.62456) (xy 432.29276 -267.62456) (xy 432.298079 -267.624951)
			(xy 432.30562 -267.632451) (xy 432.305968 -267.637768) (xy 432.305968 -268.132306) (xy 438.350152 -268.132306)
			(xy 438.350152 -267.637768) (xy 438.350669 -267.632511) (xy 438.358103 -267.625073) (xy 438.36336 -267.62456)
			(xy 438.363868 -267.62456) (xy 438.879742 -267.62456) (xy 438.887551 -267.624228) (xy 438.902422 -267.619455)
			(xy 438.908952 -267.615162) (xy 438.930041 -267.600813) (xy 438.975702 -267.578082) (xy 439.024308 -267.562623)
			(xy 439.074711 -267.5548) (xy 439.125717 -267.5548) (xy 439.17612 -267.562623) (xy 439.224726 -267.578082)
			(xy 439.270387 -267.600813) (xy 439.291476 -267.615162) (xy 439.298016 -267.619439) (xy 439.312879 -267.624231)
			(xy 439.320686 -267.62456) (xy 439.836814 -267.62456) (xy 439.842124 -267.625016) (xy 439.849696 -267.632466)
			(xy 439.850276 -267.637768) (xy 439.850276 -268.132306) (xy 439.850251 -268.13256) (xy 445.89446 -268.13256)
			(xy 445.89446 -268.132052) (xy 445.89446 -267.637768) (xy 445.89497 -267.632509) (xy 445.902409 -267.62507)
			(xy 445.907668 -267.62456) (xy 446.423796 -267.62456) (xy 446.431607 -267.624252) (xy 446.446478 -267.619463)
			(xy 446.453006 -267.615162) (xy 446.474095 -267.600813) (xy 446.519756 -267.578082) (xy 446.568362 -267.562623)
			(xy 446.618765 -267.5548) (xy 446.669771 -267.5548) (xy 446.720174 -267.562623) (xy 446.76878 -267.578082)
			(xy 446.814441 -267.600813) (xy 446.83553 -267.615162) (xy 446.842058 -267.61946) (xy 446.856931 -267.624239)
			(xy 446.86474 -267.62456) (xy 447.380868 -267.62456) (xy 447.386119 -267.625113) (xy 447.393562 -267.632519)
			(xy 447.394076 -267.637768) (xy 447.394076 -268.132306) (xy 447.394052 -268.13256) (xy 453.43826 -268.13256)
			(xy 453.43826 -268.132052) (xy 453.43826 -267.637768) (xy 453.43877 -267.632509) (xy 453.446209 -267.62507)
			(xy 453.451468 -267.62456) (xy 453.967596 -267.62456) (xy 453.975407 -267.624252) (xy 453.990278 -267.619463)
			(xy 453.996806 -267.615162) (xy 454.017895 -267.600813) (xy 454.063556 -267.578082) (xy 454.112162 -267.562623)
			(xy 454.162565 -267.5548) (xy 454.213571 -267.5548) (xy 454.263974 -267.562623) (xy 454.31258 -267.578082)
			(xy 454.358241 -267.600813) (xy 454.37933 -267.615162) (xy 454.385858 -267.61946) (xy 454.400731 -267.624239)
			(xy 454.40854 -267.62456) (xy 454.924668 -267.62456) (xy 454.929919 -267.625113) (xy 454.937362 -267.632519)
			(xy 454.937876 -267.637768) (xy 454.937876 -268.132306) (xy 454.937383 -268.137607) (xy 454.929959 -268.145177)
			(xy 454.924668 -268.145768) (xy 454.408794 -268.145768) (xy 454.400982 -268.146068) (xy 454.386111 -268.150862)
			(xy 454.379584 -268.155166) (xy 454.358465 -268.16952) (xy 454.31274 -268.192245) (xy 454.264066 -268.207674)
			(xy 454.213599 -268.215439) (xy 454.188068 -268.215872) (xy 454.162537 -268.21545) (xy 454.112073 -268.20767)
			(xy 454.0634 -268.192236) (xy 454.017673 -268.169515) (xy 453.996552 -268.155166) (xy 453.990027 -268.150864)
			(xy 453.975152 -268.146086) (xy 453.967342 -268.145768) (xy 453.451468 -268.145768) (xy 453.446122 -268.145491)
			(xy 453.43858 -268.137908) (xy 453.43826 -268.13256) (xy 447.394052 -268.13256) (xy 447.393583 -268.137607)
			(xy 447.386159 -268.145177) (xy 447.380868 -268.145768) (xy 446.864994 -268.145768) (xy 446.857182 -268.146068)
			(xy 446.842311 -268.150862) (xy 446.835784 -268.155166) (xy 446.814665 -268.16952) (xy 446.76894 -268.192245)
			(xy 446.720266 -268.207674) (xy 446.669799 -268.215439) (xy 446.644268 -268.215872) (xy 446.618737 -268.21545)
			(xy 446.568273 -268.20767) (xy 446.5196 -268.192236) (xy 446.473873 -268.169515) (xy 446.452752 -268.155166)
			(xy 446.446227 -268.150864) (xy 446.431352 -268.146086) (xy 446.423542 -268.145768) (xy 445.907668 -268.145768)
			(xy 445.902322 -268.145491) (xy 445.89478 -268.137908) (xy 445.89446 -268.13256) (xy 439.850251 -268.13256)
			(xy 439.849755 -268.137667) (xy 439.842175 -268.145252) (xy 439.836814 -268.145768) (xy 439.32094 -268.145768)
			(xy 439.31313 -268.146087) (xy 439.298258 -268.150868) (xy 439.29173 -268.155166) (xy 439.270627 -268.169543)
			(xy 439.224896 -268.192263) (xy 439.176217 -268.207685) (xy 439.125747 -268.215443) (xy 439.100214 -268.215872)
			(xy 439.074684 -268.215427) (xy 439.024221 -268.207654) (xy 438.975548 -268.192227) (xy 438.92982 -268.169512)
			(xy 438.908698 -268.155166) (xy 438.902162 -268.150882) (xy 438.887296 -268.146093) (xy 438.879488 -268.145768)
			(xy 438.363614 -268.145768) (xy 438.358183 -268.145412) (xy 438.350496 -268.137737) (xy 438.350152 -268.132306)
			(xy 432.305968 -268.132306) (xy 432.305482 -268.137609) (xy 432.298053 -268.145179) (xy 432.29276 -268.145768)
			(xy 431.776886 -268.145768) (xy 431.769074 -268.146064) (xy 431.754202 -268.150861) (xy 431.747676 -268.155166)
			(xy 431.72656 -268.169523) (xy 431.680834 -268.192248) (xy 431.632159 -268.207676) (xy 431.581691 -268.21544)
			(xy 431.55616 -268.215872) (xy 431.530629 -268.215454) (xy 431.480164 -268.207672) (xy 431.431492 -268.192238)
			(xy 431.385765 -268.169516) (xy 431.364644 -268.155166) (xy 431.35812 -268.150861) (xy 431.343244 -268.146085)
			(xy 431.335434 -268.145768) (xy 430.81956 -268.145768) (xy 430.814283 -268.145328) (xy 430.80684 -268.13784)
			(xy 430.806352 -268.13256) (xy 424.762144 -268.13256) (xy 424.761654 -268.137669) (xy 424.754069 -268.145254)
			(xy 424.748706 -268.145768) (xy 424.232832 -268.145768) (xy 424.225022 -268.146084) (xy 424.21015 -268.150867)
			(xy 424.203622 -268.155166) (xy 424.182493 -268.169504) (xy 424.136772 -268.192233) (xy 424.088101 -268.207666)
			(xy 424.037636 -268.215436) (xy 424.012106 -268.215872) (xy 423.986576 -268.215431) (xy 423.936112 -268.207656)
			(xy 423.88744 -268.192228) (xy 423.841712 -268.169513) (xy 423.82059 -268.155166) (xy 423.814056 -268.150879)
			(xy 423.799188 -268.146092) (xy 423.79138 -268.145768) (xy 423.275506 -268.145768) (xy 423.270144 -268.145246)
			(xy 423.262558 -268.137667) (xy 423.262044 -268.132306) (xy 417.21786 -268.132306) (xy 417.217381 -268.137611)
			(xy 417.209947 -268.145182) (xy 417.204652 -268.145768) (xy 415.731452 -268.145768) (xy 415.726174 -268.145333)
			(xy 415.718732 -268.137841) (xy 415.718244 -268.13256) (xy 308.118232 -268.13256) (xy 308.117753 -268.137672)
			(xy 308.110161 -268.145258) (xy 308.104794 -268.145768) (xy 306.631594 -268.145768) (xy 306.626231 -268.145254)
			(xy 306.618646 -268.137669) (xy 306.618132 -268.132306) (xy 300.573948 -268.132306) (xy 300.57348 -268.137614)
			(xy 300.566038 -268.145185) (xy 300.56074 -268.145768) (xy 300.044866 -268.145768) (xy 300.037057 -268.146098)
			(xy 300.022185 -268.150872) (xy 300.015656 -268.155166) (xy 299.994545 -268.169532) (xy 299.948817 -268.192255)
			(xy 299.900141 -268.20768) (xy 299.849672 -268.215441) (xy 299.82414 -268.215872) (xy 299.798611 -268.215414)
			(xy 299.748148 -268.207644) (xy 299.699475 -268.192221) (xy 299.653747 -268.169511) (xy 299.632624 -268.155166)
			(xy 299.626083 -268.150892) (xy 299.61122 -268.146097) (xy 299.603414 -268.145768) (xy 299.08754 -268.145768)
			(xy 299.082203 -268.145442) (xy 299.074658 -268.137897) (xy 299.074332 -268.13256) (xy 293.030133 -268.13256)
			(xy 293.029823 -268.137745) (xy 293.022125 -268.145431) (xy 293.016686 -268.145768) (xy 292.500812 -268.145768)
			(xy 292.493001 -268.146075) (xy 292.478129 -268.150865) (xy 292.471602 -268.155166) (xy 292.450478 -268.169512)
			(xy 292.404755 -268.192239) (xy 292.356083 -268.20767) (xy 292.305617 -268.215438) (xy 292.280086 -268.215872)
			(xy 292.254556 -268.215441) (xy 292.204092 -268.207663) (xy 292.155419 -268.192232) (xy 292.109692 -268.169514)
			(xy 292.08857 -268.155166) (xy 292.082041 -268.150871) (xy 292.067169 -268.146089) (xy 292.05936 -268.145768)
			(xy 291.543486 -268.145768) (xy 291.538122 -268.145259) (xy 291.530537 -268.13767) (xy 291.530024 -268.132306)
			(xy 285.48584 -268.132306) (xy 285.485379 -268.137616) (xy 285.477933 -268.145188) (xy 285.472632 -268.145768)
			(xy 284.956758 -268.145768) (xy 284.948949 -268.146095) (xy 284.934077 -268.150871) (xy 284.927548 -268.155166)
			(xy 284.90644 -268.169536) (xy 284.860711 -268.192257) (xy 284.812034 -268.207682) (xy 284.761564 -268.215442)
			(xy 284.736032 -268.215872) (xy 284.710502 -268.215418) (xy 284.660039 -268.207647) (xy 284.611367 -268.192223)
			(xy 284.565639 -268.169511) (xy 284.544516 -268.155166) (xy 284.537976 -268.150888) (xy 284.523113 -268.146096)
			(xy 284.515306 -268.145768) (xy 283.999432 -268.145768) (xy 283.994094 -268.145448) (xy 283.986549 -268.137898)
			(xy 283.986224 -268.13256) (xy 277.942018 -268.13256) (xy 277.941579 -268.137616) (xy 277.934133 -268.145188)
			(xy 277.928832 -268.145768) (xy 277.412958 -268.145768) (xy 277.405149 -268.146095) (xy 277.390277 -268.150871)
			(xy 277.383748 -268.155166) (xy 277.36264 -268.169536) (xy 277.316911 -268.192257) (xy 277.268234 -268.207682)
			(xy 277.217764 -268.215442) (xy 277.192232 -268.215872) (xy 277.166702 -268.215418) (xy 277.116239 -268.207647)
			(xy 277.067567 -268.192223) (xy 277.021839 -268.169511) (xy 277.000716 -268.155166) (xy 276.994176 -268.150888)
			(xy 276.979313 -268.146096) (xy 276.971506 -268.145768) (xy 276.455632 -268.145768) (xy 276.450294 -268.145448)
			(xy 276.442749 -268.137898) (xy 276.442424 -268.13256) (xy 270.398225 -268.13256) (xy 270.397922 -268.137747)
			(xy 270.39022 -268.145434) (xy 270.384778 -268.145768) (xy 269.868904 -268.145768) (xy 269.861093 -268.146072)
			(xy 269.846221 -268.150864) (xy 269.839694 -268.155166) (xy 269.818573 -268.169516) (xy 269.772849 -268.192242)
			(xy 269.724175 -268.207672) (xy 269.673709 -268.215439) (xy 269.648178 -268.215872) (xy 269.622647 -268.215445)
			(xy 269.572183 -268.207666) (xy 269.523511 -268.192234) (xy 269.477784 -268.169515) (xy 269.456662 -268.155166)
			(xy 269.450134 -268.150868) (xy 269.435262 -268.146088) (xy 269.427452 -268.145768) (xy 268.911578 -268.145768)
			(xy 268.906213 -268.145265) (xy 268.898629 -268.137672) (xy 268.898116 -268.132306) (xy 206.997808 -268.132306)
			(xy 206.997808 -268.13256) (xy 206.997446 -268.137887) (xy 206.989926 -268.14543) (xy 206.9846 -268.145768)
			(xy 206.468726 -268.145768) (xy 206.460849 -268.146028) (xy 206.445845 -268.15083) (xy 206.439262 -268.155166)
			(xy 206.418187 -268.169561) (xy 206.372541 -268.192388) (xy 206.323934 -268.207945) (xy 206.273517 -268.215863)
			(xy 206.248 -268.21638) (xy 206.222479 -268.215911) (xy 206.172051 -268.208011) (xy 206.123439 -268.192445)
			(xy 206.077802 -268.169584) (xy 206.056738 -268.155166) (xy 206.050136 -268.150869) (xy 206.035144 -268.14607)
			(xy 206.027274 -268.145768) (xy 205.5114 -268.145768) (xy 205.506058 -268.145469) (xy 205.498515 -268.137903)
			(xy 205.498192 -268.13256) (xy 199.454008 -268.13256) (xy 199.453646 -268.137887) (xy 199.446126 -268.14543)
			(xy 199.4408 -268.145768) (xy 198.924926 -268.145768) (xy 198.917049 -268.146028) (xy 198.902045 -268.15083)
			(xy 198.895462 -268.155166) (xy 198.874387 -268.169561) (xy 198.828741 -268.192388) (xy 198.780134 -268.207945)
			(xy 198.729717 -268.215863) (xy 198.7042 -268.21638) (xy 198.678679 -268.215911) (xy 198.628251 -268.208011)
			(xy 198.579639 -268.192445) (xy 198.534002 -268.169584) (xy 198.512938 -268.155166) (xy 198.506336 -268.150869)
			(xy 198.491344 -268.14607) (xy 198.483474 -268.145768) (xy 197.9676 -268.145768) (xy 197.962258 -268.145469)
			(xy 197.954715 -268.137903) (xy 197.954392 -268.13256) (xy 191.910208 -268.13256) (xy 191.909846 -268.137887)
			(xy 191.902326 -268.14543) (xy 191.897 -268.145768) (xy 191.896492 -268.145768) (xy 191.380872 -268.145768)
			(xy 191.372997 -268.146048) (xy 191.357993 -268.150837) (xy 191.351408 -268.155166) (xy 191.330348 -268.169584)
			(xy 191.284697 -268.192406) (xy 191.236085 -268.207956) (xy 191.185664 -268.215867) (xy 191.160146 -268.21638)
			(xy 191.134626 -268.215888) (xy 191.084199 -268.207995) (xy 191.035587 -268.192436) (xy 190.989949 -268.169581)
			(xy 190.968884 -268.155166) (xy 190.962294 -268.150848) (xy 190.947293 -268.146062) (xy 190.93942 -268.145768)
			(xy 190.423546 -268.145768) (xy 190.418249 -268.145247) (xy 190.410676 -268.137845) (xy 190.410084 -268.13256)
			(xy 184.3659 -268.13256) (xy 184.365545 -268.137889) (xy 184.35802 -268.145432) (xy 184.352692 -268.145768)
			(xy 183.836818 -268.145768) (xy 183.828944 -268.146068) (xy 183.81394 -268.150843) (xy 183.807354 -268.155166)
			(xy 183.786281 -268.169565) (xy 183.740634 -268.192391) (xy 183.692027 -268.207947) (xy 183.641609 -268.215864)
			(xy 183.616092 -268.21638) (xy 183.590573 -268.215865) (xy 183.540147 -268.207979) (xy 183.491535 -268.192426)
			(xy 183.445896 -268.169578) (xy 183.42483 -268.155166) (xy 183.41823 -268.150866) (xy 183.403237 -268.146069)
			(xy 183.395366 -268.145768) (xy 182.879492 -268.145768) (xy 182.874149 -268.145475) (xy 182.866606 -268.137904)
			(xy 182.866284 -268.13256) (xy 176.8221 -268.13256) (xy 176.821745 -268.137889) (xy 176.81422 -268.145432)
			(xy 176.808892 -268.145768) (xy 176.808384 -268.145768) (xy 176.292764 -268.145768) (xy 176.284888 -268.146045)
			(xy 176.269884 -268.150836) (xy 176.2633 -268.155166) (xy 176.242214 -268.169545) (xy 176.196572 -268.192376)
			(xy 176.147969 -268.207937) (xy 176.097554 -268.21586) (xy 176.072038 -268.21638) (xy 176.046518 -268.215892)
			(xy 175.996091 -268.207998) (xy 175.947479 -268.192437) (xy 175.901841 -268.169582) (xy 175.880776 -268.155166)
			(xy 175.874188 -268.150845) (xy 175.859185 -268.146061) (xy 175.851312 -268.145768) (xy 175.335438 -268.145768)
			(xy 175.33014 -268.145252) (xy 175.322568 -268.137846) (xy 175.321976 -268.13256) (xy 169.277792 -268.13256)
			(xy 169.277445 -268.137891) (xy 169.269914 -268.145435) (xy 169.264584 -268.145768) (xy 167.791384 -268.145768)
			(xy 167.78604 -268.14548) (xy 167.778497 -268.137906) (xy 167.778176 -268.13256) (xy 60.178188 -268.13256)
			(xy 60.177844 -268.137892) (xy 60.170311 -268.145436) (xy 60.16498 -268.145768) (xy 60.164472 -268.145768)
			(xy 58.691526 -268.145768) (xy 58.686227 -268.14526) (xy 58.678655 -268.137848) (xy 58.678064 -268.13256)
			(xy 52.63388 -268.13256) (xy 52.633543 -268.137894) (xy 52.626005 -268.145439) (xy 52.620672 -268.145768)
			(xy 52.104798 -268.145768) (xy 52.096924 -268.146059) (xy 52.08192 -268.15084) (xy 52.075334 -268.155166)
			(xy 52.054267 -268.169573) (xy 52.008618 -268.192397) (xy 51.960009 -268.207951) (xy 51.90959 -268.215865)
			(xy 51.884072 -268.21638) (xy 51.858552 -268.215875) (xy 51.808126 -268.207986) (xy 51.759514 -268.19243)
			(xy 51.713875 -268.169579) (xy 51.69281 -268.155166) (xy 51.686214 -268.150858) (xy 51.671218 -268.146066)
			(xy 51.663346 -268.145768) (xy 51.147472 -268.145768) (xy 51.142126 -268.145488) (xy 51.134584 -268.137908)
			(xy 51.134264 -268.13256) (xy 45.09008 -268.13256) (xy 45.089743 -268.137894) (xy 45.082205 -268.145439)
			(xy 45.076872 -268.145768) (xy 45.076364 -268.145768) (xy 44.560744 -268.145768) (xy 44.552868 -268.146036)
			(xy 44.537864 -268.150833) (xy 44.53128 -268.155166) (xy 44.5102 -268.169553) (xy 44.464556 -268.192382)
			(xy 44.415951 -268.207941) (xy 44.365534 -268.215862) (xy 44.340018 -268.21638) (xy 44.314497 -268.215902)
			(xy 44.26407 -268.208005) (xy 44.215458 -268.192441) (xy 44.16982 -268.169583) (xy 44.148756 -268.155166)
			(xy 44.142172 -268.150837) (xy 44.127166 -268.146058) (xy 44.119292 -268.145768) (xy 43.603418 -268.145768)
			(xy 43.598118 -268.145266) (xy 43.590546 -268.137849) (xy 43.589956 -268.13256) (xy 37.545772 -268.13256)
			(xy 37.545443 -268.137896) (xy 37.537899 -268.145441) (xy 37.532564 -268.145768) (xy 37.01669 -268.145768)
			(xy 37.008815 -268.146056) (xy 36.993811 -268.150839) (xy 36.987226 -268.155166) (xy 36.966161 -268.169577)
			(xy 36.920511 -268.1924) (xy 36.871902 -268.207953) (xy 36.821482 -268.215866) (xy 36.795964 -268.21638)
			(xy 36.770444 -268.215879) (xy 36.720018 -268.207988) (xy 36.671406 -268.192432) (xy 36.625767 -268.16958)
			(xy 36.604702 -268.155166) (xy 36.598108 -268.150855) (xy 36.58311 -268.146065) (xy 36.575238 -268.145768)
			(xy 36.059364 -268.145768) (xy 36.054017 -268.145493) (xy 36.046476 -268.137909) (xy 36.046156 -268.13256)
			(xy 30.001972 -268.13256) (xy 30.001643 -268.137896) (xy 29.994099 -268.145441) (xy 29.988764 -268.145768)
			(xy 29.47289 -268.145768) (xy 29.465015 -268.146056) (xy 29.450011 -268.150839) (xy 29.443426 -268.155166)
			(xy 29.422361 -268.169577) (xy 29.376711 -268.1924) (xy 29.328102 -268.207953) (xy 29.277682 -268.215866)
			(xy 29.252164 -268.21638) (xy 29.226644 -268.215879) (xy 29.176218 -268.207988) (xy 29.127606 -268.192432)
			(xy 29.081967 -268.16958) (xy 29.060902 -268.155166) (xy 29.054308 -268.150855) (xy 29.03931 -268.146065)
			(xy 29.031438 -268.145768) (xy 28.515564 -268.145768) (xy 28.510217 -268.145493) (xy 28.502676 -268.137909)
			(xy 28.502356 -268.13256) (xy 22.458172 -268.13256) (xy 22.457843 -268.137896) (xy 22.450299 -268.145441)
			(xy 22.444964 -268.145768) (xy 22.444456 -268.145768) (xy 21.928836 -268.145768) (xy 21.920959 -268.146033)
			(xy 21.905955 -268.150832) (xy 21.899372 -268.155166) (xy 21.878294 -268.169557) (xy 21.832649 -268.192385)
			(xy 21.784043 -268.207943) (xy 21.733627 -268.215862) (xy 21.70811 -268.21638) (xy 21.682589 -268.215906)
			(xy 21.632161 -268.208007) (xy 21.58355 -268.192443) (xy 21.537912 -268.169583) (xy 21.516848 -268.155166)
			(xy 21.510266 -268.150834) (xy 21.495259 -268.146057) (xy 21.487384 -268.145768) (xy 20.97151 -268.145768)
			(xy 20.966209 -268.145271) (xy 20.958637 -268.13785) (xy 20.958048 -268.13256) (xy 2.509012 -268.13256)
			(xy 2.509012 -268.982444) (xy 16.85798 -268.982444) (xy 16.85798 -268.487906) (xy 16.858287 -268.482462)
			(xy 16.865997 -268.474773) (xy 16.871442 -268.474444) (xy 17.38757 -268.474444) (xy 17.39538 -268.474127)
			(xy 17.410252 -268.469344) (xy 17.41678 -268.465046) (xy 17.437869 -268.450697) (xy 17.48353 -268.427966)
			(xy 17.532136 -268.412507) (xy 17.582539 -268.404684) (xy 17.633545 -268.404684) (xy 17.683948 -268.412507)
			(xy 17.732554 -268.427966) (xy 17.778215 -268.450697) (xy 17.799304 -268.465046) (xy 17.805839 -268.469332)
			(xy 17.820706 -268.474119) (xy 17.828514 -268.474444) (xy 18.344642 -268.474444) (xy 18.350013 -268.474923)
			(xy 18.357596 -268.482534) (xy 18.358104 -268.487906) (xy 18.358104 -268.982444) (xy 24.402288 -268.982444)
			(xy 24.402288 -268.487906) (xy 24.402733 -268.482591) (xy 24.41019 -268.475017) (xy 24.415496 -268.474444)
			(xy 24.931624 -268.474444) (xy 24.939436 -268.47415) (xy 24.954308 -268.469352) (xy 24.960834 -268.465046)
			(xy 24.981923 -268.450697) (xy 25.027584 -268.427966) (xy 25.07619 -268.412507) (xy 25.126593 -268.404684)
			(xy 25.177599 -268.404684) (xy 25.228002 -268.412507) (xy 25.276608 -268.427966) (xy 25.322269 -268.450697)
			(xy 25.343358 -268.465046) (xy 25.349881 -268.469353) (xy 25.364757 -268.474127) (xy 25.372568 -268.474444)
			(xy 25.888696 -268.474444) (xy 25.893947 -268.474992) (xy 25.901387 -268.482403) (xy 25.901904 -268.487652)
			(xy 25.901904 -268.48816) (xy 25.901904 -268.982444) (xy 31.946088 -268.982444) (xy 31.946088 -268.487906)
			(xy 31.946533 -268.482591) (xy 31.95399 -268.475017) (xy 31.959296 -268.474444) (xy 32.475424 -268.474444)
			(xy 32.483236 -268.47415) (xy 32.498108 -268.469352) (xy 32.504634 -268.465046) (xy 32.525723 -268.450697)
			(xy 32.571384 -268.427966) (xy 32.61999 -268.412507) (xy 32.670393 -268.404684) (xy 32.721399 -268.404684)
			(xy 32.771802 -268.412507) (xy 32.820408 -268.427966) (xy 32.866069 -268.450697) (xy 32.887158 -268.465046)
			(xy 32.893681 -268.469353) (xy 32.908557 -268.474127) (xy 32.916368 -268.474444) (xy 33.432496 -268.474444)
			(xy 33.437747 -268.474992) (xy 33.445187 -268.482403) (xy 33.445704 -268.487652) (xy 33.445704 -268.48816)
			(xy 33.445704 -268.982444) (xy 39.489888 -268.982444) (xy 39.489888 -268.487906) (xy 39.490449 -268.482555)
			(xy 39.498001 -268.474971) (xy 39.50335 -268.474444) (xy 40.019478 -268.474444) (xy 40.027288 -268.47413)
			(xy 40.04216 -268.469345) (xy 40.048688 -268.465046) (xy 40.069777 -268.450697) (xy 40.115438 -268.427966)
			(xy 40.164044 -268.412507) (xy 40.214447 -268.404684) (xy 40.265453 -268.404684) (xy 40.315856 -268.412507)
			(xy 40.364462 -268.427966) (xy 40.410123 -268.450697) (xy 40.431212 -268.465046) (xy 40.437745 -268.469335)
			(xy 40.452614 -268.47412) (xy 40.460422 -268.474444) (xy 40.97655 -268.474444) (xy 40.981921 -268.474918)
			(xy 40.989504 -268.482533) (xy 40.990012 -268.487906) (xy 40.990012 -268.982444) (xy 47.034196 -268.982444)
			(xy 47.034196 -268.487906) (xy 47.034722 -268.482613) (xy 47.042123 -268.475044) (xy 47.047404 -268.474444)
			(xy 47.563532 -268.474444) (xy 47.57134 -268.474111) (xy 47.586212 -268.469339) (xy 47.592742 -268.465046)
			(xy 47.613831 -268.450697) (xy 47.659492 -268.427966) (xy 47.708098 -268.412507) (xy 47.758501 -268.404684)
			(xy 47.809507 -268.404684) (xy 47.85991 -268.412507) (xy 47.908516 -268.427966) (xy 47.954177 -268.450697)
			(xy 47.975266 -268.465046) (xy 47.981809 -268.469318) (xy 47.99667 -268.474114) (xy 48.004476 -268.474444)
			(xy 48.520604 -268.474444) (xy 48.525856 -268.474987) (xy 48.533295 -268.482402) (xy 48.533812 -268.487652)
			(xy 48.533812 -268.48816) (xy 48.533812 -268.982444) (xy 54.577996 -268.982444) (xy 54.577996 -268.487906)
			(xy 54.57855 -268.482553) (xy 54.586107 -268.474969) (xy 54.591458 -268.474444) (xy 56.064658 -268.474444)
			(xy 56.070089 -268.474808) (xy 56.077777 -268.482476) (xy 56.07812 -268.487906) (xy 56.07812 -268.982444)
			(xy 163.678108 -268.982444) (xy 163.678108 -268.487906) (xy 163.678623 -268.48261) (xy 163.686032 -268.47504)
			(xy 163.691316 -268.474444) (xy 165.164516 -268.474444) (xy 165.169769 -268.474979) (xy 165.177208 -268.4824)
			(xy 165.177724 -268.487652) (xy 165.177724 -268.48816) (xy 165.177724 -268.982444) (xy 171.221908 -268.982444)
			(xy 171.221908 -268.487906) (xy 171.222451 -268.48255) (xy 171.230015 -268.474966) (xy 171.23537 -268.474444)
			(xy 171.751498 -268.474444) (xy 171.759309 -268.474139) (xy 171.774181 -268.469348) (xy 171.780708 -268.465046)
			(xy 171.801797 -268.450697) (xy 171.847458 -268.427966) (xy 171.896064 -268.412507) (xy 171.946467 -268.404684)
			(xy 171.997473 -268.404684) (xy 172.047876 -268.412507) (xy 172.096482 -268.427966) (xy 172.142143 -268.450697)
			(xy 172.163232 -268.465046) (xy 172.16976 -268.469343) (xy 172.184633 -268.474123) (xy 172.192442 -268.474444)
			(xy 172.70857 -268.474444) (xy 172.714002 -268.4748) (xy 172.72169 -268.482474) (xy 172.722032 -268.487906)
			(xy 172.722032 -268.982444) (xy 178.766216 -268.982444) (xy 178.766216 -268.487906) (xy 178.766724 -268.482608)
			(xy 178.774137 -268.475038) (xy 178.779424 -268.474444) (xy 179.295552 -268.474444) (xy 179.303361 -268.474119)
			(xy 179.318233 -268.469342) (xy 179.324762 -268.465046) (xy 179.345851 -268.450697) (xy 179.391512 -268.427966)
			(xy 179.440118 -268.412507) (xy 179.490521 -268.404684) (xy 179.541527 -268.404684) (xy 179.59193 -268.412507)
			(xy 179.640536 -268.427966) (xy 179.686197 -268.450697) (xy 179.707286 -268.465046) (xy 179.713825 -268.469325)
			(xy 179.728689 -268.474117) (xy 179.736496 -268.474444) (xy 180.252624 -268.474444) (xy 180.257878 -268.474974)
			(xy 180.265316 -268.482399) (xy 180.265832 -268.487652) (xy 180.265832 -268.48816) (xy 180.265832 -268.982444)
			(xy 186.310016 -268.982444) (xy 186.310016 -268.487906) (xy 186.310552 -268.482548) (xy 186.318121 -268.474963)
			(xy 186.323478 -268.474444) (xy 186.839606 -268.474444) (xy 186.847417 -268.474142) (xy 186.862289 -268.469349)
			(xy 186.868816 -268.465046) (xy 186.889905 -268.450697) (xy 186.935566 -268.427966) (xy 186.984172 -268.412507)
			(xy 187.034575 -268.404684) (xy 187.085581 -268.404684) (xy 187.135984 -268.412507) (xy 187.18459 -268.427966)
			(xy 187.230251 -268.450697) (xy 187.25134 -268.465046) (xy 187.257867 -268.469346) (xy 187.27274 -268.474125)
			(xy 187.28055 -268.474444) (xy 187.796678 -268.474444) (xy 187.802111 -268.474795) (xy 187.809799 -268.482473)
			(xy 187.81014 -268.487906) (xy 187.81014 -268.982444) (xy 193.854324 -268.982444) (xy 193.854324 -268.487906)
			(xy 193.854825 -268.482606) (xy 193.862243 -268.475036) (xy 193.867532 -268.474444) (xy 194.38366 -268.474444)
			(xy 194.39147 -268.474123) (xy 194.406341 -268.469343) (xy 194.41287 -268.465046) (xy 194.433959 -268.450697)
			(xy 194.47962 -268.427966) (xy 194.528226 -268.412507) (xy 194.578629 -268.404684) (xy 194.629635 -268.404684)
			(xy 194.680038 -268.412507) (xy 194.728644 -268.427966) (xy 194.774305 -268.450697) (xy 194.795394 -268.465046)
			(xy 194.801931 -268.469328) (xy 194.816797 -268.474118) (xy 194.824604 -268.474444) (xy 195.340732 -268.474444)
			(xy 195.345987 -268.474969) (xy 195.353425 -268.482398) (xy 195.35394 -268.487652) (xy 195.35394 -268.48816)
			(xy 195.35394 -268.982444) (xy 201.398124 -268.982444) (xy 201.398124 -268.487906) (xy 201.398625 -268.482606)
			(xy 201.406043 -268.475036) (xy 201.411332 -268.474444) (xy 201.92746 -268.474444) (xy 201.93527 -268.474123)
			(xy 201.950141 -268.469343) (xy 201.95667 -268.465046) (xy 201.977759 -268.450697) (xy 202.02342 -268.427966)
			(xy 202.072026 -268.412507) (xy 202.122429 -268.404684) (xy 202.173435 -268.404684) (xy 202.223838 -268.412507)
			(xy 202.272444 -268.427966) (xy 202.318105 -268.450697) (xy 202.339194 -268.465046) (xy 202.345731 -268.469328)
			(xy 202.360597 -268.474118) (xy 202.368404 -268.474444) (xy 202.884532 -268.474444) (xy 202.889787 -268.474969)
			(xy 202.897225 -268.482398) (xy 202.89774 -268.487652) (xy 202.89774 -268.48816) (xy 202.89774 -268.98219)
			(xy 264.798048 -268.98219) (xy 264.798048 -268.487652) (xy 264.798559 -268.482394) (xy 264.805998 -268.474957)
			(xy 264.811256 -268.474444) (xy 264.811764 -268.474444) (xy 265.327638 -268.474444) (xy 265.335447 -268.474113)
			(xy 265.350319 -268.46934) (xy 265.356848 -268.465046) (xy 265.377937 -268.450697) (xy 265.423598 -268.427966)
			(xy 265.472204 -268.412507) (xy 265.522607 -268.404684) (xy 265.573613 -268.404684) (xy 265.624016 -268.412507)
			(xy 265.672622 -268.427966) (xy 265.718283 -268.450697) (xy 265.739372 -268.465046) (xy 265.745914 -268.46932)
			(xy 265.760776 -268.474115) (xy 265.768582 -268.474444) (xy 266.28471 -268.474444) (xy 266.290016 -268.474917)
			(xy 266.297587 -268.482355) (xy 266.298172 -268.487652) (xy 266.298172 -268.98219) (xy 266.298147 -268.982444)
			(xy 272.342356 -268.982444) (xy 272.342356 -268.981936) (xy 272.342356 -268.487652) (xy 272.342859 -268.482392)
			(xy 272.350304 -268.474955) (xy 272.355564 -268.474444) (xy 272.871692 -268.474444) (xy 272.879503 -268.474136)
			(xy 272.894374 -268.469347) (xy 272.900902 -268.465046) (xy 272.921991 -268.450697) (xy 272.967652 -268.427966)
			(xy 273.016258 -268.412507) (xy 273.066661 -268.404684) (xy 273.117667 -268.404684) (xy 273.16807 -268.412507)
			(xy 273.216676 -268.427966) (xy 273.262337 -268.450697) (xy 273.283426 -268.465046) (xy 273.289956 -268.469341)
			(xy 273.304827 -268.474123) (xy 273.312636 -268.474444) (xy 273.828764 -268.474444) (xy 273.834011 -268.475014)
			(xy 273.841453 -268.482408) (xy 273.841972 -268.487652) (xy 273.841972 -268.98219) (xy 273.841948 -268.982444)
			(xy 279.886156 -268.982444) (xy 279.886156 -268.981936) (xy 279.886156 -268.487652) (xy 279.886659 -268.482392)
			(xy 279.894104 -268.474955) (xy 279.899364 -268.474444) (xy 280.415492 -268.474444) (xy 280.423303 -268.474136)
			(xy 280.438174 -268.469347) (xy 280.444702 -268.465046) (xy 280.465791 -268.450697) (xy 280.511452 -268.427966)
			(xy 280.560058 -268.412507) (xy 280.610461 -268.404684) (xy 280.661467 -268.404684) (xy 280.71187 -268.412507)
			(xy 280.760476 -268.427966) (xy 280.806137 -268.450697) (xy 280.827226 -268.465046) (xy 280.833756 -268.469341)
			(xy 280.848627 -268.474123) (xy 280.856436 -268.474444) (xy 281.372564 -268.474444) (xy 281.377811 -268.475014)
			(xy 281.385253 -268.482408) (xy 281.385772 -268.487652) (xy 281.385772 -268.98219) (xy 287.429956 -268.98219)
			(xy 287.429956 -268.487652) (xy 287.430459 -268.482392) (xy 287.437904 -268.474955) (xy 287.443164 -268.474444)
			(xy 287.443672 -268.474444) (xy 287.959546 -268.474444) (xy 287.967355 -268.474117) (xy 287.982227 -268.469341)
			(xy 287.988756 -268.465046) (xy 288.009845 -268.450697) (xy 288.055506 -268.427966) (xy 288.104112 -268.412507)
			(xy 288.154515 -268.404684) (xy 288.205521 -268.404684) (xy 288.255924 -268.412507) (xy 288.30453 -268.427966)
			(xy 288.350191 -268.450697) (xy 288.37128 -268.465046) (xy 288.37782 -268.469323) (xy 288.392683 -268.474116)
			(xy 288.40049 -268.474444) (xy 288.916618 -268.474444) (xy 288.921925 -268.474912) (xy 288.929496 -268.482354)
			(xy 288.93008 -268.487652) (xy 288.93008 -268.98219) (xy 288.930055 -268.982444) (xy 294.974264 -268.982444)
			(xy 294.974264 -268.981936) (xy 294.974264 -268.487652) (xy 294.97476 -268.48239) (xy 294.98221 -268.474952)
			(xy 294.987472 -268.474444) (xy 295.5036 -268.474444) (xy 295.511411 -268.47414) (xy 295.526283 -268.469348)
			(xy 295.53281 -268.465046) (xy 295.553899 -268.450697) (xy 295.59956 -268.427966) (xy 295.648166 -268.412507)
			(xy 295.698569 -268.404684) (xy 295.749575 -268.404684) (xy 295.799978 -268.412507) (xy 295.848584 -268.427966)
			(xy 295.894245 -268.450697) (xy 295.915334 -268.465046) (xy 295.921862 -268.469344) (xy 295.936735 -268.474124)
			(xy 295.944544 -268.474444) (xy 296.460672 -268.474444) (xy 296.46592 -268.475008) (xy 296.473361 -268.482407)
			(xy 296.47388 -268.487652) (xy 296.47388 -268.98219) (xy 302.518064 -268.98219) (xy 302.518064 -268.487652)
			(xy 302.51856 -268.48239) (xy 302.52601 -268.474952) (xy 302.531272 -268.474444) (xy 304.004726 -268.474444)
			(xy 304.010034 -268.474907) (xy 304.017604 -268.482353) (xy 304.018188 -268.487652) (xy 304.018188 -268.98219)
			(xy 304.018162 -268.982444) (xy 411.618176 -268.982444) (xy 411.618176 -268.981936) (xy 411.618176 -268.487652)
			(xy 411.618661 -268.482387) (xy 411.626118 -268.474949) (xy 411.631384 -268.474444) (xy 413.104584 -268.474444)
			(xy 413.109833 -268.475) (xy 413.117274 -268.482405) (xy 413.117792 -268.487652) (xy 413.117792 -268.98219)
			(xy 419.161976 -268.98219) (xy 419.161976 -268.487652) (xy 419.162461 -268.482387) (xy 419.169918 -268.474949)
			(xy 419.175184 -268.474444) (xy 419.175692 -268.474444) (xy 419.691566 -268.474444) (xy 419.699376 -268.474125)
			(xy 419.714248 -268.469344) (xy 419.720776 -268.465046) (xy 419.741865 -268.450697) (xy 419.787526 -268.427966)
			(xy 419.836132 -268.412507) (xy 419.886535 -268.404684) (xy 419.937541 -268.404684) (xy 419.987944 -268.412507)
			(xy 420.03655 -268.427966) (xy 420.082211 -268.450697) (xy 420.1033 -268.465046) (xy 420.109835 -268.469331)
			(xy 420.124702 -268.474119) (xy 420.13251 -268.474444) (xy 420.648638 -268.474444) (xy 420.653948 -268.474899)
			(xy 420.661517 -268.482351) (xy 420.6621 -268.487652) (xy 420.6621 -268.98219) (xy 420.662074 -268.982444)
			(xy 426.706284 -268.982444) (xy 426.706284 -268.981936) (xy 426.706284 -268.487652) (xy 426.706762 -268.482385)
			(xy 426.714224 -268.474946) (xy 426.719492 -268.474444) (xy 427.23562 -268.474444) (xy 427.243432 -268.474148)
			(xy 427.258304 -268.469351) (xy 427.26483 -268.465046) (xy 427.285919 -268.450697) (xy 427.33158 -268.427966)
			(xy 427.380186 -268.412507) (xy 427.430589 -268.404684) (xy 427.481595 -268.404684) (xy 427.531998 -268.412507)
			(xy 427.580604 -268.427966) (xy 427.626265 -268.450697) (xy 427.647354 -268.465046) (xy 427.653877 -268.469351)
			(xy 427.668754 -268.474127) (xy 427.676564 -268.474444) (xy 428.192692 -268.474444) (xy 428.197942 -268.474995)
			(xy 428.205383 -268.482404) (xy 428.2059 -268.487652) (xy 428.2059 -268.98219) (xy 434.250084 -268.98219)
			(xy 434.250084 -268.487652) (xy 434.250562 -268.482385) (xy 434.258024 -268.474946) (xy 434.263292 -268.474444)
			(xy 434.2638 -268.474444) (xy 434.779674 -268.474444) (xy 434.787484 -268.474129) (xy 434.802356 -268.469345)
			(xy 434.808884 -268.465046) (xy 434.829973 -268.450697) (xy 434.875634 -268.427966) (xy 434.92424 -268.412507)
			(xy 434.974643 -268.404684) (xy 435.025649 -268.404684) (xy 435.076052 -268.412507) (xy 435.124658 -268.427966)
			(xy 435.170319 -268.450697) (xy 435.191408 -268.465046) (xy 435.197942 -268.469334) (xy 435.21281 -268.47412)
			(xy 435.220618 -268.474444) (xy 435.736746 -268.474444) (xy 435.742045 -268.47496) (xy 435.749619 -268.482365)
			(xy 435.750208 -268.487652) (xy 435.750208 -268.98219) (xy 435.750181 -268.982444) (xy 441.794392 -268.982444)
			(xy 441.794392 -268.981936) (xy 441.794392 -268.487652) (xy 441.794863 -268.482383) (xy 441.80233 -268.474944)
			(xy 441.8076 -268.474444) (xy 442.323728 -268.474444) (xy 442.33154 -268.474152) (xy 442.346412 -268.469352)
			(xy 442.352938 -268.465046) (xy 442.374027 -268.450697) (xy 442.419688 -268.427966) (xy 442.468294 -268.412507)
			(xy 442.518697 -268.404684) (xy 442.569703 -268.404684) (xy 442.620106 -268.412507) (xy 442.668712 -268.427966)
			(xy 442.714373 -268.450697) (xy 442.735462 -268.465046) (xy 442.742006 -268.469316) (xy 442.756866 -268.474113)
			(xy 442.764672 -268.474444) (xy 443.2808 -268.474444) (xy 443.286051 -268.47499) (xy 443.293491 -268.482403)
			(xy 443.294008 -268.487652) (xy 443.294008 -268.98219) (xy 443.293982 -268.982444) (xy 449.338192 -268.982444)
			(xy 449.338192 -268.981936) (xy 449.338192 -268.487652) (xy 449.338663 -268.482383) (xy 449.34613 -268.474944)
			(xy 449.3514 -268.474444) (xy 449.867528 -268.474444) (xy 449.87534 -268.474152) (xy 449.890212 -268.469352)
			(xy 449.896738 -268.465046) (xy 449.917827 -268.450697) (xy 449.963488 -268.427966) (xy 450.012094 -268.412507)
			(xy 450.062497 -268.404684) (xy 450.113503 -268.404684) (xy 450.163906 -268.412507) (xy 450.212512 -268.427966)
			(xy 450.258173 -268.450697) (xy 450.279262 -268.465046) (xy 450.285806 -268.469316) (xy 450.300666 -268.474113)
			(xy 450.308472 -268.474444) (xy 450.8246 -268.474444) (xy 450.829851 -268.47499) (xy 450.837291 -268.482403)
			(xy 450.837808 -268.487652) (xy 450.837808 -268.98219) (xy 450.837276 -268.987482) (xy 450.829879 -268.995051)
			(xy 450.8246 -268.995652) (xy 450.308726 -268.995652) (xy 450.300916 -268.995968) (xy 450.286044 -269.000752)
			(xy 450.279516 -269.00505) (xy 450.258387 -269.019388) (xy 450.212666 -269.042118) (xy 450.163995 -269.057551)
			(xy 450.11353 -269.065321) (xy 450.088 -269.065756) (xy 450.06247 -269.065321) (xy 450.012006 -269.057545)
			(xy 449.963333 -269.042115) (xy 449.917606 -269.019398) (xy 449.896484 -269.00505) (xy 449.889952 -269.000759)
			(xy 449.875083 -268.995975) (xy 449.867274 -268.995652) (xy 449.3514 -268.995652) (xy 449.346148 -268.99511)
			(xy 449.338708 -268.987694) (xy 449.338192 -268.982444) (xy 443.293982 -268.982444) (xy 443.293476 -268.987482)
			(xy 443.286079 -268.995051) (xy 443.2808 -268.995652) (xy 442.764926 -268.995652) (xy 442.757116 -268.995968)
			(xy 442.742244 -269.000752) (xy 442.735716 -269.00505) (xy 442.714587 -269.019388) (xy 442.668866 -269.042118)
			(xy 442.620195 -269.057551) (xy 442.56973 -269.065321) (xy 442.5442 -269.065756) (xy 442.51867 -269.065321)
			(xy 442.468206 -269.057545) (xy 442.419533 -269.042115) (xy 442.373806 -269.019398) (xy 442.352684 -269.00505)
			(xy 442.346152 -269.000759) (xy 442.331283 -268.995975) (xy 442.323474 -268.995652) (xy 441.8076 -268.995652)
			(xy 441.802348 -268.99511) (xy 441.794908 -268.987694) (xy 441.794392 -268.982444) (xy 435.750181 -268.982444)
			(xy 435.749647 -268.987542) (xy 435.742095 -268.995125) (xy 435.736746 -268.995652) (xy 435.220872 -268.995652)
			(xy 435.21306 -268.995945) (xy 435.198188 -269.000744) (xy 435.191662 -269.00505) (xy 435.170548 -269.019412)
			(xy 435.124822 -269.042136) (xy 435.076146 -269.057562) (xy 435.025678 -269.065325) (xy 435.000146 -269.065756)
			(xy 434.974617 -269.065298) (xy 434.924154 -269.057529) (xy 434.875481 -269.042106) (xy 434.829753 -269.019395)
			(xy 434.80863 -269.00505) (xy 434.802088 -269.000776) (xy 434.787226 -268.995982) (xy 434.77942 -268.995652)
			(xy 434.263546 -268.995652) (xy 434.258115 -268.995289) (xy 434.250425 -268.98762) (xy 434.250084 -268.98219)
			(xy 428.2059 -268.98219) (xy 428.205375 -268.987484) (xy 428.197974 -268.995053) (xy 428.192692 -268.995652)
			(xy 427.676818 -268.995652) (xy 427.669008 -268.995965) (xy 427.654136 -269.000751) (xy 427.647608 -269.00505)
			(xy 427.626482 -269.019392) (xy 427.580759 -269.04212) (xy 427.532088 -269.057552) (xy 427.481623 -269.065321)
			(xy 427.456092 -269.065756) (xy 427.430562 -269.065325) (xy 427.380097 -269.057548) (xy 427.331425 -269.042117)
			(xy 427.285698 -269.019398) (xy 427.264576 -269.00505) (xy 427.258046 -269.000756) (xy 427.243175 -268.995974)
			(xy 427.235366 -268.995652) (xy 426.719492 -268.995652) (xy 426.714239 -268.995115) (xy 426.706799 -268.987696)
			(xy 426.706284 -268.982444) (xy 420.662074 -268.982444) (xy 420.661547 -268.987544) (xy 420.65399 -268.995128)
			(xy 420.648638 -268.995652) (xy 420.132764 -268.995652) (xy 420.124955 -268.995984) (xy 420.110084 -269.000757)
			(xy 420.103554 -269.00505) (xy 420.082443 -269.019415) (xy 420.036715 -269.042138) (xy 419.988039 -269.057564)
			(xy 419.93757 -269.065326) (xy 419.912038 -269.065756) (xy 419.886508 -269.065302) (xy 419.836045 -269.057532)
			(xy 419.787373 -269.042108) (xy 419.741644 -269.019395) (xy 419.720522 -269.00505) (xy 419.713982 -269.000773)
			(xy 419.699119 -268.99598) (xy 419.691312 -268.995652) (xy 419.175438 -268.995652) (xy 419.170006 -268.995294)
			(xy 419.162317 -268.987621) (xy 419.161976 -268.98219) (xy 413.117792 -268.98219) (xy 413.117274 -268.987486)
			(xy 413.109868 -268.995056) (xy 413.104584 -268.995652) (xy 411.631384 -268.995652) (xy 411.62613 -268.995121)
			(xy 411.618691 -268.987697) (xy 411.618176 -268.982444) (xy 304.018162 -268.982444) (xy 304.017645 -268.987546)
			(xy 304.010081 -268.995131) (xy 304.004726 -268.995652) (xy 302.531526 -268.995652) (xy 302.526092 -268.995302)
			(xy 302.518404 -268.987623) (xy 302.518064 -268.98219) (xy 296.47388 -268.98219) (xy 296.473373 -268.987488)
			(xy 296.465959 -268.995059) (xy 296.460672 -268.995652) (xy 295.944798 -268.995652) (xy 295.936987 -268.995956)
			(xy 295.922115 -269.000748) (xy 295.915588 -269.00505) (xy 295.894467 -269.0194) (xy 295.848743 -269.042127)
			(xy 295.80007 -269.057557) (xy 295.749603 -269.065323) (xy 295.724072 -269.065756) (xy 295.698541 -269.065335)
			(xy 295.648077 -269.057555) (xy 295.599404 -269.042121) (xy 295.553677 -269.0194) (xy 295.532556 -269.00505)
			(xy 295.526031 -269.000748) (xy 295.511156 -268.995971) (xy 295.503346 -268.995652) (xy 294.987472 -268.995652)
			(xy 294.982216 -268.995129) (xy 294.974778 -268.987699) (xy 294.974264 -268.982444) (xy 288.930055 -268.982444)
			(xy 288.929545 -268.987548) (xy 288.921975 -268.995133) (xy 288.916618 -268.995652) (xy 288.400744 -268.995652)
			(xy 288.392935 -268.995976) (xy 288.378063 -269.000754) (xy 288.371534 -269.00505) (xy 288.350428 -269.019424)
			(xy 288.304699 -269.042145) (xy 288.256021 -269.057568) (xy 288.20555 -269.065327) (xy 288.180018 -269.065756)
			(xy 288.154488 -269.065312) (xy 288.104024 -269.057539) (xy 288.055352 -269.042112) (xy 288.009624 -269.019397)
			(xy 287.988502 -269.00505) (xy 287.981966 -269.000766) (xy 287.9671 -268.995978) (xy 287.959292 -268.995652)
			(xy 287.443418 -268.995652) (xy 287.437983 -268.995308) (xy 287.430295 -268.987625) (xy 287.429956 -268.98219)
			(xy 281.385772 -268.98219) (xy 281.385272 -268.98749) (xy 281.377853 -268.995061) (xy 281.372564 -268.995652)
			(xy 280.85669 -268.995652) (xy 280.848879 -268.995952) (xy 280.834007 -269.000746) (xy 280.82748 -269.00505)
			(xy 280.806361 -269.019404) (xy 280.760636 -269.04213) (xy 280.711962 -269.057558) (xy 280.661495 -269.065324)
			(xy 280.635964 -269.065756) (xy 280.610433 -269.065339) (xy 280.559968 -269.057557) (xy 280.511296 -269.042123)
			(xy 280.465569 -269.0194) (xy 280.444448 -269.00505) (xy 280.437924 -269.000745) (xy 280.423048 -268.99597)
			(xy 280.415238 -268.995652) (xy 279.899364 -268.995652) (xy 279.894108 -268.995134) (xy 279.88667 -268.9877)
			(xy 279.886156 -268.982444) (xy 273.841948 -268.982444) (xy 273.841472 -268.98749) (xy 273.834053 -268.995061)
			(xy 273.828764 -268.995652) (xy 273.31289 -268.995652) (xy 273.305079 -268.995952) (xy 273.290207 -269.000746)
			(xy 273.28368 -269.00505) (xy 273.262561 -269.019404) (xy 273.216836 -269.04213) (xy 273.168162 -269.057558)
			(xy 273.117695 -269.065324) (xy 273.092164 -269.065756) (xy 273.066633 -269.065339) (xy 273.016168 -269.057557)
			(xy 272.967496 -269.042123) (xy 272.921769 -269.0194) (xy 272.900648 -269.00505) (xy 272.894124 -269.000745)
			(xy 272.879248 -268.99597) (xy 272.871438 -268.995652) (xy 272.355564 -268.995652) (xy 272.350308 -268.995134)
			(xy 272.34287 -268.9877) (xy 272.342356 -268.982444) (xy 266.298147 -268.982444) (xy 266.297644 -268.98755)
			(xy 266.290069 -268.995136) (xy 266.28471 -268.995652) (xy 265.768836 -268.995652) (xy 265.761026 -268.995972)
			(xy 265.746155 -269.000753) (xy 265.739626 -269.00505) (xy 265.718495 -269.019384) (xy 265.672774 -269.042114)
			(xy 265.624104 -269.057549) (xy 265.57364 -269.06532) (xy 265.54811 -269.065756) (xy 265.52258 -269.065316)
			(xy 265.472116 -269.057541) (xy 265.423444 -269.042113) (xy 265.377716 -269.019397) (xy 265.356594 -269.00505)
			(xy 265.35006 -269.000763) (xy 265.335192 -268.995976) (xy 265.327384 -268.995652) (xy 264.81151 -268.995652)
			(xy 264.806074 -268.995313) (xy 264.798387 -268.987626) (xy 264.798048 -268.98219) (xy 202.89774 -268.98219)
			(xy 202.89774 -268.982444) (xy 202.897238 -268.987704) (xy 202.889793 -268.995143) (xy 202.884532 -268.995652)
			(xy 202.368658 -268.995652) (xy 202.360783 -268.995929) (xy 202.345779 -269.00072) (xy 202.339194 -269.00505)
			(xy 202.318109 -269.019429) (xy 202.272467 -269.042261) (xy 202.223863 -269.057822) (xy 202.173448 -269.065745)
			(xy 202.147932 -269.066264) (xy 202.122411 -269.065782) (xy 202.071984 -269.057886) (xy 202.023372 -269.042324)
			(xy 201.977734 -269.019467) (xy 201.95667 -269.00505) (xy 201.950084 -269.000725) (xy 201.93508 -268.995944)
			(xy 201.927206 -268.995652) (xy 201.411332 -268.995652) (xy 201.406083 -268.995089) (xy 201.398642 -268.987689)
			(xy 201.398124 -268.982444) (xy 195.35394 -268.982444) (xy 195.353438 -268.987704) (xy 195.345993 -268.995143)
			(xy 195.340732 -268.995652) (xy 194.824858 -268.995652) (xy 194.816983 -268.995929) (xy 194.801979 -269.00072)
			(xy 194.795394 -269.00505) (xy 194.774309 -269.019429) (xy 194.728667 -269.042261) (xy 194.680063 -269.057822)
			(xy 194.629648 -269.065745) (xy 194.604132 -269.066264) (xy 194.578611 -269.065782) (xy 194.528184 -269.057886)
			(xy 194.479572 -269.042324) (xy 194.433934 -269.019467) (xy 194.41287 -269.00505) (xy 194.406284 -269.000725)
			(xy 194.39128 -268.995944) (xy 194.383406 -268.995652) (xy 193.867532 -268.995652) (xy 193.862283 -268.995089)
			(xy 193.854842 -268.987689) (xy 193.854324 -268.982444) (xy 187.81014 -268.982444) (xy 187.809638 -268.987704)
			(xy 187.802193 -268.995143) (xy 187.796932 -268.995652) (xy 187.796424 -268.995652) (xy 187.280804 -268.995652)
			(xy 187.27293 -268.995949) (xy 187.257926 -269.000726) (xy 187.25134 -269.00505) (xy 187.23027 -269.019453)
			(xy 187.184622 -269.042278) (xy 187.136014 -269.057833) (xy 187.085595 -269.065749) (xy 187.060078 -269.066264)
			(xy 187.034558 -269.065759) (xy 186.984132 -269.05787) (xy 186.93552 -269.042315) (xy 186.889881 -269.019464)
			(xy 186.868816 -269.00505) (xy 186.86222 -269.000743) (xy 186.847223 -268.99595) (xy 186.839352 -268.995652)
			(xy 186.323478 -268.995652) (xy 186.318169 -268.99519) (xy 186.310599 -268.987744) (xy 186.310016 -268.982444)
			(xy 180.265832 -268.982444) (xy 180.265337 -268.987706) (xy 180.257887 -268.995145) (xy 180.252624 -268.995652)
			(xy 179.73675 -268.995652) (xy 179.728874 -268.995925) (xy 179.71387 -269.000719) (xy 179.707286 -269.00505)
			(xy 179.686203 -269.019433) (xy 179.64056 -269.042263) (xy 179.591956 -269.057823) (xy 179.54154 -269.065745)
			(xy 179.516024 -269.066264) (xy 179.490503 -269.065786) (xy 179.440076 -269.057889) (xy 179.391464 -269.042326)
			(xy 179.345826 -269.019467) (xy 179.324762 -269.00505) (xy 179.318178 -269.000722) (xy 179.303172 -268.995943)
			(xy 179.295298 -268.995652) (xy 178.779424 -268.995652) (xy 178.774175 -268.995094) (xy 178.766733 -268.987691)
			(xy 178.766216 -268.982444) (xy 172.722032 -268.982444) (xy 172.721537 -268.987706) (xy 172.714087 -268.995145)
			(xy 172.708824 -268.995652) (xy 172.708316 -268.995652) (xy 172.192696 -268.995652) (xy 172.184822 -268.995945)
			(xy 172.169818 -269.000725) (xy 172.163232 -269.00505) (xy 172.142164 -269.019456) (xy 172.096516 -269.042281)
			(xy 172.047907 -269.057835) (xy 171.997488 -269.065749) (xy 171.97197 -269.066264) (xy 171.94645 -269.065763)
			(xy 171.896023 -269.057873) (xy 171.847412 -269.042316) (xy 171.801773 -269.019464) (xy 171.780708 -269.00505)
			(xy 171.774113 -269.00074) (xy 171.759116 -268.995949) (xy 171.751244 -268.995652) (xy 171.23537 -268.995652)
			(xy 171.23006 -268.995196) (xy 171.22249 -268.987745) (xy 171.221908 -268.982444) (xy 165.177724 -268.982444)
			(xy 165.177236 -268.987708) (xy 165.169781 -268.995147) (xy 165.164516 -268.995652) (xy 163.691316 -268.995652)
			(xy 163.686066 -268.995099) (xy 163.678625 -268.987692) (xy 163.678108 -268.982444) (xy 56.07812 -268.982444)
			(xy 56.077636 -268.987709) (xy 56.070178 -268.995149) (xy 56.064912 -268.995652) (xy 54.591458 -268.995652)
			(xy 54.586147 -268.995204) (xy 54.578578 -268.987747) (xy 54.577996 -268.982444) (xy 48.533812 -268.982444)
			(xy 48.533335 -268.987711) (xy 48.525873 -268.995151) (xy 48.520604 -268.995652) (xy 48.00473 -268.995652)
			(xy 47.996853 -268.995917) (xy 47.981849 -269.000716) (xy 47.975266 -269.00505) (xy 47.954189 -269.019441)
			(xy 47.908544 -269.04227) (xy 47.859938 -269.057828) (xy 47.809521 -269.065747) (xy 47.784004 -269.066264)
			(xy 47.758483 -269.065796) (xy 47.708055 -269.057896) (xy 47.659443 -269.04233) (xy 47.613806 -269.019468)
			(xy 47.592742 -269.00505) (xy 47.586162 -269.000715) (xy 47.571153 -268.99594) (xy 47.563278 -268.995652)
			(xy 47.047404 -268.995652) (xy 47.042152 -268.995107) (xy 47.034712 -268.987694) (xy 47.034196 -268.982444)
			(xy 40.990012 -268.982444) (xy 40.989535 -268.987711) (xy 40.982073 -268.995151) (xy 40.976804 -268.995652)
			(xy 40.976296 -268.995652) (xy 40.460676 -268.995652) (xy 40.452801 -268.995937) (xy 40.437797 -269.000722)
			(xy 40.431212 -269.00505) (xy 40.41015 -269.019465) (xy 40.364499 -269.042288) (xy 40.315889 -269.057839)
			(xy 40.265468 -269.065751) (xy 40.23995 -269.066264) (xy 40.21443 -269.065773) (xy 40.164003 -269.05788)
			(xy 40.115391 -269.04232) (xy 40.069753 -269.019466) (xy 40.048688 -269.00505) (xy 40.042098 -269.000732)
			(xy 40.027097 -268.995946) (xy 40.019224 -268.995652) (xy 39.50335 -268.995652) (xy 39.49805 -268.995142)
			(xy 39.490476 -268.987732) (xy 39.489888 -268.982444) (xy 33.445704 -268.982444) (xy 33.445234 -268.987713)
			(xy 33.437767 -268.995153) (xy 33.432496 -268.995652) (xy 32.916622 -268.995652) (xy 32.908749 -268.995956)
			(xy 32.893745 -269.000729) (xy 32.887158 -269.00505) (xy 32.866083 -269.019445) (xy 32.820437 -269.042272)
			(xy 32.77183 -269.057829) (xy 32.721413 -269.065747) (xy 32.695896 -269.066264) (xy 32.670375 -269.0658)
			(xy 32.619946 -269.057899) (xy 32.571335 -269.042331) (xy 32.525698 -269.019469) (xy 32.504634 -269.00505)
			(xy 32.498034 -269.00075) (xy 32.483041 -268.995953) (xy 32.47517 -268.995652) (xy 31.959296 -268.995652)
			(xy 31.954043 -268.995113) (xy 31.946603 -268.987695) (xy 31.946088 -268.982444) (xy 25.901904 -268.982444)
			(xy 25.901434 -268.987713) (xy 25.893967 -268.995153) (xy 25.888696 -268.995652) (xy 25.372822 -268.995652)
			(xy 25.364949 -268.995956) (xy 25.349945 -269.000729) (xy 25.343358 -269.00505) (xy 25.322283 -269.019445)
			(xy 25.276637 -269.042272) (xy 25.22803 -269.057829) (xy 25.177613 -269.065747) (xy 25.152096 -269.066264)
			(xy 25.126575 -269.0658) (xy 25.076146 -269.057899) (xy 25.027535 -269.042331) (xy 24.981898 -269.019469)
			(xy 24.960834 -269.00505) (xy 24.954234 -269.00075) (xy 24.939241 -268.995953) (xy 24.93137 -268.995652)
			(xy 24.415496 -268.995652) (xy 24.410243 -268.995113) (xy 24.402803 -268.987695) (xy 24.402288 -268.982444)
			(xy 18.358104 -268.982444) (xy 18.357634 -268.987713) (xy 18.350167 -268.995153) (xy 18.344896 -268.995652)
			(xy 18.344388 -268.995652) (xy 17.828768 -268.995652) (xy 17.820893 -268.995933) (xy 17.805889 -269.000721)
			(xy 17.799304 -269.00505) (xy 17.778216 -269.019425) (xy 17.732575 -269.042257) (xy 17.683972 -269.05782)
			(xy 17.633558 -269.065744) (xy 17.608042 -269.066264) (xy 17.582522 -269.065777) (xy 17.532094 -269.057883)
			(xy 17.483483 -269.042322) (xy 17.437844 -269.019466) (xy 17.41678 -269.00505) (xy 17.410192 -269.000729)
			(xy 17.395189 -268.995945) (xy 17.387316 -268.995652) (xy 16.871442 -268.995652) (xy 16.866141 -268.995148)
			(xy 16.858567 -268.987734) (xy 16.85798 -268.982444) (xy 2.509012 -268.982444) (xy 2.509012 -269.832582)
			(xy 20.958048 -269.832582) (xy 20.958048 -269.338044) (xy 20.958619 -269.332797) (xy 20.966012 -269.325354)
			(xy 20.971256 -269.324836) (xy 20.971764 -269.324836) (xy 21.487638 -269.324836) (xy 21.495447 -269.324507)
			(xy 21.510319 -269.319733) (xy 21.516848 -269.315438) (xy 21.537937 -269.301089) (xy 21.583598 -269.278358)
			(xy 21.632204 -269.262899) (xy 21.682607 -269.255076) (xy 21.733613 -269.255076) (xy 21.784016 -269.262899)
			(xy 21.832622 -269.278358) (xy 21.878283 -269.301089) (xy 21.899372 -269.315438) (xy 21.905914 -269.319711)
			(xy 21.920776 -269.324507) (xy 21.928582 -269.324836) (xy 22.44471 -269.324836) (xy 22.450014 -269.325316)
			(xy 22.457585 -269.332749) (xy 22.458172 -269.338044) (xy 22.458172 -269.832582) (xy 22.458155 -269.832836)
			(xy 28.502356 -269.832836) (xy 28.502356 -269.832328) (xy 28.502356 -269.338044) (xy 28.502753 -269.332726)
			(xy 28.510249 -269.325185) (xy 28.515564 -269.324836) (xy 29.031692 -269.324836) (xy 29.039503 -269.32453)
			(xy 29.054375 -269.31974) (xy 29.060902 -269.315438) (xy 29.081991 -269.301089) (xy 29.127652 -269.278358)
			(xy 29.176258 -269.262899) (xy 29.226661 -269.255076) (xy 29.277667 -269.255076) (xy 29.32807 -269.262899)
			(xy 29.376676 -269.278358) (xy 29.422337 -269.301089) (xy 29.443426 -269.315438) (xy 29.449956 -269.319732)
			(xy 29.464827 -269.324514) (xy 29.472636 -269.324836) (xy 29.988764 -269.324836) (xy 29.994102 -269.325155)
			(xy 30.001648 -269.332706) (xy 30.001972 -269.338044) (xy 30.001972 -269.832582) (xy 30.001948 -269.832836)
			(xy 36.046156 -269.832836) (xy 36.046156 -269.832328) (xy 36.046156 -269.338044) (xy 36.046553 -269.332726)
			(xy 36.054049 -269.325185) (xy 36.059364 -269.324836) (xy 36.575492 -269.324836) (xy 36.583303 -269.32453)
			(xy 36.598175 -269.31974) (xy 36.604702 -269.315438) (xy 36.625791 -269.301089) (xy 36.671452 -269.278358)
			(xy 36.720058 -269.262899) (xy 36.770461 -269.255076) (xy 36.821467 -269.255076) (xy 36.87187 -269.262899)
			(xy 36.920476 -269.278358) (xy 36.966137 -269.301089) (xy 36.987226 -269.315438) (xy 36.993756 -269.319732)
			(xy 37.008627 -269.324514) (xy 37.016436 -269.324836) (xy 37.532564 -269.324836) (xy 37.537902 -269.325155)
			(xy 37.545448 -269.332706) (xy 37.545772 -269.338044) (xy 37.545772 -269.832582) (xy 43.589956 -269.832582)
			(xy 43.589956 -269.338044) (xy 43.590353 -269.332726) (xy 43.597849 -269.325185) (xy 43.603164 -269.324836)
			(xy 43.603672 -269.324836) (xy 44.119546 -269.324836) (xy 44.127355 -269.32451) (xy 44.142227 -269.319734)
			(xy 44.148756 -269.315438) (xy 44.169845 -269.301089) (xy 44.215506 -269.278358) (xy 44.264112 -269.262899)
			(xy 44.314515 -269.255076) (xy 44.365521 -269.255076) (xy 44.415924 -269.262899) (xy 44.46453 -269.278358)
			(xy 44.510191 -269.301089) (xy 44.53128 -269.315438) (xy 44.53782 -269.319714) (xy 44.552683 -269.324508)
			(xy 44.56049 -269.324836) (xy 45.076618 -269.324836) (xy 45.081923 -269.325311) (xy 45.089493 -269.332748)
			(xy 45.09008 -269.338044) (xy 45.09008 -269.832582) (xy 45.090054 -269.832836) (xy 51.134264 -269.832836)
			(xy 51.134264 -269.832328) (xy 51.134264 -269.338044) (xy 51.134654 -269.332724) (xy 51.142154 -269.325183)
			(xy 51.147472 -269.324836) (xy 51.6636 -269.324836) (xy 51.671411 -269.324533) (xy 51.686283 -269.319741)
			(xy 51.69281 -269.315438) (xy 51.713899 -269.301089) (xy 51.75956 -269.278358) (xy 51.808166 -269.262899)
			(xy 51.858569 -269.255076) (xy 51.909575 -269.255076) (xy 51.959978 -269.262899) (xy 52.008584 -269.278358)
			(xy 52.054245 -269.301089) (xy 52.075334 -269.315438) (xy 52.081862 -269.319735) (xy 52.096735 -269.324516)
			(xy 52.104544 -269.324836) (xy 52.620672 -269.324836) (xy 52.626011 -269.32515) (xy 52.633557 -269.332704)
			(xy 52.63388 -269.338044) (xy 52.63388 -269.832582) (xy 58.678064 -269.832582) (xy 58.678064 -269.338044)
			(xy 58.678454 -269.332724) (xy 58.685954 -269.325183) (xy 58.691272 -269.324836) (xy 58.69178 -269.324836)
			(xy 60.164726 -269.324836) (xy 60.170032 -269.325306) (xy 60.177602 -269.332747) (xy 60.178188 -269.338044)
			(xy 60.178188 -269.832582) (xy 60.178162 -269.832836) (xy 167.778176 -269.832836) (xy 167.778176 -269.338044)
			(xy 167.778555 -269.332721) (xy 167.786063 -269.325179) (xy 167.791384 -269.324836) (xy 169.264584 -269.324836)
			(xy 169.269925 -269.325142) (xy 169.277469 -269.332702) (xy 169.277792 -269.338044) (xy 169.277792 -269.832582)
			(xy 175.321976 -269.832582) (xy 175.321976 -269.338044) (xy 175.322355 -269.332721) (xy 175.329863 -269.325179)
			(xy 175.335184 -269.324836) (xy 175.335692 -269.324836) (xy 175.851566 -269.324836) (xy 175.859376 -269.324519)
			(xy 175.874248 -269.319736) (xy 175.880776 -269.315438) (xy 175.901865 -269.301089) (xy 175.947526 -269.278358)
			(xy 175.996132 -269.262899) (xy 176.046535 -269.255076) (xy 176.097541 -269.255076) (xy 176.147944 -269.262899)
			(xy 176.19655 -269.278358) (xy 176.242211 -269.301089) (xy 176.2633 -269.315438) (xy 176.269836 -269.319722)
			(xy 176.284702 -269.324511) (xy 176.29251 -269.324836) (xy 176.808638 -269.324836) (xy 176.813946 -269.325298)
			(xy 176.821514 -269.332745) (xy 176.8221 -269.338044) (xy 176.8221 -269.832582) (xy 176.822074 -269.832836)
			(xy 182.866284 -269.832836) (xy 182.866284 -269.832328) (xy 182.866284 -269.338044) (xy 182.866656 -269.332719)
			(xy 182.874169 -269.325176) (xy 182.879492 -269.324836) (xy 183.39562 -269.324836) (xy 183.403432 -269.324542)
			(xy 183.418304 -269.319744) (xy 183.42483 -269.315438) (xy 183.445919 -269.301089) (xy 183.49158 -269.278358)
			(xy 183.540186 -269.262899) (xy 183.590589 -269.255076) (xy 183.641595 -269.255076) (xy 183.691998 -269.262899)
			(xy 183.740604 -269.278358) (xy 183.786265 -269.301089) (xy 183.807354 -269.315438) (xy 183.813878 -269.319743)
			(xy 183.828754 -269.324519) (xy 183.836564 -269.324836) (xy 184.352692 -269.324836) (xy 184.358034 -269.325136)
			(xy 184.365578 -269.332701) (xy 184.3659 -269.338044) (xy 184.3659 -269.832582) (xy 190.410084 -269.832582)
			(xy 190.410084 -269.338044) (xy 190.410456 -269.332719) (xy 190.417969 -269.325176) (xy 190.423292 -269.324836)
			(xy 190.4238 -269.324836) (xy 190.939674 -269.324836) (xy 190.947484 -269.324522) (xy 190.962356 -269.319737)
			(xy 190.968884 -269.315438) (xy 190.989973 -269.301089) (xy 191.035634 -269.278358) (xy 191.08424 -269.262899)
			(xy 191.134643 -269.255076) (xy 191.185649 -269.255076) (xy 191.236052 -269.262899) (xy 191.284658 -269.278358)
			(xy 191.330319 -269.301089) (xy 191.351408 -269.315438) (xy 191.357942 -269.319725) (xy 191.37281 -269.324512)
			(xy 191.380618 -269.324836) (xy 191.896746 -269.324836) (xy 191.902043 -269.325359) (xy 191.909617 -269.33276)
			(xy 191.910208 -269.338044) (xy 191.910208 -269.832582) (xy 191.910181 -269.832836) (xy 197.954392 -269.832836)
			(xy 197.954392 -269.832328) (xy 197.954392 -269.338044) (xy 197.954756 -269.332718) (xy 197.962275 -269.325174)
			(xy 197.9676 -269.324836) (xy 198.483728 -269.324836) (xy 198.49154 -269.324545) (xy 198.506412 -269.319745)
			(xy 198.512938 -269.315438) (xy 198.534027 -269.301089) (xy 198.579688 -269.278358) (xy 198.628294 -269.262899)
			(xy 198.678697 -269.255076) (xy 198.729703 -269.255076) (xy 198.780106 -269.262899) (xy 198.828712 -269.278358)
			(xy 198.874373 -269.301089) (xy 198.895462 -269.315438) (xy 198.902006 -269.319707) (xy 198.916866 -269.324505)
			(xy 198.924672 -269.324836) (xy 199.4408 -269.324836) (xy 199.446143 -269.325131) (xy 199.453687 -269.3327)
			(xy 199.454008 -269.338044) (xy 199.454008 -269.832582) (xy 199.453982 -269.832836) (xy 205.498192 -269.832836)
			(xy 205.498192 -269.832328) (xy 205.498192 -269.338044) (xy 205.498556 -269.332718) (xy 205.506075 -269.325174)
			(xy 205.5114 -269.324836) (xy 206.027528 -269.324836) (xy 206.03534 -269.324545) (xy 206.050212 -269.319745)
			(xy 206.056738 -269.315438) (xy 206.077827 -269.301089) (xy 206.123488 -269.278358) (xy 206.172094 -269.262899)
			(xy 206.222497 -269.255076) (xy 206.273503 -269.255076) (xy 206.323906 -269.262899) (xy 206.372512 -269.278358)
			(xy 206.418173 -269.301089) (xy 206.439262 -269.315438) (xy 206.445806 -269.319707) (xy 206.460666 -269.324505)
			(xy 206.468472 -269.324836) (xy 206.9846 -269.324836) (xy 206.989943 -269.325131) (xy 206.997487 -269.3327)
			(xy 206.997808 -269.338044) (xy 206.997808 -269.832328) (xy 268.898116 -269.832328) (xy 268.898116 -269.33779)
			(xy 268.898642 -269.33243) (xy 268.906219 -269.324846) (xy 268.911578 -269.324328) (xy 269.427706 -269.324328)
			(xy 269.435518 -269.324029) (xy 269.450389 -269.319234) (xy 269.456916 -269.31493) (xy 269.478005 -269.300581)
			(xy 269.523666 -269.27785) (xy 269.572272 -269.262391) (xy 269.622675 -269.254568) (xy 269.673681 -269.254568)
			(xy 269.724084 -269.262391) (xy 269.77269 -269.27785) (xy 269.818351 -269.300581) (xy 269.83944 -269.31493)
			(xy 269.845967 -269.319229) (xy 269.86084 -269.324008) (xy 269.86865 -269.324328) (xy 270.384778 -269.324328)
			(xy 270.390207 -269.324693) (xy 270.397894 -269.332361) (xy 270.39824 -269.33779) (xy 270.39824 -269.832328)
			(xy 276.442424 -269.832328) (xy 276.442424 -269.33779) (xy 276.442915 -269.332488) (xy 276.450341 -269.324919)
			(xy 276.455632 -269.324328) (xy 276.97176 -269.324328) (xy 276.97957 -269.324009) (xy 276.994442 -269.319228)
			(xy 277.00097 -269.31493) (xy 277.022059 -269.300581) (xy 277.06772 -269.27785) (xy 277.116326 -269.262391)
			(xy 277.166729 -269.254568) (xy 277.217735 -269.254568) (xy 277.268138 -269.262391) (xy 277.316744 -269.27785)
			(xy 277.362405 -269.300581) (xy 277.383494 -269.31493) (xy 277.390032 -269.319211) (xy 277.404897 -269.324002)
			(xy 277.412704 -269.324328) (xy 277.928832 -269.324328) (xy 277.934177 -269.324609) (xy 277.941718 -269.332189)
			(xy 277.94204 -269.337536) (xy 277.94204 -269.338044) (xy 277.94204 -269.832328) (xy 283.986224 -269.832328)
			(xy 283.986224 -269.33779) (xy 283.986715 -269.332488) (xy 283.994141 -269.324919) (xy 283.999432 -269.324328)
			(xy 284.51556 -269.324328) (xy 284.52337 -269.324009) (xy 284.538242 -269.319228) (xy 284.54477 -269.31493)
			(xy 284.565859 -269.300581) (xy 284.61152 -269.27785) (xy 284.660126 -269.262391) (xy 284.710529 -269.254568)
			(xy 284.761535 -269.254568) (xy 284.811938 -269.262391) (xy 284.860544 -269.27785) (xy 284.906205 -269.300581)
			(xy 284.927294 -269.31493) (xy 284.933832 -269.319211) (xy 284.948697 -269.324002) (xy 284.956504 -269.324328)
			(xy 285.472632 -269.324328) (xy 285.477977 -269.324609) (xy 285.485518 -269.332189) (xy 285.48584 -269.337536)
			(xy 285.48584 -269.338044) (xy 285.48584 -269.832328) (xy 291.530024 -269.832328) (xy 291.530024 -269.33779)
			(xy 291.530542 -269.332428) (xy 291.538124 -269.324844) (xy 291.543486 -269.324328) (xy 292.059614 -269.324328)
			(xy 292.067426 -269.324032) (xy 292.082298 -269.319235) (xy 292.088824 -269.31493) (xy 292.109913 -269.300581)
			(xy 292.155574 -269.27785) (xy 292.20418 -269.262391) (xy 292.254583 -269.254568) (xy 292.305589 -269.254568)
			(xy 292.355992 -269.262391) (xy 292.404598 -269.27785) (xy 292.450259 -269.300581) (xy 292.471348 -269.31493)
			(xy 292.477874 -269.319232) (xy 292.492748 -269.32401) (xy 292.500558 -269.324328) (xy 293.016686 -269.324328)
			(xy 293.022116 -269.324688) (xy 293.029803 -269.33236) (xy 293.030148 -269.33779) (xy 293.030148 -269.832328)
			(xy 299.074332 -269.832328) (xy 299.074332 -269.33779) (xy 299.074816 -269.332486) (xy 299.082247 -269.324916)
			(xy 299.08754 -269.324328) (xy 299.603668 -269.324328) (xy 299.611478 -269.324013) (xy 299.62635 -269.319229)
			(xy 299.632878 -269.31493) (xy 299.653967 -269.300581) (xy 299.699628 -269.27785) (xy 299.748234 -269.262391)
			(xy 299.798637 -269.254568) (xy 299.849643 -269.254568) (xy 299.900046 -269.262391) (xy 299.948652 -269.27785)
			(xy 299.994313 -269.300581) (xy 300.015402 -269.31493) (xy 300.021938 -269.319214) (xy 300.036804 -269.324003)
			(xy 300.044612 -269.324328) (xy 300.56074 -269.324328) (xy 300.566016 -269.324772) (xy 300.573459 -269.332257)
			(xy 300.573948 -269.337536) (xy 300.573948 -269.338044) (xy 300.573948 -269.832328) (xy 306.618132 -269.832328)
			(xy 306.618132 -269.33779) (xy 306.618643 -269.332426) (xy 306.62623 -269.324842) (xy 306.631594 -269.324328)
			(xy 308.104794 -269.324328) (xy 308.110155 -269.324853) (xy 308.11774 -269.33243) (xy 308.118256 -269.33779)
			(xy 308.118256 -269.832328) (xy 415.718244 -269.832328) (xy 415.718244 -269.33779) (xy 415.718717 -269.332484)
			(xy 415.726155 -269.324913) (xy 415.731452 -269.324328) (xy 417.204652 -269.324328) (xy 417.209987 -269.324663)
			(xy 417.217532 -269.332202) (xy 417.21786 -269.337536) (xy 417.21786 -269.832328) (xy 423.262044 -269.832328)
			(xy 423.262044 -269.33779) (xy 423.262544 -269.332423) (xy 423.270139 -269.324838) (xy 423.275506 -269.324328)
			(xy 423.791634 -269.324328) (xy 423.799443 -269.323998) (xy 423.814315 -269.319225) (xy 423.820844 -269.31493)
			(xy 423.841933 -269.300581) (xy 423.887594 -269.27785) (xy 423.9362 -269.262391) (xy 423.986603 -269.254568)
			(xy 424.037609 -269.254568) (xy 424.088012 -269.262391) (xy 424.136618 -269.27785) (xy 424.182279 -269.300581)
			(xy 424.203368 -269.31493) (xy 424.209911 -269.319201) (xy 424.224772 -269.323998) (xy 424.232578 -269.324328)
			(xy 424.748706 -269.324328) (xy 424.754068 -269.324845) (xy 424.761653 -269.332428) (xy 424.762168 -269.33779)
			(xy 424.762168 -269.832328) (xy 430.806352 -269.832328) (xy 430.806352 -269.33779) (xy 430.806818 -269.332482)
			(xy 430.814261 -269.324911) (xy 430.81956 -269.324328) (xy 431.335688 -269.324328) (xy 431.343499 -269.324021)
			(xy 431.358371 -269.319232) (xy 431.364898 -269.31493) (xy 431.385987 -269.300581) (xy 431.431648 -269.27785)
			(xy 431.480254 -269.262391) (xy 431.530657 -269.254568) (xy 431.581663 -269.254568) (xy 431.632066 -269.262391)
			(xy 431.680672 -269.27785) (xy 431.726333 -269.300581) (xy 431.747422 -269.31493) (xy 431.753953 -269.319222)
			(xy 431.768823 -269.324006) (xy 431.776632 -269.324328) (xy 432.29276 -269.324328) (xy 432.298096 -269.324657)
			(xy 432.305641 -269.332201) (xy 432.305968 -269.337536) (xy 432.305968 -269.338044) (xy 432.305968 -269.832328)
			(xy 438.350152 -269.832328) (xy 438.350152 -269.33779) (xy 438.350474 -269.33235) (xy 438.358174 -269.324664)
			(xy 438.363614 -269.324328) (xy 438.879742 -269.324328) (xy 438.887551 -269.324002) (xy 438.902423 -269.319226)
			(xy 438.908952 -269.31493) (xy 438.930041 -269.300581) (xy 438.975702 -269.27785) (xy 439.024308 -269.262391)
			(xy 439.074711 -269.254568) (xy 439.125717 -269.254568) (xy 439.17612 -269.262391) (xy 439.224726 -269.27785)
			(xy 439.270387 -269.300581) (xy 439.291476 -269.31493) (xy 439.298018 -269.319204) (xy 439.31288 -269.323999)
			(xy 439.320686 -269.324328) (xy 439.836814 -269.324328) (xy 439.842177 -269.32484) (xy 439.849761 -269.332427)
			(xy 439.850276 -269.33779) (xy 439.850276 -269.832328) (xy 445.89446 -269.832328) (xy 445.89446 -269.33779)
			(xy 445.894919 -269.33248) (xy 445.902367 -269.324908) (xy 445.907668 -269.324328) (xy 446.423796 -269.324328)
			(xy 446.431607 -269.324025) (xy 446.446479 -269.319233) (xy 446.453006 -269.31493) (xy 446.474095 -269.300581)
			(xy 446.519756 -269.27785) (xy 446.568362 -269.262391) (xy 446.618765 -269.254568) (xy 446.669771 -269.254568)
			(xy 446.720174 -269.262391) (xy 446.76878 -269.27785) (xy 446.814441 -269.300581) (xy 446.83553 -269.31493)
			(xy 446.84206 -269.319225) (xy 446.856931 -269.324007) (xy 446.86474 -269.324328) (xy 447.380868 -269.324328)
			(xy 447.386205 -269.324652) (xy 447.39375 -269.332199) (xy 447.394076 -269.337536) (xy 447.394076 -269.338044)
			(xy 447.394076 -269.832328) (xy 453.43826 -269.832328) (xy 453.43826 -269.33779) (xy 453.438719 -269.33248)
			(xy 453.446167 -269.324908) (xy 453.451468 -269.324328) (xy 453.967596 -269.324328) (xy 453.975407 -269.324025)
			(xy 453.990279 -269.319233) (xy 453.996806 -269.31493) (xy 454.017895 -269.300581) (xy 454.063556 -269.27785)
			(xy 454.112162 -269.262391) (xy 454.162565 -269.254568) (xy 454.213571 -269.254568) (xy 454.263974 -269.262391)
			(xy 454.31258 -269.27785) (xy 454.358241 -269.300581) (xy 454.37933 -269.31493) (xy 454.38586 -269.319225)
			(xy 454.400731 -269.324007) (xy 454.40854 -269.324328) (xy 454.924668 -269.324328) (xy 454.930005 -269.324652)
			(xy 454.93755 -269.332199) (xy 454.937876 -269.337536) (xy 454.937876 -269.338044) (xy 454.937876 -269.832328)
			(xy 454.937589 -269.837672) (xy 454.930013 -269.845213) (xy 454.924668 -269.845536) (xy 454.408794 -269.845536)
			(xy 454.40092 -269.845831) (xy 454.385916 -269.85061) (xy 454.37933 -269.854934) (xy 454.358261 -269.869339)
			(xy 454.312613 -269.892165) (xy 454.264005 -269.907719) (xy 454.213585 -269.915633) (xy 454.188068 -269.916148)
			(xy 454.162549 -269.915633) (xy 454.112123 -269.907744) (xy 454.063512 -269.892192) (xy 454.017872 -269.869345)
			(xy 453.996806 -269.854934) (xy 453.990213 -269.850622) (xy 453.975214 -269.845833) (xy 453.967342 -269.845536)
			(xy 453.451468 -269.845536) (xy 453.446208 -269.845029) (xy 453.438769 -269.837588) (xy 453.43826 -269.832328)
			(xy 447.394076 -269.832328) (xy 447.393789 -269.837672) (xy 447.386213 -269.845213) (xy 447.380868 -269.845536)
			(xy 446.864994 -269.845536) (xy 446.85712 -269.845831) (xy 446.842116 -269.85061) (xy 446.83553 -269.854934)
			(xy 446.814461 -269.869339) (xy 446.768813 -269.892165) (xy 446.720205 -269.907719) (xy 446.669785 -269.915633)
			(xy 446.644268 -269.916148) (xy 446.618749 -269.915633) (xy 446.568323 -269.907744) (xy 446.519712 -269.892192)
			(xy 446.474072 -269.869345) (xy 446.453006 -269.854934) (xy 446.446413 -269.850622) (xy 446.431414 -269.845833)
			(xy 446.423542 -269.845536) (xy 445.907668 -269.845536) (xy 445.902408 -269.845029) (xy 445.894969 -269.837588)
			(xy 445.89446 -269.832328) (xy 439.850276 -269.832328) (xy 439.849989 -269.837672) (xy 439.842413 -269.845213)
			(xy 439.837068 -269.845536) (xy 439.83656 -269.845536) (xy 439.32094 -269.845536) (xy 439.313064 -269.845808)
			(xy 439.29806 -269.850603) (xy 439.291476 -269.854934) (xy 439.270394 -269.869319) (xy 439.224751 -269.892149)
			(xy 439.176146 -269.907709) (xy 439.12573 -269.91563) (xy 439.100214 -269.916148) (xy 439.074694 -269.91566)
			(xy 439.024267 -269.907763) (xy 438.975656 -269.892203) (xy 438.930017 -269.869348) (xy 438.908952 -269.854934)
			(xy 438.902371 -269.850601) (xy 438.887363 -269.845825) (xy 438.879488 -269.845536) (xy 438.363614 -269.845536)
			(xy 438.358306 -269.845065) (xy 438.350733 -269.837626) (xy 438.350152 -269.832328) (xy 432.305968 -269.832328)
			(xy 432.305688 -269.837674) (xy 432.298108 -269.845216) (xy 432.29276 -269.845536) (xy 431.776886 -269.845536)
			(xy 431.769012 -269.845828) (xy 431.754008 -269.850609) (xy 431.747422 -269.854934) (xy 431.726356 -269.869343)
			(xy 431.680707 -269.892167) (xy 431.632097 -269.907721) (xy 431.581678 -269.915634) (xy 431.55616 -269.916148)
			(xy 431.530641 -269.915637) (xy 431.480215 -269.907747) (xy 431.431604 -269.892193) (xy 431.385964 -269.869346)
			(xy 431.364898 -269.854934) (xy 431.358307 -269.850619) (xy 431.343307 -269.845832) (xy 431.335434 -269.845536)
			(xy 430.81956 -269.845536) (xy 430.814299 -269.845035) (xy 430.80686 -269.837589) (xy 430.806352 -269.832328)
			(xy 424.762168 -269.832328) (xy 424.761888 -269.837674) (xy 424.754308 -269.845216) (xy 424.74896 -269.845536)
			(xy 424.748452 -269.845536) (xy 424.232832 -269.845536) (xy 424.224956 -269.845804) (xy 424.209952 -269.850601)
			(xy 424.203368 -269.854934) (xy 424.182289 -269.869323) (xy 424.136645 -269.892152) (xy 424.088039 -269.907711)
			(xy 424.037623 -269.915631) (xy 424.012106 -269.916148) (xy 423.986586 -269.915664) (xy 423.936159 -269.907766)
			(xy 423.887548 -269.892204) (xy 423.841909 -269.869349) (xy 423.820844 -269.854934) (xy 423.814265 -269.850598)
			(xy 423.799255 -269.845824) (xy 423.79138 -269.845536) (xy 423.275506 -269.845536) (xy 423.270197 -269.84507)
			(xy 423.262624 -269.837628) (xy 423.262044 -269.832328) (xy 417.21786 -269.832328) (xy 417.217587 -269.837676)
			(xy 417.210002 -269.845218) (xy 417.204652 -269.845536) (xy 415.731452 -269.845536) (xy 415.72619 -269.84504)
			(xy 415.718752 -269.83759) (xy 415.718244 -269.832328) (xy 308.118256 -269.832328) (xy 308.117729 -269.837583)
			(xy 308.110302 -269.845021) (xy 308.105048 -269.845536) (xy 308.10454 -269.845536) (xy 306.631594 -269.845536)
			(xy 306.626283 -269.845078) (xy 306.618711 -269.83763) (xy 306.618132 -269.832328) (xy 300.573948 -269.832328)
			(xy 300.573428 -269.837585) (xy 300.565996 -269.845023) (xy 300.56074 -269.845536) (xy 300.044866 -269.845536)
			(xy 300.036991 -269.845819) (xy 300.021987 -269.850606) (xy 300.015402 -269.854934) (xy 299.994313 -269.869308)
			(xy 299.948673 -269.892141) (xy 299.90007 -269.907704) (xy 299.849656 -269.915628) (xy 299.82414 -269.916148)
			(xy 299.79862 -269.915647) (xy 299.748194 -269.907754) (xy 299.699583 -269.892197) (xy 299.653944 -269.869347)
			(xy 299.632878 -269.854934) (xy 299.626291 -269.850611) (xy 299.611288 -269.845829) (xy 299.603414 -269.845536)
			(xy 299.08754 -269.845536) (xy 299.08222 -269.845149) (xy 299.074678 -269.837646) (xy 299.074332 -269.832328)
			(xy 293.030148 -269.832328) (xy 293.029628 -269.837585) (xy 293.022196 -269.845023) (xy 293.01694 -269.845536)
			(xy 293.016432 -269.845536) (xy 292.500812 -269.845536) (xy 292.492939 -269.845839) (xy 292.477935 -269.850612)
			(xy 292.471348 -269.854934) (xy 292.450274 -269.869331) (xy 292.404628 -269.892159) (xy 292.356021 -269.907715)
			(xy 292.305603 -269.915632) (xy 292.280086 -269.916148) (xy 292.254567 -269.915624) (xy 292.204142 -269.907738)
			(xy 292.155531 -269.892188) (xy 292.109891 -269.869344) (xy 292.088824 -269.854934) (xy 292.082227 -269.850629)
			(xy 292.067231 -269.845835) (xy 292.05936 -269.845536) (xy 291.543486 -269.845536) (xy 291.538175 -269.845083)
			(xy 291.530603 -269.837631) (xy 291.530024 -269.832328) (xy 285.48584 -269.832328) (xy 285.485327 -269.837586)
			(xy 285.47789 -269.845026) (xy 285.472632 -269.845536) (xy 284.956758 -269.845536) (xy 284.948883 -269.845815)
			(xy 284.933879 -269.850605) (xy 284.927294 -269.854934) (xy 284.906207 -269.869312) (xy 284.860566 -269.892143)
			(xy 284.811963 -269.907705) (xy 284.761548 -269.915629) (xy 284.736032 -269.916148) (xy 284.710512 -269.915651)
			(xy 284.660086 -269.907757) (xy 284.611475 -269.892199) (xy 284.565836 -269.869347) (xy 284.54477 -269.854934)
			(xy 284.538185 -269.850608) (xy 284.52318 -269.845828) (xy 284.515306 -269.845536) (xy 283.999432 -269.845536)
			(xy 283.994111 -269.845154) (xy 283.98657 -269.837648) (xy 283.986224 -269.832328) (xy 277.94204 -269.832328)
			(xy 277.941527 -269.837586) (xy 277.93409 -269.845026) (xy 277.928832 -269.845536) (xy 277.412958 -269.845536)
			(xy 277.405083 -269.845815) (xy 277.390079 -269.850605) (xy 277.383494 -269.854934) (xy 277.362407 -269.869312)
			(xy 277.316766 -269.892143) (xy 277.268163 -269.907705) (xy 277.217748 -269.915629) (xy 277.192232 -269.916148)
			(xy 277.166712 -269.915651) (xy 277.116286 -269.907757) (xy 277.067675 -269.892199) (xy 277.022036 -269.869347)
			(xy 277.00097 -269.854934) (xy 276.994385 -269.850608) (xy 276.97938 -269.845828) (xy 276.971506 -269.845536)
			(xy 276.455632 -269.845536) (xy 276.450311 -269.845154) (xy 276.44277 -269.837648) (xy 276.442424 -269.832328)
			(xy 270.39824 -269.832328) (xy 270.397727 -269.837586) (xy 270.39029 -269.845026) (xy 270.385032 -269.845536)
			(xy 270.384524 -269.845536) (xy 269.868904 -269.845536) (xy 269.861031 -269.845835) (xy 269.846027 -269.850611)
			(xy 269.83944 -269.854934) (xy 269.818369 -269.869335) (xy 269.772722 -269.892161) (xy 269.724114 -269.907717)
			(xy 269.673695 -269.915633) (xy 269.648178 -269.916148) (xy 269.622659 -269.915628) (xy 269.572234 -269.907741)
			(xy 269.523622 -269.89219) (xy 269.477982 -269.869344) (xy 269.456916 -269.854934) (xy 269.450321 -269.850626)
			(xy 269.435324 -269.845834) (xy 269.427452 -269.845536) (xy 268.911578 -269.845536) (xy 268.906266 -269.845089)
			(xy 268.898694 -269.837632) (xy 268.898116 -269.832328) (xy 206.997808 -269.832328) (xy 206.997808 -269.832582)
			(xy 206.997271 -269.837873) (xy 206.989878 -269.845442) (xy 206.9846 -269.846044) (xy 206.468726 -269.846044)
			(xy 206.460916 -269.846362) (xy 206.446044 -269.851144) (xy 206.439516 -269.855442) (xy 206.418387 -269.869779)
			(xy 206.372666 -269.892509) (xy 206.323995 -269.907942) (xy 206.27353 -269.915713) (xy 206.248 -269.916148)
			(xy 206.22247 -269.915714) (xy 206.172006 -269.907938) (xy 206.123333 -269.892508) (xy 206.077606 -269.86979)
			(xy 206.056484 -269.855442) (xy 206.049953 -269.85115) (xy 206.035083 -269.846367) (xy 206.027274 -269.846044)
			(xy 205.5114 -269.846044) (xy 205.506146 -269.845509) (xy 205.498706 -269.838089) (xy 205.498192 -269.832836)
			(xy 199.453982 -269.832836) (xy 199.453471 -269.837873) (xy 199.446078 -269.845442) (xy 199.4408 -269.846044)
			(xy 198.924926 -269.846044) (xy 198.917116 -269.846362) (xy 198.902244 -269.851144) (xy 198.895716 -269.855442)
			(xy 198.874587 -269.869779) (xy 198.828866 -269.892509) (xy 198.780195 -269.907942) (xy 198.72973 -269.915713)
			(xy 198.7042 -269.916148) (xy 198.67867 -269.915714) (xy 198.628206 -269.907938) (xy 198.579533 -269.892508)
			(xy 198.533806 -269.86979) (xy 198.512684 -269.855442) (xy 198.506153 -269.85115) (xy 198.491283 -269.846367)
			(xy 198.483474 -269.846044) (xy 197.9676 -269.846044) (xy 197.962346 -269.845509) (xy 197.954906 -269.838089)
			(xy 197.954392 -269.832836) (xy 191.910181 -269.832836) (xy 191.909642 -269.837933) (xy 191.902094 -269.845517)
			(xy 191.896746 -269.846044) (xy 191.380872 -269.846044) (xy 191.37306 -269.846338) (xy 191.358188 -269.851137)
			(xy 191.351662 -269.855442) (xy 191.330548 -269.869803) (xy 191.284821 -269.892527) (xy 191.236146 -269.907954)
			(xy 191.185678 -269.915717) (xy 191.160146 -269.916148) (xy 191.134616 -269.915691) (xy 191.084153 -269.907922)
			(xy 191.035481 -269.892499) (xy 190.989752 -269.869787) (xy 190.96863 -269.855442) (xy 190.962089 -269.851168)
			(xy 190.947226 -269.846374) (xy 190.93942 -269.846044) (xy 190.423546 -269.846044) (xy 190.418113 -269.845688)
			(xy 190.410423 -269.838014) (xy 190.410084 -269.832582) (xy 184.3659 -269.832582) (xy 184.36537 -269.837875)
			(xy 184.357972 -269.845445) (xy 184.352692 -269.846044) (xy 183.836818 -269.846044) (xy 183.829008 -269.846358)
			(xy 183.814136 -269.851143) (xy 183.807608 -269.855442) (xy 183.786481 -269.869783) (xy 183.740759 -269.892512)
			(xy 183.692088 -269.907944) (xy 183.641623 -269.915713) (xy 183.616092 -269.916148) (xy 183.590561 -269.915718)
			(xy 183.540097 -269.907941) (xy 183.491425 -269.89251) (xy 183.445698 -269.869791) (xy 183.424576 -269.855442)
			(xy 183.418047 -269.851147) (xy 183.403175 -269.846366) (xy 183.395366 -269.846044) (xy 182.879492 -269.846044)
			(xy 182.874237 -269.845514) (xy 182.866797 -269.83809) (xy 182.866284 -269.832836) (xy 176.822074 -269.832836)
			(xy 176.821542 -269.837935) (xy 176.813989 -269.845519) (xy 176.808638 -269.846044) (xy 176.292764 -269.846044)
			(xy 176.284956 -269.846378) (xy 176.270084 -269.851149) (xy 176.263554 -269.855442) (xy 176.242442 -269.869806)
			(xy 176.196715 -269.89253) (xy 176.148039 -269.907956) (xy 176.09757 -269.915718) (xy 176.072038 -269.916148)
			(xy 176.046508 -269.915695) (xy 175.996045 -269.907925) (xy 175.947372 -269.8925) (xy 175.901644 -269.869788)
			(xy 175.880522 -269.855442) (xy 175.873982 -269.851165) (xy 175.859119 -269.846372) (xy 175.851312 -269.846044)
			(xy 175.335438 -269.846044) (xy 175.330004 -269.845694) (xy 175.322314 -269.838016) (xy 175.321976 -269.832582)
			(xy 169.277792 -269.832582) (xy 169.277269 -269.837877) (xy 169.269866 -269.845447) (xy 169.264584 -269.846044)
			(xy 167.791384 -269.846044) (xy 167.786128 -269.84552) (xy 167.778688 -269.838091) (xy 167.778176 -269.832836)
			(xy 60.178162 -269.832836) (xy 60.17764 -269.837938) (xy 60.17008 -269.845523) (xy 60.164726 -269.846044)
			(xy 58.691526 -269.846044) (xy 58.68609 -269.845702) (xy 58.678402 -269.838018) (xy 58.678064 -269.832582)
			(xy 52.63388 -269.832582) (xy 52.633367 -269.837879) (xy 52.625958 -269.84545) (xy 52.620672 -269.846044)
			(xy 52.104798 -269.846044) (xy 52.096987 -269.846349) (xy 52.082115 -269.85114) (xy 52.075588 -269.855442)
			(xy 52.054466 -269.869791) (xy 52.008743 -269.892518) (xy 51.960069 -269.907948) (xy 51.909603 -269.915715)
			(xy 51.884072 -269.916148) (xy 51.858541 -269.915728) (xy 51.808076 -269.907948) (xy 51.759404 -269.892514)
			(xy 51.713677 -269.869792) (xy 51.692556 -269.855442) (xy 51.686031 -269.851139) (xy 51.671156 -269.846363)
			(xy 51.663346 -269.846044) (xy 51.147472 -269.846044) (xy 51.142215 -269.845528) (xy 51.134775 -269.838093)
			(xy 51.134264 -269.832836) (xy 45.090054 -269.832836) (xy 45.08954 -269.83794) (xy 45.081974 -269.845525)
			(xy 45.076618 -269.846044) (xy 44.560744 -269.846044) (xy 44.552935 -269.846369) (xy 44.538063 -269.851147)
			(xy 44.531534 -269.855442) (xy 44.510428 -269.869815) (xy 44.464698 -269.892536) (xy 44.41602 -269.90796)
			(xy 44.36555 -269.915719) (xy 44.340018 -269.916148) (xy 44.314488 -269.915705) (xy 44.264024 -269.907932)
			(xy 44.215352 -269.892505) (xy 44.169624 -269.869789) (xy 44.148502 -269.855442) (xy 44.141967 -269.851157)
			(xy 44.1271 -269.846369) (xy 44.119292 -269.846044) (xy 43.603418 -269.846044) (xy 43.597981 -269.845707)
			(xy 43.590293 -269.838019) (xy 43.589956 -269.832582) (xy 37.545772 -269.832582) (xy 37.545266 -269.837881)
			(xy 37.537852 -269.845453) (xy 37.532564 -269.846044) (xy 37.01669 -269.846044) (xy 37.008879 -269.846346)
			(xy 36.994007 -269.851139) (xy 36.98748 -269.855442) (xy 36.966361 -269.869795) (xy 36.920636 -269.892521)
			(xy 36.871962 -269.90795) (xy 36.821495 -269.915716) (xy 36.795964 -269.916148) (xy 36.770433 -269.915732)
			(xy 36.719968 -269.907951) (xy 36.671296 -269.892515) (xy 36.625569 -269.869793) (xy 36.604448 -269.855442)
			(xy 36.597925 -269.851136) (xy 36.583048 -269.846362) (xy 36.575238 -269.846044) (xy 36.059364 -269.846044)
			(xy 36.054106 -269.845533) (xy 36.046667 -269.838094) (xy 36.046156 -269.832836) (xy 30.001948 -269.832836)
			(xy 30.001466 -269.837881) (xy 29.994052 -269.845453) (xy 29.988764 -269.846044) (xy 29.47289 -269.846044)
			(xy 29.465079 -269.846346) (xy 29.450207 -269.851139) (xy 29.44368 -269.855442) (xy 29.422561 -269.869795)
			(xy 29.376836 -269.892521) (xy 29.328162 -269.90795) (xy 29.277695 -269.915716) (xy 29.252164 -269.916148)
			(xy 29.226633 -269.915732) (xy 29.176168 -269.907951) (xy 29.127496 -269.892515) (xy 29.081769 -269.869793)
			(xy 29.060648 -269.855442) (xy 29.054125 -269.851136) (xy 29.039248 -269.846362) (xy 29.031438 -269.846044)
			(xy 28.515564 -269.846044) (xy 28.510306 -269.845533) (xy 28.502867 -269.838094) (xy 28.502356 -269.832836)
			(xy 22.458155 -269.832836) (xy 22.45781 -269.838012) (xy 22.450139 -269.845699) (xy 22.44471 -269.846044)
			(xy 21.928836 -269.846044) (xy 21.921027 -269.846366) (xy 21.906155 -269.851146) (xy 21.899626 -269.855442)
			(xy 21.878494 -269.869775) (xy 21.832774 -269.892506) (xy 21.784104 -269.90794) (xy 21.73364 -269.915712)
			(xy 21.70811 -269.916148) (xy 21.68258 -269.915709) (xy 21.632116 -269.907935) (xy 21.583443 -269.892506)
			(xy 21.537716 -269.86979) (xy 21.516594 -269.855442) (xy 21.510061 -269.851154) (xy 21.495192 -269.846368)
			(xy 21.487384 -269.846044) (xy 20.97151 -269.846044) (xy 20.966072 -269.845712) (xy 20.958384 -269.83802)
			(xy 20.958048 -269.832582) (xy 2.509012 -269.832582) (xy 2.509012 -270.682466) (xy 20.958048 -270.682466)
			(xy 20.958048 -270.187928) (xy 20.958609 -270.182679) (xy 20.96601 -270.175238) (xy 20.971256 -270.17472)
			(xy 20.971764 -270.17472) (xy 21.487638 -270.17472) (xy 21.495447 -270.174393) (xy 21.510319 -270.169618)
			(xy 21.516848 -270.165322) (xy 21.537937 -270.150973) (xy 21.583598 -270.128242) (xy 21.632204 -270.112783)
			(xy 21.682607 -270.10496) (xy 21.733613 -270.10496) (xy 21.784016 -270.112783) (xy 21.832622 -270.128242)
			(xy 21.878283 -270.150973) (xy 21.899372 -270.165322) (xy 21.905915 -270.169594) (xy 21.920776 -270.17439)
			(xy 21.928582 -270.17472) (xy 22.44471 -270.17472) (xy 22.450011 -270.175214) (xy 22.45758 -270.182638)
			(xy 22.458172 -270.187928) (xy 22.458172 -270.682466) (xy 22.458155 -270.68272) (xy 28.502356 -270.68272)
			(xy 28.502356 -270.682212) (xy 28.502356 -270.187928) (xy 28.50291 -270.182677) (xy 28.510316 -270.175235)
			(xy 28.515564 -270.17472) (xy 29.031692 -270.17472) (xy 29.039503 -270.174416) (xy 29.054375 -270.169625)
			(xy 29.060902 -270.165322) (xy 29.081991 -270.150973) (xy 29.127652 -270.128242) (xy 29.176258 -270.112783)
			(xy 29.226661 -270.10496) (xy 29.277667 -270.10496) (xy 29.32807 -270.112783) (xy 29.376676 -270.128242)
			(xy 29.422337 -270.150973) (xy 29.443426 -270.165322) (xy 29.449957 -270.169615) (xy 29.464827 -270.174398)
			(xy 29.472636 -270.17472) (xy 29.988764 -270.17472) (xy 29.994098 -270.175054) (xy 30.001643 -270.182594)
			(xy 30.001972 -270.187928) (xy 30.001972 -270.682466) (xy 30.001947 -270.68272) (xy 36.046156 -270.68272)
			(xy 36.046156 -270.682212) (xy 36.046156 -270.187928) (xy 36.04671 -270.182677) (xy 36.054116 -270.175235)
			(xy 36.059364 -270.17472) (xy 36.575492 -270.17472) (xy 36.583303 -270.174416) (xy 36.598175 -270.169625)
			(xy 36.604702 -270.165322) (xy 36.625791 -270.150973) (xy 36.671452 -270.128242) (xy 36.720058 -270.112783)
			(xy 36.770461 -270.10496) (xy 36.821467 -270.10496) (xy 36.87187 -270.112783) (xy 36.920476 -270.128242)
			(xy 36.966137 -270.150973) (xy 36.987226 -270.165322) (xy 36.993757 -270.169615) (xy 37.008627 -270.174398)
			(xy 37.016436 -270.17472) (xy 37.532564 -270.17472) (xy 37.537898 -270.175054) (xy 37.545443 -270.182594)
			(xy 37.545772 -270.187928) (xy 37.545772 -270.682466) (xy 43.589956 -270.682466) (xy 43.589956 -270.187928)
			(xy 43.59051 -270.182677) (xy 43.597916 -270.175235) (xy 43.603164 -270.17472) (xy 43.603672 -270.17472)
			(xy 44.119546 -270.17472) (xy 44.127355 -270.174397) (xy 44.142228 -270.169619) (xy 44.148756 -270.165322)
			(xy 44.169845 -270.150973) (xy 44.215506 -270.128242) (xy 44.264112 -270.112783) (xy 44.314515 -270.10496)
			(xy 44.365521 -270.10496) (xy 44.415924 -270.112783) (xy 44.46453 -270.128242) (xy 44.510191 -270.150973)
			(xy 44.53128 -270.165322) (xy 44.537821 -270.169597) (xy 44.552684 -270.174392) (xy 44.56049 -270.17472)
			(xy 45.076618 -270.17472) (xy 45.08192 -270.175209) (xy 45.089489 -270.182636) (xy 45.09008 -270.187928)
			(xy 45.09008 -270.682466) (xy 45.090062 -270.68272) (xy 51.134264 -270.68272) (xy 51.134264 -270.682212)
			(xy 51.134264 -270.187928) (xy 51.13481 -270.182675) (xy 51.142222 -270.175233) (xy 51.147472 -270.17472)
			(xy 51.6636 -270.17472) (xy 51.671412 -270.17442) (xy 51.686283 -270.169626) (xy 51.69281 -270.165322)
			(xy 51.713899 -270.150973) (xy 51.75956 -270.128242) (xy 51.808166 -270.112783) (xy 51.858569 -270.10496)
			(xy 51.909575 -270.10496) (xy 51.959978 -270.112783) (xy 52.008584 -270.128242) (xy 52.054245 -270.150973)
			(xy 52.075334 -270.165322) (xy 52.081863 -270.169618) (xy 52.096735 -270.174399) (xy 52.104544 -270.17472)
			(xy 52.620672 -270.17472) (xy 52.626007 -270.175048) (xy 52.633552 -270.182593) (xy 52.63388 -270.187928)
			(xy 52.63388 -270.682466) (xy 58.678064 -270.682466) (xy 58.678064 -270.187928) (xy 58.67861 -270.182675)
			(xy 58.686022 -270.175233) (xy 58.691272 -270.17472) (xy 58.69178 -270.17472) (xy 60.164726 -270.17472)
			(xy 60.170029 -270.175204) (xy 60.177597 -270.182635) (xy 60.178188 -270.187928) (xy 60.178188 -270.682466)
			(xy 60.17817 -270.68272) (xy 167.778176 -270.68272) (xy 167.778176 -270.187928) (xy 167.778544 -270.182603)
			(xy 167.78606 -270.175062) (xy 167.791384 -270.17472) (xy 169.264584 -270.17472) (xy 169.269921 -270.17504)
			(xy 169.277465 -270.182591) (xy 169.277792 -270.187928) (xy 169.277792 -270.682466) (xy 175.321976 -270.682466)
			(xy 175.321976 -270.187928) (xy 175.322344 -270.182603) (xy 175.32986 -270.175062) (xy 175.335184 -270.17472)
			(xy 175.335692 -270.17472) (xy 175.851566 -270.17472) (xy 175.859376 -270.174405) (xy 175.874248 -270.169621)
			(xy 175.880776 -270.165322) (xy 175.901865 -270.150973) (xy 175.947526 -270.128242) (xy 175.996132 -270.112783)
			(xy 176.046535 -270.10496) (xy 176.097541 -270.10496) (xy 176.147944 -270.112783) (xy 176.19655 -270.128242)
			(xy 176.242211 -270.150973) (xy 176.2633 -270.165322) (xy 176.269837 -270.169605) (xy 176.284703 -270.174394)
			(xy 176.29251 -270.17472) (xy 176.808638 -270.17472) (xy 176.813942 -270.175196) (xy 176.82151 -270.182633)
			(xy 176.8221 -270.187928) (xy 176.8221 -270.682466) (xy 176.822073 -270.68272) (xy 182.866284 -270.68272)
			(xy 182.866284 -270.682212) (xy 182.866284 -270.187928) (xy 182.866645 -270.182601) (xy 182.874166 -270.175059)
			(xy 182.879492 -270.17472) (xy 183.39562 -270.17472) (xy 183.403432 -270.174428) (xy 183.418304 -270.169628)
			(xy 183.42483 -270.165322) (xy 183.445919 -270.150973) (xy 183.49158 -270.128242) (xy 183.540186 -270.112783)
			(xy 183.590589 -270.10496) (xy 183.641595 -270.10496) (xy 183.691998 -270.112783) (xy 183.740604 -270.128242)
			(xy 183.786265 -270.150973) (xy 183.807354 -270.165322) (xy 183.813879 -270.169625) (xy 183.828754 -270.174402)
			(xy 183.836564 -270.17472) (xy 184.352692 -270.17472) (xy 184.35803 -270.175035) (xy 184.365573 -270.182589)
			(xy 184.3659 -270.187928) (xy 184.3659 -270.682466) (xy 190.410084 -270.682466) (xy 190.410084 -270.187928)
			(xy 190.410445 -270.182601) (xy 190.417966 -270.175059) (xy 190.423292 -270.17472) (xy 190.4238 -270.17472)
			(xy 190.939674 -270.17472) (xy 190.947485 -270.174409) (xy 190.962356 -270.169622) (xy 190.968884 -270.165322)
			(xy 190.989973 -270.150973) (xy 191.035634 -270.128242) (xy 191.08424 -270.112783) (xy 191.134643 -270.10496)
			(xy 191.185649 -270.10496) (xy 191.236052 -270.112783) (xy 191.284658 -270.128242) (xy 191.330319 -270.150973)
			(xy 191.351408 -270.165322) (xy 191.357943 -270.169608) (xy 191.37281 -270.174396) (xy 191.380618 -270.17472)
			(xy 191.896746 -270.17472) (xy 191.902039 -270.175257) (xy 191.909612 -270.182648) (xy 191.910208 -270.187928)
			(xy 191.910208 -270.682466) (xy 191.910181 -270.68272) (xy 197.954392 -270.68272) (xy 197.954392 -270.682212)
			(xy 197.954392 -270.187928) (xy 197.954745 -270.182599) (xy 197.962272 -270.175057) (xy 197.9676 -270.17472)
			(xy 198.483728 -270.17472) (xy 198.491541 -270.174431) (xy 198.506412 -270.16963) (xy 198.512938 -270.165322)
			(xy 198.534027 -270.150973) (xy 198.579688 -270.128242) (xy 198.628294 -270.112783) (xy 198.678697 -270.10496)
			(xy 198.729703 -270.10496) (xy 198.780106 -270.112783) (xy 198.828712 -270.128242) (xy 198.874373 -270.150973)
			(xy 198.895462 -270.165322) (xy 198.902007 -270.16959) (xy 198.916867 -270.174389) (xy 198.924672 -270.17472)
			(xy 199.4408 -270.17472) (xy 199.446139 -270.175029) (xy 199.453682 -270.182588) (xy 199.454008 -270.187928)
			(xy 199.454008 -270.682466) (xy 199.453982 -270.68272) (xy 205.498192 -270.68272) (xy 205.498192 -270.682212)
			(xy 205.498192 -270.187928) (xy 205.498545 -270.182599) (xy 205.506072 -270.175057) (xy 205.5114 -270.17472)
			(xy 206.027528 -270.17472) (xy 206.035341 -270.174431) (xy 206.050212 -270.16963) (xy 206.056738 -270.165322)
			(xy 206.077827 -270.150973) (xy 206.123488 -270.128242) (xy 206.172094 -270.112783) (xy 206.222497 -270.10496)
			(xy 206.273503 -270.10496) (xy 206.323906 -270.112783) (xy 206.372512 -270.128242) (xy 206.418173 -270.150973)
			(xy 206.439262 -270.165322) (xy 206.445807 -270.16959) (xy 206.460667 -270.174389) (xy 206.468472 -270.17472)
			(xy 206.9846 -270.17472) (xy 206.989939 -270.175029) (xy 206.997482 -270.182588) (xy 206.997808 -270.187928)
			(xy 206.997808 -270.682212) (xy 268.898116 -270.682212) (xy 268.898116 -270.187674) (xy 268.898631 -270.182312)
			(xy 268.906216 -270.174729) (xy 268.911578 -270.174212) (xy 269.427706 -270.174212) (xy 269.435518 -270.173916)
			(xy 269.45039 -270.169119) (xy 269.456916 -270.164814) (xy 269.478005 -270.150465) (xy 269.523666 -270.127734)
			(xy 269.572272 -270.112275) (xy 269.622675 -270.104452) (xy 269.673681 -270.104452) (xy 269.724084 -270.112275)
			(xy 269.77269 -270.127734) (xy 269.818351 -270.150465) (xy 269.83944 -270.164814) (xy 269.845968 -270.169111)
			(xy 269.860841 -270.173892) (xy 269.86865 -270.174212) (xy 270.384778 -270.174212) (xy 270.390133 -270.174763)
			(xy 270.397718 -270.182321) (xy 270.39824 -270.187674) (xy 270.39824 -270.682212) (xy 276.442424 -270.682212)
			(xy 276.442424 -270.187674) (xy 276.442904 -270.18237) (xy 276.450338 -270.174802) (xy 276.455632 -270.174212)
			(xy 276.97176 -270.174212) (xy 276.97957 -270.173896) (xy 276.994442 -270.169113) (xy 277.00097 -270.164814)
			(xy 277.022059 -270.150465) (xy 277.06772 -270.127734) (xy 277.116326 -270.112275) (xy 277.166729 -270.104452)
			(xy 277.217735 -270.104452) (xy 277.268138 -270.112275) (xy 277.316744 -270.127734) (xy 277.362405 -270.150465)
			(xy 277.383494 -270.164814) (xy 277.390033 -270.169094) (xy 277.404897 -270.173885) (xy 277.412704 -270.174212)
			(xy 277.928832 -270.174212) (xy 277.934103 -270.174675) (xy 277.941545 -270.182147) (xy 277.94204 -270.18742)
			(xy 277.94204 -270.187928) (xy 277.94204 -270.682212) (xy 283.986224 -270.682212) (xy 283.986224 -270.187674)
			(xy 283.986704 -270.18237) (xy 283.994138 -270.174802) (xy 283.999432 -270.174212) (xy 284.51556 -270.174212)
			(xy 284.52337 -270.173896) (xy 284.538242 -270.169113) (xy 284.54477 -270.164814) (xy 284.565859 -270.150465)
			(xy 284.61152 -270.127734) (xy 284.660126 -270.112275) (xy 284.710529 -270.104452) (xy 284.761535 -270.104452)
			(xy 284.811938 -270.112275) (xy 284.860544 -270.127734) (xy 284.906205 -270.150465) (xy 284.927294 -270.164814)
			(xy 284.933833 -270.169094) (xy 284.948697 -270.173885) (xy 284.956504 -270.174212) (xy 285.472632 -270.174212)
			(xy 285.477903 -270.174675) (xy 285.485345 -270.182147) (xy 285.48584 -270.18742) (xy 285.48584 -270.187928)
			(xy 285.48584 -270.682212) (xy 291.530024 -270.682212) (xy 291.530024 -270.187674) (xy 291.530532 -270.18231)
			(xy 291.538122 -270.174727) (xy 291.543486 -270.174212) (xy 292.059614 -270.174212) (xy 292.067426 -270.173919)
			(xy 292.082298 -270.16912) (xy 292.088824 -270.164814) (xy 292.109913 -270.150465) (xy 292.155574 -270.127734)
			(xy 292.20418 -270.112275) (xy 292.254583 -270.104452) (xy 292.305589 -270.104452) (xy 292.355992 -270.112275)
			(xy 292.404598 -270.127734) (xy 292.450259 -270.150465) (xy 292.471348 -270.164814) (xy 292.477875 -270.169114)
			(xy 292.492748 -270.173893) (xy 292.500558 -270.174212) (xy 293.016686 -270.174212) (xy 293.022042 -270.174757)
			(xy 293.029627 -270.18232) (xy 293.030148 -270.187674) (xy 293.030148 -270.682212) (xy 299.074332 -270.682212)
			(xy 299.074332 -270.187674) (xy 299.074805 -270.182369) (xy 299.082244 -270.1748) (xy 299.08754 -270.174212)
			(xy 299.603668 -270.174212) (xy 299.611478 -270.1739) (xy 299.62635 -270.169114) (xy 299.632878 -270.164814)
			(xy 299.653967 -270.150465) (xy 299.699628 -270.127734) (xy 299.748234 -270.112275) (xy 299.798637 -270.104452)
			(xy 299.849643 -270.104452) (xy 299.900046 -270.112275) (xy 299.948652 -270.127734) (xy 299.994313 -270.150465)
			(xy 300.015402 -270.164814) (xy 300.021939 -270.169097) (xy 300.036805 -270.173887) (xy 300.044612 -270.174212)
			(xy 300.56074 -270.174212) (xy 300.566013 -270.17467) (xy 300.573454 -270.182145) (xy 300.573948 -270.18742)
			(xy 300.573948 -270.187928) (xy 300.573948 -270.682212) (xy 306.618132 -270.682212) (xy 306.618132 -270.187674)
			(xy 306.618633 -270.182308) (xy 306.626228 -270.174725) (xy 306.631594 -270.174212) (xy 308.104794 -270.174212)
			(xy 308.110151 -270.174752) (xy 308.117736 -270.182318) (xy 308.118256 -270.187674) (xy 308.118256 -270.682212)
			(xy 415.718244 -270.682212) (xy 415.718244 -270.187674) (xy 415.718707 -270.182366) (xy 415.726153 -270.174796)
			(xy 415.731452 -270.174212) (xy 417.204652 -270.174212) (xy 417.209983 -270.174561) (xy 417.217527 -270.18209)
			(xy 417.21786 -270.18742) (xy 417.21786 -270.682212) (xy 423.262044 -270.682212) (xy 423.262044 -270.187674)
			(xy 423.262534 -270.182306) (xy 423.270136 -270.174721) (xy 423.275506 -270.174212) (xy 423.791634 -270.174212)
			(xy 423.799443 -270.173885) (xy 423.814315 -270.16911) (xy 423.820844 -270.164814) (xy 423.841933 -270.150465)
			(xy 423.887594 -270.127734) (xy 423.9362 -270.112275) (xy 423.986603 -270.104452) (xy 424.037609 -270.104452)
			(xy 424.088012 -270.112275) (xy 424.136618 -270.127734) (xy 424.182279 -270.150465) (xy 424.203368 -270.164814)
			(xy 424.209912 -270.169084) (xy 424.224772 -270.173882) (xy 424.232578 -270.174212) (xy 424.748706 -270.174212)
			(xy 424.754064 -270.174744) (xy 424.761648 -270.182316) (xy 424.762168 -270.187674) (xy 424.762168 -270.682212)
			(xy 430.806352 -270.682212) (xy 430.806352 -270.187674) (xy 430.806807 -270.182364) (xy 430.814259 -270.174794)
			(xy 430.81956 -270.174212) (xy 431.335688 -270.174212) (xy 431.343499 -270.173908) (xy 431.358371 -270.169117)
			(xy 431.364898 -270.164814) (xy 431.385987 -270.150465) (xy 431.431648 -270.127734) (xy 431.480254 -270.112275)
			(xy 431.530657 -270.104452) (xy 431.581663 -270.104452) (xy 431.632066 -270.112275) (xy 431.680672 -270.127734)
			(xy 431.726333 -270.150465) (xy 431.747422 -270.164814) (xy 431.753954 -270.169104) (xy 431.768823 -270.17389)
			(xy 431.776632 -270.174212) (xy 432.29276 -270.174212) (xy 432.298092 -270.174556) (xy 432.305636 -270.182089)
			(xy 432.305968 -270.18742) (xy 432.305968 -270.187928) (xy 432.305968 -270.682212) (xy 438.350152 -270.682212)
			(xy 438.350152 -270.187674) (xy 438.350635 -270.182304) (xy 438.358242 -270.174719) (xy 438.363614 -270.174212)
			(xy 438.879742 -270.174212) (xy 438.887551 -270.173889) (xy 438.902424 -270.169111) (xy 438.908952 -270.164814)
			(xy 438.930041 -270.150465) (xy 438.975702 -270.127734) (xy 439.024308 -270.112275) (xy 439.074711 -270.104452)
			(xy 439.125717 -270.104452) (xy 439.17612 -270.112275) (xy 439.224726 -270.127734) (xy 439.270387 -270.150465)
			(xy 439.291476 -270.164814) (xy 439.298019 -270.169087) (xy 439.31288 -270.173883) (xy 439.320686 -270.174212)
			(xy 439.836814 -270.174212) (xy 439.842173 -270.174739) (xy 439.849757 -270.182315) (xy 439.850276 -270.187674)
			(xy 439.850276 -270.682212) (xy 445.89446 -270.682212) (xy 445.89446 -270.187674) (xy 445.894908 -270.182362)
			(xy 445.902364 -270.174791) (xy 445.907668 -270.174212) (xy 446.423796 -270.174212) (xy 446.431608 -270.173911)
			(xy 446.446479 -270.169118) (xy 446.453006 -270.164814) (xy 446.474095 -270.150465) (xy 446.519756 -270.127734)
			(xy 446.568362 -270.112275) (xy 446.618765 -270.104452) (xy 446.669771 -270.104452) (xy 446.720174 -270.112275)
			(xy 446.76878 -270.127734) (xy 446.814441 -270.150465) (xy 446.83553 -270.164814) (xy 446.842061 -270.169107)
			(xy 446.856931 -270.173891) (xy 446.86474 -270.174212) (xy 447.380868 -270.174212) (xy 447.386201 -270.17455)
			(xy 447.393745 -270.182088) (xy 447.394076 -270.18742) (xy 447.394076 -270.187928) (xy 447.394076 -270.682212)
			(xy 453.43826 -270.682212) (xy 453.43826 -270.187674) (xy 453.438708 -270.182362) (xy 453.446164 -270.174791)
			(xy 453.451468 -270.174212) (xy 453.967596 -270.174212) (xy 453.975408 -270.173911) (xy 453.990279 -270.169118)
			(xy 453.996806 -270.164814) (xy 454.017895 -270.150465) (xy 454.063556 -270.127734) (xy 454.112162 -270.112275)
			(xy 454.162565 -270.104452) (xy 454.213571 -270.104452) (xy 454.263974 -270.112275) (xy 454.31258 -270.127734)
			(xy 454.358241 -270.150465) (xy 454.37933 -270.164814) (xy 454.385861 -270.169107) (xy 454.400731 -270.173891)
			(xy 454.40854 -270.174212) (xy 454.924668 -270.174212) (xy 454.930001 -270.17455) (xy 454.937545 -270.182088)
			(xy 454.937876 -270.18742) (xy 454.937876 -270.187928) (xy 454.937876 -270.682212) (xy 454.937578 -270.687554)
			(xy 454.930011 -270.695096) (xy 454.924668 -270.69542) (xy 454.408794 -270.69542) (xy 454.40092 -270.695717)
			(xy 454.385917 -270.700495) (xy 454.37933 -270.704818) (xy 454.35826 -270.719221) (xy 454.312613 -270.742048)
			(xy 454.264004 -270.757603) (xy 454.213585 -270.765517) (xy 454.188068 -270.766032) (xy 454.162549 -270.765519)
			(xy 454.112123 -270.757631) (xy 454.063512 -270.742077) (xy 454.017872 -270.71923) (xy 453.996806 -270.704818)
			(xy 453.990214 -270.700504) (xy 453.975214 -270.695717) (xy 453.967342 -270.69542) (xy 453.451468 -270.69542)
			(xy 453.446204 -270.694928) (xy 453.438764 -270.687476) (xy 453.43826 -270.682212) (xy 447.394076 -270.682212)
			(xy 447.393778 -270.687554) (xy 447.386211 -270.695096) (xy 447.380868 -270.69542) (xy 446.864994 -270.69542)
			(xy 446.85712 -270.695717) (xy 446.842117 -270.700495) (xy 446.83553 -270.704818) (xy 446.81446 -270.719221)
			(xy 446.768813 -270.742048) (xy 446.720204 -270.757603) (xy 446.669785 -270.765517) (xy 446.644268 -270.766032)
			(xy 446.618749 -270.765519) (xy 446.568323 -270.757631) (xy 446.519712 -270.742077) (xy 446.474072 -270.71923)
			(xy 446.453006 -270.704818) (xy 446.446414 -270.700504) (xy 446.431414 -270.695717) (xy 446.423542 -270.69542)
			(xy 445.907668 -270.69542) (xy 445.902404 -270.694928) (xy 445.894964 -270.687476) (xy 445.89446 -270.682212)
			(xy 439.850276 -270.682212) (xy 439.849978 -270.687554) (xy 439.842411 -270.695096) (xy 439.837068 -270.69542)
			(xy 439.83656 -270.69542) (xy 439.32094 -270.69542) (xy 439.313064 -270.695694) (xy 439.298061 -270.700488)
			(xy 439.291476 -270.704818) (xy 439.270393 -270.719201) (xy 439.224751 -270.742032) (xy 439.176146 -270.757593)
			(xy 439.12573 -270.765514) (xy 439.100214 -270.766032) (xy 439.074694 -270.765547) (xy 439.024267 -270.75765)
			(xy 438.975655 -270.742088) (xy 438.930017 -270.719233) (xy 438.908952 -270.704818) (xy 438.902372 -270.700484)
			(xy 438.887363 -270.695709) (xy 438.879488 -270.69542) (xy 438.363614 -270.69542) (xy 438.358302 -270.694963)
			(xy 438.350728 -270.687515) (xy 438.350152 -270.682212) (xy 432.305968 -270.682212) (xy 432.305677 -270.687556)
			(xy 432.298105 -270.695098) (xy 432.29276 -270.69542) (xy 431.776886 -270.69542) (xy 431.769012 -270.695714)
			(xy 431.754008 -270.700494) (xy 431.747422 -270.704818) (xy 431.726354 -270.719225) (xy 431.680706 -270.74205)
			(xy 431.632097 -270.757604) (xy 431.581678 -270.765518) (xy 431.55616 -270.766032) (xy 431.530641 -270.765523)
			(xy 431.480215 -270.757634) (xy 431.431603 -270.742079) (xy 431.385964 -270.71923) (xy 431.364898 -270.704818)
			(xy 431.358307 -270.700501) (xy 431.343307 -270.695715) (xy 431.335434 -270.69542) (xy 430.81956 -270.69542)
			(xy 430.814295 -270.694933) (xy 430.806856 -270.687478) (xy 430.806352 -270.682212) (xy 424.762168 -270.682212)
			(xy 424.761877 -270.687556) (xy 424.754305 -270.695098) (xy 424.74896 -270.69542) (xy 424.748452 -270.69542)
			(xy 424.232832 -270.69542) (xy 424.224956 -270.695691) (xy 424.209952 -270.700487) (xy 424.203368 -270.704818)
			(xy 424.182287 -270.719205) (xy 424.136644 -270.742035) (xy 424.088039 -270.757594) (xy 424.037622 -270.765514)
			(xy 424.012106 -270.766032) (xy 423.986586 -270.765551) (xy 423.936159 -270.757653) (xy 423.887547 -270.74209)
			(xy 423.841909 -270.719234) (xy 423.820844 -270.704818) (xy 423.814266 -270.700481) (xy 423.799255 -270.695708)
			(xy 423.79138 -270.69542) (xy 423.275506 -270.69542) (xy 423.270193 -270.694968) (xy 423.262619 -270.687516)
			(xy 423.262044 -270.682212) (xy 417.21786 -270.682212) (xy 417.217576 -270.687558) (xy 417.209999 -270.695101)
			(xy 417.204652 -270.69542) (xy 415.731452 -270.69542) (xy 415.726186 -270.694938) (xy 415.718747 -270.687479)
			(xy 415.718244 -270.682212) (xy 308.118256 -270.682212) (xy 308.117718 -270.687465) (xy 308.110299 -270.694904)
			(xy 308.105048 -270.69542) (xy 308.10454 -270.69542) (xy 306.631594 -270.69542) (xy 306.62628 -270.694976)
			(xy 306.618707 -270.687518) (xy 306.618132 -270.682212) (xy 300.573948 -270.682212) (xy 300.573417 -270.687466)
			(xy 300.565993 -270.694906) (xy 300.56074 -270.69542) (xy 300.044866 -270.69542) (xy 300.036991 -270.695706)
			(xy 300.021988 -270.700491) (xy 300.015402 -270.704818) (xy 299.994312 -270.71919) (xy 299.948672 -270.742024)
			(xy 299.90007 -270.757587) (xy 299.849656 -270.765512) (xy 299.82414 -270.766032) (xy 299.79862 -270.765534)
			(xy 299.748194 -270.757641) (xy 299.699582 -270.742083) (xy 299.653944 -270.719231) (xy 299.632878 -270.704818)
			(xy 299.626292 -270.700494) (xy 299.611288 -270.695713) (xy 299.603414 -270.69542) (xy 299.08754 -270.69542)
			(xy 299.082216 -270.695047) (xy 299.074674 -270.687535) (xy 299.074332 -270.682212) (xy 293.030148 -270.682212)
			(xy 293.029617 -270.687466) (xy 293.022193 -270.694906) (xy 293.01694 -270.69542) (xy 293.016432 -270.69542)
			(xy 292.500812 -270.69542) (xy 292.492939 -270.695726) (xy 292.477935 -270.700498) (xy 292.471348 -270.704818)
			(xy 292.450273 -270.719213) (xy 292.404628 -270.742042) (xy 292.356021 -270.757599) (xy 292.305603 -270.765516)
			(xy 292.280086 -270.766032) (xy 292.254567 -270.76551) (xy 292.204142 -270.757625) (xy 292.15553 -270.742074)
			(xy 292.10989 -270.719228) (xy 292.088824 -270.704818) (xy 292.082228 -270.700511) (xy 292.067231 -270.695719)
			(xy 292.05936 -270.69542) (xy 291.543486 -270.69542) (xy 291.538171 -270.694981) (xy 291.530598 -270.687519)
			(xy 291.530024 -270.682212) (xy 285.48584 -270.682212) (xy 285.485316 -270.687468) (xy 285.477888 -270.694908)
			(xy 285.472632 -270.69542) (xy 284.956758 -270.69542) (xy 284.948883 -270.695702) (xy 284.933879 -270.70049)
			(xy 284.927294 -270.704818) (xy 284.906206 -270.719194) (xy 284.860565 -270.742026) (xy 284.811963 -270.757589)
			(xy 284.761548 -270.765513) (xy 284.736032 -270.766032) (xy 284.710512 -270.765538) (xy 284.660086 -270.757643)
			(xy 284.611474 -270.742085) (xy 284.565835 -270.719232) (xy 284.54477 -270.704818) (xy 284.538186 -270.700491)
			(xy 284.52318 -270.695711) (xy 284.515306 -270.69542) (xy 283.999432 -270.69542) (xy 283.994107 -270.695053)
			(xy 283.986565 -270.687536) (xy 283.986224 -270.682212) (xy 277.94204 -270.682212) (xy 277.941516 -270.687468)
			(xy 277.934088 -270.694908) (xy 277.928832 -270.69542) (xy 277.412958 -270.69542) (xy 277.405083 -270.695702)
			(xy 277.390079 -270.70049) (xy 277.383494 -270.704818) (xy 277.362406 -270.719194) (xy 277.316765 -270.742026)
			(xy 277.268163 -270.757589) (xy 277.217748 -270.765513) (xy 277.192232 -270.766032) (xy 277.166712 -270.765538)
			(xy 277.116286 -270.757643) (xy 277.067674 -270.742085) (xy 277.022035 -270.719232) (xy 277.00097 -270.704818)
			(xy 276.994386 -270.700491) (xy 276.97938 -270.695711) (xy 276.971506 -270.69542) (xy 276.455632 -270.69542)
			(xy 276.450307 -270.695053) (xy 276.442765 -270.687536) (xy 276.442424 -270.682212) (xy 270.39824 -270.682212)
			(xy 270.397716 -270.687468) (xy 270.390288 -270.694908) (xy 270.385032 -270.69542) (xy 270.384524 -270.69542)
			(xy 269.868904 -270.69542) (xy 269.861031 -270.695722) (xy 269.846027 -270.700497) (xy 269.83944 -270.704818)
			(xy 269.818367 -270.719217) (xy 269.772721 -270.742044) (xy 269.724114 -270.7576) (xy 269.673695 -270.765517)
			(xy 269.648178 -270.766032) (xy 269.622659 -270.765514) (xy 269.572233 -270.757627) (xy 269.523622 -270.742075)
			(xy 269.477982 -270.719229) (xy 269.456916 -270.704818) (xy 269.450321 -270.700508) (xy 269.435324 -270.695718)
			(xy 269.427452 -270.69542) (xy 268.911578 -270.69542) (xy 268.906262 -270.694987) (xy 268.89869 -270.687521)
			(xy 268.898116 -270.682212) (xy 206.997808 -270.682212) (xy 206.997808 -270.682466) (xy 206.99726 -270.687755)
			(xy 206.989876 -270.695325) (xy 206.9846 -270.695928) (xy 206.468726 -270.695928) (xy 206.460916 -270.696248)
			(xy 206.446045 -270.701029) (xy 206.439516 -270.705326) (xy 206.418385 -270.719661) (xy 206.372665 -270.742392)
			(xy 206.323995 -270.757826) (xy 206.27353 -270.765597) (xy 206.248 -270.766032) (xy 206.222469 -270.765601)
			(xy 206.172005 -270.757825) (xy 206.123333 -270.742394) (xy 206.077605 -270.719675) (xy 206.056484 -270.705326)
			(xy 206.049954 -270.701033) (xy 206.035083 -270.696251) (xy 206.027274 -270.695928) (xy 205.5114 -270.695928)
			(xy 205.506142 -270.695407) (xy 205.498701 -270.687977) (xy 205.498192 -270.68272) (xy 199.453982 -270.68272)
			(xy 199.45346 -270.687755) (xy 199.446076 -270.695325) (xy 199.4408 -270.695928) (xy 198.924926 -270.695928)
			(xy 198.917116 -270.696248) (xy 198.902245 -270.701029) (xy 198.895716 -270.705326) (xy 198.874585 -270.719661)
			(xy 198.828865 -270.742392) (xy 198.780195 -270.757826) (xy 198.72973 -270.765597) (xy 198.7042 -270.766032)
			(xy 198.678669 -270.765601) (xy 198.628205 -270.757825) (xy 198.579533 -270.742394) (xy 198.533805 -270.719675)
			(xy 198.512684 -270.705326) (xy 198.506154 -270.701033) (xy 198.491283 -270.696251) (xy 198.483474 -270.695928)
			(xy 197.9676 -270.695928) (xy 197.962342 -270.695407) (xy 197.954901 -270.687977) (xy 197.954392 -270.68272)
			(xy 191.910181 -270.68272) (xy 191.909631 -270.687815) (xy 191.902092 -270.6954) (xy 191.896746 -270.695928)
			(xy 191.380872 -270.695928) (xy 191.37306 -270.696225) (xy 191.358189 -270.701022) (xy 191.351662 -270.705326)
			(xy 191.330546 -270.719685) (xy 191.284821 -270.74241) (xy 191.236146 -270.757838) (xy 191.185678 -270.765601)
			(xy 191.160146 -270.766032) (xy 191.134616 -270.765578) (xy 191.084153 -270.757809) (xy 191.03548 -270.742385)
			(xy 190.989752 -270.719672) (xy 190.96863 -270.705326) (xy 190.962089 -270.70105) (xy 190.947226 -270.696257)
			(xy 190.93942 -270.695928) (xy 190.423546 -270.695928) (xy 190.418109 -270.695587) (xy 190.410418 -270.687903)
			(xy 190.410084 -270.682466) (xy 184.3659 -270.682466) (xy 184.365359 -270.687757) (xy 184.35797 -270.695328)
			(xy 184.352692 -270.695928) (xy 183.836818 -270.695928) (xy 183.829008 -270.696244) (xy 183.814136 -270.701028)
			(xy 183.807608 -270.705326) (xy 183.78648 -270.719665) (xy 183.740758 -270.742395) (xy 183.692087 -270.757828)
			(xy 183.641622 -270.765597) (xy 183.616092 -270.766032) (xy 183.590561 -270.765605) (xy 183.540097 -270.757827)
			(xy 183.491424 -270.742396) (xy 183.445697 -270.719675) (xy 183.424576 -270.705326) (xy 183.418047 -270.70103)
			(xy 183.403175 -270.696249) (xy 183.395366 -270.695928) (xy 182.879492 -270.695928) (xy 182.874233 -270.695413)
			(xy 182.866792 -270.687978) (xy 182.866284 -270.68272) (xy 176.822073 -270.68272) (xy 176.821531 -270.687817)
			(xy 176.813986 -270.695402) (xy 176.808638 -270.695928) (xy 176.292764 -270.695928) (xy 176.284956 -270.696264)
			(xy 176.270084 -270.701034) (xy 176.263554 -270.705326) (xy 176.242441 -270.719688) (xy 176.196714 -270.742413)
			(xy 176.148038 -270.757839) (xy 176.09757 -270.765602) (xy 176.072038 -270.766032) (xy 176.046508 -270.765582)
			(xy 175.996045 -270.757811) (xy 175.947372 -270.742386) (xy 175.901644 -270.719672) (xy 175.880522 -270.705326)
			(xy 175.873983 -270.701047) (xy 175.859119 -270.696256) (xy 175.851312 -270.695928) (xy 175.335438 -270.695928)
			(xy 175.33 -270.695592) (xy 175.32231 -270.687904) (xy 175.321976 -270.682466) (xy 169.277792 -270.682466)
			(xy 169.277258 -270.687759) (xy 169.269864 -270.69533) (xy 169.264584 -270.695928) (xy 167.791384 -270.695928)
			(xy 167.786124 -270.695418) (xy 167.778683 -270.68798) (xy 167.778176 -270.68272) (xy 60.17817 -270.68272)
			(xy 60.177801 -270.68789) (xy 60.170148 -270.695576) (xy 60.164726 -270.695928) (xy 58.691526 -270.695928)
			(xy 58.686086 -270.6956) (xy 58.678397 -270.687906) (xy 58.678064 -270.682466) (xy 52.63388 -270.682466)
			(xy 52.633357 -270.687762) (xy 52.625955 -270.695333) (xy 52.620672 -270.695928) (xy 52.104798 -270.695928)
			(xy 52.096987 -270.696236) (xy 52.082116 -270.701025) (xy 52.075588 -270.705326) (xy 52.054465 -270.719674)
			(xy 52.008742 -270.742401) (xy 51.960069 -270.757832) (xy 51.909603 -270.765599) (xy 51.884072 -270.766032)
			(xy 51.858541 -270.765615) (xy 51.808076 -270.757834) (xy 51.759403 -270.7424) (xy 51.713677 -270.719677)
			(xy 51.692556 -270.705326) (xy 51.686032 -270.701022) (xy 51.671156 -270.696247) (xy 51.663346 -270.695928)
			(xy 51.147472 -270.695928) (xy 51.142211 -270.695426) (xy 51.134771 -270.687982) (xy 51.134264 -270.68272)
			(xy 45.090062 -270.68272) (xy 45.0897 -270.687892) (xy 45.082043 -270.695579) (xy 45.076618 -270.695928)
			(xy 44.560744 -270.695928) (xy 44.552935 -270.696256) (xy 44.538064 -270.701032) (xy 44.531534 -270.705326)
			(xy 44.510426 -270.719697) (xy 44.464698 -270.742419) (xy 44.41602 -270.757844) (xy 44.36555 -270.765603)
			(xy 44.340018 -270.766032) (xy 44.314488 -270.765592) (xy 44.264024 -270.757818) (xy 44.215351 -270.74239)
			(xy 44.169624 -270.719674) (xy 44.148502 -270.705326) (xy 44.141968 -270.70104) (xy 44.1271 -270.696253)
			(xy 44.119292 -270.695928) (xy 43.603418 -270.695928) (xy 43.597977 -270.695605) (xy 43.590288 -270.687907)
			(xy 43.589956 -270.682466) (xy 37.545772 -270.682466) (xy 37.545256 -270.687763) (xy 37.537849 -270.695336)
			(xy 37.532564 -270.695928) (xy 37.01669 -270.695928) (xy 37.008879 -270.696233) (xy 36.994007 -270.701024)
			(xy 36.98748 -270.705326) (xy 36.966359 -270.719677) (xy 36.920636 -270.742404) (xy 36.871962 -270.757834)
			(xy 36.821495 -270.7656) (xy 36.795964 -270.766032) (xy 36.770433 -270.765619) (xy 36.719968 -270.757837)
			(xy 36.671295 -270.742401) (xy 36.625569 -270.719677) (xy 36.604448 -270.705326) (xy 36.597926 -270.701019)
			(xy 36.583049 -270.696245) (xy 36.575238 -270.695928) (xy 36.059364 -270.695928) (xy 36.054102 -270.695431)
			(xy 36.046663 -270.687983) (xy 36.046156 -270.68272) (xy 30.001947 -270.68272) (xy 30.001456 -270.687763)
			(xy 29.994049 -270.695336) (xy 29.988764 -270.695928) (xy 29.47289 -270.695928) (xy 29.465079 -270.696233)
			(xy 29.450207 -270.701024) (xy 29.44368 -270.705326) (xy 29.422559 -270.719677) (xy 29.376836 -270.742404)
			(xy 29.328162 -270.757834) (xy 29.277695 -270.7656) (xy 29.252164 -270.766032) (xy 29.226633 -270.765619)
			(xy 29.176168 -270.757837) (xy 29.127495 -270.742401) (xy 29.081769 -270.719677) (xy 29.060648 -270.705326)
			(xy 29.054126 -270.701019) (xy 29.039249 -270.696245) (xy 29.031438 -270.695928) (xy 28.515564 -270.695928)
			(xy 28.510302 -270.695431) (xy 28.502863 -270.687983) (xy 28.502356 -270.68272) (xy 22.458155 -270.68272)
			(xy 22.457799 -270.687894) (xy 22.450137 -270.695581) (xy 22.44471 -270.695928) (xy 21.928836 -270.695928)
			(xy 21.921027 -270.696253) (xy 21.906155 -270.701031) (xy 21.899626 -270.705326) (xy 21.878493 -270.719657)
			(xy 21.832773 -270.742389) (xy 21.784104 -270.757824) (xy 21.73364 -270.765596) (xy 21.70811 -270.766032)
			(xy 21.68258 -270.765596) (xy 21.632116 -270.757821) (xy 21.583443 -270.742392) (xy 21.537716 -270.719674)
			(xy 21.516594 -270.705326) (xy 21.510061 -270.701036) (xy 21.495192 -270.696252) (xy 21.487384 -270.695928)
			(xy 20.97151 -270.695928) (xy 20.966068 -270.695611) (xy 20.958379 -270.687908) (xy 20.958048 -270.682466)
			(xy 2.509012 -270.682466) (xy 2.509012 -272.382488) (xy 20.958048 -272.382488) (xy 20.958048 -271.88795)
			(xy 20.958518 -271.882578) (xy 20.966136 -271.874994) (xy 20.97151 -271.874488) (xy 21.487638 -271.874488)
			(xy 21.495446 -271.87415) (xy 21.510317 -271.869381) (xy 21.516848 -271.86509) (xy 21.537937 -271.850741)
			(xy 21.583598 -271.82801) (xy 21.632204 -271.812551) (xy 21.682607 -271.804728) (xy 21.733613 -271.804728)
			(xy 21.784016 -271.812551) (xy 21.832622 -271.82801) (xy 21.878283 -271.850741) (xy 21.899372 -271.86509)
			(xy 21.905911 -271.869368) (xy 21.920775 -271.87416) (xy 21.928582 -271.874488) (xy 22.44471 -271.874488)
			(xy 22.450063 -271.875039) (xy 22.457645 -271.882598) (xy 22.458172 -271.88795) (xy 22.458172 -272.382488)
			(xy 28.502356 -272.382488) (xy 28.502356 -271.88795) (xy 28.502858 -271.882648) (xy 28.510273 -271.875073)
			(xy 28.515564 -271.874488) (xy 29.031692 -271.874488) (xy 29.039502 -271.874173) (xy 29.054373 -271.869388)
			(xy 29.060902 -271.86509) (xy 29.081991 -271.850741) (xy 29.127652 -271.82801) (xy 29.176258 -271.812551)
			(xy 29.226661 -271.804728) (xy 29.277667 -271.804728) (xy 29.32807 -271.812551) (xy 29.376676 -271.82801)
			(xy 29.422337 -271.850741) (xy 29.443426 -271.86509) (xy 29.449953 -271.869389) (xy 29.464826 -271.874167)
			(xy 29.472636 -271.874488) (xy 29.988764 -271.874488) (xy 29.994091 -271.874851) (xy 30.001633 -271.882371)
			(xy 30.001972 -271.887696) (xy 30.001972 -271.888204) (xy 30.001972 -272.382488) (xy 36.046156 -272.382488)
			(xy 36.046156 -271.88795) (xy 36.046658 -271.882648) (xy 36.054073 -271.875073) (xy 36.059364 -271.874488)
			(xy 36.575492 -271.874488) (xy 36.583302 -271.874173) (xy 36.598173 -271.869388) (xy 36.604702 -271.86509)
			(xy 36.625791 -271.850741) (xy 36.671452 -271.82801) (xy 36.720058 -271.812551) (xy 36.770461 -271.804728)
			(xy 36.821467 -271.804728) (xy 36.87187 -271.812551) (xy 36.920476 -271.82801) (xy 36.966137 -271.850741)
			(xy 36.987226 -271.86509) (xy 36.993753 -271.869389) (xy 37.008626 -271.874167) (xy 37.016436 -271.874488)
			(xy 37.532564 -271.874488) (xy 37.537891 -271.874851) (xy 37.545433 -271.882371) (xy 37.545772 -271.887696)
			(xy 37.545772 -271.888204) (xy 37.545772 -272.382488) (xy 43.589956 -272.382488) (xy 43.589956 -271.88795)
			(xy 43.590419 -271.882576) (xy 43.598041 -271.874992) (xy 43.603418 -271.874488) (xy 44.119546 -271.874488)
			(xy 44.127354 -271.874154) (xy 44.142226 -271.869382) (xy 44.148756 -271.86509) (xy 44.169845 -271.850741)
			(xy 44.215506 -271.82801) (xy 44.264112 -271.812551) (xy 44.314515 -271.804728) (xy 44.365521 -271.804728)
			(xy 44.415924 -271.812551) (xy 44.46453 -271.82801) (xy 44.510191 -271.850741) (xy 44.53128 -271.86509)
			(xy 44.537817 -271.869371) (xy 44.552683 -271.874161) (xy 44.56049 -271.874488) (xy 45.076618 -271.874488)
			(xy 45.081972 -271.875033) (xy 45.089554 -271.882597) (xy 45.09008 -271.88795) (xy 45.09008 -272.382488)
			(xy 51.134264 -272.382488) (xy 51.134264 -271.88795) (xy 51.134759 -271.882646) (xy 51.142179 -271.875071)
			(xy 51.147472 -271.874488) (xy 51.6636 -271.874488) (xy 51.67141 -271.874176) (xy 51.686282 -271.869389)
			(xy 51.69281 -271.86509) (xy 51.713899 -271.850741) (xy 51.75956 -271.82801) (xy 51.808166 -271.812551)
			(xy 51.858569 -271.804728) (xy 51.909575 -271.804728) (xy 51.959978 -271.812551) (xy 52.008584 -271.82801)
			(xy 52.054245 -271.850741) (xy 52.075334 -271.86509) (xy 52.081859 -271.869392) (xy 52.096734 -271.874169)
			(xy 52.104544 -271.874488) (xy 52.620672 -271.874488) (xy 52.626 -271.874845) (xy 52.633542 -271.882369)
			(xy 52.63388 -271.887696) (xy 52.63388 -271.888204) (xy 52.63388 -272.382488) (xy 58.678064 -272.382488)
			(xy 58.678064 -271.88795) (xy 58.67852 -271.882574) (xy 58.686147 -271.87499) (xy 58.691526 -271.874488)
			(xy 60.164726 -271.874488) (xy 60.170081 -271.875028) (xy 60.177662 -271.882596) (xy 60.178188 -271.88795)
			(xy 60.178188 -272.382488) (xy 167.778176 -272.382488) (xy 167.778176 -271.88795) (xy 167.778661 -271.882643)
			(xy 167.786088 -271.875067) (xy 167.791384 -271.874488) (xy 169.264584 -271.874488) (xy 169.269913 -271.874837)
			(xy 169.277455 -271.882367) (xy 169.277792 -271.887696) (xy 169.277792 -272.382488) (xy 175.321976 -272.382488)
			(xy 175.321976 -271.88795) (xy 175.322421 -271.882571) (xy 175.330056 -271.874986) (xy 175.335438 -271.874488)
			(xy 175.851566 -271.874488) (xy 175.859375 -271.874162) (xy 175.874247 -271.869385) (xy 175.880776 -271.86509)
			(xy 175.901865 -271.850741) (xy 175.947526 -271.82801) (xy 175.996132 -271.812551) (xy 176.046535 -271.804728)
			(xy 176.097541 -271.804728) (xy 176.147944 -271.812551) (xy 176.19655 -271.82801) (xy 176.242211 -271.850741)
			(xy 176.2633 -271.86509) (xy 176.269833 -271.869379) (xy 176.284702 -271.874164) (xy 176.29251 -271.874488)
			(xy 176.808638 -271.874488) (xy 176.813994 -271.87502) (xy 176.821575 -271.882594) (xy 176.8221 -271.88795)
			(xy 176.8221 -272.382488) (xy 182.866284 -272.382488) (xy 182.866284 -271.88795) (xy 182.866762 -271.882642)
			(xy 182.874194 -271.875065) (xy 182.879492 -271.874488) (xy 183.39562 -271.874488) (xy 183.403431 -271.874185)
			(xy 183.418302 -271.869392) (xy 183.42483 -271.86509) (xy 183.445919 -271.850741) (xy 183.49158 -271.82801)
			(xy 183.540186 -271.812551) (xy 183.590589 -271.804728) (xy 183.641595 -271.804728) (xy 183.691998 -271.812551)
			(xy 183.740604 -271.82801) (xy 183.786265 -271.850741) (xy 183.807354 -271.86509) (xy 183.813875 -271.8694)
			(xy 183.828753 -271.874172) (xy 183.836564 -271.874488) (xy 184.352692 -271.874488) (xy 184.358022 -271.874832)
			(xy 184.365563 -271.882366) (xy 184.3659 -271.887696) (xy 184.3659 -271.888204) (xy 184.3659 -272.382488)
			(xy 190.410084 -272.382488) (xy 190.410084 -271.88795) (xy 190.410522 -271.882569) (xy 190.418162 -271.874984)
			(xy 190.423546 -271.874488) (xy 190.939674 -271.874488) (xy 190.947483 -271.874165) (xy 190.962355 -271.869386)
			(xy 190.968884 -271.86509) (xy 190.989973 -271.850741) (xy 191.035634 -271.82801) (xy 191.08424 -271.812551)
			(xy 191.134643 -271.804728) (xy 191.185649 -271.804728) (xy 191.236052 -271.812551) (xy 191.284658 -271.82801)
			(xy 191.330319 -271.850741) (xy 191.351408 -271.86509) (xy 191.357939 -271.869382) (xy 191.372809 -271.874165)
			(xy 191.380618 -271.874488) (xy 191.896746 -271.874488) (xy 191.902103 -271.875015) (xy 191.909684 -271.882593)
			(xy 191.910208 -271.88795) (xy 191.910208 -272.382488) (xy 197.954392 -272.382488) (xy 197.954392 -271.88795)
			(xy 197.954951 -271.882663) (xy 197.962327 -271.875092) (xy 197.9676 -271.874488) (xy 198.483728 -271.874488)
			(xy 198.491539 -271.874188) (xy 198.506411 -271.869393) (xy 198.512938 -271.86509) (xy 198.534027 -271.850741)
			(xy 198.579688 -271.82801) (xy 198.628294 -271.812551) (xy 198.678697 -271.804728) (xy 198.729703 -271.804728)
			(xy 198.780106 -271.812551) (xy 198.828712 -271.82801) (xy 198.874373 -271.850741) (xy 198.895462 -271.86509)
			(xy 198.902003 -271.869365) (xy 198.916866 -271.874158) (xy 198.924672 -271.874488) (xy 199.4408 -271.874488)
			(xy 199.446062 -271.874994) (xy 199.453504 -271.882434) (xy 199.454008 -271.887696) (xy 199.454008 -271.888204)
			(xy 199.454008 -272.382488) (xy 205.498192 -272.382488) (xy 205.498192 -271.88795) (xy 205.498751 -271.882663)
			(xy 205.506127 -271.875092) (xy 205.5114 -271.874488) (xy 206.027528 -271.874488) (xy 206.035339 -271.874188)
			(xy 206.050211 -271.869393) (xy 206.056738 -271.86509) (xy 206.077827 -271.850741) (xy 206.123488 -271.82801)
			(xy 206.172094 -271.812551) (xy 206.222497 -271.804728) (xy 206.273503 -271.804728) (xy 206.323906 -271.812551)
			(xy 206.372512 -271.82801) (xy 206.418173 -271.850741) (xy 206.439262 -271.86509) (xy 206.445803 -271.869365)
			(xy 206.460666 -271.874158) (xy 206.468472 -271.874488) (xy 206.9846 -271.874488) (xy 206.989862 -271.874994)
			(xy 206.997304 -271.882434) (xy 206.997808 -271.887696) (xy 206.997808 -271.888204) (xy 206.997808 -272.382234)
			(xy 268.898116 -272.382234) (xy 268.898116 -271.887696) (xy 268.898427 -271.882357) (xy 268.905985 -271.874815)
			(xy 268.911324 -271.874488) (xy 268.911832 -271.874488) (xy 269.427706 -271.874488) (xy 269.435517 -271.874179)
			(xy 269.450388 -271.86939) (xy 269.456916 -271.86509) (xy 269.478005 -271.850741) (xy 269.523666 -271.82801)
			(xy 269.572272 -271.812551) (xy 269.622675 -271.804728) (xy 269.673681 -271.804728) (xy 269.724084 -271.812551)
			(xy 269.77269 -271.82801) (xy 269.818351 -271.850741) (xy 269.83944 -271.86509) (xy 269.845964 -271.869394)
			(xy 269.86084 -271.87417) (xy 269.86865 -271.874488) (xy 270.384778 -271.874488) (xy 270.390091 -271.874944)
			(xy 270.397666 -271.882392) (xy 270.39824 -271.887696) (xy 270.39824 -272.382234) (xy 270.398218 -272.382488)
			(xy 276.442424 -272.382488) (xy 276.442424 -272.38198) (xy 276.442424 -271.887696) (xy 276.442727 -271.882355)
			(xy 276.450291 -271.874813) (xy 276.455632 -271.874488) (xy 276.97176 -271.874488) (xy 276.979569 -271.87416)
			(xy 276.99444 -271.869384) (xy 277.00097 -271.86509) (xy 277.022059 -271.850741) (xy 277.06772 -271.82801)
			(xy 277.116326 -271.812551) (xy 277.166729 -271.804728) (xy 277.217735 -271.804728) (xy 277.268138 -271.812551)
			(xy 277.316744 -271.82801) (xy 277.362405 -271.850741) (xy 277.383494 -271.86509) (xy 277.390028 -271.869377)
			(xy 277.404896 -271.874163) (xy 277.412704 -271.874488) (xy 277.928832 -271.874488) (xy 277.934098 -271.874973)
			(xy 277.941538 -271.882429) (xy 277.94204 -271.887696) (xy 277.94204 -272.382234) (xy 277.942019 -272.382488)
			(xy 283.986224 -272.382488) (xy 283.986224 -272.38198) (xy 283.986224 -271.887696) (xy 283.986527 -271.882355)
			(xy 283.994091 -271.874813) (xy 283.999432 -271.874488) (xy 284.51556 -271.874488) (xy 284.523369 -271.87416)
			(xy 284.53824 -271.869384) (xy 284.54477 -271.86509) (xy 284.565859 -271.850741) (xy 284.61152 -271.82801)
			(xy 284.660126 -271.812551) (xy 284.710529 -271.804728) (xy 284.761535 -271.804728) (xy 284.811938 -271.812551)
			(xy 284.860544 -271.82801) (xy 284.906205 -271.850741) (xy 284.927294 -271.86509) (xy 284.933828 -271.869377)
			(xy 284.948696 -271.874163) (xy 284.956504 -271.874488) (xy 285.472632 -271.874488) (xy 285.477898 -271.874973)
			(xy 285.485338 -271.882429) (xy 285.48584 -271.887696) (xy 285.48584 -272.382234) (xy 291.530024 -272.382234)
			(xy 291.530024 -271.887696) (xy 291.530327 -271.882355) (xy 291.537891 -271.874813) (xy 291.543232 -271.874488)
			(xy 291.54374 -271.874488) (xy 292.059614 -271.874488) (xy 292.067425 -271.874182) (xy 292.082296 -271.869391)
			(xy 292.088824 -271.86509) (xy 292.109913 -271.850741) (xy 292.155574 -271.82801) (xy 292.20418 -271.812551)
			(xy 292.254583 -271.804728) (xy 292.305589 -271.804728) (xy 292.355992 -271.812551) (xy 292.404598 -271.82801)
			(xy 292.450259 -271.850741) (xy 292.471348 -271.86509) (xy 292.47787 -271.869398) (xy 292.492747 -271.874171)
			(xy 292.500558 -271.874488) (xy 293.016686 -271.874488) (xy 293.022 -271.874938) (xy 293.029574 -271.882391)
			(xy 293.030148 -271.887696) (xy 293.030148 -272.382234) (xy 293.030125 -272.382488) (xy 299.074332 -272.382488)
			(xy 299.074332 -272.38198) (xy 299.074332 -271.887696) (xy 299.074628 -271.882353) (xy 299.082196 -271.87481)
			(xy 299.08754 -271.874488) (xy 299.603668 -271.874488) (xy 299.611477 -271.874163) (xy 299.626349 -271.869385)
			(xy 299.632878 -271.86509) (xy 299.653967 -271.850741) (xy 299.699628 -271.82801) (xy 299.748234 -271.812551)
			(xy 299.798637 -271.804728) (xy 299.849643 -271.804728) (xy 299.900046 -271.812551) (xy 299.948652 -271.82801)
			(xy 299.994313 -271.850741) (xy 300.015402 -271.86509) (xy 300.021934 -271.86938) (xy 300.036804 -271.874164)
			(xy 300.044612 -271.874488) (xy 300.56074 -271.874488) (xy 300.566007 -271.874968) (xy 300.573447 -271.882428)
			(xy 300.573948 -271.887696) (xy 300.573948 -272.382234) (xy 306.618132 -272.382234) (xy 306.618132 -271.887696)
			(xy 306.618428 -271.882353) (xy 306.625996 -271.87481) (xy 306.63134 -271.874488) (xy 306.631848 -271.874488)
			(xy 308.104794 -271.874488) (xy 308.110109 -271.874933) (xy 308.117683 -271.88239) (xy 308.118256 -271.887696)
			(xy 308.118256 -272.382234) (xy 308.118233 -272.382488) (xy 415.718244 -272.382488) (xy 415.718244 -271.887696)
			(xy 415.718787 -271.882444) (xy 415.726202 -271.875005) (xy 415.731452 -271.874488) (xy 417.204652 -271.874488)
			(xy 417.209977 -271.874859) (xy 417.21752 -271.882373) (xy 417.21786 -271.887696) (xy 417.21786 -272.382234)
			(xy 423.262044 -272.382234) (xy 423.262044 -271.887696) (xy 423.262587 -271.882444) (xy 423.270002 -271.875005)
			(xy 423.275252 -271.874488) (xy 423.27576 -271.874488) (xy 423.791634 -271.874488) (xy 423.799442 -271.874148)
			(xy 423.814313 -271.86938) (xy 423.820844 -271.86509) (xy 423.841933 -271.850741) (xy 423.887594 -271.82801)
			(xy 423.9362 -271.812551) (xy 423.986603 -271.804728) (xy 424.037609 -271.804728) (xy 424.088012 -271.812551)
			(xy 424.136618 -271.82801) (xy 424.182279 -271.850741) (xy 424.203368 -271.86509) (xy 424.209908 -271.869367)
			(xy 424.224771 -271.874159) (xy 424.232578 -271.874488) (xy 424.748706 -271.874488) (xy 424.754022 -271.874925)
			(xy 424.761596 -271.882388) (xy 424.762168 -271.887696) (xy 424.762168 -272.382234) (xy 424.762145 -272.382488)
			(xy 430.806352 -272.382488) (xy 430.806352 -272.38198) (xy 430.806352 -271.887696) (xy 430.806888 -271.882442)
			(xy 430.814308 -271.875002) (xy 430.81956 -271.874488) (xy 431.335688 -271.874488) (xy 431.343498 -271.874171)
			(xy 431.358369 -271.869388) (xy 431.364898 -271.86509) (xy 431.385987 -271.850741) (xy 431.431648 -271.82801)
			(xy 431.480254 -271.812551) (xy 431.530657 -271.804728) (xy 431.581663 -271.804728) (xy 431.632066 -271.812551)
			(xy 431.680672 -271.82801) (xy 431.726333 -271.850741) (xy 431.747422 -271.86509) (xy 431.75395 -271.869388)
			(xy 431.768823 -271.874167) (xy 431.776632 -271.874488) (xy 432.29276 -271.874488) (xy 432.298086 -271.874853)
			(xy 432.305629 -271.882371) (xy 432.305968 -271.887696) (xy 432.305968 -272.382234) (xy 438.350152 -272.382234)
			(xy 438.350152 -271.887696) (xy 438.350688 -271.882442) (xy 438.358108 -271.875002) (xy 438.36336 -271.874488)
			(xy 438.363868 -271.874488) (xy 438.879742 -271.874488) (xy 438.88755 -271.874151) (xy 438.902422 -271.869381)
			(xy 438.908952 -271.86509) (xy 438.930041 -271.850741) (xy 438.975702 -271.82801) (xy 439.024308 -271.812551)
			(xy 439.074711 -271.804728) (xy 439.125717 -271.804728) (xy 439.17612 -271.812551) (xy 439.224726 -271.82801)
			(xy 439.270387 -271.850741) (xy 439.291476 -271.86509) (xy 439.298014 -271.86937) (xy 439.312879 -271.87416)
			(xy 439.320686 -271.874488) (xy 439.836814 -271.874488) (xy 439.842131 -271.87492) (xy 439.849704 -271.882387)
			(xy 439.850276 -271.887696) (xy 439.850276 -272.382234) (xy 439.850252 -272.382488) (xy 445.89446 -272.382488)
			(xy 445.89446 -272.38198) (xy 445.89446 -271.887696) (xy 445.894989 -271.88244) (xy 445.902413 -271.875)
			(xy 445.907668 -271.874488) (xy 446.423796 -271.874488) (xy 446.431606 -271.874175) (xy 446.446478 -271.869389)
			(xy 446.453006 -271.86509) (xy 446.474095 -271.850741) (xy 446.519756 -271.82801) (xy 446.568362 -271.812551)
			(xy 446.618765 -271.804728) (xy 446.669771 -271.804728) (xy 446.720174 -271.812551) (xy 446.76878 -271.82801)
			(xy 446.814441 -271.850741) (xy 446.83553 -271.86509) (xy 446.842056 -271.869391) (xy 446.85693 -271.874168)
			(xy 446.86474 -271.874488) (xy 447.380868 -271.874488) (xy 447.386195 -271.874848) (xy 447.393737 -271.88237)
			(xy 447.394076 -271.887696) (xy 447.394076 -272.382234) (xy 447.394053 -272.382488) (xy 453.43826 -272.382488)
			(xy 453.43826 -272.38198) (xy 453.43826 -271.887696) (xy 453.438789 -271.88244) (xy 453.446213 -271.875)
			(xy 453.451468 -271.874488) (xy 453.967596 -271.874488) (xy 453.975406 -271.874175) (xy 453.990278 -271.869389)
			(xy 453.996806 -271.86509) (xy 454.017895 -271.850741) (xy 454.063556 -271.82801) (xy 454.112162 -271.812551)
			(xy 454.162565 -271.804728) (xy 454.213571 -271.804728) (xy 454.263974 -271.812551) (xy 454.31258 -271.82801)
			(xy 454.358241 -271.850741) (xy 454.37933 -271.86509) (xy 454.385856 -271.869391) (xy 454.40073 -271.874168)
			(xy 454.40854 -271.874488) (xy 454.924668 -271.874488) (xy 454.929995 -271.874848) (xy 454.937537 -271.88237)
			(xy 454.937876 -271.887696) (xy 454.937876 -272.382234) (xy 454.937401 -272.387539) (xy 454.929963 -272.395107)
			(xy 454.924668 -272.395696) (xy 454.408794 -272.395696) (xy 454.400984 -272.396008) (xy 454.386112 -272.400795)
			(xy 454.379584 -272.405094) (xy 454.35846 -272.41944) (xy 454.312737 -272.442169) (xy 454.264065 -272.4576)
			(xy 454.213599 -272.465367) (xy 454.188068 -272.4658) (xy 454.162537 -272.465373) (xy 454.112073 -272.457593)
			(xy 454.063401 -272.442161) (xy 454.017674 -272.419442) (xy 453.996552 -272.405094) (xy 453.990031 -272.400785)
			(xy 453.975153 -272.396013) (xy 453.967342 -272.395696) (xy 453.451468 -272.395696) (xy 453.446198 -272.395225)
			(xy 453.438757 -272.387759) (xy 453.43826 -272.382488) (xy 447.394053 -272.382488) (xy 447.393601 -272.387539)
			(xy 447.386163 -272.395107) (xy 447.380868 -272.395696) (xy 446.864994 -272.395696) (xy 446.857184 -272.396008)
			(xy 446.842312 -272.400795) (xy 446.835784 -272.405094) (xy 446.81466 -272.41944) (xy 446.768937 -272.442169)
			(xy 446.720265 -272.4576) (xy 446.669799 -272.465367) (xy 446.644268 -272.4658) (xy 446.618737 -272.465373)
			(xy 446.568273 -272.457593) (xy 446.519601 -272.442161) (xy 446.473874 -272.419442) (xy 446.452752 -272.405094)
			(xy 446.446231 -272.400785) (xy 446.431353 -272.396013) (xy 446.423542 -272.395696) (xy 445.907668 -272.395696)
			(xy 445.902398 -272.395225) (xy 445.894957 -272.387759) (xy 445.89446 -272.382488) (xy 439.850252 -272.382488)
			(xy 439.849774 -272.387599) (xy 439.842179 -272.395182) (xy 439.836814 -272.395696) (xy 439.32094 -272.395696)
			(xy 439.313132 -272.396027) (xy 439.29826 -272.400801) (xy 439.29173 -272.405094) (xy 439.270621 -272.419463)
			(xy 439.224893 -272.442187) (xy 439.176216 -272.457612) (xy 439.125746 -272.465371) (xy 439.100214 -272.4658)
			(xy 439.074684 -272.46535) (xy 439.024221 -272.457577) (xy 438.975549 -272.442152) (xy 438.929821 -272.419439)
			(xy 438.908698 -272.405094) (xy 438.902167 -272.400803) (xy 438.887296 -272.39602) (xy 438.879488 -272.395696)
			(xy 438.363614 -272.395696) (xy 438.35826 -272.395144) (xy 438.350675 -272.387586) (xy 438.350152 -272.382234)
			(xy 432.305968 -272.382234) (xy 432.3055 -272.38754) (xy 432.298057 -272.395109) (xy 432.29276 -272.395696)
			(xy 431.776886 -272.395696) (xy 431.769075 -272.396004) (xy 431.754204 -272.400794) (xy 431.747676 -272.405094)
			(xy 431.726554 -272.419443) (xy 431.680831 -272.442171) (xy 431.632158 -272.457602) (xy 431.581691 -272.465368)
			(xy 431.55616 -272.4658) (xy 431.530629 -272.465377) (xy 431.480165 -272.457596) (xy 431.431493 -272.442163)
			(xy 431.385766 -272.419443) (xy 431.364644 -272.405094) (xy 431.358125 -272.400782) (xy 431.343245 -272.396012)
			(xy 431.335434 -272.395696) (xy 430.81956 -272.395696) (xy 430.814289 -272.395231) (xy 430.806848 -272.38776)
			(xy 430.806352 -272.382488) (xy 424.762145 -272.382488) (xy 424.761673 -272.387601) (xy 424.754074 -272.395184)
			(xy 424.748706 -272.395696) (xy 424.232832 -272.395696) (xy 424.225023 -272.396024) (xy 424.210152 -272.4008)
			(xy 424.203622 -272.405094) (xy 424.182487 -272.419423) (xy 424.136769 -272.442156) (xy 424.088099 -272.457592)
			(xy 424.037636 -272.465364) (xy 424.012106 -272.4658) (xy 423.986576 -272.465354) (xy 423.936113 -272.45758)
			(xy 423.887441 -272.442153) (xy 423.841713 -272.41944) (xy 423.82059 -272.405094) (xy 423.81406 -272.4008)
			(xy 423.799189 -272.396019) (xy 423.79138 -272.395696) (xy 423.275506 -272.395696) (xy 423.270151 -272.395149)
			(xy 423.262567 -272.387588) (xy 423.262044 -272.382234) (xy 417.21786 -272.382234) (xy 417.217399 -272.387542)
			(xy 417.209951 -272.395111) (xy 417.204652 -272.395696) (xy 415.731452 -272.395696) (xy 415.726181 -272.395236)
			(xy 415.71874 -272.387762) (xy 415.718244 -272.382488) (xy 308.118233 -272.382488) (xy 308.117772 -272.387604)
			(xy 308.110165 -272.395188) (xy 308.104794 -272.395696) (xy 306.631594 -272.395696) (xy 306.626237 -272.395157)
			(xy 306.618654 -272.387589) (xy 306.618132 -272.382234) (xy 300.573948 -272.382234) (xy 300.573498 -272.387545)
			(xy 300.566043 -272.395115) (xy 300.56074 -272.395696) (xy 300.044866 -272.395696) (xy 300.037059 -272.396038)
			(xy 300.022187 -272.400805) (xy 300.015656 -272.405094) (xy 299.99454 -272.419452) (xy 299.948815 -272.442178)
			(xy 299.90014 -272.457606) (xy 299.849672 -272.465369) (xy 299.82414 -272.4658) (xy 299.798611 -272.465337)
			(xy 299.748148 -272.457568) (xy 299.699476 -272.442146) (xy 299.653747 -272.419438) (xy 299.632624 -272.405094)
			(xy 299.626087 -272.400813) (xy 299.611221 -272.396024) (xy 299.603414 -272.395696) (xy 299.08754 -272.395696)
			(xy 299.08221 -272.395345) (xy 299.074666 -272.387817) (xy 299.074332 -272.382488) (xy 293.030125 -272.382488)
			(xy 293.029671 -272.387605) (xy 293.022059 -272.39519) (xy 293.016686 -272.395696) (xy 292.500812 -272.395696)
			(xy 292.493002 -272.396015) (xy 292.478131 -272.400798) (xy 292.471602 -272.405094) (xy 292.450473 -272.419432)
			(xy 292.404752 -272.442163) (xy 292.356081 -272.457596) (xy 292.305616 -272.465366) (xy 292.280086 -272.4658)
			(xy 292.254556 -272.465364) (xy 292.204092 -272.457587) (xy 292.15542 -272.442157) (xy 292.109692 -272.419441)
			(xy 292.08857 -272.405094) (xy 292.082045 -272.400792) (xy 292.06717 -272.396016) (xy 292.05936 -272.395696)
			(xy 291.543486 -272.395696) (xy 291.538129 -272.395162) (xy 291.530546 -272.387591) (xy 291.530024 -272.382234)
			(xy 285.48584 -272.382234) (xy 285.485397 -272.387547) (xy 285.477937 -272.395117) (xy 285.472632 -272.395696)
			(xy 284.956758 -272.395696) (xy 284.94895 -272.396035) (xy 284.934079 -272.400804) (xy 284.927548 -272.405094)
			(xy 284.906434 -272.419455) (xy 284.860708 -272.442181) (xy 284.812032 -272.457608) (xy 284.761564 -272.46537)
			(xy 284.736032 -272.4658) (xy 284.710503 -272.465341) (xy 284.66004 -272.457571) (xy 284.611368 -272.442148)
			(xy 284.565639 -272.419438) (xy 284.544516 -272.405094) (xy 284.537981 -272.40081) (xy 284.523114 -272.396022)
			(xy 284.515306 -272.395696) (xy 283.999432 -272.395696) (xy 283.994101 -272.39535) (xy 283.986558 -272.387818)
			(xy 283.986224 -272.382488) (xy 277.942019 -272.382488) (xy 277.941597 -272.387547) (xy 277.934137 -272.395117)
			(xy 277.928832 -272.395696) (xy 277.412958 -272.395696) (xy 277.40515 -272.396035) (xy 277.390279 -272.400804)
			(xy 277.383748 -272.405094) (xy 277.362634 -272.419455) (xy 277.316908 -272.442181) (xy 277.268232 -272.457608)
			(xy 277.217764 -272.46537) (xy 277.192232 -272.4658) (xy 277.166703 -272.465341) (xy 277.11624 -272.457571)
			(xy 277.067568 -272.442148) (xy 277.021839 -272.419438) (xy 277.000716 -272.405094) (xy 276.994181 -272.40081)
			(xy 276.979314 -272.396022) (xy 276.971506 -272.395696) (xy 276.455632 -272.395696) (xy 276.450301 -272.39535)
			(xy 276.442758 -272.387818) (xy 276.442424 -272.382488) (xy 270.398218 -272.382488) (xy 270.39777 -272.387607)
			(xy 270.390153 -272.395192) (xy 270.384778 -272.395696) (xy 269.868904 -272.395696) (xy 269.861094 -272.396012)
			(xy 269.846223 -272.400797) (xy 269.839694 -272.405094) (xy 269.818567 -272.419435) (xy 269.772846 -272.442165)
			(xy 269.724174 -272.457598) (xy 269.673709 -272.465366) (xy 269.648178 -272.4658) (xy 269.622648 -272.465368)
			(xy 269.572184 -272.45759) (xy 269.523512 -272.442159) (xy 269.477784 -272.419442) (xy 269.456662 -272.405094)
			(xy 269.450139 -272.400789) (xy 269.435262 -272.396015) (xy 269.427452 -272.395696) (xy 268.911578 -272.395696)
			(xy 268.90622 -272.395168) (xy 268.898637 -272.387592) (xy 268.898116 -272.382234) (xy 206.997808 -272.382234)
			(xy 206.997808 -272.382488) (xy 206.997465 -272.387819) (xy 206.98993 -272.39536) (xy 206.9846 -272.395696)
			(xy 206.468726 -272.395696) (xy 206.460849 -272.395952) (xy 206.445844 -272.400757) (xy 206.439262 -272.405094)
			(xy 206.418189 -272.419492) (xy 206.372542 -272.442318) (xy 206.323935 -272.457873) (xy 206.273517 -272.465791)
			(xy 206.248 -272.466308) (xy 206.222479 -272.465834) (xy 206.172052 -272.457934) (xy 206.12344 -272.44237)
			(xy 206.077802 -272.419511) (xy 206.056738 -272.405094) (xy 206.05014 -272.40079) (xy 206.035145 -272.395997)
			(xy 206.027274 -272.395696) (xy 205.5114 -272.395696) (xy 205.506065 -272.395372) (xy 205.498523 -272.387824)
			(xy 205.498192 -272.382488) (xy 199.454008 -272.382488) (xy 199.453665 -272.387819) (xy 199.44613 -272.39536)
			(xy 199.4408 -272.395696) (xy 198.924926 -272.395696) (xy 198.917049 -272.395952) (xy 198.902044 -272.400757)
			(xy 198.895462 -272.405094) (xy 198.874389 -272.419492) (xy 198.828742 -272.442318) (xy 198.780135 -272.457873)
			(xy 198.729717 -272.465791) (xy 198.7042 -272.466308) (xy 198.678679 -272.465834) (xy 198.628252 -272.457934)
			(xy 198.57964 -272.44237) (xy 198.534002 -272.419511) (xy 198.512938 -272.405094) (xy 198.50634 -272.40079)
			(xy 198.491345 -272.395997) (xy 198.483474 -272.395696) (xy 197.9676 -272.395696) (xy 197.962265 -272.395372)
			(xy 197.954723 -272.387824) (xy 197.954392 -272.382488) (xy 191.910208 -272.382488) (xy 191.909865 -272.387819)
			(xy 191.90233 -272.39536) (xy 191.897 -272.395696) (xy 191.896492 -272.395696) (xy 191.380872 -272.395696)
			(xy 191.372996 -272.395971) (xy 191.357992 -272.400763) (xy 191.351408 -272.405094) (xy 191.33035 -272.419516)
			(xy 191.284698 -272.442336) (xy 191.236086 -272.457885) (xy 191.185664 -272.465795) (xy 191.160146 -272.466308)
			(xy 191.134626 -272.465811) (xy 191.0842 -272.457918) (xy 191.035588 -272.442361) (xy 190.989949 -272.419508)
			(xy 190.968884 -272.405094) (xy 190.962298 -272.400769) (xy 190.947294 -272.395989) (xy 190.93942 -272.395696)
			(xy 190.423546 -272.395696) (xy 190.418256 -272.39515) (xy 190.410684 -272.387765) (xy 190.410084 -272.382488)
			(xy 184.3659 -272.382488) (xy 184.365564 -272.387821) (xy 184.358024 -272.395363) (xy 184.352692 -272.395696)
			(xy 183.836818 -272.395696) (xy 183.828944 -272.395991) (xy 183.81394 -272.400769) (xy 183.807354 -272.405094)
			(xy 183.786283 -272.419496) (xy 183.740636 -272.442321) (xy 183.692028 -272.457875) (xy 183.641609 -272.465792)
			(xy 183.616092 -272.466308) (xy 183.590573 -272.465788) (xy 183.540147 -272.457902) (xy 183.491536 -272.442351)
			(xy 183.445896 -272.419505) (xy 183.42483 -272.405094) (xy 183.418234 -272.400787) (xy 183.403237 -272.395995)
			(xy 183.395366 -272.395696) (xy 182.879492 -272.395696) (xy 182.874156 -272.395378) (xy 182.866614 -272.387825)
			(xy 182.866284 -272.382488) (xy 176.8221 -272.382488) (xy 176.821764 -272.387821) (xy 176.814224 -272.395363)
			(xy 176.808892 -272.395696) (xy 176.808384 -272.395696) (xy 176.292764 -272.395696) (xy 176.284888 -272.395968)
			(xy 176.269884 -272.400762) (xy 176.2633 -272.405094) (xy 176.242217 -272.419476) (xy 176.196573 -272.442305)
			(xy 176.147969 -272.457865) (xy 176.097554 -272.465788) (xy 176.072038 -272.466308) (xy 176.046518 -272.465815)
			(xy 175.996091 -272.457921) (xy 175.94748 -272.442362) (xy 175.901841 -272.419509) (xy 175.880776 -272.405094)
			(xy 175.874192 -272.400766) (xy 175.859186 -272.395988) (xy 175.851312 -272.395696) (xy 175.335438 -272.395696)
			(xy 175.330147 -272.395156) (xy 175.322576 -272.387766) (xy 175.321976 -272.382488) (xy 169.277792 -272.382488)
			(xy 169.277463 -272.387822) (xy 169.269919 -272.395365) (xy 169.264584 -272.395696) (xy 167.791384 -272.395696)
			(xy 167.786116 -272.395215) (xy 167.778674 -272.387757) (xy 167.778176 -272.382488) (xy 60.178188 -272.382488)
			(xy 60.177863 -272.387823) (xy 60.170316 -272.395366) (xy 60.16498 -272.395696) (xy 60.164472 -272.395696)
			(xy 58.691526 -272.395696) (xy 58.686233 -272.395164) (xy 58.678663 -272.387768) (xy 58.678064 -272.382488)
			(xy 52.63388 -272.382488) (xy 52.633562 -272.387825) (xy 52.62601 -272.395369) (xy 52.620672 -272.395696)
			(xy 52.104798 -272.395696) (xy 52.096923 -272.395983) (xy 52.081919 -272.400766) (xy 52.075334 -272.405094)
			(xy 52.054269 -272.419504) (xy 52.008619 -272.442327) (xy 51.960009 -272.457879) (xy 51.90959 -272.465793)
			(xy 51.884072 -272.466308) (xy 51.858553 -272.465798) (xy 51.808127 -272.457909) (xy 51.759515 -272.442355)
			(xy 51.713876 -272.419506) (xy 51.69281 -272.405094) (xy 51.686218 -272.400779) (xy 51.671218 -272.395993)
			(xy 51.663346 -272.395696) (xy 51.147472 -272.395696) (xy 51.142203 -272.395223) (xy 51.134761 -272.387759)
			(xy 51.134264 -272.382488) (xy 45.09008 -272.382488) (xy 45.089762 -272.387825) (xy 45.08221 -272.395369)
			(xy 45.076872 -272.395696) (xy 45.076364 -272.395696) (xy 44.560744 -272.395696) (xy 44.552867 -272.39596)
			(xy 44.537863 -272.400759) (xy 44.53128 -272.405094) (xy 44.510202 -272.419485) (xy 44.464557 -272.442312)
			(xy 44.415951 -272.45787) (xy 44.365535 -272.46579) (xy 44.340018 -272.466308) (xy 44.314498 -272.465825)
			(xy 44.26407 -272.457928) (xy 44.215459 -272.442366) (xy 44.169821 -272.41951) (xy 44.148756 -272.405094)
			(xy 44.142176 -272.400759) (xy 44.127167 -272.395985) (xy 44.119292 -272.395696) (xy 43.603418 -272.395696)
			(xy 43.598124 -272.395169) (xy 43.590554 -272.387769) (xy 43.589956 -272.382488) (xy 37.545772 -272.382488)
			(xy 37.545461 -272.387827) (xy 37.537904 -272.395371) (xy 37.532564 -272.395696) (xy 37.01669 -272.395696)
			(xy 37.008815 -272.395979) (xy 36.993811 -272.400765) (xy 36.987226 -272.405094) (xy 36.966163 -272.419508)
			(xy 36.920513 -272.44233) (xy 36.871902 -272.457881) (xy 36.821482 -272.465794) (xy 36.795964 -272.466308)
			(xy 36.770445 -272.465802) (xy 36.720018 -272.457912) (xy 36.671407 -272.442357) (xy 36.625768 -272.419507)
			(xy 36.604702 -272.405094) (xy 36.598112 -272.400776) (xy 36.583111 -272.395991) (xy 36.575238 -272.395696)
			(xy 36.059364 -272.395696) (xy 36.054094 -272.395228) (xy 36.046653 -272.38776) (xy 36.046156 -272.382488)
			(xy 30.001972 -272.382488) (xy 30.001661 -272.387827) (xy 29.994104 -272.395371) (xy 29.988764 -272.395696)
			(xy 29.47289 -272.395696) (xy 29.465015 -272.395979) (xy 29.450011 -272.400765) (xy 29.443426 -272.405094)
			(xy 29.422363 -272.419508) (xy 29.376713 -272.44233) (xy 29.328102 -272.457881) (xy 29.277682 -272.465794)
			(xy 29.252164 -272.466308) (xy 29.226645 -272.465802) (xy 29.176218 -272.457912) (xy 29.127607 -272.442357)
			(xy 29.081968 -272.419507) (xy 29.060902 -272.405094) (xy 29.054312 -272.400776) (xy 29.039311 -272.395991)
			(xy 29.031438 -272.395696) (xy 28.515564 -272.395696) (xy 28.510294 -272.395228) (xy 28.502853 -272.38776)
			(xy 28.502356 -272.382488) (xy 22.458172 -272.382488) (xy 22.457861 -272.387827) (xy 22.450304 -272.395371)
			(xy 22.444964 -272.395696) (xy 22.444456 -272.395696) (xy 21.928836 -272.395696) (xy 21.920959 -272.395956)
			(xy 21.905955 -272.400758) (xy 21.899372 -272.405094) (xy 21.878296 -272.419488) (xy 21.83265 -272.442315)
			(xy 21.784044 -272.457871) (xy 21.733627 -272.46579) (xy 21.70811 -272.466308) (xy 21.682589 -272.465829)
			(xy 21.632162 -272.457931) (xy 21.583551 -272.442368) (xy 21.537913 -272.41951) (xy 21.516848 -272.405094)
			(xy 21.51027 -272.400755) (xy 21.49526 -272.395983) (xy 21.487384 -272.395696) (xy 20.97151 -272.395696)
			(xy 20.966215 -272.395175) (xy 20.958646 -272.387771) (xy 20.958048 -272.382488) (xy 2.509012 -272.382488)
			(xy 2.509012 -273.232372) (xy 16.85798 -273.232372) (xy 16.85798 -272.737834) (xy 16.858306 -272.732394)
			(xy 16.866001 -272.724703) (xy 16.871442 -272.724372) (xy 17.38757 -272.724372) (xy 17.395379 -272.724051)
			(xy 17.410251 -272.719271) (xy 17.41678 -272.714974) (xy 17.437869 -272.700625) (xy 17.48353 -272.677894)
			(xy 17.532136 -272.662435) (xy 17.582539 -272.654612) (xy 17.633545 -272.654612) (xy 17.683948 -272.662435)
			(xy 17.732554 -272.677894) (xy 17.778215 -272.700625) (xy 17.799304 -272.714974) (xy 17.805837 -272.719263)
			(xy 17.820706 -272.724048) (xy 17.828514 -272.724372) (xy 18.344642 -272.724372) (xy 18.350019 -272.724826)
			(xy 18.357605 -272.732454) (xy 18.358104 -272.737834) (xy 18.358104 -273.232372) (xy 24.402288 -273.232372)
			(xy 24.402288 -272.737834) (xy 24.402752 -272.732523) (xy 24.410194 -272.724947) (xy 24.415496 -272.724372)
			(xy 24.931624 -272.724372) (xy 24.939436 -272.724073) (xy 24.954307 -272.719278) (xy 24.960834 -272.714974)
			(xy 24.981923 -272.700625) (xy 25.027584 -272.677894) (xy 25.07619 -272.662435) (xy 25.126593 -272.654612)
			(xy 25.177599 -272.654612) (xy 25.228002 -272.662435) (xy 25.276608 -272.677894) (xy 25.322269 -272.700625)
			(xy 25.343358 -272.714974) (xy 25.349879 -272.719283) (xy 25.364757 -272.724055) (xy 25.372568 -272.724372)
			(xy 25.888696 -272.724372) (xy 25.893953 -272.724895) (xy 25.901395 -272.732323) (xy 25.901904 -272.73758)
			(xy 25.901904 -272.738088) (xy 25.901904 -273.232372) (xy 31.946088 -273.232372) (xy 31.946088 -272.737834)
			(xy 31.946552 -272.732523) (xy 31.953994 -272.724947) (xy 31.959296 -272.724372) (xy 32.475424 -272.724372)
			(xy 32.483236 -272.724073) (xy 32.498107 -272.719278) (xy 32.504634 -272.714974) (xy 32.525723 -272.700625)
			(xy 32.571384 -272.677894) (xy 32.61999 -272.662435) (xy 32.670393 -272.654612) (xy 32.721399 -272.654612)
			(xy 32.771802 -272.662435) (xy 32.820408 -272.677894) (xy 32.866069 -272.700625) (xy 32.887158 -272.714974)
			(xy 32.893679 -272.719283) (xy 32.908557 -272.724055) (xy 32.916368 -272.724372) (xy 33.432496 -272.724372)
			(xy 33.437753 -272.724895) (xy 33.445195 -272.732323) (xy 33.445704 -272.73758) (xy 33.445704 -272.738088)
			(xy 33.445704 -273.232372) (xy 39.489888 -273.232372) (xy 39.489888 -272.737834) (xy 39.490468 -272.732486)
			(xy 39.498006 -272.724902) (xy 39.50335 -272.724372) (xy 40.019478 -272.724372) (xy 40.027288 -272.724054)
			(xy 40.042159 -272.719272) (xy 40.048688 -272.714974) (xy 40.069777 -272.700625) (xy 40.115438 -272.677894)
			(xy 40.164044 -272.662435) (xy 40.214447 -272.654612) (xy 40.265453 -272.654612) (xy 40.315856 -272.662435)
			(xy 40.364462 -272.677894) (xy 40.410123 -272.700625) (xy 40.431212 -272.714974) (xy 40.437743 -272.719266)
			(xy 40.452613 -272.724049) (xy 40.460422 -272.724372) (xy 40.97655 -272.724372) (xy 40.981928 -272.724821)
			(xy 40.989513 -272.732453) (xy 40.990012 -272.737834) (xy 40.990012 -273.232372) (xy 47.034196 -273.232372)
			(xy 47.034196 -272.737834) (xy 47.034741 -272.732544) (xy 47.042127 -272.724973) (xy 47.047404 -272.724372)
			(xy 47.563532 -272.724372) (xy 47.57134 -272.724034) (xy 47.586212 -272.719265) (xy 47.592742 -272.714974)
			(xy 47.613831 -272.700625) (xy 47.659492 -272.677894) (xy 47.708098 -272.662435) (xy 47.758501 -272.654612)
			(xy 47.809507 -272.654612) (xy 47.85991 -272.662435) (xy 47.908516 -272.677894) (xy 47.954177 -272.700625)
			(xy 47.975266 -272.714974) (xy 47.981807 -272.719248) (xy 47.99667 -272.724042) (xy 48.004476 -272.724372)
			(xy 48.520604 -272.724372) (xy 48.525862 -272.72489) (xy 48.533304 -272.732322) (xy 48.533812 -272.73758)
			(xy 48.533812 -272.738088) (xy 48.533812 -273.232372) (xy 54.577996 -273.232372) (xy 54.577996 -272.737834)
			(xy 54.578569 -272.732484) (xy 54.586111 -272.724899) (xy 54.591458 -272.724372) (xy 56.064658 -272.724372)
			(xy 56.070095 -272.724711) (xy 56.077786 -272.732397) (xy 56.07812 -272.737834) (xy 56.07812 -273.232372)
			(xy 163.678108 -273.232372) (xy 163.678108 -272.737834) (xy 163.678642 -272.732541) (xy 163.686036 -272.72497)
			(xy 163.691316 -272.724372) (xy 165.164516 -272.724372) (xy 165.169776 -272.724882) (xy 165.177217 -272.73232)
			(xy 165.177724 -272.73758) (xy 165.177724 -272.738088) (xy 165.177724 -273.232372) (xy 171.221908 -273.232372)
			(xy 171.221908 -272.737834) (xy 171.222299 -272.732411) (xy 171.229949 -272.724725) (xy 171.23537 -272.724372)
			(xy 171.751498 -272.724372) (xy 171.759309 -272.724062) (xy 171.77418 -272.719274) (xy 171.780708 -272.714974)
			(xy 171.801797 -272.700625) (xy 171.847458 -272.677894) (xy 171.896064 -272.662435) (xy 171.946467 -272.654612)
			(xy 171.997473 -272.654612) (xy 172.047876 -272.662435) (xy 172.096482 -272.677894) (xy 172.142143 -272.700625)
			(xy 172.163232 -272.714974) (xy 172.169759 -272.719274) (xy 172.184632 -272.724052) (xy 172.192442 -272.724372)
			(xy 172.70857 -272.724372) (xy 172.714009 -272.724703) (xy 172.721699 -272.732395) (xy 172.722032 -272.737834)
			(xy 172.722032 -273.232372) (xy 178.766216 -273.232372) (xy 178.766216 -272.737834) (xy 178.766743 -272.732539)
			(xy 178.774142 -272.724968) (xy 178.779424 -272.724372) (xy 179.295552 -272.724372) (xy 179.303361 -272.724042)
			(xy 179.318232 -272.719268) (xy 179.324762 -272.714974) (xy 179.345851 -272.700625) (xy 179.391512 -272.677894)
			(xy 179.440118 -272.662435) (xy 179.490521 -272.654612) (xy 179.541527 -272.654612) (xy 179.59193 -272.662435)
			(xy 179.640536 -272.677894) (xy 179.686197 -272.700625) (xy 179.707286 -272.714974) (xy 179.713823 -272.719256)
			(xy 179.728689 -272.724045) (xy 179.736496 -272.724372) (xy 180.252624 -272.724372) (xy 180.257885 -272.724877)
			(xy 180.265325 -272.732319) (xy 180.265832 -272.73758) (xy 180.265832 -272.738088) (xy 180.265832 -273.232372)
			(xy 186.310016 -273.232372) (xy 186.310016 -272.737834) (xy 186.3104 -272.732409) (xy 186.318055 -272.724722)
			(xy 186.323478 -272.724372) (xy 186.839606 -272.724372) (xy 186.847417 -272.724066) (xy 186.862288 -272.719275)
			(xy 186.868816 -272.714974) (xy 186.889905 -272.700625) (xy 186.935566 -272.677894) (xy 186.984172 -272.662435)
			(xy 187.034575 -272.654612) (xy 187.085581 -272.654612) (xy 187.135984 -272.662435) (xy 187.18459 -272.677894)
			(xy 187.230251 -272.700625) (xy 187.25134 -272.714974) (xy 187.257865 -272.719277) (xy 187.27274 -272.724053)
			(xy 187.28055 -272.724372) (xy 187.796678 -272.724372) (xy 187.802118 -272.724698) (xy 187.809807 -272.732394)
			(xy 187.81014 -272.737834) (xy 187.81014 -273.232372) (xy 193.854324 -273.232372) (xy 193.854324 -272.737834)
			(xy 193.854844 -272.732538) (xy 193.862248 -272.724965) (xy 193.867532 -272.724372) (xy 194.38366 -272.724372)
			(xy 194.391469 -272.724046) (xy 194.406341 -272.719269) (xy 194.41287 -272.714974) (xy 194.433959 -272.700625)
			(xy 194.47962 -272.677894) (xy 194.528226 -272.662435) (xy 194.578629 -272.654612) (xy 194.629635 -272.654612)
			(xy 194.680038 -272.662435) (xy 194.728644 -272.677894) (xy 194.774305 -272.700625) (xy 194.795394 -272.714974)
			(xy 194.801929 -272.719259) (xy 194.816796 -272.724046) (xy 194.824604 -272.724372) (xy 195.340732 -272.724372)
			(xy 195.345994 -272.724871) (xy 195.353433 -272.732318) (xy 195.35394 -272.73758) (xy 195.35394 -272.738088)
			(xy 195.35394 -273.232372) (xy 201.398124 -273.232372) (xy 201.398124 -272.737834) (xy 201.398644 -272.732538)
			(xy 201.406048 -272.724965) (xy 201.411332 -272.724372) (xy 201.92746 -272.724372) (xy 201.935269 -272.724046)
			(xy 201.950141 -272.719269) (xy 201.95667 -272.714974) (xy 201.977759 -272.700625) (xy 202.02342 -272.677894)
			(xy 202.072026 -272.662435) (xy 202.122429 -272.654612) (xy 202.173435 -272.654612) (xy 202.223838 -272.662435)
			(xy 202.272444 -272.677894) (xy 202.318105 -272.700625) (xy 202.339194 -272.714974) (xy 202.345729 -272.719259)
			(xy 202.360596 -272.724046) (xy 202.368404 -272.724372) (xy 202.884532 -272.724372) (xy 202.889794 -272.724871)
			(xy 202.897233 -272.732318) (xy 202.89774 -272.73758) (xy 202.89774 -272.738088) (xy 202.89774 -273.232118)
			(xy 264.798048 -273.232118) (xy 264.798048 -272.73758) (xy 264.798577 -272.732325) (xy 264.806002 -272.724887)
			(xy 264.811256 -272.724372) (xy 264.811764 -272.724372) (xy 265.327638 -272.724372) (xy 265.335446 -272.724036)
			(xy 265.350318 -272.719266) (xy 265.356848 -272.714974) (xy 265.377937 -272.700625) (xy 265.423598 -272.677894)
			(xy 265.472204 -272.662435) (xy 265.522607 -272.654612) (xy 265.573613 -272.654612) (xy 265.624016 -272.662435)
			(xy 265.672622 -272.677894) (xy 265.718283 -272.700625) (xy 265.739372 -272.714974) (xy 265.745912 -272.719251)
			(xy 265.760775 -272.724043) (xy 265.768582 -272.724372) (xy 266.28471 -272.724372) (xy 266.290023 -272.72482)
			(xy 266.297595 -272.732275) (xy 266.298172 -272.73758) (xy 266.298172 -273.232118) (xy 266.298148 -273.232372)
			(xy 272.342356 -273.232372) (xy 272.342356 -273.231864) (xy 272.342356 -272.73758) (xy 272.342878 -272.732324)
			(xy 272.350308 -272.724884) (xy 272.355564 -272.724372) (xy 272.871692 -272.724372) (xy 272.879502 -272.72406)
			(xy 272.894374 -272.719273) (xy 272.900902 -272.714974) (xy 272.921991 -272.700625) (xy 272.967652 -272.677894)
			(xy 273.016258 -272.662435) (xy 273.066661 -272.654612) (xy 273.117667 -272.654612) (xy 273.16807 -272.662435)
			(xy 273.216676 -272.677894) (xy 273.262337 -272.700625) (xy 273.283426 -272.714974) (xy 273.289954 -272.719271)
			(xy 273.304827 -272.724051) (xy 273.312636 -272.724372) (xy 273.828764 -272.724372) (xy 273.834087 -272.724749)
			(xy 273.841629 -272.732259) (xy 273.841972 -272.73758) (xy 273.841972 -273.232118) (xy 273.841949 -273.232372)
			(xy 279.886156 -273.232372) (xy 279.886156 -273.231864) (xy 279.886156 -272.73758) (xy 279.886678 -272.732324)
			(xy 279.894108 -272.724884) (xy 279.899364 -272.724372) (xy 280.415492 -272.724372) (xy 280.423302 -272.72406)
			(xy 280.438174 -272.719273) (xy 280.444702 -272.714974) (xy 280.465791 -272.700625) (xy 280.511452 -272.677894)
			(xy 280.560058 -272.662435) (xy 280.610461 -272.654612) (xy 280.661467 -272.654612) (xy 280.71187 -272.662435)
			(xy 280.760476 -272.677894) (xy 280.806137 -272.700625) (xy 280.827226 -272.714974) (xy 280.833754 -272.719271)
			(xy 280.848627 -272.724051) (xy 280.856436 -272.724372) (xy 281.372564 -272.724372) (xy 281.377887 -272.724749)
			(xy 281.385429 -272.732259) (xy 281.385772 -272.73758) (xy 281.385772 -273.232118) (xy 287.429956 -273.232118)
			(xy 287.429956 -272.73758) (xy 287.430478 -272.732324) (xy 287.437908 -272.724884) (xy 287.443164 -272.724372)
			(xy 287.443672 -272.724372) (xy 287.959546 -272.724372) (xy 287.967354 -272.72404) (xy 287.982226 -272.719267)
			(xy 287.988756 -272.714974) (xy 288.009845 -272.700625) (xy 288.055506 -272.677894) (xy 288.104112 -272.662435)
			(xy 288.154515 -272.654612) (xy 288.205521 -272.654612) (xy 288.255924 -272.662435) (xy 288.30453 -272.677894)
			(xy 288.350191 -272.700625) (xy 288.37128 -272.714974) (xy 288.377818 -272.719254) (xy 288.392683 -272.724044)
			(xy 288.40049 -272.724372) (xy 288.916618 -272.724372) (xy 288.921932 -272.724815) (xy 288.929504 -272.732274)
			(xy 288.93008 -272.73758) (xy 288.93008 -273.232118) (xy 288.930056 -273.232372) (xy 294.974264 -273.232372)
			(xy 294.974264 -273.231864) (xy 294.974264 -272.73758) (xy 294.974779 -272.732322) (xy 294.982214 -272.724882)
			(xy 294.987472 -272.724372) (xy 295.5036 -272.724372) (xy 295.511411 -272.724063) (xy 295.526282 -272.719274)
			(xy 295.53281 -272.714974) (xy 295.553899 -272.700625) (xy 295.59956 -272.677894) (xy 295.648166 -272.662435)
			(xy 295.698569 -272.654612) (xy 295.749575 -272.654612) (xy 295.799978 -272.662435) (xy 295.848584 -272.677894)
			(xy 295.894245 -272.700625) (xy 295.915334 -272.714974) (xy 295.92186 -272.719274) (xy 295.936734 -272.724052)
			(xy 295.944544 -272.724372) (xy 296.460672 -272.724372) (xy 296.465996 -272.724743) (xy 296.473537 -272.732258)
			(xy 296.47388 -272.73758) (xy 296.47388 -273.232118) (xy 302.518064 -273.232118) (xy 302.518064 -272.73758)
			(xy 302.518579 -272.732322) (xy 302.526014 -272.724882) (xy 302.531272 -272.724372) (xy 304.004726 -272.724372)
			(xy 304.010041 -272.72481) (xy 304.017612 -272.732273) (xy 304.018188 -272.73758) (xy 304.018188 -273.232118)
			(xy 304.018163 -273.232372) (xy 411.618176 -273.232372) (xy 411.618176 -273.231864) (xy 411.618176 -272.73758)
			(xy 411.61868 -272.732319) (xy 411.626123 -272.724878) (xy 411.631384 -272.724372) (xy 413.104584 -272.724372)
			(xy 413.10984 -272.724903) (xy 413.117282 -272.732325) (xy 413.117792 -272.73758) (xy 413.117792 -273.232118)
			(xy 419.161976 -273.232118) (xy 419.161976 -272.73758) (xy 419.16248 -272.732319) (xy 419.169923 -272.724878)
			(xy 419.175184 -272.724372) (xy 419.175692 -272.724372) (xy 419.691566 -272.724372) (xy 419.699375 -272.724048)
			(xy 419.714247 -272.71927) (xy 419.720776 -272.714974) (xy 419.741865 -272.700625) (xy 419.787526 -272.677894)
			(xy 419.836132 -272.662435) (xy 419.886535 -272.654612) (xy 419.937541 -272.654612) (xy 419.987944 -272.662435)
			(xy 420.03655 -272.677894) (xy 420.082211 -272.700625) (xy 420.1033 -272.714974) (xy 420.109834 -272.719261)
			(xy 420.124702 -272.724047) (xy 420.13251 -272.724372) (xy 420.648638 -272.724372) (xy 420.653954 -272.724802)
			(xy 420.661525 -272.732271) (xy 420.6621 -272.73758) (xy 420.6621 -273.232118) (xy 420.662075 -273.232372)
			(xy 426.706284 -273.232372) (xy 426.706284 -273.231864) (xy 426.706284 -272.73758) (xy 426.706781 -272.732317)
			(xy 426.714228 -272.724876) (xy 426.719492 -272.724372) (xy 427.23562 -272.724372) (xy 427.243431 -272.724072)
			(xy 427.258303 -272.719277) (xy 427.26483 -272.714974) (xy 427.285919 -272.700625) (xy 427.33158 -272.677894)
			(xy 427.380186 -272.662435) (xy 427.430589 -272.654612) (xy 427.481595 -272.654612) (xy 427.531998 -272.662435)
			(xy 427.580604 -272.677894) (xy 427.626265 -272.700625) (xy 427.647354 -272.714974) (xy 427.653876 -272.719282)
			(xy 427.668753 -272.724055) (xy 427.676564 -272.724372) (xy 428.192692 -272.724372) (xy 428.197949 -272.724898)
			(xy 428.205391 -272.732324) (xy 428.2059 -272.73758) (xy 428.2059 -273.232118) (xy 434.250084 -273.232118)
			(xy 434.250084 -272.73758) (xy 434.250581 -272.732317) (xy 434.258028 -272.724876) (xy 434.263292 -272.724372)
			(xy 434.2638 -272.724372) (xy 434.779674 -272.724372) (xy 434.787484 -272.724052) (xy 434.802355 -272.719271)
			(xy 434.808884 -272.714974) (xy 434.829973 -272.700625) (xy 434.875634 -272.677894) (xy 434.92424 -272.662435)
			(xy 434.974643 -272.654612) (xy 435.025649 -272.654612) (xy 435.076052 -272.662435) (xy 435.124658 -272.677894)
			(xy 435.170319 -272.700625) (xy 435.191408 -272.714974) (xy 435.19794 -272.719264) (xy 435.21281 -272.724048)
			(xy 435.220618 -272.724372) (xy 435.736746 -272.724372) (xy 435.742051 -272.724863) (xy 435.749627 -272.732286)
			(xy 435.750208 -272.73758) (xy 435.750208 -273.232118) (xy 435.750182 -273.232372) (xy 441.794392 -273.232372)
			(xy 441.794392 -273.231864) (xy 441.794392 -272.73758) (xy 441.794881 -272.732315) (xy 441.802334 -272.724873)
			(xy 441.8076 -272.724372) (xy 442.323728 -272.724372) (xy 442.33154 -272.724075) (xy 442.346411 -272.719278)
			(xy 442.352938 -272.714974) (xy 442.374027 -272.700625) (xy 442.419688 -272.677894) (xy 442.468294 -272.662435)
			(xy 442.518697 -272.654612) (xy 442.569703 -272.654612) (xy 442.620106 -272.662435) (xy 442.668712 -272.677894)
			(xy 442.714373 -272.700625) (xy 442.735462 -272.714974) (xy 442.742004 -272.719247) (xy 442.756866 -272.724041)
			(xy 442.764672 -272.724372) (xy 443.2808 -272.724372) (xy 443.286058 -272.724893) (xy 443.293499 -272.732323)
			(xy 443.294008 -272.73758) (xy 443.294008 -273.232118) (xy 443.293983 -273.232372) (xy 449.338192 -273.232372)
			(xy 449.338192 -273.231864) (xy 449.338192 -272.73758) (xy 449.338681 -272.732315) (xy 449.346134 -272.724873)
			(xy 449.3514 -272.724372) (xy 449.867528 -272.724372) (xy 449.87534 -272.724075) (xy 449.890211 -272.719278)
			(xy 449.896738 -272.714974) (xy 449.917827 -272.700625) (xy 449.963488 -272.677894) (xy 450.012094 -272.662435)
			(xy 450.062497 -272.654612) (xy 450.113503 -272.654612) (xy 450.163906 -272.662435) (xy 450.212512 -272.677894)
			(xy 450.258173 -272.700625) (xy 450.279262 -272.714974) (xy 450.285804 -272.719247) (xy 450.300666 -272.724041)
			(xy 450.308472 -272.724372) (xy 450.8246 -272.724372) (xy 450.829858 -272.724893) (xy 450.837299 -272.732323)
			(xy 450.837808 -272.73758) (xy 450.837808 -273.232118) (xy 450.837295 -273.237413) (xy 450.829884 -273.244981)
			(xy 450.8246 -273.24558) (xy 450.308726 -273.24558) (xy 450.300915 -273.245891) (xy 450.286044 -273.250678)
			(xy 450.279516 -273.254978) (xy 450.25839 -273.26932) (xy 450.212667 -273.292047) (xy 450.163995 -273.307479)
			(xy 450.11353 -273.315249) (xy 450.088 -273.315684) (xy 450.06247 -273.315244) (xy 450.012006 -273.307469)
			(xy 449.963334 -273.29204) (xy 449.917606 -273.269325) (xy 449.896484 -273.254978) (xy 449.889951 -273.250689)
			(xy 449.875082 -273.245903) (xy 449.867274 -273.24558) (xy 449.3514 -273.24558) (xy 449.346061 -273.245271)
			(xy 449.338518 -273.237712) (xy 449.338192 -273.232372) (xy 443.293983 -273.232372) (xy 443.293495 -273.237413)
			(xy 443.286084 -273.244981) (xy 443.2808 -273.24558) (xy 442.764926 -273.24558) (xy 442.757115 -273.245891)
			(xy 442.742244 -273.250678) (xy 442.735716 -273.254978) (xy 442.71459 -273.26932) (xy 442.668867 -273.292047)
			(xy 442.620195 -273.307479) (xy 442.56973 -273.315249) (xy 442.5442 -273.315684) (xy 442.51867 -273.315244)
			(xy 442.468206 -273.307469) (xy 442.419534 -273.29204) (xy 442.373806 -273.269325) (xy 442.352684 -273.254978)
			(xy 442.346151 -273.250689) (xy 442.331282 -273.245903) (xy 442.323474 -273.24558) (xy 441.8076 -273.24558)
			(xy 441.802261 -273.245271) (xy 441.794718 -273.237712) (xy 441.794392 -273.232372) (xy 435.750182 -273.232372)
			(xy 435.749666 -273.237473) (xy 435.7421 -273.245055) (xy 435.736746 -273.24558) (xy 435.220872 -273.24558)
			(xy 435.213059 -273.245869) (xy 435.198188 -273.25067) (xy 435.191662 -273.254978) (xy 435.170551 -273.269343)
			(xy 435.124823 -273.292065) (xy 435.076146 -273.307491) (xy 435.025678 -273.315253) (xy 435.000146 -273.315684)
			(xy 434.974617 -273.315221) (xy 434.924154 -273.307452) (xy 434.875482 -273.292031) (xy 434.829753 -273.269322)
			(xy 434.80863 -273.254978) (xy 434.802087 -273.250707) (xy 434.787226 -273.24591) (xy 434.77942 -273.24558)
			(xy 434.263546 -273.24558) (xy 434.258122 -273.245192) (xy 434.250434 -273.237541) (xy 434.250084 -273.232118)
			(xy 428.2059 -273.232118) (xy 428.205394 -273.237415) (xy 428.197978 -273.244983) (xy 428.192692 -273.24558)
			(xy 427.676818 -273.24558) (xy 427.669007 -273.245888) (xy 427.654135 -273.250676) (xy 427.647608 -273.254978)
			(xy 427.626484 -273.269323) (xy 427.580761 -273.29205) (xy 427.532088 -273.307481) (xy 427.481623 -273.31525)
			(xy 427.456092 -273.315684) (xy 427.430562 -273.315248) (xy 427.380098 -273.307471) (xy 427.331426 -273.292042)
			(xy 427.285698 -273.269325) (xy 427.264576 -273.254978) (xy 427.258045 -273.250686) (xy 427.243175 -273.245902)
			(xy 427.235366 -273.24558) (xy 426.719492 -273.24558) (xy 426.714152 -273.245276) (xy 426.70661 -273.237713)
			(xy 426.706284 -273.232372) (xy 420.662075 -273.232372) (xy 420.661566 -273.237475) (xy 420.653994 -273.245058)
			(xy 420.648638 -273.24558) (xy 420.132764 -273.24558) (xy 420.124955 -273.245907) (xy 420.110083 -273.250682)
			(xy 420.103554 -273.254978) (xy 420.082445 -273.269346) (xy 420.036716 -273.292068) (xy 419.988039 -273.307493)
			(xy 419.93757 -273.315254) (xy 419.912038 -273.315684) (xy 419.886509 -273.315225) (xy 419.836046 -273.307455)
			(xy 419.787373 -273.292033) (xy 419.741645 -273.269322) (xy 419.720522 -273.254978) (xy 419.71398 -273.250704)
			(xy 419.699118 -273.245909) (xy 419.691312 -273.24558) (xy 419.175438 -273.24558) (xy 419.170012 -273.245197)
			(xy 419.162325 -273.237542) (xy 419.161976 -273.232118) (xy 413.117792 -273.232118) (xy 413.117293 -273.237417)
			(xy 413.109872 -273.244985) (xy 413.104584 -273.24558) (xy 411.631384 -273.24558) (xy 411.626043 -273.245281)
			(xy 411.618501 -273.237714) (xy 411.618176 -273.232372) (xy 304.018163 -273.232372) (xy 304.017664 -273.237478)
			(xy 304.010086 -273.245061) (xy 304.004726 -273.24558) (xy 302.531526 -273.24558) (xy 302.526099 -273.245205)
			(xy 302.518413 -273.237544) (xy 302.518064 -273.232118) (xy 296.47388 -273.232118) (xy 296.473391 -273.23742)
			(xy 296.465964 -273.244989) (xy 296.460672 -273.24558) (xy 295.944798 -273.24558) (xy 295.936986 -273.245879)
			(xy 295.922115 -273.250674) (xy 295.915588 -273.254978) (xy 295.894469 -273.269332) (xy 295.848744 -273.292057)
			(xy 295.80007 -273.307485) (xy 295.749603 -273.315251) (xy 295.724072 -273.315684) (xy 295.698541 -273.315258)
			(xy 295.648077 -273.307478) (xy 295.599405 -273.292046) (xy 295.553678 -273.269327) (xy 295.532556 -273.254978)
			(xy 295.526029 -273.250679) (xy 295.511156 -273.245899) (xy 295.503346 -273.24558) (xy 294.987472 -273.24558)
			(xy 294.982199 -273.245121) (xy 294.974756 -273.237647) (xy 294.974264 -273.232372) (xy 288.930056 -273.232372)
			(xy 288.929564 -273.23748) (xy 288.92198 -273.245064) (xy 288.916618 -273.24558) (xy 288.400744 -273.24558)
			(xy 288.392934 -273.245899) (xy 288.378062 -273.25068) (xy 288.371534 -273.254978) (xy 288.35043 -273.269355)
			(xy 288.3047 -273.292075) (xy 288.256021 -273.307497) (xy 288.20555 -273.315255) (xy 288.180018 -273.315684)
			(xy 288.154488 -273.315235) (xy 288.104025 -273.307462) (xy 288.055353 -273.292037) (xy 288.009625 -273.269324)
			(xy 287.988502 -273.254978) (xy 287.981965 -273.250696) (xy 287.967099 -273.245906) (xy 287.959292 -273.24558)
			(xy 287.443418 -273.24558) (xy 287.43806 -273.24504) (xy 287.430475 -273.237474) (xy 287.429956 -273.232118)
			(xy 281.385772 -273.232118) (xy 281.38529 -273.237422) (xy 281.377858 -273.244991) (xy 281.372564 -273.24558)
			(xy 280.85669 -273.24558) (xy 280.848878 -273.245876) (xy 280.834006 -273.250673) (xy 280.82748 -273.254978)
			(xy 280.806364 -273.269335) (xy 280.760638 -273.292059) (xy 280.711963 -273.307487) (xy 280.661495 -273.315252)
			(xy 280.635964 -273.315684) (xy 280.610433 -273.315262) (xy 280.559969 -273.307481) (xy 280.511297 -273.292048)
			(xy 280.46557 -273.269327) (xy 280.444448 -273.254978) (xy 280.437923 -273.250675) (xy 280.423048 -273.245898)
			(xy 280.415238 -273.24558) (xy 279.899364 -273.24558) (xy 279.89409 -273.245126) (xy 279.886648 -273.237648)
			(xy 279.886156 -273.232372) (xy 273.841949 -273.232372) (xy 273.84149 -273.237422) (xy 273.834058 -273.244991)
			(xy 273.828764 -273.24558) (xy 273.31289 -273.24558) (xy 273.305078 -273.245876) (xy 273.290206 -273.250673)
			(xy 273.28368 -273.254978) (xy 273.262564 -273.269335) (xy 273.216838 -273.292059) (xy 273.168163 -273.307487)
			(xy 273.117695 -273.315252) (xy 273.092164 -273.315684) (xy 273.066633 -273.315262) (xy 273.016169 -273.307481)
			(xy 272.967497 -273.292048) (xy 272.92177 -273.269327) (xy 272.900648 -273.254978) (xy 272.894123 -273.250675)
			(xy 272.879248 -273.245898) (xy 272.871438 -273.24558) (xy 272.355564 -273.24558) (xy 272.35029 -273.245126)
			(xy 272.342848 -273.237648) (xy 272.342356 -273.232372) (xy 266.298148 -273.232372) (xy 266.297663 -273.237482)
			(xy 266.290074 -273.245066) (xy 266.28471 -273.24558) (xy 265.768836 -273.24558) (xy 265.761026 -273.245896)
			(xy 265.746154 -273.250679) (xy 265.739626 -273.254978) (xy 265.718497 -273.269315) (xy 265.672775 -273.292044)
			(xy 265.624105 -273.307477) (xy 265.57364 -273.315248) (xy 265.54811 -273.315684) (xy 265.52258 -273.315239)
			(xy 265.472117 -273.307465) (xy 265.423444 -273.292038) (xy 265.377716 -273.269324) (xy 265.356594 -273.254978)
			(xy 265.350059 -273.250693) (xy 265.335192 -273.245905) (xy 265.327384 -273.24558) (xy 264.81151 -273.24558)
			(xy 264.806152 -273.245045) (xy 264.798567 -273.237475) (xy 264.798048 -273.232118) (xy 202.89774 -273.232118)
			(xy 202.89774 -273.232372) (xy 202.89719 -273.237624) (xy 202.889781 -273.245066) (xy 202.884532 -273.24558)
			(xy 202.368658 -273.24558) (xy 202.360782 -273.245852) (xy 202.345778 -273.250646) (xy 202.339194 -273.254978)
			(xy 202.318111 -273.269361) (xy 202.272468 -273.29219) (xy 202.223864 -273.30775) (xy 202.173448 -273.315673)
			(xy 202.147932 -273.316192) (xy 202.122412 -273.315705) (xy 202.071985 -273.30781) (xy 202.023373 -273.292249)
			(xy 201.977735 -273.269394) (xy 201.95667 -273.254978) (xy 201.950082 -273.250656) (xy 201.93508 -273.245872)
			(xy 201.927206 -273.24558) (xy 201.411332 -273.24558) (xy 201.405997 -273.245249) (xy 201.398453 -273.237707)
			(xy 201.398124 -273.232372) (xy 195.35394 -273.232372) (xy 195.35339 -273.237624) (xy 195.345981 -273.245066)
			(xy 195.340732 -273.24558) (xy 194.824858 -273.24558) (xy 194.816982 -273.245852) (xy 194.801978 -273.250646)
			(xy 194.795394 -273.254978) (xy 194.774311 -273.269361) (xy 194.728668 -273.29219) (xy 194.680064 -273.30775)
			(xy 194.629648 -273.315673) (xy 194.604132 -273.316192) (xy 194.578612 -273.315705) (xy 194.528185 -273.30781)
			(xy 194.479573 -273.292249) (xy 194.433935 -273.269394) (xy 194.41287 -273.254978) (xy 194.406282 -273.250656)
			(xy 194.39128 -273.245872) (xy 194.383406 -273.24558) (xy 193.867532 -273.24558) (xy 193.862197 -273.245249)
			(xy 193.854653 -273.237707) (xy 193.854324 -273.232372) (xy 187.81014 -273.232372) (xy 187.80959 -273.237624)
			(xy 187.802181 -273.245066) (xy 187.796932 -273.24558) (xy 187.796424 -273.24558) (xy 187.280804 -273.24558)
			(xy 187.27293 -273.245872) (xy 187.257925 -273.250652) (xy 187.25134 -273.254978) (xy 187.230272 -273.269384)
			(xy 187.184623 -273.292208) (xy 187.136015 -273.307762) (xy 187.085595 -273.315677) (xy 187.060078 -273.316192)
			(xy 187.034559 -273.315682) (xy 186.984132 -273.307794) (xy 186.935521 -273.29224) (xy 186.889882 -273.269391)
			(xy 186.868816 -273.254978) (xy 186.862218 -273.250674) (xy 186.847223 -273.245879) (xy 186.839352 -273.24558)
			(xy 186.323478 -273.24558) (xy 186.318176 -273.245094) (xy 186.310607 -273.237664) (xy 186.310016 -273.232372)
			(xy 180.265832 -273.232372) (xy 180.265457 -273.237695) (xy 180.257945 -273.245236) (xy 180.252624 -273.24558)
			(xy 179.73675 -273.24558) (xy 179.728874 -273.245849) (xy 179.71387 -273.250645) (xy 179.707286 -273.254978)
			(xy 179.686205 -273.269364) (xy 179.640561 -273.292193) (xy 179.591956 -273.307752) (xy 179.54154 -273.315673)
			(xy 179.516024 -273.316192) (xy 179.490504 -273.315709) (xy 179.440076 -273.307813) (xy 179.391465 -273.292251)
			(xy 179.345827 -273.269394) (xy 179.324762 -273.254978) (xy 179.318176 -273.250653) (xy 179.303172 -273.245871)
			(xy 179.295298 -273.24558) (xy 178.779424 -273.24558) (xy 178.774088 -273.245254) (xy 178.766544 -273.237708)
			(xy 178.766216 -273.232372) (xy 172.722032 -273.232372) (xy 172.721657 -273.237695) (xy 172.714145 -273.245236)
			(xy 172.708824 -273.24558) (xy 172.708316 -273.24558) (xy 172.192696 -273.24558) (xy 172.184821 -273.245868)
			(xy 172.169817 -273.250651) (xy 172.163232 -273.254978) (xy 172.142166 -273.269387) (xy 172.096517 -273.292211)
			(xy 172.047907 -273.307764) (xy 171.997488 -273.315677) (xy 171.97197 -273.316192) (xy 171.94645 -273.315686)
			(xy 171.896024 -273.307796) (xy 171.847412 -273.292241) (xy 171.801773 -273.269391) (xy 171.780708 -273.254978)
			(xy 171.774112 -273.250671) (xy 171.759116 -273.245878) (xy 171.751244 -273.24558) (xy 171.23537 -273.24558)
			(xy 171.230067 -273.245099) (xy 171.222498 -273.237665) (xy 171.221908 -273.232372) (xy 165.177724 -273.232372)
			(xy 165.177356 -273.237697) (xy 165.16984 -273.245238) (xy 165.164516 -273.24558) (xy 163.691316 -273.24558)
			(xy 163.685979 -273.24526) (xy 163.678435 -273.237709) (xy 163.678108 -273.232372) (xy 56.07812 -273.232372)
			(xy 56.077756 -273.237698) (xy 56.070237 -273.24524) (xy 56.064912 -273.24558) (xy 54.591458 -273.24558)
			(xy 54.586153 -273.245107) (xy 54.578586 -273.237667) (xy 54.577996 -273.232372) (xy 48.533812 -273.232372)
			(xy 48.533455 -273.2377) (xy 48.525931 -273.245242) (xy 48.520604 -273.24558) (xy 48.00473 -273.24558)
			(xy 47.996853 -273.24584) (xy 47.981849 -273.250642) (xy 47.975266 -273.254978) (xy 47.954191 -273.269373)
			(xy 47.908545 -273.2922) (xy 47.859938 -273.307756) (xy 47.809521 -273.315675) (xy 47.784004 -273.316192)
			(xy 47.758483 -273.315719) (xy 47.708055 -273.30782) (xy 47.659444 -273.292255) (xy 47.613806 -273.269395)
			(xy 47.592742 -273.254978) (xy 47.586161 -273.250645) (xy 47.571153 -273.245868) (xy 47.563278 -273.24558)
			(xy 47.047404 -273.24558) (xy 47.042066 -273.245268) (xy 47.034523 -273.237711) (xy 47.034196 -273.232372)
			(xy 40.990012 -273.232372) (xy 40.989655 -273.2377) (xy 40.982131 -273.245242) (xy 40.976804 -273.24558)
			(xy 40.976296 -273.24558) (xy 40.460676 -273.24558) (xy 40.452801 -273.24586) (xy 40.437797 -273.250648)
			(xy 40.431212 -273.254978) (xy 40.410152 -273.269396) (xy 40.3645 -273.292218) (xy 40.315889 -273.307768)
			(xy 40.265468 -273.315679) (xy 40.23995 -273.316192) (xy 40.21443 -273.315696) (xy 40.164003 -273.307803)
			(xy 40.115392 -273.292245) (xy 40.069753 -273.269392) (xy 40.048688 -273.254978) (xy 40.042096 -273.250663)
			(xy 40.027097 -273.245875) (xy 40.019224 -273.24558) (xy 39.50335 -273.24558) (xy 39.498056 -273.245046)
			(xy 39.490484 -273.237653) (xy 39.489888 -273.232372) (xy 33.445704 -273.232372) (xy 33.445354 -273.237702)
			(xy 33.437825 -273.245244) (xy 33.432496 -273.24558) (xy 32.916622 -273.24558) (xy 32.908748 -273.24588)
			(xy 32.893744 -273.250654) (xy 32.887158 -273.254978) (xy 32.866085 -273.269376) (xy 32.820438 -273.292202)
			(xy 32.771831 -273.307758) (xy 32.721413 -273.315675) (xy 32.695896 -273.316192) (xy 32.670375 -273.315723)
			(xy 32.619947 -273.307822) (xy 32.571336 -273.292256) (xy 32.525698 -273.269396) (xy 32.504634 -273.254978)
			(xy 32.498032 -273.250681) (xy 32.48304 -273.245881) (xy 32.47517 -273.24558) (xy 31.959296 -273.24558)
			(xy 31.953956 -273.245273) (xy 31.946414 -273.237712) (xy 31.946088 -273.232372) (xy 25.901904 -273.232372)
			(xy 25.901554 -273.237702) (xy 25.894025 -273.245244) (xy 25.888696 -273.24558) (xy 25.372822 -273.24558)
			(xy 25.364948 -273.24588) (xy 25.349944 -273.250654) (xy 25.343358 -273.254978) (xy 25.322285 -273.269376)
			(xy 25.276638 -273.292202) (xy 25.228031 -273.307758) (xy 25.177613 -273.315675) (xy 25.152096 -273.316192)
			(xy 25.126575 -273.315723) (xy 25.076147 -273.307822) (xy 25.027536 -273.292256) (xy 24.981898 -273.269396)
			(xy 24.960834 -273.254978) (xy 24.954232 -273.250681) (xy 24.93924 -273.245881) (xy 24.93137 -273.24558)
			(xy 24.415496 -273.24558) (xy 24.410156 -273.245273) (xy 24.402614 -273.237712) (xy 24.402288 -273.232372)
			(xy 18.358104 -273.232372) (xy 18.357754 -273.237702) (xy 18.350225 -273.245244) (xy 18.344896 -273.24558)
			(xy 18.344388 -273.24558) (xy 17.828768 -273.24558) (xy 17.820892 -273.245857) (xy 17.805888 -273.250647)
			(xy 17.799304 -273.254978) (xy 17.778218 -273.269356) (xy 17.732576 -273.292187) (xy 17.683973 -273.307748)
			(xy 17.633558 -273.315672) (xy 17.608042 -273.316192) (xy 17.582522 -273.3157) (xy 17.532095 -273.307806)
			(xy 17.483483 -273.292247) (xy 17.437845 -273.269393) (xy 17.41678 -273.254978) (xy 17.41019 -273.25066)
			(xy 17.395189 -273.245873) (xy 17.387316 -273.24558) (xy 16.871442 -273.24558) (xy 16.866147 -273.245051)
			(xy 16.858575 -273.237654) (xy 16.85798 -273.232372) (xy 2.509012 -273.232372) (xy 2.509012 -274.08251)
			(xy 20.958048 -274.08251) (xy 20.958048 -273.587972) (xy 20.958571 -273.582716) (xy 20.966001 -273.575278)
			(xy 20.971256 -273.574764) (xy 20.971764 -273.574764) (xy 21.487638 -273.574764) (xy 21.495446 -273.57443)
			(xy 21.510318 -273.569658) (xy 21.516848 -273.565366) (xy 21.537937 -273.551017) (xy 21.583598 -273.528286)
			(xy 21.632204 -273.512827) (xy 21.682607 -273.505004) (xy 21.733613 -273.505004) (xy 21.784016 -273.512827)
			(xy 21.832622 -273.528286) (xy 21.878283 -273.551017) (xy 21.899372 -273.565366) (xy 21.905913 -273.569642)
			(xy 21.920776 -273.574435) (xy 21.928582 -273.574764) (xy 22.44471 -273.574764) (xy 22.450021 -273.575219)
			(xy 22.457593 -273.58267) (xy 22.458172 -273.587972) (xy 22.458172 -274.08251) (xy 22.458148 -274.082764)
			(xy 28.502356 -274.082764) (xy 28.502356 -274.082256) (xy 28.502356 -273.587972) (xy 28.502872 -273.582715)
			(xy 28.510307 -273.575275) (xy 28.515564 -273.574764) (xy 29.031692 -273.574764) (xy 29.039502 -273.574453)
			(xy 29.054374 -273.569666) (xy 29.060902 -273.565366) (xy 29.081991 -273.551017) (xy 29.127652 -273.528286)
			(xy 29.176258 -273.512827) (xy 29.226661 -273.505004) (xy 29.277667 -273.505004) (xy 29.32807 -273.512827)
			(xy 29.376676 -273.528286) (xy 29.422337 -273.551017) (xy 29.443426 -273.565366) (xy 29.449955 -273.569663)
			(xy 29.464827 -273.574443) (xy 29.472636 -273.574764) (xy 29.988764 -273.574764) (xy 29.994085 -273.575148)
			(xy 30.001626 -273.582653) (xy 30.001972 -273.587972) (xy 30.001972 -274.08251) (xy 30.001949 -274.082764)
			(xy 36.046156 -274.082764) (xy 36.046156 -274.082256) (xy 36.046156 -273.587972) (xy 36.046672 -273.582715)
			(xy 36.054107 -273.575275) (xy 36.059364 -273.574764) (xy 36.575492 -273.574764) (xy 36.583302 -273.574453)
			(xy 36.598174 -273.569666) (xy 36.604702 -273.565366) (xy 36.625791 -273.551017) (xy 36.671452 -273.528286)
			(xy 36.720058 -273.512827) (xy 36.770461 -273.505004) (xy 36.821467 -273.505004) (xy 36.87187 -273.512827)
			(xy 36.920476 -273.528286) (xy 36.966137 -273.551017) (xy 36.987226 -273.565366) (xy 36.993755 -273.569663)
			(xy 37.008627 -273.574443) (xy 37.016436 -273.574764) (xy 37.532564 -273.574764) (xy 37.537885 -273.575148)
			(xy 37.545426 -273.582653) (xy 37.545772 -273.587972) (xy 37.545772 -274.08251) (xy 43.589956 -274.08251)
			(xy 43.589956 -273.587972) (xy 43.590472 -273.582715) (xy 43.597907 -273.575275) (xy 43.603164 -273.574764)
			(xy 43.603672 -273.574764) (xy 44.119546 -273.574764) (xy 44.127355 -273.574433) (xy 44.142226 -273.56966)
			(xy 44.148756 -273.565366) (xy 44.169845 -273.551017) (xy 44.215506 -273.528286) (xy 44.264112 -273.512827)
			(xy 44.314515 -273.505004) (xy 44.365521 -273.505004) (xy 44.415924 -273.512827) (xy 44.46453 -273.528286)
			(xy 44.510191 -273.551017) (xy 44.53128 -273.565366) (xy 44.537819 -273.569645) (xy 44.552683 -273.574436)
			(xy 44.56049 -273.574764) (xy 45.076618 -273.574764) (xy 45.08193 -273.575214) (xy 45.089502 -273.582668)
			(xy 45.09008 -273.587972) (xy 45.09008 -274.08251) (xy 45.090055 -274.082764) (xy 51.134264 -274.082764)
			(xy 51.134264 -274.082256) (xy 51.134264 -273.587972) (xy 51.134773 -273.582713) (xy 51.142213 -273.575273)
			(xy 51.147472 -273.574764) (xy 51.6636 -273.574764) (xy 51.671411 -273.574457) (xy 51.686282 -273.569667)
			(xy 51.69281 -273.565366) (xy 51.713899 -273.551017) (xy 51.75956 -273.528286) (xy 51.808166 -273.512827)
			(xy 51.858569 -273.505004) (xy 51.909575 -273.505004) (xy 51.959978 -273.512827) (xy 52.008584 -273.528286)
			(xy 52.054245 -273.551017) (xy 52.075334 -273.565366) (xy 52.081861 -273.569666) (xy 52.096734 -273.574444)
			(xy 52.104544 -273.574764) (xy 52.620672 -273.574764) (xy 52.625925 -273.57531) (xy 52.633367 -273.582722)
			(xy 52.63388 -273.587972) (xy 52.63388 -274.08251) (xy 58.678064 -274.08251) (xy 58.678064 -273.587972)
			(xy 58.678573 -273.582713) (xy 58.686013 -273.575273) (xy 58.691272 -273.574764) (xy 58.69178 -273.574764)
			(xy 60.164726 -273.574764) (xy 60.170039 -273.575209) (xy 60.17761 -273.582667) (xy 60.178188 -273.587972)
			(xy 60.178188 -274.08251) (xy 60.178163 -274.082764) (xy 167.778176 -274.082764) (xy 167.778176 -273.587972)
			(xy 167.778674 -273.58271) (xy 167.786121 -273.57527) (xy 167.791384 -273.574764) (xy 169.264584 -273.574764)
			(xy 169.269838 -273.575302) (xy 169.27728 -273.58272) (xy 169.277792 -273.587972) (xy 169.277792 -274.08251)
			(xy 175.321976 -274.08251) (xy 175.321976 -273.587972) (xy 175.322474 -273.58271) (xy 175.329921 -273.57527)
			(xy 175.335184 -273.574764) (xy 175.335692 -273.574764) (xy 175.851566 -273.574764) (xy 175.859375 -273.574442)
			(xy 175.874247 -273.569662) (xy 175.880776 -273.565366) (xy 175.901865 -273.551017) (xy 175.947526 -273.528286)
			(xy 175.996132 -273.512827) (xy 176.046535 -273.505004) (xy 176.097541 -273.505004) (xy 176.147944 -273.512827)
			(xy 176.19655 -273.528286) (xy 176.242211 -273.551017) (xy 176.2633 -273.565366) (xy 176.269834 -273.569653)
			(xy 176.284702 -273.574439) (xy 176.29251 -273.574764) (xy 176.808638 -273.574764) (xy 176.813952 -273.575201)
			(xy 176.821523 -273.582665) (xy 176.8221 -273.587972) (xy 176.8221 -274.08251) (xy 176.822074 -274.082764)
			(xy 182.866284 -274.082764) (xy 182.866284 -274.082256) (xy 182.866284 -273.587972) (xy 182.866775 -273.582708)
			(xy 182.874227 -273.575267) (xy 182.879492 -273.574764) (xy 183.39562 -273.574764) (xy 183.403432 -273.574465)
			(xy 183.418303 -273.56967) (xy 183.42483 -273.565366) (xy 183.445919 -273.551017) (xy 183.49158 -273.528286)
			(xy 183.540186 -273.512827) (xy 183.590589 -273.505004) (xy 183.641595 -273.505004) (xy 183.691998 -273.512827)
			(xy 183.740604 -273.528286) (xy 183.786265 -273.551017) (xy 183.807354 -273.565366) (xy 183.813876 -273.569673)
			(xy 183.828753 -273.574447) (xy 183.836564 -273.574764) (xy 184.352692 -273.574764) (xy 184.357947 -273.575297)
			(xy 184.365389 -273.582718) (xy 184.3659 -273.587972) (xy 184.3659 -274.08251) (xy 190.410084 -274.08251)
			(xy 190.410084 -273.587972) (xy 190.410575 -273.582708) (xy 190.418027 -273.575267) (xy 190.423292 -273.574764)
			(xy 190.4238 -273.574764) (xy 190.939674 -273.574764) (xy 190.947484 -273.574445) (xy 190.962355 -273.569663)
			(xy 190.968884 -273.565366) (xy 190.989973 -273.551017) (xy 191.035634 -273.528286) (xy 191.08424 -273.512827)
			(xy 191.134643 -273.505004) (xy 191.185649 -273.505004) (xy 191.236052 -273.512827) (xy 191.284658 -273.528286)
			(xy 191.330319 -273.551017) (xy 191.351408 -273.565366) (xy 191.357941 -273.569656) (xy 191.37281 -273.57444)
			(xy 191.380618 -273.574764) (xy 191.896746 -273.574764) (xy 191.902049 -273.575262) (xy 191.909625 -273.58268)
			(xy 191.910208 -273.587972) (xy 191.910208 -274.08251) (xy 191.910182 -274.082764) (xy 197.954392 -274.082764)
			(xy 197.954392 -274.082256) (xy 197.954392 -273.587972) (xy 197.954876 -273.582706) (xy 197.962333 -273.575265)
			(xy 197.9676 -273.574764) (xy 198.483728 -273.574764) (xy 198.49154 -273.574468) (xy 198.506411 -273.569671)
			(xy 198.512938 -273.565366) (xy 198.534027 -273.551017) (xy 198.579688 -273.528286) (xy 198.628294 -273.512827)
			(xy 198.678697 -273.505004) (xy 198.729703 -273.505004) (xy 198.780106 -273.512827) (xy 198.828712 -273.528286)
			(xy 198.874373 -273.551017) (xy 198.895462 -273.565366) (xy 198.902005 -273.569638) (xy 198.916866 -273.574433)
			(xy 198.924672 -273.574764) (xy 199.4408 -273.574764) (xy 199.446056 -273.575292) (xy 199.453497 -273.582717)
			(xy 199.454008 -273.587972) (xy 199.454008 -274.08251) (xy 199.453983 -274.082764) (xy 205.498192 -274.082764)
			(xy 205.498192 -274.082256) (xy 205.498192 -273.587972) (xy 205.498676 -273.582706) (xy 205.506133 -273.575265)
			(xy 205.5114 -273.574764) (xy 206.027528 -273.574764) (xy 206.03534 -273.574468) (xy 206.050211 -273.569671)
			(xy 206.056738 -273.565366) (xy 206.077827 -273.551017) (xy 206.123488 -273.528286) (xy 206.172094 -273.512827)
			(xy 206.222497 -273.505004) (xy 206.273503 -273.505004) (xy 206.323906 -273.512827) (xy 206.372512 -273.528286)
			(xy 206.418173 -273.551017) (xy 206.439262 -273.565366) (xy 206.445805 -273.569638) (xy 206.460666 -273.574433)
			(xy 206.468472 -273.574764) (xy 206.9846 -273.574764) (xy 206.989856 -273.575292) (xy 206.997297 -273.582717)
			(xy 206.997808 -273.587972) (xy 206.997808 -274.082256) (xy 268.898116 -274.082256) (xy 268.898116 -273.587718)
			(xy 268.89866 -273.582361) (xy 268.906223 -273.574776) (xy 268.911578 -273.574256) (xy 269.427706 -273.574256)
			(xy 269.435517 -273.573952) (xy 269.450389 -273.56916) (xy 269.456916 -273.564858) (xy 269.478005 -273.550509)
			(xy 269.523666 -273.527778) (xy 269.572272 -273.512319) (xy 269.622675 -273.504496) (xy 269.673681 -273.504496)
			(xy 269.724084 -273.512319) (xy 269.77269 -273.527778) (xy 269.818351 -273.550509) (xy 269.83944 -273.564858)
			(xy 269.845966 -273.569159) (xy 269.86084 -273.573937) (xy 269.86865 -273.574256) (xy 270.384778 -273.574256)
			(xy 270.390214 -273.574596) (xy 270.397902 -273.582282) (xy 270.39824 -273.587718) (xy 270.39824 -274.082256)
			(xy 276.442424 -274.082256) (xy 276.442424 -273.587718) (xy 276.442933 -273.58242) (xy 276.450345 -273.574848)
			(xy 276.455632 -273.574256) (xy 276.97176 -273.574256) (xy 276.979569 -273.573933) (xy 276.994441 -273.569154)
			(xy 277.00097 -273.564858) (xy 277.022059 -273.550509) (xy 277.06772 -273.527778) (xy 277.116326 -273.512319)
			(xy 277.166729 -273.504496) (xy 277.217735 -273.504496) (xy 277.268138 -273.512319) (xy 277.316744 -273.527778)
			(xy 277.362405 -273.550509) (xy 277.383494 -273.564858) (xy 277.39003 -273.569142) (xy 277.404896 -273.57393)
			(xy 277.412704 -273.574256) (xy 277.928832 -273.574256) (xy 277.93409 -273.57477) (xy 277.941529 -273.582206)
			(xy 277.94204 -273.587464) (xy 277.94204 -273.587972) (xy 277.94204 -274.082256) (xy 283.986224 -274.082256)
			(xy 283.986224 -273.587718) (xy 283.986733 -273.58242) (xy 283.994145 -273.574848) (xy 283.999432 -273.574256)
			(xy 284.51556 -273.574256) (xy 284.523369 -273.573933) (xy 284.538241 -273.569154) (xy 284.54477 -273.564858)
			(xy 284.565859 -273.550509) (xy 284.61152 -273.527778) (xy 284.660126 -273.512319) (xy 284.710529 -273.504496)
			(xy 284.761535 -273.504496) (xy 284.811938 -273.512319) (xy 284.860544 -273.527778) (xy 284.906205 -273.550509)
			(xy 284.927294 -273.564858) (xy 284.93383 -273.569142) (xy 284.948696 -273.57393) (xy 284.956504 -273.574256)
			(xy 285.472632 -273.574256) (xy 285.47789 -273.57477) (xy 285.485329 -273.582206) (xy 285.48584 -273.587464)
			(xy 285.48584 -273.587972) (xy 285.48584 -274.082256) (xy 291.530024 -274.082256) (xy 291.530024 -273.587718)
			(xy 291.53039 -273.582289) (xy 291.538058 -273.574603) (xy 291.543486 -273.574256) (xy 292.059614 -273.574256)
			(xy 292.067425 -273.573956) (xy 292.082297 -273.569161) (xy 292.088824 -273.564858) (xy 292.109913 -273.550509)
			(xy 292.155574 -273.527778) (xy 292.20418 -273.512319) (xy 292.254583 -273.504496) (xy 292.305589 -273.504496)
			(xy 292.355992 -273.512319) (xy 292.404598 -273.527778) (xy 292.450259 -273.550509) (xy 292.471348 -273.564858)
			(xy 292.477872 -273.569162) (xy 292.492748 -273.573938) (xy 292.500558 -273.574256) (xy 293.016686 -273.574256)
			(xy 293.022123 -273.57459) (xy 293.029811 -273.582281) (xy 293.030148 -273.587718) (xy 293.030148 -274.082256)
			(xy 299.074332 -274.082256) (xy 299.074332 -273.587718) (xy 299.074834 -273.582418) (xy 299.082251 -273.574846)
			(xy 299.08754 -273.574256) (xy 299.603668 -273.574256) (xy 299.611478 -273.573936) (xy 299.626349 -273.569155)
			(xy 299.632878 -273.564858) (xy 299.653967 -273.550509) (xy 299.699628 -273.527778) (xy 299.748234 -273.512319)
			(xy 299.798637 -273.504496) (xy 299.849643 -273.504496) (xy 299.900046 -273.512319) (xy 299.948652 -273.527778)
			(xy 299.994313 -273.550509) (xy 300.015402 -273.564858) (xy 300.021936 -273.569145) (xy 300.036804 -273.573931)
			(xy 300.044612 -273.574256) (xy 300.56074 -273.574256) (xy 300.565999 -273.574764) (xy 300.573437 -273.582205)
			(xy 300.573948 -273.587464) (xy 300.573948 -273.587972) (xy 300.573948 -274.082256) (xy 306.618132 -274.082256)
			(xy 306.618132 -273.587718) (xy 306.618491 -273.582287) (xy 306.626164 -273.5746) (xy 306.631594 -273.574256)
			(xy 308.104794 -273.574256) (xy 308.110232 -273.574585) (xy 308.11792 -273.582279) (xy 308.118256 -273.587718)
			(xy 308.118256 -274.082256) (xy 415.718244 -274.082256) (xy 415.718244 -273.587718) (xy 415.718736 -273.582415)
			(xy 415.72616 -273.574843) (xy 415.731452 -273.574256) (xy 417.204652 -273.574256) (xy 417.209969 -273.574656)
			(xy 417.21751 -273.582149) (xy 417.21786 -273.587464) (xy 417.21786 -274.082256) (xy 423.262044 -274.082256)
			(xy 423.262044 -273.587718) (xy 423.262392 -273.582284) (xy 423.270072 -273.574597) (xy 423.275506 -273.574256)
			(xy 423.791634 -273.574256) (xy 423.799442 -273.573922) (xy 423.814314 -273.569151) (xy 423.820844 -273.564858)
			(xy 423.841933 -273.550509) (xy 423.887594 -273.527778) (xy 423.9362 -273.512319) (xy 423.986603 -273.504496)
			(xy 424.037609 -273.504496) (xy 424.088012 -273.512319) (xy 424.136618 -273.527778) (xy 424.182279 -273.550509)
			(xy 424.203368 -273.564858) (xy 424.20991 -273.569132) (xy 424.224772 -273.573926) (xy 424.232578 -273.574256)
			(xy 424.748706 -273.574256) (xy 424.754146 -273.574577) (xy 424.761833 -273.582277) (xy 424.762168 -273.587718)
			(xy 424.762168 -274.082256) (xy 430.806352 -274.082256) (xy 430.806352 -273.587718) (xy 430.806836 -273.582413)
			(xy 430.814265 -273.57484) (xy 430.81956 -273.574256) (xy 431.335688 -273.574256) (xy 431.343498 -273.573944)
			(xy 431.35837 -273.569158) (xy 431.364898 -273.564858) (xy 431.385987 -273.550509) (xy 431.431648 -273.527778)
			(xy 431.480254 -273.512319) (xy 431.530657 -273.504496) (xy 431.581663 -273.504496) (xy 431.632066 -273.512319)
			(xy 431.680672 -273.527778) (xy 431.726333 -273.550509) (xy 431.747422 -273.564858) (xy 431.753952 -273.569152)
			(xy 431.768823 -273.573934) (xy 431.776632 -273.574256) (xy 432.29276 -273.574256) (xy 432.298078 -273.57465)
			(xy 432.305619 -273.582148) (xy 432.305968 -273.587464) (xy 432.305968 -273.587972) (xy 432.305968 -274.082256)
			(xy 438.350152 -274.082256) (xy 438.350152 -273.587718) (xy 438.350493 -273.582282) (xy 438.358178 -273.574594)
			(xy 438.363614 -273.574256) (xy 438.879742 -273.574256) (xy 438.887551 -273.573925) (xy 438.902422 -273.569152)
			(xy 438.908952 -273.564858) (xy 438.930041 -273.550509) (xy 438.975702 -273.527778) (xy 439.024308 -273.512319)
			(xy 439.074711 -273.504496) (xy 439.125717 -273.504496) (xy 439.17612 -273.512319) (xy 439.224726 -273.527778)
			(xy 439.270387 -273.550509) (xy 439.291476 -273.564858) (xy 439.298016 -273.569135) (xy 439.312879 -273.573927)
			(xy 439.320686 -273.574256) (xy 439.836814 -273.574256) (xy 439.842255 -273.574572) (xy 439.849941 -273.582276)
			(xy 439.850276 -273.587718) (xy 439.850276 -274.082256) (xy 445.89446 -274.082256) (xy 445.89446 -273.587718)
			(xy 445.894937 -273.582411) (xy 445.902371 -273.574838) (xy 445.907668 -273.574256) (xy 446.423796 -273.574256)
			(xy 446.431607 -273.573948) (xy 446.446478 -273.569159) (xy 446.453006 -273.564858) (xy 446.474095 -273.550509)
			(xy 446.519756 -273.527778) (xy 446.568362 -273.512319) (xy 446.618765 -273.504496) (xy 446.669771 -273.504496)
			(xy 446.720174 -273.512319) (xy 446.76878 -273.527778) (xy 446.814441 -273.550509) (xy 446.83553 -273.564858)
			(xy 446.842058 -273.569155) (xy 446.856931 -273.573935) (xy 446.86474 -273.574256) (xy 447.380868 -273.574256)
			(xy 447.386118 -273.574812) (xy 447.393561 -273.582216) (xy 447.394076 -273.587464) (xy 447.394076 -273.587972)
			(xy 447.394076 -274.082256) (xy 453.43826 -274.082256) (xy 453.43826 -273.587718) (xy 453.438737 -273.582411)
			(xy 453.446171 -273.574838) (xy 453.451468 -273.574256) (xy 453.967596 -273.574256) (xy 453.975407 -273.573948)
			(xy 453.990278 -273.569159) (xy 453.996806 -273.564858) (xy 454.017895 -273.550509) (xy 454.063556 -273.527778)
			(xy 454.112162 -273.512319) (xy 454.162565 -273.504496) (xy 454.213571 -273.504496) (xy 454.263974 -273.512319)
			(xy 454.31258 -273.527778) (xy 454.358241 -273.550509) (xy 454.37933 -273.564858) (xy 454.385858 -273.569155)
			(xy 454.400731 -273.573935) (xy 454.40854 -273.574256) (xy 454.924668 -273.574256) (xy 454.929918 -273.574812)
			(xy 454.937361 -273.582216) (xy 454.937876 -273.587464) (xy 454.937876 -273.587972) (xy 454.937876 -274.082256)
			(xy 454.93754 -274.08759) (xy 454.930002 -274.095136) (xy 454.924668 -274.095464) (xy 454.408794 -274.095464)
			(xy 454.40092 -274.095754) (xy 454.385916 -274.100536) (xy 454.37933 -274.104862) (xy 454.358264 -274.11927)
			(xy 454.312615 -274.142095) (xy 454.264005 -274.157648) (xy 454.213586 -274.165561) (xy 454.188068 -274.166076)
			(xy 454.162548 -274.165574) (xy 454.112122 -274.157684) (xy 454.06351 -274.142128) (xy 454.017871 -274.119276)
			(xy 453.996806 -274.104862) (xy 453.990211 -274.100552) (xy 453.975214 -274.095761) (xy 453.967342 -274.095464)
			(xy 453.451468 -274.095464) (xy 453.446121 -274.09519) (xy 453.438579 -274.087605) (xy 453.43826 -274.082256)
			(xy 447.394076 -274.082256) (xy 447.39374 -274.08759) (xy 447.386202 -274.095136) (xy 447.380868 -274.095464)
			(xy 446.864994 -274.095464) (xy 446.85712 -274.095754) (xy 446.842116 -274.100536) (xy 446.83553 -274.104862)
			(xy 446.814464 -274.11927) (xy 446.768815 -274.142095) (xy 446.720205 -274.157648) (xy 446.669786 -274.165561)
			(xy 446.644268 -274.166076) (xy 446.618748 -274.165574) (xy 446.568322 -274.157684) (xy 446.51971 -274.142128)
			(xy 446.474071 -274.119276) (xy 446.453006 -274.104862) (xy 446.446411 -274.100552) (xy 446.431414 -274.095761)
			(xy 446.423542 -274.095464) (xy 445.907668 -274.095464) (xy 445.902321 -274.09519) (xy 445.894779 -274.087605)
			(xy 445.89446 -274.082256) (xy 439.850276 -274.082256) (xy 439.84994 -274.08759) (xy 439.842402 -274.095136)
			(xy 439.837068 -274.095464) (xy 439.83656 -274.095464) (xy 439.32094 -274.095464) (xy 439.313064 -274.095731)
			(xy 439.29806 -274.100529) (xy 439.291476 -274.104862) (xy 439.270397 -274.119251) (xy 439.224752 -274.142079)
			(xy 439.176147 -274.157638) (xy 439.12573 -274.165558) (xy 439.100214 -274.166076) (xy 439.074693 -274.165601)
			(xy 439.024265 -274.157703) (xy 438.975654 -274.142138) (xy 438.930016 -274.119279) (xy 438.908952 -274.104862)
			(xy 438.902369 -274.100532) (xy 438.887363 -274.095753) (xy 438.879488 -274.095464) (xy 438.363614 -274.095464)
			(xy 438.358312 -274.094968) (xy 438.350741 -274.087547) (xy 438.350152 -274.082256) (xy 432.305968 -274.082256)
			(xy 432.30564 -274.087592) (xy 432.298096 -274.095138) (xy 432.29276 -274.095464) (xy 431.776886 -274.095464)
			(xy 431.769011 -274.095751) (xy 431.754007 -274.100535) (xy 431.747422 -274.104862) (xy 431.726358 -274.119274)
			(xy 431.680708 -274.142097) (xy 431.632098 -274.157649) (xy 431.581678 -274.165562) (xy 431.55616 -274.166076)
			(xy 431.53064 -274.165578) (xy 431.480213 -274.157686) (xy 431.431602 -274.142129) (xy 431.385963 -274.119276)
			(xy 431.364898 -274.104862) (xy 431.358305 -274.100549) (xy 431.343306 -274.09576) (xy 431.335434 -274.095464)
			(xy 430.81956 -274.095464) (xy 430.814211 -274.095196) (xy 430.80667 -274.087606) (xy 430.806352 -274.082256)
			(xy 424.762168 -274.082256) (xy 424.76184 -274.087592) (xy 424.754296 -274.095138) (xy 424.74896 -274.095464)
			(xy 424.748452 -274.095464) (xy 424.232832 -274.095464) (xy 424.224955 -274.095727) (xy 424.209951 -274.100527)
			(xy 424.203368 -274.104862) (xy 424.182291 -274.119254) (xy 424.136646 -274.142082) (xy 424.08804 -274.157639)
			(xy 424.037623 -274.165559) (xy 424.012106 -274.166076) (xy 423.986585 -274.165605) (xy 423.936157 -274.157705)
			(xy 423.887546 -274.14214) (xy 423.841908 -274.11928) (xy 423.820844 -274.104862) (xy 423.814263 -274.100528)
			(xy 423.799255 -274.095752) (xy 423.79138 -274.095464) (xy 423.275506 -274.095464) (xy 423.270203 -274.094973)
			(xy 423.262632 -274.087548) (xy 423.262044 -274.082256) (xy 417.21786 -274.082256) (xy 417.217539 -274.087594)
			(xy 417.20999 -274.095141) (xy 417.204652 -274.095464) (xy 415.731452 -274.095464) (xy 415.726173 -274.095033)
			(xy 415.718731 -274.087538) (xy 415.718244 -274.082256) (xy 308.118256 -274.082256) (xy 308.117681 -274.087502)
			(xy 308.11029 -274.094944) (xy 308.105048 -274.095464) (xy 308.10454 -274.095464) (xy 306.631594 -274.095464)
			(xy 306.62629 -274.094981) (xy 306.618719 -274.08755) (xy 306.618132 -274.082256) (xy 300.573948 -274.082256)
			(xy 300.573548 -274.087573) (xy 300.566054 -274.095114) (xy 300.56074 -274.095464) (xy 300.044866 -274.095464)
			(xy 300.036991 -274.095742) (xy 300.021987 -274.100532) (xy 300.015402 -274.104862) (xy 299.994315 -274.119239)
			(xy 299.948674 -274.142071) (xy 299.900071 -274.157632) (xy 299.849656 -274.165556) (xy 299.82414 -274.166076)
			(xy 299.79862 -274.165588) (xy 299.748193 -274.157693) (xy 299.699581 -274.142133) (xy 299.653943 -274.119278)
			(xy 299.632878 -274.104862) (xy 299.62629 -274.100542) (xy 299.611287 -274.095757) (xy 299.603414 -274.095464)
			(xy 299.08754 -274.095464) (xy 299.082202 -274.095142) (xy 299.074657 -274.087594) (xy 299.074332 -274.082256)
			(xy 293.030148 -274.082256) (xy 293.029748 -274.087573) (xy 293.022254 -274.095114) (xy 293.01694 -274.095464)
			(xy 293.016432 -274.095464) (xy 292.500812 -274.095464) (xy 292.492938 -274.095762) (xy 292.477934 -274.100538)
			(xy 292.471348 -274.104862) (xy 292.450277 -274.119263) (xy 292.404629 -274.142089) (xy 292.356022 -274.157644)
			(xy 292.305603 -274.16556) (xy 292.280086 -274.166076) (xy 292.254567 -274.165565) (xy 292.20414 -274.157677)
			(xy 292.155529 -274.142124) (xy 292.109889 -274.119275) (xy 292.088824 -274.104862) (xy 292.082225 -274.100559)
			(xy 292.067231 -274.095764) (xy 292.05936 -274.095464) (xy 291.543486 -274.095464) (xy 291.538181 -274.094986)
			(xy 291.530611 -274.087551) (xy 291.530024 -274.082256) (xy 285.48584 -274.082256) (xy 285.485447 -274.087575)
			(xy 285.477949 -274.095116) (xy 285.472632 -274.095464) (xy 284.956758 -274.095464) (xy 284.948882 -274.095739)
			(xy 284.933878 -274.100531) (xy 284.927294 -274.104862) (xy 284.90621 -274.119243) (xy 284.860567 -274.142073)
			(xy 284.811963 -274.157634) (xy 284.761548 -274.165557) (xy 284.736032 -274.166076) (xy 284.710512 -274.165592)
			(xy 284.660084 -274.157696) (xy 284.611473 -274.142135) (xy 284.565835 -274.119278) (xy 284.54477 -274.104862)
			(xy 284.538183 -274.100539) (xy 284.52318 -274.095756) (xy 284.515306 -274.095464) (xy 283.999432 -274.095464)
			(xy 283.994093 -274.095147) (xy 283.986548 -274.087595) (xy 283.986224 -274.082256) (xy 277.94204 -274.082256)
			(xy 277.941647 -274.087575) (xy 277.934149 -274.095116) (xy 277.928832 -274.095464) (xy 277.412958 -274.095464)
			(xy 277.405082 -274.095739) (xy 277.390078 -274.100531) (xy 277.383494 -274.104862) (xy 277.36241 -274.119243)
			(xy 277.316767 -274.142073) (xy 277.268163 -274.157634) (xy 277.217748 -274.165557) (xy 277.192232 -274.166076)
			(xy 277.166712 -274.165592) (xy 277.116284 -274.157696) (xy 277.067673 -274.142135) (xy 277.022035 -274.119278)
			(xy 277.00097 -274.104862) (xy 276.994383 -274.100539) (xy 276.97938 -274.095756) (xy 276.971506 -274.095464)
			(xy 276.455632 -274.095464) (xy 276.450293 -274.095147) (xy 276.442748 -274.087595) (xy 276.442424 -274.082256)
			(xy 270.39824 -274.082256) (xy 270.397847 -274.087575) (xy 270.390349 -274.095116) (xy 270.385032 -274.095464)
			(xy 270.384524 -274.095464) (xy 269.868904 -274.095464) (xy 269.86103 -274.095759) (xy 269.846026 -274.100537)
			(xy 269.83944 -274.104862) (xy 269.818371 -274.119266) (xy 269.772723 -274.142091) (xy 269.724114 -274.157645)
			(xy 269.673695 -274.165561) (xy 269.648178 -274.166076) (xy 269.622658 -274.165569) (xy 269.572232 -274.15768)
			(xy 269.52362 -274.142126) (xy 269.477981 -274.119275) (xy 269.456916 -274.104862) (xy 269.450319 -274.100556)
			(xy 269.435323 -274.095763) (xy 269.427452 -274.095464) (xy 268.911578 -274.095464) (xy 268.906272 -274.094992)
			(xy 268.898702 -274.087552) (xy 268.898116 -274.082256) (xy 206.997808 -274.082256) (xy 206.997808 -274.08251)
			(xy 206.997289 -274.087804) (xy 206.989882 -274.095372) (xy 206.9846 -274.095972) (xy 206.468726 -274.095972)
			(xy 206.460916 -274.096285) (xy 206.446044 -274.10107) (xy 206.439516 -274.10537) (xy 206.418389 -274.119711)
			(xy 206.372667 -274.142439) (xy 206.323995 -274.157871) (xy 206.27353 -274.165641) (xy 206.248 -274.166076)
			(xy 206.22247 -274.165637) (xy 206.172006 -274.157862) (xy 206.123334 -274.142433) (xy 206.077606 -274.119717)
			(xy 206.056484 -274.10537) (xy 206.049951 -274.101081) (xy 206.035082 -274.096295) (xy 206.027274 -274.095972)
			(xy 205.5114 -274.095972) (xy 205.506059 -274.09567) (xy 205.498516 -274.088106) (xy 205.498192 -274.082764)
			(xy 199.453983 -274.082764) (xy 199.453489 -274.087804) (xy 199.446082 -274.095372) (xy 199.4408 -274.095972)
			(xy 198.924926 -274.095972) (xy 198.917116 -274.096285) (xy 198.902244 -274.10107) (xy 198.895716 -274.10537)
			(xy 198.874589 -274.119711) (xy 198.828867 -274.142439) (xy 198.780195 -274.157871) (xy 198.72973 -274.165641)
			(xy 198.7042 -274.166076) (xy 198.67867 -274.165637) (xy 198.628206 -274.157862) (xy 198.579534 -274.142433)
			(xy 198.533806 -274.119717) (xy 198.512684 -274.10537) (xy 198.506151 -274.101081) (xy 198.491282 -274.096295)
			(xy 198.483474 -274.095972) (xy 197.9676 -274.095972) (xy 197.962259 -274.09567) (xy 197.954716 -274.088106)
			(xy 197.954392 -274.082764) (xy 191.910182 -274.082764) (xy 191.909661 -274.087864) (xy 191.902099 -274.095447)
			(xy 191.896746 -274.095972) (xy 191.380872 -274.095972) (xy 191.37306 -274.096262) (xy 191.358188 -274.101063)
			(xy 191.351662 -274.10537) (xy 191.33055 -274.119734) (xy 191.284822 -274.142457) (xy 191.236146 -274.157883)
			(xy 191.185678 -274.165645) (xy 191.160146 -274.166076) (xy 191.134617 -274.165614) (xy 191.084154 -274.157846)
			(xy 191.035482 -274.142424) (xy 190.989753 -274.119714) (xy 190.96863 -274.10537) (xy 190.962087 -274.101098)
			(xy 190.947226 -274.096302) (xy 190.93942 -274.095972) (xy 190.423546 -274.095972) (xy 190.41812 -274.095591)
			(xy 190.410432 -274.087935) (xy 190.410084 -274.08251) (xy 184.3659 -274.08251) (xy 184.365388 -274.087806)
			(xy 184.357977 -274.095374) (xy 184.352692 -274.095972) (xy 183.836818 -274.095972) (xy 183.829007 -274.096281)
			(xy 183.814135 -274.101069) (xy 183.807608 -274.10537) (xy 183.786483 -274.119714) (xy 183.74076 -274.142441)
			(xy 183.692088 -274.157873) (xy 183.641623 -274.165642) (xy 183.616092 -274.166076) (xy 183.590562 -274.165641)
			(xy 183.540098 -274.157865) (xy 183.491426 -274.142435) (xy 183.445698 -274.119718) (xy 183.424576 -274.10537)
			(xy 183.418045 -274.101078) (xy 183.403175 -274.096294) (xy 183.395366 -274.095972) (xy 182.879492 -274.095972)
			(xy 182.87415 -274.095675) (xy 182.866607 -274.088107) (xy 182.866284 -274.082764) (xy 176.822074 -274.082764)
			(xy 176.82156 -274.087866) (xy 176.813993 -274.095449) (xy 176.808638 -274.095972) (xy 176.292764 -274.095972)
			(xy 176.284955 -274.096301) (xy 176.270083 -274.101075) (xy 176.263554 -274.10537) (xy 176.242444 -274.119737)
			(xy 176.196716 -274.14246) (xy 176.148039 -274.157884) (xy 176.09757 -274.165646) (xy 176.072038 -274.166076)
			(xy 176.046509 -274.165618) (xy 175.996046 -274.157849) (xy 175.947373 -274.142425) (xy 175.901645 -274.119715)
			(xy 175.880522 -274.10537) (xy 175.873981 -274.101095) (xy 175.859118 -274.096301) (xy 175.851312 -274.095972)
			(xy 175.335438 -274.095972) (xy 175.330011 -274.095596) (xy 175.322323 -274.087936) (xy 175.321976 -274.08251)
			(xy 169.277792 -274.08251) (xy 169.277287 -274.087808) (xy 169.269871 -274.095377) (xy 169.264584 -274.095972)
			(xy 167.791384 -274.095972) (xy 167.786041 -274.095681) (xy 167.778498 -274.088109) (xy 167.778176 -274.082764)
			(xy 60.178163 -274.082764) (xy 60.177659 -274.087869) (xy 60.170084 -274.095452) (xy 60.164726 -274.095972)
			(xy 58.691526 -274.095972) (xy 58.686097 -274.095604) (xy 58.67841 -274.087938) (xy 58.678064 -274.08251)
			(xy 52.63388 -274.08251) (xy 52.633386 -274.087811) (xy 52.625962 -274.09538) (xy 52.620672 -274.095972)
			(xy 52.104798 -274.095972) (xy 52.096987 -274.096273) (xy 52.082115 -274.101066) (xy 52.075588 -274.10537)
			(xy 52.054469 -274.119723) (xy 52.008744 -274.142448) (xy 51.96007 -274.157877) (xy 51.909603 -274.165643)
			(xy 51.884072 -274.166076) (xy 51.858541 -274.165651) (xy 51.808077 -274.157872) (xy 51.759405 -274.142439)
			(xy 51.713678 -274.119719) (xy 51.692556 -274.10537) (xy 51.686029 -274.10107) (xy 51.671156 -274.096291)
			(xy 51.663346 -274.095972) (xy 51.147472 -274.095972) (xy 51.142127 -274.095688) (xy 51.134586 -274.08811)
			(xy 51.134264 -274.082764) (xy 45.090055 -274.082764) (xy 45.089558 -274.087871) (xy 45.081978 -274.095455)
			(xy 45.076618 -274.095972) (xy 44.560744 -274.095972) (xy 44.552934 -274.096292) (xy 44.538062 -274.101072)
			(xy 44.531534 -274.10537) (xy 44.51043 -274.119746) (xy 44.464699 -274.142466) (xy 44.416021 -274.157889)
			(xy 44.36555 -274.165647) (xy 44.340018 -274.166076) (xy 44.314488 -274.165628) (xy 44.264025 -274.157855)
			(xy 44.215352 -274.14243) (xy 44.169624 -274.119716) (xy 44.148502 -274.10537) (xy 44.141965 -274.101087)
			(xy 44.127099 -274.096298) (xy 44.119292 -274.095972) (xy 43.603418 -274.095972) (xy 43.597988 -274.09561)
			(xy 43.590301 -274.087939) (xy 43.589956 -274.08251) (xy 37.545772 -274.08251) (xy 37.545285 -274.087813)
			(xy 37.537856 -274.095382) (xy 37.532564 -274.095972) (xy 37.01669 -274.095972) (xy 37.008878 -274.096269)
			(xy 36.994007 -274.101065) (xy 36.98748 -274.10537) (xy 36.966363 -274.119726) (xy 36.920637 -274.142451)
			(xy 36.871963 -274.157879) (xy 36.821495 -274.165644) (xy 36.795964 -274.166076) (xy 36.770433 -274.165655)
			(xy 36.719969 -274.157874) (xy 36.671296 -274.14244) (xy 36.625569 -274.119719) (xy 36.604448 -274.10537)
			(xy 36.597923 -274.101067) (xy 36.583048 -274.09629) (xy 36.575238 -274.095972) (xy 36.059364 -274.095972)
			(xy 36.054088 -274.095525) (xy 36.046646 -274.088042) (xy 36.046156 -274.082764) (xy 30.001949 -274.082764)
			(xy 30.001485 -274.087813) (xy 29.994056 -274.095382) (xy 29.988764 -274.095972) (xy 29.47289 -274.095972)
			(xy 29.465078 -274.096269) (xy 29.450207 -274.101065) (xy 29.44368 -274.10537) (xy 29.422563 -274.119726)
			(xy 29.376837 -274.142451) (xy 29.328163 -274.157879) (xy 29.277695 -274.165644) (xy 29.252164 -274.166076)
			(xy 29.226633 -274.165655) (xy 29.176169 -274.157874) (xy 29.127496 -274.14244) (xy 29.081769 -274.119719)
			(xy 29.060648 -274.10537) (xy 29.054123 -274.101067) (xy 29.039248 -274.09629) (xy 29.031438 -274.095972)
			(xy 28.515564 -274.095972) (xy 28.510288 -274.095525) (xy 28.502846 -274.088042) (xy 28.502356 -274.082764)
			(xy 22.458148 -274.082764) (xy 22.457657 -274.087873) (xy 22.450073 -274.095457) (xy 22.44471 -274.095972)
			(xy 21.928836 -274.095972) (xy 21.921026 -274.096289) (xy 21.906154 -274.101071) (xy 21.899626 -274.10537)
			(xy 21.878496 -274.119706) (xy 21.832775 -274.142435) (xy 21.784104 -274.157869) (xy 21.73364 -274.16564)
			(xy 21.70811 -274.166076) (xy 21.68258 -274.165632) (xy 21.632117 -274.157858) (xy 21.583444 -274.142431)
			(xy 21.537716 -274.119716) (xy 21.516594 -274.10537) (xy 21.510059 -274.101084) (xy 21.495192 -274.096297)
			(xy 21.487384 -274.095972) (xy 20.97151 -274.095972) (xy 20.96615 -274.095444) (xy 20.958564 -274.087869)
			(xy 20.958048 -274.08251) (xy 2.509012 -274.08251) (xy 2.509012 -274.932394) (xy 16.85798 -274.932394)
			(xy 16.85798 -274.437856) (xy 16.858464 -274.432591) (xy 16.865922 -274.425151) (xy 16.871188 -274.424648)
			(xy 16.871696 -274.424648) (xy 17.38757 -274.424648) (xy 17.39538 -274.42433) (xy 17.410252 -274.419548)
			(xy 17.41678 -274.41525) (xy 17.437869 -274.400901) (xy 17.48353 -274.37817) (xy 17.532136 -274.362711)
			(xy 17.582539 -274.354888) (xy 17.633545 -274.354888) (xy 17.683948 -274.362711) (xy 17.732554 -274.37817)
			(xy 17.778215 -274.400901) (xy 17.799304 -274.41525) (xy 17.805838 -274.419537) (xy 17.820706 -274.424323)
			(xy 17.828514 -274.424648) (xy 18.344642 -274.424648) (xy 18.349953 -274.425096) (xy 18.357522 -274.432553)
			(xy 18.358104 -274.437856) (xy 18.358104 -274.932394) (xy 18.358078 -274.932648) (xy 24.402288 -274.932648)
			(xy 24.402288 -274.93214) (xy 24.402288 -274.437856) (xy 24.402765 -274.432589) (xy 24.410227 -274.425149)
			(xy 24.415496 -274.424648) (xy 24.931624 -274.424648) (xy 24.939436 -274.424353) (xy 24.954308 -274.419555)
			(xy 24.960834 -274.41525) (xy 24.981923 -274.400901) (xy 25.027584 -274.37817) (xy 25.07619 -274.362711)
			(xy 25.126593 -274.354888) (xy 25.177599 -274.354888) (xy 25.228002 -274.362711) (xy 25.276608 -274.37817)
			(xy 25.322269 -274.400901) (xy 25.343358 -274.41525) (xy 25.34988 -274.419557) (xy 25.364757 -274.424331)
			(xy 25.372568 -274.424648) (xy 25.888696 -274.424648) (xy 25.893948 -274.425193) (xy 25.901388 -274.432606)
			(xy 25.901904 -274.437856) (xy 25.901904 -274.932394) (xy 25.901879 -274.932648) (xy 31.946088 -274.932648)
			(xy 31.946088 -274.93214) (xy 31.946088 -274.437856) (xy 31.946565 -274.432589) (xy 31.954027 -274.425149)
			(xy 31.959296 -274.424648) (xy 32.475424 -274.424648) (xy 32.483236 -274.424353) (xy 32.498108 -274.419555)
			(xy 32.504634 -274.41525) (xy 32.525723 -274.400901) (xy 32.571384 -274.37817) (xy 32.61999 -274.362711)
			(xy 32.670393 -274.354888) (xy 32.721399 -274.354888) (xy 32.771802 -274.362711) (xy 32.820408 -274.37817)
			(xy 32.866069 -274.400901) (xy 32.887158 -274.41525) (xy 32.89368 -274.419557) (xy 32.908557 -274.424331)
			(xy 32.916368 -274.424648) (xy 33.432496 -274.424648) (xy 33.437748 -274.425193) (xy 33.445188 -274.432606)
			(xy 33.445704 -274.437856) (xy 33.445704 -274.932394) (xy 39.489888 -274.932394) (xy 39.489888 -274.437856)
			(xy 39.490365 -274.432589) (xy 39.497827 -274.425149) (xy 39.503096 -274.424648) (xy 39.503604 -274.424648)
			(xy 40.019478 -274.424648) (xy 40.027288 -274.424334) (xy 40.04216 -274.419549) (xy 40.048688 -274.41525)
			(xy 40.069777 -274.400901) (xy 40.115438 -274.37817) (xy 40.164044 -274.362711) (xy 40.214447 -274.354888)
			(xy 40.265453 -274.354888) (xy 40.315856 -274.362711) (xy 40.364462 -274.37817) (xy 40.410123 -274.400901)
			(xy 40.431212 -274.41525) (xy 40.437745 -274.41954) (xy 40.452614 -274.424325) (xy 40.460422 -274.424648)
			(xy 40.97655 -274.424648) (xy 40.98185 -274.425158) (xy 40.989424 -274.432568) (xy 40.990012 -274.437856)
			(xy 40.990012 -274.932394) (xy 40.989985 -274.932648) (xy 47.034196 -274.932648) (xy 47.034196 -274.93214)
			(xy 47.034196 -274.437856) (xy 47.034666 -274.432587) (xy 47.042133 -274.425147) (xy 47.047404 -274.424648)
			(xy 47.563532 -274.424648) (xy 47.57134 -274.424314) (xy 47.586212 -274.419543) (xy 47.592742 -274.41525)
			(xy 47.613831 -274.400901) (xy 47.659492 -274.37817) (xy 47.708098 -274.362711) (xy 47.758501 -274.354888)
			(xy 47.809507 -274.354888) (xy 47.85991 -274.362711) (xy 47.908516 -274.37817) (xy 47.954177 -274.400901)
			(xy 47.975266 -274.41525) (xy 47.981809 -274.419522) (xy 47.99667 -274.424318) (xy 48.004476 -274.424648)
			(xy 48.520604 -274.424648) (xy 48.525857 -274.425187) (xy 48.533297 -274.432605) (xy 48.533812 -274.437856)
			(xy 48.533812 -274.932394) (xy 54.577996 -274.932394) (xy 54.577996 -274.437856) (xy 54.578466 -274.432587)
			(xy 54.585933 -274.425147) (xy 54.591204 -274.424648) (xy 56.064658 -274.424648) (xy 56.069959 -274.425152)
			(xy 56.077533 -274.432566) (xy 56.07812 -274.437856) (xy 56.07812 -274.932394) (xy 56.078106 -274.932648)
			(xy 163.678108 -274.932648) (xy 163.678108 -274.93214) (xy 163.678108 -274.437856) (xy 163.678567 -274.432584)
			(xy 163.686042 -274.425143) (xy 163.691316 -274.424648) (xy 165.164516 -274.424648) (xy 165.16977 -274.425179)
			(xy 165.177209 -274.432603) (xy 165.177724 -274.437856) (xy 165.177724 -274.932394) (xy 171.221908 -274.932394)
			(xy 171.221908 -274.437856) (xy 171.222367 -274.432584) (xy 171.229842 -274.425143) (xy 171.235116 -274.424648)
			(xy 171.235624 -274.424648) (xy 171.751498 -274.424648) (xy 171.759309 -274.424342) (xy 171.774181 -274.419552)
			(xy 171.780708 -274.41525) (xy 171.801797 -274.400901) (xy 171.847458 -274.37817) (xy 171.896064 -274.362711)
			(xy 171.946467 -274.354888) (xy 171.997473 -274.354888) (xy 172.047876 -274.362711) (xy 172.096482 -274.37817)
			(xy 172.142143 -274.400901) (xy 172.163232 -274.41525) (xy 172.16976 -274.419547) (xy 172.184633 -274.424327)
			(xy 172.192442 -274.424648) (xy 172.70857 -274.424648) (xy 172.713872 -274.425144) (xy 172.721446 -274.432564)
			(xy 172.722032 -274.437856) (xy 172.722032 -274.932394) (xy 172.722017 -274.932648) (xy 178.766216 -274.932648)
			(xy 178.766216 -274.93214) (xy 178.766216 -274.437856) (xy 178.766668 -274.432582) (xy 178.774148 -274.425141)
			(xy 178.779424 -274.424648) (xy 179.295552 -274.424648) (xy 179.303361 -274.424323) (xy 179.318233 -274.419546)
			(xy 179.324762 -274.41525) (xy 179.345851 -274.400901) (xy 179.391512 -274.37817) (xy 179.440118 -274.362711)
			(xy 179.490521 -274.354888) (xy 179.541527 -274.354888) (xy 179.59193 -274.362711) (xy 179.640536 -274.37817)
			(xy 179.686197 -274.400901) (xy 179.707286 -274.41525) (xy 179.713824 -274.41953) (xy 179.728689 -274.424321)
			(xy 179.736496 -274.424648) (xy 180.252624 -274.424648) (xy 180.257879 -274.425174) (xy 180.265318 -274.432602)
			(xy 180.265832 -274.437856) (xy 180.265832 -274.932394) (xy 186.310016 -274.932394) (xy 186.310016 -274.437856)
			(xy 186.310468 -274.432582) (xy 186.317948 -274.425141) (xy 186.323224 -274.424648) (xy 186.323732 -274.424648)
			(xy 186.839606 -274.424648) (xy 186.847417 -274.424346) (xy 186.862289 -274.419553) (xy 186.868816 -274.41525)
			(xy 186.889905 -274.400901) (xy 186.935566 -274.37817) (xy 186.984172 -274.362711) (xy 187.034575 -274.354888)
			(xy 187.085581 -274.354888) (xy 187.135984 -274.362711) (xy 187.18459 -274.37817) (xy 187.230251 -274.400901)
			(xy 187.25134 -274.41525) (xy 187.257866 -274.41955) (xy 187.27274 -274.424329) (xy 187.28055 -274.424648)
			(xy 187.796678 -274.424648) (xy 187.801981 -274.425139) (xy 187.809554 -274.432563) (xy 187.81014 -274.437856)
			(xy 187.81014 -274.932394) (xy 187.810125 -274.932648) (xy 193.854324 -274.932648) (xy 193.854324 -274.93214)
			(xy 193.854324 -274.437856) (xy 193.854769 -274.43258) (xy 193.862253 -274.425138) (xy 193.867532 -274.424648)
			(xy 194.38366 -274.424648) (xy 194.391469 -274.424326) (xy 194.406341 -274.419547) (xy 194.41287 -274.41525)
			(xy 194.433959 -274.400901) (xy 194.47962 -274.37817) (xy 194.528226 -274.362711) (xy 194.578629 -274.354888)
			(xy 194.629635 -274.354888) (xy 194.680038 -274.362711) (xy 194.728644 -274.37817) (xy 194.774305 -274.400901)
			(xy 194.795394 -274.41525) (xy 194.801931 -274.419533) (xy 194.816797 -274.424322) (xy 194.824604 -274.424648)
			(xy 195.340732 -274.424648) (xy 195.345988 -274.425169) (xy 195.353426 -274.4326) (xy 195.35394 -274.437856)
			(xy 195.35394 -274.932394) (xy 195.353918 -274.932648) (xy 201.398124 -274.932648) (xy 201.398124 -274.93214)
			(xy 201.398124 -274.437856) (xy 201.398569 -274.43258) (xy 201.406053 -274.425138) (xy 201.411332 -274.424648)
			(xy 201.92746 -274.424648) (xy 201.935269 -274.424326) (xy 201.950141 -274.419547) (xy 201.95667 -274.41525)
			(xy 201.977759 -274.400901) (xy 202.02342 -274.37817) (xy 202.072026 -274.362711) (xy 202.122429 -274.354888)
			(xy 202.173435 -274.354888) (xy 202.223838 -274.362711) (xy 202.272444 -274.37817) (xy 202.318105 -274.400901)
			(xy 202.339194 -274.41525) (xy 202.345731 -274.419533) (xy 202.360597 -274.424322) (xy 202.368404 -274.424648)
			(xy 202.884532 -274.424648) (xy 202.889788 -274.425169) (xy 202.897226 -274.4326) (xy 202.89774 -274.437856)
			(xy 202.89774 -274.93214) (xy 264.798048 -274.93214) (xy 264.798048 -274.437602) (xy 264.798382 -274.432165)
			(xy 264.806073 -274.424479) (xy 264.81151 -274.42414) (xy 265.327638 -274.42414) (xy 265.335447 -274.42381)
			(xy 265.350319 -274.419036) (xy 265.356848 -274.414742) (xy 265.377937 -274.400393) (xy 265.423598 -274.377662)
			(xy 265.472204 -274.362203) (xy 265.522607 -274.35438) (xy 265.573613 -274.35438) (xy 265.624016 -274.362203)
			(xy 265.672622 -274.377662) (xy 265.718283 -274.400393) (xy 265.739372 -274.414742) (xy 265.745914 -274.419016)
			(xy 265.760776 -274.423811) (xy 265.768582 -274.42414) (xy 266.28471 -274.42414) (xy 266.290076 -274.424644)
			(xy 266.297661 -274.432236) (xy 266.298172 -274.437602) (xy 266.298172 -274.93214) (xy 272.342356 -274.93214)
			(xy 272.342356 -274.437602) (xy 272.342826 -274.432294) (xy 272.350266 -274.424722) (xy 272.355564 -274.42414)
			(xy 272.871692 -274.42414) (xy 272.879503 -274.423833) (xy 272.894375 -274.419043) (xy 272.900902 -274.414742)
			(xy 272.921991 -274.400393) (xy 272.967652 -274.377662) (xy 273.016258 -274.362203) (xy 273.066661 -274.35438)
			(xy 273.117667 -274.35438) (xy 273.16807 -274.362203) (xy 273.216676 -274.377662) (xy 273.262337 -274.400393)
			(xy 273.283426 -274.414742) (xy 273.289956 -274.419036) (xy 273.304827 -274.423818) (xy 273.312636 -274.42414)
			(xy 273.828764 -274.42414) (xy 273.834103 -274.424456) (xy 273.841649 -274.432009) (xy 273.841972 -274.437348)
			(xy 273.841972 -274.437856) (xy 273.841972 -274.93214) (xy 279.886156 -274.93214) (xy 279.886156 -274.437602)
			(xy 279.886626 -274.432294) (xy 279.894066 -274.424722) (xy 279.899364 -274.42414) (xy 280.415492 -274.42414)
			(xy 280.423303 -274.423833) (xy 280.438175 -274.419043) (xy 280.444702 -274.414742) (xy 280.465791 -274.400393)
			(xy 280.511452 -274.377662) (xy 280.560058 -274.362203) (xy 280.610461 -274.35438) (xy 280.661467 -274.35438)
			(xy 280.71187 -274.362203) (xy 280.760476 -274.377662) (xy 280.806137 -274.400393) (xy 280.827226 -274.414742)
			(xy 280.833756 -274.419036) (xy 280.848627 -274.423818) (xy 280.856436 -274.42414) (xy 281.372564 -274.42414)
			(xy 281.377903 -274.424456) (xy 281.385449 -274.432009) (xy 281.385772 -274.437348) (xy 281.385772 -274.437856)
			(xy 281.385772 -274.93214) (xy 287.429956 -274.93214) (xy 287.429956 -274.437602) (xy 287.430283 -274.432163)
			(xy 287.437979 -274.424476) (xy 287.443418 -274.42414) (xy 287.959546 -274.42414) (xy 287.967355 -274.423813)
			(xy 287.982227 -274.419037) (xy 287.988756 -274.414742) (xy 288.009845 -274.400393) (xy 288.055506 -274.377662)
			(xy 288.104112 -274.362203) (xy 288.154515 -274.35438) (xy 288.205521 -274.35438) (xy 288.255924 -274.362203)
			(xy 288.30453 -274.377662) (xy 288.350191 -274.400393) (xy 288.37128 -274.414742) (xy 288.37782 -274.419019)
			(xy 288.392683 -274.423812) (xy 288.40049 -274.42414) (xy 288.916618 -274.42414) (xy 288.921985 -274.424638)
			(xy 288.92957 -274.432235) (xy 288.93008 -274.437602) (xy 288.93008 -274.93214) (xy 294.974264 -274.93214)
			(xy 294.974264 -274.437602) (xy 294.974727 -274.432292) (xy 294.982172 -274.42472) (xy 294.987472 -274.42414)
			(xy 295.5036 -274.42414) (xy 295.511411 -274.423836) (xy 295.526283 -274.419044) (xy 295.53281 -274.414742)
			(xy 295.553899 -274.400393) (xy 295.59956 -274.377662) (xy 295.648166 -274.362203) (xy 295.698569 -274.35438)
			(xy 295.749575 -274.35438) (xy 295.799978 -274.362203) (xy 295.848584 -274.377662) (xy 295.894245 -274.400393)
			(xy 295.915334 -274.414742) (xy 295.921862 -274.419039) (xy 295.936735 -274.42382) (xy 295.944544 -274.42414)
			(xy 296.460672 -274.42414) (xy 296.466012 -274.42445) (xy 296.473558 -274.432007) (xy 296.47388 -274.437348)
			(xy 296.47388 -274.437856) (xy 296.47388 -274.93214) (xy 302.518064 -274.93214) (xy 302.518064 -274.437602)
			(xy 302.518383 -274.432161) (xy 302.526085 -274.424474) (xy 302.531526 -274.42414) (xy 304.004726 -274.42414)
			(xy 304.010093 -274.424633) (xy 304.017678 -274.432233) (xy 304.018188 -274.437602) (xy 304.018188 -274.93214)
			(xy 411.618176 -274.93214) (xy 411.618176 -274.437602) (xy 411.618629 -274.43229) (xy 411.62608 -274.424716)
			(xy 411.631384 -274.42414) (xy 413.104584 -274.42414) (xy 413.109926 -274.424442) (xy 413.117471 -274.432005)
			(xy 413.117792 -274.437348) (xy 413.117792 -274.437856) (xy 413.117792 -274.93214) (xy 419.161976 -274.93214)
			(xy 419.161976 -274.437602) (xy 419.162285 -274.432158) (xy 419.169993 -274.42447) (xy 419.175438 -274.42414)
			(xy 419.691566 -274.42414) (xy 419.699376 -274.423822) (xy 419.714248 -274.41904) (xy 419.720776 -274.414742)
			(xy 419.741865 -274.400393) (xy 419.787526 -274.377662) (xy 419.836132 -274.362203) (xy 419.886535 -274.35438)
			(xy 419.937541 -274.35438) (xy 419.987944 -274.362203) (xy 420.03655 -274.377662) (xy 420.082211 -274.400393)
			(xy 420.1033 -274.414742) (xy 420.109836 -274.419026) (xy 420.124702 -274.423815) (xy 420.13251 -274.42414)
			(xy 420.648638 -274.42414) (xy 420.654007 -274.424626) (xy 420.66159 -274.432232) (xy 420.6621 -274.437602)
			(xy 420.6621 -274.93214) (xy 426.706284 -274.93214) (xy 426.706284 -274.437602) (xy 426.70673 -274.432288)
			(xy 426.714186 -274.424714) (xy 426.719492 -274.42414) (xy 427.23562 -274.42414) (xy 427.243432 -274.423845)
			(xy 427.258304 -274.419047) (xy 427.26483 -274.414742) (xy 427.285919 -274.400393) (xy 427.33158 -274.377662)
			(xy 427.380186 -274.362203) (xy 427.430589 -274.35438) (xy 427.481595 -274.35438) (xy 427.531998 -274.362203)
			(xy 427.580604 -274.377662) (xy 427.626265 -274.400393) (xy 427.647354 -274.414742) (xy 427.653878 -274.419047)
			(xy 427.668754 -274.423823) (xy 427.676564 -274.42414) (xy 428.192692 -274.42414) (xy 428.198035 -274.424437)
			(xy 428.205579 -274.432004) (xy 428.2059 -274.437348) (xy 428.2059 -274.437856) (xy 428.2059 -274.93214)
			(xy 434.250084 -274.93214) (xy 434.250084 -274.437602) (xy 434.250385 -274.432156) (xy 434.258099 -274.424468)
			(xy 434.263546 -274.42414) (xy 434.779674 -274.42414) (xy 434.787484 -274.423825) (xy 434.802356 -274.419041)
			(xy 434.808884 -274.414742) (xy 434.829973 -274.400393) (xy 434.875634 -274.377662) (xy 434.92424 -274.362203)
			(xy 434.974643 -274.35438) (xy 435.025649 -274.35438) (xy 435.076052 -274.362203) (xy 435.124658 -274.377662)
			(xy 435.170319 -274.400393) (xy 435.191408 -274.414742) (xy 435.197942 -274.419029) (xy 435.21281 -274.423816)
			(xy 435.220618 -274.42414) (xy 435.736746 -274.42414) (xy 435.742116 -274.42462) (xy 435.749699 -274.43223)
			(xy 435.750208 -274.437602) (xy 435.750208 -274.93214) (xy 441.794392 -274.93214) (xy 441.794392 -274.437602)
			(xy 441.794919 -274.432309) (xy 441.802319 -274.424741) (xy 441.8076 -274.42414) (xy 442.323728 -274.42414)
			(xy 442.33154 -274.423849) (xy 442.346412 -274.419048) (xy 442.352938 -274.414742) (xy 442.374027 -274.400393)
			(xy 442.419688 -274.377662) (xy 442.468294 -274.362203) (xy 442.518697 -274.35438) (xy 442.569703 -274.35438)
			(xy 442.620106 -274.362203) (xy 442.668712 -274.377662) (xy 442.714373 -274.400393) (xy 442.735462 -274.414742)
			(xy 442.742006 -274.419012) (xy 442.756866 -274.423809) (xy 442.764672 -274.42414) (xy 443.2808 -274.42414)
			(xy 443.286144 -274.424431) (xy 443.293688 -274.432003) (xy 443.294008 -274.437348) (xy 443.294008 -274.437856)
			(xy 443.294008 -274.93214) (xy 449.338192 -274.93214) (xy 449.338192 -274.437602) (xy 449.338719 -274.432309)
			(xy 449.346119 -274.424741) (xy 449.3514 -274.42414) (xy 449.867528 -274.42414) (xy 449.87534 -274.423849)
			(xy 449.890212 -274.419048) (xy 449.896738 -274.414742) (xy 449.917827 -274.400393) (xy 449.963488 -274.377662)
			(xy 450.012094 -274.362203) (xy 450.062497 -274.35438) (xy 450.113503 -274.35438) (xy 450.163906 -274.362203)
			(xy 450.212512 -274.377662) (xy 450.258173 -274.400393) (xy 450.279262 -274.414742) (xy 450.285806 -274.419012)
			(xy 450.300666 -274.423809) (xy 450.308472 -274.42414) (xy 450.8246 -274.42414) (xy 450.829944 -274.424431)
			(xy 450.837488 -274.432003) (xy 450.837808 -274.437348) (xy 450.837808 -274.437856) (xy 450.837808 -274.93214)
			(xy 450.837332 -274.937408) (xy 450.829869 -274.944848) (xy 450.8246 -274.945348) (xy 450.308726 -274.945348)
			(xy 450.300849 -274.945612) (xy 450.285845 -274.950412) (xy 450.279262 -274.954746) (xy 450.258185 -274.969139)
			(xy 450.21254 -274.991967) (xy 450.163934 -275.007524) (xy 450.113517 -275.015443) (xy 450.088 -275.01596)
			(xy 450.062479 -275.015495) (xy 450.012051 -275.007594) (xy 449.963439 -274.992027) (xy 449.917802 -274.969165)
			(xy 449.896738 -274.954746) (xy 449.890137 -274.950447) (xy 449.875144 -274.94565) (xy 449.867274 -274.945348)
			(xy 449.3514 -274.945348) (xy 449.346147 -274.944809) (xy 449.338707 -274.937392) (xy 449.338192 -274.93214)
			(xy 443.294008 -274.93214) (xy 443.293532 -274.937408) (xy 443.286069 -274.944848) (xy 443.2808 -274.945348)
			(xy 442.764926 -274.945348) (xy 442.757049 -274.945612) (xy 442.742045 -274.950412) (xy 442.735462 -274.954746)
			(xy 442.714385 -274.969139) (xy 442.66874 -274.991967) (xy 442.620134 -275.007524) (xy 442.569717 -275.015443)
			(xy 442.5442 -275.01596) (xy 442.518679 -275.015495) (xy 442.468251 -275.007594) (xy 442.419639 -274.992027)
			(xy 442.374002 -274.969165) (xy 442.352938 -274.954746) (xy 442.346337 -274.950447) (xy 442.331344 -274.94565)
			(xy 442.323474 -274.945348) (xy 441.8076 -274.945348) (xy 441.802347 -274.944809) (xy 441.794907 -274.937392)
			(xy 441.794392 -274.93214) (xy 435.750208 -274.93214) (xy 435.749732 -274.937408) (xy 435.742269 -274.944848)
			(xy 435.737 -274.945348) (xy 435.736492 -274.945348) (xy 435.220872 -274.945348) (xy 435.212997 -274.945632)
			(xy 435.197993 -274.950418) (xy 435.191408 -274.954746) (xy 435.170346 -274.969162) (xy 435.124696 -274.991985)
			(xy 435.076085 -275.007536) (xy 435.025664 -275.015447) (xy 435.000146 -275.01596) (xy 434.974626 -275.015472)
			(xy 434.924198 -275.007578) (xy 434.875587 -274.992018) (xy 434.829949 -274.969162) (xy 434.808884 -274.954746)
			(xy 434.802295 -274.950427) (xy 434.787293 -274.945642) (xy 434.77942 -274.945348) (xy 434.263546 -274.945348)
			(xy 434.258244 -274.944845) (xy 434.25067 -274.93743) (xy 434.250084 -274.93214) (xy 428.2059 -274.93214)
			(xy 428.205431 -274.93741) (xy 428.197963 -274.94485) (xy 428.192692 -274.945348) (xy 427.676818 -274.945348)
			(xy 427.668945 -274.945651) (xy 427.653941 -274.950424) (xy 427.647354 -274.954746) (xy 427.62628 -274.969142)
			(xy 427.580634 -274.99197) (xy 427.532027 -275.007526) (xy 427.481609 -275.015444) (xy 427.456092 -275.01596)
			(xy 427.430573 -275.015449) (xy 427.380146 -275.007562) (xy 427.331534 -274.992008) (xy 427.285895 -274.969159)
			(xy 427.26483 -274.954746) (xy 427.258231 -274.950444) (xy 427.243237 -274.945649) (xy 427.235366 -274.945348)
			(xy 426.719492 -274.945348) (xy 426.714238 -274.944815) (xy 426.706798 -274.937393) (xy 426.706284 -274.93214)
			(xy 420.6621 -274.93214) (xy 420.661631 -274.93741) (xy 420.654163 -274.94485) (xy 420.648892 -274.945348)
			(xy 420.648384 -274.945348) (xy 420.132764 -274.945348) (xy 420.124889 -274.945628) (xy 420.109885 -274.950417)
			(xy 420.1033 -274.954746) (xy 420.082213 -274.969122) (xy 420.036571 -274.991954) (xy 419.987968 -275.007516)
			(xy 419.937554 -275.01544) (xy 419.912038 -275.01596) (xy 419.886518 -275.015476) (xy 419.83609 -275.007581)
			(xy 419.787478 -274.992019) (xy 419.74184 -274.969162) (xy 419.720776 -274.954746) (xy 419.714189 -274.950423)
			(xy 419.699186 -274.945641) (xy 419.691312 -274.945348) (xy 419.175438 -274.945348) (xy 419.170136 -274.94485)
			(xy 419.162562 -274.937431) (xy 419.161976 -274.93214) (xy 413.117792 -274.93214) (xy 413.11733 -274.937412)
			(xy 413.109858 -274.944853) (xy 413.104584 -274.945348) (xy 411.631384 -274.945348) (xy 411.626129 -274.94482)
			(xy 411.618689 -274.937394) (xy 411.618176 -274.93214) (xy 304.018188 -274.93214) (xy 304.01773 -274.937413)
			(xy 304.010255 -274.944854) (xy 304.00498 -274.945348) (xy 302.531526 -274.945348) (xy 302.526222 -274.944858)
			(xy 302.518649 -274.937433) (xy 302.518064 -274.93214) (xy 296.47388 -274.93214) (xy 296.473429 -274.937414)
			(xy 296.465949 -274.944856) (xy 296.460672 -274.945348) (xy 295.944798 -274.945348) (xy 295.936924 -274.945643)
			(xy 295.92192 -274.950422) (xy 295.915334 -274.954746) (xy 295.894265 -274.969151) (xy 295.848617 -274.991976)
			(xy 295.800009 -275.00753) (xy 295.749589 -275.015445) (xy 295.724072 -275.01596) (xy 295.698552 -275.015459)
			(xy 295.648125 -275.007569) (xy 295.599514 -274.992012) (xy 295.553875 -274.96916) (xy 295.53281 -274.954746)
			(xy 295.526215 -274.950437) (xy 295.511218 -274.945646) (xy 295.503346 -274.945348) (xy 294.987472 -274.945348)
			(xy 294.982215 -274.944828) (xy 294.974777 -274.937396) (xy 294.974264 -274.93214) (xy 288.93008 -274.93214)
			(xy 288.929629 -274.937414) (xy 288.922149 -274.944856) (xy 288.916872 -274.945348) (xy 288.916364 -274.945348)
			(xy 288.400744 -274.945348) (xy 288.392868 -274.945619) (xy 288.377864 -274.950414) (xy 288.37128 -274.954746)
			(xy 288.350198 -274.969131) (xy 288.304555 -274.991961) (xy 288.25595 -275.007521) (xy 288.205534 -275.015442)
			(xy 288.180018 -275.01596) (xy 288.154497 -275.015486) (xy 288.104069 -275.007588) (xy 288.055458 -274.992023)
			(xy 288.00982 -274.969164) (xy 287.988756 -274.954746) (xy 287.982173 -274.950416) (xy 287.967167 -274.945638)
			(xy 287.959292 -274.945348) (xy 287.443418 -274.945348) (xy 287.438113 -274.944864) (xy 287.43054 -274.937435)
			(xy 287.429956 -274.93214) (xy 281.385772 -274.93214) (xy 281.385328 -274.937416) (xy 281.377843 -274.944859)
			(xy 281.372564 -274.945348) (xy 280.85669 -274.945348) (xy 280.848816 -274.945639) (xy 280.833812 -274.950421)
			(xy 280.827226 -274.954746) (xy 280.806159 -274.969154) (xy 280.760511 -274.991979) (xy 280.711901 -275.007532)
			(xy 280.661482 -275.015446) (xy 280.635964 -275.01596) (xy 280.610444 -275.015463) (xy 280.560017 -275.007572)
			(xy 280.511405 -274.992014) (xy 280.465767 -274.969161) (xy 280.444702 -274.954746) (xy 280.438109 -274.950433)
			(xy 280.42311 -274.945644) (xy 280.415238 -274.945348) (xy 279.899364 -274.945348) (xy 279.894107 -274.944833)
			(xy 279.886668 -274.937397) (xy 279.886156 -274.93214) (xy 273.841972 -274.93214) (xy 273.841528 -274.937416)
			(xy 273.834043 -274.944859) (xy 273.828764 -274.945348) (xy 273.31289 -274.945348) (xy 273.305016 -274.945639)
			(xy 273.290012 -274.950421) (xy 273.283426 -274.954746) (xy 273.262359 -274.969154) (xy 273.216711 -274.991979)
			(xy 273.168101 -275.007532) (xy 273.117682 -275.015446) (xy 273.092164 -275.01596) (xy 273.066644 -275.015463)
			(xy 273.016217 -275.007572) (xy 272.967605 -274.992014) (xy 272.921967 -274.969161) (xy 272.900902 -274.954746)
			(xy 272.894309 -274.950433) (xy 272.87931 -274.945644) (xy 272.871438 -274.945348) (xy 272.355564 -274.945348)
			(xy 272.350307 -274.944833) (xy 272.342868 -274.937397) (xy 272.342356 -274.93214) (xy 266.298172 -274.93214)
			(xy 266.297728 -274.937416) (xy 266.290243 -274.944859) (xy 266.284964 -274.945348) (xy 266.284456 -274.945348)
			(xy 265.768836 -274.945348) (xy 265.76096 -274.945616) (xy 265.745956 -274.950413) (xy 265.739372 -274.954746)
			(xy 265.718293 -274.969134) (xy 265.672648 -274.991964) (xy 265.624043 -275.007522) (xy 265.573627 -275.015442)
			(xy 265.54811 -275.01596) (xy 265.522589 -275.01549) (xy 265.472161 -275.00759) (xy 265.423549 -274.992025)
			(xy 265.377912 -274.969164) (xy 265.356848 -274.954746) (xy 265.350267 -274.950413) (xy 265.335259 -274.945636)
			(xy 265.327384 -274.945348) (xy 264.81151 -274.945348) (xy 264.806204 -274.944869) (xy 264.798632 -274.937436)
			(xy 264.798048 -274.93214) (xy 202.89774 -274.93214) (xy 202.89774 -274.932394) (xy 202.897271 -274.937702)
			(xy 202.889831 -274.945275) (xy 202.884532 -274.945856) (xy 202.368658 -274.945856) (xy 202.360849 -274.946185)
			(xy 202.345977 -274.950959) (xy 202.339448 -274.955254) (xy 202.318339 -274.969622) (xy 202.27261 -274.992345)
			(xy 202.223933 -275.007769) (xy 202.173464 -275.01553) (xy 202.147932 -275.01596) (xy 202.122402 -275.015508)
			(xy 202.071939 -275.007737) (xy 202.023267 -274.992312) (xy 201.977538 -274.9696) (xy 201.956416 -274.955254)
			(xy 201.949877 -274.950975) (xy 201.935013 -274.946184) (xy 201.927206 -274.945856) (xy 201.411332 -274.945856)
			(xy 201.406084 -274.945289) (xy 201.398643 -274.937892) (xy 201.398124 -274.932648) (xy 195.353918 -274.932648)
			(xy 195.353471 -274.937702) (xy 195.346031 -274.945275) (xy 195.340732 -274.945856) (xy 194.824858 -274.945856)
			(xy 194.817049 -274.946185) (xy 194.802177 -274.950959) (xy 194.795648 -274.955254) (xy 194.774539 -274.969622)
			(xy 194.72881 -274.992345) (xy 194.680133 -275.007769) (xy 194.629664 -275.01553) (xy 194.604132 -275.01596)
			(xy 194.578602 -275.015508) (xy 194.528139 -275.007737) (xy 194.479467 -274.992312) (xy 194.433738 -274.9696)
			(xy 194.412616 -274.955254) (xy 194.406077 -274.950975) (xy 194.391213 -274.946184) (xy 194.383406 -274.945856)
			(xy 193.867532 -274.945856) (xy 193.862284 -274.945289) (xy 193.854843 -274.937892) (xy 193.854324 -274.932648)
			(xy 187.810125 -274.932648) (xy 187.809815 -274.937833) (xy 187.802118 -274.945521) (xy 187.796678 -274.945856)
			(xy 187.280804 -274.945856) (xy 187.272993 -274.946162) (xy 187.258121 -274.950952) (xy 187.251594 -274.955254)
			(xy 187.230472 -274.969602) (xy 187.184748 -274.992329) (xy 187.136075 -275.007759) (xy 187.085609 -275.015527)
			(xy 187.060078 -275.01596) (xy 187.034547 -275.015535) (xy 186.984083 -275.007756) (xy 186.935411 -274.992323)
			(xy 186.889683 -274.969603) (xy 186.868562 -274.955254) (xy 186.862035 -274.950955) (xy 186.847162 -274.946176)
			(xy 186.839352 -274.945856) (xy 186.323478 -274.945856) (xy 186.31811 -274.945364) (xy 186.310525 -274.937763)
			(xy 186.310016 -274.932394) (xy 180.265832 -274.932394) (xy 180.26537 -274.937704) (xy 180.257925 -274.945277)
			(xy 180.252624 -274.945856) (xy 179.73675 -274.945856) (xy 179.728941 -274.946182) (xy 179.714069 -274.950958)
			(xy 179.70754 -274.955254) (xy 179.686433 -274.969626) (xy 179.640704 -274.992347) (xy 179.592026 -275.007771)
			(xy 179.541556 -275.015531) (xy 179.516024 -275.01596) (xy 179.490494 -275.015512) (xy 179.440031 -275.00774)
			(xy 179.391358 -274.992314) (xy 179.34563 -274.9696) (xy 179.324508 -274.955254) (xy 179.317971 -274.950972)
			(xy 179.303105 -274.946182) (xy 179.295298 -274.945856) (xy 178.779424 -274.945856) (xy 178.774176 -274.945294)
			(xy 178.766735 -274.937893) (xy 178.766216 -274.932648) (xy 172.722017 -274.932648) (xy 172.721714 -274.937835)
			(xy 172.714012 -274.945523) (xy 172.70857 -274.945856) (xy 172.192696 -274.945856) (xy 172.184885 -274.946159)
			(xy 172.170013 -274.950951) (xy 172.163486 -274.955254) (xy 172.142366 -274.969606) (xy 172.096642 -274.992332)
			(xy 172.047968 -275.007761) (xy 171.997501 -275.015527) (xy 171.97197 -275.01596) (xy 171.946439 -275.015539)
			(xy 171.895975 -275.007759) (xy 171.847302 -274.992325) (xy 171.801575 -274.969604) (xy 171.780454 -274.955254)
			(xy 171.773929 -274.950952) (xy 171.759054 -274.946175) (xy 171.751244 -274.945856) (xy 171.23537 -274.945856)
			(xy 171.230001 -274.945369) (xy 171.222417 -274.937764) (xy 171.221908 -274.932394) (xy 165.177724 -274.932394)
			(xy 165.177269 -274.937706) (xy 165.169819 -274.94528) (xy 165.164516 -274.945856) (xy 163.691316 -274.945856)
			(xy 163.686067 -274.9453) (xy 163.678626 -274.937895) (xy 163.678108 -274.932648) (xy 56.078106 -274.932648)
			(xy 56.077813 -274.937838) (xy 56.070103 -274.945527) (xy 56.064658 -274.945856) (xy 54.591458 -274.945856)
			(xy 54.586087 -274.945377) (xy 54.578504 -274.937766) (xy 54.577996 -274.932394) (xy 48.533812 -274.932394)
			(xy 48.533367 -274.937709) (xy 48.52591 -274.945283) (xy 48.520604 -274.945856) (xy 48.00473 -274.945856)
			(xy 47.99692 -274.946173) (xy 47.982048 -274.950956) (xy 47.97552 -274.955254) (xy 47.954391 -274.969591)
			(xy 47.908669 -274.99232) (xy 47.859999 -275.007754) (xy 47.809534 -275.015525) (xy 47.784004 -275.01596)
			(xy 47.758474 -275.015522) (xy 47.70801 -275.007747) (xy 47.659338 -274.992318) (xy 47.61361 -274.969602)
			(xy 47.592488 -274.955254) (xy 47.585955 -274.950965) (xy 47.571086 -274.94618) (xy 47.563278 -274.945856)
			(xy 47.047404 -274.945856) (xy 47.042153 -274.945308) (xy 47.034713 -274.937897) (xy 47.034196 -274.932648)
			(xy 40.989985 -274.932648) (xy 40.989451 -274.937745) (xy 40.981899 -274.945329) (xy 40.97655 -274.945856)
			(xy 40.460676 -274.945856) (xy 40.452864 -274.94615) (xy 40.437992 -274.950948) (xy 40.431466 -274.955254)
			(xy 40.410352 -274.969614) (xy 40.364625 -274.992339) (xy 40.31595 -275.007765) (xy 40.265482 -275.015529)
			(xy 40.23995 -275.01596) (xy 40.214421 -275.015499) (xy 40.163958 -275.007731) (xy 40.115285 -274.992309)
			(xy 40.069557 -274.969599) (xy 40.048434 -274.955254) (xy 40.041891 -274.950982) (xy 40.02703 -274.946186)
			(xy 40.019224 -274.945856) (xy 39.50335 -274.945856) (xy 39.497979 -274.945382) (xy 39.490396 -274.937767)
			(xy 39.489888 -274.932394) (xy 33.445704 -274.932394) (xy 33.445178 -274.937687) (xy 33.437777 -274.945256)
			(xy 33.432496 -274.945856) (xy 32.916622 -274.945856) (xy 32.908812 -274.94617) (xy 32.89394 -274.950955)
			(xy 32.887412 -274.955254) (xy 32.866285 -274.969595) (xy 32.820563 -274.992323) (xy 32.771891 -275.007756)
			(xy 32.721426 -275.015525) (xy 32.695896 -275.01596) (xy 32.670366 -275.015526) (xy 32.619902 -275.00775)
			(xy 32.571229 -274.99232) (xy 32.525502 -274.969602) (xy 32.50438 -274.955254) (xy 32.497849 -274.950962)
			(xy 32.482979 -274.946178) (xy 32.47517 -274.945856) (xy 31.959296 -274.945856) (xy 31.954044 -274.945313)
			(xy 31.946605 -274.937898) (xy 31.946088 -274.932648) (xy 25.901879 -274.932648) (xy 25.901378 -274.937687)
			(xy 25.893977 -274.945256) (xy 25.888696 -274.945856) (xy 25.372822 -274.945856) (xy 25.365012 -274.94617)
			(xy 25.35014 -274.950955) (xy 25.343612 -274.955254) (xy 25.322485 -274.969595) (xy 25.276763 -274.992323)
			(xy 25.228091 -275.007756) (xy 25.177626 -275.015525) (xy 25.152096 -275.01596) (xy 25.126566 -275.015526)
			(xy 25.076102 -275.00775) (xy 25.027429 -274.99232) (xy 24.981702 -274.969602) (xy 24.96058 -274.955254)
			(xy 24.954049 -274.950962) (xy 24.939179 -274.946178) (xy 24.93137 -274.945856) (xy 24.415496 -274.945856)
			(xy 24.410244 -274.945313) (xy 24.402805 -274.937898) (xy 24.402288 -274.932648) (xy 18.358078 -274.932648)
			(xy 18.35755 -274.937747) (xy 18.349993 -274.945331) (xy 18.344642 -274.945856) (xy 17.828768 -274.945856)
			(xy 17.82096 -274.946189) (xy 17.806088 -274.950961) (xy 17.799558 -274.955254) (xy 17.778446 -274.969618)
			(xy 17.732719 -274.992341) (xy 17.684042 -275.007767) (xy 17.633574 -275.015529) (xy 17.608042 -275.01596)
			(xy 17.582513 -275.015503) (xy 17.532049 -275.007734) (xy 17.483377 -274.99231) (xy 17.437649 -274.969599)
			(xy 17.416526 -274.955254) (xy 17.409985 -274.950979) (xy 17.395122 -274.946185) (xy 17.387316 -274.945856)
			(xy 16.871442 -274.945856) (xy 16.866011 -274.945492) (xy 16.858323 -274.937824) (xy 16.85798 -274.932394)
			(xy 2.509012 -274.932394) (xy 2.509012 -275.782532) (xy 20.958048 -275.782532) (xy 20.958048 -275.287994)
			(xy 20.958376 -275.282556) (xy 20.966072 -275.27487) (xy 20.97151 -275.274532) (xy 21.487638 -275.274532)
			(xy 21.495447 -275.274203) (xy 21.510319 -275.269429) (xy 21.516848 -275.265134) (xy 21.537937 -275.250785)
			(xy 21.583598 -275.228054) (xy 21.632204 -275.212595) (xy 21.682607 -275.204772) (xy 21.733613 -275.204772)
			(xy 21.784016 -275.212595) (xy 21.832622 -275.228054) (xy 21.878283 -275.250785) (xy 21.899372 -275.265134)
			(xy 21.905914 -275.269407) (xy 21.920776 -275.274202) (xy 21.928582 -275.274532) (xy 22.44471 -275.274532)
			(xy 22.450074 -275.275043) (xy 22.457658 -275.28263) (xy 22.458172 -275.287994) (xy 22.458172 -275.782532)
			(xy 28.502356 -275.782532) (xy 28.502356 -275.287994) (xy 28.502821 -275.282685) (xy 28.510264 -275.275114)
			(xy 28.515564 -275.274532) (xy 29.031692 -275.274532) (xy 29.039503 -275.274226) (xy 29.054375 -275.269436)
			(xy 29.060902 -275.265134) (xy 29.081991 -275.250785) (xy 29.127652 -275.228054) (xy 29.176258 -275.212595)
			(xy 29.226661 -275.204772) (xy 29.277667 -275.204772) (xy 29.32807 -275.212595) (xy 29.376676 -275.228054)
			(xy 29.422337 -275.250785) (xy 29.443426 -275.265134) (xy 29.449956 -275.269428) (xy 29.464827 -275.27421)
			(xy 29.472636 -275.274532) (xy 29.988764 -275.274532) (xy 29.994101 -275.274855) (xy 30.001647 -275.282403)
			(xy 30.001972 -275.28774) (xy 30.001972 -275.288248) (xy 30.001972 -275.782532) (xy 36.046156 -275.782532)
			(xy 36.046156 -275.287994) (xy 36.046621 -275.282685) (xy 36.054064 -275.275114) (xy 36.059364 -275.274532)
			(xy 36.575492 -275.274532) (xy 36.583303 -275.274226) (xy 36.598175 -275.269436) (xy 36.604702 -275.265134)
			(xy 36.625791 -275.250785) (xy 36.671452 -275.228054) (xy 36.720058 -275.212595) (xy 36.770461 -275.204772)
			(xy 36.821467 -275.204772) (xy 36.87187 -275.212595) (xy 36.920476 -275.228054) (xy 36.966137 -275.250785)
			(xy 36.987226 -275.265134) (xy 36.993756 -275.269428) (xy 37.008627 -275.27421) (xy 37.016436 -275.274532)
			(xy 37.532564 -275.274532) (xy 37.537901 -275.274855) (xy 37.545447 -275.282403) (xy 37.545772 -275.28774)
			(xy 37.545772 -275.288248) (xy 37.545772 -275.782532) (xy 43.589956 -275.782532) (xy 43.589956 -275.287994)
			(xy 43.590277 -275.282554) (xy 43.597977 -275.274867) (xy 43.603418 -275.274532) (xy 44.119546 -275.274532)
			(xy 44.127355 -275.274207) (xy 44.142227 -275.26943) (xy 44.148756 -275.265134) (xy 44.169845 -275.250785)
			(xy 44.215506 -275.228054) (xy 44.264112 -275.212595) (xy 44.314515 -275.204772) (xy 44.365521 -275.204772)
			(xy 44.415924 -275.212595) (xy 44.46453 -275.228054) (xy 44.510191 -275.250785) (xy 44.53128 -275.265134)
			(xy 44.537821 -275.26941) (xy 44.552683 -275.274204) (xy 44.56049 -275.274532) (xy 45.076618 -275.274532)
			(xy 45.081983 -275.275038) (xy 45.089567 -275.282629) (xy 45.09008 -275.287994) (xy 45.09008 -275.782532)
			(xy 51.134264 -275.782532) (xy 51.134264 -275.287994) (xy 51.134722 -275.282683) (xy 51.14217 -275.275111)
			(xy 51.147472 -275.274532) (xy 51.6636 -275.274532) (xy 51.671411 -275.27423) (xy 51.686283 -275.269437)
			(xy 51.69281 -275.265134) (xy 51.713899 -275.250785) (xy 51.75956 -275.228054) (xy 51.808166 -275.212595)
			(xy 51.858569 -275.204772) (xy 51.909575 -275.204772) (xy 51.959978 -275.212595) (xy 52.008584 -275.228054)
			(xy 52.054245 -275.250785) (xy 52.075334 -275.265134) (xy 52.081863 -275.269431) (xy 52.096735 -275.274212)
			(xy 52.104544 -275.274532) (xy 52.620672 -275.274532) (xy 52.62601 -275.274849) (xy 52.633555 -275.282401)
			(xy 52.63388 -275.28774) (xy 52.63388 -275.288248) (xy 52.63388 -275.782532) (xy 58.678064 -275.782532)
			(xy 58.678064 -275.287994) (xy 58.678378 -275.282552) (xy 58.686083 -275.274865) (xy 58.691526 -275.274532)
			(xy 60.164726 -275.274532) (xy 60.170092 -275.275033) (xy 60.177675 -275.282628) (xy 60.178188 -275.287994)
			(xy 60.178188 -275.782532) (xy 167.778176 -275.782532) (xy 167.778176 -275.287994) (xy 167.778623 -275.282681)
			(xy 167.786079 -275.275108) (xy 167.791384 -275.274532) (xy 169.264584 -275.274532) (xy 169.269924 -275.274841)
			(xy 169.277468 -275.2824) (xy 169.277792 -275.28774) (xy 169.277792 -275.782532) (xy 175.321976 -275.782532)
			(xy 175.321976 -275.287994) (xy 175.322279 -275.282549) (xy 175.329992 -275.274861) (xy 175.335438 -275.274532)
			(xy 175.851566 -275.274532) (xy 175.859376 -275.274215) (xy 175.874248 -275.269433) (xy 175.880776 -275.265134)
			(xy 175.901865 -275.250785) (xy 175.947526 -275.228054) (xy 175.996132 -275.212595) (xy 176.046535 -275.204772)
			(xy 176.097541 -275.204772) (xy 176.147944 -275.212595) (xy 176.19655 -275.228054) (xy 176.242211 -275.250785)
			(xy 176.2633 -275.265134) (xy 176.269836 -275.269418) (xy 176.284702 -275.274207) (xy 176.29251 -275.274532)
			(xy 176.808638 -275.274532) (xy 176.814005 -275.275025) (xy 176.821588 -275.282626) (xy 176.8221 -275.287994)
			(xy 176.8221 -275.782532) (xy 182.866284 -275.782532) (xy 182.866284 -275.287994) (xy 182.866724 -275.282679)
			(xy 182.874185 -275.275105) (xy 182.879492 -275.274532) (xy 183.39562 -275.274532) (xy 183.403432 -275.274238)
			(xy 183.418304 -275.26944) (xy 183.42483 -275.265134) (xy 183.445919 -275.250785) (xy 183.49158 -275.228054)
			(xy 183.540186 -275.212595) (xy 183.590589 -275.204772) (xy 183.641595 -275.204772) (xy 183.691998 -275.212595)
			(xy 183.740604 -275.228054) (xy 183.786265 -275.250785) (xy 183.807354 -275.265134) (xy 183.813878 -275.269438)
			(xy 183.828754 -275.274214) (xy 183.836564 -275.274532) (xy 184.352692 -275.274532) (xy 184.358033 -275.274836)
			(xy 184.365577 -275.282398) (xy 184.3659 -275.28774) (xy 184.3659 -275.288248) (xy 184.3659 -275.782532)
			(xy 190.410084 -275.782532) (xy 190.410084 -275.287994) (xy 190.41038 -275.282547) (xy 190.418098 -275.274859)
			(xy 190.423546 -275.274532) (xy 190.939674 -275.274532) (xy 190.947484 -275.274219) (xy 190.962356 -275.269434)
			(xy 190.968884 -275.265134) (xy 190.989973 -275.250785) (xy 191.035634 -275.228054) (xy 191.08424 -275.212595)
			(xy 191.134643 -275.204772) (xy 191.185649 -275.204772) (xy 191.236052 -275.212595) (xy 191.284658 -275.228054)
			(xy 191.330319 -275.250785) (xy 191.351408 -275.265134) (xy 191.357942 -275.269421) (xy 191.37281 -275.274208)
			(xy 191.380618 -275.274532) (xy 191.896746 -275.274532) (xy 191.902114 -275.275019) (xy 191.909697 -275.282625)
			(xy 191.910208 -275.287994) (xy 191.910208 -275.782532) (xy 197.954392 -275.782532) (xy 197.954392 -275.287994)
			(xy 197.954913 -275.2827) (xy 197.962318 -275.275132) (xy 197.9676 -275.274532) (xy 198.483728 -275.274532)
			(xy 198.49154 -275.274242) (xy 198.506412 -275.269441) (xy 198.512938 -275.265134) (xy 198.534027 -275.250785)
			(xy 198.579688 -275.228054) (xy 198.628294 -275.212595) (xy 198.678697 -275.204772) (xy 198.729703 -275.204772)
			(xy 198.780106 -275.212595) (xy 198.828712 -275.228054) (xy 198.874373 -275.250785) (xy 198.895462 -275.265134)
			(xy 198.902007 -275.269403) (xy 198.916866 -275.274201) (xy 198.924672 -275.274532) (xy 199.4408 -275.274532)
			(xy 199.446142 -275.274831) (xy 199.453685 -275.282397) (xy 199.454008 -275.28774) (xy 199.454008 -275.288248)
			(xy 199.454008 -275.782532) (xy 205.498192 -275.782532) (xy 205.498192 -275.287994) (xy 205.498713 -275.2827)
			(xy 205.506118 -275.275132) (xy 205.5114 -275.274532) (xy 206.027528 -275.274532) (xy 206.03534 -275.274242)
			(xy 206.050212 -275.269441) (xy 206.056738 -275.265134) (xy 206.077827 -275.250785) (xy 206.123488 -275.228054)
			(xy 206.172094 -275.212595) (xy 206.222497 -275.204772) (xy 206.273503 -275.204772) (xy 206.323906 -275.212595)
			(xy 206.372512 -275.228054) (xy 206.418173 -275.250785) (xy 206.439262 -275.265134) (xy 206.445807 -275.269403)
			(xy 206.460666 -275.274201) (xy 206.468472 -275.274532) (xy 206.9846 -275.274532) (xy 206.989942 -275.274831)
			(xy 206.997485 -275.282397) (xy 206.997808 -275.28774) (xy 206.997808 -275.288248) (xy 206.997808 -275.782278)
			(xy 268.898116 -275.782278) (xy 268.898116 -275.28774) (xy 268.898456 -275.282407) (xy 268.905992 -275.274863)
			(xy 268.911324 -275.274532) (xy 268.911832 -275.274532) (xy 269.427706 -275.274532) (xy 269.435518 -275.274232)
			(xy 269.450389 -275.269438) (xy 269.456916 -275.265134) (xy 269.478005 -275.250785) (xy 269.523666 -275.228054)
			(xy 269.572272 -275.212595) (xy 269.622675 -275.204772) (xy 269.673681 -275.204772) (xy 269.724084 -275.212595)
			(xy 269.77269 -275.228054) (xy 269.818351 -275.250785) (xy 269.83944 -275.265134) (xy 269.845967 -275.269433)
			(xy 269.86084 -275.274212) (xy 269.86865 -275.274532) (xy 270.384778 -275.274532) (xy 270.390078 -275.275037)
			(xy 270.39765 -275.282451) (xy 270.39824 -275.28774) (xy 270.39824 -275.782278) (xy 270.398224 -275.782532)
			(xy 276.442424 -275.782532) (xy 276.442424 -275.782024) (xy 276.442424 -275.28774) (xy 276.442757 -275.282405)
			(xy 276.450298 -275.27486) (xy 276.455632 -275.274532) (xy 276.97176 -275.274532) (xy 276.97957 -275.274213)
			(xy 276.994442 -275.269432) (xy 277.00097 -275.265134) (xy 277.022059 -275.250785) (xy 277.06772 -275.228054)
			(xy 277.116326 -275.212595) (xy 277.166729 -275.204772) (xy 277.217735 -275.204772) (xy 277.268138 -275.212595)
			(xy 277.316744 -275.228054) (xy 277.362405 -275.250785) (xy 277.383494 -275.265134) (xy 277.390031 -275.269415)
			(xy 277.404897 -275.274206) (xy 277.412704 -275.274532) (xy 277.928832 -275.274532) (xy 277.934178 -275.274809)
			(xy 277.94172 -275.282392) (xy 277.94204 -275.28774) (xy 277.94204 -275.782278) (xy 277.942017 -275.782532)
			(xy 283.986224 -275.782532) (xy 283.986224 -275.782024) (xy 283.986224 -275.28774) (xy 283.986557 -275.282405)
			(xy 283.994098 -275.27486) (xy 283.999432 -275.274532) (xy 284.51556 -275.274532) (xy 284.52337 -275.274213)
			(xy 284.538242 -275.269432) (xy 284.54477 -275.265134) (xy 284.565859 -275.250785) (xy 284.61152 -275.228054)
			(xy 284.660126 -275.212595) (xy 284.710529 -275.204772) (xy 284.761535 -275.204772) (xy 284.811938 -275.212595)
			(xy 284.860544 -275.228054) (xy 284.906205 -275.250785) (xy 284.927294 -275.265134) (xy 284.933831 -275.269415)
			(xy 284.948697 -275.274206) (xy 284.956504 -275.274532) (xy 285.472632 -275.274532) (xy 285.477978 -275.274809)
			(xy 285.48552 -275.282392) (xy 285.48584 -275.28774) (xy 285.48584 -275.782278) (xy 291.530024 -275.782278)
			(xy 291.530024 -275.28774) (xy 291.530357 -275.282405) (xy 291.537898 -275.27486) (xy 291.543232 -275.274532)
			(xy 291.54374 -275.274532) (xy 292.059614 -275.274532) (xy 292.067426 -275.274236) (xy 292.082298 -275.269439)
			(xy 292.088824 -275.265134) (xy 292.109913 -275.250785) (xy 292.155574 -275.228054) (xy 292.20418 -275.212595)
			(xy 292.254583 -275.204772) (xy 292.305589 -275.204772) (xy 292.355992 -275.212595) (xy 292.404598 -275.228054)
			(xy 292.450259 -275.250785) (xy 292.471348 -275.265134) (xy 292.477873 -275.269436) (xy 292.492748 -275.274214)
			(xy 292.500558 -275.274532) (xy 293.016686 -275.274532) (xy 293.021987 -275.275032) (xy 293.029558 -275.28245)
			(xy 293.030148 -275.28774) (xy 293.030148 -275.782278) (xy 293.030132 -275.782532) (xy 299.074332 -275.782532)
			(xy 299.074332 -275.782024) (xy 299.074332 -275.28774) (xy 299.074658 -275.282403) (xy 299.082203 -275.274858)
			(xy 299.08754 -275.274532) (xy 299.603668 -275.274532) (xy 299.611478 -275.274216) (xy 299.62635 -275.269433)
			(xy 299.632878 -275.265134) (xy 299.653967 -275.250785) (xy 299.699628 -275.228054) (xy 299.748234 -275.212595)
			(xy 299.798637 -275.204772) (xy 299.849643 -275.204772) (xy 299.900046 -275.212595) (xy 299.948652 -275.228054)
			(xy 299.994313 -275.250785) (xy 300.015402 -275.265134) (xy 300.021938 -275.269418) (xy 300.036804 -275.274207)
			(xy 300.044612 -275.274532) (xy 300.56074 -275.274532) (xy 300.566017 -275.274972) (xy 300.57346 -275.28246)
			(xy 300.573948 -275.28774) (xy 300.573948 -275.782278) (xy 306.618132 -275.782278) (xy 306.618132 -275.28774)
			(xy 306.618458 -275.282403) (xy 306.626003 -275.274858) (xy 306.63134 -275.274532) (xy 306.631848 -275.274532)
			(xy 308.104794 -275.274532) (xy 308.110096 -275.275026) (xy 308.117667 -275.282449) (xy 308.118256 -275.28774)
			(xy 308.118256 -275.782278) (xy 308.11824 -275.782532) (xy 415.718244 -275.782532) (xy 415.718244 -275.28774)
			(xy 415.718816 -275.282493) (xy 415.726209 -275.275051) (xy 415.731452 -275.274532) (xy 417.204652 -275.274532)
			(xy 417.209987 -275.274863) (xy 417.217534 -275.282405) (xy 417.21786 -275.28774) (xy 417.21786 -275.782278)
			(xy 423.262044 -275.782278) (xy 423.262044 -275.28774) (xy 423.262616 -275.282493) (xy 423.270009 -275.275051)
			(xy 423.275252 -275.274532) (xy 423.27576 -275.274532) (xy 423.791634 -275.274532) (xy 423.799443 -275.274202)
			(xy 423.814315 -275.269428) (xy 423.820844 -275.265134) (xy 423.841933 -275.250785) (xy 423.887594 -275.228054)
			(xy 423.9362 -275.212595) (xy 423.986603 -275.204772) (xy 424.037609 -275.204772) (xy 424.088012 -275.212595)
			(xy 424.136618 -275.228054) (xy 424.182279 -275.250785) (xy 424.203368 -275.265134) (xy 424.209911 -275.269405)
			(xy 424.224772 -275.274202) (xy 424.232578 -275.274532) (xy 424.748706 -275.274532) (xy 424.754009 -275.275018)
			(xy 424.761579 -275.282447) (xy 424.762168 -275.28774) (xy 424.762168 -275.782278) (xy 424.762151 -275.782532)
			(xy 430.806352 -275.782532) (xy 430.806352 -275.782024) (xy 430.806352 -275.28774) (xy 430.806917 -275.282492)
			(xy 430.814315 -275.275049) (xy 430.81956 -275.274532) (xy 431.335688 -275.274532) (xy 431.343499 -275.274225)
			(xy 431.358371 -275.269435) (xy 431.364898 -275.265134) (xy 431.385987 -275.250785) (xy 431.431648 -275.228054)
			(xy 431.480254 -275.212595) (xy 431.530657 -275.204772) (xy 431.581663 -275.204772) (xy 431.632066 -275.212595)
			(xy 431.680672 -275.228054) (xy 431.726333 -275.250785) (xy 431.747422 -275.265134) (xy 431.753953 -275.269426)
			(xy 431.768823 -275.27421) (xy 431.776632 -275.274532) (xy 432.29276 -275.274532) (xy 432.298097 -275.274858)
			(xy 432.305642 -275.282403) (xy 432.305968 -275.28774) (xy 432.305968 -275.782278) (xy 438.350152 -275.782278)
			(xy 438.350152 -275.28774) (xy 438.350717 -275.282492) (xy 438.358115 -275.275049) (xy 438.36336 -275.274532)
			(xy 438.363868 -275.274532) (xy 438.879742 -275.274532) (xy 438.887551 -275.274205) (xy 438.902423 -275.269429)
			(xy 438.908952 -275.265134) (xy 438.930041 -275.250785) (xy 438.975702 -275.228054) (xy 439.024308 -275.212595)
			(xy 439.074711 -275.204772) (xy 439.125717 -275.204772) (xy 439.17612 -275.212595) (xy 439.224726 -275.228054)
			(xy 439.270387 -275.250785) (xy 439.291476 -275.265134) (xy 439.298017 -275.269408) (xy 439.31288 -275.274203)
			(xy 439.320686 -275.274532) (xy 439.836814 -275.274532) (xy 439.842118 -275.275013) (xy 439.849688 -275.282446)
			(xy 439.850276 -275.28774) (xy 439.850276 -275.782278) (xy 439.850259 -275.782532) (xy 445.89446 -275.782532)
			(xy 445.89446 -275.782024) (xy 445.89446 -275.28774) (xy 445.894851 -275.282421) (xy 445.902351 -275.27488)
			(xy 445.907668 -275.274532) (xy 446.423796 -275.274532) (xy 446.431607 -275.274228) (xy 446.446479 -275.269436)
			(xy 446.453006 -275.265134) (xy 446.474095 -275.250785) (xy 446.519756 -275.228054) (xy 446.568362 -275.212595)
			(xy 446.618765 -275.204772) (xy 446.669771 -275.204772) (xy 446.720174 -275.212595) (xy 446.76878 -275.228054)
			(xy 446.814441 -275.250785) (xy 446.83553 -275.265134) (xy 446.842059 -275.269429) (xy 446.856931 -275.274211)
			(xy 446.86474 -275.274532) (xy 447.380868 -275.274532) (xy 447.386206 -275.274852) (xy 447.393751 -275.282402)
			(xy 447.394076 -275.28774) (xy 447.394076 -275.782278) (xy 447.394051 -275.782532) (xy 453.43826 -275.782532)
			(xy 453.43826 -275.782024) (xy 453.43826 -275.28774) (xy 453.438651 -275.282421) (xy 453.446151 -275.27488)
			(xy 453.451468 -275.274532) (xy 453.967596 -275.274532) (xy 453.975407 -275.274228) (xy 453.990279 -275.269436)
			(xy 453.996806 -275.265134) (xy 454.017895 -275.250785) (xy 454.063556 -275.228054) (xy 454.112162 -275.212595)
			(xy 454.162565 -275.204772) (xy 454.213571 -275.204772) (xy 454.263974 -275.212595) (xy 454.31258 -275.228054)
			(xy 454.358241 -275.250785) (xy 454.37933 -275.265134) (xy 454.385859 -275.269429) (xy 454.400731 -275.274211)
			(xy 454.40854 -275.274532) (xy 454.924668 -275.274532) (xy 454.930006 -275.274852) (xy 454.937551 -275.282402)
			(xy 454.937876 -275.28774) (xy 454.937876 -275.782278) (xy 454.937364 -275.787576) (xy 454.929954 -275.795147)
			(xy 454.924668 -275.79574) (xy 454.408794 -275.79574) (xy 454.400983 -275.796044) (xy 454.386111 -275.800836)
			(xy 454.379584 -275.805138) (xy 454.358463 -275.819489) (xy 454.312739 -275.842216) (xy 454.264066 -275.857645)
			(xy 454.213599 -275.865411) (xy 454.188068 -275.865844) (xy 454.162537 -275.865427) (xy 454.112072 -275.857646)
			(xy 454.0634 -275.842211) (xy 454.017673 -275.819488) (xy 453.996552 -275.805138) (xy 453.990028 -275.800833)
			(xy 453.975152 -275.796058) (xy 453.967342 -275.79574) (xy 453.451468 -275.79574) (xy 453.446209 -275.79523)
			(xy 453.43877 -275.787791) (xy 453.43826 -275.782532) (xy 447.394051 -275.782532) (xy 447.393564 -275.787576)
			(xy 447.386154 -275.795147) (xy 447.380868 -275.79574) (xy 446.864994 -275.79574) (xy 446.857183 -275.796044)
			(xy 446.842311 -275.800836) (xy 446.835784 -275.805138) (xy 446.814663 -275.819489) (xy 446.768939 -275.842216)
			(xy 446.720266 -275.857645) (xy 446.669799 -275.865411) (xy 446.644268 -275.865844) (xy 446.618737 -275.865427)
			(xy 446.568272 -275.857646) (xy 446.5196 -275.842211) (xy 446.473873 -275.819488) (xy 446.452752 -275.805138)
			(xy 446.446228 -275.800833) (xy 446.431352 -275.796058) (xy 446.423542 -275.79574) (xy 445.907668 -275.79574)
			(xy 445.902409 -275.79523) (xy 445.89497 -275.787791) (xy 445.89446 -275.782532) (xy 439.850259 -275.782532)
			(xy 439.849907 -275.787706) (xy 439.842241 -275.795393) (xy 439.836814 -275.79574) (xy 439.32094 -275.79574)
			(xy 439.313131 -275.796064) (xy 439.298259 -275.800842) (xy 439.29173 -275.805138) (xy 439.270624 -275.819512)
			(xy 439.224895 -275.842234) (xy 439.176217 -275.857657) (xy 439.125746 -275.865415) (xy 439.100214 -275.865844)
			(xy 439.074684 -275.865404) (xy 439.02422 -275.85763) (xy 438.975547 -275.842202) (xy 438.92982 -275.819486)
			(xy 438.908698 -275.805138) (xy 438.902164 -275.800851) (xy 438.887296 -275.796065) (xy 438.879488 -275.79574)
			(xy 438.363614 -275.79574) (xy 438.358176 -275.795409) (xy 438.350488 -275.787716) (xy 438.350152 -275.782278)
			(xy 432.305968 -275.782278) (xy 432.305463 -275.787578) (xy 432.298049 -275.79515) (xy 432.29276 -275.79574)
			(xy 431.776886 -275.79574) (xy 431.769075 -275.796041) (xy 431.754203 -275.800835) (xy 431.747676 -275.805138)
			(xy 431.726558 -275.819492) (xy 431.680833 -275.842218) (xy 431.632158 -275.857647) (xy 431.581691 -275.865412)
			(xy 431.55616 -275.865844) (xy 431.530629 -275.865431) (xy 431.480164 -275.857649) (xy 431.431491 -275.842213)
			(xy 431.385765 -275.819489) (xy 431.364644 -275.805138) (xy 431.358122 -275.80083) (xy 431.343245 -275.796057)
			(xy 431.335434 -275.79574) (xy 430.81956 -275.79574) (xy 430.8143 -275.795235) (xy 430.806862 -275.787792)
			(xy 430.806352 -275.782532) (xy 424.762151 -275.782532) (xy 424.761806 -275.787708) (xy 424.754136 -275.795395)
			(xy 424.748706 -275.79574) (xy 424.232832 -275.79574) (xy 424.225022 -275.796061) (xy 424.210151 -275.800841)
			(xy 424.203622 -275.805138) (xy 424.182491 -275.819472) (xy 424.13677 -275.842203) (xy 424.0881 -275.857637)
			(xy 424.037636 -275.865408) (xy 424.012106 -275.865844) (xy 423.986576 -275.865408) (xy 423.936112 -275.857633)
			(xy 423.887439 -275.842203) (xy 423.841712 -275.819486) (xy 423.82059 -275.805138) (xy 423.814058 -275.800848)
			(xy 423.799188 -275.796064) (xy 423.79138 -275.79574) (xy 423.275506 -275.79574) (xy 423.270067 -275.795415)
			(xy 423.262379 -275.787718) (xy 423.262044 -275.782278) (xy 417.21786 -275.782278) (xy 417.217362 -275.78758)
			(xy 417.209943 -275.795152) (xy 417.204652 -275.79574) (xy 415.731452 -275.79574) (xy 415.726191 -275.79524)
			(xy 415.718753 -275.787793) (xy 415.718244 -275.782532) (xy 308.11824 -275.782532) (xy 308.117905 -275.787711)
			(xy 308.110227 -275.795399) (xy 308.104794 -275.79574) (xy 306.631594 -275.79574) (xy 306.626153 -275.795422)
			(xy 306.618466 -275.78772) (xy 306.618132 -275.782278) (xy 300.573948 -275.782278) (xy 300.573461 -275.787582)
			(xy 300.566034 -275.795156) (xy 300.56074 -275.79574) (xy 300.044866 -275.79574) (xy 300.037058 -275.796075)
			(xy 300.022186 -275.800846) (xy 300.015656 -275.805138) (xy 299.994543 -275.819501) (xy 299.948816 -275.842225)
			(xy 299.90014 -275.857651) (xy 299.849672 -275.865413) (xy 299.82414 -275.865844) (xy 299.79861 -275.865391)
			(xy 299.748147 -275.857621) (xy 299.699474 -275.842196) (xy 299.653746 -275.819484) (xy 299.632624 -275.805138)
			(xy 299.626084 -275.800861) (xy 299.611221 -275.796069) (xy 299.603414 -275.79574) (xy 299.08754 -275.79574)
			(xy 299.082221 -275.795349) (xy 299.07468 -275.787849) (xy 299.074332 -275.782532) (xy 293.030132 -275.782532)
			(xy 293.029804 -275.787713) (xy 293.022121 -275.795401) (xy 293.016686 -275.79574) (xy 292.500812 -275.79574)
			(xy 292.493002 -275.796052) (xy 292.47813 -275.800838) (xy 292.471602 -275.805138) (xy 292.450476 -275.819481)
			(xy 292.404754 -275.842209) (xy 292.356082 -275.857641) (xy 292.305617 -275.86541) (xy 292.280086 -275.865844)
			(xy 292.254555 -275.865418) (xy 292.204091 -275.85764) (xy 292.155418 -275.842207) (xy 292.109691 -275.819487)
			(xy 292.08857 -275.805138) (xy 292.082042 -275.80084) (xy 292.067169 -275.796061) (xy 292.05936 -275.79574)
			(xy 291.543486 -275.79574) (xy 291.538044 -275.795428) (xy 291.530358 -275.787721) (xy 291.530024 -275.782278)
			(xy 285.48584 -275.782278) (xy 285.48536 -275.787584) (xy 285.477928 -275.795158) (xy 285.472632 -275.79574)
			(xy 284.956758 -275.79574) (xy 284.948949 -275.796072) (xy 284.934078 -275.800845) (xy 284.927548 -275.805138)
			(xy 284.906437 -275.819504) (xy 284.86071 -275.842228) (xy 284.812033 -275.857653) (xy 284.761564 -275.865414)
			(xy 284.736032 -275.865844) (xy 284.710502 -275.865395) (xy 284.660039 -275.857624) (xy 284.611366 -275.842198)
			(xy 284.565638 -275.819484) (xy 284.544516 -275.805138) (xy 284.537978 -275.800858) (xy 284.523113 -275.796067)
			(xy 284.515306 -275.79574) (xy 283.999432 -275.79574) (xy 283.994181 -275.795187) (xy 283.986738 -275.787781)
			(xy 283.986224 -275.782532) (xy 277.942017 -275.782532) (xy 277.94156 -275.787584) (xy 277.934128 -275.795158)
			(xy 277.928832 -275.79574) (xy 277.412958 -275.79574) (xy 277.405149 -275.796072) (xy 277.390278 -275.800845)
			(xy 277.383748 -275.805138) (xy 277.362637 -275.819504) (xy 277.31691 -275.842228) (xy 277.268233 -275.857653)
			(xy 277.217764 -275.865414) (xy 277.192232 -275.865844) (xy 277.166702 -275.865395) (xy 277.116239 -275.857624)
			(xy 277.067566 -275.842198) (xy 277.021838 -275.819484) (xy 277.000716 -275.805138) (xy 276.994178 -275.800858)
			(xy 276.979313 -275.796067) (xy 276.971506 -275.79574) (xy 276.455632 -275.79574) (xy 276.450381 -275.795187)
			(xy 276.442938 -275.787781) (xy 276.442424 -275.782532) (xy 270.398224 -275.782532) (xy 270.397904 -275.787715)
			(xy 270.390215 -275.795404) (xy 270.384778 -275.79574) (xy 269.868904 -275.79574) (xy 269.861093 -275.796048)
			(xy 269.846222 -275.800837) (xy 269.839694 -275.805138) (xy 269.818571 -275.819484) (xy 269.772847 -275.842212)
			(xy 269.724175 -275.857643) (xy 269.673709 -275.865411) (xy 269.648178 -275.865844) (xy 269.622647 -275.865422)
			(xy 269.572183 -275.857642) (xy 269.52351 -275.842209) (xy 269.477783 -275.819488) (xy 269.456662 -275.805138)
			(xy 269.450136 -275.800837) (xy 269.435262 -275.79606) (xy 269.427452 -275.79574) (xy 268.911578 -275.79574)
			(xy 268.906206 -275.795262) (xy 268.89862 -275.787652) (xy 268.898116 -275.782278) (xy 206.997808 -275.782278)
			(xy 206.997808 -275.782532) (xy 206.997327 -275.787799) (xy 206.989868 -275.795239) (xy 206.9846 -275.79574)
			(xy 206.468726 -275.79574) (xy 206.460849 -275.796005) (xy 206.445846 -275.800804) (xy 206.439262 -275.805138)
			(xy 206.418185 -275.81953) (xy 206.37254 -275.842358) (xy 206.323934 -275.857916) (xy 206.273517 -275.865835)
			(xy 206.248 -275.866352) (xy 206.22248 -275.86587) (xy 206.172053 -275.857972) (xy 206.123441 -275.842409)
			(xy 206.077803 -275.819553) (xy 206.056738 -275.805138) (xy 206.050137 -275.800839) (xy 206.035144 -275.796042)
			(xy 206.027274 -275.79574) (xy 205.5114 -275.79574) (xy 205.506145 -275.795208) (xy 205.498704 -275.787786)
			(xy 205.498192 -275.782532) (xy 199.454008 -275.782532) (xy 199.453527 -275.787799) (xy 199.446068 -275.795239)
			(xy 199.4408 -275.79574) (xy 198.924926 -275.79574) (xy 198.917049 -275.796005) (xy 198.902046 -275.800804)
			(xy 198.895462 -275.805138) (xy 198.874385 -275.81953) (xy 198.82874 -275.842358) (xy 198.780134 -275.857916)
			(xy 198.729717 -275.865835) (xy 198.7042 -275.866352) (xy 198.67868 -275.86587) (xy 198.628253 -275.857972)
			(xy 198.579641 -275.842409) (xy 198.534003 -275.819553) (xy 198.512938 -275.805138) (xy 198.506337 -275.800839)
			(xy 198.491344 -275.796042) (xy 198.483474 -275.79574) (xy 197.9676 -275.79574) (xy 197.962345 -275.795208)
			(xy 197.954904 -275.787786) (xy 197.954392 -275.782532) (xy 191.910208 -275.782532) (xy 191.909727 -275.787799)
			(xy 191.902268 -275.795239) (xy 191.897 -275.79574) (xy 191.896492 -275.79574) (xy 191.380872 -275.79574)
			(xy 191.372997 -275.796025) (xy 191.357993 -275.800811) (xy 191.351408 -275.805138) (xy 191.330346 -275.819553)
			(xy 191.284696 -275.842376) (xy 191.236085 -275.857928) (xy 191.185664 -275.865839) (xy 191.160146 -275.866352)
			(xy 191.134627 -275.865847) (xy 191.084201 -275.857955) (xy 191.035589 -275.8424) (xy 190.98995 -275.81955)
			(xy 190.968884 -275.805138) (xy 190.962296 -275.800818) (xy 190.947293 -275.796034) (xy 190.93942 -275.79574)
			(xy 190.423546 -275.79574) (xy 190.418243 -275.795244) (xy 190.410668 -275.787824) (xy 190.410084 -275.782532)
			(xy 184.3659 -275.782532) (xy 184.365426 -275.787801) (xy 184.357962 -275.795242) (xy 184.352692 -275.79574)
			(xy 183.836818 -275.79574) (xy 183.828945 -275.796045) (xy 183.813941 -275.800817) (xy 183.807354 -275.805138)
			(xy 183.786279 -275.819533) (xy 183.740633 -275.842361) (xy 183.692027 -275.857918) (xy 183.641609 -275.865836)
			(xy 183.616092 -275.866352) (xy 183.590573 -275.865824) (xy 183.540149 -275.857939) (xy 183.491537 -275.84239)
			(xy 183.445897 -275.819547) (xy 183.42483 -275.805138) (xy 183.418231 -275.800836) (xy 183.403237 -275.79604)
			(xy 183.395366 -275.79574) (xy 182.879492 -275.79574) (xy 182.874236 -275.795214) (xy 182.866796 -275.787787)
			(xy 182.866284 -275.782532) (xy 176.8221 -275.782532) (xy 176.821626 -275.787801) (xy 176.814162 -275.795242)
			(xy 176.808892 -275.79574) (xy 176.808384 -275.79574) (xy 176.292764 -275.79574) (xy 176.284889 -275.796021)
			(xy 176.269885 -275.800809) (xy 176.2633 -275.805138) (xy 176.242212 -275.819513) (xy 176.196571 -275.842346)
			(xy 176.147968 -275.857908) (xy 176.097554 -275.865832) (xy 176.072038 -275.866352) (xy 176.046518 -275.865851)
			(xy 175.996092 -275.857958) (xy 175.947481 -275.842401) (xy 175.901842 -275.819551) (xy 175.880776 -275.805138)
			(xy 175.874189 -275.800815) (xy 175.859186 -275.796032) (xy 175.851312 -275.79574) (xy 175.335438 -275.79574)
			(xy 175.330134 -275.795249) (xy 175.322559 -275.787826) (xy 175.321976 -275.782532) (xy 169.277792 -275.782532)
			(xy 169.277325 -275.787802) (xy 169.269856 -275.795244) (xy 169.264584 -275.79574) (xy 167.791384 -275.79574)
			(xy 167.786127 -275.795219) (xy 167.778687 -275.787788) (xy 167.778176 -275.782532) (xy 60.178188 -275.782532)
			(xy 60.177725 -275.787803) (xy 60.170253 -275.795245) (xy 60.16498 -275.79574) (xy 60.164472 -275.79574)
			(xy 58.691526 -275.79574) (xy 58.68622 -275.795257) (xy 58.678647 -275.787827) (xy 58.678064 -275.782532)
			(xy 52.63388 -275.782532) (xy 52.633424 -275.787805) (xy 52.625948 -275.795248) (xy 52.620672 -275.79574)
			(xy 52.104798 -275.79574) (xy 52.096924 -275.796036) (xy 52.08192 -275.800814) (xy 52.075334 -275.805138)
			(xy 52.054265 -275.819542) (xy 52.008617 -275.842368) (xy 51.960008 -275.857922) (xy 51.909589 -275.865837)
			(xy 51.884072 -275.866352) (xy 51.858553 -275.865834) (xy 51.808128 -275.857946) (xy 51.759516 -275.842394)
			(xy 51.713876 -275.819549) (xy 51.69281 -275.805138) (xy 51.686216 -275.800828) (xy 51.671218 -275.796037)
			(xy 51.663346 -275.79574) (xy 51.147472 -275.79574) (xy 51.142214 -275.795227) (xy 51.134774 -275.78779)
			(xy 51.134264 -275.782532) (xy 45.09008 -275.782532) (xy 45.089624 -275.787805) (xy 45.082148 -275.795248)
			(xy 45.076872 -275.79574) (xy 45.076364 -275.79574) (xy 44.560744 -275.79574) (xy 44.552868 -275.796013)
			(xy 44.537864 -275.800807) (xy 44.53128 -275.805138) (xy 44.510198 -275.819522) (xy 44.464555 -275.842352)
			(xy 44.41595 -275.857912) (xy 44.365534 -275.865834) (xy 44.340018 -275.866352) (xy 44.314498 -275.865861)
			(xy 44.264072 -275.857965) (xy 44.21546 -275.842405) (xy 44.169821 -275.819552) (xy 44.148756 -275.805138)
			(xy 44.142174 -275.800807) (xy 44.127167 -275.79603) (xy 44.119292 -275.79574) (xy 43.603418 -275.79574)
			(xy 43.598111 -275.795263) (xy 43.590538 -275.787829) (xy 43.589956 -275.782532) (xy 37.545772 -275.782532)
			(xy 37.545491 -275.787877) (xy 37.537911 -275.795418) (xy 37.532564 -275.79574) (xy 37.01669 -275.79574)
			(xy 37.008816 -275.796033) (xy 36.993812 -275.800813) (xy 36.987226 -275.805138) (xy 36.966159 -275.819545)
			(xy 36.92051 -275.84237) (xy 36.871901 -275.857924) (xy 36.821482 -275.865838) (xy 36.795964 -275.866352)
			(xy 36.770445 -275.865838) (xy 36.720019 -275.857949) (xy 36.671408 -275.842396) (xy 36.625768 -275.819549)
			(xy 36.604702 -275.805138) (xy 36.598109 -275.800825) (xy 36.58311 -275.796036) (xy 36.575238 -275.79574)
			(xy 36.059364 -275.79574) (xy 36.054105 -275.795232) (xy 36.046666 -275.787791) (xy 36.046156 -275.782532)
			(xy 30.001972 -275.782532) (xy 30.001691 -275.787877) (xy 29.994111 -275.795418) (xy 29.988764 -275.79574)
			(xy 29.47289 -275.79574) (xy 29.465016 -275.796033) (xy 29.450012 -275.800813) (xy 29.443426 -275.805138)
			(xy 29.422359 -275.819545) (xy 29.37671 -275.84237) (xy 29.328101 -275.857924) (xy 29.277682 -275.865838)
			(xy 29.252164 -275.866352) (xy 29.226645 -275.865838) (xy 29.176219 -275.857949) (xy 29.127608 -275.842396)
			(xy 29.081968 -275.819549) (xy 29.060902 -275.805138) (xy 29.054309 -275.800825) (xy 29.03931 -275.796036)
			(xy 29.031438 -275.79574) (xy 28.515564 -275.79574) (xy 28.510305 -275.795232) (xy 28.502866 -275.787791)
			(xy 28.502356 -275.782532) (xy 22.458172 -275.782532) (xy 22.457891 -275.787877) (xy 22.450311 -275.795418)
			(xy 22.444964 -275.79574) (xy 22.444456 -275.79574) (xy 21.928836 -275.79574) (xy 21.92096 -275.796009)
			(xy 21.905956 -275.800806) (xy 21.899372 -275.805138) (xy 21.878292 -275.819525) (xy 21.832648 -275.842355)
			(xy 21.784043 -275.857914) (xy 21.733626 -275.865834) (xy 21.70811 -275.866352) (xy 21.68259 -275.865865)
			(xy 21.632163 -275.857968) (xy 21.583552 -275.842407) (xy 21.537913 -275.819553) (xy 21.516848 -275.805138)
			(xy 21.510268 -275.800804) (xy 21.495259 -275.796028) (xy 21.487384 -275.79574) (xy 20.97151 -275.79574)
			(xy 20.966202 -275.795268) (xy 20.958629 -275.78783) (xy 20.958048 -275.782532) (xy 2.509012 -275.782532)
			(xy 2.509012 -276.632416) (xy 16.85798 -276.632416) (xy 16.85798 -276.137878) (xy 16.858269 -276.13243)
			(xy 16.865992 -276.124743) (xy 16.871442 -276.124416) (xy 17.38757 -276.124416) (xy 17.39538 -276.124104)
			(xy 17.410252 -276.119318) (xy 17.41678 -276.115018) (xy 17.437869 -276.100669) (xy 17.48353 -276.077938)
			(xy 17.532136 -276.062479) (xy 17.582539 -276.054656) (xy 17.633545 -276.054656) (xy 17.683948 -276.062479)
			(xy 17.732554 -276.077938) (xy 17.778215 -276.100669) (xy 17.799304 -276.115018) (xy 17.80584 -276.119302)
			(xy 17.820706 -276.124091) (xy 17.828514 -276.124416) (xy 18.344642 -276.124416) (xy 18.350006 -276.12492)
			(xy 18.357588 -276.132514) (xy 18.358104 -276.137878) (xy 18.358104 -276.632416) (xy 20.958048 -276.632416)
			(xy 20.958048 -276.137878) (xy 20.958537 -276.132509) (xy 20.96614 -276.124924) (xy 20.97151 -276.124416)
			(xy 21.487638 -276.124416) (xy 21.495447 -276.12409) (xy 21.510319 -276.119314) (xy 21.516848 -276.115018)
			(xy 21.537937 -276.100669) (xy 21.583598 -276.077938) (xy 21.632204 -276.062479) (xy 21.682607 -276.054656)
			(xy 21.733613 -276.054656) (xy 21.784016 -276.062479) (xy 21.832622 -276.077938) (xy 21.878283 -276.100669)
			(xy 21.899372 -276.115018) (xy 21.905915 -276.119289) (xy 21.920776 -276.124086) (xy 21.928582 -276.124416)
			(xy 22.44471 -276.124416) (xy 22.45007 -276.124942) (xy 22.457654 -276.132519) (xy 22.458172 -276.137878)
			(xy 22.458172 -276.632416) (xy 24.402288 -276.632416) (xy 24.402288 -276.137878) (xy 24.402714 -276.13256)
			(xy 24.410185 -276.124987) (xy 24.415496 -276.124416) (xy 24.931624 -276.124416) (xy 24.939437 -276.124126)
			(xy 24.954308 -276.119325) (xy 24.960834 -276.115018) (xy 24.981923 -276.100669) (xy 25.027584 -276.077938)
			(xy 25.07619 -276.062479) (xy 25.126593 -276.054656) (xy 25.177599 -276.054656) (xy 25.228002 -276.062479)
			(xy 25.276608 -276.077938) (xy 25.322269 -276.100669) (xy 25.343358 -276.115018) (xy 25.349882 -276.119322)
			(xy 25.364758 -276.124099) (xy 25.372568 -276.124416) (xy 25.888696 -276.124416) (xy 25.894034 -276.124732)
			(xy 25.901576 -276.132286) (xy 25.901904 -276.137624) (xy 25.901904 -276.138132) (xy 25.901904 -276.632416)
			(xy 28.502356 -276.632416) (xy 28.502356 -276.137878) (xy 28.50281 -276.132567) (xy 28.510262 -276.124997)
			(xy 28.515564 -276.124416) (xy 29.031692 -276.124416) (xy 29.039503 -276.124113) (xy 29.054375 -276.119321)
			(xy 29.060902 -276.115018) (xy 29.081991 -276.100669) (xy 29.127652 -276.077938) (xy 29.176258 -276.062479)
			(xy 29.226661 -276.054656) (xy 29.277667 -276.054656) (xy 29.32807 -276.062479) (xy 29.376676 -276.077938)
			(xy 29.422337 -276.100669) (xy 29.443426 -276.115018) (xy 29.449957 -276.11931) (xy 29.464827 -276.124094)
			(xy 29.472636 -276.124416) (xy 29.988764 -276.124416) (xy 29.994097 -276.124753) (xy 30.001642 -276.132291)
			(xy 30.001972 -276.137624) (xy 30.001972 -276.138132) (xy 30.001972 -276.632416) (xy 31.946088 -276.632416)
			(xy 31.946088 -276.137878) (xy 31.946514 -276.13256) (xy 31.953985 -276.124987) (xy 31.959296 -276.124416)
			(xy 32.475424 -276.124416) (xy 32.483237 -276.124126) (xy 32.498108 -276.119325) (xy 32.504634 -276.115018)
			(xy 32.525723 -276.100669) (xy 32.571384 -276.077938) (xy 32.61999 -276.062479) (xy 32.670393 -276.054656)
			(xy 32.721399 -276.054656) (xy 32.771802 -276.062479) (xy 32.820408 -276.077938) (xy 32.866069 -276.100669)
			(xy 32.887158 -276.115018) (xy 32.893682 -276.119322) (xy 32.908558 -276.124099) (xy 32.916368 -276.124416)
			(xy 33.432496 -276.124416) (xy 33.437834 -276.124732) (xy 33.445376 -276.132286) (xy 33.445704 -276.137624)
			(xy 33.445704 -276.138132) (xy 33.445704 -276.632416) (xy 36.046156 -276.632416) (xy 36.046156 -276.137878)
			(xy 36.04661 -276.132567) (xy 36.054062 -276.124997) (xy 36.059364 -276.124416) (xy 36.575492 -276.124416)
			(xy 36.583303 -276.124113) (xy 36.598175 -276.119321) (xy 36.604702 -276.115018) (xy 36.625791 -276.100669)
			(xy 36.671452 -276.077938) (xy 36.720058 -276.062479) (xy 36.770461 -276.054656) (xy 36.821467 -276.054656)
			(xy 36.87187 -276.062479) (xy 36.920476 -276.077938) (xy 36.966137 -276.100669) (xy 36.987226 -276.115018)
			(xy 36.993757 -276.11931) (xy 37.008627 -276.124094) (xy 37.016436 -276.124416) (xy 37.532564 -276.124416)
			(xy 37.537897 -276.124753) (xy 37.545442 -276.132291) (xy 37.545772 -276.137624) (xy 37.545772 -276.138132)
			(xy 37.545772 -276.632416) (xy 39.489888 -276.632416) (xy 39.489888 -276.137878) (xy 39.490431 -276.132523)
			(xy 39.497997 -276.124942) (xy 39.50335 -276.124416) (xy 40.019478 -276.124416) (xy 40.027289 -276.124107)
			(xy 40.042161 -276.119319) (xy 40.048688 -276.115018) (xy 40.069777 -276.100669) (xy 40.115438 -276.077938)
			(xy 40.164044 -276.062479) (xy 40.214447 -276.054656) (xy 40.265453 -276.054656) (xy 40.315856 -276.062479)
			(xy 40.364462 -276.077938) (xy 40.410123 -276.100669) (xy 40.431212 -276.115018) (xy 40.437746 -276.119305)
			(xy 40.452614 -276.124092) (xy 40.460422 -276.124416) (xy 40.97655 -276.124416) (xy 40.981915 -276.124915)
			(xy 40.989496 -276.132512) (xy 40.990012 -276.137878) (xy 40.990012 -276.632416) (xy 43.589956 -276.632416)
			(xy 43.589956 -276.137878) (xy 43.590438 -276.132507) (xy 43.598046 -276.124922) (xy 43.603418 -276.124416)
			(xy 44.119546 -276.124416) (xy 44.127356 -276.124094) (xy 44.142228 -276.119315) (xy 44.148756 -276.115018)
			(xy 44.169845 -276.100669) (xy 44.215506 -276.077938) (xy 44.264112 -276.062479) (xy 44.314515 -276.054656)
			(xy 44.365521 -276.054656) (xy 44.415924 -276.062479) (xy 44.46453 -276.077938) (xy 44.510191 -276.100669)
			(xy 44.53128 -276.115018) (xy 44.537821 -276.119293) (xy 44.552684 -276.124087) (xy 44.56049 -276.124416)
			(xy 45.076618 -276.124416) (xy 45.081979 -276.124936) (xy 45.089562 -276.132517) (xy 45.09008 -276.137878)
			(xy 45.09008 -276.632416) (xy 47.034196 -276.632416) (xy 47.034196 -276.137878) (xy 47.034703 -276.132581)
			(xy 47.042118 -276.125014) (xy 47.047404 -276.124416) (xy 47.563532 -276.124416) (xy 47.571341 -276.124088)
			(xy 47.586213 -276.119313) (xy 47.592742 -276.115018) (xy 47.613831 -276.100669) (xy 47.659492 -276.077938)
			(xy 47.708098 -276.062479) (xy 47.758501 -276.054656) (xy 47.809507 -276.054656) (xy 47.85991 -276.062479)
			(xy 47.908516 -276.077938) (xy 47.954177 -276.100669) (xy 47.975266 -276.115018) (xy 47.981811 -276.119287)
			(xy 47.99667 -276.124085) (xy 48.004476 -276.124416) (xy 48.520604 -276.124416) (xy 48.525943 -276.124727)
			(xy 48.533485 -276.132285) (xy 48.533812 -276.137624) (xy 48.533812 -276.138132) (xy 48.533812 -276.632416)
			(xy 51.134264 -276.632416) (xy 51.134264 -276.137878) (xy 51.134711 -276.132566) (xy 51.142168 -276.124994)
			(xy 51.147472 -276.124416) (xy 51.6636 -276.124416) (xy 51.671412 -276.124116) (xy 51.686283 -276.119322)
			(xy 51.69281 -276.115018) (xy 51.713899 -276.100669) (xy 51.75956 -276.077938) (xy 51.808166 -276.062479)
			(xy 51.858569 -276.054656) (xy 51.909575 -276.054656) (xy 51.959978 -276.062479) (xy 52.008584 -276.077938)
			(xy 52.054245 -276.100669) (xy 52.075334 -276.115018) (xy 52.081863 -276.119313) (xy 52.096735 -276.124095)
			(xy 52.104544 -276.124416) (xy 52.620672 -276.124416) (xy 52.626006 -276.124748) (xy 52.633551 -276.13229)
			(xy 52.63388 -276.137624) (xy 52.63388 -276.138132) (xy 52.63388 -276.632416) (xy 54.577996 -276.632416)
			(xy 54.577996 -276.137878) (xy 54.578532 -276.132522) (xy 54.586102 -276.12494) (xy 54.591458 -276.124416)
			(xy 56.064658 -276.124416) (xy 56.070082 -276.124805) (xy 56.077769 -276.132456) (xy 56.07812 -276.137878)
			(xy 56.07812 -276.632416) (xy 58.678064 -276.632416) (xy 58.678064 -276.137878) (xy 58.678367 -276.132434)
			(xy 58.686081 -276.124748) (xy 58.691526 -276.124416) (xy 60.164726 -276.124416) (xy 60.170088 -276.124931)
			(xy 60.177671 -276.132516) (xy 60.178188 -276.137878) (xy 60.178188 -276.632416) (xy 163.678108 -276.632416)
			(xy 163.678108 -276.137878) (xy 163.678605 -276.132579) (xy 163.686027 -276.125011) (xy 163.691316 -276.124416)
			(xy 165.164516 -276.124416) (xy 165.169856 -276.124718) (xy 165.177398 -276.132283) (xy 165.177724 -276.137624)
			(xy 165.177724 -276.138132) (xy 165.177724 -276.632416) (xy 167.778176 -276.632416) (xy 167.778176 -276.137878)
			(xy 167.778613 -276.132563) (xy 167.786076 -276.124991) (xy 167.791384 -276.124416) (xy 169.264584 -276.124416)
			(xy 169.26992 -276.12474) (xy 169.277463 -276.132288) (xy 169.277792 -276.137624) (xy 169.277792 -276.632416)
			(xy 171.221908 -276.632416) (xy 171.221908 -276.137878) (xy 171.222433 -276.132519) (xy 171.230011 -276.124936)
			(xy 171.23537 -276.124416) (xy 171.751498 -276.124416) (xy 171.75931 -276.124116) (xy 171.774181 -276.119322)
			(xy 171.780708 -276.115018) (xy 171.801797 -276.100669) (xy 171.847458 -276.077938) (xy 171.896064 -276.062479)
			(xy 171.946467 -276.054656) (xy 171.997473 -276.054656) (xy 172.047876 -276.062479) (xy 172.096482 -276.077938)
			(xy 172.142143 -276.100669) (xy 172.163232 -276.115018) (xy 172.169762 -276.119312) (xy 172.184633 -276.124095)
			(xy 172.192442 -276.124416) (xy 172.70857 -276.124416) (xy 172.713995 -276.124797) (xy 172.721682 -276.132454)
			(xy 172.722032 -276.137878) (xy 172.722032 -276.632416) (xy 175.321976 -276.632416) (xy 175.321976 -276.137878)
			(xy 175.322268 -276.132431) (xy 175.329989 -276.124744) (xy 175.335438 -276.124416) (xy 175.851566 -276.124416)
			(xy 175.859376 -276.124102) (xy 175.874248 -276.119318) (xy 175.880776 -276.115018) (xy 175.901865 -276.100669)
			(xy 175.947526 -276.077938) (xy 175.996132 -276.062479) (xy 176.046535 -276.054656) (xy 176.097541 -276.054656)
			(xy 176.147944 -276.062479) (xy 176.19655 -276.077938) (xy 176.242211 -276.100669) (xy 176.2633 -276.115018)
			(xy 176.269837 -276.1193) (xy 176.284703 -276.12409) (xy 176.29251 -276.124416) (xy 176.808638 -276.124416)
			(xy 176.814001 -276.124923) (xy 176.821583 -276.132514) (xy 176.8221 -276.137878) (xy 176.8221 -276.632416)
			(xy 178.766216 -276.632416) (xy 178.766216 -276.137878) (xy 178.766706 -276.132577) (xy 178.774133 -276.125008)
			(xy 178.779424 -276.124416) (xy 179.295552 -276.124416) (xy 179.303362 -276.124096) (xy 179.318234 -276.119316)
			(xy 179.324762 -276.115018) (xy 179.345851 -276.100669) (xy 179.391512 -276.077938) (xy 179.440118 -276.062479)
			(xy 179.490521 -276.054656) (xy 179.541527 -276.054656) (xy 179.59193 -276.062479) (xy 179.640536 -276.077938)
			(xy 179.686197 -276.100669) (xy 179.707286 -276.115018) (xy 179.713826 -276.119295) (xy 179.728689 -276.124088)
			(xy 179.736496 -276.124416) (xy 180.252624 -276.124416) (xy 180.257895 -276.124881) (xy 180.265338 -276.132351)
			(xy 180.265832 -276.137624) (xy 180.265832 -276.138132) (xy 180.265832 -276.632416) (xy 182.866284 -276.632416)
			(xy 182.866284 -276.137878) (xy 182.866714 -276.132561) (xy 182.874182 -276.124988) (xy 182.879492 -276.124416)
			(xy 183.39562 -276.124416) (xy 183.403432 -276.124125) (xy 183.418304 -276.119325) (xy 183.42483 -276.115018)
			(xy 183.445919 -276.100669) (xy 183.49158 -276.077938) (xy 183.540186 -276.062479) (xy 183.590589 -276.054656)
			(xy 183.641595 -276.054656) (xy 183.691998 -276.062479) (xy 183.740604 -276.077938) (xy 183.786265 -276.100669)
			(xy 183.807354 -276.115018) (xy 183.813879 -276.119321) (xy 183.828754 -276.124098) (xy 183.836564 -276.124416)
			(xy 184.352692 -276.124416) (xy 184.358029 -276.124734) (xy 184.365572 -276.132287) (xy 184.3659 -276.137624)
			(xy 184.3659 -276.138132) (xy 184.3659 -276.632416) (xy 186.310016 -276.632416) (xy 186.310016 -276.137878)
			(xy 186.310534 -276.132517) (xy 186.318117 -276.124934) (xy 186.323478 -276.124416) (xy 186.839606 -276.124416)
			(xy 186.847418 -276.124119) (xy 186.86229 -276.119323) (xy 186.868816 -276.115018) (xy 186.889905 -276.100669)
			(xy 186.935566 -276.077938) (xy 186.984172 -276.062479) (xy 187.034575 -276.054656) (xy 187.085581 -276.054656)
			(xy 187.135984 -276.062479) (xy 187.18459 -276.077938) (xy 187.230251 -276.100669) (xy 187.25134 -276.115018)
			(xy 187.257868 -276.119316) (xy 187.272741 -276.124096) (xy 187.28055 -276.124416) (xy 187.796678 -276.124416)
			(xy 187.802034 -276.124963) (xy 187.80962 -276.132524) (xy 187.81014 -276.137878) (xy 187.81014 -276.632416)
			(xy 190.410084 -276.632416) (xy 190.410084 -276.137878) (xy 190.410369 -276.132429) (xy 190.418095 -276.124742)
			(xy 190.423546 -276.124416) (xy 190.939674 -276.124416) (xy 190.947485 -276.124105) (xy 190.962357 -276.119319)
			(xy 190.968884 -276.115018) (xy 190.989973 -276.100669) (xy 191.035634 -276.077938) (xy 191.08424 -276.062479)
			(xy 191.134643 -276.054656) (xy 191.185649 -276.054656) (xy 191.236052 -276.062479) (xy 191.284658 -276.077938)
			(xy 191.330319 -276.100669) (xy 191.351408 -276.115018) (xy 191.357943 -276.119303) (xy 191.37281 -276.124092)
			(xy 191.380618 -276.124416) (xy 191.896746 -276.124416) (xy 191.90211 -276.124918) (xy 191.909692 -276.132513)
			(xy 191.910208 -276.137878) (xy 191.910208 -276.632416) (xy 193.854324 -276.632416) (xy 193.854324 -276.137878)
			(xy 193.854807 -276.132575) (xy 193.862239 -276.125006) (xy 193.867532 -276.124416) (xy 194.38366 -276.124416)
			(xy 194.39147 -276.124099) (xy 194.406342 -276.119317) (xy 194.41287 -276.115018) (xy 194.433959 -276.100669)
			(xy 194.47962 -276.077938) (xy 194.528226 -276.062479) (xy 194.578629 -276.054656) (xy 194.629635 -276.054656)
			(xy 194.680038 -276.062479) (xy 194.728644 -276.077938) (xy 194.774305 -276.100669) (xy 194.795394 -276.115018)
			(xy 194.801932 -276.119298) (xy 194.816797 -276.12409) (xy 194.824604 -276.124416) (xy 195.340732 -276.124416)
			(xy 195.346004 -276.124876) (xy 195.353447 -276.13235) (xy 195.35394 -276.137624) (xy 195.35394 -276.138132)
			(xy 195.35394 -276.632416) (xy 197.954392 -276.632416) (xy 197.954392 -276.137878) (xy 197.954903 -276.132582)
			(xy 197.962316 -276.125015) (xy 197.9676 -276.124416) (xy 198.483728 -276.124416) (xy 198.491541 -276.124128)
			(xy 198.506412 -276.119326) (xy 198.512938 -276.115018) (xy 198.534027 -276.100669) (xy 198.579688 -276.077938)
			(xy 198.628294 -276.062479) (xy 198.678697 -276.054656) (xy 198.729703 -276.054656) (xy 198.780106 -276.062479)
			(xy 198.828712 -276.077938) (xy 198.874373 -276.100669) (xy 198.895462 -276.115018) (xy 198.902008 -276.119286)
			(xy 198.916867 -276.124085) (xy 198.924672 -276.124416) (xy 199.4408 -276.124416) (xy 199.446138 -276.124729)
			(xy 199.453681 -276.132285) (xy 199.454008 -276.137624) (xy 199.454008 -276.138132) (xy 199.454008 -276.632416)
			(xy 201.398124 -276.632416) (xy 201.398124 -276.137878) (xy 201.398607 -276.132575) (xy 201.406039 -276.125006)
			(xy 201.411332 -276.124416) (xy 201.92746 -276.124416) (xy 201.93527 -276.124099) (xy 201.950142 -276.119317)
			(xy 201.95667 -276.115018) (xy 201.977759 -276.100669) (xy 202.02342 -276.077938) (xy 202.072026 -276.062479)
			(xy 202.122429 -276.054656) (xy 202.173435 -276.054656) (xy 202.223838 -276.062479) (xy 202.272444 -276.077938)
			(xy 202.318105 -276.100669) (xy 202.339194 -276.115018) (xy 202.345732 -276.119298) (xy 202.360597 -276.12409)
			(xy 202.368404 -276.124416) (xy 202.884532 -276.124416) (xy 202.889804 -276.124876) (xy 202.897247 -276.13235)
			(xy 202.89774 -276.137624) (xy 202.89774 -276.138132) (xy 202.89774 -276.632416) (xy 205.498192 -276.632416)
			(xy 205.498192 -276.137878) (xy 205.498703 -276.132582) (xy 205.506116 -276.125015) (xy 205.5114 -276.124416)
			(xy 206.027528 -276.124416) (xy 206.035341 -276.124128) (xy 206.050212 -276.119326) (xy 206.056738 -276.115018)
			(xy 206.077827 -276.100669) (xy 206.123488 -276.077938) (xy 206.172094 -276.062479) (xy 206.222497 -276.054656)
			(xy 206.273503 -276.054656) (xy 206.323906 -276.062479) (xy 206.372512 -276.077938) (xy 206.418173 -276.100669)
			(xy 206.439262 -276.115018) (xy 206.445808 -276.119286) (xy 206.460667 -276.124085) (xy 206.468472 -276.124416)
			(xy 206.9846 -276.124416) (xy 206.989938 -276.124729) (xy 206.997481 -276.132285) (xy 206.997808 -276.137624)
			(xy 206.997808 -276.138132) (xy 206.997808 -276.632162) (xy 264.798048 -276.632162) (xy 264.798048 -276.137624)
			(xy 264.798606 -276.132375) (xy 264.806009 -276.124933) (xy 264.811256 -276.124416) (xy 264.811764 -276.124416)
			(xy 265.327638 -276.124416) (xy 265.335447 -276.12409) (xy 265.350319 -276.119314) (xy 265.356848 -276.115018)
			(xy 265.377937 -276.100669) (xy 265.423598 -276.077938) (xy 265.472204 -276.062479) (xy 265.522607 -276.054656)
			(xy 265.573613 -276.054656) (xy 265.624016 -276.062479) (xy 265.672622 -276.077938) (xy 265.718283 -276.100669)
			(xy 265.739372 -276.115018) (xy 265.745915 -276.119289) (xy 265.760776 -276.124086) (xy 265.768582 -276.124416)
			(xy 266.28471 -276.124416) (xy 266.29001 -276.124914) (xy 266.297579 -276.132335) (xy 266.298172 -276.137624)
			(xy 266.298172 -276.632162) (xy 268.898116 -276.632162) (xy 268.898116 -276.137624) (xy 268.898445 -276.132289)
			(xy 268.905989 -276.124745) (xy 268.911324 -276.124416) (xy 268.911832 -276.124416) (xy 269.427706 -276.124416)
			(xy 269.435518 -276.124119) (xy 269.45039 -276.119323) (xy 269.456916 -276.115018) (xy 269.478005 -276.100669)
			(xy 269.523666 -276.077938) (xy 269.572272 -276.062479) (xy 269.622675 -276.054656) (xy 269.673681 -276.054656)
			(xy 269.724084 -276.062479) (xy 269.77269 -276.077938) (xy 269.818351 -276.100669) (xy 269.83944 -276.115018)
			(xy 269.845968 -276.119316) (xy 269.860841 -276.124096) (xy 269.86865 -276.124416) (xy 270.384778 -276.124416)
			(xy 270.390074 -276.124935) (xy 270.397645 -276.13234) (xy 270.39824 -276.137624) (xy 270.39824 -276.632162)
			(xy 270.398224 -276.632416) (xy 272.342356 -276.632416) (xy 272.342356 -276.631908) (xy 272.342356 -276.137624)
			(xy 272.342907 -276.132373) (xy 272.350315 -276.124931) (xy 272.355564 -276.124416) (xy 272.871692 -276.124416)
			(xy 272.879503 -276.124113) (xy 272.894375 -276.119321) (xy 272.900902 -276.115018) (xy 272.921991 -276.100669)
			(xy 272.967652 -276.077938) (xy 273.016258 -276.062479) (xy 273.066661 -276.054656) (xy 273.117667 -276.054656)
			(xy 273.16807 -276.062479) (xy 273.216676 -276.077938) (xy 273.262337 -276.100669) (xy 273.283426 -276.115018)
			(xy 273.289957 -276.11931) (xy 273.304827 -276.124094) (xy 273.312636 -276.124416) (xy 273.828764 -276.124416)
			(xy 273.834097 -276.124753) (xy 273.841642 -276.132291) (xy 273.841972 -276.137624) (xy 273.841972 -276.632162)
			(xy 273.841947 -276.632416) (xy 276.442424 -276.632416) (xy 276.442424 -276.631908) (xy 276.442424 -276.137624)
			(xy 276.442746 -276.132287) (xy 276.450295 -276.124743) (xy 276.455632 -276.124416) (xy 276.97176 -276.124416)
			(xy 276.97957 -276.124099) (xy 276.994442 -276.119317) (xy 277.00097 -276.115018) (xy 277.022059 -276.100669)
			(xy 277.06772 -276.077938) (xy 277.116326 -276.062479) (xy 277.166729 -276.054656) (xy 277.217735 -276.054656)
			(xy 277.268138 -276.062479) (xy 277.316744 -276.077938) (xy 277.362405 -276.100669) (xy 277.383494 -276.115018)
			(xy 277.390032 -276.119298) (xy 277.404897 -276.12409) (xy 277.412704 -276.124416) (xy 277.928832 -276.124416)
			(xy 277.934104 -276.124876) (xy 277.941547 -276.13235) (xy 277.94204 -276.137624) (xy 277.94204 -276.632162)
			(xy 277.942016 -276.632416) (xy 279.886156 -276.632416) (xy 279.886156 -276.631908) (xy 279.886156 -276.137624)
			(xy 279.886707 -276.132373) (xy 279.894115 -276.124931) (xy 279.899364 -276.124416) (xy 280.415492 -276.124416)
			(xy 280.423303 -276.124113) (xy 280.438175 -276.119321) (xy 280.444702 -276.115018) (xy 280.465791 -276.100669)
			(xy 280.511452 -276.077938) (xy 280.560058 -276.062479) (xy 280.610461 -276.054656) (xy 280.661467 -276.054656)
			(xy 280.71187 -276.062479) (xy 280.760476 -276.077938) (xy 280.806137 -276.100669) (xy 280.827226 -276.115018)
			(xy 280.833757 -276.11931) (xy 280.848627 -276.124094) (xy 280.856436 -276.124416) (xy 281.372564 -276.124416)
			(xy 281.377897 -276.124753) (xy 281.385442 -276.132291) (xy 281.385772 -276.137624) (xy 281.385772 -276.632162)
			(xy 281.385747 -276.632416) (xy 283.986224 -276.632416) (xy 283.986224 -276.631908) (xy 283.986224 -276.137624)
			(xy 283.986546 -276.132287) (xy 283.994095 -276.124743) (xy 283.999432 -276.124416) (xy 284.51556 -276.124416)
			(xy 284.52337 -276.124099) (xy 284.538242 -276.119317) (xy 284.54477 -276.115018) (xy 284.565859 -276.100669)
			(xy 284.61152 -276.077938) (xy 284.660126 -276.062479) (xy 284.710529 -276.054656) (xy 284.761535 -276.054656)
			(xy 284.811938 -276.062479) (xy 284.860544 -276.077938) (xy 284.906205 -276.100669) (xy 284.927294 -276.115018)
			(xy 284.933832 -276.119298) (xy 284.948697 -276.12409) (xy 284.956504 -276.124416) (xy 285.472632 -276.124416)
			(xy 285.477904 -276.124876) (xy 285.485347 -276.13235) (xy 285.48584 -276.137624) (xy 285.48584 -276.632162)
			(xy 287.429956 -276.632162) (xy 287.429956 -276.137624) (xy 287.430507 -276.132373) (xy 287.437915 -276.124931)
			(xy 287.443164 -276.124416) (xy 287.443672 -276.124416) (xy 287.959546 -276.124416) (xy 287.967356 -276.124094)
			(xy 287.982228 -276.119315) (xy 287.988756 -276.115018) (xy 288.009845 -276.100669) (xy 288.055506 -276.077938)
			(xy 288.104112 -276.062479) (xy 288.154515 -276.054656) (xy 288.205521 -276.054656) (xy 288.255924 -276.062479)
			(xy 288.30453 -276.077938) (xy 288.350191 -276.100669) (xy 288.37128 -276.115018) (xy 288.377821 -276.119293)
			(xy 288.392684 -276.124087) (xy 288.40049 -276.124416) (xy 288.916618 -276.124416) (xy 288.921919 -276.124908)
			(xy 288.929488 -276.132334) (xy 288.93008 -276.137624) (xy 288.93008 -276.632162) (xy 291.530024 -276.632162)
			(xy 291.530024 -276.137624) (xy 291.530346 -276.132287) (xy 291.537895 -276.124743) (xy 291.543232 -276.124416)
			(xy 291.54374 -276.124416) (xy 292.059614 -276.124416) (xy 292.067426 -276.124122) (xy 292.082298 -276.119324)
			(xy 292.088824 -276.115018) (xy 292.109913 -276.100669) (xy 292.155574 -276.077938) (xy 292.20418 -276.062479)
			(xy 292.254583 -276.054656) (xy 292.305589 -276.054656) (xy 292.355992 -276.062479) (xy 292.404598 -276.077938)
			(xy 292.450259 -276.100669) (xy 292.471348 -276.115018) (xy 292.477874 -276.119319) (xy 292.492748 -276.124097)
			(xy 292.500558 -276.124416) (xy 293.016686 -276.124416) (xy 293.021983 -276.12493) (xy 293.029553 -276.132339)
			(xy 293.030148 -276.137624) (xy 293.030148 -276.632162) (xy 293.030131 -276.632416) (xy 294.974264 -276.632416)
			(xy 294.974264 -276.631908) (xy 294.974264 -276.137624) (xy 294.974808 -276.132371) (xy 294.982221 -276.124929)
			(xy 294.987472 -276.124416) (xy 295.5036 -276.124416) (xy 295.511412 -276.124116) (xy 295.526283 -276.119322)
			(xy 295.53281 -276.115018) (xy 295.553899 -276.100669) (xy 295.59956 -276.077938) (xy 295.648166 -276.062479)
			(xy 295.698569 -276.054656) (xy 295.749575 -276.054656) (xy 295.799978 -276.062479) (xy 295.848584 -276.077938)
			(xy 295.894245 -276.100669) (xy 295.915334 -276.115018) (xy 295.921863 -276.119313) (xy 295.936735 -276.124095)
			(xy 295.944544 -276.124416) (xy 296.460672 -276.124416) (xy 296.466006 -276.124748) (xy 296.473551 -276.13229)
			(xy 296.47388 -276.137624) (xy 296.47388 -276.632162) (xy 296.473855 -276.632416) (xy 299.074332 -276.632416)
			(xy 299.074332 -276.631908) (xy 299.074332 -276.137624) (xy 299.074647 -276.132285) (xy 299.082201 -276.124741)
			(xy 299.08754 -276.124416) (xy 299.603668 -276.124416) (xy 299.611478 -276.124103) (xy 299.62635 -276.119318)
			(xy 299.632878 -276.115018) (xy 299.653967 -276.100669) (xy 299.699628 -276.077938) (xy 299.748234 -276.062479)
			(xy 299.798637 -276.054656) (xy 299.849643 -276.054656) (xy 299.900046 -276.062479) (xy 299.948652 -276.077938)
			(xy 299.994313 -276.100669) (xy 300.015402 -276.115018) (xy 300.021939 -276.119301) (xy 300.036804 -276.124091)
			(xy 300.044612 -276.124416) (xy 300.56074 -276.124416) (xy 300.566013 -276.12487) (xy 300.573455 -276.132348)
			(xy 300.573948 -276.137624) (xy 300.573948 -276.632162) (xy 302.518064 -276.632162) (xy 302.518064 -276.137624)
			(xy 302.518608 -276.132371) (xy 302.526021 -276.124929) (xy 302.531272 -276.124416) (xy 304.004726 -276.124416)
			(xy 304.010028 -276.124903) (xy 304.017596 -276.132332) (xy 304.018188 -276.137624) (xy 304.018188 -276.632162)
			(xy 306.618132 -276.632162) (xy 306.618132 -276.137624) (xy 306.618447 -276.132285) (xy 306.626001 -276.124741)
			(xy 306.63134 -276.124416) (xy 306.631848 -276.124416) (xy 308.104794 -276.124416) (xy 308.110092 -276.124924)
			(xy 308.117662 -276.132337) (xy 308.118256 -276.137624) (xy 308.118256 -276.632162) (xy 308.118239 -276.632416)
			(xy 411.618176 -276.632416) (xy 411.618176 -276.631908) (xy 411.618176 -276.137624) (xy 411.618541 -276.132299)
			(xy 411.62606 -276.124757) (xy 411.631384 -276.124416) (xy 413.104584 -276.124416) (xy 413.10992 -276.12474)
			(xy 413.117463 -276.132288) (xy 413.117792 -276.137624) (xy 413.117792 -276.632162) (xy 413.117766 -276.632416)
			(xy 415.718244 -276.632416) (xy 415.718244 -276.137624) (xy 415.718806 -276.132376) (xy 415.726207 -276.124935)
			(xy 415.731452 -276.124416) (xy 417.204652 -276.124416) (xy 417.209984 -276.124762) (xy 417.217529 -276.132293)
			(xy 417.21786 -276.137624) (xy 417.21786 -276.632162) (xy 419.161976 -276.632162) (xy 419.161976 -276.137624)
			(xy 419.162341 -276.132299) (xy 419.16986 -276.124757) (xy 419.175184 -276.124416) (xy 419.175692 -276.124416)
			(xy 419.691566 -276.124416) (xy 419.699376 -276.124102) (xy 419.714248 -276.119318) (xy 419.720776 -276.115018)
			(xy 419.741865 -276.100669) (xy 419.787526 -276.077938) (xy 419.836132 -276.062479) (xy 419.886535 -276.054656)
			(xy 419.937541 -276.054656) (xy 419.987944 -276.062479) (xy 420.03655 -276.077938) (xy 420.082211 -276.100669)
			(xy 420.1033 -276.115018) (xy 420.109837 -276.1193) (xy 420.124703 -276.12409) (xy 420.13251 -276.124416)
			(xy 420.648638 -276.124416) (xy 420.653941 -276.124895) (xy 420.661509 -276.132331) (xy 420.6621 -276.137624)
			(xy 420.6621 -276.632162) (xy 423.262044 -276.632162) (xy 423.262044 -276.137624) (xy 423.262606 -276.132376)
			(xy 423.270007 -276.124935) (xy 423.275252 -276.124416) (xy 423.27576 -276.124416) (xy 423.791634 -276.124416)
			(xy 423.799443 -276.124088) (xy 423.814315 -276.119314) (xy 423.820844 -276.115018) (xy 423.841933 -276.100669)
			(xy 423.887594 -276.077938) (xy 423.9362 -276.062479) (xy 423.986603 -276.054656) (xy 424.037609 -276.054656)
			(xy 424.088012 -276.062479) (xy 424.136618 -276.077938) (xy 424.182279 -276.100669) (xy 424.203368 -276.115018)
			(xy 424.209912 -276.119288) (xy 424.224772 -276.124086) (xy 424.232578 -276.124416) (xy 424.748706 -276.124416)
			(xy 424.754005 -276.124916) (xy 424.761575 -276.132335) (xy 424.762168 -276.137624) (xy 424.762168 -276.632162)
			(xy 424.762151 -276.632416) (xy 426.706284 -276.632416) (xy 426.706284 -276.631908) (xy 426.706284 -276.137624)
			(xy 426.706642 -276.132297) (xy 426.714166 -276.124755) (xy 426.719492 -276.124416) (xy 427.23562 -276.124416)
			(xy 427.243432 -276.124125) (xy 427.258304 -276.119325) (xy 427.26483 -276.115018) (xy 427.285919 -276.100669)
			(xy 427.33158 -276.077938) (xy 427.380186 -276.062479) (xy 427.430589 -276.054656) (xy 427.481595 -276.054656)
			(xy 427.531998 -276.062479) (xy 427.580604 -276.077938) (xy 427.626265 -276.100669) (xy 427.647354 -276.115018)
			(xy 427.653879 -276.119321) (xy 427.668754 -276.124098) (xy 427.676564 -276.124416) (xy 428.192692 -276.124416)
			(xy 428.198029 -276.124734) (xy 428.205572 -276.132287) (xy 428.2059 -276.137624) (xy 428.2059 -276.632162)
			(xy 428.205874 -276.632416) (xy 430.806352 -276.632416) (xy 430.806352 -276.631908) (xy 430.806352 -276.137624)
			(xy 430.806907 -276.132374) (xy 430.814312 -276.124932) (xy 430.81956 -276.124416) (xy 431.335688 -276.124416)
			(xy 431.343499 -276.124111) (xy 431.358371 -276.119321) (xy 431.364898 -276.115018) (xy 431.385987 -276.100669)
			(xy 431.431648 -276.077938) (xy 431.480254 -276.062479) (xy 431.530657 -276.054656) (xy 431.581663 -276.054656)
			(xy 431.632066 -276.062479) (xy 431.680672 -276.077938) (xy 431.726333 -276.100669) (xy 431.747422 -276.115018)
			(xy 431.753954 -276.119309) (xy 431.768823 -276.124094) (xy 431.776632 -276.124416) (xy 432.29276 -276.124416)
			(xy 432.298093 -276.124756) (xy 432.305637 -276.132292) (xy 432.305968 -276.137624) (xy 432.305968 -276.632162)
			(xy 434.250084 -276.632162) (xy 434.250084 -276.137624) (xy 434.250442 -276.132297) (xy 434.257966 -276.124755)
			(xy 434.263292 -276.124416) (xy 434.2638 -276.124416) (xy 434.779674 -276.124416) (xy 434.787485 -276.124105)
			(xy 434.802357 -276.119319) (xy 434.808884 -276.115018) (xy 434.829973 -276.100669) (xy 434.875634 -276.077938)
			(xy 434.92424 -276.062479) (xy 434.974643 -276.054656) (xy 435.025649 -276.054656) (xy 435.076052 -276.062479)
			(xy 435.124658 -276.077938) (xy 435.170319 -276.100669) (xy 435.191408 -276.115018) (xy 435.197943 -276.119303)
			(xy 435.21281 -276.124092) (xy 435.220618 -276.124416) (xy 435.736746 -276.124416) (xy 435.742038 -276.124956)
			(xy 435.749611 -276.132345) (xy 435.750208 -276.137624) (xy 435.750208 -276.632162) (xy 438.350152 -276.632162)
			(xy 438.350152 -276.137624) (xy 438.350707 -276.132374) (xy 438.358112 -276.124932) (xy 438.36336 -276.124416)
			(xy 438.363868 -276.124416) (xy 438.879742 -276.124416) (xy 438.887551 -276.124092) (xy 438.902423 -276.119315)
			(xy 438.908952 -276.115018) (xy 438.930041 -276.100669) (xy 438.975702 -276.077938) (xy 439.024308 -276.062479)
			(xy 439.074711 -276.054656) (xy 439.125717 -276.054656) (xy 439.17612 -276.062479) (xy 439.224726 -276.077938)
			(xy 439.270387 -276.100669) (xy 439.291476 -276.115018) (xy 439.298018 -276.119291) (xy 439.31288 -276.124087)
			(xy 439.320686 -276.124416) (xy 439.836814 -276.124416) (xy 439.842114 -276.124911) (xy 439.849683 -276.132334)
			(xy 439.850276 -276.137624) (xy 439.850276 -276.632162) (xy 439.850258 -276.632416) (xy 441.794392 -276.632416)
			(xy 441.794392 -276.631908) (xy 441.794392 -276.137624) (xy 441.794743 -276.132295) (xy 441.802272 -276.124753)
			(xy 441.8076 -276.124416) (xy 442.323728 -276.124416) (xy 442.331541 -276.124128) (xy 442.346412 -276.119326)
			(xy 442.352938 -276.115018) (xy 442.374027 -276.100669) (xy 442.419688 -276.077938) (xy 442.468294 -276.062479)
			(xy 442.518697 -276.054656) (xy 442.569703 -276.054656) (xy 442.620106 -276.062479) (xy 442.668712 -276.077938)
			(xy 442.714373 -276.100669) (xy 442.735462 -276.115018) (xy 442.742008 -276.119286) (xy 442.756867 -276.124085)
			(xy 442.764672 -276.124416) (xy 443.2808 -276.124416) (xy 443.286138 -276.124729) (xy 443.293681 -276.132285)
			(xy 443.294008 -276.137624) (xy 443.294008 -276.632162) (xy 443.293982 -276.632416) (xy 445.89446 -276.632416)
			(xy 445.89446 -276.631908) (xy 445.89446 -276.137624) (xy 445.895008 -276.132372) (xy 445.902418 -276.12493)
			(xy 445.907668 -276.124416) (xy 446.423796 -276.124416) (xy 446.431607 -276.124115) (xy 446.446479 -276.119322)
			(xy 446.453006 -276.115018) (xy 446.474095 -276.100669) (xy 446.519756 -276.077938) (xy 446.568362 -276.062479)
			(xy 446.618765 -276.054656) (xy 446.669771 -276.054656) (xy 446.720174 -276.062479) (xy 446.76878 -276.077938)
			(xy 446.814441 -276.100669) (xy 446.83553 -276.115018) (xy 446.84206 -276.119312) (xy 446.856931 -276.124095)
			(xy 446.86474 -276.124416) (xy 447.380868 -276.124416) (xy 447.386202 -276.124751) (xy 447.393746 -276.13229)
			(xy 447.394076 -276.137624) (xy 447.394076 -276.632162) (xy 447.394051 -276.632416) (xy 449.338192 -276.632416)
			(xy 449.338192 -276.631908) (xy 449.338192 -276.137624) (xy 449.338543 -276.132295) (xy 449.346072 -276.124753)
			(xy 449.3514 -276.124416) (xy 449.867528 -276.124416) (xy 449.875341 -276.124128) (xy 449.890212 -276.119326)
			(xy 449.896738 -276.115018) (xy 449.917827 -276.100669) (xy 449.963488 -276.077938) (xy 450.012094 -276.062479)
			(xy 450.062497 -276.054656) (xy 450.113503 -276.054656) (xy 450.163906 -276.062479) (xy 450.212512 -276.077938)
			(xy 450.258173 -276.100669) (xy 450.279262 -276.115018) (xy 450.285808 -276.119286) (xy 450.300667 -276.124085)
			(xy 450.308472 -276.124416) (xy 450.8246 -276.124416) (xy 450.829938 -276.124729) (xy 450.837481 -276.132285)
			(xy 450.837808 -276.137624) (xy 450.837808 -276.632162) (xy 450.837782 -276.632416) (xy 453.43826 -276.632416)
			(xy 453.43826 -276.631908) (xy 453.43826 -276.137624) (xy 453.438808 -276.132372) (xy 453.446218 -276.12493)
			(xy 453.451468 -276.124416) (xy 453.967596 -276.124416) (xy 453.975407 -276.124115) (xy 453.990279 -276.119322)
			(xy 453.996806 -276.115018) (xy 454.017895 -276.100669) (xy 454.063556 -276.077938) (xy 454.112162 -276.062479)
			(xy 454.162565 -276.054656) (xy 454.213571 -276.054656) (xy 454.263974 -276.062479) (xy 454.31258 -276.077938)
			(xy 454.358241 -276.100669) (xy 454.37933 -276.115018) (xy 454.38586 -276.119312) (xy 454.400731 -276.124095)
			(xy 454.40854 -276.124416) (xy 454.924668 -276.124416) (xy 454.930002 -276.124751) (xy 454.937546 -276.13229)
			(xy 454.937876 -276.137624) (xy 454.937876 -276.632162) (xy 454.937353 -276.637458) (xy 454.929952 -276.64503)
			(xy 454.924668 -276.645624) (xy 454.408794 -276.645624) (xy 454.400983 -276.645931) (xy 454.386112 -276.650721)
			(xy 454.379584 -276.655022) (xy 454.358462 -276.669371) (xy 454.312739 -276.692099) (xy 454.264065 -276.707529)
			(xy 454.213599 -276.715295) (xy 454.188068 -276.715728) (xy 454.162537 -276.715314) (xy 454.112072 -276.707532)
			(xy 454.063399 -276.692097) (xy 454.017673 -276.669373) (xy 453.996552 -276.655022) (xy 453.990029 -276.650716)
			(xy 453.975152 -276.645942) (xy 453.967342 -276.645624) (xy 453.451468 -276.645624) (xy 453.446205 -276.645128)
			(xy 453.438765 -276.637679) (xy 453.43826 -276.632416) (xy 450.837782 -276.632416) (xy 450.837257 -276.63745)
			(xy 450.829875 -276.645021) (xy 450.8246 -276.645624) (xy 450.308726 -276.645624) (xy 450.300916 -276.645944)
			(xy 450.286045 -276.650725) (xy 450.279516 -276.655022) (xy 450.258385 -276.669357) (xy 450.212665 -276.692088)
			(xy 450.163994 -276.707522) (xy 450.11353 -276.715293) (xy 450.088 -276.715728) (xy 450.062469 -276.715298)
			(xy 450.012005 -276.707521) (xy 449.963332 -276.69209) (xy 449.917605 -276.669371) (xy 449.896484 -276.655022)
			(xy 449.889954 -276.650728) (xy 449.875083 -276.645947) (xy 449.867274 -276.645624) (xy 449.3514 -276.645624)
			(xy 449.346141 -276.645107) (xy 449.3387 -276.637674) (xy 449.338192 -276.632416) (xy 447.394051 -276.632416)
			(xy 447.393553 -276.637458) (xy 447.386152 -276.64503) (xy 447.380868 -276.645624) (xy 446.864994 -276.645624)
			(xy 446.857183 -276.645931) (xy 446.842312 -276.650721) (xy 446.835784 -276.655022) (xy 446.814662 -276.669371)
			(xy 446.768939 -276.692099) (xy 446.720265 -276.707529) (xy 446.669799 -276.715295) (xy 446.644268 -276.715728)
			(xy 446.618737 -276.715314) (xy 446.568272 -276.707532) (xy 446.519599 -276.692097) (xy 446.473873 -276.669373)
			(xy 446.452752 -276.655022) (xy 446.446229 -276.650716) (xy 446.431352 -276.645942) (xy 446.423542 -276.645624)
			(xy 445.907668 -276.645624) (xy 445.902405 -276.645128) (xy 445.894965 -276.637679) (xy 445.89446 -276.632416)
			(xy 443.293982 -276.632416) (xy 443.293457 -276.63745) (xy 443.286075 -276.645021) (xy 443.2808 -276.645624)
			(xy 442.764926 -276.645624) (xy 442.757116 -276.645944) (xy 442.742245 -276.650725) (xy 442.735716 -276.655022)
			(xy 442.714585 -276.669357) (xy 442.668865 -276.692088) (xy 442.620194 -276.707522) (xy 442.56973 -276.715293)
			(xy 442.5442 -276.715728) (xy 442.518669 -276.715298) (xy 442.468205 -276.707521) (xy 442.419532 -276.69209)
			(xy 442.373805 -276.669371) (xy 442.352684 -276.655022) (xy 442.346154 -276.650728) (xy 442.331283 -276.645947)
			(xy 442.323474 -276.645624) (xy 441.8076 -276.645624) (xy 441.802341 -276.645107) (xy 441.7949 -276.637674)
			(xy 441.794392 -276.632416) (xy 439.850258 -276.632416) (xy 439.849897 -276.637588) (xy 439.842239 -276.645276)
			(xy 439.836814 -276.645624) (xy 439.32094 -276.645624) (xy 439.313131 -276.645951) (xy 439.29826 -276.650728)
			(xy 439.29173 -276.655022) (xy 439.270623 -276.669394) (xy 439.224894 -276.692117) (xy 439.176216 -276.70754)
			(xy 439.125746 -276.715299) (xy 439.100214 -276.715728) (xy 439.074684 -276.715291) (xy 439.02422 -276.707516)
			(xy 438.975547 -276.692087) (xy 438.92982 -276.66937) (xy 438.908698 -276.655022) (xy 438.902165 -276.650734)
			(xy 438.887296 -276.645949) (xy 438.879488 -276.645624) (xy 438.363614 -276.645624) (xy 438.358172 -276.645308)
			(xy 438.350483 -276.637605) (xy 438.350152 -276.632162) (xy 435.750208 -276.632162) (xy 435.749629 -276.63751)
			(xy 435.742091 -276.645096) (xy 435.736746 -276.645624) (xy 435.220872 -276.645624) (xy 435.21306 -276.645922)
			(xy 435.198189 -276.650718) (xy 435.191662 -276.655022) (xy 435.170546 -276.66938) (xy 435.124821 -276.692106)
			(xy 435.076145 -276.707534) (xy 435.025678 -276.715297) (xy 435.000146 -276.715728) (xy 434.974616 -276.715275)
			(xy 434.924153 -276.707505) (xy 434.87548 -276.692081) (xy 434.829752 -276.669368) (xy 434.80863 -276.655022)
			(xy 434.80209 -276.650746) (xy 434.787226 -276.645953) (xy 434.77942 -276.645624) (xy 434.263546 -276.645624)
			(xy 434.258108 -276.645286) (xy 434.250417 -276.6376) (xy 434.250084 -276.632162) (xy 432.305968 -276.632162)
			(xy 432.305452 -276.63746) (xy 432.298046 -276.645032) (xy 432.29276 -276.645624) (xy 431.776886 -276.645624)
			(xy 431.769075 -276.645928) (xy 431.754203 -276.65072) (xy 431.747676 -276.655022) (xy 431.726556 -276.669374)
			(xy 431.680832 -276.692101) (xy 431.632158 -276.707531) (xy 431.581691 -276.715296) (xy 431.55616 -276.715728)
			(xy 431.530629 -276.715318) (xy 431.480163 -276.707535) (xy 431.431491 -276.692098) (xy 431.385765 -276.669374)
			(xy 431.364644 -276.655022) (xy 431.358123 -276.650713) (xy 431.343245 -276.645941) (xy 431.335434 -276.645624)
			(xy 430.81956 -276.645624) (xy 430.814296 -276.645134) (xy 430.806857 -276.637681) (xy 430.806352 -276.632416)
			(xy 428.205874 -276.632416) (xy 428.205356 -276.637452) (xy 428.197969 -276.645023) (xy 428.192692 -276.645624)
			(xy 427.676818 -276.645624) (xy 427.669008 -276.645941) (xy 427.654137 -276.650724) (xy 427.647608 -276.655022)
			(xy 427.626479 -276.66936) (xy 427.580758 -276.69209) (xy 427.532087 -276.707524) (xy 427.481622 -276.715293)
			(xy 427.456092 -276.715728) (xy 427.430561 -276.715302) (xy 427.380097 -276.707524) (xy 427.331424 -276.692092)
			(xy 427.285697 -276.669372) (xy 427.264576 -276.655022) (xy 427.258048 -276.650725) (xy 427.243175 -276.645945)
			(xy 427.235366 -276.645624) (xy 426.719492 -276.645624) (xy 426.714232 -276.645112) (xy 426.706791 -276.637676)
			(xy 426.706284 -276.632416) (xy 424.762151 -276.632416) (xy 424.761796 -276.63759) (xy 424.754133 -276.645278)
			(xy 424.748706 -276.645624) (xy 424.232832 -276.645624) (xy 424.225023 -276.645947) (xy 424.210151 -276.650726)
			(xy 424.203622 -276.655022) (xy 424.182489 -276.669354) (xy 424.13677 -276.692086) (xy 424.0881 -276.707521)
			(xy 424.037636 -276.715292) (xy 424.012106 -276.715728) (xy 423.986576 -276.715295) (xy 423.936111 -276.707519)
			(xy 423.887439 -276.692089) (xy 423.841711 -276.669371) (xy 423.82059 -276.655022) (xy 423.814059 -276.650731)
			(xy 423.799189 -276.645947) (xy 423.79138 -276.645624) (xy 423.275506 -276.645624) (xy 423.270063 -276.645313)
			(xy 423.262374 -276.637606) (xy 423.262044 -276.632162) (xy 420.6621 -276.632162) (xy 420.661528 -276.637512)
			(xy 420.653985 -276.645098) (xy 420.648638 -276.645624) (xy 420.132764 -276.645624) (xy 420.124956 -276.645961)
			(xy 420.110084 -276.650731) (xy 420.103554 -276.655022) (xy 420.08244 -276.669384) (xy 420.036714 -276.692109)
			(xy 419.988038 -276.707535) (xy 419.93757 -276.715297) (xy 419.912038 -276.715728) (xy 419.886508 -276.715279)
			(xy 419.836045 -276.707508) (xy 419.787372 -276.692083) (xy 419.741644 -276.669369) (xy 419.720522 -276.655022)
			(xy 419.713983 -276.650743) (xy 419.699119 -276.645952) (xy 419.691312 -276.645624) (xy 419.175438 -276.645624)
			(xy 419.169999 -276.645292) (xy 419.162308 -276.637601) (xy 419.161976 -276.632162) (xy 417.21786 -276.632162)
			(xy 417.217351 -276.637462) (xy 417.20994 -276.645035) (xy 417.204652 -276.645624) (xy 415.731452 -276.645624)
			(xy 415.726187 -276.645139) (xy 415.718749 -276.637682) (xy 415.718244 -276.632416) (xy 413.117766 -276.632416)
			(xy 413.117255 -276.637454) (xy 413.109863 -276.645025) (xy 413.104584 -276.645624) (xy 411.631384 -276.645624)
			(xy 411.626123 -276.645118) (xy 411.618682 -276.637677) (xy 411.618176 -276.632416) (xy 308.118239 -276.632416)
			(xy 308.117895 -276.637593) (xy 308.110224 -276.645282) (xy 308.104794 -276.645624) (xy 306.631594 -276.645624)
			(xy 306.626149 -276.645321) (xy 306.618461 -276.637608) (xy 306.618132 -276.632162) (xy 304.018188 -276.632162)
			(xy 304.017798 -276.637586) (xy 304.010148 -276.645272) (xy 304.004726 -276.645624) (xy 302.531526 -276.645624)
			(xy 302.526085 -276.6453) (xy 302.518396 -276.637603) (xy 302.518064 -276.632162) (xy 300.573948 -276.632162)
			(xy 300.57345 -276.637464) (xy 300.566031 -276.645038) (xy 300.56074 -276.645624) (xy 300.044866 -276.645624)
			(xy 300.037058 -276.645962) (xy 300.022186 -276.650731) (xy 300.015656 -276.655022) (xy 299.994542 -276.669383)
			(xy 299.948816 -276.692108) (xy 299.90014 -276.707535) (xy 299.849672 -276.715297) (xy 299.82414 -276.715728)
			(xy 299.79861 -276.715278) (xy 299.748147 -276.707507) (xy 299.699474 -276.692082) (xy 299.653746 -276.669368)
			(xy 299.632624 -276.655022) (xy 299.626085 -276.650744) (xy 299.611221 -276.645952) (xy 299.603414 -276.645624)
			(xy 299.08754 -276.645624) (xy 299.082217 -276.645248) (xy 299.074675 -276.637737) (xy 299.074332 -276.632416)
			(xy 296.473855 -276.632416) (xy 296.473354 -276.637457) (xy 296.465954 -276.645029) (xy 296.460672 -276.645624)
			(xy 295.944798 -276.645624) (xy 295.936987 -276.645933) (xy 295.922116 -276.650722) (xy 295.915588 -276.655022)
			(xy 295.894465 -276.669369) (xy 295.848742 -276.692097) (xy 295.800069 -276.707528) (xy 295.749603 -276.715295)
			(xy 295.724072 -276.715728) (xy 295.698541 -276.715312) (xy 295.648076 -276.707531) (xy 295.599403 -276.692096)
			(xy 295.553677 -276.669373) (xy 295.532556 -276.655022) (xy 295.526032 -276.650718) (xy 295.511156 -276.645943)
			(xy 295.503346 -276.645624) (xy 294.987472 -276.645624) (xy 294.98221 -276.645126) (xy 294.97477 -276.637679)
			(xy 294.974264 -276.632416) (xy 293.030131 -276.632416) (xy 293.029794 -276.637595) (xy 293.022119 -276.645284)
			(xy 293.016686 -276.645624) (xy 292.500812 -276.645624) (xy 292.493002 -276.645939) (xy 292.47813 -276.650723)
			(xy 292.471602 -276.655022) (xy 292.450475 -276.669363) (xy 292.404753 -276.692092) (xy 292.356082 -276.707525)
			(xy 292.305617 -276.715294) (xy 292.280086 -276.715728) (xy 292.254555 -276.715305) (xy 292.20409 -276.707526)
			(xy 292.155418 -276.692093) (xy 292.109691 -276.669372) (xy 292.08857 -276.655022) (xy 292.082043 -276.650723)
			(xy 292.06717 -276.645945) (xy 292.05936 -276.645624) (xy 291.543486 -276.645624) (xy 291.53804 -276.645326)
			(xy 291.530353 -276.637609) (xy 291.530024 -276.632162) (xy 288.93008 -276.632162) (xy 288.929697 -276.637588)
			(xy 288.922042 -276.645275) (xy 288.916618 -276.645624) (xy 288.400744 -276.645624) (xy 288.392935 -276.645953)
			(xy 288.378064 -276.650728) (xy 288.371534 -276.655022) (xy 288.350426 -276.669392) (xy 288.304698 -276.692115)
			(xy 288.25602 -276.70754) (xy 288.20555 -276.715299) (xy 288.180018 -276.715728) (xy 288.154488 -276.715289)
			(xy 288.104024 -276.707515) (xy 288.055351 -276.692087) (xy 288.009624 -276.66937) (xy 287.988502 -276.655022)
			(xy 287.981968 -276.650735) (xy 287.9671 -276.645949) (xy 287.959292 -276.645624) (xy 287.443418 -276.645624)
			(xy 287.437976 -276.645305) (xy 287.430287 -276.637604) (xy 287.429956 -276.632162) (xy 285.48584 -276.632162)
			(xy 285.485349 -276.637466) (xy 285.477926 -276.645041) (xy 285.472632 -276.645624) (xy 284.956758 -276.645624)
			(xy 284.94895 -276.645959) (xy 284.934078 -276.65073) (xy 284.927548 -276.655022) (xy 284.906436 -276.669386)
			(xy 284.860709 -276.692111) (xy 284.812033 -276.707537) (xy 284.761564 -276.715298) (xy 284.736032 -276.715728)
			(xy 284.710502 -276.715282) (xy 284.660038 -276.70751) (xy 284.611366 -276.692084) (xy 284.565638 -276.669369)
			(xy 284.544516 -276.655022) (xy 284.537979 -276.650741) (xy 284.523113 -276.645951) (xy 284.515306 -276.645624)
			(xy 283.999432 -276.645624) (xy 283.994108 -276.645253) (xy 283.986566 -276.637739) (xy 283.986224 -276.632416)
			(xy 281.385747 -276.632416) (xy 281.385253 -276.637459) (xy 281.377849 -276.645031) (xy 281.372564 -276.645624)
			(xy 280.85669 -276.645624) (xy 280.848879 -276.645929) (xy 280.834008 -276.650721) (xy 280.82748 -276.655022)
			(xy 280.806359 -276.669373) (xy 280.760635 -276.6921) (xy 280.711962 -276.70753) (xy 280.661495 -276.715296)
			(xy 280.635964 -276.715728) (xy 280.610433 -276.715316) (xy 280.559968 -276.707534) (xy 280.511295 -276.692098)
			(xy 280.465569 -276.669373) (xy 280.444448 -276.655022) (xy 280.437926 -276.650714) (xy 280.423049 -276.645941)
			(xy 280.415238 -276.645624) (xy 279.899364 -276.645624) (xy 279.894101 -276.645131) (xy 279.886661 -276.63768)
			(xy 279.886156 -276.632416) (xy 277.942016 -276.632416) (xy 277.941549 -276.637466) (xy 277.934126 -276.645041)
			(xy 277.928832 -276.645624) (xy 277.412958 -276.645624) (xy 277.40515 -276.645959) (xy 277.390278 -276.65073)
			(xy 277.383748 -276.655022) (xy 277.362636 -276.669386) (xy 277.316909 -276.692111) (xy 277.268233 -276.707537)
			(xy 277.217764 -276.715298) (xy 277.192232 -276.715728) (xy 277.166702 -276.715282) (xy 277.116238 -276.70751)
			(xy 277.067566 -276.692084) (xy 277.021838 -276.669369) (xy 277.000716 -276.655022) (xy 276.994179 -276.650741)
			(xy 276.979313 -276.645951) (xy 276.971506 -276.645624) (xy 276.455632 -276.645624) (xy 276.450308 -276.645253)
			(xy 276.442766 -276.637739) (xy 276.442424 -276.632416) (xy 273.841947 -276.632416) (xy 273.841453 -276.637459)
			(xy 273.834049 -276.645031) (xy 273.828764 -276.645624) (xy 273.31289 -276.645624) (xy 273.305079 -276.645929)
			(xy 273.290208 -276.650721) (xy 273.28368 -276.655022) (xy 273.262559 -276.669373) (xy 273.216835 -276.6921)
			(xy 273.168162 -276.70753) (xy 273.117695 -276.715296) (xy 273.092164 -276.715728) (xy 273.066633 -276.715316)
			(xy 273.016168 -276.707534) (xy 272.967495 -276.692098) (xy 272.921769 -276.669373) (xy 272.900648 -276.655022)
			(xy 272.894126 -276.650714) (xy 272.879249 -276.645941) (xy 272.871438 -276.645624) (xy 272.355564 -276.645624)
			(xy 272.350301 -276.645131) (xy 272.342861 -276.63768) (xy 272.342356 -276.632416) (xy 270.398224 -276.632416)
			(xy 270.397893 -276.637597) (xy 270.390213 -276.645287) (xy 270.384778 -276.645624) (xy 269.868904 -276.645624)
			(xy 269.861094 -276.645935) (xy 269.846222 -276.650722) (xy 269.839694 -276.655022) (xy 269.818569 -276.669367)
			(xy 269.772847 -276.692095) (xy 269.724174 -276.707527) (xy 269.673709 -276.715294) (xy 269.648178 -276.715728)
			(xy 269.622647 -276.715309) (xy 269.572182 -276.707529) (xy 269.52351 -276.692095) (xy 269.477783 -276.669372)
			(xy 269.456662 -276.655022) (xy 269.450137 -276.65072) (xy 269.435262 -276.645943) (xy 269.427452 -276.645624)
			(xy 268.911578 -276.645624) (xy 268.906131 -276.645332) (xy 268.898444 -276.637611) (xy 268.898116 -276.632162)
			(xy 266.298172 -276.632162) (xy 266.297796 -276.637589) (xy 266.290136 -276.645277) (xy 266.28471 -276.645624)
			(xy 265.768836 -276.645624) (xy 265.761027 -276.645949) (xy 265.746155 -276.650727) (xy 265.739626 -276.655022)
			(xy 265.718492 -276.669353) (xy 265.672773 -276.692084) (xy 265.624104 -276.70752) (xy 265.57364 -276.715292)
			(xy 265.54811 -276.715728) (xy 265.52258 -276.715293) (xy 265.472115 -276.707518) (xy 265.423443 -276.692088)
			(xy 265.377716 -276.66937) (xy 265.356594 -276.655022) (xy 265.350062 -276.650732) (xy 265.335192 -276.645948)
			(xy 265.327384 -276.645624) (xy 264.81151 -276.645624) (xy 264.806067 -276.64531) (xy 264.798378 -276.637606)
			(xy 264.798048 -276.632162) (xy 206.997808 -276.632162) (xy 206.997808 -276.632416) (xy 206.997316 -276.637681)
			(xy 206.989865 -276.645122) (xy 206.9846 -276.645624) (xy 206.468726 -276.645624) (xy 206.46085 -276.645892)
			(xy 206.445846 -276.65069) (xy 206.439262 -276.655022) (xy 206.418183 -276.669412) (xy 206.372539 -276.692241)
			(xy 206.323934 -276.7078) (xy 206.273517 -276.715719) (xy 206.248 -276.716236) (xy 206.222479 -276.715757)
			(xy 206.172052 -276.707858) (xy 206.123441 -276.692295) (xy 206.077803 -276.669438) (xy 206.056738 -276.655022)
			(xy 206.050138 -276.650721) (xy 206.035145 -276.645925) (xy 206.027274 -276.645624) (xy 205.5114 -276.645624)
			(xy 205.506141 -276.645107) (xy 205.4987 -276.637674) (xy 205.498192 -276.632416) (xy 202.89774 -276.632416)
			(xy 202.897219 -276.637673) (xy 202.889788 -276.645113) (xy 202.884532 -276.645624) (xy 202.368658 -276.645624)
			(xy 202.360783 -276.645905) (xy 202.345779 -276.650694) (xy 202.339194 -276.655022) (xy 202.318107 -276.669398)
			(xy 202.272466 -276.692231) (xy 202.223863 -276.707793) (xy 202.173448 -276.715717) (xy 202.147932 -276.716236)
			(xy 202.122412 -276.715741) (xy 202.071986 -276.707847) (xy 202.023374 -276.692288) (xy 201.977735 -276.669436)
			(xy 201.95667 -276.655022) (xy 201.950086 -276.650695) (xy 201.93508 -276.645915) (xy 201.927206 -276.645624)
			(xy 201.411332 -276.645624) (xy 201.406008 -276.645253) (xy 201.398466 -276.637739) (xy 201.398124 -276.632416)
			(xy 199.454008 -276.632416) (xy 199.453516 -276.637681) (xy 199.446065 -276.645122) (xy 199.4408 -276.645624)
			(xy 198.924926 -276.645624) (xy 198.91705 -276.645892) (xy 198.902046 -276.65069) (xy 198.895462 -276.655022)
			(xy 198.874383 -276.669412) (xy 198.828739 -276.692241) (xy 198.780134 -276.7078) (xy 198.729717 -276.715719)
			(xy 198.7042 -276.716236) (xy 198.678679 -276.715757) (xy 198.628252 -276.707858) (xy 198.579641 -276.692295)
			(xy 198.534003 -276.669438) (xy 198.512938 -276.655022) (xy 198.506338 -276.650721) (xy 198.491345 -276.645925)
			(xy 198.483474 -276.645624) (xy 197.9676 -276.645624) (xy 197.962341 -276.645107) (xy 197.9549 -276.637674)
			(xy 197.954392 -276.632416) (xy 195.35394 -276.632416) (xy 195.353419 -276.637673) (xy 195.345988 -276.645113)
			(xy 195.340732 -276.645624) (xy 194.824858 -276.645624) (xy 194.816983 -276.645905) (xy 194.801979 -276.650694)
			(xy 194.795394 -276.655022) (xy 194.774307 -276.669398) (xy 194.728666 -276.692231) (xy 194.680063 -276.707793)
			(xy 194.629648 -276.715717) (xy 194.604132 -276.716236) (xy 194.578612 -276.715741) (xy 194.528186 -276.707847)
			(xy 194.479574 -276.692288) (xy 194.433935 -276.669436) (xy 194.41287 -276.655022) (xy 194.406286 -276.650695)
			(xy 194.39128 -276.645915) (xy 194.383406 -276.645624) (xy 193.867532 -276.645624) (xy 193.862208 -276.645253)
			(xy 193.854666 -276.637739) (xy 193.854324 -276.632416) (xy 191.910208 -276.632416) (xy 191.909716 -276.637681)
			(xy 191.902265 -276.645122) (xy 191.897 -276.645624) (xy 191.896492 -276.645624) (xy 191.380872 -276.645624)
			(xy 191.372998 -276.645911) (xy 191.357994 -276.650696) (xy 191.351408 -276.655022) (xy 191.330345 -276.669435)
			(xy 191.284695 -276.692259) (xy 191.236085 -276.707811) (xy 191.185664 -276.715723) (xy 191.160146 -276.716236)
			(xy 191.134626 -276.715734) (xy 191.0842 -276.707842) (xy 191.035589 -276.692285) (xy 190.98995 -276.669435)
			(xy 190.968884 -276.655022) (xy 190.962296 -276.6507) (xy 190.947293 -276.645917) (xy 190.93942 -276.645624)
			(xy 190.423546 -276.645624) (xy 190.418239 -276.645142) (xy 190.410663 -276.637713) (xy 190.410084 -276.632416)
			(xy 187.81014 -276.632416) (xy 187.809619 -276.637673) (xy 187.802188 -276.645113) (xy 187.796932 -276.645624)
			(xy 187.796424 -276.645624) (xy 187.280804 -276.645624) (xy 187.272931 -276.645926) (xy 187.257927 -276.6507)
			(xy 187.25134 -276.655022) (xy 187.230268 -276.669421) (xy 187.184621 -276.692249) (xy 187.136014 -276.707804)
			(xy 187.085595 -276.715721) (xy 187.060078 -276.716236) (xy 187.034559 -276.715718) (xy 186.984134 -276.707831)
			(xy 186.935522 -276.692279) (xy 186.889882 -276.669433) (xy 186.868816 -276.655022) (xy 186.862221 -276.650713)
			(xy 186.847224 -276.645922) (xy 186.839352 -276.645624) (xy 186.323478 -276.645624) (xy 186.318163 -276.645187)
			(xy 186.310591 -276.637724) (xy 186.310016 -276.632416) (xy 184.3659 -276.632416) (xy 184.365415 -276.637683)
			(xy 184.35796 -276.645125) (xy 184.352692 -276.645624) (xy 183.836818 -276.645624) (xy 183.828945 -276.645932)
			(xy 183.813941 -276.650702) (xy 183.807354 -276.655022) (xy 183.786278 -276.669415) (xy 183.740633 -276.692244)
			(xy 183.692026 -276.707802) (xy 183.641609 -276.71572) (xy 183.616092 -276.716236) (xy 183.590573 -276.715711)
			(xy 183.540148 -276.707826) (xy 183.491537 -276.692276) (xy 183.445897 -276.669432) (xy 183.42483 -276.655022)
			(xy 183.418232 -276.650718) (xy 183.403237 -276.645924) (xy 183.395366 -276.645624) (xy 182.879492 -276.645624)
			(xy 182.874232 -276.645112) (xy 182.866791 -276.637676) (xy 182.866284 -276.632416) (xy 180.265832 -276.632416)
			(xy 180.265319 -276.637675) (xy 180.257883 -276.645115) (xy 180.252624 -276.645624) (xy 179.73675 -276.645624)
			(xy 179.728875 -276.645902) (xy 179.713871 -276.650693) (xy 179.707286 -276.655022) (xy 179.686201 -276.669402)
			(xy 179.640559 -276.692233) (xy 179.591955 -276.707795) (xy 179.54154 -276.715717) (xy 179.516024 -276.716236)
			(xy 179.490504 -276.715745) (xy 179.440077 -276.70785) (xy 179.391466 -276.69229) (xy 179.345827 -276.669436)
			(xy 179.324762 -276.655022) (xy 179.318179 -276.650692) (xy 179.303172 -276.645914) (xy 179.295298 -276.645624)
			(xy 178.779424 -276.645624) (xy 178.774099 -276.645259) (xy 178.766557 -276.63774) (xy 178.766216 -276.632416)
			(xy 176.8221 -276.632416) (xy 176.821615 -276.637683) (xy 176.81416 -276.645125) (xy 176.808892 -276.645624)
			(xy 176.808384 -276.645624) (xy 176.292764 -276.645624) (xy 176.284889 -276.645908) (xy 176.269885 -276.650695)
			(xy 176.2633 -276.655022) (xy 176.242211 -276.669396) (xy 176.19657 -276.692229) (xy 176.147968 -276.707792)
			(xy 176.097554 -276.715716) (xy 176.072038 -276.716236) (xy 176.046518 -276.715738) (xy 175.996092 -276.707845)
			(xy 175.94748 -276.692287) (xy 175.901842 -276.669435) (xy 175.880776 -276.655022) (xy 175.87419 -276.650697)
			(xy 175.859186 -276.645916) (xy 175.851312 -276.645624) (xy 175.335438 -276.645624) (xy 175.33013 -276.645147)
			(xy 175.322555 -276.637714) (xy 175.321976 -276.632416) (xy 172.722032 -276.632416) (xy 172.721519 -276.637675)
			(xy 172.714083 -276.645115) (xy 172.708824 -276.645624) (xy 172.708316 -276.645624) (xy 172.192696 -276.645624)
			(xy 172.184822 -276.645922) (xy 172.169819 -276.650699) (xy 172.163232 -276.655022) (xy 172.142162 -276.669425)
			(xy 172.096515 -276.692251) (xy 172.047906 -276.707806) (xy 171.997487 -276.715721) (xy 171.97197 -276.716236)
			(xy 171.946451 -276.715722) (xy 171.896025 -276.707834) (xy 171.847414 -276.692281) (xy 171.801774 -276.669433)
			(xy 171.780708 -276.655022) (xy 171.774115 -276.65071) (xy 171.759116 -276.645921) (xy 171.751244 -276.645624)
			(xy 171.23537 -276.645624) (xy 171.230054 -276.645193) (xy 171.222482 -276.637725) (xy 171.221908 -276.632416)
			(xy 169.277792 -276.632416) (xy 169.277315 -276.637685) (xy 169.269854 -276.645127) (xy 169.264584 -276.645624)
			(xy 167.791384 -276.645624) (xy 167.786123 -276.645118) (xy 167.778682 -276.637677) (xy 167.778176 -276.632416)
			(xy 165.177724 -276.632416) (xy 165.177218 -276.637677) (xy 165.169777 -276.645118) (xy 165.164516 -276.645624)
			(xy 163.691316 -276.645624) (xy 163.686059 -276.645096) (xy 163.678616 -276.637672) (xy 163.678108 -276.632416)
			(xy 60.178188 -276.632416) (xy 60.177882 -276.637755) (xy 60.17032 -276.645297) (xy 60.16498 -276.645624)
			(xy 60.164472 -276.645624) (xy 58.691526 -276.645624) (xy 58.686217 -276.645155) (xy 58.678642 -276.637716)
			(xy 58.678064 -276.632416) (xy 56.07812 -276.632416) (xy 56.077617 -276.637678) (xy 56.070174 -276.645119)
			(xy 56.064912 -276.645624) (xy 54.591458 -276.645624) (xy 54.58614 -276.645201) (xy 54.578569 -276.637727)
			(xy 54.577996 -276.632416) (xy 52.63388 -276.632416) (xy 52.633581 -276.637757) (xy 52.626014 -276.645299)
			(xy 52.620672 -276.645624) (xy 52.104798 -276.645624) (xy 52.096925 -276.645923) (xy 52.081921 -276.650699)
			(xy 52.075334 -276.655022) (xy 52.054263 -276.669424) (xy 52.008616 -276.692251) (xy 51.960008 -276.707806)
			(xy 51.909589 -276.715721) (xy 51.884072 -276.716236) (xy 51.858553 -276.715721) (xy 51.808127 -276.707833)
			(xy 51.759516 -276.69228) (xy 51.713876 -276.669433) (xy 51.69281 -276.655022) (xy 51.686217 -276.65071)
			(xy 51.671218 -276.645921) (xy 51.663346 -276.645624) (xy 51.147472 -276.645624) (xy 51.14221 -276.645126)
			(xy 51.13477 -276.637679) (xy 51.134264 -276.632416) (xy 48.533812 -276.632416) (xy 48.533317 -276.63768)
			(xy 48.525868 -276.645121) (xy 48.520604 -276.645624) (xy 48.00473 -276.645624) (xy 47.996854 -276.645894)
			(xy 47.98185 -276.65069) (xy 47.975266 -276.655022) (xy 47.954186 -276.66941) (xy 47.908543 -276.69224)
			(xy 47.859937 -276.707799) (xy 47.809521 -276.715719) (xy 47.784004 -276.716236) (xy 47.758484 -276.715755)
			(xy 47.708057 -276.707857) (xy 47.659445 -276.692294) (xy 47.613807 -276.669438) (xy 47.592742 -276.655022)
			(xy 47.586164 -276.650684) (xy 47.571154 -276.645911) (xy 47.563278 -276.645624) (xy 47.047404 -276.645624)
			(xy 47.042146 -276.645104) (xy 47.034704 -276.637674) (xy 47.034196 -276.632416) (xy 45.09008 -276.632416)
			(xy 45.089781 -276.637757) (xy 45.082214 -276.645299) (xy 45.076872 -276.645624) (xy 45.076364 -276.645624)
			(xy 44.560744 -276.645624) (xy 44.552868 -276.645899) (xy 44.537865 -276.650692) (xy 44.53128 -276.655022)
			(xy 44.510196 -276.669404) (xy 44.464554 -276.692235) (xy 44.41595 -276.707796) (xy 44.365534 -276.715718)
			(xy 44.340018 -276.716236) (xy 44.314498 -276.715748) (xy 44.264071 -276.707852) (xy 44.21546 -276.692291)
			(xy 44.169821 -276.669437) (xy 44.148756 -276.655022) (xy 44.142175 -276.65069) (xy 44.127167 -276.645913)
			(xy 44.119292 -276.645624) (xy 43.603418 -276.645624) (xy 43.598108 -276.645161) (xy 43.590533 -276.637717)
			(xy 43.589956 -276.632416) (xy 40.990012 -276.632416) (xy 40.989517 -276.63768) (xy 40.982068 -276.645121)
			(xy 40.976804 -276.645624) (xy 40.976296 -276.645624) (xy 40.460676 -276.645624) (xy 40.452802 -276.645913)
			(xy 40.437798 -276.650696) (xy 40.431212 -276.655022) (xy 40.410147 -276.669433) (xy 40.364498 -276.692258)
			(xy 40.315888 -276.70781) (xy 40.265468 -276.715723) (xy 40.23995 -276.716236) (xy 40.21443 -276.715732)
			(xy 40.164004 -276.707841) (xy 40.115393 -276.692285) (xy 40.069754 -276.669435) (xy 40.048688 -276.655022)
			(xy 40.0421 -276.650702) (xy 40.027097 -276.645918) (xy 40.019224 -276.645624) (xy 39.50335 -276.645624)
			(xy 39.498043 -276.645139) (xy 39.490467 -276.637712) (xy 39.489888 -276.632416) (xy 37.545772 -276.632416)
			(xy 37.545481 -276.637759) (xy 37.537909 -276.645302) (xy 37.532564 -276.645624) (xy 37.01669 -276.645624)
			(xy 37.008816 -276.645919) (xy 36.993812 -276.650698) (xy 36.987226 -276.655022) (xy 36.966157 -276.669427)
			(xy 36.92051 -276.692253) (xy 36.871901 -276.707807) (xy 36.821482 -276.715722) (xy 36.795964 -276.716236)
			(xy 36.770445 -276.715725) (xy 36.720019 -276.707836) (xy 36.671408 -276.692282) (xy 36.625768 -276.669434)
			(xy 36.604702 -276.655022) (xy 36.59811 -276.650707) (xy 36.58311 -276.64592) (xy 36.575238 -276.645624)
			(xy 36.059364 -276.645624) (xy 36.054101 -276.645131) (xy 36.046661 -276.63768) (xy 36.046156 -276.632416)
			(xy 33.445704 -276.632416) (xy 33.445216 -276.637682) (xy 33.437762 -276.645124) (xy 33.432496 -276.645624)
			(xy 32.916622 -276.645624) (xy 32.908749 -276.645933) (xy 32.893746 -276.650703) (xy 32.887158 -276.655022)
			(xy 32.866081 -276.669414) (xy 32.820436 -276.692243) (xy 32.77183 -276.707801) (xy 32.721413 -276.715719)
			(xy 32.695896 -276.716236) (xy 32.670375 -276.715759) (xy 32.619948 -276.707859) (xy 32.571337 -276.692296)
			(xy 32.525699 -276.669438) (xy 32.504634 -276.655022) (xy 32.498035 -276.65072) (xy 32.483041 -276.645925)
			(xy 32.47517 -276.645624) (xy 31.959296 -276.645624) (xy 31.954037 -276.64511) (xy 31.946595 -276.637675)
			(xy 31.946088 -276.632416) (xy 30.001972 -276.632416) (xy 30.001681 -276.637759) (xy 29.994109 -276.645302)
			(xy 29.988764 -276.645624) (xy 29.47289 -276.645624) (xy 29.465016 -276.645919) (xy 29.450012 -276.650698)
			(xy 29.443426 -276.655022) (xy 29.422357 -276.669427) (xy 29.37671 -276.692253) (xy 29.328101 -276.707807)
			(xy 29.277682 -276.715722) (xy 29.252164 -276.716236) (xy 29.226645 -276.715725) (xy 29.176219 -276.707836)
			(xy 29.127608 -276.692282) (xy 29.081968 -276.669434) (xy 29.060902 -276.655022) (xy 29.05431 -276.650707)
			(xy 29.03931 -276.64592) (xy 29.031438 -276.645624) (xy 28.515564 -276.645624) (xy 28.510301 -276.645131)
			(xy 28.502861 -276.63768) (xy 28.502356 -276.632416) (xy 25.901904 -276.632416) (xy 25.901416 -276.637682)
			(xy 25.893962 -276.645124) (xy 25.888696 -276.645624) (xy 25.372822 -276.645624) (xy 25.364949 -276.645933)
			(xy 25.349946 -276.650703) (xy 25.343358 -276.655022) (xy 25.322281 -276.669414) (xy 25.276636 -276.692243)
			(xy 25.22803 -276.707801) (xy 25.177613 -276.715719) (xy 25.152096 -276.716236) (xy 25.126575 -276.715759)
			(xy 25.076148 -276.707859) (xy 25.027537 -276.692296) (xy 24.981899 -276.669438) (xy 24.960834 -276.655022)
			(xy 24.954235 -276.65072) (xy 24.939241 -276.645925) (xy 24.93137 -276.645624) (xy 24.415496 -276.645624)
			(xy 24.410237 -276.64511) (xy 24.402795 -276.637675) (xy 24.402288 -276.632416) (xy 22.458172 -276.632416)
			(xy 22.457881 -276.637759) (xy 22.450309 -276.645302) (xy 22.444964 -276.645624) (xy 22.444456 -276.645624)
			(xy 21.928836 -276.645624) (xy 21.92096 -276.645896) (xy 21.905956 -276.650691) (xy 21.899372 -276.655022)
			(xy 21.878291 -276.669408) (xy 21.832647 -276.692238) (xy 21.784043 -276.707798) (xy 21.733626 -276.715718)
			(xy 21.70811 -276.716236) (xy 21.68259 -276.715752) (xy 21.632163 -276.707855) (xy 21.583551 -276.692293)
			(xy 21.537913 -276.669437) (xy 21.516848 -276.655022) (xy 21.510268 -276.650686) (xy 21.495259 -276.645912)
			(xy 21.487384 -276.645624) (xy 20.97151 -276.645624) (xy 20.966199 -276.645166) (xy 20.958625 -276.637718)
			(xy 20.958048 -276.632416) (xy 18.358104 -276.632416) (xy 18.357616 -276.637682) (xy 18.350162 -276.645124)
			(xy 18.344896 -276.645624) (xy 18.344388 -276.645624) (xy 17.828768 -276.645624) (xy 17.820893 -276.64591)
			(xy 17.80589 -276.650695) (xy 17.799304 -276.655022) (xy 17.778214 -276.669394) (xy 17.732574 -276.692227)
			(xy 17.683972 -276.707791) (xy 17.633558 -276.715716) (xy 17.608042 -276.716236) (xy 17.582522 -276.715736)
			(xy 17.532096 -276.707843) (xy 17.483485 -276.692286) (xy 17.437846 -276.669435) (xy 17.41678 -276.655022)
			(xy 17.410193 -276.650699) (xy 17.39519 -276.645917) (xy 17.387316 -276.645624) (xy 16.871442 -276.645624)
			(xy 16.866134 -276.645145) (xy 16.858559 -276.637713) (xy 16.85798 -276.632416) (xy 2.509012 -276.632416)
			(xy 2.509012 -277.482554) (xy 16.85798 -277.482554) (xy 16.85798 -276.988016) (xy 16.858336 -276.982689)
			(xy 16.865862 -276.975148) (xy 16.871188 -276.974808) (xy 16.871696 -276.974808) (xy 17.38757 -276.974808)
			(xy 17.395379 -276.97448) (xy 17.41025 -276.969704) (xy 17.41678 -276.96541) (xy 17.437869 -276.951061)
			(xy 17.48353 -276.92833) (xy 17.532136 -276.912871) (xy 17.582539 -276.905048) (xy 17.633545 -276.905048)
			(xy 17.683948 -276.912871) (xy 17.732554 -276.92833) (xy 17.778215 -276.951061) (xy 17.799304 -276.96541)
			(xy 17.805835 -276.969702) (xy 17.820705 -276.974484) (xy 17.828514 -276.974808) (xy 18.344642 -276.974808)
			(xy 18.349944 -276.975291) (xy 18.357511 -276.982724) (xy 18.358104 -276.988016) (xy 18.358104 -277.482554)
			(xy 18.358085 -277.482808) (xy 24.402288 -277.482808) (xy 24.402288 -277.4823) (xy 24.402288 -276.988016)
			(xy 24.402637 -276.982687) (xy 24.410167 -276.975145) (xy 24.415496 -276.974808) (xy 24.931624 -276.974808)
			(xy 24.939435 -276.974503) (xy 24.954306 -276.969711) (xy 24.960834 -276.96541) (xy 24.981923 -276.951061)
			(xy 25.027584 -276.92833) (xy 25.07619 -276.912871) (xy 25.126593 -276.905048) (xy 25.177599 -276.905048)
			(xy 25.228002 -276.912871) (xy 25.276608 -276.92833) (xy 25.322269 -276.951061) (xy 25.343358 -276.96541)
			(xy 25.349877 -276.969723) (xy 25.364757 -276.974492) (xy 25.372568 -276.974808) (xy 25.888696 -276.974808)
			(xy 25.894032 -276.975131) (xy 25.901574 -276.98268) (xy 25.901904 -276.988016) (xy 25.901904 -277.482554)
			(xy 25.901877 -277.482808) (xy 31.946088 -277.482808) (xy 31.946088 -277.4823) (xy 31.946088 -276.988016)
			(xy 31.946437 -276.982687) (xy 31.953967 -276.975145) (xy 31.959296 -276.974808) (xy 32.475424 -276.974808)
			(xy 32.483235 -276.974503) (xy 32.498106 -276.969711) (xy 32.504634 -276.96541) (xy 32.525723 -276.951061)
			(xy 32.571384 -276.92833) (xy 32.61999 -276.912871) (xy 32.670393 -276.905048) (xy 32.721399 -276.905048)
			(xy 32.771802 -276.912871) (xy 32.820408 -276.92833) (xy 32.866069 -276.951061) (xy 32.887158 -276.96541)
			(xy 32.893677 -276.969723) (xy 32.908557 -276.974492) (xy 32.916368 -276.974808) (xy 33.432496 -276.974808)
			(xy 33.437832 -276.975131) (xy 33.445374 -276.98268) (xy 33.445704 -276.988016) (xy 33.445704 -277.482554)
			(xy 39.489888 -277.482554) (xy 39.489888 -276.988016) (xy 39.490237 -276.982687) (xy 39.497767 -276.975145)
			(xy 39.503096 -276.974808) (xy 39.503604 -276.974808) (xy 40.019478 -276.974808) (xy 40.027287 -276.974484)
			(xy 40.042158 -276.969705) (xy 40.048688 -276.96541) (xy 40.069777 -276.951061) (xy 40.115438 -276.92833)
			(xy 40.164044 -276.912871) (xy 40.214447 -276.905048) (xy 40.265453 -276.905048) (xy 40.315856 -276.912871)
			(xy 40.364462 -276.92833) (xy 40.410123 -276.951061) (xy 40.431212 -276.96541) (xy 40.437741 -276.969706)
			(xy 40.452613 -276.974486) (xy 40.460422 -276.974808) (xy 40.97655 -276.974808) (xy 40.981841 -276.975353)
			(xy 40.989413 -276.982739) (xy 40.990012 -276.988016) (xy 40.990012 -277.482554) (xy 40.989984 -277.482808)
			(xy 47.034196 -277.482808) (xy 47.034196 -277.4823) (xy 47.034196 -276.988016) (xy 47.034538 -276.982685)
			(xy 47.042073 -276.975143) (xy 47.047404 -276.974808) (xy 47.563532 -276.974808) (xy 47.571339 -276.974464)
			(xy 47.586211 -276.969699) (xy 47.592742 -276.96541) (xy 47.613831 -276.951061) (xy 47.659492 -276.92833)
			(xy 47.708098 -276.912871) (xy 47.758501 -276.905048) (xy 47.809507 -276.905048) (xy 47.85991 -276.912871)
			(xy 47.908516 -276.92833) (xy 47.954177 -276.951061) (xy 47.975266 -276.96541) (xy 47.981805 -276.969688)
			(xy 47.996669 -276.974479) (xy 48.004476 -276.974808) (xy 48.520604 -276.974808) (xy 48.525941 -276.975126)
			(xy 48.533482 -276.982679) (xy 48.533812 -276.988016) (xy 48.533812 -277.482554) (xy 54.577996 -277.482554)
			(xy 54.577996 -276.988016) (xy 54.578338 -276.982685) (xy 54.585873 -276.975143) (xy 54.591204 -276.974808)
			(xy 56.064658 -276.974808) (xy 56.06995 -276.975347) (xy 56.077521 -276.982737) (xy 56.07812 -276.988016)
			(xy 56.07812 -277.482554) (xy 56.078104 -277.482808) (xy 163.678108 -277.482808) (xy 163.678108 -277.4823)
			(xy 163.678108 -276.988016) (xy 163.678439 -276.982682) (xy 163.685982 -276.975139) (xy 163.691316 -276.974808)
			(xy 165.164516 -276.974808) (xy 165.169785 -276.975285) (xy 165.177227 -276.982746) (xy 165.177724 -276.988016)
			(xy 165.177724 -277.482554) (xy 171.221908 -277.482554) (xy 171.221908 -276.988016) (xy 171.222239 -276.982682)
			(xy 171.229782 -276.975139) (xy 171.235116 -276.974808) (xy 171.235624 -276.974808) (xy 171.751498 -276.974808)
			(xy 171.759308 -276.974492) (xy 171.774179 -276.969707) (xy 171.780708 -276.96541) (xy 171.801797 -276.951061)
			(xy 171.847458 -276.92833) (xy 171.896064 -276.912871) (xy 171.946467 -276.905048) (xy 171.997473 -276.905048)
			(xy 172.047876 -276.912871) (xy 172.096482 -276.92833) (xy 172.142143 -276.951061) (xy 172.163232 -276.96541)
			(xy 172.169757 -276.969713) (xy 172.184632 -276.974489) (xy 172.192442 -276.974808) (xy 172.70857 -276.974808)
			(xy 172.713863 -276.975339) (xy 172.721434 -276.982735) (xy 172.722032 -276.988016) (xy 172.722032 -277.482554)
			(xy 172.722016 -277.482808) (xy 178.766216 -277.482808) (xy 178.766216 -277.4823) (xy 178.766216 -276.988016)
			(xy 178.76654 -276.98268) (xy 178.774088 -276.975137) (xy 178.779424 -276.974808) (xy 179.295552 -276.974808)
			(xy 179.30336 -276.974473) (xy 179.318232 -276.969701) (xy 179.324762 -276.96541) (xy 179.345851 -276.951061)
			(xy 179.391512 -276.92833) (xy 179.440118 -276.912871) (xy 179.490521 -276.905048) (xy 179.541527 -276.905048)
			(xy 179.59193 -276.912871) (xy 179.640536 -276.92833) (xy 179.686197 -276.951061) (xy 179.707286 -276.96541)
			(xy 179.713821 -276.969696) (xy 179.728688 -276.974482) (xy 179.736496 -276.974808) (xy 180.252624 -276.974808)
			(xy 180.257893 -276.975281) (xy 180.265335 -276.982745) (xy 180.265832 -276.988016) (xy 180.265832 -277.482554)
			(xy 186.310016 -277.482554) (xy 186.310016 -276.988016) (xy 186.31034 -276.98268) (xy 186.317888 -276.975137)
			(xy 186.323224 -276.974808) (xy 186.323732 -276.974808) (xy 186.839606 -276.974808) (xy 186.847416 -276.974496)
			(xy 186.862287 -276.969708) (xy 186.868816 -276.96541) (xy 186.889905 -276.951061) (xy 186.935566 -276.92833)
			(xy 186.984172 -276.912871) (xy 187.034575 -276.905048) (xy 187.085581 -276.905048) (xy 187.135984 -276.912871)
			(xy 187.18459 -276.92833) (xy 187.230251 -276.951061) (xy 187.25134 -276.96541) (xy 187.257863 -276.969716)
			(xy 187.27274 -276.97449) (xy 187.28055 -276.974808) (xy 187.796678 -276.974808) (xy 187.801972 -276.975334)
			(xy 187.809543 -276.982734) (xy 187.81014 -276.988016) (xy 187.81014 -277.482554) (xy 187.810124 -277.482808)
			(xy 193.854324 -277.482808) (xy 193.854324 -277.4823) (xy 193.854324 -276.988016) (xy 193.854641 -276.982678)
			(xy 193.862194 -276.975134) (xy 193.867532 -276.974808) (xy 194.38366 -276.974808) (xy 194.391468 -276.974476)
			(xy 194.40634 -276.969702) (xy 194.41287 -276.96541) (xy 194.433959 -276.951061) (xy 194.47962 -276.92833)
			(xy 194.528226 -276.912871) (xy 194.578629 -276.905048) (xy 194.629635 -276.905048) (xy 194.680038 -276.912871)
			(xy 194.728644 -276.92833) (xy 194.774305 -276.951061) (xy 194.795394 -276.96541) (xy 194.801927 -276.969699)
			(xy 194.816796 -276.974483) (xy 194.824604 -276.974808) (xy 195.340732 -276.974808) (xy 195.346002 -276.975275)
			(xy 195.353444 -276.982744) (xy 195.35394 -276.988016) (xy 195.35394 -277.482554) (xy 195.353916 -277.482808)
			(xy 201.398124 -277.482808) (xy 201.398124 -277.4823) (xy 201.398124 -276.988016) (xy 201.398441 -276.982678)
			(xy 201.405994 -276.975134) (xy 201.411332 -276.974808) (xy 201.92746 -276.974808) (xy 201.935268 -276.974476)
			(xy 201.95014 -276.969702) (xy 201.95667 -276.96541) (xy 201.977759 -276.951061) (xy 202.02342 -276.92833)
			(xy 202.072026 -276.912871) (xy 202.122429 -276.905048) (xy 202.173435 -276.905048) (xy 202.223838 -276.912871)
			(xy 202.272444 -276.92833) (xy 202.318105 -276.951061) (xy 202.339194 -276.96541) (xy 202.345727 -276.969699)
			(xy 202.360596 -276.974483) (xy 202.368404 -276.974808) (xy 202.884532 -276.974808) (xy 202.889802 -276.975275)
			(xy 202.897244 -276.982744) (xy 202.89774 -276.988016) (xy 202.89774 -277.4823) (xy 264.798048 -277.4823)
			(xy 264.798048 -276.987762) (xy 264.798526 -276.982391) (xy 264.806137 -276.974807) (xy 264.81151 -276.9743)
			(xy 265.327638 -276.9743) (xy 265.335446 -276.97396) (xy 265.350317 -276.969192) (xy 265.356848 -276.964902)
			(xy 265.377937 -276.950553) (xy 265.423598 -276.927822) (xy 265.472204 -276.912363) (xy 265.522607 -276.90454)
			(xy 265.573613 -276.90454) (xy 265.624016 -276.912363) (xy 265.672622 -276.927822) (xy 265.718283 -276.950553)
			(xy 265.739372 -276.964902) (xy 265.74591 -276.969182) (xy 265.760775 -276.973972) (xy 265.768582 -276.9743)
			(xy 266.28471 -276.9743) (xy 266.290066 -276.97484) (xy 266.297649 -276.982407) (xy 266.298172 -276.987762)
			(xy 266.298172 -277.4823) (xy 272.342356 -277.4823) (xy 272.342356 -276.987762) (xy 272.3428 -276.982449)
			(xy 272.35026 -276.97488) (xy 272.355564 -276.9743) (xy 272.871692 -276.9743) (xy 272.879502 -276.973983)
			(xy 272.894373 -276.969199) (xy 272.900902 -276.964902) (xy 272.921991 -276.950553) (xy 272.967652 -276.927822)
			(xy 273.016258 -276.912363) (xy 273.066661 -276.90454) (xy 273.117667 -276.90454) (xy 273.16807 -276.912363)
			(xy 273.216676 -276.927822) (xy 273.262337 -276.950553) (xy 273.283426 -276.964902) (xy 273.289952 -276.969202)
			(xy 273.304826 -276.97398) (xy 273.312636 -276.9743) (xy 273.828764 -276.9743) (xy 273.834093 -276.974652)
			(xy 273.841637 -276.982179) (xy 273.841972 -276.987508) (xy 273.841972 -276.988016) (xy 273.841972 -277.4823)
			(xy 279.886156 -277.4823) (xy 279.886156 -276.987762) (xy 279.8866 -276.982449) (xy 279.89406 -276.97488)
			(xy 279.899364 -276.9743) (xy 280.415492 -276.9743) (xy 280.423302 -276.973983) (xy 280.438173 -276.969199)
			(xy 280.444702 -276.964902) (xy 280.465791 -276.950553) (xy 280.511452 -276.927822) (xy 280.560058 -276.912363)
			(xy 280.610461 -276.90454) (xy 280.661467 -276.90454) (xy 280.71187 -276.912363) (xy 280.760476 -276.927822)
			(xy 280.806137 -276.950553) (xy 280.827226 -276.964902) (xy 280.833752 -276.969202) (xy 280.848626 -276.97398)
			(xy 280.856436 -276.9743) (xy 281.372564 -276.9743) (xy 281.377893 -276.974652) (xy 281.385437 -276.982179)
			(xy 281.385772 -276.987508) (xy 281.385772 -276.988016) (xy 281.385772 -277.4823) (xy 287.429956 -277.4823)
			(xy 287.429956 -276.987762) (xy 287.430427 -276.982389) (xy 287.438043 -276.974805) (xy 287.443418 -276.9743)
			(xy 287.959546 -276.9743) (xy 287.967354 -276.973964) (xy 287.982226 -276.969193) (xy 287.988756 -276.964902)
			(xy 288.009845 -276.950553) (xy 288.055506 -276.927822) (xy 288.104112 -276.912363) (xy 288.154515 -276.90454)
			(xy 288.205521 -276.90454) (xy 288.255924 -276.912363) (xy 288.30453 -276.927822) (xy 288.350191 -276.950553)
			(xy 288.37128 -276.964902) (xy 288.377817 -276.969185) (xy 288.392683 -276.973973) (xy 288.40049 -276.9743)
			(xy 288.916618 -276.9743) (xy 288.921975 -276.974834) (xy 288.929558 -276.982406) (xy 288.93008 -276.987762)
			(xy 288.93008 -277.4823) (xy 294.974264 -277.4823) (xy 294.974264 -276.987762) (xy 294.974701 -276.982448)
			(xy 294.982165 -276.974877) (xy 294.987472 -276.9743) (xy 295.5036 -276.9743) (xy 295.51141 -276.973986)
			(xy 295.526281 -276.9692) (xy 295.53281 -276.964902) (xy 295.553899 -276.950553) (xy 295.59956 -276.927822)
			(xy 295.648166 -276.912363) (xy 295.698569 -276.90454) (xy 295.749575 -276.90454) (xy 295.799978 -276.912363)
			(xy 295.848584 -276.927822) (xy 295.894245 -276.950553) (xy 295.915334 -276.964902) (xy 295.921859 -276.969205)
			(xy 295.936734 -276.973981) (xy 295.944544 -276.9743) (xy 296.460672 -276.9743) (xy 296.466003 -276.974646)
			(xy 296.473546 -276.982178) (xy 296.47388 -276.987508) (xy 296.47388 -276.988016) (xy 296.47388 -277.4823)
			(xy 302.518064 -277.4823) (xy 302.518064 -276.987762) (xy 302.518528 -276.982387) (xy 302.526149 -276.974802)
			(xy 302.531526 -276.9743) (xy 304.004726 -276.9743) (xy 304.010084 -276.974829) (xy 304.017666 -276.982405)
			(xy 304.018188 -276.987762) (xy 304.018188 -277.4823) (xy 411.618176 -277.4823) (xy 411.618176 -276.987762)
			(xy 411.618602 -276.982445) (xy 411.626074 -276.974874) (xy 411.631384 -276.9743) (xy 413.104584 -276.9743)
			(xy 413.109916 -276.974638) (xy 413.117458 -276.982176) (xy 413.117792 -276.987508) (xy 413.117792 -276.988016)
			(xy 413.117792 -277.4823) (xy 419.161976 -277.4823) (xy 419.161976 -276.987762) (xy 419.162429 -276.982384)
			(xy 419.170058 -276.974799) (xy 419.175438 -276.9743) (xy 419.691566 -276.9743) (xy 419.699375 -276.973972)
			(xy 419.714246 -276.969196) (xy 419.720776 -276.964902) (xy 419.741865 -276.950553) (xy 419.787526 -276.927822)
			(xy 419.836132 -276.912363) (xy 419.886535 -276.90454) (xy 419.937541 -276.90454) (xy 419.987944 -276.912363)
			(xy 420.03655 -276.927822) (xy 420.082211 -276.950553) (xy 420.1033 -276.964902) (xy 420.109832 -276.969192)
			(xy 420.124702 -276.973976) (xy 420.13251 -276.9743) (xy 420.648638 -276.9743) (xy 420.653997 -276.974821)
			(xy 420.661579 -276.982403) (xy 420.6621 -276.987762) (xy 420.6621 -277.4823) (xy 426.706284 -277.4823)
			(xy 426.706284 -276.987762) (xy 426.706703 -276.982443) (xy 426.71418 -276.974872) (xy 426.719492 -276.9743)
			(xy 427.23562 -276.9743) (xy 427.243431 -276.973995) (xy 427.258302 -276.969203) (xy 427.26483 -276.964902)
			(xy 427.285919 -276.950553) (xy 427.33158 -276.927822) (xy 427.380186 -276.912363) (xy 427.430589 -276.90454)
			(xy 427.481595 -276.90454) (xy 427.531998 -276.912363) (xy 427.580604 -276.927822) (xy 427.626265 -276.950553)
			(xy 427.647354 -276.964902) (xy 427.653874 -276.969213) (xy 427.668753 -276.973984) (xy 427.676564 -276.9743)
			(xy 428.192692 -276.9743) (xy 428.198025 -276.974633) (xy 428.205567 -276.982175) (xy 428.2059 -276.987508)
			(xy 428.2059 -276.988016) (xy 428.2059 -277.4823) (xy 434.250084 -277.4823) (xy 434.250084 -276.987762)
			(xy 434.250358 -276.982311) (xy 434.258093 -276.974624) (xy 434.263546 -276.9743) (xy 434.779674 -276.9743)
			(xy 434.787483 -276.973975) (xy 434.802355 -276.969197) (xy 434.808884 -276.964902) (xy 434.829973 -276.950553)
			(xy 434.875634 -276.927822) (xy 434.92424 -276.912363) (xy 434.974643 -276.90454) (xy 435.025649 -276.90454)
			(xy 435.076052 -276.912363) (xy 435.124658 -276.927822) (xy 435.170319 -276.950553) (xy 435.191408 -276.964902)
			(xy 435.197938 -276.969195) (xy 435.212809 -276.973977) (xy 435.220618 -276.9743) (xy 435.736746 -276.9743)
			(xy 435.742106 -276.974816) (xy 435.749687 -276.982401) (xy 435.750208 -276.987762) (xy 435.750208 -277.4823)
			(xy 441.794392 -277.4823) (xy 441.794392 -276.987762) (xy 441.794892 -276.982464) (xy 441.802313 -276.974898)
			(xy 441.8076 -276.9743) (xy 442.323728 -276.9743) (xy 442.331539 -276.973998) (xy 442.34641 -276.969204)
			(xy 442.352938 -276.964902) (xy 442.374027 -276.950553) (xy 442.419688 -276.927822) (xy 442.468294 -276.912363)
			(xy 442.518697 -276.90454) (xy 442.569703 -276.90454) (xy 442.620106 -276.912363) (xy 442.668712 -276.927822)
			(xy 442.714373 -276.950553) (xy 442.735462 -276.964902) (xy 442.742003 -276.969178) (xy 442.756866 -276.97397)
			(xy 442.764672 -276.9743) (xy 443.2808 -276.9743) (xy 443.286134 -276.974627) (xy 443.293676 -276.982174)
			(xy 443.294008 -276.987508) (xy 443.294008 -276.988016) (xy 443.294008 -277.4823) (xy 449.338192 -277.4823)
			(xy 449.338192 -276.987762) (xy 449.338692 -276.982464) (xy 449.346113 -276.974898) (xy 449.3514 -276.9743)
			(xy 449.867528 -276.9743) (xy 449.875339 -276.973998) (xy 449.89021 -276.969204) (xy 449.896738 -276.964902)
			(xy 449.917827 -276.950553) (xy 449.963488 -276.927822) (xy 450.012094 -276.912363) (xy 450.062497 -276.90454)
			(xy 450.113503 -276.90454) (xy 450.163906 -276.912363) (xy 450.212512 -276.927822) (xy 450.258173 -276.950553)
			(xy 450.279262 -276.964902) (xy 450.285803 -276.969178) (xy 450.300666 -276.97397) (xy 450.308472 -276.9743)
			(xy 450.8246 -276.9743) (xy 450.829934 -276.974627) (xy 450.837476 -276.982174) (xy 450.837808 -276.987508)
			(xy 450.837808 -276.988016) (xy 450.837808 -277.4823) (xy 450.837305 -277.487563) (xy 450.829863 -277.495005)
			(xy 450.8246 -277.495508) (xy 450.308726 -277.495508) (xy 450.30085 -277.495779) (xy 450.285847 -277.500575)
			(xy 450.279262 -277.504906) (xy 450.258182 -277.519294) (xy 450.212539 -277.542124) (xy 450.163933 -277.557683)
			(xy 450.113517 -277.565603) (xy 450.088 -277.56612) (xy 450.062479 -277.565644) (xy 450.012052 -277.557745)
			(xy 449.963441 -277.542181) (xy 449.917803 -277.519322) (xy 449.896738 -277.504906) (xy 449.890139 -277.500603)
			(xy 449.875145 -277.495809) (xy 449.867274 -277.495508) (xy 449.3514 -277.495508) (xy 449.346137 -277.495005)
			(xy 449.338695 -277.487563) (xy 449.338192 -277.4823) (xy 443.294008 -277.4823) (xy 443.293505 -277.487563)
			(xy 443.286063 -277.495005) (xy 443.2808 -277.495508) (xy 442.764926 -277.495508) (xy 442.75705 -277.495779)
			(xy 442.742047 -277.500575) (xy 442.735462 -277.504906) (xy 442.714382 -277.519294) (xy 442.668739 -277.542124)
			(xy 442.620133 -277.557683) (xy 442.569717 -277.565603) (xy 442.5442 -277.56612) (xy 442.518679 -277.565644)
			(xy 442.468252 -277.557745) (xy 442.419641 -277.542181) (xy 442.374003 -277.519322) (xy 442.352938 -277.504906)
			(xy 442.346339 -277.500603) (xy 442.331345 -277.495809) (xy 442.323474 -277.495508) (xy 441.8076 -277.495508)
			(xy 441.802337 -277.495005) (xy 441.794895 -277.487563) (xy 441.794392 -277.4823) (xy 435.750208 -277.4823)
			(xy 435.749705 -277.487563) (xy 435.742263 -277.495005) (xy 435.737 -277.495508) (xy 435.736492 -277.495508)
			(xy 435.220872 -277.495508) (xy 435.212998 -277.495798) (xy 435.197994 -277.500581) (xy 435.191408 -277.504906)
			(xy 435.170343 -277.519317) (xy 435.124694 -277.542142) (xy 435.076084 -277.557695) (xy 435.025664 -277.565607)
			(xy 435.000146 -277.56612) (xy 434.974626 -277.565621) (xy 434.9242 -277.557728) (xy 434.875588 -277.542171)
			(xy 434.829949 -277.51932) (xy 434.808884 -277.504906) (xy 434.802298 -277.500582) (xy 434.787294 -277.495801)
			(xy 434.77942 -277.495508) (xy 434.263546 -277.495508) (xy 434.258258 -277.494952) (xy 434.250687 -277.487574)
			(xy 434.250084 -277.4823) (xy 428.2059 -277.4823) (xy 428.205573 -277.487634) (xy 428.198026 -277.495176)
			(xy 428.192692 -277.495508) (xy 427.676818 -277.495508) (xy 427.668946 -277.495818) (xy 427.653942 -277.500587)
			(xy 427.647354 -277.504906) (xy 427.626276 -277.519297) (xy 427.580632 -277.542127) (xy 427.532026 -277.557685)
			(xy 427.481609 -277.565603) (xy 427.456092 -277.56612) (xy 427.430573 -277.565598) (xy 427.380148 -277.557712)
			(xy 427.331536 -277.542162) (xy 427.285896 -277.519317) (xy 427.26483 -277.504906) (xy 427.258233 -277.5006)
			(xy 427.243237 -277.495808) (xy 427.235366 -277.495508) (xy 426.719492 -277.495508) (xy 426.714228 -277.495011)
			(xy 426.706786 -277.487564) (xy 426.706284 -277.4823) (xy 420.6621 -277.4823) (xy 420.661773 -277.487634)
			(xy 420.654226 -277.495176) (xy 420.648892 -277.495508) (xy 420.648384 -277.495508) (xy 420.132764 -277.495508)
			(xy 420.12489 -277.495795) (xy 420.109886 -277.50058) (xy 420.1033 -277.504906) (xy 420.08221 -277.519278)
			(xy 420.03657 -277.542112) (xy 419.987968 -277.557675) (xy 419.937554 -277.5656) (xy 419.912038 -277.56612)
			(xy 419.886518 -277.565625) (xy 419.836092 -277.557731) (xy 419.78748 -277.542173) (xy 419.741841 -277.51932)
			(xy 419.720776 -277.504906) (xy 419.714191 -277.500579) (xy 419.699186 -277.4958) (xy 419.691312 -277.495508)
			(xy 419.175438 -277.495508) (xy 419.17015 -277.494957) (xy 419.162579 -277.487575) (xy 419.161976 -277.4823)
			(xy 413.117792 -277.4823) (xy 413.117472 -277.487636) (xy 413.109921 -277.495178) (xy 413.104584 -277.495508)
			(xy 411.631384 -277.495508) (xy 411.626119 -277.495016) (xy 411.618678 -277.487565) (xy 411.618176 -277.4823)
			(xy 304.018188 -277.4823) (xy 304.017871 -277.487637) (xy 304.010318 -277.495179) (xy 304.00498 -277.495508)
			(xy 302.531526 -277.495508) (xy 302.526236 -277.494965) (xy 302.518666 -277.487577) (xy 302.518064 -277.4823)
			(xy 296.47388 -277.4823) (xy 296.473571 -277.487639) (xy 296.466012 -277.495182) (xy 296.460672 -277.495508)
			(xy 295.944798 -277.495508) (xy 295.936925 -277.495809) (xy 295.921921 -277.500584) (xy 295.915334 -277.504906)
			(xy 295.894262 -277.519306) (xy 295.848616 -277.542134) (xy 295.800008 -277.557689) (xy 295.749589 -277.565605)
			(xy 295.724072 -277.56612) (xy 295.698553 -277.565608) (xy 295.648127 -277.557719) (xy 295.599515 -277.542166)
			(xy 295.553876 -277.519318) (xy 295.53281 -277.504906) (xy 295.526218 -277.500593) (xy 295.511218 -277.495805)
			(xy 295.503346 -277.495508) (xy 294.987472 -277.495508) (xy 294.982206 -277.495024) (xy 294.974765 -277.487567)
			(xy 294.974264 -277.4823) (xy 288.93008 -277.4823) (xy 288.929771 -277.487639) (xy 288.922212 -277.495182)
			(xy 288.916872 -277.495508) (xy 288.916364 -277.495508) (xy 288.400744 -277.495508) (xy 288.392869 -277.495786)
			(xy 288.377865 -277.500577) (xy 288.37128 -277.504906) (xy 288.350195 -277.519286) (xy 288.304553 -277.542118)
			(xy 288.25595 -277.55768) (xy 288.205534 -277.565602) (xy 288.180018 -277.56612) (xy 288.154498 -277.565635)
			(xy 288.104071 -277.557738) (xy 288.055459 -277.542177) (xy 288.009821 -277.519321) (xy 287.988756 -277.504906)
			(xy 287.982176 -277.500572) (xy 287.967167 -277.495797) (xy 287.959292 -277.495508) (xy 287.443418 -277.495508)
			(xy 287.438127 -277.494971) (xy 287.430558 -277.487578) (xy 287.429956 -277.4823) (xy 281.385772 -277.4823)
			(xy 281.38547 -277.487641) (xy 281.377906 -277.495184) (xy 281.372564 -277.495508) (xy 280.85669 -277.495508)
			(xy 280.848816 -277.495806) (xy 280.833813 -277.500583) (xy 280.827226 -277.504906) (xy 280.806156 -277.519309)
			(xy 280.760509 -277.542136) (xy 280.711901 -277.557691) (xy 280.661481 -277.565606) (xy 280.635964 -277.56612)
			(xy 280.610445 -277.565612) (xy 280.560019 -277.557722) (xy 280.511407 -277.542168) (xy 280.465768 -277.519318)
			(xy 280.444702 -277.504906) (xy 280.438111 -277.500589) (xy 280.423111 -277.495803) (xy 280.415238 -277.495508)
			(xy 279.899364 -277.495508) (xy 279.894097 -277.495029) (xy 279.886657 -277.487568) (xy 279.886156 -277.4823)
			(xy 273.841972 -277.4823) (xy 273.84167 -277.487641) (xy 273.834106 -277.495184) (xy 273.828764 -277.495508)
			(xy 273.31289 -277.495508) (xy 273.305016 -277.495806) (xy 273.290013 -277.500583) (xy 273.283426 -277.504906)
			(xy 273.262356 -277.519309) (xy 273.216709 -277.542136) (xy 273.168101 -277.557691) (xy 273.117681 -277.565606)
			(xy 273.092164 -277.56612) (xy 273.066645 -277.565612) (xy 273.016219 -277.557722) (xy 272.967607 -277.542168)
			(xy 272.921968 -277.519318) (xy 272.900902 -277.504906) (xy 272.894311 -277.500589) (xy 272.879311 -277.495803)
			(xy 272.871438 -277.495508) (xy 272.355564 -277.495508) (xy 272.350297 -277.495029) (xy 272.342857 -277.487568)
			(xy 272.342356 -277.4823) (xy 266.298172 -277.4823) (xy 266.29787 -277.487641) (xy 266.290306 -277.495184)
			(xy 266.284964 -277.495508) (xy 266.284456 -277.495508) (xy 265.768836 -277.495508) (xy 265.76096 -277.495783)
			(xy 265.745957 -277.500576) (xy 265.739372 -277.504906) (xy 265.718289 -277.51929) (xy 265.672647 -277.542121)
			(xy 265.624042 -277.557681) (xy 265.573626 -277.565602) (xy 265.54811 -277.56612) (xy 265.52259 -277.565639)
			(xy 265.472162 -277.557741) (xy 265.423551 -277.542179) (xy 265.377913 -277.519322) (xy 265.356848 -277.504906)
			(xy 265.35027 -277.500569) (xy 265.335259 -277.495796) (xy 265.327384 -277.495508) (xy 264.81151 -277.495508)
			(xy 264.806218 -277.494976) (xy 264.798649 -277.487579) (xy 264.798048 -277.4823) (xy 202.89774 -277.4823)
			(xy 202.89774 -277.482554) (xy 202.897244 -277.487857) (xy 202.889824 -277.495432) (xy 202.884532 -277.496016)
			(xy 202.368658 -277.496016) (xy 202.36085 -277.496352) (xy 202.345978 -277.501122) (xy 202.339448 -277.505414)
			(xy 202.318335 -277.519777) (xy 202.272609 -277.542502) (xy 202.223933 -277.557928) (xy 202.173464 -277.56569)
			(xy 202.147932 -277.56612) (xy 202.122402 -277.565675) (xy 202.071938 -277.557903) (xy 202.023265 -277.542477)
			(xy 201.977538 -277.519761) (xy 201.956416 -277.505414) (xy 201.949879 -277.501131) (xy 201.935013 -277.496343)
			(xy 201.927206 -277.496016) (xy 201.411332 -277.496016) (xy 201.406006 -277.495652) (xy 201.398464 -277.488133)
			(xy 201.398124 -277.482808) (xy 195.353916 -277.482808) (xy 195.353444 -277.487857) (xy 195.346024 -277.495432)
			(xy 195.340732 -277.496016) (xy 194.824858 -277.496016) (xy 194.81705 -277.496352) (xy 194.802178 -277.501122)
			(xy 194.795648 -277.505414) (xy 194.774535 -277.519777) (xy 194.728809 -277.542502) (xy 194.680133 -277.557928)
			(xy 194.629664 -277.56569) (xy 194.604132 -277.56612) (xy 194.578602 -277.565675) (xy 194.528138 -277.557903)
			(xy 194.479465 -277.542477) (xy 194.433738 -277.519761) (xy 194.412616 -277.505414) (xy 194.406079 -277.501131)
			(xy 194.391213 -277.496343) (xy 194.383406 -277.496016) (xy 193.867532 -277.496016) (xy 193.862206 -277.495652)
			(xy 193.854664 -277.488133) (xy 193.854324 -277.482808) (xy 187.810124 -277.482808) (xy 187.809788 -277.487988)
			(xy 187.802111 -277.495678) (xy 187.796678 -277.496016) (xy 187.280804 -277.496016) (xy 187.272994 -277.496329)
			(xy 187.258122 -277.501115) (xy 187.251594 -277.505414) (xy 187.230469 -277.519758) (xy 187.184747 -277.542487)
			(xy 187.136074 -277.557919) (xy 187.085609 -277.565686) (xy 187.060078 -277.56612) (xy 187.034547 -277.565703)
			(xy 186.984082 -277.557922) (xy 186.935409 -277.542488) (xy 186.889683 -277.519765) (xy 186.868562 -277.505414)
			(xy 186.862037 -277.501111) (xy 186.847162 -277.496335) (xy 186.839352 -277.496016) (xy 186.323478 -277.496016)
			(xy 186.318029 -277.495731) (xy 186.310342 -277.488005) (xy 186.310016 -277.482554) (xy 180.265832 -277.482554)
			(xy 180.265343 -277.487859) (xy 180.257918 -277.495434) (xy 180.252624 -277.496016) (xy 179.73675 -277.496016)
			(xy 179.728942 -277.496348) (xy 179.71407 -277.501121) (xy 179.70754 -277.505414) (xy 179.68643 -277.519781)
			(xy 179.640702 -277.542505) (xy 179.592025 -277.55793) (xy 179.541556 -277.565691) (xy 179.516024 -277.56612)
			(xy 179.490494 -277.565679) (xy 179.44003 -277.557906) (xy 179.391357 -277.542478) (xy 179.34563 -277.519762)
			(xy 179.324508 -277.505414) (xy 179.317973 -277.501128) (xy 179.303106 -277.496342) (xy 179.295298 -277.496016)
			(xy 178.779424 -277.496016) (xy 178.774097 -277.495658) (xy 178.766555 -277.488134) (xy 178.766216 -277.482808)
			(xy 172.722016 -277.482808) (xy 172.721687 -277.48799) (xy 172.714006 -277.495681) (xy 172.70857 -277.496016)
			(xy 172.192696 -277.496016) (xy 172.184885 -277.496325) (xy 172.170014 -277.501114) (xy 172.163486 -277.505414)
			(xy 172.142363 -277.519761) (xy 172.09664 -277.542489) (xy 172.047967 -277.55792) (xy 171.997501 -277.565687)
			(xy 171.97197 -277.56612) (xy 171.946439 -277.565707) (xy 171.895974 -277.557925) (xy 171.847301 -277.542489)
			(xy 171.801575 -277.519765) (xy 171.780454 -277.505414) (xy 171.773931 -277.501108) (xy 171.759055 -277.496334)
			(xy 171.751244 -277.496016) (xy 171.23537 -277.496016) (xy 171.22992 -277.495736) (xy 171.222233 -277.488006)
			(xy 171.221908 -277.482554) (xy 165.177724 -277.482554) (xy 165.177242 -277.487861) (xy 165.169813 -277.495437)
			(xy 165.164516 -277.496016) (xy 163.691316 -277.496016) (xy 163.685988 -277.495663) (xy 163.678446 -277.488136)
			(xy 163.678108 -277.482808) (xy 56.078104 -277.482808) (xy 56.077786 -277.487993) (xy 56.070097 -277.495684)
			(xy 56.064658 -277.496016) (xy 54.591458 -277.496016) (xy 54.586006 -277.495744) (xy 54.57832 -277.488008)
			(xy 54.577996 -277.482554) (xy 48.533812 -277.482554) (xy 48.53334 -277.487864) (xy 48.525904 -277.49544)
			(xy 48.520604 -277.496016) (xy 48.00473 -277.496016) (xy 47.996921 -277.49634) (xy 47.982049 -277.501118)
			(xy 47.97552 -277.505414) (xy 47.954387 -277.519746) (xy 47.908668 -277.542478) (xy 47.859998 -277.557913)
			(xy 47.809534 -277.565684) (xy 47.784004 -277.56612) (xy 47.758473 -277.565689) (xy 47.708009 -277.557913)
			(xy 47.659336 -277.542482) (xy 47.613609 -277.519763) (xy 47.592488 -277.505414) (xy 47.585958 -277.501121)
			(xy 47.571087 -277.496339) (xy 47.563278 -277.496016) (xy 47.047404 -277.496016) (xy 47.042144 -277.495503)
			(xy 47.034701 -277.488068) (xy 47.034196 -277.482808) (xy 40.989984 -277.482808) (xy 40.989424 -277.487901)
			(xy 40.981893 -277.495486) (xy 40.97655 -277.496016) (xy 40.460676 -277.496016) (xy 40.452865 -277.496317)
			(xy 40.437993 -277.501111) (xy 40.431466 -277.505414) (xy 40.410348 -277.51977) (xy 40.364624 -277.542496)
			(xy 40.315949 -277.557925) (xy 40.265481 -277.565689) (xy 40.23995 -277.56612) (xy 40.21442 -277.565666)
			(xy 40.163957 -277.557897) (xy 40.115284 -277.542473) (xy 40.069556 -277.51976) (xy 40.048434 -277.505414)
			(xy 40.041893 -277.501138) (xy 40.02703 -277.496345) (xy 40.019224 -277.496016) (xy 39.50335 -277.496016)
			(xy 39.497969 -277.495578) (xy 39.490384 -277.487938) (xy 39.489888 -277.482554) (xy 33.445704 -277.482554)
			(xy 33.445151 -277.487843) (xy 33.437771 -277.495414) (xy 33.432496 -277.496016) (xy 32.916622 -277.496016)
			(xy 32.908812 -277.496336) (xy 32.893941 -277.501117) (xy 32.887412 -277.505414) (xy 32.866282 -277.51975)
			(xy 32.820561 -277.542481) (xy 32.771891 -277.557915) (xy 32.721426 -277.565685) (xy 32.695896 -277.56612)
			(xy 32.670365 -277.565693) (xy 32.619901 -277.557916) (xy 32.571228 -277.542484) (xy 32.525501 -277.519764)
			(xy 32.50438 -277.505414) (xy 32.497851 -277.501118) (xy 32.482979 -277.496337) (xy 32.47517 -277.496016)
			(xy 31.959296 -277.496016) (xy 31.954035 -277.495509) (xy 31.946593 -277.488069) (xy 31.946088 -277.482808)
			(xy 25.901877 -277.482808) (xy 25.901351 -277.487843) (xy 25.893971 -277.495414) (xy 25.888696 -277.496016)
			(xy 25.372822 -277.496016) (xy 25.365012 -277.496336) (xy 25.350141 -277.501117) (xy 25.343612 -277.505414)
			(xy 25.322482 -277.51975) (xy 25.276761 -277.542481) (xy 25.228091 -277.557915) (xy 25.177626 -277.565685)
			(xy 25.152096 -277.56612) (xy 25.126565 -277.565693) (xy 25.076101 -277.557916) (xy 25.027428 -277.542484)
			(xy 24.981701 -277.519764) (xy 24.96058 -277.505414) (xy 24.954051 -277.501118) (xy 24.939179 -277.496337)
			(xy 24.93137 -277.496016) (xy 24.415496 -277.496016) (xy 24.410235 -277.495509) (xy 24.402793 -277.488069)
			(xy 24.402288 -277.482808) (xy 18.358085 -277.482808) (xy 18.357694 -277.487973) (xy 18.350058 -277.495659)
			(xy 18.344642 -277.496016) (xy 17.828768 -277.496016) (xy 17.82096 -277.496356) (xy 17.806089 -277.501124)
			(xy 17.799558 -277.505414) (xy 17.778443 -277.519773) (xy 17.732717 -277.542499) (xy 17.684042 -277.557926)
			(xy 17.633574 -277.565689) (xy 17.608042 -277.56612) (xy 17.582512 -277.56567) (xy 17.532048 -277.5579)
			(xy 17.483376 -277.542475) (xy 17.437648 -277.519761) (xy 17.416526 -277.505414) (xy 17.409987 -277.501135)
			(xy 17.395123 -277.496344) (xy 17.387316 -277.496016) (xy 16.871442 -277.496016) (xy 16.866002 -277.495688)
			(xy 16.85831 -277.487994) (xy 16.85798 -277.482554) (xy 2.509012 -277.482554) (xy 2.509012 -278.332438)
			(xy 20.958048 -278.332438) (xy 20.958048 -277.8379) (xy 20.95859 -277.832648) (xy 20.966006 -277.825208)
			(xy 20.971256 -277.824692) (xy 20.971764 -277.824692) (xy 21.487638 -277.824692) (xy 21.495446 -277.824353)
			(xy 21.510317 -277.819584) (xy 21.516848 -277.815294) (xy 21.537937 -277.800945) (xy 21.583598 -277.778214)
			(xy 21.632204 -277.762755) (xy 21.682607 -277.754932) (xy 21.733613 -277.754932) (xy 21.784016 -277.762755)
			(xy 21.832622 -277.778214) (xy 21.878283 -277.800945) (xy 21.899372 -277.815294) (xy 21.905911 -277.819573)
			(xy 21.920775 -277.824364) (xy 21.928582 -277.824692) (xy 22.44471 -277.824692) (xy 22.450004 -277.825211)
			(xy 22.457572 -277.832618) (xy 22.458172 -277.8379) (xy 22.458172 -278.332438) (xy 22.458149 -278.332692)
			(xy 28.502356 -278.332692) (xy 28.502356 -278.332184) (xy 28.502356 -277.8379) (xy 28.502891 -277.832646)
			(xy 28.510311 -277.825206) (xy 28.515564 -277.824692) (xy 29.031692 -277.824692) (xy 29.039502 -277.824376)
			(xy 29.054373 -277.819592) (xy 29.060902 -277.815294) (xy 29.081991 -277.800945) (xy 29.127652 -277.778214)
			(xy 29.176258 -277.762755) (xy 29.226661 -277.754932) (xy 29.277667 -277.754932) (xy 29.32807 -277.762755)
			(xy 29.376676 -277.778214) (xy 29.422337 -277.800945) (xy 29.443426 -277.815294) (xy 29.449953 -277.819593)
			(xy 29.464826 -277.824372) (xy 29.472636 -277.824692) (xy 29.988764 -277.824692) (xy 29.994092 -277.825051)
			(xy 30.001635 -277.832573) (xy 30.001972 -277.8379) (xy 30.001972 -278.332438) (xy 30.00195 -278.332692)
			(xy 36.046156 -278.332692) (xy 36.046156 -278.332184) (xy 36.046156 -277.8379) (xy 36.046691 -277.832646)
			(xy 36.054111 -277.825206) (xy 36.059364 -277.824692) (xy 36.575492 -277.824692) (xy 36.583302 -277.824376)
			(xy 36.598173 -277.819592) (xy 36.604702 -277.815294) (xy 36.625791 -277.800945) (xy 36.671452 -277.778214)
			(xy 36.720058 -277.762755) (xy 36.770461 -277.754932) (xy 36.821467 -277.754932) (xy 36.87187 -277.762755)
			(xy 36.920476 -277.778214) (xy 36.966137 -277.800945) (xy 36.987226 -277.815294) (xy 36.993753 -277.819593)
			(xy 37.008626 -277.824372) (xy 37.016436 -277.824692) (xy 37.532564 -277.824692) (xy 37.537892 -277.825051)
			(xy 37.545435 -277.832573) (xy 37.545772 -277.8379) (xy 37.545772 -278.332438) (xy 43.589956 -278.332438)
			(xy 43.589956 -277.8379) (xy 43.590491 -277.832646) (xy 43.597911 -277.825206) (xy 43.603164 -277.824692)
			(xy 43.603672 -277.824692) (xy 44.119546 -277.824692) (xy 44.127354 -277.824357) (xy 44.142226 -277.819586)
			(xy 44.148756 -277.815294) (xy 44.169845 -277.800945) (xy 44.215506 -277.778214) (xy 44.264112 -277.762755)
			(xy 44.314515 -277.754932) (xy 44.365521 -277.754932) (xy 44.415924 -277.762755) (xy 44.46453 -277.778214)
			(xy 44.510191 -277.800945) (xy 44.53128 -277.815294) (xy 44.537817 -277.819576) (xy 44.552683 -277.824365)
			(xy 44.56049 -277.824692) (xy 45.076618 -277.824692) (xy 45.081913 -277.825205) (xy 45.089481 -277.832616)
			(xy 45.09008 -277.8379) (xy 45.09008 -278.332438) (xy 45.090056 -278.332692) (xy 51.134264 -278.332692)
			(xy 51.134264 -278.332184) (xy 51.134264 -277.8379) (xy 51.134792 -277.832644) (xy 51.142217 -277.825203)
			(xy 51.147472 -277.824692) (xy 51.6636 -277.824692) (xy 51.67141 -277.82438) (xy 51.686282 -277.819593)
			(xy 51.69281 -277.815294) (xy 51.713899 -277.800945) (xy 51.75956 -277.778214) (xy 51.808166 -277.762755)
			(xy 51.858569 -277.754932) (xy 51.909575 -277.754932) (xy 51.959978 -277.762755) (xy 52.008584 -277.778214)
			(xy 52.054245 -277.800945) (xy 52.075334 -277.815294) (xy 52.081859 -277.819597) (xy 52.096734 -277.824373)
			(xy 52.104544 -277.824692) (xy 52.620672 -277.824692) (xy 52.626001 -277.825045) (xy 52.633543 -277.832572)
			(xy 52.63388 -277.8379) (xy 52.63388 -278.332438) (xy 58.678064 -278.332438) (xy 58.678064 -277.8379)
			(xy 58.678592 -277.832644) (xy 58.686017 -277.825203) (xy 58.691272 -277.824692) (xy 58.69178 -277.824692)
			(xy 60.164726 -277.824692) (xy 60.170022 -277.8252) (xy 60.177589 -277.832615) (xy 60.178188 -277.8379)
			(xy 60.178188 -278.332438) (xy 60.178164 -278.332692) (xy 167.778176 -278.332692) (xy 167.778176 -277.8379)
			(xy 167.778693 -277.832641) (xy 167.786126 -277.8252) (xy 167.791384 -277.824692) (xy 169.264584 -277.824692)
			(xy 169.269914 -277.825038) (xy 169.277456 -277.83257) (xy 169.277792 -277.8379) (xy 169.277792 -278.332438)
			(xy 175.321976 -278.332438) (xy 175.321976 -277.8379) (xy 175.322493 -277.832641) (xy 175.329926 -277.8252)
			(xy 175.335184 -277.824692) (xy 175.335692 -277.824692) (xy 175.851566 -277.824692) (xy 175.859375 -277.824365)
			(xy 175.874246 -277.819588) (xy 175.880776 -277.815294) (xy 175.901865 -277.800945) (xy 175.947526 -277.778214)
			(xy 175.996132 -277.762755) (xy 176.046535 -277.754932) (xy 176.097541 -277.754932) (xy 176.147944 -277.762755)
			(xy 176.19655 -277.778214) (xy 176.242211 -277.800945) (xy 176.2633 -277.815294) (xy 176.269833 -277.819584)
			(xy 176.284702 -277.824368) (xy 176.29251 -277.824692) (xy 176.808638 -277.824692) (xy 176.813936 -277.825192)
			(xy 176.821502 -277.832613) (xy 176.8221 -277.8379) (xy 176.8221 -278.332438) (xy 176.822075 -278.332692)
			(xy 182.866284 -278.332692) (xy 182.866284 -278.332184) (xy 182.866284 -277.8379) (xy 182.866794 -277.832639)
			(xy 182.874232 -277.825197) (xy 182.879492 -277.824692) (xy 183.39562 -277.824692) (xy 183.403431 -277.824388)
			(xy 183.418302 -277.819595) (xy 183.42483 -277.815294) (xy 183.445919 -277.800945) (xy 183.49158 -277.778214)
			(xy 183.540186 -277.762755) (xy 183.590589 -277.754932) (xy 183.641595 -277.754932) (xy 183.691998 -277.762755)
			(xy 183.740604 -277.778214) (xy 183.786265 -277.800945) (xy 183.807354 -277.815294) (xy 183.813875 -277.819604)
			(xy 183.828753 -277.824376) (xy 183.836564 -277.824692) (xy 184.352692 -277.824692) (xy 184.358023 -277.825032)
			(xy 184.365565 -277.832569) (xy 184.3659 -277.8379) (xy 184.3659 -278.332438) (xy 190.410084 -278.332438)
			(xy 190.410084 -277.8379) (xy 190.410594 -277.832639) (xy 190.418032 -277.825197) (xy 190.423292 -277.824692)
			(xy 190.4238 -277.824692) (xy 190.939674 -277.824692) (xy 190.947483 -277.824369) (xy 190.962355 -277.81959)
			(xy 190.968884 -277.815294) (xy 190.989973 -277.800945) (xy 191.035634 -277.778214) (xy 191.08424 -277.762755)
			(xy 191.134643 -277.754932) (xy 191.185649 -277.754932) (xy 191.236052 -277.762755) (xy 191.284658 -277.778214)
			(xy 191.330319 -277.800945) (xy 191.351408 -277.815294) (xy 191.357939 -277.819587) (xy 191.372809 -277.824369)
			(xy 191.380618 -277.824692) (xy 191.896746 -277.824692) (xy 191.902033 -277.825254) (xy 191.909604 -277.832628)
			(xy 191.910208 -277.8379) (xy 191.910208 -278.332438) (xy 191.910183 -278.332692) (xy 197.954392 -278.332692)
			(xy 197.954392 -278.332184) (xy 197.954392 -277.8379) (xy 197.954895 -277.832637) (xy 197.962337 -277.825195)
			(xy 197.9676 -277.824692) (xy 198.483728 -277.824692) (xy 198.491539 -277.824392) (xy 198.506411 -277.819597)
			(xy 198.512938 -277.815294) (xy 198.534027 -277.800945) (xy 198.579688 -277.778214) (xy 198.628294 -277.762755)
			(xy 198.678697 -277.754932) (xy 198.729703 -277.754932) (xy 198.780106 -277.762755) (xy 198.828712 -277.778214)
			(xy 198.874373 -277.800945) (xy 198.895462 -277.815294) (xy 198.902003 -277.819569) (xy 198.916866 -277.824362)
			(xy 198.924672 -277.824692) (xy 199.4408 -277.824692) (xy 199.446063 -277.825195) (xy 199.453505 -277.832637)
			(xy 199.454008 -277.8379) (xy 199.454008 -278.332438) (xy 199.453984 -278.332692) (xy 205.498192 -278.332692)
			(xy 205.498192 -278.332184) (xy 205.498192 -277.8379) (xy 205.498695 -277.832637) (xy 205.506137 -277.825195)
			(xy 205.5114 -277.824692) (xy 206.027528 -277.824692) (xy 206.035339 -277.824392) (xy 206.050211 -277.819597)
			(xy 206.056738 -277.815294) (xy 206.077827 -277.800945) (xy 206.123488 -277.778214) (xy 206.172094 -277.762755)
			(xy 206.222497 -277.754932) (xy 206.273503 -277.754932) (xy 206.323906 -277.762755) (xy 206.372512 -277.778214)
			(xy 206.418173 -277.800945) (xy 206.439262 -277.815294) (xy 206.445803 -277.819569) (xy 206.460666 -277.824362)
			(xy 206.468472 -277.824692) (xy 206.9846 -277.824692) (xy 206.989863 -277.825195) (xy 206.997305 -277.832637)
			(xy 206.997808 -277.8379) (xy 206.997808 -278.332184) (xy 268.898116 -278.332184) (xy 268.898116 -277.837646)
			(xy 268.898508 -277.832223) (xy 268.906156 -277.824535) (xy 268.911578 -277.824184) (xy 269.427706 -277.824184)
			(xy 269.435517 -277.823876) (xy 269.450388 -277.819086) (xy 269.456916 -277.814786) (xy 269.478005 -277.800437)
			(xy 269.523666 -277.777706) (xy 269.572272 -277.762247) (xy 269.622675 -277.754424) (xy 269.673681 -277.754424)
			(xy 269.724084 -277.762247) (xy 269.77269 -277.777706) (xy 269.818351 -277.800437) (xy 269.83944 -277.814786)
			(xy 269.845964 -277.81909) (xy 269.86084 -277.823865) (xy 269.86865 -277.824184) (xy 270.384778 -277.824184)
			(xy 270.390221 -277.824499) (xy 270.397911 -277.832202) (xy 270.39824 -277.837646) (xy 270.39824 -278.332184)
			(xy 276.442424 -278.332184) (xy 276.442424 -277.837646) (xy 276.442952 -277.832351) (xy 276.45035 -277.824778)
			(xy 276.455632 -277.824184) (xy 276.97176 -277.824184) (xy 276.979569 -277.823856) (xy 276.99444 -277.81908)
			(xy 277.00097 -277.814786) (xy 277.022059 -277.800437) (xy 277.06772 -277.777706) (xy 277.116326 -277.762247)
			(xy 277.166729 -277.754424) (xy 277.217735 -277.754424) (xy 277.268138 -277.762247) (xy 277.316744 -277.777706)
			(xy 277.362405 -277.800437) (xy 277.383494 -277.814786) (xy 277.390028 -277.819072) (xy 277.404896 -277.823859)
			(xy 277.412704 -277.824184) (xy 277.928832 -277.824184) (xy 277.934097 -277.824673) (xy 277.941537 -277.832126)
			(xy 277.94204 -277.837392) (xy 277.94204 -277.8379) (xy 277.94204 -278.332184) (xy 283.986224 -278.332184)
			(xy 283.986224 -277.837646) (xy 283.986752 -277.832351) (xy 283.99415 -277.824778) (xy 283.999432 -277.824184)
			(xy 284.51556 -277.824184) (xy 284.523369 -277.823856) (xy 284.53824 -277.81908) (xy 284.54477 -277.814786)
			(xy 284.565859 -277.800437) (xy 284.61152 -277.777706) (xy 284.660126 -277.762247) (xy 284.710529 -277.754424)
			(xy 284.761535 -277.754424) (xy 284.811938 -277.762247) (xy 284.860544 -277.777706) (xy 284.906205 -277.800437)
			(xy 284.927294 -277.814786) (xy 284.933828 -277.819072) (xy 284.948696 -277.823859) (xy 284.956504 -277.824184)
			(xy 285.472632 -277.824184) (xy 285.477897 -277.824673) (xy 285.485337 -277.832126) (xy 285.48584 -277.837392)
			(xy 285.48584 -277.8379) (xy 285.48584 -278.332184) (xy 291.530024 -278.332184) (xy 291.530024 -277.837646)
			(xy 291.530409 -277.832221) (xy 291.538062 -277.824533) (xy 291.543486 -277.824184) (xy 292.059614 -277.824184)
			(xy 292.067425 -277.823879) (xy 292.082296 -277.819087) (xy 292.088824 -277.814786) (xy 292.109913 -277.800437)
			(xy 292.155574 -277.777706) (xy 292.20418 -277.762247) (xy 292.254583 -277.754424) (xy 292.305589 -277.754424)
			(xy 292.355992 -277.762247) (xy 292.404598 -277.777706) (xy 292.450259 -277.800437) (xy 292.471348 -277.814786)
			(xy 292.47787 -277.819093) (xy 292.492747 -277.823867) (xy 292.500558 -277.824184) (xy 293.016686 -277.824184)
			(xy 293.02213 -277.824493) (xy 293.02982 -277.832201) (xy 293.030148 -277.837646) (xy 293.030148 -278.332184)
			(xy 299.074332 -278.332184) (xy 299.074332 -277.837646) (xy 299.074853 -277.832349) (xy 299.082255 -277.824776)
			(xy 299.08754 -277.824184) (xy 299.603668 -277.824184) (xy 299.611477 -277.82386) (xy 299.626349 -277.819081)
			(xy 299.632878 -277.814786) (xy 299.653967 -277.800437) (xy 299.699628 -277.777706) (xy 299.748234 -277.762247)
			(xy 299.798637 -277.754424) (xy 299.849643 -277.754424) (xy 299.900046 -277.762247) (xy 299.948652 -277.777706)
			(xy 299.994313 -277.800437) (xy 300.015402 -277.814786) (xy 300.021935 -277.819076) (xy 300.036804 -277.82386)
			(xy 300.044612 -277.824184) (xy 300.56074 -277.824184) (xy 300.566006 -277.824667) (xy 300.573446 -277.832125)
			(xy 300.573948 -277.837392) (xy 300.573948 -277.8379) (xy 300.573948 -278.332184) (xy 306.618132 -278.332184)
			(xy 306.618132 -277.837646) (xy 306.618509 -277.832219) (xy 306.626168 -277.82453) (xy 306.631594 -277.824184)
			(xy 308.104794 -277.824184) (xy 308.110239 -277.824488) (xy 308.117928 -277.8322) (xy 308.118256 -277.837646)
			(xy 308.118256 -278.332184) (xy 415.718244 -278.332184) (xy 415.718244 -277.837646) (xy 415.718754 -277.832346)
			(xy 415.726164 -277.824772) (xy 415.731452 -277.824184) (xy 417.204652 -277.824184) (xy 417.209976 -277.824559)
			(xy 417.217519 -277.83207) (xy 417.21786 -277.837392) (xy 417.21786 -278.332184) (xy 423.262044 -278.332184)
			(xy 423.262044 -277.837646) (xy 423.262411 -277.832216) (xy 423.270077 -277.824527) (xy 423.275506 -277.824184)
			(xy 423.791634 -277.824184) (xy 423.799442 -277.823845) (xy 423.814313 -277.819076) (xy 423.820844 -277.814786)
			(xy 423.841933 -277.800437) (xy 423.887594 -277.777706) (xy 423.9362 -277.762247) (xy 423.986603 -277.754424)
			(xy 424.037609 -277.754424) (xy 424.088012 -277.762247) (xy 424.136618 -277.777706) (xy 424.182279 -277.800437)
			(xy 424.203368 -277.814786) (xy 424.209908 -277.819063) (xy 424.224771 -277.823855) (xy 424.232578 -277.824184)
			(xy 424.748706 -277.824184) (xy 424.754153 -277.82448) (xy 424.761841 -277.832198) (xy 424.762168 -277.837646)
			(xy 424.762168 -278.332184) (xy 430.806352 -278.332184) (xy 430.806352 -277.837646) (xy 430.806855 -277.832344)
			(xy 430.81427 -277.82477) (xy 430.81956 -277.824184) (xy 431.335688 -277.824184) (xy 431.343498 -277.823868)
			(xy 431.358369 -277.819084) (xy 431.364898 -277.814786) (xy 431.385987 -277.800437) (xy 431.431648 -277.777706)
			(xy 431.480254 -277.762247) (xy 431.530657 -277.754424) (xy 431.581663 -277.754424) (xy 431.632066 -277.762247)
			(xy 431.680672 -277.777706) (xy 431.726333 -277.800437) (xy 431.747422 -277.814786) (xy 431.75395 -277.819083)
			(xy 431.768823 -277.823863) (xy 431.776632 -277.824184) (xy 432.29276 -277.824184) (xy 432.298085 -277.824553)
			(xy 432.305628 -277.832068) (xy 432.305968 -277.837392) (xy 432.305968 -277.8379) (xy 432.305968 -278.332184)
			(xy 438.350152 -278.332184) (xy 438.350152 -277.837646) (xy 438.350511 -277.832214) (xy 438.358183 -277.824524)
			(xy 438.363614 -277.824184) (xy 438.879742 -277.824184) (xy 438.88755 -277.823848) (xy 438.902422 -277.819078)
			(xy 438.908952 -277.814786) (xy 438.930041 -277.800437) (xy 438.975702 -277.777706) (xy 439.024308 -277.762247)
			(xy 439.074711 -277.754424) (xy 439.125717 -277.754424) (xy 439.17612 -277.762247) (xy 439.224726 -277.777706)
			(xy 439.270387 -277.800437) (xy 439.291476 -277.814786) (xy 439.298014 -277.819066) (xy 439.312879 -277.823856)
			(xy 439.320686 -277.824184) (xy 439.836814 -277.824184) (xy 439.842262 -277.824475) (xy 439.84995 -277.832197)
			(xy 439.850276 -277.837646) (xy 439.850276 -278.332184) (xy 445.89446 -278.332184) (xy 445.89446 -277.837646)
			(xy 445.894956 -277.832343) (xy 445.902376 -277.824768) (xy 445.907668 -277.824184) (xy 446.423796 -277.824184)
			(xy 446.431606 -277.823871) (xy 446.446478 -277.819085) (xy 446.453006 -277.814786) (xy 446.474095 -277.800437)
			(xy 446.519756 -277.777706) (xy 446.568362 -277.762247) (xy 446.618765 -277.754424) (xy 446.669771 -277.754424)
			(xy 446.720174 -277.762247) (xy 446.76878 -277.777706) (xy 446.814441 -277.800437) (xy 446.83553 -277.814786)
			(xy 446.842056 -277.819086) (xy 446.85693 -277.823864) (xy 446.86474 -277.824184) (xy 447.380868 -277.824184)
			(xy 447.386194 -277.824548) (xy 447.393736 -277.832067) (xy 447.394076 -277.837392) (xy 447.394076 -277.8379)
			(xy 447.394076 -278.332184) (xy 453.43826 -278.332184) (xy 453.43826 -277.837646) (xy 453.438756 -277.832343)
			(xy 453.446176 -277.824768) (xy 453.451468 -277.824184) (xy 453.967596 -277.824184) (xy 453.975406 -277.823871)
			(xy 453.990278 -277.819085) (xy 453.996806 -277.814786) (xy 454.017895 -277.800437) (xy 454.063556 -277.777706)
			(xy 454.112162 -277.762247) (xy 454.162565 -277.754424) (xy 454.213571 -277.754424) (xy 454.263974 -277.762247)
			(xy 454.31258 -277.777706) (xy 454.358241 -277.800437) (xy 454.37933 -277.814786) (xy 454.385856 -277.819086)
			(xy 454.40073 -277.823864) (xy 454.40854 -277.824184) (xy 454.924668 -277.824184) (xy 454.929994 -277.824548)
			(xy 454.937536 -277.832067) (xy 454.937876 -277.837392) (xy 454.937876 -277.8379) (xy 454.937876 -278.332184)
			(xy 454.937559 -278.337522) (xy 454.930006 -278.345066) (xy 454.924668 -278.345392) (xy 454.408794 -278.345392)
			(xy 454.400919 -278.345678) (xy 454.385915 -278.350462) (xy 454.37933 -278.35479) (xy 454.358266 -278.369202)
			(xy 454.312616 -278.392024) (xy 454.264006 -278.407576) (xy 454.213586 -278.41549) (xy 454.188068 -278.416004)
			(xy 454.162549 -278.415497) (xy 454.112122 -278.407607) (xy 454.063511 -278.392053) (xy 454.017872 -278.369203)
			(xy 453.996806 -278.35479) (xy 453.990215 -278.350474) (xy 453.975215 -278.345688) (xy 453.967342 -278.345392)
			(xy 453.451468 -278.345392) (xy 453.446198 -278.344925) (xy 453.438756 -278.337456) (xy 453.43826 -278.332184)
			(xy 447.394076 -278.332184) (xy 447.393759 -278.337522) (xy 447.386206 -278.345066) (xy 447.380868 -278.345392)
			(xy 446.864994 -278.345392) (xy 446.857119 -278.345678) (xy 446.842115 -278.350462) (xy 446.83553 -278.35479)
			(xy 446.814466 -278.369202) (xy 446.768816 -278.392024) (xy 446.720206 -278.407576) (xy 446.669786 -278.41549)
			(xy 446.644268 -278.416004) (xy 446.618749 -278.415497) (xy 446.568322 -278.407607) (xy 446.519711 -278.392053)
			(xy 446.474072 -278.369203) (xy 446.453006 -278.35479) (xy 446.446415 -278.350474) (xy 446.431415 -278.345688)
			(xy 446.423542 -278.345392) (xy 445.907668 -278.345392) (xy 445.902398 -278.344925) (xy 445.894956 -278.337456)
			(xy 445.89446 -278.332184) (xy 439.850276 -278.332184) (xy 439.849959 -278.337522) (xy 439.842406 -278.345066)
			(xy 439.837068 -278.345392) (xy 439.83656 -278.345392) (xy 439.32094 -278.345392) (xy 439.313063 -278.345654)
			(xy 439.298059 -278.350455) (xy 439.291476 -278.35479) (xy 439.270399 -278.369182) (xy 439.224754 -278.392009)
			(xy 439.176147 -278.407566) (xy 439.125731 -278.415486) (xy 439.100214 -278.416004) (xy 439.074693 -278.415524)
			(xy 439.024266 -278.407626) (xy 438.975655 -278.392063) (xy 438.930017 -278.369206) (xy 438.908952 -278.35479)
			(xy 438.902374 -278.350453) (xy 438.887363 -278.34568) (xy 438.879488 -278.345392) (xy 438.363614 -278.345392)
			(xy 438.358319 -278.344871) (xy 438.350749 -278.337467) (xy 438.350152 -278.332184) (xy 432.305968 -278.332184)
			(xy 432.305659 -278.337524) (xy 432.2981 -278.345068) (xy 432.29276 -278.345392) (xy 431.776886 -278.345392)
			(xy 431.769011 -278.345674) (xy 431.754007 -278.350461) (xy 431.747422 -278.35479) (xy 431.72636 -278.369205)
			(xy 431.680709 -278.392027) (xy 431.632098 -278.407578) (xy 431.581678 -278.41549) (xy 431.55616 -278.416004)
			(xy 431.53064 -278.415501) (xy 431.480214 -278.40761) (xy 431.431602 -278.392054) (xy 431.385963 -278.369203)
			(xy 431.364898 -278.35479) (xy 431.358309 -278.35047) (xy 431.343307 -278.345687) (xy 431.335434 -278.345392)
			(xy 430.81956 -278.345392) (xy 430.814288 -278.34493) (xy 430.806847 -278.337458) (xy 430.806352 -278.332184)
			(xy 424.762168 -278.332184) (xy 424.761859 -278.337524) (xy 424.7543 -278.345068) (xy 424.74896 -278.345392)
			(xy 424.748452 -278.345392) (xy 424.232832 -278.345392) (xy 424.224955 -278.345651) (xy 424.209951 -278.350454)
			(xy 424.203368 -278.35479) (xy 424.182293 -278.369185) (xy 424.136647 -278.392012) (xy 424.08804 -278.407568)
			(xy 424.037623 -278.415487) (xy 424.012106 -278.416004) (xy 423.986585 -278.415528) (xy 423.936158 -278.407629)
			(xy 423.887546 -278.392065) (xy 423.841908 -278.369207) (xy 423.820844 -278.35479) (xy 423.814267 -278.35045)
			(xy 423.799256 -278.345679) (xy 423.79138 -278.345392) (xy 423.275506 -278.345392) (xy 423.27021 -278.344877)
			(xy 423.26264 -278.337468) (xy 423.262044 -278.332184) (xy 417.21786 -278.332184) (xy 417.217558 -278.337526)
			(xy 417.209995 -278.345071) (xy 417.204652 -278.345392) (xy 415.731452 -278.345392) (xy 415.72618 -278.344935)
			(xy 415.718739 -278.337459) (xy 415.718244 -278.332184) (xy 308.118256 -278.332184) (xy 308.1177 -278.337433)
			(xy 308.110295 -278.344874) (xy 308.105048 -278.345392) (xy 308.10454 -278.345392) (xy 306.631594 -278.345392)
			(xy 306.626297 -278.344885) (xy 306.618728 -278.33747) (xy 306.618132 -278.332184) (xy 300.573948 -278.332184)
			(xy 300.573399 -278.337435) (xy 300.565989 -278.344876) (xy 300.56074 -278.345392) (xy 300.044866 -278.345392)
			(xy 300.03699 -278.345666) (xy 300.021986 -278.350458) (xy 300.015402 -278.35479) (xy 299.994318 -278.369171)
			(xy 299.948675 -278.392) (xy 299.900071 -278.407561) (xy 299.849656 -278.415484) (xy 299.82414 -278.416004)
			(xy 299.79862 -278.415511) (xy 299.748193 -278.407617) (xy 299.699582 -278.392058) (xy 299.653943 -278.369205)
			(xy 299.632878 -278.35479) (xy 299.626294 -278.350463) (xy 299.611288 -278.345684) (xy 299.603414 -278.345392)
			(xy 299.08754 -278.345392) (xy 299.082209 -278.345045) (xy 299.074665 -278.337514) (xy 299.074332 -278.332184)
			(xy 293.030148 -278.332184) (xy 293.029599 -278.337435) (xy 293.022189 -278.344876) (xy 293.01694 -278.345392)
			(xy 293.016432 -278.345392) (xy 292.500812 -278.345392) (xy 292.492938 -278.345685) (xy 292.477933 -278.350464)
			(xy 292.471348 -278.35479) (xy 292.450279 -278.369194) (xy 292.404631 -278.392018) (xy 292.356022 -278.407572)
			(xy 292.305603 -278.415488) (xy 292.280086 -278.416004) (xy 292.254567 -278.415488) (xy 292.204141 -278.407601)
			(xy 292.155529 -278.392049) (xy 292.10989 -278.369202) (xy 292.088824 -278.35479) (xy 292.082229 -278.35048)
			(xy 292.067232 -278.345691) (xy 292.05936 -278.345392) (xy 291.543486 -278.345392) (xy 291.538188 -278.34489)
			(xy 291.530619 -278.337471) (xy 291.530024 -278.332184) (xy 285.48584 -278.332184) (xy 285.485298 -278.337437)
			(xy 285.477883 -278.344879) (xy 285.472632 -278.345392) (xy 284.956758 -278.345392) (xy 284.948882 -278.345662)
			(xy 284.933878 -278.350457) (xy 284.927294 -278.35479) (xy 284.906212 -278.369174) (xy 284.860568 -278.392003)
			(xy 284.811964 -278.407563) (xy 284.761548 -278.415485) (xy 284.736032 -278.416004) (xy 284.710512 -278.415515)
			(xy 284.660085 -278.40762) (xy 284.611473 -278.39206) (xy 284.565835 -278.369205) (xy 284.54477 -278.35479)
			(xy 284.538188 -278.35046) (xy 284.52318 -278.345683) (xy 284.515306 -278.345392) (xy 283.999432 -278.345392)
			(xy 283.9941 -278.34505) (xy 283.986556 -278.337515) (xy 283.986224 -278.332184) (xy 277.94204 -278.332184)
			(xy 277.941498 -278.337437) (xy 277.934083 -278.344879) (xy 277.928832 -278.345392) (xy 277.412958 -278.345392)
			(xy 277.405082 -278.345662) (xy 277.390078 -278.350457) (xy 277.383494 -278.35479) (xy 277.362412 -278.369174)
			(xy 277.316768 -278.392003) (xy 277.268164 -278.407563) (xy 277.217748 -278.415485) (xy 277.192232 -278.416004)
			(xy 277.166712 -278.415515) (xy 277.116285 -278.40762) (xy 277.067673 -278.39206) (xy 277.022035 -278.369205)
			(xy 277.00097 -278.35479) (xy 276.994388 -278.35046) (xy 276.97938 -278.345683) (xy 276.971506 -278.345392)
			(xy 276.455632 -278.345392) (xy 276.4503 -278.34505) (xy 276.442756 -278.337515) (xy 276.442424 -278.332184)
			(xy 270.39824 -278.332184) (xy 270.397698 -278.337437) (xy 270.390283 -278.344879) (xy 270.385032 -278.345392)
			(xy 270.384524 -278.345392) (xy 269.868904 -278.345392) (xy 269.86103 -278.345682) (xy 269.846025 -278.350463)
			(xy 269.83944 -278.35479) (xy 269.818373 -278.369197) (xy 269.772724 -278.392021) (xy 269.724115 -278.407574)
			(xy 269.673696 -278.415489) (xy 269.648178 -278.416004) (xy 269.622659 -278.415492) (xy 269.572233 -278.407604)
			(xy 269.523621 -278.39205) (xy 269.477982 -278.369202) (xy 269.456916 -278.35479) (xy 269.450323 -278.350477)
			(xy 269.435324 -278.345689) (xy 269.427452 -278.345392) (xy 268.911578 -278.345392) (xy 268.906279 -278.344895)
			(xy 268.898711 -278.337473) (xy 268.898116 -278.332184) (xy 206.997808 -278.332184) (xy 206.997808 -278.332438)
			(xy 206.997308 -278.337736) (xy 206.989887 -278.345302) (xy 206.9846 -278.3459) (xy 206.468726 -278.3459)
			(xy 206.460917 -278.346225) (xy 206.446045 -278.351003) (xy 206.439516 -278.355298) (xy 206.418383 -278.36963)
			(xy 206.372664 -278.392362) (xy 206.323994 -278.407797) (xy 206.27353 -278.415569) (xy 206.248 -278.416004)
			(xy 206.22247 -278.41556) (xy 206.172007 -278.407785) (xy 206.123335 -278.392358) (xy 206.077607 -278.369644)
			(xy 206.056484 -278.355298) (xy 206.049955 -278.351002) (xy 206.035083 -278.346222) (xy 206.027274 -278.3459)
			(xy 205.5114 -278.3459) (xy 205.506066 -278.345573) (xy 205.498524 -278.338026) (xy 205.498192 -278.332692)
			(xy 199.453984 -278.332692) (xy 199.453508 -278.337736) (xy 199.446087 -278.345302) (xy 199.4408 -278.3459)
			(xy 198.924926 -278.3459) (xy 198.917117 -278.346225) (xy 198.902245 -278.351003) (xy 198.895716 -278.355298)
			(xy 198.874583 -278.36963) (xy 198.828864 -278.392362) (xy 198.780194 -278.407797) (xy 198.72973 -278.415569)
			(xy 198.7042 -278.416004) (xy 198.67867 -278.41556) (xy 198.628207 -278.407785) (xy 198.579535 -278.392358)
			(xy 198.533807 -278.369644) (xy 198.512684 -278.355298) (xy 198.506155 -278.351002) (xy 198.491283 -278.346222)
			(xy 198.483474 -278.3459) (xy 197.9676 -278.3459) (xy 197.962266 -278.345573) (xy 197.954724 -278.338026)
			(xy 197.954392 -278.332692) (xy 191.910183 -278.332692) (xy 191.909679 -278.337795) (xy 191.902103 -278.345376)
			(xy 191.896746 -278.3459) (xy 191.380872 -278.3459) (xy 191.373061 -278.346202) (xy 191.35819 -278.350996)
			(xy 191.351662 -278.355298) (xy 191.330544 -278.369654) (xy 191.28482 -278.39238) (xy 191.236145 -278.407809)
			(xy 191.185677 -278.415573) (xy 191.160146 -278.416004) (xy 191.134617 -278.415537) (xy 191.084155 -278.407769)
			(xy 191.035482 -278.392349) (xy 190.989753 -278.369641) (xy 190.96863 -278.355298) (xy 190.962091 -278.351019)
			(xy 190.947227 -278.346229) (xy 190.93942 -278.3459) (xy 190.423546 -278.3459) (xy 190.418126 -278.345494)
			(xy 190.41044 -278.337855) (xy 190.410084 -278.332438) (xy 184.3659 -278.332438) (xy 184.365407 -278.337738)
			(xy 184.357981 -278.345304) (xy 184.352692 -278.3459) (xy 183.836818 -278.3459) (xy 183.829009 -278.346221)
			(xy 183.814137 -278.351002) (xy 183.807608 -278.355298) (xy 183.786477 -278.369634) (xy 183.740757 -278.392365)
			(xy 183.692087 -278.407799) (xy 183.641622 -278.415569) (xy 183.616092 -278.416004) (xy 183.590562 -278.415564)
			(xy 183.540099 -278.407788) (xy 183.491426 -278.39236) (xy 183.445698 -278.369645) (xy 183.424576 -278.355298)
			(xy 183.418049 -278.350999) (xy 183.403176 -278.346221) (xy 183.395366 -278.3459) (xy 182.879492 -278.3459)
			(xy 182.874226 -278.34541) (xy 182.866784 -278.337958) (xy 182.866284 -278.332692) (xy 176.822075 -278.332692)
			(xy 176.821579 -278.337797) (xy 176.813997 -278.345379) (xy 176.808638 -278.3459) (xy 176.292764 -278.3459)
			(xy 176.284956 -278.346241) (xy 176.270085 -278.351008) (xy 176.263554 -278.355298) (xy 176.242439 -278.369657)
			(xy 176.196713 -278.392383) (xy 176.148038 -278.407811) (xy 176.09757 -278.415573) (xy 176.072038 -278.416004)
			(xy 176.046509 -278.415541) (xy 175.996046 -278.407772) (xy 175.947374 -278.39235) (xy 175.901645 -278.369642)
			(xy 175.880522 -278.355298) (xy 175.873985 -278.351016) (xy 175.859119 -278.346227) (xy 175.851312 -278.3459)
			(xy 175.335438 -278.3459) (xy 175.330088 -278.345328) (xy 175.322502 -278.337785) (xy 175.321976 -278.332438)
			(xy 169.277792 -278.332438) (xy 169.277306 -278.337739) (xy 169.269875 -278.345306) (xy 169.264584 -278.3459)
			(xy 167.791384 -278.3459) (xy 167.786117 -278.345415) (xy 167.778675 -278.33796) (xy 167.778176 -278.332692)
			(xy 60.178164 -278.332692) (xy 60.177677 -278.3378) (xy 60.170089 -278.345382) (xy 60.164726 -278.3459)
			(xy 58.691526 -278.3459) (xy 58.686174 -278.345336) (xy 58.678589 -278.337787) (xy 58.678064 -278.332438)
			(xy 52.63388 -278.332438) (xy 52.633404 -278.337742) (xy 52.625967 -278.34531) (xy 52.620672 -278.3459)
			(xy 52.104798 -278.3459) (xy 52.096988 -278.346213) (xy 52.082116 -278.350999) (xy 52.075588 -278.355298)
			(xy 52.054463 -278.369642) (xy 52.008741 -278.392372) (xy 51.960069 -278.407803) (xy 51.909603 -278.415571)
			(xy 51.884072 -278.416004) (xy 51.858542 -278.415574) (xy 51.808078 -278.407795) (xy 51.759406 -278.392364)
			(xy 51.713678 -278.369646) (xy 51.692556 -278.355298) (xy 51.686034 -278.350991) (xy 51.671157 -278.346218)
			(xy 51.663346 -278.3459) (xy 51.147472 -278.3459) (xy 51.142204 -278.345423) (xy 51.134762 -278.337961)
			(xy 51.134264 -278.332692) (xy 45.090056 -278.332692) (xy 45.089576 -278.337802) (xy 45.081983 -278.345384)
			(xy 45.076618 -278.3459) (xy 44.560744 -278.3459) (xy 44.552936 -278.346232) (xy 44.538064 -278.351005)
			(xy 44.531534 -278.355298) (xy 44.510424 -278.369666) (xy 44.464697 -278.39239) (xy 44.41602 -278.407815)
			(xy 44.36555 -278.415575) (xy 44.340018 -278.416004) (xy 44.314488 -278.415551) (xy 44.264026 -278.407779)
			(xy 44.215353 -278.392355) (xy 44.169625 -278.369643) (xy 44.148502 -278.355298) (xy 44.141969 -278.351009)
			(xy 44.1271 -278.346224) (xy 44.119292 -278.3459) (xy 43.603418 -278.3459) (xy 43.598065 -278.345342)
			(xy 43.590481 -278.337789) (xy 43.589956 -278.332438) (xy 37.545772 -278.332438) (xy 37.545303 -278.337744)
			(xy 37.537861 -278.345312) (xy 37.532564 -278.3459) (xy 37.01669 -278.3459) (xy 37.00888 -278.346209)
			(xy 36.994008 -278.350998) (xy 36.98748 -278.355298) (xy 36.966357 -278.369646) (xy 36.920634 -278.392374)
			(xy 36.871961 -278.407805) (xy 36.821495 -278.415571) (xy 36.795964 -278.416004) (xy 36.770433 -278.415578)
			(xy 36.719969 -278.407798) (xy 36.671297 -278.392365) (xy 36.62557 -278.369646) (xy 36.604448 -278.355298)
			(xy 36.597927 -278.350988) (xy 36.583049 -278.346217) (xy 36.575238 -278.3459) (xy 36.059364 -278.3459)
			(xy 36.054095 -278.345428) (xy 36.046654 -278.337963) (xy 36.046156 -278.332692) (xy 30.00195 -278.332692)
			(xy 30.001503 -278.337744) (xy 29.994061 -278.345312) (xy 29.988764 -278.3459) (xy 29.47289 -278.3459)
			(xy 29.46508 -278.346209) (xy 29.450208 -278.350998) (xy 29.44368 -278.355298) (xy 29.422557 -278.369646)
			(xy 29.376834 -278.392374) (xy 29.328161 -278.407805) (xy 29.277695 -278.415571) (xy 29.252164 -278.416004)
			(xy 29.226633 -278.415578) (xy 29.176169 -278.407798) (xy 29.127497 -278.392365) (xy 29.08177 -278.369646)
			(xy 29.060648 -278.355298) (xy 29.054127 -278.350988) (xy 29.039249 -278.346217) (xy 29.031438 -278.3459)
			(xy 28.515564 -278.3459) (xy 28.510295 -278.345428) (xy 28.502854 -278.337963) (xy 28.502356 -278.332692)
			(xy 22.458149 -278.332692) (xy 22.457676 -278.337804) (xy 22.450077 -278.345387) (xy 22.44471 -278.3459)
			(xy 21.928836 -278.3459) (xy 21.921027 -278.346229) (xy 21.906156 -278.351004) (xy 21.899626 -278.355298)
			(xy 21.87849 -278.369626) (xy 21.832772 -278.392359) (xy 21.784103 -278.407795) (xy 21.73364 -278.415568)
			(xy 21.70811 -278.416004) (xy 21.68258 -278.415555) (xy 21.632117 -278.407782) (xy 21.583445 -278.392356)
			(xy 21.537717 -278.369643) (xy 21.516594 -278.355298) (xy 21.510063 -278.351005) (xy 21.495193 -278.346223)
			(xy 21.487384 -278.3459) (xy 20.97151 -278.3459) (xy 20.966156 -278.345347) (xy 20.958572 -278.33779)
			(xy 20.958048 -278.332438) (xy 2.509012 -278.332438) (xy 2.509012 -279.182576) (xy 16.85798 -279.182576)
			(xy 16.85798 -278.688038) (xy 16.858309 -278.682598) (xy 16.866002 -278.674907) (xy 16.871442 -278.674576)
			(xy 17.38757 -278.674576) (xy 17.395379 -278.674254) (xy 17.410251 -278.669474) (xy 17.41678 -278.665178)
			(xy 17.437869 -278.650829) (xy 17.48353 -278.628098) (xy 17.532136 -278.612639) (xy 17.582539 -278.604816)
			(xy 17.633545 -278.604816) (xy 17.683948 -278.612639) (xy 17.732554 -278.628098) (xy 17.778215 -278.650829)
			(xy 17.799304 -278.665178) (xy 17.805837 -278.669467) (xy 17.820706 -278.674252) (xy 17.828514 -278.674576)
			(xy 18.344642 -278.674576) (xy 18.35002 -278.675026) (xy 18.357606 -278.682657) (xy 18.358104 -278.688038)
			(xy 18.358104 -279.182576) (xy 24.402288 -279.182576) (xy 24.402288 -278.688038) (xy 24.402754 -278.682727)
			(xy 24.410195 -278.675151) (xy 24.415496 -278.674576) (xy 24.931624 -278.674576) (xy 24.939435 -278.674277)
			(xy 24.954307 -278.669481) (xy 24.960834 -278.665178) (xy 24.981923 -278.650829) (xy 25.027584 -278.628098)
			(xy 25.07619 -278.612639) (xy 25.126593 -278.604816) (xy 25.177599 -278.604816) (xy 25.228002 -278.612639)
			(xy 25.276608 -278.628098) (xy 25.322269 -278.650829) (xy 25.343358 -278.665178) (xy 25.349879 -278.669488)
			(xy 25.364757 -278.67426) (xy 25.372568 -278.674576) (xy 25.888696 -278.674576) (xy 25.893954 -278.675096)
			(xy 25.901396 -278.682526) (xy 25.901904 -278.687784) (xy 25.901904 -278.688292) (xy 25.901904 -279.182576)
			(xy 31.946088 -279.182576) (xy 31.946088 -278.688038) (xy 31.946554 -278.682727) (xy 31.953995 -278.675151)
			(xy 31.959296 -278.674576) (xy 32.475424 -278.674576) (xy 32.483235 -278.674277) (xy 32.498107 -278.669481)
			(xy 32.504634 -278.665178) (xy 32.525723 -278.650829) (xy 32.571384 -278.628098) (xy 32.61999 -278.612639)
			(xy 32.670393 -278.604816) (xy 32.721399 -278.604816) (xy 32.771802 -278.612639) (xy 32.820408 -278.628098)
			(xy 32.866069 -278.650829) (xy 32.887158 -278.665178) (xy 32.893679 -278.669488) (xy 32.908557 -278.67426)
			(xy 32.916368 -278.674576) (xy 33.432496 -278.674576) (xy 33.437754 -278.675096) (xy 33.445196 -278.682526)
			(xy 33.445704 -278.687784) (xy 33.445704 -278.688292) (xy 33.445704 -279.182576) (xy 39.489888 -279.182576)
			(xy 39.489888 -278.688038) (xy 39.490471 -278.68269) (xy 39.498006 -278.675106) (xy 39.50335 -278.674576)
			(xy 40.019478 -278.674576) (xy 40.027288 -278.674257) (xy 40.042159 -278.669475) (xy 40.048688 -278.665178)
			(xy 40.069777 -278.650829) (xy 40.115438 -278.628098) (xy 40.164044 -278.612639) (xy 40.214447 -278.604816)
			(xy 40.265453 -278.604816) (xy 40.315856 -278.612639) (xy 40.364462 -278.628098) (xy 40.410123 -278.650829)
			(xy 40.431212 -278.665178) (xy 40.437743 -278.66947) (xy 40.452613 -278.674253) (xy 40.460422 -278.674576)
			(xy 40.97655 -278.674576) (xy 40.981929 -278.675021) (xy 40.989514 -278.682656) (xy 40.990012 -278.688038)
			(xy 40.990012 -279.182576) (xy 47.034196 -279.182576) (xy 47.034196 -278.688038) (xy 47.034744 -278.682749)
			(xy 47.042128 -278.675178) (xy 47.047404 -278.674576) (xy 47.563532 -278.674576) (xy 47.57134 -278.674237)
			(xy 47.586212 -278.669469) (xy 47.592742 -278.665178) (xy 47.613831 -278.650829) (xy 47.659492 -278.628098)
			(xy 47.708098 -278.612639) (xy 47.758501 -278.604816) (xy 47.809507 -278.604816) (xy 47.85991 -278.612639)
			(xy 47.908516 -278.628098) (xy 47.954177 -278.650829) (xy 47.975266 -278.665178) (xy 47.981807 -278.669453)
			(xy 47.99667 -278.674246) (xy 48.004476 -278.674576) (xy 48.520604 -278.674576) (xy 48.525863 -278.67509)
			(xy 48.533305 -278.682525) (xy 48.533812 -278.687784) (xy 48.533812 -278.688292) (xy 48.533812 -279.182576)
			(xy 54.577996 -279.182576) (xy 54.577996 -278.688038) (xy 54.578571 -278.682689) (xy 54.586112 -278.675103)
			(xy 54.591458 -278.674576) (xy 56.064658 -278.674576) (xy 56.070096 -278.674911) (xy 56.077787 -278.6826)
			(xy 56.07812 -278.688038) (xy 56.07812 -279.182576) (xy 163.678108 -279.182576) (xy 163.678108 -278.688038)
			(xy 163.678645 -278.682746) (xy 163.686037 -278.675175) (xy 163.691316 -278.674576) (xy 165.164516 -278.674576)
			(xy 165.169777 -278.675082) (xy 165.177218 -278.682523) (xy 165.177724 -278.687784) (xy 165.177724 -278.688292)
			(xy 165.177724 -279.182576) (xy 171.221908 -279.182576) (xy 171.221908 -278.688038) (xy 171.222302 -278.682615)
			(xy 171.229949 -278.674929) (xy 171.23537 -278.674576) (xy 171.751498 -278.674576) (xy 171.759308 -278.674266)
			(xy 171.77418 -278.669478) (xy 171.780708 -278.665178) (xy 171.801797 -278.650829) (xy 171.847458 -278.628098)
			(xy 171.896064 -278.612639) (xy 171.946467 -278.604816) (xy 171.997473 -278.604816) (xy 172.047876 -278.612639)
			(xy 172.096482 -278.628098) (xy 172.142143 -278.650829) (xy 172.163232 -278.665178) (xy 172.169759 -278.669478)
			(xy 172.184632 -278.674256) (xy 172.192442 -278.674576) (xy 172.70857 -278.674576) (xy 172.71401 -278.674903)
			(xy 172.7217 -278.682598) (xy 172.722032 -278.688038) (xy 172.722032 -279.182576) (xy 178.766216 -279.182576)
			(xy 178.766216 -278.688038) (xy 178.766746 -278.682744) (xy 178.774143 -278.675172) (xy 178.779424 -278.674576)
			(xy 179.295552 -278.674576) (xy 179.303361 -278.674246) (xy 179.318232 -278.669471) (xy 179.324762 -278.665178)
			(xy 179.345851 -278.650829) (xy 179.391512 -278.628098) (xy 179.440118 -278.612639) (xy 179.490521 -278.604816)
			(xy 179.541527 -278.604816) (xy 179.59193 -278.612639) (xy 179.640536 -278.628098) (xy 179.686197 -278.650829)
			(xy 179.707286 -278.665178) (xy 179.713823 -278.66946) (xy 179.728689 -278.674249) (xy 179.736496 -278.674576)
			(xy 180.252624 -278.674576) (xy 180.257886 -278.675077) (xy 180.265326 -278.682522) (xy 180.265832 -278.687784)
			(xy 180.265832 -278.688292) (xy 180.265832 -279.182576) (xy 186.310016 -279.182576) (xy 186.310016 -278.688038)
			(xy 186.310402 -278.682613) (xy 186.318055 -278.674927) (xy 186.323478 -278.674576) (xy 186.839606 -278.674576)
			(xy 186.847417 -278.674269) (xy 186.862288 -278.669479) (xy 186.868816 -278.665178) (xy 186.889905 -278.650829)
			(xy 186.935566 -278.628098) (xy 186.984172 -278.612639) (xy 187.034575 -278.604816) (xy 187.085581 -278.604816)
			(xy 187.135984 -278.612639) (xy 187.18459 -278.628098) (xy 187.230251 -278.650829) (xy 187.25134 -278.665178)
			(xy 187.257865 -278.669481) (xy 187.27274 -278.674257) (xy 187.28055 -278.674576) (xy 187.796678 -278.674576)
			(xy 187.802119 -278.674898) (xy 187.809809 -278.682597) (xy 187.81014 -278.688038) (xy 187.81014 -279.182576)
			(xy 193.854324 -279.182576) (xy 193.854324 -278.688038) (xy 193.854847 -278.682742) (xy 193.862248 -278.67517)
			(xy 193.867532 -278.674576) (xy 194.38366 -278.674576) (xy 194.391469 -278.674249) (xy 194.40634 -278.669472)
			(xy 194.41287 -278.665178) (xy 194.433959 -278.650829) (xy 194.47962 -278.628098) (xy 194.528226 -278.612639)
			(xy 194.578629 -278.604816) (xy 194.629635 -278.604816) (xy 194.680038 -278.612639) (xy 194.728644 -278.628098)
			(xy 194.774305 -278.650829) (xy 194.795394 -278.665178) (xy 194.801929 -278.669463) (xy 194.816796 -278.67425)
			(xy 194.824604 -278.674576) (xy 195.340732 -278.674576) (xy 195.345995 -278.675072) (xy 195.353435 -278.682521)
			(xy 195.35394 -278.687784) (xy 195.35394 -278.688292) (xy 195.35394 -279.182576) (xy 201.398124 -279.182576)
			(xy 201.398124 -278.688038) (xy 201.398647 -278.682742) (xy 201.406048 -278.67517) (xy 201.411332 -278.674576)
			(xy 201.92746 -278.674576) (xy 201.935269 -278.674249) (xy 201.95014 -278.669472) (xy 201.95667 -278.665178)
			(xy 201.977759 -278.650829) (xy 202.02342 -278.628098) (xy 202.072026 -278.612639) (xy 202.122429 -278.604816)
			(xy 202.173435 -278.604816) (xy 202.223838 -278.612639) (xy 202.272444 -278.628098) (xy 202.318105 -278.650829)
			(xy 202.339194 -278.665178) (xy 202.345729 -278.669463) (xy 202.360596 -278.67425) (xy 202.368404 -278.674576)
			(xy 202.884532 -278.674576) (xy 202.889795 -278.675072) (xy 202.897235 -278.682521) (xy 202.89774 -278.687784)
			(xy 202.89774 -278.688292) (xy 202.89774 -279.182322) (xy 264.798048 -279.182322) (xy 264.798048 -278.687784)
			(xy 264.798579 -278.68253) (xy 264.806003 -278.675091) (xy 264.811256 -278.674576) (xy 264.811764 -278.674576)
			(xy 265.327638 -278.674576) (xy 265.335446 -278.67424) (xy 265.350318 -278.66947) (xy 265.356848 -278.665178)
			(xy 265.377937 -278.650829) (xy 265.423598 -278.628098) (xy 265.472204 -278.612639) (xy 265.522607 -278.604816)
			(xy 265.573613 -278.604816) (xy 265.624016 -278.612639) (xy 265.672622 -278.628098) (xy 265.718283 -278.650829)
			(xy 265.739372 -278.665178) (xy 265.745912 -278.669455) (xy 265.760775 -278.674247) (xy 265.768582 -278.674576)
			(xy 266.28471 -278.674576) (xy 266.290024 -278.675021) (xy 266.297596 -278.682478) (xy 266.298172 -278.687784)
			(xy 266.298172 -279.182322) (xy 266.298148 -279.182576) (xy 272.342356 -279.182576) (xy 272.342356 -279.182068)
			(xy 272.342356 -278.687784) (xy 272.34288 -278.682528) (xy 272.350309 -278.675088) (xy 272.355564 -278.674576)
			(xy 272.871692 -278.674576) (xy 272.879502 -278.674263) (xy 272.894374 -278.669477) (xy 272.900902 -278.665178)
			(xy 272.921991 -278.650829) (xy 272.967652 -278.628098) (xy 273.016258 -278.612639) (xy 273.066661 -278.604816)
			(xy 273.117667 -278.604816) (xy 273.16807 -278.612639) (xy 273.216676 -278.628098) (xy 273.262337 -278.650829)
			(xy 273.283426 -278.665178) (xy 273.289954 -278.669476) (xy 273.304827 -278.674255) (xy 273.312636 -278.674576)
			(xy 273.828764 -278.674576) (xy 273.834088 -278.674949) (xy 273.84163 -278.682462) (xy 273.841972 -278.687784)
			(xy 273.841972 -279.182322) (xy 273.841949 -279.182576) (xy 279.886156 -279.182576) (xy 279.886156 -279.182068)
			(xy 279.886156 -278.687784) (xy 279.88668 -278.682528) (xy 279.894109 -278.675088) (xy 279.899364 -278.674576)
			(xy 280.415492 -278.674576) (xy 280.423302 -278.674263) (xy 280.438174 -278.669477) (xy 280.444702 -278.665178)
			(xy 280.465791 -278.650829) (xy 280.511452 -278.628098) (xy 280.560058 -278.612639) (xy 280.610461 -278.604816)
			(xy 280.661467 -278.604816) (xy 280.71187 -278.612639) (xy 280.760476 -278.628098) (xy 280.806137 -278.650829)
			(xy 280.827226 -278.665178) (xy 280.833754 -278.669476) (xy 280.848627 -278.674255) (xy 280.856436 -278.674576)
			(xy 281.372564 -278.674576) (xy 281.377888 -278.674949) (xy 281.38543 -278.682462) (xy 281.385772 -278.687784)
			(xy 281.385772 -279.182322) (xy 287.429956 -279.182322) (xy 287.429956 -278.687784) (xy 287.43048 -278.682528)
			(xy 287.437909 -278.675088) (xy 287.443164 -278.674576) (xy 287.443672 -278.674576) (xy 287.959546 -278.674576)
			(xy 287.967354 -278.674243) (xy 287.982226 -278.669471) (xy 287.988756 -278.665178) (xy 288.009845 -278.650829)
			(xy 288.055506 -278.628098) (xy 288.104112 -278.612639) (xy 288.154515 -278.604816) (xy 288.205521 -278.604816)
			(xy 288.255924 -278.612639) (xy 288.30453 -278.628098) (xy 288.350191 -278.650829) (xy 288.37128 -278.665178)
			(xy 288.377818 -278.669458) (xy 288.392683 -278.674248) (xy 288.40049 -278.674576) (xy 288.916618 -278.674576)
			(xy 288.921933 -278.675015) (xy 288.929505 -278.682477) (xy 288.93008 -278.687784) (xy 288.93008 -279.182322)
			(xy 288.930056 -279.182576) (xy 294.974264 -279.182576) (xy 294.974264 -279.182068) (xy 294.974264 -278.687784)
			(xy 294.974781 -278.682526) (xy 294.982214 -278.675086) (xy 294.987472 -278.674576) (xy 295.5036 -278.674576)
			(xy 295.511411 -278.674266) (xy 295.526282 -278.669478) (xy 295.53281 -278.665178) (xy 295.553899 -278.650829)
			(xy 295.59956 -278.628098) (xy 295.648166 -278.612639) (xy 295.698569 -278.604816) (xy 295.749575 -278.604816)
			(xy 295.799978 -278.612639) (xy 295.848584 -278.628098) (xy 295.894245 -278.650829) (xy 295.915334 -278.665178)
			(xy 295.92186 -278.669479) (xy 295.936734 -278.674256) (xy 295.944544 -278.674576) (xy 296.460672 -278.674576)
			(xy 296.465997 -278.674944) (xy 296.473538 -278.68246) (xy 296.47388 -278.687784) (xy 296.47388 -279.182322)
			(xy 302.518064 -279.182322) (xy 302.518064 -278.687784) (xy 302.518581 -278.682526) (xy 302.526014 -278.675086)
			(xy 302.531272 -278.674576) (xy 304.004726 -278.674576) (xy 304.010042 -278.67501) (xy 304.017613 -278.682476)
			(xy 304.018188 -278.687784) (xy 304.018188 -279.182322) (xy 304.018163 -279.182576) (xy 411.618176 -279.182576)
			(xy 411.618176 -279.182068) (xy 411.618176 -278.687784) (xy 411.618682 -278.682523) (xy 411.626123 -278.675082)
			(xy 411.631384 -278.674576) (xy 413.104584 -278.674576) (xy 413.109841 -278.675104) (xy 413.117284 -278.682528)
			(xy 413.117792 -278.687784) (xy 413.117792 -279.182322) (xy 419.161976 -279.182322) (xy 419.161976 -278.687784)
			(xy 419.162482 -278.682523) (xy 419.169923 -278.675082) (xy 419.175184 -278.674576) (xy 419.175692 -278.674576)
			(xy 419.691566 -278.674576) (xy 419.699375 -278.674252) (xy 419.714247 -278.669474) (xy 419.720776 -278.665178)
			(xy 419.741865 -278.650829) (xy 419.787526 -278.628098) (xy 419.836132 -278.612639) (xy 419.886535 -278.604816)
			(xy 419.937541 -278.604816) (xy 419.987944 -278.612639) (xy 420.03655 -278.628098) (xy 420.082211 -278.650829)
			(xy 420.1033 -278.665178) (xy 420.109834 -278.669466) (xy 420.124702 -278.674251) (xy 420.13251 -278.674576)
			(xy 420.648638 -278.674576) (xy 420.653955 -278.675002) (xy 420.661526 -278.682474) (xy 420.6621 -278.687784)
			(xy 420.6621 -279.182322) (xy 420.662075 -279.182576) (xy 426.706284 -279.182576) (xy 426.706284 -279.182068)
			(xy 426.706284 -278.687784) (xy 426.706783 -278.682521) (xy 426.714229 -278.67508) (xy 426.719492 -278.674576)
			(xy 427.23562 -278.674576) (xy 427.243431 -278.674275) (xy 427.258303 -278.669481) (xy 427.26483 -278.665178)
			(xy 427.285919 -278.650829) (xy 427.33158 -278.628098) (xy 427.380186 -278.612639) (xy 427.430589 -278.604816)
			(xy 427.481595 -278.604816) (xy 427.531998 -278.612639) (xy 427.580604 -278.628098) (xy 427.626265 -278.650829)
			(xy 427.647354 -278.665178) (xy 427.653876 -278.669486) (xy 427.668753 -278.674259) (xy 427.676564 -278.674576)
			(xy 428.192692 -278.674576) (xy 428.19795 -278.675098) (xy 428.205392 -278.682527) (xy 428.2059 -278.687784)
			(xy 428.2059 -279.182322) (xy 434.250084 -279.182322) (xy 434.250084 -278.687784) (xy 434.250583 -278.682521)
			(xy 434.258029 -278.67508) (xy 434.263292 -278.674576) (xy 434.2638 -278.674576) (xy 434.779674 -278.674576)
			(xy 434.787484 -278.674256) (xy 434.802355 -278.669475) (xy 434.808884 -278.665178) (xy 434.829973 -278.650829)
			(xy 434.875634 -278.628098) (xy 434.92424 -278.612639) (xy 434.974643 -278.604816) (xy 435.025649 -278.604816)
			(xy 435.076052 -278.612639) (xy 435.124658 -278.628098) (xy 435.170319 -278.650829) (xy 435.191408 -278.665178)
			(xy 435.19794 -278.669469) (xy 435.21281 -278.674252) (xy 435.220618 -278.674576) (xy 435.736746 -278.674576)
			(xy 435.742052 -278.675063) (xy 435.749628 -278.682489) (xy 435.750208 -278.687784) (xy 435.750208 -279.182322)
			(xy 435.750182 -279.182576) (xy 441.794392 -279.182576) (xy 441.794392 -279.182068) (xy 441.794392 -278.687784)
			(xy 441.794884 -278.682519) (xy 441.802335 -278.675078) (xy 441.8076 -278.674576) (xy 442.323728 -278.674576)
			(xy 442.33154 -278.674278) (xy 442.346411 -278.669482) (xy 442.352938 -278.665178) (xy 442.374027 -278.650829)
			(xy 442.419688 -278.628098) (xy 442.468294 -278.612639) (xy 442.518697 -278.604816) (xy 442.569703 -278.604816)
			(xy 442.620106 -278.612639) (xy 442.668712 -278.628098) (xy 442.714373 -278.650829) (xy 442.735462 -278.665178)
			(xy 442.742004 -278.669451) (xy 442.756866 -278.674246) (xy 442.764672 -278.674576) (xy 443.2808 -278.674576)
			(xy 443.286059 -278.675093) (xy 443.2935 -278.682526) (xy 443.294008 -278.687784) (xy 443.294008 -279.182322)
			(xy 443.293983 -279.182576) (xy 449.338192 -279.182576) (xy 449.338192 -279.182068) (xy 449.338192 -278.687784)
			(xy 449.338684 -278.682519) (xy 449.346135 -278.675078) (xy 449.3514 -278.674576) (xy 449.867528 -278.674576)
			(xy 449.87534 -278.674278) (xy 449.890211 -278.669482) (xy 449.896738 -278.665178) (xy 449.917827 -278.650829)
			(xy 449.963488 -278.628098) (xy 450.012094 -278.612639) (xy 450.062497 -278.604816) (xy 450.113503 -278.604816)
			(xy 450.163906 -278.612639) (xy 450.212512 -278.628098) (xy 450.258173 -278.650829) (xy 450.279262 -278.665178)
			(xy 450.285804 -278.669451) (xy 450.300666 -278.674246) (xy 450.308472 -278.674576) (xy 450.8246 -278.674576)
			(xy 450.829859 -278.675093) (xy 450.8373 -278.682526) (xy 450.837808 -278.687784) (xy 450.837808 -279.182322)
			(xy 450.837297 -279.187618) (xy 450.829884 -279.195185) (xy 450.8246 -279.195784) (xy 450.308726 -279.195784)
			(xy 450.300915 -279.196095) (xy 450.286043 -279.200881) (xy 450.279516 -279.205182) (xy 450.25839 -279.219524)
			(xy 450.212667 -279.242252) (xy 450.163996 -279.257683) (xy 450.11353 -279.265453) (xy 450.088 -279.265888)
			(xy 450.06247 -279.265447) (xy 450.012006 -279.257672) (xy 449.963334 -279.242244) (xy 449.917606 -279.219529)
			(xy 449.896484 -279.205182) (xy 449.889951 -279.200894) (xy 449.875082 -279.196107) (xy 449.867274 -279.195784)
			(xy 449.3514 -279.195784) (xy 449.346062 -279.195471) (xy 449.338519 -279.187915) (xy 449.338192 -279.182576)
			(xy 443.293983 -279.182576) (xy 443.293497 -279.187618) (xy 443.286084 -279.195185) (xy 443.2808 -279.195784)
			(xy 442.764926 -279.195784) (xy 442.757115 -279.196095) (xy 442.742243 -279.200881) (xy 442.735716 -279.205182)
			(xy 442.71459 -279.219524) (xy 442.668867 -279.242252) (xy 442.620196 -279.257683) (xy 442.56973 -279.265453)
			(xy 442.5442 -279.265888) (xy 442.51867 -279.265447) (xy 442.468206 -279.257672) (xy 442.419534 -279.242244)
			(xy 442.373806 -279.219529) (xy 442.352684 -279.205182) (xy 442.346151 -279.200894) (xy 442.331282 -279.196107)
			(xy 442.323474 -279.195784) (xy 441.8076 -279.195784) (xy 441.802262 -279.195471) (xy 441.794719 -279.187915)
			(xy 441.794392 -279.182576) (xy 435.750182 -279.182576) (xy 435.749669 -279.187677) (xy 435.742101 -279.195259)
			(xy 435.736746 -279.195784) (xy 435.220872 -279.195784) (xy 435.213059 -279.196072) (xy 435.198188 -279.200874)
			(xy 435.191662 -279.205182) (xy 435.170551 -279.219547) (xy 435.124823 -279.24227) (xy 435.076147 -279.257695)
			(xy 435.025678 -279.265457) (xy 435.000146 -279.265888) (xy 434.974617 -279.265424) (xy 434.924154 -279.257656)
			(xy 434.875482 -279.242235) (xy 434.829753 -279.219526) (xy 434.80863 -279.205182) (xy 434.802086 -279.200911)
			(xy 434.787226 -279.196114) (xy 434.77942 -279.195784) (xy 434.263546 -279.195784) (xy 434.258123 -279.195392)
			(xy 434.250435 -279.187744) (xy 434.250084 -279.182322) (xy 428.2059 -279.182322) (xy 428.205396 -279.187619)
			(xy 428.197979 -279.195187) (xy 428.192692 -279.195784) (xy 427.676818 -279.195784) (xy 427.669007 -279.196091)
			(xy 427.654135 -279.20088) (xy 427.647608 -279.205182) (xy 427.626484 -279.219528) (xy 427.580761 -279.242254)
			(xy 427.532088 -279.257685) (xy 427.481623 -279.265454) (xy 427.456092 -279.265888) (xy 427.430562 -279.265451)
			(xy 427.380098 -279.257675) (xy 427.331426 -279.242245) (xy 427.285698 -279.219529) (xy 427.264576 -279.205182)
			(xy 427.258044 -279.200891) (xy 427.243175 -279.196106) (xy 427.235366 -279.195784) (xy 426.719492 -279.195784)
			(xy 426.714153 -279.195476) (xy 426.706611 -279.187916) (xy 426.706284 -279.182576) (xy 420.662075 -279.182576)
			(xy 420.661568 -279.187679) (xy 420.653995 -279.195262) (xy 420.648638 -279.195784) (xy 420.132764 -279.195784)
			(xy 420.124955 -279.196111) (xy 420.110083 -279.200886) (xy 420.103554 -279.205182) (xy 420.082445 -279.219551)
			(xy 420.036716 -279.242272) (xy 419.988039 -279.257697) (xy 419.93757 -279.265458) (xy 419.912038 -279.265888)
			(xy 419.886509 -279.265428) (xy 419.836046 -279.257659) (xy 419.787374 -279.242236) (xy 419.741645 -279.219526)
			(xy 419.720522 -279.205182) (xy 419.71398 -279.200908) (xy 419.699118 -279.196113) (xy 419.691312 -279.195784)
			(xy 419.175438 -279.195784) (xy 419.170013 -279.195398) (xy 419.162327 -279.187745) (xy 419.161976 -279.182322)
			(xy 413.117792 -279.182322) (xy 413.117295 -279.187621) (xy 413.109873 -279.195189) (xy 413.104584 -279.195784)
			(xy 411.631384 -279.195784) (xy 411.626044 -279.195482) (xy 411.618502 -279.187917) (xy 411.618176 -279.182576)
			(xy 304.018163 -279.182576) (xy 304.017667 -279.187682) (xy 304.010086 -279.195265) (xy 304.004726 -279.195784)
			(xy 302.531526 -279.195784) (xy 302.5261 -279.195406) (xy 302.518414 -279.187747) (xy 302.518064 -279.182322)
			(xy 296.47388 -279.182322) (xy 296.473394 -279.187624) (xy 296.465964 -279.195193) (xy 296.460672 -279.195784)
			(xy 295.944798 -279.195784) (xy 295.936986 -279.196083) (xy 295.922114 -279.200878) (xy 295.915588 -279.205182)
			(xy 295.89447 -279.219536) (xy 295.848744 -279.242261) (xy 295.80007 -279.257689) (xy 295.749603 -279.265455)
			(xy 295.724072 -279.265888) (xy 295.698541 -279.265461) (xy 295.648077 -279.257682) (xy 295.599405 -279.24225)
			(xy 295.553678 -279.21953) (xy 295.532556 -279.205182) (xy 295.526029 -279.200883) (xy 295.511156 -279.196103)
			(xy 295.503346 -279.195784) (xy 294.987472 -279.195784) (xy 294.9822 -279.195322) (xy 294.974758 -279.18785)
			(xy 294.974264 -279.182576) (xy 288.930056 -279.182576) (xy 288.929566 -279.187684) (xy 288.92198 -279.195268)
			(xy 288.916618 -279.195784) (xy 288.400744 -279.195784) (xy 288.392934 -279.196102) (xy 288.378062 -279.200884)
			(xy 288.371534 -279.205182) (xy 288.350431 -279.21956) (xy 288.3047 -279.242279) (xy 288.256021 -279.257701)
			(xy 288.20555 -279.265459) (xy 288.180018 -279.265888) (xy 288.154488 -279.265438) (xy 288.104025 -279.257666)
			(xy 288.055353 -279.24224) (xy 288.009625 -279.219528) (xy 287.988502 -279.205182) (xy 287.981965 -279.200901)
			(xy 287.967099 -279.19611) (xy 287.959292 -279.195784) (xy 287.443418 -279.195784) (xy 287.438061 -279.19524)
			(xy 287.430476 -279.187677) (xy 287.429956 -279.182322) (xy 281.385772 -279.182322) (xy 281.385293 -279.187626)
			(xy 281.377858 -279.195195) (xy 281.372564 -279.195784) (xy 280.85669 -279.195784) (xy 280.848878 -279.196079)
			(xy 280.834006 -279.200877) (xy 280.82748 -279.205182) (xy 280.806364 -279.21954) (xy 280.760638 -279.242264)
			(xy 280.711963 -279.257691) (xy 280.661495 -279.265456) (xy 280.635964 -279.265888) (xy 280.610433 -279.265465)
			(xy 280.559969 -279.257684) (xy 280.511297 -279.242251) (xy 280.46557 -279.219531) (xy 280.444448 -279.205182)
			(xy 280.437923 -279.20088) (xy 280.423048 -279.196102) (xy 280.415238 -279.195784) (xy 279.899364 -279.195784)
			(xy 279.894091 -279.195327) (xy 279.886649 -279.187851) (xy 279.886156 -279.182576) (xy 273.841949 -279.182576)
			(xy 273.841493 -279.187626) (xy 273.834058 -279.195195) (xy 273.828764 -279.195784) (xy 273.31289 -279.195784)
			(xy 273.305078 -279.196079) (xy 273.290206 -279.200877) (xy 273.28368 -279.205182) (xy 273.262564 -279.21954)
			(xy 273.216838 -279.242264) (xy 273.168163 -279.257691) (xy 273.117695 -279.265456) (xy 273.092164 -279.265888)
			(xy 273.066633 -279.265465) (xy 273.016169 -279.257684) (xy 272.967497 -279.242251) (xy 272.92177 -279.219531)
			(xy 272.900648 -279.205182) (xy 272.894123 -279.20088) (xy 272.879248 -279.196102) (xy 272.871438 -279.195784)
			(xy 272.355564 -279.195784) (xy 272.350291 -279.195327) (xy 272.342849 -279.187851) (xy 272.342356 -279.182576)
			(xy 266.298148 -279.182576) (xy 266.297665 -279.187686) (xy 266.290075 -279.19527) (xy 266.28471 -279.195784)
			(xy 265.768836 -279.195784) (xy 265.761026 -279.196099) (xy 265.746154 -279.200883) (xy 265.739626 -279.205182)
			(xy 265.718497 -279.21952) (xy 265.672776 -279.242248) (xy 265.624105 -279.257681) (xy 265.57364 -279.265452)
			(xy 265.54811 -279.265888) (xy 265.52258 -279.265442) (xy 265.472117 -279.257668) (xy 265.423445 -279.242242)
			(xy 265.377716 -279.219528) (xy 265.356594 -279.205182) (xy 265.350058 -279.200898) (xy 265.335192 -279.196109)
			(xy 265.327384 -279.195784) (xy 264.81151 -279.195784) (xy 264.806153 -279.195245) (xy 264.798568 -279.187678)
			(xy 264.798048 -279.182322) (xy 202.89774 -279.182322) (xy 202.89774 -279.182576) (xy 202.897192 -279.187828)
			(xy 202.889782 -279.19527) (xy 202.884532 -279.195784) (xy 202.368658 -279.195784) (xy 202.360782 -279.196056)
			(xy 202.345778 -279.20085) (xy 202.339194 -279.205182) (xy 202.318111 -279.219565) (xy 202.272468 -279.242395)
			(xy 202.223864 -279.257954) (xy 202.173448 -279.265877) (xy 202.147932 -279.266396) (xy 202.122412 -279.265908)
			(xy 202.071985 -279.258013) (xy 202.023373 -279.242453) (xy 201.977735 -279.219597) (xy 201.95667 -279.205182)
			(xy 201.950088 -279.200851) (xy 201.935081 -279.196074) (xy 201.927206 -279.195784) (xy 201.411332 -279.195784)
			(xy 201.405998 -279.195449) (xy 201.398454 -279.18791) (xy 201.398124 -279.182576) (xy 195.35394 -279.182576)
			(xy 195.353392 -279.187828) (xy 195.345982 -279.19527) (xy 195.340732 -279.195784) (xy 194.824858 -279.195784)
			(xy 194.816982 -279.196056) (xy 194.801978 -279.20085) (xy 194.795394 -279.205182) (xy 194.774311 -279.219565)
			(xy 194.728668 -279.242395) (xy 194.680064 -279.257954) (xy 194.629648 -279.265877) (xy 194.604132 -279.266396)
			(xy 194.578612 -279.265908) (xy 194.528185 -279.258013) (xy 194.479573 -279.242453) (xy 194.433935 -279.219597)
			(xy 194.41287 -279.205182) (xy 194.406288 -279.200851) (xy 194.391281 -279.196074) (xy 194.383406 -279.195784)
			(xy 193.867532 -279.195784) (xy 193.862198 -279.195449) (xy 193.854654 -279.18791) (xy 193.854324 -279.182576)
			(xy 187.81014 -279.182576) (xy 187.809592 -279.187828) (xy 187.802182 -279.19527) (xy 187.796932 -279.195784)
			(xy 187.796424 -279.195784) (xy 187.280804 -279.195784) (xy 187.27293 -279.196075) (xy 187.257925 -279.200856)
			(xy 187.25134 -279.205182) (xy 187.230272 -279.219588) (xy 187.184624 -279.242412) (xy 187.136015 -279.257966)
			(xy 187.085595 -279.265881) (xy 187.060078 -279.266396) (xy 187.034559 -279.265885) (xy 186.984133 -279.257997)
			(xy 186.935521 -279.242443) (xy 186.889882 -279.219594) (xy 186.868816 -279.205182) (xy 186.862224 -279.200869)
			(xy 186.847224 -279.196081) (xy 186.839352 -279.195784) (xy 186.323478 -279.195784) (xy 186.318177 -279.195294)
			(xy 186.310608 -279.187867) (xy 186.310016 -279.182576) (xy 180.265832 -279.182576) (xy 180.265292 -279.18783)
			(xy 180.257876 -279.195273) (xy 180.252624 -279.195784) (xy 179.73675 -279.195784) (xy 179.728874 -279.196052)
			(xy 179.71387 -279.200849) (xy 179.707286 -279.205182) (xy 179.686206 -279.219569) (xy 179.640561 -279.242397)
			(xy 179.591956 -279.257956) (xy 179.54154 -279.265877) (xy 179.516024 -279.266396) (xy 179.490504 -279.265912)
			(xy 179.440076 -279.258016) (xy 179.391465 -279.242454) (xy 179.345827 -279.219598) (xy 179.324762 -279.205182)
			(xy 179.318182 -279.200848) (xy 179.303173 -279.196073) (xy 179.295298 -279.195784) (xy 178.779424 -279.195784)
			(xy 178.774089 -279.195455) (xy 178.766545 -279.187911) (xy 178.766216 -279.182576) (xy 172.722032 -279.182576)
			(xy 172.721492 -279.18783) (xy 172.714076 -279.195273) (xy 172.708824 -279.195784) (xy 172.708316 -279.195784)
			(xy 172.192696 -279.195784) (xy 172.184821 -279.196072) (xy 172.169817 -279.200855) (xy 172.163232 -279.205182)
			(xy 172.142167 -279.219592) (xy 172.096517 -279.242415) (xy 172.047907 -279.257968) (xy 171.997488 -279.265881)
			(xy 171.97197 -279.266396) (xy 171.946451 -279.265889) (xy 171.896024 -279.258) (xy 171.847413 -279.242445)
			(xy 171.801774 -279.219595) (xy 171.780708 -279.205182) (xy 171.774117 -279.200866) (xy 171.759117 -279.19608)
			(xy 171.751244 -279.195784) (xy 171.23537 -279.195784) (xy 171.230068 -279.1953) (xy 171.2225 -279.187868)
			(xy 171.221908 -279.182576) (xy 165.177724 -279.182576) (xy 165.177359 -279.187901) (xy 165.16984 -279.195443)
			(xy 165.164516 -279.195784) (xy 163.691316 -279.195784) (xy 163.68598 -279.19546) (xy 163.678437 -279.187912)
			(xy 163.678108 -279.182576) (xy 56.07812 -279.182576) (xy 56.077758 -279.187902) (xy 56.070237 -279.195444)
			(xy 56.064912 -279.195784) (xy 54.591458 -279.195784) (xy 54.586154 -279.195308) (xy 54.578587 -279.18787)
			(xy 54.577996 -279.182576) (xy 48.533812 -279.182576) (xy 48.533457 -279.187904) (xy 48.525931 -279.195446)
			(xy 48.520604 -279.195784) (xy 48.00473 -279.195784) (xy 47.996853 -279.196044) (xy 47.981849 -279.200846)
			(xy 47.975266 -279.205182) (xy 47.954191 -279.219577) (xy 47.908545 -279.242404) (xy 47.859938 -279.25796)
			(xy 47.809521 -279.265879) (xy 47.784004 -279.266396) (xy 47.758483 -279.265922) (xy 47.708056 -279.258023)
			(xy 47.659444 -279.242458) (xy 47.613806 -279.219599) (xy 47.592742 -279.205182) (xy 47.586166 -279.20084)
			(xy 47.571154 -279.19607) (xy 47.563278 -279.195784) (xy 47.047404 -279.195784) (xy 47.042066 -279.195468)
			(xy 47.034524 -279.187914) (xy 47.034196 -279.182576) (xy 40.990012 -279.182576) (xy 40.989657 -279.187904)
			(xy 40.982131 -279.195446) (xy 40.976804 -279.195784) (xy 40.976296 -279.195784) (xy 40.460676 -279.195784)
			(xy 40.452801 -279.196063) (xy 40.437796 -279.200852) (xy 40.431212 -279.205182) (xy 40.410152 -279.219601)
			(xy 40.364501 -279.242422) (xy 40.315889 -279.257972) (xy 40.265468 -279.265883) (xy 40.23995 -279.266396)
			(xy 40.21443 -279.265899) (xy 40.164003 -279.258007) (xy 40.115392 -279.242449) (xy 40.069753 -279.219596)
			(xy 40.048688 -279.205182) (xy 40.042102 -279.200858) (xy 40.027098 -279.196077) (xy 40.019224 -279.195784)
			(xy 39.50335 -279.195784) (xy 39.498057 -279.195246) (xy 39.490485 -279.187855) (xy 39.489888 -279.182576)
			(xy 33.445704 -279.182576) (xy 33.445357 -279.187906) (xy 33.437825 -279.195449) (xy 33.432496 -279.195784)
			(xy 32.916622 -279.195784) (xy 32.908748 -279.196083) (xy 32.893744 -279.200858) (xy 32.887158 -279.205182)
			(xy 32.866085 -279.219581) (xy 32.820438 -279.242406) (xy 32.771831 -279.257962) (xy 32.721413 -279.265879)
			(xy 32.695896 -279.266396) (xy 32.670375 -279.265926) (xy 32.619947 -279.258026) (xy 32.571336 -279.24246)
			(xy 32.525698 -279.2196) (xy 32.504634 -279.205182) (xy 32.498038 -279.200876) (xy 32.483041 -279.196084)
			(xy 32.47517 -279.195784) (xy 31.959296 -279.195784) (xy 31.953957 -279.195473) (xy 31.946415 -279.187915)
			(xy 31.946088 -279.182576) (xy 25.901904 -279.182576) (xy 25.901557 -279.187906) (xy 25.894025 -279.195449)
			(xy 25.888696 -279.195784) (xy 25.372822 -279.195784) (xy 25.364948 -279.196083) (xy 25.349944 -279.200858)
			(xy 25.343358 -279.205182) (xy 25.322285 -279.219581) (xy 25.276638 -279.242406) (xy 25.228031 -279.257962)
			(xy 25.177613 -279.265879) (xy 25.152096 -279.266396) (xy 25.126575 -279.265926) (xy 25.076147 -279.258026)
			(xy 25.027536 -279.24246) (xy 24.981898 -279.2196) (xy 24.960834 -279.205182) (xy 24.954238 -279.200876)
			(xy 24.939241 -279.196084) (xy 24.93137 -279.195784) (xy 24.415496 -279.195784) (xy 24.410157 -279.195473)
			(xy 24.402615 -279.187915) (xy 24.402288 -279.182576) (xy 18.358104 -279.182576) (xy 18.357757 -279.187906)
			(xy 18.350225 -279.195449) (xy 18.344896 -279.195784) (xy 18.344388 -279.195784) (xy 17.828768 -279.195784)
			(xy 17.820892 -279.19606) (xy 17.805888 -279.200851) (xy 17.799304 -279.205182) (xy 17.778218 -279.219561)
			(xy 17.732576 -279.242391) (xy 17.683973 -279.257952) (xy 17.633558 -279.265876) (xy 17.608042 -279.266396)
			(xy 17.582522 -279.265903) (xy 17.532095 -279.25801) (xy 17.483483 -279.242451) (xy 17.437845 -279.219597)
			(xy 17.41678 -279.205182) (xy 17.410196 -279.200855) (xy 17.39519 -279.196076) (xy 17.387316 -279.195784)
			(xy 16.871442 -279.195784) (xy 16.866148 -279.195252) (xy 16.858576 -279.187857) (xy 16.85798 -279.182576)
			(xy 2.509012 -279.182576) (xy 2.509012 -280.03246) (xy 20.958048 -280.03246) (xy 20.958048 -279.537922)
			(xy 20.958395 -279.532488) (xy 20.966076 -279.5248) (xy 20.97151 -279.52446) (xy 21.487638 -279.52446)
			(xy 21.495446 -279.524127) (xy 21.510318 -279.519355) (xy 21.516848 -279.515062) (xy 21.537937 -279.500713)
			(xy 21.583598 -279.477982) (xy 21.632204 -279.462523) (xy 21.682607 -279.4547) (xy 21.733613 -279.4547)
			(xy 21.784016 -279.462523) (xy 21.832622 -279.477982) (xy 21.878283 -279.500713) (xy 21.899372 -279.515062)
			(xy 21.905913 -279.519337) (xy 21.920776 -279.524131) (xy 21.928582 -279.52446) (xy 22.44471 -279.52446)
			(xy 22.450152 -279.524775) (xy 22.457838 -279.53248) (xy 22.458172 -279.537922) (xy 22.458172 -280.03246)
			(xy 28.502356 -280.03246) (xy 28.502356 -279.537922) (xy 28.502839 -279.532617) (xy 28.510269 -279.525043)
			(xy 28.515564 -279.52446) (xy 29.031692 -279.52446) (xy 29.039503 -279.52415) (xy 29.054374 -279.519362)
			(xy 29.060902 -279.515062) (xy 29.081991 -279.500713) (xy 29.127652 -279.477982) (xy 29.176258 -279.462523)
			(xy 29.226661 -279.4547) (xy 29.277667 -279.4547) (xy 29.32807 -279.462523) (xy 29.376676 -279.477982)
			(xy 29.422337 -279.500713) (xy 29.443426 -279.515062) (xy 29.449955 -279.519358) (xy 29.464827 -279.524139)
			(xy 29.472636 -279.52446) (xy 29.988764 -279.52446) (xy 29.994084 -279.524848) (xy 30.001625 -279.53235)
			(xy 30.001972 -279.537668) (xy 30.001972 -279.538176) (xy 30.001972 -280.03246) (xy 36.046156 -280.03246)
			(xy 36.046156 -279.537922) (xy 36.046639 -279.532617) (xy 36.054069 -279.525043) (xy 36.059364 -279.52446)
			(xy 36.575492 -279.52446) (xy 36.583303 -279.52415) (xy 36.598174 -279.519362) (xy 36.604702 -279.515062)
			(xy 36.625791 -279.500713) (xy 36.671452 -279.477982) (xy 36.720058 -279.462523) (xy 36.770461 -279.4547)
			(xy 36.821467 -279.4547) (xy 36.87187 -279.462523) (xy 36.920476 -279.477982) (xy 36.966137 -279.500713)
			(xy 36.987226 -279.515062) (xy 36.993755 -279.519358) (xy 37.008627 -279.524139) (xy 37.016436 -279.52446)
			(xy 37.532564 -279.52446) (xy 37.537884 -279.524848) (xy 37.545425 -279.53235) (xy 37.545772 -279.537668)
			(xy 37.545772 -279.538176) (xy 37.545772 -280.03246) (xy 43.589956 -280.03246) (xy 43.589956 -279.537922)
			(xy 43.590296 -279.532486) (xy 43.597982 -279.524798) (xy 43.603418 -279.52446) (xy 44.119546 -279.52446)
			(xy 44.127355 -279.52413) (xy 44.142226 -279.519356) (xy 44.148756 -279.515062) (xy 44.169845 -279.500713)
			(xy 44.215506 -279.477982) (xy 44.264112 -279.462523) (xy 44.314515 -279.4547) (xy 44.365521 -279.4547)
			(xy 44.415924 -279.462523) (xy 44.46453 -279.477982) (xy 44.510191 -279.500713) (xy 44.53128 -279.515062)
			(xy 44.537819 -279.519341) (xy 44.552683 -279.524132) (xy 44.56049 -279.52446) (xy 45.076618 -279.52446)
			(xy 45.082061 -279.524769) (xy 45.089747 -279.532478) (xy 45.09008 -279.537922) (xy 45.09008 -280.03246)
			(xy 51.134264 -280.03246) (xy 51.134264 -279.537922) (xy 51.134741 -279.532615) (xy 51.142175 -279.525041)
			(xy 51.147472 -279.52446) (xy 51.6636 -279.52446) (xy 51.671411 -279.524153) (xy 51.686283 -279.519363)
			(xy 51.69281 -279.515062) (xy 51.713899 -279.500713) (xy 51.75956 -279.477982) (xy 51.808166 -279.462523)
			(xy 51.858569 -279.4547) (xy 51.909575 -279.4547) (xy 51.959978 -279.462523) (xy 52.008584 -279.477982)
			(xy 52.054245 -279.500713) (xy 52.075334 -279.515062) (xy 52.081861 -279.519361) (xy 52.096734 -279.52414)
			(xy 52.104544 -279.52446) (xy 52.620672 -279.52446) (xy 52.625924 -279.52501) (xy 52.633366 -279.532419)
			(xy 52.63388 -279.537668) (xy 52.63388 -279.538176) (xy 52.63388 -280.03246) (xy 58.678064 -280.03246)
			(xy 58.678064 -279.537922) (xy 58.678397 -279.532484) (xy 58.686088 -279.524795) (xy 58.691526 -279.52446)
			(xy 60.164726 -279.52446) (xy 60.170098 -279.524935) (xy 60.177684 -279.532548) (xy 60.178188 -279.537922)
			(xy 60.178188 -280.03246) (xy 167.778176 -280.03246) (xy 167.778176 -279.537922) (xy 167.778642 -279.532612)
			(xy 167.786084 -279.525038) (xy 167.791384 -279.52446) (xy 169.264584 -279.52446) (xy 169.269837 -279.525002)
			(xy 169.277279 -279.532417) (xy 169.277792 -279.537668) (xy 169.277792 -280.03246) (xy 175.321976 -280.03246)
			(xy 175.321976 -279.537922) (xy 175.322298 -279.532481) (xy 175.329997 -279.524791) (xy 175.335438 -279.52446)
			(xy 175.851566 -279.52446) (xy 175.859375 -279.524138) (xy 175.874247 -279.519358) (xy 175.880776 -279.515062)
			(xy 175.901865 -279.500713) (xy 175.947526 -279.477982) (xy 175.996132 -279.462523) (xy 176.046535 -279.4547)
			(xy 176.097541 -279.4547) (xy 176.147944 -279.462523) (xy 176.19655 -279.477982) (xy 176.242211 -279.500713)
			(xy 176.2633 -279.515062) (xy 176.269835 -279.519348) (xy 176.284702 -279.524135) (xy 176.29251 -279.52446)
			(xy 176.808638 -279.52446) (xy 176.814012 -279.524928) (xy 176.821596 -279.532546) (xy 176.8221 -279.537922)
			(xy 176.8221 -280.03246) (xy 182.866284 -280.03246) (xy 182.866284 -279.537922) (xy 182.866743 -279.53261)
			(xy 182.874189 -279.525035) (xy 182.879492 -279.52446) (xy 183.39562 -279.52446) (xy 183.403432 -279.524162)
			(xy 183.418303 -279.519366) (xy 183.42483 -279.515062) (xy 183.445919 -279.500713) (xy 183.49158 -279.477982)
			(xy 183.540186 -279.462523) (xy 183.590589 -279.4547) (xy 183.641595 -279.4547) (xy 183.691998 -279.462523)
			(xy 183.740604 -279.477982) (xy 183.786265 -279.500713) (xy 183.807354 -279.515062) (xy 183.813877 -279.519369)
			(xy 183.828753 -279.524143) (xy 183.836564 -279.52446) (xy 184.352692 -279.52446) (xy 184.357946 -279.524997)
			(xy 184.365387 -279.532415) (xy 184.3659 -279.537668) (xy 184.3659 -279.538176) (xy 184.3659 -280.03246)
			(xy 190.410084 -280.03246) (xy 190.410084 -279.537922) (xy 190.410399 -279.532479) (xy 190.418102 -279.524789)
			(xy 190.423546 -279.52446) (xy 190.939674 -279.52446) (xy 190.947484 -279.524142) (xy 190.962355 -279.519359)
			(xy 190.968884 -279.515062) (xy 190.989973 -279.500713) (xy 191.035634 -279.477982) (xy 191.08424 -279.462523)
			(xy 191.134643 -279.4547) (xy 191.185649 -279.4547) (xy 191.236052 -279.462523) (xy 191.284658 -279.477982)
			(xy 191.330319 -279.500713) (xy 191.351408 -279.515062) (xy 191.357941 -279.519351) (xy 191.37281 -279.524136)
			(xy 191.380618 -279.52446) (xy 191.896746 -279.52446) (xy 191.902121 -279.524922) (xy 191.909705 -279.532545)
			(xy 191.910208 -279.537922) (xy 191.910208 -280.03246) (xy 197.954392 -280.03246) (xy 197.954392 -279.537922)
			(xy 197.954932 -279.532632) (xy 197.962323 -279.525062) (xy 197.9676 -279.52446) (xy 198.483728 -279.52446)
			(xy 198.49154 -279.524165) (xy 198.506411 -279.519367) (xy 198.512938 -279.515062) (xy 198.534027 -279.500713)
			(xy 198.579688 -279.477982) (xy 198.628294 -279.462523) (xy 198.678697 -279.4547) (xy 198.729703 -279.4547)
			(xy 198.780106 -279.462523) (xy 198.828712 -279.477982) (xy 198.874373 -279.500713) (xy 198.895462 -279.515062)
			(xy 198.902005 -279.519334) (xy 198.916866 -279.524129) (xy 198.924672 -279.52446) (xy 199.4408 -279.52446)
			(xy 199.446055 -279.524992) (xy 199.453496 -279.532414) (xy 199.454008 -279.537668) (xy 199.454008 -279.538176)
			(xy 199.454008 -280.03246) (xy 205.498192 -280.03246) (xy 205.498192 -279.537922) (xy 205.498732 -279.532632)
			(xy 205.506123 -279.525062) (xy 205.5114 -279.52446) (xy 206.027528 -279.52446) (xy 206.03534 -279.524165)
			(xy 206.050211 -279.519367) (xy 206.056738 -279.515062) (xy 206.077827 -279.500713) (xy 206.123488 -279.477982)
			(xy 206.172094 -279.462523) (xy 206.222497 -279.4547) (xy 206.273503 -279.4547) (xy 206.323906 -279.462523)
			(xy 206.372512 -279.477982) (xy 206.418173 -279.500713) (xy 206.439262 -279.515062) (xy 206.445805 -279.519334)
			(xy 206.460666 -279.524129) (xy 206.468472 -279.52446) (xy 206.9846 -279.52446) (xy 206.989855 -279.524992)
			(xy 206.997296 -279.532414) (xy 206.997808 -279.537668) (xy 206.997808 -279.538176) (xy 206.997808 -280.032206)
			(xy 268.898116 -280.032206) (xy 268.898116 -279.537668) (xy 268.898576 -279.532396) (xy 268.90605 -279.524953)
			(xy 268.911324 -279.52446) (xy 268.911832 -279.52446) (xy 269.427706 -279.52446) (xy 269.435517 -279.524156)
			(xy 269.450389 -279.519364) (xy 269.456916 -279.515062) (xy 269.478005 -279.500713) (xy 269.523666 -279.477982)
			(xy 269.572272 -279.462523) (xy 269.622675 -279.4547) (xy 269.673681 -279.4547) (xy 269.724084 -279.462523)
			(xy 269.77269 -279.477982) (xy 269.818351 -279.500713) (xy 269.83944 -279.515062) (xy 269.845966 -279.519364)
			(xy 269.86084 -279.524141) (xy 269.86865 -279.52446) (xy 270.384778 -279.52446) (xy 270.390084 -279.52494)
			(xy 270.397658 -279.532372) (xy 270.39824 -279.537668) (xy 270.39824 -280.032206) (xy 270.398225 -280.03246)
			(xy 276.442424 -280.03246) (xy 276.442424 -280.031952) (xy 276.442424 -279.537668) (xy 276.442877 -279.532394)
			(xy 276.450355 -279.524951) (xy 276.455632 -279.52446) (xy 276.97176 -279.52446) (xy 276.979569 -279.524136)
			(xy 276.994441 -279.519358) (xy 277.00097 -279.515062) (xy 277.022059 -279.500713) (xy 277.06772 -279.477982)
			(xy 277.116326 -279.462523) (xy 277.166729 -279.4547) (xy 277.217735 -279.4547) (xy 277.268138 -279.462523)
			(xy 277.316744 -279.477982) (xy 277.362405 -279.500713) (xy 277.383494 -279.515062) (xy 277.39003 -279.519346)
			(xy 277.404896 -279.524134) (xy 277.412704 -279.52446) (xy 277.928832 -279.52446) (xy 277.934091 -279.52497)
			(xy 277.94153 -279.532409) (xy 277.94204 -279.537668) (xy 277.94204 -280.032206) (xy 277.942018 -280.03246)
			(xy 283.986224 -280.03246) (xy 283.986224 -280.031952) (xy 283.986224 -279.537668) (xy 283.986677 -279.532394)
			(xy 283.994155 -279.524951) (xy 283.999432 -279.52446) (xy 284.51556 -279.52446) (xy 284.523369 -279.524136)
			(xy 284.538241 -279.519358) (xy 284.54477 -279.515062) (xy 284.565859 -279.500713) (xy 284.61152 -279.477982)
			(xy 284.660126 -279.462523) (xy 284.710529 -279.4547) (xy 284.761535 -279.4547) (xy 284.811938 -279.462523)
			(xy 284.860544 -279.477982) (xy 284.906205 -279.500713) (xy 284.927294 -279.515062) (xy 284.93383 -279.519346)
			(xy 284.948696 -279.524134) (xy 284.956504 -279.52446) (xy 285.472632 -279.52446) (xy 285.477891 -279.52497)
			(xy 285.48533 -279.532409) (xy 285.48584 -279.537668) (xy 285.48584 -280.032206) (xy 291.530024 -280.032206)
			(xy 291.530024 -279.537668) (xy 291.530477 -279.532394) (xy 291.537955 -279.524951) (xy 291.543232 -279.52446)
			(xy 291.54374 -279.52446) (xy 292.059614 -279.52446) (xy 292.067425 -279.524159) (xy 292.082297 -279.519365)
			(xy 292.088824 -279.515062) (xy 292.109913 -279.500713) (xy 292.155574 -279.477982) (xy 292.20418 -279.462523)
			(xy 292.254583 -279.4547) (xy 292.305589 -279.4547) (xy 292.355992 -279.462523) (xy 292.404598 -279.477982)
			(xy 292.450259 -279.500713) (xy 292.471348 -279.515062) (xy 292.477872 -279.519367) (xy 292.492748 -279.524142)
			(xy 292.500558 -279.52446) (xy 293.016686 -279.52446) (xy 293.021993 -279.524935) (xy 293.029566 -279.532371)
			(xy 293.030148 -279.537668) (xy 293.030148 -280.032206) (xy 293.030133 -280.03246) (xy 299.074332 -280.03246)
			(xy 299.074332 -280.031952) (xy 299.074332 -279.537668) (xy 299.074609 -279.532322) (xy 299.082192 -279.52478)
			(xy 299.08754 -279.52446) (xy 299.603668 -279.52446) (xy 299.611478 -279.524139) (xy 299.626349 -279.519359)
			(xy 299.632878 -279.515062) (xy 299.653967 -279.500713) (xy 299.699628 -279.477982) (xy 299.748234 -279.462523)
			(xy 299.798637 -279.4547) (xy 299.849643 -279.4547) (xy 299.900046 -279.462523) (xy 299.948652 -279.477982)
			(xy 299.994313 -279.500713) (xy 300.015402 -279.515062) (xy 300.021936 -279.519349) (xy 300.036804 -279.524135)
			(xy 300.044612 -279.52446) (xy 300.56074 -279.52446) (xy 300.566 -279.524965) (xy 300.573438 -279.532408)
			(xy 300.573948 -279.537668) (xy 300.573948 -280.032206) (xy 306.618132 -280.032206) (xy 306.618132 -279.537668)
			(xy 306.618409 -279.532322) (xy 306.625992 -279.52478) (xy 306.63134 -279.52446) (xy 306.631848 -279.52446)
			(xy 308.104794 -279.52446) (xy 308.110102 -279.524929) (xy 308.117675 -279.532369) (xy 308.118256 -279.537668)
			(xy 308.118256 -280.032206) (xy 308.118232 -280.03246) (xy 415.718244 -280.03246) (xy 415.718244 -279.537668)
			(xy 415.718769 -279.532413) (xy 415.726198 -279.524975) (xy 415.731452 -279.52446) (xy 417.204652 -279.52446)
			(xy 417.20997 -279.524856) (xy 417.217512 -279.532352) (xy 417.21786 -279.537668) (xy 417.21786 -280.032206)
			(xy 423.262044 -280.032206) (xy 423.262044 -279.537668) (xy 423.262569 -279.532413) (xy 423.269998 -279.524975)
			(xy 423.275252 -279.52446) (xy 423.27576 -279.52446) (xy 423.791634 -279.52446) (xy 423.799442 -279.524125)
			(xy 423.814314 -279.519354) (xy 423.820844 -279.515062) (xy 423.841933 -279.500713) (xy 423.887594 -279.477982)
			(xy 423.9362 -279.462523) (xy 423.986603 -279.4547) (xy 424.037609 -279.4547) (xy 424.088012 -279.462523)
			(xy 424.136618 -279.477982) (xy 424.182279 -279.500713) (xy 424.203368 -279.515062) (xy 424.20991 -279.519336)
			(xy 424.224772 -279.52413) (xy 424.232578 -279.52446) (xy 424.748706 -279.52446) (xy 424.754016 -279.524921)
			(xy 424.761588 -279.532367) (xy 424.762168 -279.537668) (xy 424.762168 -280.032206) (xy 424.762144 -280.03246)
			(xy 430.806352 -280.03246) (xy 430.806352 -280.031952) (xy 430.806352 -279.537668) (xy 430.806869 -279.532411)
			(xy 430.814303 -279.524973) (xy 430.81956 -279.52446) (xy 431.335688 -279.52446) (xy 431.343498 -279.524148)
			(xy 431.35837 -279.519362) (xy 431.364898 -279.515062) (xy 431.385987 -279.500713) (xy 431.431648 -279.477982)
			(xy 431.480254 -279.462523) (xy 431.530657 -279.4547) (xy 431.581663 -279.4547) (xy 431.632066 -279.462523)
			(xy 431.680672 -279.477982) (xy 431.726333 -279.500713) (xy 431.747422 -279.515062) (xy 431.753952 -279.519357)
			(xy 431.768823 -279.524138) (xy 431.776632 -279.52446) (xy 432.29276 -279.52446) (xy 432.298079 -279.524851)
			(xy 432.30562 -279.532351) (xy 432.305968 -279.537668) (xy 432.305968 -280.032206) (xy 438.350152 -280.032206)
			(xy 438.350152 -279.537668) (xy 438.350669 -279.532411) (xy 438.358103 -279.524973) (xy 438.36336 -279.52446)
			(xy 438.363868 -279.52446) (xy 438.879742 -279.52446) (xy 438.887551 -279.524128) (xy 438.902422 -279.519355)
			(xy 438.908952 -279.515062) (xy 438.930041 -279.500713) (xy 438.975702 -279.477982) (xy 439.024308 -279.462523)
			(xy 439.074711 -279.4547) (xy 439.125717 -279.4547) (xy 439.17612 -279.462523) (xy 439.224726 -279.477982)
			(xy 439.270387 -279.500713) (xy 439.291476 -279.515062) (xy 439.298016 -279.519339) (xy 439.312879 -279.524131)
			(xy 439.320686 -279.52446) (xy 439.836814 -279.52446) (xy 439.842124 -279.524916) (xy 439.849696 -279.532366)
			(xy 439.850276 -279.537668) (xy 439.850276 -280.032206) (xy 439.850251 -280.03246) (xy 445.89446 -280.03246)
			(xy 445.89446 -280.031952) (xy 445.89446 -279.537668) (xy 445.89497 -279.532409) (xy 445.902409 -279.52497)
			(xy 445.907668 -279.52446) (xy 446.423796 -279.52446) (xy 446.431607 -279.524152) (xy 446.446478 -279.519363)
			(xy 446.453006 -279.515062) (xy 446.474095 -279.500713) (xy 446.519756 -279.477982) (xy 446.568362 -279.462523)
			(xy 446.618765 -279.4547) (xy 446.669771 -279.4547) (xy 446.720174 -279.462523) (xy 446.76878 -279.477982)
			(xy 446.814441 -279.500713) (xy 446.83553 -279.515062) (xy 446.842058 -279.51936) (xy 446.856931 -279.524139)
			(xy 446.86474 -279.52446) (xy 447.380868 -279.52446) (xy 447.386119 -279.525013) (xy 447.393562 -279.532419)
			(xy 447.394076 -279.537668) (xy 447.394076 -280.032206) (xy 447.394052 -280.03246) (xy 453.43826 -280.03246)
			(xy 453.43826 -280.031952) (xy 453.43826 -279.537668) (xy 453.43877 -279.532409) (xy 453.446209 -279.52497)
			(xy 453.451468 -279.52446) (xy 453.967596 -279.52446) (xy 453.975407 -279.524152) (xy 453.990278 -279.519363)
			(xy 453.996806 -279.515062) (xy 454.017895 -279.500713) (xy 454.063556 -279.477982) (xy 454.112162 -279.462523)
			(xy 454.162565 -279.4547) (xy 454.213571 -279.4547) (xy 454.263974 -279.462523) (xy 454.31258 -279.477982)
			(xy 454.358241 -279.500713) (xy 454.37933 -279.515062) (xy 454.385858 -279.51936) (xy 454.400731 -279.524139)
			(xy 454.40854 -279.52446) (xy 454.924668 -279.52446) (xy 454.929919 -279.525013) (xy 454.937362 -279.532419)
			(xy 454.937876 -279.537668) (xy 454.937876 -280.032206) (xy 454.937383 -280.037507) (xy 454.929959 -280.045077)
			(xy 454.924668 -280.045668) (xy 454.408794 -280.045668) (xy 454.400982 -280.045968) (xy 454.386111 -280.050762)
			(xy 454.379584 -280.055066) (xy 454.358465 -280.06942) (xy 454.31274 -280.092145) (xy 454.264066 -280.107574)
			(xy 454.213599 -280.115339) (xy 454.188068 -280.115772) (xy 454.162537 -280.11535) (xy 454.112073 -280.10757)
			(xy 454.0634 -280.092136) (xy 454.017673 -280.069415) (xy 453.996552 -280.055066) (xy 453.990027 -280.050764)
			(xy 453.975152 -280.045986) (xy 453.967342 -280.045668) (xy 453.451468 -280.045668) (xy 453.446122 -280.045391)
			(xy 453.43858 -280.037808) (xy 453.43826 -280.03246) (xy 447.394052 -280.03246) (xy 447.393583 -280.037507)
			(xy 447.386159 -280.045077) (xy 447.380868 -280.045668) (xy 446.864994 -280.045668) (xy 446.857182 -280.045968)
			(xy 446.842311 -280.050762) (xy 446.835784 -280.055066) (xy 446.814665 -280.06942) (xy 446.76894 -280.092145)
			(xy 446.720266 -280.107574) (xy 446.669799 -280.115339) (xy 446.644268 -280.115772) (xy 446.618737 -280.11535)
			(xy 446.568273 -280.10757) (xy 446.5196 -280.092136) (xy 446.473873 -280.069415) (xy 446.452752 -280.055066)
			(xy 446.446227 -280.050764) (xy 446.431352 -280.045986) (xy 446.423542 -280.045668) (xy 445.907668 -280.045668)
			(xy 445.902322 -280.045391) (xy 445.89478 -280.037808) (xy 445.89446 -280.03246) (xy 439.850251 -280.03246)
			(xy 439.849755 -280.037567) (xy 439.842175 -280.045152) (xy 439.836814 -280.045668) (xy 439.32094 -280.045668)
			(xy 439.31313 -280.045987) (xy 439.298258 -280.050768) (xy 439.29173 -280.055066) (xy 439.270627 -280.069443)
			(xy 439.224896 -280.092163) (xy 439.176217 -280.107585) (xy 439.125747 -280.115343) (xy 439.100214 -280.115772)
			(xy 439.074684 -280.115327) (xy 439.024221 -280.107554) (xy 438.975548 -280.092127) (xy 438.92982 -280.069412)
			(xy 438.908698 -280.055066) (xy 438.902162 -280.050782) (xy 438.887296 -280.045993) (xy 438.879488 -280.045668)
			(xy 438.363614 -280.045668) (xy 438.358183 -280.045312) (xy 438.350496 -280.037637) (xy 438.350152 -280.032206)
			(xy 432.305968 -280.032206) (xy 432.305482 -280.037509) (xy 432.298053 -280.045079) (xy 432.29276 -280.045668)
			(xy 431.776886 -280.045668) (xy 431.769074 -280.045964) (xy 431.754202 -280.050761) (xy 431.747676 -280.055066)
			(xy 431.72656 -280.069423) (xy 431.680834 -280.092148) (xy 431.632159 -280.107576) (xy 431.581691 -280.11534)
			(xy 431.55616 -280.115772) (xy 431.530629 -280.115354) (xy 431.480164 -280.107572) (xy 431.431492 -280.092138)
			(xy 431.385765 -280.069416) (xy 431.364644 -280.055066) (xy 431.35812 -280.050761) (xy 431.343244 -280.045985)
			(xy 431.335434 -280.045668) (xy 430.81956 -280.045668) (xy 430.814283 -280.045228) (xy 430.80684 -280.03774)
			(xy 430.806352 -280.03246) (xy 424.762144 -280.03246) (xy 424.761654 -280.037569) (xy 424.754069 -280.045154)
			(xy 424.748706 -280.045668) (xy 424.232832 -280.045668) (xy 424.225022 -280.045984) (xy 424.21015 -280.050767)
			(xy 424.203622 -280.055066) (xy 424.182493 -280.069404) (xy 424.136772 -280.092133) (xy 424.088101 -280.107566)
			(xy 424.037636 -280.115336) (xy 424.012106 -280.115772) (xy 423.986576 -280.115331) (xy 423.936112 -280.107556)
			(xy 423.88744 -280.092128) (xy 423.841712 -280.069413) (xy 423.82059 -280.055066) (xy 423.814056 -280.050779)
			(xy 423.799188 -280.045992) (xy 423.79138 -280.045668) (xy 423.275506 -280.045668) (xy 423.270144 -280.045146)
			(xy 423.262558 -280.037567) (xy 423.262044 -280.032206) (xy 417.21786 -280.032206) (xy 417.217381 -280.037511)
			(xy 417.209947 -280.045082) (xy 417.204652 -280.045668) (xy 415.731452 -280.045668) (xy 415.726174 -280.045233)
			(xy 415.718732 -280.037741) (xy 415.718244 -280.03246) (xy 308.118232 -280.03246) (xy 308.117753 -280.037572)
			(xy 308.110161 -280.045158) (xy 308.104794 -280.045668) (xy 306.631594 -280.045668) (xy 306.626231 -280.045154)
			(xy 306.618646 -280.037569) (xy 306.618132 -280.032206) (xy 300.573948 -280.032206) (xy 300.57348 -280.037514)
			(xy 300.566038 -280.045085) (xy 300.56074 -280.045668) (xy 300.044866 -280.045668) (xy 300.037057 -280.045998)
			(xy 300.022185 -280.050772) (xy 300.015656 -280.055066) (xy 299.994545 -280.069432) (xy 299.948817 -280.092155)
			(xy 299.900141 -280.10758) (xy 299.849672 -280.115341) (xy 299.82414 -280.115772) (xy 299.798611 -280.115314)
			(xy 299.748148 -280.107544) (xy 299.699475 -280.092121) (xy 299.653747 -280.069411) (xy 299.632624 -280.055066)
			(xy 299.626083 -280.050792) (xy 299.61122 -280.045997) (xy 299.603414 -280.045668) (xy 299.08754 -280.045668)
			(xy 299.082203 -280.045342) (xy 299.074658 -280.037797) (xy 299.074332 -280.03246) (xy 293.030133 -280.03246)
			(xy 293.029823 -280.037645) (xy 293.022125 -280.045331) (xy 293.016686 -280.045668) (xy 292.500812 -280.045668)
			(xy 292.493001 -280.045975) (xy 292.478129 -280.050765) (xy 292.471602 -280.055066) (xy 292.450478 -280.069412)
			(xy 292.404755 -280.092139) (xy 292.356083 -280.10757) (xy 292.305617 -280.115338) (xy 292.280086 -280.115772)
			(xy 292.254556 -280.115341) (xy 292.204092 -280.107563) (xy 292.155419 -280.092132) (xy 292.109692 -280.069414)
			(xy 292.08857 -280.055066) (xy 292.082041 -280.050771) (xy 292.067169 -280.045989) (xy 292.05936 -280.045668)
			(xy 291.543486 -280.045668) (xy 291.538122 -280.045159) (xy 291.530537 -280.03757) (xy 291.530024 -280.032206)
			(xy 285.48584 -280.032206) (xy 285.485379 -280.037516) (xy 285.477933 -280.045088) (xy 285.472632 -280.045668)
			(xy 284.956758 -280.045668) (xy 284.948949 -280.045995) (xy 284.934077 -280.050771) (xy 284.927548 -280.055066)
			(xy 284.90644 -280.069436) (xy 284.860711 -280.092157) (xy 284.812034 -280.107582) (xy 284.761564 -280.115342)
			(xy 284.736032 -280.115772) (xy 284.710502 -280.115318) (xy 284.660039 -280.107547) (xy 284.611367 -280.092123)
			(xy 284.565639 -280.069411) (xy 284.544516 -280.055066) (xy 284.537976 -280.050788) (xy 284.523113 -280.045996)
			(xy 284.515306 -280.045668) (xy 283.999432 -280.045668) (xy 283.994094 -280.045348) (xy 283.986549 -280.037798)
			(xy 283.986224 -280.03246) (xy 277.942018 -280.03246) (xy 277.941579 -280.037516) (xy 277.934133 -280.045088)
			(xy 277.928832 -280.045668) (xy 277.412958 -280.045668) (xy 277.405149 -280.045995) (xy 277.390277 -280.050771)
			(xy 277.383748 -280.055066) (xy 277.36264 -280.069436) (xy 277.316911 -280.092157) (xy 277.268234 -280.107582)
			(xy 277.217764 -280.115342) (xy 277.192232 -280.115772) (xy 277.166702 -280.115318) (xy 277.116239 -280.107547)
			(xy 277.067567 -280.092123) (xy 277.021839 -280.069411) (xy 277.000716 -280.055066) (xy 276.994176 -280.050788)
			(xy 276.979313 -280.045996) (xy 276.971506 -280.045668) (xy 276.455632 -280.045668) (xy 276.450294 -280.045348)
			(xy 276.442749 -280.037798) (xy 276.442424 -280.03246) (xy 270.398225 -280.03246) (xy 270.397922 -280.037647)
			(xy 270.39022 -280.045334) (xy 270.384778 -280.045668) (xy 269.868904 -280.045668) (xy 269.861093 -280.045972)
			(xy 269.846221 -280.050764) (xy 269.839694 -280.055066) (xy 269.818573 -280.069416) (xy 269.772849 -280.092142)
			(xy 269.724175 -280.107572) (xy 269.673709 -280.115339) (xy 269.648178 -280.115772) (xy 269.622647 -280.115345)
			(xy 269.572183 -280.107566) (xy 269.523511 -280.092134) (xy 269.477784 -280.069415) (xy 269.456662 -280.055066)
			(xy 269.450134 -280.050768) (xy 269.435262 -280.045988) (xy 269.427452 -280.045668) (xy 268.911578 -280.045668)
			(xy 268.906213 -280.045165) (xy 268.898629 -280.037572) (xy 268.898116 -280.032206) (xy 206.997808 -280.032206)
			(xy 206.997808 -280.03246) (xy 206.997446 -280.037787) (xy 206.989926 -280.04533) (xy 206.9846 -280.045668)
			(xy 206.468726 -280.045668) (xy 206.460849 -280.045928) (xy 206.445845 -280.05073) (xy 206.439262 -280.055066)
			(xy 206.418187 -280.069461) (xy 206.372541 -280.092288) (xy 206.323934 -280.107845) (xy 206.273517 -280.115763)
			(xy 206.248 -280.11628) (xy 206.222479 -280.115811) (xy 206.172051 -280.107911) (xy 206.123439 -280.092345)
			(xy 206.077802 -280.069484) (xy 206.056738 -280.055066) (xy 206.050136 -280.050769) (xy 206.035144 -280.04597)
			(xy 206.027274 -280.045668) (xy 205.5114 -280.045668) (xy 205.506058 -280.045369) (xy 205.498515 -280.037803)
			(xy 205.498192 -280.03246) (xy 199.454008 -280.03246) (xy 199.453646 -280.037787) (xy 199.446126 -280.04533)
			(xy 199.4408 -280.045668) (xy 198.924926 -280.045668) (xy 198.917049 -280.045928) (xy 198.902045 -280.05073)
			(xy 198.895462 -280.055066) (xy 198.874387 -280.069461) (xy 198.828741 -280.092288) (xy 198.780134 -280.107845)
			(xy 198.729717 -280.115763) (xy 198.7042 -280.11628) (xy 198.678679 -280.115811) (xy 198.628251 -280.107911)
			(xy 198.579639 -280.092345) (xy 198.534002 -280.069484) (xy 198.512938 -280.055066) (xy 198.506336 -280.050769)
			(xy 198.491344 -280.04597) (xy 198.483474 -280.045668) (xy 197.9676 -280.045668) (xy 197.962258 -280.045369)
			(xy 197.954715 -280.037803) (xy 197.954392 -280.03246) (xy 191.910208 -280.03246) (xy 191.909846 -280.037787)
			(xy 191.902326 -280.04533) (xy 191.897 -280.045668) (xy 191.896492 -280.045668) (xy 191.380872 -280.045668)
			(xy 191.372997 -280.045948) (xy 191.357993 -280.050737) (xy 191.351408 -280.055066) (xy 191.330348 -280.069484)
			(xy 191.284697 -280.092306) (xy 191.236085 -280.107856) (xy 191.185664 -280.115767) (xy 191.160146 -280.11628)
			(xy 191.134626 -280.115788) (xy 191.084199 -280.107895) (xy 191.035587 -280.092336) (xy 190.989949 -280.069481)
			(xy 190.968884 -280.055066) (xy 190.962294 -280.050748) (xy 190.947293 -280.045962) (xy 190.93942 -280.045668)
			(xy 190.423546 -280.045668) (xy 190.418249 -280.045147) (xy 190.410676 -280.037745) (xy 190.410084 -280.03246)
			(xy 184.3659 -280.03246) (xy 184.365545 -280.037789) (xy 184.35802 -280.045332) (xy 184.352692 -280.045668)
			(xy 183.836818 -280.045668) (xy 183.828944 -280.045968) (xy 183.81394 -280.050743) (xy 183.807354 -280.055066)
			(xy 183.786281 -280.069465) (xy 183.740634 -280.092291) (xy 183.692027 -280.107847) (xy 183.641609 -280.115764)
			(xy 183.616092 -280.11628) (xy 183.590573 -280.115765) (xy 183.540147 -280.107879) (xy 183.491535 -280.092326)
			(xy 183.445896 -280.069478) (xy 183.42483 -280.055066) (xy 183.41823 -280.050766) (xy 183.403237 -280.045969)
			(xy 183.395366 -280.045668) (xy 182.879492 -280.045668) (xy 182.874149 -280.045375) (xy 182.866606 -280.037804)
			(xy 182.866284 -280.03246) (xy 176.8221 -280.03246) (xy 176.821745 -280.037789) (xy 176.81422 -280.045332)
			(xy 176.808892 -280.045668) (xy 176.808384 -280.045668) (xy 176.292764 -280.045668) (xy 176.284888 -280.045945)
			(xy 176.269884 -280.050736) (xy 176.2633 -280.055066) (xy 176.242214 -280.069445) (xy 176.196572 -280.092276)
			(xy 176.147969 -280.107837) (xy 176.097554 -280.11576) (xy 176.072038 -280.11628) (xy 176.046518 -280.115792)
			(xy 175.996091 -280.107898) (xy 175.947479 -280.092337) (xy 175.901841 -280.069482) (xy 175.880776 -280.055066)
			(xy 175.874188 -280.050745) (xy 175.859185 -280.045961) (xy 175.851312 -280.045668) (xy 175.335438 -280.045668)
			(xy 175.33014 -280.045152) (xy 175.322568 -280.037746) (xy 175.321976 -280.03246) (xy 169.277792 -280.03246)
			(xy 169.277445 -280.037791) (xy 169.269914 -280.045335) (xy 169.264584 -280.045668) (xy 167.791384 -280.045668)
			(xy 167.78604 -280.04538) (xy 167.778497 -280.037806) (xy 167.778176 -280.03246) (xy 60.178188 -280.03246)
			(xy 60.177844 -280.037792) (xy 60.170311 -280.045336) (xy 60.16498 -280.045668) (xy 60.164472 -280.045668)
			(xy 58.691526 -280.045668) (xy 58.686227 -280.04516) (xy 58.678655 -280.037748) (xy 58.678064 -280.03246)
			(xy 52.63388 -280.03246) (xy 52.633543 -280.037794) (xy 52.626005 -280.045339) (xy 52.620672 -280.045668)
			(xy 52.104798 -280.045668) (xy 52.096924 -280.045959) (xy 52.08192 -280.05074) (xy 52.075334 -280.055066)
			(xy 52.054267 -280.069473) (xy 52.008618 -280.092297) (xy 51.960009 -280.107851) (xy 51.90959 -280.115765)
			(xy 51.884072 -280.11628) (xy 51.858552 -280.115775) (xy 51.808126 -280.107886) (xy 51.759514 -280.09233)
			(xy 51.713875 -280.069479) (xy 51.69281 -280.055066) (xy 51.686214 -280.050758) (xy 51.671218 -280.045966)
			(xy 51.663346 -280.045668) (xy 51.147472 -280.045668) (xy 51.142126 -280.045388) (xy 51.134584 -280.037808)
			(xy 51.134264 -280.03246) (xy 45.09008 -280.03246) (xy 45.089743 -280.037794) (xy 45.082205 -280.045339)
			(xy 45.076872 -280.045668) (xy 45.076364 -280.045668) (xy 44.560744 -280.045668) (xy 44.552868 -280.045936)
			(xy 44.537864 -280.050733) (xy 44.53128 -280.055066) (xy 44.5102 -280.069453) (xy 44.464556 -280.092282)
			(xy 44.415951 -280.107841) (xy 44.365534 -280.115762) (xy 44.340018 -280.11628) (xy 44.314497 -280.115802)
			(xy 44.26407 -280.107905) (xy 44.215458 -280.092341) (xy 44.16982 -280.069483) (xy 44.148756 -280.055066)
			(xy 44.142172 -280.050737) (xy 44.127166 -280.045958) (xy 44.119292 -280.045668) (xy 43.603418 -280.045668)
			(xy 43.598118 -280.045166) (xy 43.590546 -280.037749) (xy 43.589956 -280.03246) (xy 37.545772 -280.03246)
			(xy 37.545443 -280.037796) (xy 37.537899 -280.045341) (xy 37.532564 -280.045668) (xy 37.01669 -280.045668)
			(xy 37.008815 -280.045956) (xy 36.993811 -280.050739) (xy 36.987226 -280.055066) (xy 36.966161 -280.069477)
			(xy 36.920511 -280.0923) (xy 36.871902 -280.107853) (xy 36.821482 -280.115766) (xy 36.795964 -280.11628)
			(xy 36.770444 -280.115779) (xy 36.720018 -280.107888) (xy 36.671406 -280.092332) (xy 36.625767 -280.06948)
			(xy 36.604702 -280.055066) (xy 36.598108 -280.050755) (xy 36.58311 -280.045965) (xy 36.575238 -280.045668)
			(xy 36.059364 -280.045668) (xy 36.054017 -280.045393) (xy 36.046476 -280.037809) (xy 36.046156 -280.03246)
			(xy 30.001972 -280.03246) (xy 30.001643 -280.037796) (xy 29.994099 -280.045341) (xy 29.988764 -280.045668)
			(xy 29.47289 -280.045668) (xy 29.465015 -280.045956) (xy 29.450011 -280.050739) (xy 29.443426 -280.055066)
			(xy 29.422361 -280.069477) (xy 29.376711 -280.0923) (xy 29.328102 -280.107853) (xy 29.277682 -280.115766)
			(xy 29.252164 -280.11628) (xy 29.226644 -280.115779) (xy 29.176218 -280.107888) (xy 29.127606 -280.092332)
			(xy 29.081967 -280.06948) (xy 29.060902 -280.055066) (xy 29.054308 -280.050755) (xy 29.03931 -280.045965)
			(xy 29.031438 -280.045668) (xy 28.515564 -280.045668) (xy 28.510217 -280.045393) (xy 28.502676 -280.037809)
			(xy 28.502356 -280.03246) (xy 22.458172 -280.03246) (xy 22.457843 -280.037796) (xy 22.450299 -280.045341)
			(xy 22.444964 -280.045668) (xy 22.444456 -280.045668) (xy 21.928836 -280.045668) (xy 21.920959 -280.045933)
			(xy 21.905955 -280.050732) (xy 21.899372 -280.055066) (xy 21.878294 -280.069457) (xy 21.832649 -280.092285)
			(xy 21.784043 -280.107843) (xy 21.733627 -280.115762) (xy 21.70811 -280.11628) (xy 21.682589 -280.115806)
			(xy 21.632161 -280.107907) (xy 21.58355 -280.092343) (xy 21.537912 -280.069483) (xy 21.516848 -280.055066)
			(xy 21.510266 -280.050734) (xy 21.495259 -280.045957) (xy 21.487384 -280.045668) (xy 20.97151 -280.045668)
			(xy 20.966209 -280.045171) (xy 20.958637 -280.03775) (xy 20.958048 -280.03246) (xy 2.509012 -280.03246)
			(xy 2.509012 -280.882344) (xy 16.85798 -280.882344) (xy 16.85798 -280.387806) (xy 16.858287 -280.382362)
			(xy 16.865997 -280.374673) (xy 16.871442 -280.374344) (xy 17.38757 -280.374344) (xy 17.39538 -280.374027)
			(xy 17.410252 -280.369244) (xy 17.41678 -280.364946) (xy 17.437869 -280.350597) (xy 17.48353 -280.327866)
			(xy 17.532136 -280.312407) (xy 17.582539 -280.304584) (xy 17.633545 -280.304584) (xy 17.683948 -280.312407)
			(xy 17.732554 -280.327866) (xy 17.778215 -280.350597) (xy 17.799304 -280.364946) (xy 17.805839 -280.369232)
			(xy 17.820706 -280.374019) (xy 17.828514 -280.374344) (xy 18.344642 -280.374344) (xy 18.350013 -280.374823)
			(xy 18.357596 -280.382434) (xy 18.358104 -280.387806) (xy 18.358104 -280.882344) (xy 24.402288 -280.882344)
			(xy 24.402288 -280.387806) (xy 24.402733 -280.382491) (xy 24.41019 -280.374917) (xy 24.415496 -280.374344)
			(xy 24.931624 -280.374344) (xy 24.939436 -280.37405) (xy 24.954308 -280.369252) (xy 24.960834 -280.364946)
			(xy 24.981923 -280.350597) (xy 25.027584 -280.327866) (xy 25.07619 -280.312407) (xy 25.126593 -280.304584)
			(xy 25.177599 -280.304584) (xy 25.228002 -280.312407) (xy 25.276608 -280.327866) (xy 25.322269 -280.350597)
			(xy 25.343358 -280.364946) (xy 25.349881 -280.369253) (xy 25.364757 -280.374027) (xy 25.372568 -280.374344)
			(xy 25.888696 -280.374344) (xy 25.893947 -280.374892) (xy 25.901387 -280.382303) (xy 25.901904 -280.387552)
			(xy 25.901904 -280.38806) (xy 25.901904 -280.882344) (xy 31.946088 -280.882344) (xy 31.946088 -280.387806)
			(xy 31.946533 -280.382491) (xy 31.95399 -280.374917) (xy 31.959296 -280.374344) (xy 32.475424 -280.374344)
			(xy 32.483236 -280.37405) (xy 32.498108 -280.369252) (xy 32.504634 -280.364946) (xy 32.525723 -280.350597)
			(xy 32.571384 -280.327866) (xy 32.61999 -280.312407) (xy 32.670393 -280.304584) (xy 32.721399 -280.304584)
			(xy 32.771802 -280.312407) (xy 32.820408 -280.327866) (xy 32.866069 -280.350597) (xy 32.887158 -280.364946)
			(xy 32.893681 -280.369253) (xy 32.908557 -280.374027) (xy 32.916368 -280.374344) (xy 33.432496 -280.374344)
			(xy 33.437747 -280.374892) (xy 33.445187 -280.382303) (xy 33.445704 -280.387552) (xy 33.445704 -280.38806)
			(xy 33.445704 -280.882344) (xy 39.489888 -280.882344) (xy 39.489888 -280.387806) (xy 39.490449 -280.382455)
			(xy 39.498001 -280.374871) (xy 39.50335 -280.374344) (xy 40.019478 -280.374344) (xy 40.027288 -280.37403)
			(xy 40.04216 -280.369245) (xy 40.048688 -280.364946) (xy 40.069777 -280.350597) (xy 40.115438 -280.327866)
			(xy 40.164044 -280.312407) (xy 40.214447 -280.304584) (xy 40.265453 -280.304584) (xy 40.315856 -280.312407)
			(xy 40.364462 -280.327866) (xy 40.410123 -280.350597) (xy 40.431212 -280.364946) (xy 40.437745 -280.369235)
			(xy 40.452614 -280.37402) (xy 40.460422 -280.374344) (xy 40.97655 -280.374344) (xy 40.981921 -280.374818)
			(xy 40.989504 -280.382433) (xy 40.990012 -280.387806) (xy 40.990012 -280.882344) (xy 47.034196 -280.882344)
			(xy 47.034196 -280.387806) (xy 47.034722 -280.382513) (xy 47.042123 -280.374944) (xy 47.047404 -280.374344)
			(xy 47.563532 -280.374344) (xy 47.57134 -280.374011) (xy 47.586212 -280.369239) (xy 47.592742 -280.364946)
			(xy 47.613831 -280.350597) (xy 47.659492 -280.327866) (xy 47.708098 -280.312407) (xy 47.758501 -280.304584)
			(xy 47.809507 -280.304584) (xy 47.85991 -280.312407) (xy 47.908516 -280.327866) (xy 47.954177 -280.350597)
			(xy 47.975266 -280.364946) (xy 47.981809 -280.369218) (xy 47.99667 -280.374014) (xy 48.004476 -280.374344)
			(xy 48.520604 -280.374344) (xy 48.525856 -280.374887) (xy 48.533295 -280.382302) (xy 48.533812 -280.387552)
			(xy 48.533812 -280.38806) (xy 48.533812 -280.882344) (xy 54.577996 -280.882344) (xy 54.577996 -280.387806)
			(xy 54.57855 -280.382453) (xy 54.586107 -280.374869) (xy 54.591458 -280.374344) (xy 56.064658 -280.374344)
			(xy 56.070089 -280.374708) (xy 56.077777 -280.382376) (xy 56.07812 -280.387806) (xy 56.07812 -280.882344)
			(xy 163.678108 -280.882344) (xy 163.678108 -280.387806) (xy 163.678623 -280.38251) (xy 163.686032 -280.37494)
			(xy 163.691316 -280.374344) (xy 165.164516 -280.374344) (xy 165.169769 -280.374879) (xy 165.177208 -280.3823)
			(xy 165.177724 -280.387552) (xy 165.177724 -280.38806) (xy 165.177724 -280.882344) (xy 171.221908 -280.882344)
			(xy 171.221908 -280.387806) (xy 171.222451 -280.38245) (xy 171.230015 -280.374866) (xy 171.23537 -280.374344)
			(xy 171.751498 -280.374344) (xy 171.759309 -280.374039) (xy 171.774181 -280.369248) (xy 171.780708 -280.364946)
			(xy 171.801797 -280.350597) (xy 171.847458 -280.327866) (xy 171.896064 -280.312407) (xy 171.946467 -280.304584)
			(xy 171.997473 -280.304584) (xy 172.047876 -280.312407) (xy 172.096482 -280.327866) (xy 172.142143 -280.350597)
			(xy 172.163232 -280.364946) (xy 172.16976 -280.369243) (xy 172.184633 -280.374023) (xy 172.192442 -280.374344)
			(xy 172.70857 -280.374344) (xy 172.714002 -280.3747) (xy 172.72169 -280.382374) (xy 172.722032 -280.387806)
			(xy 172.722032 -280.882344) (xy 178.766216 -280.882344) (xy 178.766216 -280.387806) (xy 178.766724 -280.382508)
			(xy 178.774137 -280.374938) (xy 178.779424 -280.374344) (xy 179.295552 -280.374344) (xy 179.303361 -280.374019)
			(xy 179.318233 -280.369242) (xy 179.324762 -280.364946) (xy 179.345851 -280.350597) (xy 179.391512 -280.327866)
			(xy 179.440118 -280.312407) (xy 179.490521 -280.304584) (xy 179.541527 -280.304584) (xy 179.59193 -280.312407)
			(xy 179.640536 -280.327866) (xy 179.686197 -280.350597) (xy 179.707286 -280.364946) (xy 179.713825 -280.369225)
			(xy 179.728689 -280.374017) (xy 179.736496 -280.374344) (xy 180.252624 -280.374344) (xy 180.257878 -280.374874)
			(xy 180.265316 -280.382299) (xy 180.265832 -280.387552) (xy 180.265832 -280.38806) (xy 180.265832 -280.882344)
			(xy 186.310016 -280.882344) (xy 186.310016 -280.387806) (xy 186.310552 -280.382448) (xy 186.318121 -280.374863)
			(xy 186.323478 -280.374344) (xy 186.839606 -280.374344) (xy 186.847417 -280.374042) (xy 186.862289 -280.369249)
			(xy 186.868816 -280.364946) (xy 186.889905 -280.350597) (xy 186.935566 -280.327866) (xy 186.984172 -280.312407)
			(xy 187.034575 -280.304584) (xy 187.085581 -280.304584) (xy 187.135984 -280.312407) (xy 187.18459 -280.327866)
			(xy 187.230251 -280.350597) (xy 187.25134 -280.364946) (xy 187.257867 -280.369246) (xy 187.27274 -280.374025)
			(xy 187.28055 -280.374344) (xy 187.796678 -280.374344) (xy 187.802111 -280.374695) (xy 187.809799 -280.382373)
			(xy 187.81014 -280.387806) (xy 187.81014 -280.882344) (xy 193.854324 -280.882344) (xy 193.854324 -280.387806)
			(xy 193.854825 -280.382506) (xy 193.862243 -280.374936) (xy 193.867532 -280.374344) (xy 194.38366 -280.374344)
			(xy 194.39147 -280.374023) (xy 194.406341 -280.369243) (xy 194.41287 -280.364946) (xy 194.433959 -280.350597)
			(xy 194.47962 -280.327866) (xy 194.528226 -280.312407) (xy 194.578629 -280.304584) (xy 194.629635 -280.304584)
			(xy 194.680038 -280.312407) (xy 194.728644 -280.327866) (xy 194.774305 -280.350597) (xy 194.795394 -280.364946)
			(xy 194.801931 -280.369228) (xy 194.816797 -280.374018) (xy 194.824604 -280.374344) (xy 195.340732 -280.374344)
			(xy 195.345987 -280.374869) (xy 195.353425 -280.382298) (xy 195.35394 -280.387552) (xy 195.35394 -280.38806)
			(xy 195.35394 -280.882344) (xy 201.398124 -280.882344) (xy 201.398124 -280.387806) (xy 201.398625 -280.382506)
			(xy 201.406043 -280.374936) (xy 201.411332 -280.374344) (xy 201.92746 -280.374344) (xy 201.93527 -280.374023)
			(xy 201.950141 -280.369243) (xy 201.95667 -280.364946) (xy 201.977759 -280.350597) (xy 202.02342 -280.327866)
			(xy 202.072026 -280.312407) (xy 202.122429 -280.304584) (xy 202.173435 -280.304584) (xy 202.223838 -280.312407)
			(xy 202.272444 -280.327866) (xy 202.318105 -280.350597) (xy 202.339194 -280.364946) (xy 202.345731 -280.369228)
			(xy 202.360597 -280.374018) (xy 202.368404 -280.374344) (xy 202.884532 -280.374344) (xy 202.889787 -280.374869)
			(xy 202.897225 -280.382298) (xy 202.89774 -280.387552) (xy 202.89774 -280.38806) (xy 202.89774 -280.88209)
			(xy 264.798048 -280.88209) (xy 264.798048 -280.387552) (xy 264.798559 -280.382294) (xy 264.805998 -280.374857)
			(xy 264.811256 -280.374344) (xy 264.811764 -280.374344) (xy 265.327638 -280.374344) (xy 265.335447 -280.374013)
			(xy 265.350319 -280.36924) (xy 265.356848 -280.364946) (xy 265.377937 -280.350597) (xy 265.423598 -280.327866)
			(xy 265.472204 -280.312407) (xy 265.522607 -280.304584) (xy 265.573613 -280.304584) (xy 265.624016 -280.312407)
			(xy 265.672622 -280.327866) (xy 265.718283 -280.350597) (xy 265.739372 -280.364946) (xy 265.745914 -280.36922)
			(xy 265.760776 -280.374015) (xy 265.768582 -280.374344) (xy 266.28471 -280.374344) (xy 266.290016 -280.374817)
			(xy 266.297587 -280.382255) (xy 266.298172 -280.387552) (xy 266.298172 -280.88209) (xy 266.298147 -280.882344)
			(xy 272.342356 -280.882344) (xy 272.342356 -280.881836) (xy 272.342356 -280.387552) (xy 272.342859 -280.382292)
			(xy 272.350304 -280.374855) (xy 272.355564 -280.374344) (xy 272.871692 -280.374344) (xy 272.879503 -280.374036)
			(xy 272.894374 -280.369247) (xy 272.900902 -280.364946) (xy 272.921991 -280.350597) (xy 272.967652 -280.327866)
			(xy 273.016258 -280.312407) (xy 273.066661 -280.304584) (xy 273.117667 -280.304584) (xy 273.16807 -280.312407)
			(xy 273.216676 -280.327866) (xy 273.262337 -280.350597) (xy 273.283426 -280.364946) (xy 273.289956 -280.369241)
			(xy 273.304827 -280.374023) (xy 273.312636 -280.374344) (xy 273.828764 -280.374344) (xy 273.834011 -280.374914)
			(xy 273.841453 -280.382308) (xy 273.841972 -280.387552) (xy 273.841972 -280.88209) (xy 273.841948 -280.882344)
			(xy 279.886156 -280.882344) (xy 279.886156 -280.881836) (xy 279.886156 -280.387552) (xy 279.886659 -280.382292)
			(xy 279.894104 -280.374855) (xy 279.899364 -280.374344) (xy 280.415492 -280.374344) (xy 280.423303 -280.374036)
			(xy 280.438174 -280.369247) (xy 280.444702 -280.364946) (xy 280.465791 -280.350597) (xy 280.511452 -280.327866)
			(xy 280.560058 -280.312407) (xy 280.610461 -280.304584) (xy 280.661467 -280.304584) (xy 280.71187 -280.312407)
			(xy 280.760476 -280.327866) (xy 280.806137 -280.350597) (xy 280.827226 -280.364946) (xy 280.833756 -280.369241)
			(xy 280.848627 -280.374023) (xy 280.856436 -280.374344) (xy 281.372564 -280.374344) (xy 281.377811 -280.374914)
			(xy 281.385253 -280.382308) (xy 281.385772 -280.387552) (xy 281.385772 -280.88209) (xy 287.429956 -280.88209)
			(xy 287.429956 -280.387552) (xy 287.430459 -280.382292) (xy 287.437904 -280.374855) (xy 287.443164 -280.374344)
			(xy 287.443672 -280.374344) (xy 287.959546 -280.374344) (xy 287.967355 -280.374017) (xy 287.982227 -280.369241)
			(xy 287.988756 -280.364946) (xy 288.009845 -280.350597) (xy 288.055506 -280.327866) (xy 288.104112 -280.312407)
			(xy 288.154515 -280.304584) (xy 288.205521 -280.304584) (xy 288.255924 -280.312407) (xy 288.30453 -280.327866)
			(xy 288.350191 -280.350597) (xy 288.37128 -280.364946) (xy 288.37782 -280.369223) (xy 288.392683 -280.374016)
			(xy 288.40049 -280.374344) (xy 288.916618 -280.374344) (xy 288.921925 -280.374812) (xy 288.929496 -280.382254)
			(xy 288.93008 -280.387552) (xy 288.93008 -280.88209) (xy 288.930055 -280.882344) (xy 294.974264 -280.882344)
			(xy 294.974264 -280.881836) (xy 294.974264 -280.387552) (xy 294.97476 -280.38229) (xy 294.98221 -280.374852)
			(xy 294.987472 -280.374344) (xy 295.5036 -280.374344) (xy 295.511411 -280.37404) (xy 295.526283 -280.369248)
			(xy 295.53281 -280.364946) (xy 295.553899 -280.350597) (xy 295.59956 -280.327866) (xy 295.648166 -280.312407)
			(xy 295.698569 -280.304584) (xy 295.749575 -280.304584) (xy 295.799978 -280.312407) (xy 295.848584 -280.327866)
			(xy 295.894245 -280.350597) (xy 295.915334 -280.364946) (xy 295.921862 -280.369244) (xy 295.936735 -280.374024)
			(xy 295.944544 -280.374344) (xy 296.460672 -280.374344) (xy 296.46592 -280.374908) (xy 296.473361 -280.382307)
			(xy 296.47388 -280.387552) (xy 296.47388 -280.88209) (xy 302.518064 -280.88209) (xy 302.518064 -280.387552)
			(xy 302.51856 -280.38229) (xy 302.52601 -280.374852) (xy 302.531272 -280.374344) (xy 304.004726 -280.374344)
			(xy 304.010034 -280.374807) (xy 304.017604 -280.382253) (xy 304.018188 -280.387552) (xy 304.018188 -280.88209)
			(xy 304.018162 -280.882344) (xy 411.618176 -280.882344) (xy 411.618176 -280.881836) (xy 411.618176 -280.387552)
			(xy 411.618661 -280.382287) (xy 411.626118 -280.374849) (xy 411.631384 -280.374344) (xy 413.104584 -280.374344)
			(xy 413.109833 -280.3749) (xy 413.117274 -280.382305) (xy 413.117792 -280.387552) (xy 413.117792 -280.88209)
			(xy 419.161976 -280.88209) (xy 419.161976 -280.387552) (xy 419.162461 -280.382287) (xy 419.169918 -280.374849)
			(xy 419.175184 -280.374344) (xy 419.175692 -280.374344) (xy 419.691566 -280.374344) (xy 419.699376 -280.374025)
			(xy 419.714248 -280.369244) (xy 419.720776 -280.364946) (xy 419.741865 -280.350597) (xy 419.787526 -280.327866)
			(xy 419.836132 -280.312407) (xy 419.886535 -280.304584) (xy 419.937541 -280.304584) (xy 419.987944 -280.312407)
			(xy 420.03655 -280.327866) (xy 420.082211 -280.350597) (xy 420.1033 -280.364946) (xy 420.109835 -280.369231)
			(xy 420.124702 -280.374019) (xy 420.13251 -280.374344) (xy 420.648638 -280.374344) (xy 420.653948 -280.374799)
			(xy 420.661517 -280.382251) (xy 420.6621 -280.387552) (xy 420.6621 -280.88209) (xy 420.662074 -280.882344)
			(xy 426.706284 -280.882344) (xy 426.706284 -280.881836) (xy 426.706284 -280.387552) (xy 426.706762 -280.382285)
			(xy 426.714224 -280.374846) (xy 426.719492 -280.374344) (xy 427.23562 -280.374344) (xy 427.243432 -280.374048)
			(xy 427.258304 -280.369251) (xy 427.26483 -280.364946) (xy 427.285919 -280.350597) (xy 427.33158 -280.327866)
			(xy 427.380186 -280.312407) (xy 427.430589 -280.304584) (xy 427.481595 -280.304584) (xy 427.531998 -280.312407)
			(xy 427.580604 -280.327866) (xy 427.626265 -280.350597) (xy 427.647354 -280.364946) (xy 427.653877 -280.369251)
			(xy 427.668754 -280.374027) (xy 427.676564 -280.374344) (xy 428.192692 -280.374344) (xy 428.197942 -280.374895)
			(xy 428.205383 -280.382304) (xy 428.2059 -280.387552) (xy 428.2059 -280.88209) (xy 434.250084 -280.88209)
			(xy 434.250084 -280.387552) (xy 434.250562 -280.382285) (xy 434.258024 -280.374846) (xy 434.263292 -280.374344)
			(xy 434.2638 -280.374344) (xy 434.779674 -280.374344) (xy 434.787484 -280.374029) (xy 434.802356 -280.369245)
			(xy 434.808884 -280.364946) (xy 434.829973 -280.350597) (xy 434.875634 -280.327866) (xy 434.92424 -280.312407)
			(xy 434.974643 -280.304584) (xy 435.025649 -280.304584) (xy 435.076052 -280.312407) (xy 435.124658 -280.327866)
			(xy 435.170319 -280.350597) (xy 435.191408 -280.364946) (xy 435.197942 -280.369234) (xy 435.21281 -280.37402)
			(xy 435.220618 -280.374344) (xy 435.736746 -280.374344) (xy 435.742045 -280.37486) (xy 435.749619 -280.382265)
			(xy 435.750208 -280.387552) (xy 435.750208 -280.88209) (xy 435.750181 -280.882344) (xy 441.794392 -280.882344)
			(xy 441.794392 -280.881836) (xy 441.794392 -280.387552) (xy 441.794863 -280.382283) (xy 441.80233 -280.374844)
			(xy 441.8076 -280.374344) (xy 442.323728 -280.374344) (xy 442.33154 -280.374052) (xy 442.346412 -280.369252)
			(xy 442.352938 -280.364946) (xy 442.374027 -280.350597) (xy 442.419688 -280.327866) (xy 442.468294 -280.312407)
			(xy 442.518697 -280.304584) (xy 442.569703 -280.304584) (xy 442.620106 -280.312407) (xy 442.668712 -280.327866)
			(xy 442.714373 -280.350597) (xy 442.735462 -280.364946) (xy 442.742006 -280.369216) (xy 442.756866 -280.374013)
			(xy 442.764672 -280.374344) (xy 443.2808 -280.374344) (xy 443.286051 -280.37489) (xy 443.293491 -280.382303)
			(xy 443.294008 -280.387552) (xy 443.294008 -280.88209) (xy 443.293982 -280.882344) (xy 449.338192 -280.882344)
			(xy 449.338192 -280.881836) (xy 449.338192 -280.387552) (xy 449.338663 -280.382283) (xy 449.34613 -280.374844)
			(xy 449.3514 -280.374344) (xy 449.867528 -280.374344) (xy 449.87534 -280.374052) (xy 449.890212 -280.369252)
			(xy 449.896738 -280.364946) (xy 449.917827 -280.350597) (xy 449.963488 -280.327866) (xy 450.012094 -280.312407)
			(xy 450.062497 -280.304584) (xy 450.113503 -280.304584) (xy 450.163906 -280.312407) (xy 450.212512 -280.327866)
			(xy 450.258173 -280.350597) (xy 450.279262 -280.364946) (xy 450.285806 -280.369216) (xy 450.300666 -280.374013)
			(xy 450.308472 -280.374344) (xy 450.8246 -280.374344) (xy 450.829851 -280.37489) (xy 450.837291 -280.382303)
			(xy 450.837808 -280.387552) (xy 450.837808 -280.88209) (xy 450.837276 -280.887382) (xy 450.829879 -280.894951)
			(xy 450.8246 -280.895552) (xy 450.308726 -280.895552) (xy 450.300916 -280.895868) (xy 450.286044 -280.900652)
			(xy 450.279516 -280.90495) (xy 450.258387 -280.919288) (xy 450.212666 -280.942018) (xy 450.163995 -280.957451)
			(xy 450.11353 -280.965221) (xy 450.088 -280.965656) (xy 450.06247 -280.965221) (xy 450.012006 -280.957445)
			(xy 449.963333 -280.942015) (xy 449.917606 -280.919298) (xy 449.896484 -280.90495) (xy 449.889952 -280.900659)
			(xy 449.875083 -280.895875) (xy 449.867274 -280.895552) (xy 449.3514 -280.895552) (xy 449.346148 -280.89501)
			(xy 449.338708 -280.887594) (xy 449.338192 -280.882344) (xy 443.293982 -280.882344) (xy 443.293476 -280.887382)
			(xy 443.286079 -280.894951) (xy 443.2808 -280.895552) (xy 442.764926 -280.895552) (xy 442.757116 -280.895868)
			(xy 442.742244 -280.900652) (xy 442.735716 -280.90495) (xy 442.714587 -280.919288) (xy 442.668866 -280.942018)
			(xy 442.620195 -280.957451) (xy 442.56973 -280.965221) (xy 442.5442 -280.965656) (xy 442.51867 -280.965221)
			(xy 442.468206 -280.957445) (xy 442.419533 -280.942015) (xy 442.373806 -280.919298) (xy 442.352684 -280.90495)
			(xy 442.346152 -280.900659) (xy 442.331283 -280.895875) (xy 442.323474 -280.895552) (xy 441.8076 -280.895552)
			(xy 441.802348 -280.89501) (xy 441.794908 -280.887594) (xy 441.794392 -280.882344) (xy 435.750181 -280.882344)
			(xy 435.749647 -280.887442) (xy 435.742095 -280.895025) (xy 435.736746 -280.895552) (xy 435.220872 -280.895552)
			(xy 435.21306 -280.895845) (xy 435.198188 -280.900644) (xy 435.191662 -280.90495) (xy 435.170548 -280.919312)
			(xy 435.124822 -280.942036) (xy 435.076146 -280.957462) (xy 435.025678 -280.965225) (xy 435.000146 -280.965656)
			(xy 434.974617 -280.965198) (xy 434.924154 -280.957429) (xy 434.875481 -280.942006) (xy 434.829753 -280.919295)
			(xy 434.80863 -280.90495) (xy 434.802088 -280.900676) (xy 434.787226 -280.895882) (xy 434.77942 -280.895552)
			(xy 434.263546 -280.895552) (xy 434.258115 -280.895189) (xy 434.250425 -280.88752) (xy 434.250084 -280.88209)
			(xy 428.2059 -280.88209) (xy 428.205375 -280.887384) (xy 428.197974 -280.894953) (xy 428.192692 -280.895552)
			(xy 427.676818 -280.895552) (xy 427.669008 -280.895865) (xy 427.654136 -280.900651) (xy 427.647608 -280.90495)
			(xy 427.626482 -280.919292) (xy 427.580759 -280.94202) (xy 427.532088 -280.957452) (xy 427.481623 -280.965221)
			(xy 427.456092 -280.965656) (xy 427.430562 -280.965225) (xy 427.380097 -280.957448) (xy 427.331425 -280.942017)
			(xy 427.285698 -280.919298) (xy 427.264576 -280.90495) (xy 427.258046 -280.900656) (xy 427.243175 -280.895874)
			(xy 427.235366 -280.895552) (xy 426.719492 -280.895552) (xy 426.714239 -280.895015) (xy 426.706799 -280.887596)
			(xy 426.706284 -280.882344) (xy 420.662074 -280.882344) (xy 420.661547 -280.887444) (xy 420.65399 -280.895028)
			(xy 420.648638 -280.895552) (xy 420.132764 -280.895552) (xy 420.124955 -280.895884) (xy 420.110084 -280.900657)
			(xy 420.103554 -280.90495) (xy 420.082443 -280.919315) (xy 420.036715 -280.942038) (xy 419.988039 -280.957464)
			(xy 419.93757 -280.965226) (xy 419.912038 -280.965656) (xy 419.886508 -280.965202) (xy 419.836045 -280.957432)
			(xy 419.787373 -280.942008) (xy 419.741644 -280.919295) (xy 419.720522 -280.90495) (xy 419.713982 -280.900673)
			(xy 419.699119 -280.89588) (xy 419.691312 -280.895552) (xy 419.175438 -280.895552) (xy 419.170006 -280.895194)
			(xy 419.162317 -280.887521) (xy 419.161976 -280.88209) (xy 413.117792 -280.88209) (xy 413.117274 -280.887386)
			(xy 413.109868 -280.894956) (xy 413.104584 -280.895552) (xy 411.631384 -280.895552) (xy 411.62613 -280.895021)
			(xy 411.618691 -280.887597) (xy 411.618176 -280.882344) (xy 304.018162 -280.882344) (xy 304.017645 -280.887446)
			(xy 304.010081 -280.895031) (xy 304.004726 -280.895552) (xy 302.531526 -280.895552) (xy 302.526092 -280.895202)
			(xy 302.518404 -280.887523) (xy 302.518064 -280.88209) (xy 296.47388 -280.88209) (xy 296.473373 -280.887388)
			(xy 296.465959 -280.894959) (xy 296.460672 -280.895552) (xy 295.944798 -280.895552) (xy 295.936987 -280.895856)
			(xy 295.922115 -280.900648) (xy 295.915588 -280.90495) (xy 295.894467 -280.9193) (xy 295.848743 -280.942027)
			(xy 295.80007 -280.957457) (xy 295.749603 -280.965223) (xy 295.724072 -280.965656) (xy 295.698541 -280.965235)
			(xy 295.648077 -280.957455) (xy 295.599404 -280.942021) (xy 295.553677 -280.9193) (xy 295.532556 -280.90495)
			(xy 295.526031 -280.900648) (xy 295.511156 -280.895871) (xy 295.503346 -280.895552) (xy 294.987472 -280.895552)
			(xy 294.982216 -280.895029) (xy 294.974778 -280.887599) (xy 294.974264 -280.882344) (xy 288.930055 -280.882344)
			(xy 288.929545 -280.887448) (xy 288.921975 -280.895033) (xy 288.916618 -280.895552) (xy 288.400744 -280.895552)
			(xy 288.392935 -280.895876) (xy 288.378063 -280.900654) (xy 288.371534 -280.90495) (xy 288.350428 -280.919324)
			(xy 288.304699 -280.942045) (xy 288.256021 -280.957468) (xy 288.20555 -280.965227) (xy 288.180018 -280.965656)
			(xy 288.154488 -280.965212) (xy 288.104024 -280.957439) (xy 288.055352 -280.942012) (xy 288.009624 -280.919297)
			(xy 287.988502 -280.90495) (xy 287.981966 -280.900666) (xy 287.9671 -280.895878) (xy 287.959292 -280.895552)
			(xy 287.443418 -280.895552) (xy 287.437983 -280.895208) (xy 287.430295 -280.887525) (xy 287.429956 -280.88209)
			(xy 281.385772 -280.88209) (xy 281.385272 -280.88739) (xy 281.377853 -280.894961) (xy 281.372564 -280.895552)
			(xy 280.85669 -280.895552) (xy 280.848879 -280.895852) (xy 280.834007 -280.900646) (xy 280.82748 -280.90495)
			(xy 280.806361 -280.919304) (xy 280.760636 -280.94203) (xy 280.711962 -280.957458) (xy 280.661495 -280.965224)
			(xy 280.635964 -280.965656) (xy 280.610433 -280.965239) (xy 280.559968 -280.957457) (xy 280.511296 -280.942023)
			(xy 280.465569 -280.9193) (xy 280.444448 -280.90495) (xy 280.437924 -280.900645) (xy 280.423048 -280.89587)
			(xy 280.415238 -280.895552) (xy 279.899364 -280.895552) (xy 279.894108 -280.895034) (xy 279.88667 -280.8876)
			(xy 279.886156 -280.882344) (xy 273.841948 -280.882344) (xy 273.841472 -280.88739) (xy 273.834053 -280.894961)
			(xy 273.828764 -280.895552) (xy 273.31289 -280.895552) (xy 273.305079 -280.895852) (xy 273.290207 -280.900646)
			(xy 273.28368 -280.90495) (xy 273.262561 -280.919304) (xy 273.216836 -280.94203) (xy 273.168162 -280.957458)
			(xy 273.117695 -280.965224) (xy 273.092164 -280.965656) (xy 273.066633 -280.965239) (xy 273.016168 -280.957457)
			(xy 272.967496 -280.942023) (xy 272.921769 -280.9193) (xy 272.900648 -280.90495) (xy 272.894124 -280.900645)
			(xy 272.879248 -280.89587) (xy 272.871438 -280.895552) (xy 272.355564 -280.895552) (xy 272.350308 -280.895034)
			(xy 272.34287 -280.8876) (xy 272.342356 -280.882344) (xy 266.298147 -280.882344) (xy 266.297644 -280.88745)
			(xy 266.290069 -280.895036) (xy 266.28471 -280.895552) (xy 265.768836 -280.895552) (xy 265.761026 -280.895872)
			(xy 265.746155 -280.900653) (xy 265.739626 -280.90495) (xy 265.718495 -280.919284) (xy 265.672774 -280.942014)
			(xy 265.624104 -280.957449) (xy 265.57364 -280.96522) (xy 265.54811 -280.965656) (xy 265.52258 -280.965216)
			(xy 265.472116 -280.957441) (xy 265.423444 -280.942013) (xy 265.377716 -280.919297) (xy 265.356594 -280.90495)
			(xy 265.35006 -280.900663) (xy 265.335192 -280.895876) (xy 265.327384 -280.895552) (xy 264.81151 -280.895552)
			(xy 264.806074 -280.895213) (xy 264.798387 -280.887526) (xy 264.798048 -280.88209) (xy 202.89774 -280.88209)
			(xy 202.89774 -280.882344) (xy 202.897238 -280.887604) (xy 202.889793 -280.895043) (xy 202.884532 -280.895552)
			(xy 202.368658 -280.895552) (xy 202.360783 -280.895829) (xy 202.345779 -280.90062) (xy 202.339194 -280.90495)
			(xy 202.318109 -280.919329) (xy 202.272467 -280.942161) (xy 202.223863 -280.957722) (xy 202.173448 -280.965645)
			(xy 202.147932 -280.966164) (xy 202.122411 -280.965682) (xy 202.071984 -280.957786) (xy 202.023372 -280.942224)
			(xy 201.977734 -280.919367) (xy 201.95667 -280.90495) (xy 201.950084 -280.900625) (xy 201.93508 -280.895844)
			(xy 201.927206 -280.895552) (xy 201.411332 -280.895552) (xy 201.406083 -280.894989) (xy 201.398642 -280.887589)
			(xy 201.398124 -280.882344) (xy 195.35394 -280.882344) (xy 195.353438 -280.887604) (xy 195.345993 -280.895043)
			(xy 195.340732 -280.895552) (xy 194.824858 -280.895552) (xy 194.816983 -280.895829) (xy 194.801979 -280.90062)
			(xy 194.795394 -280.90495) (xy 194.774309 -280.919329) (xy 194.728667 -280.942161) (xy 194.680063 -280.957722)
			(xy 194.629648 -280.965645) (xy 194.604132 -280.966164) (xy 194.578611 -280.965682) (xy 194.528184 -280.957786)
			(xy 194.479572 -280.942224) (xy 194.433934 -280.919367) (xy 194.41287 -280.90495) (xy 194.406284 -280.900625)
			(xy 194.39128 -280.895844) (xy 194.383406 -280.895552) (xy 193.867532 -280.895552) (xy 193.862283 -280.894989)
			(xy 193.854842 -280.887589) (xy 193.854324 -280.882344) (xy 187.81014 -280.882344) (xy 187.809638 -280.887604)
			(xy 187.802193 -280.895043) (xy 187.796932 -280.895552) (xy 187.796424 -280.895552) (xy 187.280804 -280.895552)
			(xy 187.27293 -280.895849) (xy 187.257926 -280.900626) (xy 187.25134 -280.90495) (xy 187.23027 -280.919353)
			(xy 187.184622 -280.942178) (xy 187.136014 -280.957733) (xy 187.085595 -280.965649) (xy 187.060078 -280.966164)
			(xy 187.034558 -280.965659) (xy 186.984132 -280.95777) (xy 186.93552 -280.942215) (xy 186.889881 -280.919364)
			(xy 186.868816 -280.90495) (xy 186.86222 -280.900643) (xy 186.847223 -280.89585) (xy 186.839352 -280.895552)
			(xy 186.323478 -280.895552) (xy 186.318169 -280.89509) (xy 186.310599 -280.887644) (xy 186.310016 -280.882344)
			(xy 180.265832 -280.882344) (xy 180.265337 -280.887606) (xy 180.257887 -280.895045) (xy 180.252624 -280.895552)
			(xy 179.73675 -280.895552) (xy 179.728874 -280.895825) (xy 179.71387 -280.900619) (xy 179.707286 -280.90495)
			(xy 179.686203 -280.919333) (xy 179.64056 -280.942163) (xy 179.591956 -280.957723) (xy 179.54154 -280.965645)
			(xy 179.516024 -280.966164) (xy 179.490503 -280.965686) (xy 179.440076 -280.957789) (xy 179.391464 -280.942226)
			(xy 179.345826 -280.919367) (xy 179.324762 -280.90495) (xy 179.318178 -280.900622) (xy 179.303172 -280.895843)
			(xy 179.295298 -280.895552) (xy 178.779424 -280.895552) (xy 178.774175 -280.894994) (xy 178.766733 -280.887591)
			(xy 178.766216 -280.882344) (xy 172.722032 -280.882344) (xy 172.721537 -280.887606) (xy 172.714087 -280.895045)
			(xy 172.708824 -280.895552) (xy 172.708316 -280.895552) (xy 172.192696 -280.895552) (xy 172.184822 -280.895845)
			(xy 172.169818 -280.900625) (xy 172.163232 -280.90495) (xy 172.142164 -280.919356) (xy 172.096516 -280.942181)
			(xy 172.047907 -280.957735) (xy 171.997488 -280.965649) (xy 171.97197 -280.966164) (xy 171.94645 -280.965663)
			(xy 171.896023 -280.957773) (xy 171.847412 -280.942216) (xy 171.801773 -280.919364) (xy 171.780708 -280.90495)
			(xy 171.774113 -280.90064) (xy 171.759116 -280.895849) (xy 171.751244 -280.895552) (xy 171.23537 -280.895552)
			(xy 171.23006 -280.895096) (xy 171.22249 -280.887645) (xy 171.221908 -280.882344) (xy 165.177724 -280.882344)
			(xy 165.177236 -280.887608) (xy 165.169781 -280.895047) (xy 165.164516 -280.895552) (xy 163.691316 -280.895552)
			(xy 163.686066 -280.894999) (xy 163.678625 -280.887592) (xy 163.678108 -280.882344) (xy 56.07812 -280.882344)
			(xy 56.077636 -280.887609) (xy 56.070178 -280.895049) (xy 56.064912 -280.895552) (xy 54.591458 -280.895552)
			(xy 54.586147 -280.895104) (xy 54.578578 -280.887647) (xy 54.577996 -280.882344) (xy 48.533812 -280.882344)
			(xy 48.533335 -280.887611) (xy 48.525873 -280.895051) (xy 48.520604 -280.895552) (xy 48.00473 -280.895552)
			(xy 47.996853 -280.895817) (xy 47.981849 -280.900616) (xy 47.975266 -280.90495) (xy 47.954189 -280.919341)
			(xy 47.908544 -280.94217) (xy 47.859938 -280.957728) (xy 47.809521 -280.965647) (xy 47.784004 -280.966164)
			(xy 47.758483 -280.965696) (xy 47.708055 -280.957796) (xy 47.659443 -280.94223) (xy 47.613806 -280.919368)
			(xy 47.592742 -280.90495) (xy 47.586162 -280.900615) (xy 47.571153 -280.89584) (xy 47.563278 -280.895552)
			(xy 47.047404 -280.895552) (xy 47.042152 -280.895007) (xy 47.034712 -280.887594) (xy 47.034196 -280.882344)
			(xy 40.990012 -280.882344) (xy 40.989535 -280.887611) (xy 40.982073 -280.895051) (xy 40.976804 -280.895552)
			(xy 40.976296 -280.895552) (xy 40.460676 -280.895552) (xy 40.452801 -280.895837) (xy 40.437797 -280.900622)
			(xy 40.431212 -280.90495) (xy 40.41015 -280.919365) (xy 40.364499 -280.942188) (xy 40.315889 -280.957739)
			(xy 40.265468 -280.965651) (xy 40.23995 -280.966164) (xy 40.21443 -280.965673) (xy 40.164003 -280.95778)
			(xy 40.115391 -280.94222) (xy 40.069753 -280.919366) (xy 40.048688 -280.90495) (xy 40.042098 -280.900632)
			(xy 40.027097 -280.895846) (xy 40.019224 -280.895552) (xy 39.50335 -280.895552) (xy 39.49805 -280.895042)
			(xy 39.490476 -280.887632) (xy 39.489888 -280.882344) (xy 33.445704 -280.882344) (xy 33.445234 -280.887613)
			(xy 33.437767 -280.895053) (xy 33.432496 -280.895552) (xy 32.916622 -280.895552) (xy 32.908749 -280.895856)
			(xy 32.893745 -280.900629) (xy 32.887158 -280.90495) (xy 32.866083 -280.919345) (xy 32.820437 -280.942172)
			(xy 32.77183 -280.957729) (xy 32.721413 -280.965647) (xy 32.695896 -280.966164) (xy 32.670375 -280.9657)
			(xy 32.619946 -280.957799) (xy 32.571335 -280.942231) (xy 32.525698 -280.919369) (xy 32.504634 -280.90495)
			(xy 32.498034 -280.90065) (xy 32.483041 -280.895853) (xy 32.47517 -280.895552) (xy 31.959296 -280.895552)
			(xy 31.954043 -280.895013) (xy 31.946603 -280.887595) (xy 31.946088 -280.882344) (xy 25.901904 -280.882344)
			(xy 25.901434 -280.887613) (xy 25.893967 -280.895053) (xy 25.888696 -280.895552) (xy 25.372822 -280.895552)
			(xy 25.364949 -280.895856) (xy 25.349945 -280.900629) (xy 25.343358 -280.90495) (xy 25.322283 -280.919345)
			(xy 25.276637 -280.942172) (xy 25.22803 -280.957729) (xy 25.177613 -280.965647) (xy 25.152096 -280.966164)
			(xy 25.126575 -280.9657) (xy 25.076146 -280.957799) (xy 25.027535 -280.942231) (xy 24.981898 -280.919369)
			(xy 24.960834 -280.90495) (xy 24.954234 -280.90065) (xy 24.939241 -280.895853) (xy 24.93137 -280.895552)
			(xy 24.415496 -280.895552) (xy 24.410243 -280.895013) (xy 24.402803 -280.887595) (xy 24.402288 -280.882344)
			(xy 18.358104 -280.882344) (xy 18.357634 -280.887613) (xy 18.350167 -280.895053) (xy 18.344896 -280.895552)
			(xy 18.344388 -280.895552) (xy 17.828768 -280.895552) (xy 17.820893 -280.895833) (xy 17.805889 -280.900621)
			(xy 17.799304 -280.90495) (xy 17.778216 -280.919325) (xy 17.732575 -280.942157) (xy 17.683972 -280.95772)
			(xy 17.633558 -280.965644) (xy 17.608042 -280.966164) (xy 17.582522 -280.965677) (xy 17.532094 -280.957783)
			(xy 17.483483 -280.942222) (xy 17.437844 -280.919366) (xy 17.41678 -280.90495) (xy 17.410192 -280.900629)
			(xy 17.395189 -280.895845) (xy 17.387316 -280.895552) (xy 16.871442 -280.895552) (xy 16.866141 -280.895048)
			(xy 16.858567 -280.887634) (xy 16.85798 -280.882344) (xy 2.509012 -280.882344) (xy 2.509012 -281.732482)
			(xy 20.958048 -281.732482) (xy 20.958048 -281.237944) (xy 20.958619 -281.232697) (xy 20.966012 -281.225254)
			(xy 20.971256 -281.224736) (xy 20.971764 -281.224736) (xy 21.487638 -281.224736) (xy 21.495447 -281.224407)
			(xy 21.510319 -281.219633) (xy 21.516848 -281.215338) (xy 21.537937 -281.200989) (xy 21.583598 -281.178258)
			(xy 21.632204 -281.162799) (xy 21.682607 -281.154976) (xy 21.733613 -281.154976) (xy 21.784016 -281.162799)
			(xy 21.832622 -281.178258) (xy 21.878283 -281.200989) (xy 21.899372 -281.215338) (xy 21.905914 -281.219611)
			(xy 21.920776 -281.224407) (xy 21.928582 -281.224736) (xy 22.44471 -281.224736) (xy 22.450014 -281.225216)
			(xy 22.457585 -281.232649) (xy 22.458172 -281.237944) (xy 22.458172 -281.732482) (xy 22.458155 -281.732736)
			(xy 28.502356 -281.732736) (xy 28.502356 -281.732228) (xy 28.502356 -281.237944) (xy 28.502753 -281.232626)
			(xy 28.510249 -281.225085) (xy 28.515564 -281.224736) (xy 29.031692 -281.224736) (xy 29.039503 -281.22443)
			(xy 29.054375 -281.21964) (xy 29.060902 -281.215338) (xy 29.081991 -281.200989) (xy 29.127652 -281.178258)
			(xy 29.176258 -281.162799) (xy 29.226661 -281.154976) (xy 29.277667 -281.154976) (xy 29.32807 -281.162799)
			(xy 29.376676 -281.178258) (xy 29.422337 -281.200989) (xy 29.443426 -281.215338) (xy 29.449956 -281.219632)
			(xy 29.464827 -281.224414) (xy 29.472636 -281.224736) (xy 29.988764 -281.224736) (xy 29.994102 -281.225055)
			(xy 30.001648 -281.232606) (xy 30.001972 -281.237944) (xy 30.001972 -281.732482) (xy 30.001948 -281.732736)
			(xy 36.046156 -281.732736) (xy 36.046156 -281.732228) (xy 36.046156 -281.237944) (xy 36.046553 -281.232626)
			(xy 36.054049 -281.225085) (xy 36.059364 -281.224736) (xy 36.575492 -281.224736) (xy 36.583303 -281.22443)
			(xy 36.598175 -281.21964) (xy 36.604702 -281.215338) (xy 36.625791 -281.200989) (xy 36.671452 -281.178258)
			(xy 36.720058 -281.162799) (xy 36.770461 -281.154976) (xy 36.821467 -281.154976) (xy 36.87187 -281.162799)
			(xy 36.920476 -281.178258) (xy 36.966137 -281.200989) (xy 36.987226 -281.215338) (xy 36.993756 -281.219632)
			(xy 37.008627 -281.224414) (xy 37.016436 -281.224736) (xy 37.532564 -281.224736) (xy 37.537902 -281.225055)
			(xy 37.545448 -281.232606) (xy 37.545772 -281.237944) (xy 37.545772 -281.732482) (xy 43.589956 -281.732482)
			(xy 43.589956 -281.237944) (xy 43.590353 -281.232626) (xy 43.597849 -281.225085) (xy 43.603164 -281.224736)
			(xy 43.603672 -281.224736) (xy 44.119546 -281.224736) (xy 44.127355 -281.22441) (xy 44.142227 -281.219634)
			(xy 44.148756 -281.215338) (xy 44.169845 -281.200989) (xy 44.215506 -281.178258) (xy 44.264112 -281.162799)
			(xy 44.314515 -281.154976) (xy 44.365521 -281.154976) (xy 44.415924 -281.162799) (xy 44.46453 -281.178258)
			(xy 44.510191 -281.200989) (xy 44.53128 -281.215338) (xy 44.53782 -281.219614) (xy 44.552683 -281.224408)
			(xy 44.56049 -281.224736) (xy 45.076618 -281.224736) (xy 45.081923 -281.225211) (xy 45.089493 -281.232648)
			(xy 45.09008 -281.237944) (xy 45.09008 -281.732482) (xy 45.090054 -281.732736) (xy 51.134264 -281.732736)
			(xy 51.134264 -281.732228) (xy 51.134264 -281.237944) (xy 51.134654 -281.232624) (xy 51.142154 -281.225083)
			(xy 51.147472 -281.224736) (xy 51.6636 -281.224736) (xy 51.671411 -281.224433) (xy 51.686283 -281.219641)
			(xy 51.69281 -281.215338) (xy 51.713899 -281.200989) (xy 51.75956 -281.178258) (xy 51.808166 -281.162799)
			(xy 51.858569 -281.154976) (xy 51.909575 -281.154976) (xy 51.959978 -281.162799) (xy 52.008584 -281.178258)
			(xy 52.054245 -281.200989) (xy 52.075334 -281.215338) (xy 52.081862 -281.219635) (xy 52.096735 -281.224416)
			(xy 52.104544 -281.224736) (xy 52.620672 -281.224736) (xy 52.626011 -281.22505) (xy 52.633557 -281.232604)
			(xy 52.63388 -281.237944) (xy 52.63388 -281.732482) (xy 58.678064 -281.732482) (xy 58.678064 -281.237944)
			(xy 58.678454 -281.232624) (xy 58.685954 -281.225083) (xy 58.691272 -281.224736) (xy 58.69178 -281.224736)
			(xy 60.164726 -281.224736) (xy 60.170032 -281.225206) (xy 60.177602 -281.232647) (xy 60.178188 -281.237944)
			(xy 60.178188 -281.3764) (xy 97.674859 -281.3764) (xy 97.679035 -281.32601) (xy 97.691448 -281.276995)
			(xy 97.711759 -281.230691) (xy 97.739414 -281.188362) (xy 97.77366 -281.151162) (xy 97.813561 -281.120107)
			(xy 97.85803 -281.096042) (xy 97.905853 -281.079626) (xy 97.955727 -281.071304) (xy 97.981008 -281.070812)
			(xy 98.921062 -281.070812) (xy 98.946341 -281.071354) (xy 98.996209 -281.07967) (xy 99.044029 -281.096081)
			(xy 99.088494 -281.12014) (xy 99.128393 -281.15119) (xy 99.162637 -281.188384) (xy 99.190291 -281.230707)
			(xy 99.210601 -281.277006) (xy 99.223013 -281.326016) (xy 99.227189 -281.3764) (xy 100.495088 -281.3764)
			(xy 100.499263 -281.326019) (xy 100.511672 -281.277012) (xy 100.531978 -281.230715) (xy 100.559627 -281.188392)
			(xy 100.593865 -281.151197) (xy 100.633757 -281.120144) (xy 100.678216 -281.09608) (xy 100.72603 -281.079662)
			(xy 100.775893 -281.071336) (xy 100.80117 -281.070812) (xy 101.741224 -281.070812) (xy 101.766497 -281.071388)
			(xy 101.816353 -281.079711) (xy 101.864159 -281.096126) (xy 101.908611 -281.120186) (xy 101.948498 -281.151233)
			(xy 101.98273 -281.188422) (xy 102.010375 -281.230738) (xy 102.030678 -281.277027) (xy 102.043086 -281.326027)
			(xy 102.04726 -281.3764) (xy 122.108688 -281.3764) (xy 122.112863 -281.326017) (xy 122.125274 -281.277007)
			(xy 122.145582 -281.230709) (xy 122.173233 -281.188385) (xy 122.207473 -281.151189) (xy 122.247369 -281.120136)
			(xy 122.291831 -281.096074) (xy 122.339648 -281.079657) (xy 122.389514 -281.071335) (xy 122.414792 -281.070812)
			(xy 123.354846 -281.070812) (xy 123.380118 -281.071389) (xy 123.429971 -281.079715) (xy 123.477774 -281.096133)
			(xy 123.522223 -281.120193) (xy 123.562106 -281.151241) (xy 123.596336 -281.18843) (xy 123.623978 -281.230745)
			(xy 123.64428 -281.277032) (xy 123.656686 -281.326029) (xy 123.66086 -281.3764) (xy 124.928589 -281.3764)
			(xy 124.932763 -281.326016) (xy 124.945174 -281.277006) (xy 124.965483 -281.230707) (xy 124.993135 -281.188382)
			(xy 125.027376 -281.151186) (xy 125.067273 -281.120134) (xy 125.111736 -281.096071) (xy 125.159554 -281.079655)
			(xy 125.209422 -281.071334) (xy 125.2347 -281.070812) (xy 126.174754 -281.070812) (xy 126.200033 -281.071353)
			(xy 126.249903 -281.079668) (xy 126.297723 -281.096079) (xy 126.34219 -281.120137) (xy 126.38209 -281.151187)
			(xy 126.416335 -281.188381) (xy 126.44399 -281.230705) (xy 126.464301 -281.277004) (xy 126.476713 -281.326015)
			(xy 126.480889 -281.3764) (xy 126.476713 -281.426785) (xy 126.464301 -281.475796) (xy 126.44399 -281.522095)
			(xy 126.416335 -281.564419) (xy 126.38209 -281.601613) (xy 126.34219 -281.632663) (xy 126.297723 -281.656721)
			(xy 126.249903 -281.673132) (xy 126.200033 -281.681447) (xy 126.174754 -281.681936) (xy 125.2347 -281.681936)
			(xy 125.209422 -281.681466) (xy 125.159554 -281.673145) (xy 125.111736 -281.656729) (xy 125.067273 -281.632666)
			(xy 125.027376 -281.601614) (xy 124.993135 -281.564418) (xy 124.965483 -281.522093) (xy 124.945174 -281.475794)
			(xy 124.932763 -281.426784) (xy 124.928589 -281.3764) (xy 123.66086 -281.3764) (xy 123.656686 -281.426771)
			(xy 123.64428 -281.475768) (xy 123.623978 -281.522055) (xy 123.596336 -281.56437) (xy 123.562106 -281.601559)
			(xy 123.522223 -281.632607) (xy 123.477774 -281.656667) (xy 123.429971 -281.673085) (xy 123.380118 -281.681411)
			(xy 123.354846 -281.681936) (xy 122.414792 -281.681936) (xy 122.389514 -281.681465) (xy 122.339648 -281.673143)
			(xy 122.291831 -281.656726) (xy 122.247369 -281.632664) (xy 122.207473 -281.601611) (xy 122.173233 -281.564415)
			(xy 122.145582 -281.522091) (xy 122.125274 -281.475793) (xy 122.112863 -281.426783) (xy 122.108688 -281.3764)
			(xy 102.04726 -281.3764) (xy 102.043086 -281.426773) (xy 102.030678 -281.475773) (xy 102.010375 -281.522062)
			(xy 101.98273 -281.564378) (xy 101.948498 -281.601567) (xy 101.908611 -281.632614) (xy 101.864159 -281.656674)
			(xy 101.816353 -281.673089) (xy 101.766497 -281.681412) (xy 101.741224 -281.681936) (xy 100.80117 -281.681936)
			(xy 100.775893 -281.681464) (xy 100.72603 -281.673138) (xy 100.678216 -281.65672) (xy 100.633757 -281.632656)
			(xy 100.593865 -281.601603) (xy 100.559627 -281.564408) (xy 100.531978 -281.522085) (xy 100.511672 -281.475788)
			(xy 100.499263 -281.426781) (xy 100.495088 -281.3764) (xy 99.227189 -281.3764) (xy 99.223013 -281.426784)
			(xy 99.210601 -281.475794) (xy 99.190291 -281.522093) (xy 99.162637 -281.564416) (xy 99.128393 -281.60161)
			(xy 99.088494 -281.63266) (xy 99.044029 -281.656719) (xy 98.996209 -281.67313) (xy 98.946341 -281.681446)
			(xy 98.921062 -281.681936) (xy 97.981008 -281.681936) (xy 97.955727 -281.681496) (xy 97.905853 -281.673174)
			(xy 97.85803 -281.656758) (xy 97.813561 -281.632693) (xy 97.77366 -281.601638) (xy 97.739414 -281.564438)
			(xy 97.711759 -281.522109) (xy 97.691448 -281.475805) (xy 97.679035 -281.42679) (xy 97.674859 -281.3764)
			(xy 60.178188 -281.3764) (xy 60.178188 -281.732482) (xy 60.178162 -281.732736) (xy 167.778176 -281.732736)
			(xy 167.778176 -281.237944) (xy 167.778555 -281.232621) (xy 167.786063 -281.225079) (xy 167.791384 -281.224736)
			(xy 169.264584 -281.224736) (xy 169.269925 -281.225042) (xy 169.277469 -281.232602) (xy 169.277792 -281.237944)
			(xy 169.277792 -281.732482) (xy 175.321976 -281.732482) (xy 175.321976 -281.237944) (xy 175.322355 -281.232621)
			(xy 175.329863 -281.225079) (xy 175.335184 -281.224736) (xy 175.335692 -281.224736) (xy 175.851566 -281.224736)
			(xy 175.859376 -281.224419) (xy 175.874248 -281.219636) (xy 175.880776 -281.215338) (xy 175.901865 -281.200989)
			(xy 175.947526 -281.178258) (xy 175.996132 -281.162799) (xy 176.046535 -281.154976) (xy 176.097541 -281.154976)
			(xy 176.147944 -281.162799) (xy 176.19655 -281.178258) (xy 176.242211 -281.200989) (xy 176.2633 -281.215338)
			(xy 176.269836 -281.219622) (xy 176.284702 -281.224411) (xy 176.29251 -281.224736) (xy 176.808638 -281.224736)
			(xy 176.813946 -281.225198) (xy 176.821514 -281.232645) (xy 176.8221 -281.237944) (xy 176.8221 -281.732482)
			(xy 176.822074 -281.732736) (xy 182.866284 -281.732736) (xy 182.866284 -281.732228) (xy 182.866284 -281.237944)
			(xy 182.866656 -281.232619) (xy 182.874169 -281.225076) (xy 182.879492 -281.224736) (xy 183.39562 -281.224736)
			(xy 183.403432 -281.224442) (xy 183.418304 -281.219644) (xy 183.42483 -281.215338) (xy 183.445919 -281.200989)
			(xy 183.49158 -281.178258) (xy 183.540186 -281.162799) (xy 183.590589 -281.154976) (xy 183.641595 -281.154976)
			(xy 183.691998 -281.162799) (xy 183.740604 -281.178258) (xy 183.786265 -281.200989) (xy 183.807354 -281.215338)
			(xy 183.813878 -281.219643) (xy 183.828754 -281.224419) (xy 183.836564 -281.224736) (xy 184.352692 -281.224736)
			(xy 184.358034 -281.225036) (xy 184.365578 -281.232601) (xy 184.3659 -281.237944) (xy 184.3659 -281.732482)
			(xy 190.410084 -281.732482) (xy 190.410084 -281.237944) (xy 190.410456 -281.232619) (xy 190.417969 -281.225076)
			(xy 190.423292 -281.224736) (xy 190.4238 -281.224736) (xy 190.939674 -281.224736) (xy 190.947484 -281.224422)
			(xy 190.962356 -281.219637) (xy 190.968884 -281.215338) (xy 190.989973 -281.200989) (xy 191.035634 -281.178258)
			(xy 191.08424 -281.162799) (xy 191.134643 -281.154976) (xy 191.185649 -281.154976) (xy 191.236052 -281.162799)
			(xy 191.284658 -281.178258) (xy 191.330319 -281.200989) (xy 191.351408 -281.215338) (xy 191.357942 -281.219625)
			(xy 191.37281 -281.224412) (xy 191.380618 -281.224736) (xy 191.896746 -281.224736) (xy 191.902043 -281.225259)
			(xy 191.909617 -281.23266) (xy 191.910208 -281.237944) (xy 191.910208 -281.732482) (xy 191.910181 -281.732736)
			(xy 197.954392 -281.732736) (xy 197.954392 -281.732228) (xy 197.954392 -281.237944) (xy 197.954756 -281.232618)
			(xy 197.962275 -281.225074) (xy 197.9676 -281.224736) (xy 198.483728 -281.224736) (xy 198.49154 -281.224445)
			(xy 198.506412 -281.219645) (xy 198.512938 -281.215338) (xy 198.534027 -281.200989) (xy 198.579688 -281.178258)
			(xy 198.628294 -281.162799) (xy 198.678697 -281.154976) (xy 198.729703 -281.154976) (xy 198.780106 -281.162799)
			(xy 198.828712 -281.178258) (xy 198.874373 -281.200989) (xy 198.895462 -281.215338) (xy 198.902006 -281.219607)
			(xy 198.916866 -281.224405) (xy 198.924672 -281.224736) (xy 199.4408 -281.224736) (xy 199.446143 -281.225031)
			(xy 199.453687 -281.2326) (xy 199.454008 -281.237944) (xy 199.454008 -281.732482) (xy 199.453982 -281.732736)
			(xy 205.498192 -281.732736) (xy 205.498192 -281.732228) (xy 205.498192 -281.237944) (xy 205.498556 -281.232618)
			(xy 205.506075 -281.225074) (xy 205.5114 -281.224736) (xy 206.027528 -281.224736) (xy 206.03534 -281.224445)
			(xy 206.050212 -281.219645) (xy 206.056738 -281.215338) (xy 206.077827 -281.200989) (xy 206.123488 -281.178258)
			(xy 206.172094 -281.162799) (xy 206.222497 -281.154976) (xy 206.273503 -281.154976) (xy 206.323906 -281.162799)
			(xy 206.372512 -281.178258) (xy 206.418173 -281.200989) (xy 206.439262 -281.215338) (xy 206.445806 -281.219607)
			(xy 206.460666 -281.224405) (xy 206.468472 -281.224736) (xy 206.9846 -281.224736) (xy 206.989943 -281.225031)
			(xy 206.997487 -281.2326) (xy 206.997808 -281.237944) (xy 206.997808 -281.732228) (xy 268.898116 -281.732228)
			(xy 268.898116 -281.23769) (xy 268.898642 -281.23233) (xy 268.906219 -281.224746) (xy 268.911578 -281.224228)
			(xy 269.427706 -281.224228) (xy 269.435518 -281.223929) (xy 269.450389 -281.219134) (xy 269.456916 -281.21483)
			(xy 269.478005 -281.200481) (xy 269.523666 -281.17775) (xy 269.572272 -281.162291) (xy 269.622675 -281.154468)
			(xy 269.673681 -281.154468) (xy 269.724084 -281.162291) (xy 269.77269 -281.17775) (xy 269.818351 -281.200481)
			(xy 269.83944 -281.21483) (xy 269.845967 -281.219129) (xy 269.86084 -281.223908) (xy 269.86865 -281.224228)
			(xy 270.384778 -281.224228) (xy 270.390207 -281.224593) (xy 270.397894 -281.232261) (xy 270.39824 -281.23769)
			(xy 270.39824 -281.732228) (xy 276.442424 -281.732228) (xy 276.442424 -281.23769) (xy 276.442915 -281.232388)
			(xy 276.450341 -281.224819) (xy 276.455632 -281.224228) (xy 276.97176 -281.224228) (xy 276.97957 -281.223909)
			(xy 276.994442 -281.219128) (xy 277.00097 -281.21483) (xy 277.022059 -281.200481) (xy 277.06772 -281.17775)
			(xy 277.116326 -281.162291) (xy 277.166729 -281.154468) (xy 277.217735 -281.154468) (xy 277.268138 -281.162291)
			(xy 277.316744 -281.17775) (xy 277.362405 -281.200481) (xy 277.383494 -281.21483) (xy 277.390032 -281.219111)
			(xy 277.404897 -281.223902) (xy 277.412704 -281.224228) (xy 277.928832 -281.224228) (xy 277.934177 -281.224509)
			(xy 277.941718 -281.232089) (xy 277.94204 -281.237436) (xy 277.94204 -281.237944) (xy 277.94204 -281.732228)
			(xy 283.986224 -281.732228) (xy 283.986224 -281.23769) (xy 283.986715 -281.232388) (xy 283.994141 -281.224819)
			(xy 283.999432 -281.224228) (xy 284.51556 -281.224228) (xy 284.52337 -281.223909) (xy 284.538242 -281.219128)
			(xy 284.54477 -281.21483) (xy 284.565859 -281.200481) (xy 284.61152 -281.17775) (xy 284.660126 -281.162291)
			(xy 284.710529 -281.154468) (xy 284.761535 -281.154468) (xy 284.811938 -281.162291) (xy 284.860544 -281.17775)
			(xy 284.906205 -281.200481) (xy 284.927294 -281.21483) (xy 284.933832 -281.219111) (xy 284.948697 -281.223902)
			(xy 284.956504 -281.224228) (xy 285.472632 -281.224228) (xy 285.477977 -281.224509) (xy 285.485518 -281.232089)
			(xy 285.48584 -281.237436) (xy 285.48584 -281.237944) (xy 285.48584 -281.732228) (xy 291.530024 -281.732228)
			(xy 291.530024 -281.23769) (xy 291.530542 -281.232328) (xy 291.538124 -281.224744) (xy 291.543486 -281.224228)
			(xy 292.059614 -281.224228) (xy 292.067426 -281.223932) (xy 292.082298 -281.219135) (xy 292.088824 -281.21483)
			(xy 292.109913 -281.200481) (xy 292.155574 -281.17775) (xy 292.20418 -281.162291) (xy 292.254583 -281.154468)
			(xy 292.305589 -281.154468) (xy 292.355992 -281.162291) (xy 292.404598 -281.17775) (xy 292.450259 -281.200481)
			(xy 292.471348 -281.21483) (xy 292.477874 -281.219132) (xy 292.492748 -281.22391) (xy 292.500558 -281.224228)
			(xy 293.016686 -281.224228) (xy 293.022116 -281.224588) (xy 293.029803 -281.23226) (xy 293.030148 -281.23769)
			(xy 293.030148 -281.732228) (xy 299.074332 -281.732228) (xy 299.074332 -281.23769) (xy 299.074816 -281.232386)
			(xy 299.082247 -281.224816) (xy 299.08754 -281.224228) (xy 299.603668 -281.224228) (xy 299.611478 -281.223913)
			(xy 299.62635 -281.219129) (xy 299.632878 -281.21483) (xy 299.653967 -281.200481) (xy 299.699628 -281.17775)
			(xy 299.748234 -281.162291) (xy 299.798637 -281.154468) (xy 299.849643 -281.154468) (xy 299.900046 -281.162291)
			(xy 299.948652 -281.17775) (xy 299.994313 -281.200481) (xy 300.015402 -281.21483) (xy 300.021938 -281.219114)
			(xy 300.036804 -281.223903) (xy 300.044612 -281.224228) (xy 300.56074 -281.224228) (xy 300.566016 -281.224672)
			(xy 300.573459 -281.232157) (xy 300.573948 -281.237436) (xy 300.573948 -281.237944) (xy 300.573948 -281.732228)
			(xy 306.618132 -281.732228) (xy 306.618132 -281.23769) (xy 306.618643 -281.232326) (xy 306.62623 -281.224742)
			(xy 306.631594 -281.224228) (xy 308.104794 -281.224228) (xy 308.110155 -281.224753) (xy 308.11774 -281.23233)
			(xy 308.118256 -281.23769) (xy 308.118256 -281.3761) (xy 345.615289 -281.3761) (xy 345.619459 -281.325768)
			(xy 345.631857 -281.276808) (xy 345.652144 -281.230557) (xy 345.679766 -281.188275) (xy 345.713971 -281.151116)
			(xy 345.753825 -281.120094) (xy 345.798241 -281.096054) (xy 345.846008 -281.079652) (xy 345.895824 -281.071335)
			(xy 345.921076 -281.070812) (xy 346.86113 -281.070812) (xy 346.886385 -281.071296) (xy 346.936207 -281.079614)
			(xy 346.983979 -281.096019) (xy 347.028401 -281.120062) (xy 347.068259 -281.151089) (xy 347.102467 -281.188252)
			(xy 347.130092 -281.230539) (xy 347.150381 -281.276796) (xy 347.16278 -281.325762) (xy 347.166951 -281.3761)
			(xy 348.43536 -281.3761) (xy 348.439532 -281.325756) (xy 348.451934 -281.276786) (xy 348.472227 -281.230526)
			(xy 348.499859 -281.188237) (xy 348.534075 -281.151073) (xy 348.573942 -281.120048) (xy 348.618371 -281.096009)
			(xy 348.666152 -281.079611) (xy 348.71598 -281.071302) (xy 348.741238 -281.070812) (xy 349.681292 -281.070812)
			(xy 349.706552 -281.071264) (xy 349.756383 -281.079578) (xy 349.804165 -281.095981) (xy 349.848596 -281.120025)
			(xy 349.888464 -281.151054) (xy 349.92268 -281.188222) (xy 349.950312 -281.230515) (xy 349.970606 -281.276779)
			(xy 349.983008 -281.325753) (xy 349.98718 -281.3761) (xy 370.049089 -281.3761) (xy 370.053259 -281.325769)
			(xy 370.065656 -281.276811) (xy 370.085941 -281.230561) (xy 370.113562 -281.18828) (xy 370.147764 -281.151122)
			(xy 370.187616 -281.120099) (xy 370.23203 -281.096058) (xy 370.279795 -281.079655) (xy 370.329608 -281.071337)
			(xy 370.35486 -281.070812) (xy 371.294914 -281.070812) (xy 371.32017 -281.071295) (xy 371.369993 -281.079611)
			(xy 371.417768 -281.096014) (xy 371.462192 -281.120057) (xy 371.502053 -281.151083) (xy 371.536263 -281.188247)
			(xy 371.56389 -281.230535) (xy 371.58418 -281.276793) (xy 371.59658 -281.32576) (xy 371.600751 -281.3761)
			(xy 372.868989 -281.3761) (xy 372.873159 -281.325768) (xy 372.885556 -281.27681) (xy 372.905842 -281.230559)
			(xy 372.933464 -281.188278) (xy 372.967667 -281.151119) (xy 373.00752 -281.120096) (xy 373.051935 -281.096056)
			(xy 373.099702 -281.079653) (xy 373.149516 -281.071336) (xy 373.174768 -281.070812) (xy 374.114822 -281.070812)
			(xy 374.140078 -281.071295) (xy 374.1899 -281.079613) (xy 374.237674 -281.096016) (xy 374.282096 -281.120059)
			(xy 374.321956 -281.151086) (xy 374.356165 -281.18825) (xy 374.383791 -281.230537) (xy 374.404081 -281.276795)
			(xy 374.41648 -281.325761) (xy 374.420651 -281.3761) (xy 374.41648 -281.426439) (xy 374.404081 -281.475405)
			(xy 374.383791 -281.521663) (xy 374.356165 -281.56395) (xy 374.321956 -281.601114) (xy 374.282096 -281.632141)
			(xy 374.237674 -281.656184) (xy 374.1899 -281.672587) (xy 374.140078 -281.680905) (xy 374.114822 -281.681428)
			(xy 373.174768 -281.681428) (xy 373.149516 -281.680864) (xy 373.099702 -281.672547) (xy 373.051935 -281.656144)
			(xy 373.00752 -281.632104) (xy 372.967667 -281.601081) (xy 372.933464 -281.563922) (xy 372.905842 -281.521641)
			(xy 372.885556 -281.47539) (xy 372.873159 -281.426432) (xy 372.868989 -281.3761) (xy 371.600751 -281.3761)
			(xy 371.59658 -281.42644) (xy 371.58418 -281.475407) (xy 371.56389 -281.521665) (xy 371.536263 -281.563953)
			(xy 371.502053 -281.601117) (xy 371.462192 -281.632143) (xy 371.417768 -281.656186) (xy 371.369993 -281.672589)
			(xy 371.32017 -281.680905) (xy 371.294914 -281.681428) (xy 370.35486 -281.681428) (xy 370.329609 -281.680863)
			(xy 370.279795 -281.672545) (xy 370.23203 -281.656142) (xy 370.187616 -281.632101) (xy 370.147764 -281.601078)
			(xy 370.113562 -281.56392) (xy 370.085941 -281.521639) (xy 370.065656 -281.475389) (xy 370.053259 -281.426431)
			(xy 370.049089 -281.3761) (xy 349.98718 -281.3761) (xy 349.983008 -281.426447) (xy 349.970606 -281.475421)
			(xy 349.950312 -281.521685) (xy 349.92268 -281.563978) (xy 349.888464 -281.601146) (xy 349.848596 -281.632175)
			(xy 349.804165 -281.656219) (xy 349.756383 -281.672622) (xy 349.706552 -281.680936) (xy 349.681292 -281.681428)
			(xy 348.741238 -281.681428) (xy 348.71598 -281.680898) (xy 348.666152 -281.672589) (xy 348.618371 -281.656191)
			(xy 348.573941 -281.632152) (xy 348.534075 -281.601127) (xy 348.499859 -281.563963) (xy 348.472227 -281.521674)
			(xy 348.451934 -281.475414) (xy 348.439532 -281.426444) (xy 348.43536 -281.3761) (xy 347.166951 -281.3761)
			(xy 347.16278 -281.426438) (xy 347.150381 -281.475404) (xy 347.130092 -281.521661) (xy 347.102467 -281.563948)
			(xy 347.068259 -281.601111) (xy 347.028401 -281.632138) (xy 346.983979 -281.656181) (xy 346.936207 -281.672586)
			(xy 346.886385 -281.680904) (xy 346.86113 -281.681428) (xy 345.921076 -281.681428) (xy 345.895824 -281.680865)
			(xy 345.846008 -281.672548) (xy 345.798241 -281.656146) (xy 345.753825 -281.632106) (xy 345.713971 -281.601084)
			(xy 345.679766 -281.563925) (xy 345.652144 -281.521643) (xy 345.631857 -281.475392) (xy 345.619459 -281.426432)
			(xy 345.615289 -281.3761) (xy 308.118256 -281.3761) (xy 308.118256 -281.732228) (xy 415.718244 -281.732228)
			(xy 415.718244 -281.23769) (xy 415.718717 -281.232384) (xy 415.726155 -281.224813) (xy 415.731452 -281.224228)
			(xy 417.204652 -281.224228) (xy 417.209987 -281.224563) (xy 417.217532 -281.232102) (xy 417.21786 -281.237436)
			(xy 417.21786 -281.732228) (xy 423.262044 -281.732228) (xy 423.262044 -281.23769) (xy 423.262544 -281.232323)
			(xy 423.270139 -281.224738) (xy 423.275506 -281.224228) (xy 423.791634 -281.224228) (xy 423.799443 -281.223898)
			(xy 423.814315 -281.219125) (xy 423.820844 -281.21483) (xy 423.841933 -281.200481) (xy 423.887594 -281.17775)
			(xy 423.9362 -281.162291) (xy 423.986603 -281.154468) (xy 424.037609 -281.154468) (xy 424.088012 -281.162291)
			(xy 424.136618 -281.17775) (xy 424.182279 -281.200481) (xy 424.203368 -281.21483) (xy 424.209911 -281.219101)
			(xy 424.224772 -281.223898) (xy 424.232578 -281.224228) (xy 424.748706 -281.224228) (xy 424.754068 -281.224745)
			(xy 424.761653 -281.232328) (xy 424.762168 -281.23769) (xy 424.762168 -281.732228) (xy 430.806352 -281.732228)
			(xy 430.806352 -281.23769) (xy 430.806818 -281.232382) (xy 430.814261 -281.224811) (xy 430.81956 -281.224228)
			(xy 431.335688 -281.224228) (xy 431.343499 -281.223921) (xy 431.358371 -281.219132) (xy 431.364898 -281.21483)
			(xy 431.385987 -281.200481) (xy 431.431648 -281.17775) (xy 431.480254 -281.162291) (xy 431.530657 -281.154468)
			(xy 431.581663 -281.154468) (xy 431.632066 -281.162291) (xy 431.680672 -281.17775) (xy 431.726333 -281.200481)
			(xy 431.747422 -281.21483) (xy 431.753953 -281.219122) (xy 431.768823 -281.223906) (xy 431.776632 -281.224228)
			(xy 432.29276 -281.224228) (xy 432.298096 -281.224557) (xy 432.305641 -281.232101) (xy 432.305968 -281.237436)
			(xy 432.305968 -281.237944) (xy 432.305968 -281.732228) (xy 438.350152 -281.732228) (xy 438.350152 -281.23769)
			(xy 438.350474 -281.23225) (xy 438.358174 -281.224564) (xy 438.363614 -281.224228) (xy 438.879742 -281.224228)
			(xy 438.887551 -281.223902) (xy 438.902423 -281.219126) (xy 438.908952 -281.21483) (xy 438.930041 -281.200481)
			(xy 438.975702 -281.17775) (xy 439.024308 -281.162291) (xy 439.074711 -281.154468) (xy 439.125717 -281.154468)
			(xy 439.17612 -281.162291) (xy 439.224726 -281.17775) (xy 439.270387 -281.200481) (xy 439.291476 -281.21483)
			(xy 439.298018 -281.219104) (xy 439.31288 -281.223899) (xy 439.320686 -281.224228) (xy 439.836814 -281.224228)
			(xy 439.842177 -281.22474) (xy 439.849761 -281.232327) (xy 439.850276 -281.23769) (xy 439.850276 -281.732228)
			(xy 445.89446 -281.732228) (xy 445.89446 -281.23769) (xy 445.894919 -281.23238) (xy 445.902367 -281.224808)
			(xy 445.907668 -281.224228) (xy 446.423796 -281.224228) (xy 446.431607 -281.223925) (xy 446.446479 -281.219133)
			(xy 446.453006 -281.21483) (xy 446.474095 -281.200481) (xy 446.519756 -281.17775) (xy 446.568362 -281.162291)
			(xy 446.618765 -281.154468) (xy 446.669771 -281.154468) (xy 446.720174 -281.162291) (xy 446.76878 -281.17775)
			(xy 446.814441 -281.200481) (xy 446.83553 -281.21483) (xy 446.84206 -281.219125) (xy 446.856931 -281.223907)
			(xy 446.86474 -281.224228) (xy 447.380868 -281.224228) (xy 447.386205 -281.224552) (xy 447.39375 -281.232099)
			(xy 447.394076 -281.237436) (xy 447.394076 -281.237944) (xy 447.394076 -281.732228) (xy 453.43826 -281.732228)
			(xy 453.43826 -281.23769) (xy 453.438719 -281.23238) (xy 453.446167 -281.224808) (xy 453.451468 -281.224228)
			(xy 453.967596 -281.224228) (xy 453.975407 -281.223925) (xy 453.990279 -281.219133) (xy 453.996806 -281.21483)
			(xy 454.017895 -281.200481) (xy 454.063556 -281.17775) (xy 454.112162 -281.162291) (xy 454.162565 -281.154468)
			(xy 454.213571 -281.154468) (xy 454.263974 -281.162291) (xy 454.31258 -281.17775) (xy 454.358241 -281.200481)
			(xy 454.37933 -281.21483) (xy 454.38586 -281.219125) (xy 454.400731 -281.223907) (xy 454.40854 -281.224228)
			(xy 454.924668 -281.224228) (xy 454.930005 -281.224552) (xy 454.93755 -281.232099) (xy 454.937876 -281.237436)
			(xy 454.937876 -281.237944) (xy 454.937876 -281.732228) (xy 454.937589 -281.737572) (xy 454.930013 -281.745113)
			(xy 454.924668 -281.745436) (xy 454.408794 -281.745436) (xy 454.40092 -281.745731) (xy 454.385916 -281.75051)
			(xy 454.37933 -281.754834) (xy 454.358261 -281.769239) (xy 454.312613 -281.792065) (xy 454.264005 -281.807619)
			(xy 454.213585 -281.815533) (xy 454.188068 -281.816048) (xy 454.162549 -281.815533) (xy 454.112123 -281.807644)
			(xy 454.063512 -281.792092) (xy 454.017872 -281.769245) (xy 453.996806 -281.754834) (xy 453.990213 -281.750522)
			(xy 453.975214 -281.745733) (xy 453.967342 -281.745436) (xy 453.451468 -281.745436) (xy 453.446208 -281.744929)
			(xy 453.438769 -281.737488) (xy 453.43826 -281.732228) (xy 447.394076 -281.732228) (xy 447.393789 -281.737572)
			(xy 447.386213 -281.745113) (xy 447.380868 -281.745436) (xy 446.864994 -281.745436) (xy 446.85712 -281.745731)
			(xy 446.842116 -281.75051) (xy 446.83553 -281.754834) (xy 446.814461 -281.769239) (xy 446.768813 -281.792065)
			(xy 446.720205 -281.807619) (xy 446.669785 -281.815533) (xy 446.644268 -281.816048) (xy 446.618749 -281.815533)
			(xy 446.568323 -281.807644) (xy 446.519712 -281.792092) (xy 446.474072 -281.769245) (xy 446.453006 -281.754834)
			(xy 446.446413 -281.750522) (xy 446.431414 -281.745733) (xy 446.423542 -281.745436) (xy 445.907668 -281.745436)
			(xy 445.902408 -281.744929) (xy 445.894969 -281.737488) (xy 445.89446 -281.732228) (xy 439.850276 -281.732228)
			(xy 439.849989 -281.737572) (xy 439.842413 -281.745113) (xy 439.837068 -281.745436) (xy 439.83656 -281.745436)
			(xy 439.32094 -281.745436) (xy 439.313064 -281.745708) (xy 439.29806 -281.750503) (xy 439.291476 -281.754834)
			(xy 439.270394 -281.769219) (xy 439.224751 -281.792049) (xy 439.176146 -281.807609) (xy 439.12573 -281.81553)
			(xy 439.100214 -281.816048) (xy 439.074694 -281.81556) (xy 439.024267 -281.807663) (xy 438.975656 -281.792103)
			(xy 438.930017 -281.769248) (xy 438.908952 -281.754834) (xy 438.902371 -281.750501) (xy 438.887363 -281.745725)
			(xy 438.879488 -281.745436) (xy 438.363614 -281.745436) (xy 438.358306 -281.744965) (xy 438.350733 -281.737526)
			(xy 438.350152 -281.732228) (xy 432.305968 -281.732228) (xy 432.305688 -281.737574) (xy 432.298108 -281.745116)
			(xy 432.29276 -281.745436) (xy 431.776886 -281.745436) (xy 431.769012 -281.745728) (xy 431.754008 -281.750509)
			(xy 431.747422 -281.754834) (xy 431.726356 -281.769243) (xy 431.680707 -281.792067) (xy 431.632097 -281.807621)
			(xy 431.581678 -281.815534) (xy 431.55616 -281.816048) (xy 431.530641 -281.815537) (xy 431.480215 -281.807647)
			(xy 431.431604 -281.792093) (xy 431.385964 -281.769246) (xy 431.364898 -281.754834) (xy 431.358307 -281.750519)
			(xy 431.343307 -281.745732) (xy 431.335434 -281.745436) (xy 430.81956 -281.745436) (xy 430.814299 -281.744935)
			(xy 430.80686 -281.737489) (xy 430.806352 -281.732228) (xy 424.762168 -281.732228) (xy 424.761888 -281.737574)
			(xy 424.754308 -281.745116) (xy 424.74896 -281.745436) (xy 424.748452 -281.745436) (xy 424.232832 -281.745436)
			(xy 424.224956 -281.745704) (xy 424.209952 -281.750501) (xy 424.203368 -281.754834) (xy 424.182289 -281.769223)
			(xy 424.136645 -281.792052) (xy 424.088039 -281.807611) (xy 424.037623 -281.815531) (xy 424.012106 -281.816048)
			(xy 423.986586 -281.815564) (xy 423.936159 -281.807666) (xy 423.887548 -281.792104) (xy 423.841909 -281.769249)
			(xy 423.820844 -281.754834) (xy 423.814265 -281.750498) (xy 423.799255 -281.745724) (xy 423.79138 -281.745436)
			(xy 423.275506 -281.745436) (xy 423.270197 -281.74497) (xy 423.262624 -281.737528) (xy 423.262044 -281.732228)
			(xy 417.21786 -281.732228) (xy 417.217587 -281.737576) (xy 417.210002 -281.745118) (xy 417.204652 -281.745436)
			(xy 415.731452 -281.745436) (xy 415.72619 -281.74494) (xy 415.718752 -281.73749) (xy 415.718244 -281.732228)
			(xy 308.118256 -281.732228) (xy 308.117729 -281.737483) (xy 308.110302 -281.744921) (xy 308.105048 -281.745436)
			(xy 308.10454 -281.745436) (xy 306.631594 -281.745436) (xy 306.626283 -281.744978) (xy 306.618711 -281.73753)
			(xy 306.618132 -281.732228) (xy 300.573948 -281.732228) (xy 300.573428 -281.737485) (xy 300.565996 -281.744923)
			(xy 300.56074 -281.745436) (xy 300.044866 -281.745436) (xy 300.036991 -281.745719) (xy 300.021987 -281.750506)
			(xy 300.015402 -281.754834) (xy 299.994313 -281.769208) (xy 299.948673 -281.792041) (xy 299.90007 -281.807604)
			(xy 299.849656 -281.815528) (xy 299.82414 -281.816048) (xy 299.79862 -281.815547) (xy 299.748194 -281.807654)
			(xy 299.699583 -281.792097) (xy 299.653944 -281.769247) (xy 299.632878 -281.754834) (xy 299.626291 -281.750511)
			(xy 299.611288 -281.745729) (xy 299.603414 -281.745436) (xy 299.08754 -281.745436) (xy 299.08222 -281.745049)
			(xy 299.074678 -281.737546) (xy 299.074332 -281.732228) (xy 293.030148 -281.732228) (xy 293.029628 -281.737485)
			(xy 293.022196 -281.744923) (xy 293.01694 -281.745436) (xy 293.016432 -281.745436) (xy 292.500812 -281.745436)
			(xy 292.492939 -281.745739) (xy 292.477935 -281.750512) (xy 292.471348 -281.754834) (xy 292.450274 -281.769231)
			(xy 292.404628 -281.792059) (xy 292.356021 -281.807615) (xy 292.305603 -281.815532) (xy 292.280086 -281.816048)
			(xy 292.254567 -281.815524) (xy 292.204142 -281.807638) (xy 292.155531 -281.792088) (xy 292.109891 -281.769244)
			(xy 292.088824 -281.754834) (xy 292.082227 -281.750529) (xy 292.067231 -281.745735) (xy 292.05936 -281.745436)
			(xy 291.543486 -281.745436) (xy 291.538175 -281.744983) (xy 291.530603 -281.737531) (xy 291.530024 -281.732228)
			(xy 285.48584 -281.732228) (xy 285.485327 -281.737486) (xy 285.47789 -281.744926) (xy 285.472632 -281.745436)
			(xy 284.956758 -281.745436) (xy 284.948883 -281.745715) (xy 284.933879 -281.750505) (xy 284.927294 -281.754834)
			(xy 284.906207 -281.769212) (xy 284.860566 -281.792043) (xy 284.811963 -281.807605) (xy 284.761548 -281.815529)
			(xy 284.736032 -281.816048) (xy 284.710512 -281.815551) (xy 284.660086 -281.807657) (xy 284.611475 -281.792099)
			(xy 284.565836 -281.769247) (xy 284.54477 -281.754834) (xy 284.538185 -281.750508) (xy 284.52318 -281.745728)
			(xy 284.515306 -281.745436) (xy 283.999432 -281.745436) (xy 283.994111 -281.745054) (xy 283.98657 -281.737548)
			(xy 283.986224 -281.732228) (xy 277.94204 -281.732228) (xy 277.941527 -281.737486) (xy 277.93409 -281.744926)
			(xy 277.928832 -281.745436) (xy 277.412958 -281.745436) (xy 277.405083 -281.745715) (xy 277.390079 -281.750505)
			(xy 277.383494 -281.754834) (xy 277.362407 -281.769212) (xy 277.316766 -281.792043) (xy 277.268163 -281.807605)
			(xy 277.217748 -281.815529) (xy 277.192232 -281.816048) (xy 277.166712 -281.815551) (xy 277.116286 -281.807657)
			(xy 277.067675 -281.792099) (xy 277.022036 -281.769247) (xy 277.00097 -281.754834) (xy 276.994385 -281.750508)
			(xy 276.97938 -281.745728) (xy 276.971506 -281.745436) (xy 276.455632 -281.745436) (xy 276.450311 -281.745054)
			(xy 276.44277 -281.737548) (xy 276.442424 -281.732228) (xy 270.39824 -281.732228) (xy 270.397727 -281.737486)
			(xy 270.39029 -281.744926) (xy 270.385032 -281.745436) (xy 270.384524 -281.745436) (xy 269.868904 -281.745436)
			(xy 269.861031 -281.745735) (xy 269.846027 -281.750511) (xy 269.83944 -281.754834) (xy 269.818369 -281.769235)
			(xy 269.772722 -281.792061) (xy 269.724114 -281.807617) (xy 269.673695 -281.815533) (xy 269.648178 -281.816048)
			(xy 269.622659 -281.815528) (xy 269.572234 -281.807641) (xy 269.523622 -281.79209) (xy 269.477982 -281.769244)
			(xy 269.456916 -281.754834) (xy 269.450321 -281.750526) (xy 269.435324 -281.745734) (xy 269.427452 -281.745436)
			(xy 268.911578 -281.745436) (xy 268.906266 -281.744989) (xy 268.898694 -281.737532) (xy 268.898116 -281.732228)
			(xy 206.997808 -281.732228) (xy 206.997808 -281.732482) (xy 206.997271 -281.737773) (xy 206.989878 -281.745342)
			(xy 206.9846 -281.745944) (xy 206.468726 -281.745944) (xy 206.460916 -281.746262) (xy 206.446044 -281.751044)
			(xy 206.439516 -281.755342) (xy 206.418387 -281.769679) (xy 206.372666 -281.792409) (xy 206.323995 -281.807842)
			(xy 206.27353 -281.815613) (xy 206.248 -281.816048) (xy 206.22247 -281.815614) (xy 206.172006 -281.807838)
			(xy 206.123333 -281.792408) (xy 206.077606 -281.76969) (xy 206.056484 -281.755342) (xy 206.049953 -281.75105)
			(xy 206.035083 -281.746267) (xy 206.027274 -281.745944) (xy 205.5114 -281.745944) (xy 205.506146 -281.745409)
			(xy 205.498706 -281.737989) (xy 205.498192 -281.732736) (xy 199.453982 -281.732736) (xy 199.453471 -281.737773)
			(xy 199.446078 -281.745342) (xy 199.4408 -281.745944) (xy 198.924926 -281.745944) (xy 198.917116 -281.746262)
			(xy 198.902244 -281.751044) (xy 198.895716 -281.755342) (xy 198.874587 -281.769679) (xy 198.828866 -281.792409)
			(xy 198.780195 -281.807842) (xy 198.72973 -281.815613) (xy 198.7042 -281.816048) (xy 198.67867 -281.815614)
			(xy 198.628206 -281.807838) (xy 198.579533 -281.792408) (xy 198.533806 -281.76969) (xy 198.512684 -281.755342)
			(xy 198.506153 -281.75105) (xy 198.491283 -281.746267) (xy 198.483474 -281.745944) (xy 197.9676 -281.745944)
			(xy 197.962346 -281.745409) (xy 197.954906 -281.737989) (xy 197.954392 -281.732736) (xy 191.910181 -281.732736)
			(xy 191.909642 -281.737833) (xy 191.902094 -281.745417) (xy 191.896746 -281.745944) (xy 191.380872 -281.745944)
			(xy 191.37306 -281.746238) (xy 191.358188 -281.751037) (xy 191.351662 -281.755342) (xy 191.330548 -281.769703)
			(xy 191.284821 -281.792427) (xy 191.236146 -281.807854) (xy 191.185678 -281.815617) (xy 191.160146 -281.816048)
			(xy 191.134616 -281.815591) (xy 191.084153 -281.807822) (xy 191.035481 -281.792399) (xy 190.989752 -281.769687)
			(xy 190.96863 -281.755342) (xy 190.962089 -281.751068) (xy 190.947226 -281.746274) (xy 190.93942 -281.745944)
			(xy 190.423546 -281.745944) (xy 190.418113 -281.745588) (xy 190.410423 -281.737914) (xy 190.410084 -281.732482)
			(xy 184.3659 -281.732482) (xy 184.36537 -281.737775) (xy 184.357972 -281.745345) (xy 184.352692 -281.745944)
			(xy 183.836818 -281.745944) (xy 183.829008 -281.746258) (xy 183.814136 -281.751043) (xy 183.807608 -281.755342)
			(xy 183.786481 -281.769683) (xy 183.740759 -281.792412) (xy 183.692088 -281.807844) (xy 183.641623 -281.815613)
			(xy 183.616092 -281.816048) (xy 183.590561 -281.815618) (xy 183.540097 -281.807841) (xy 183.491425 -281.79241)
			(xy 183.445698 -281.769691) (xy 183.424576 -281.755342) (xy 183.418047 -281.751047) (xy 183.403175 -281.746266)
			(xy 183.395366 -281.745944) (xy 182.879492 -281.745944) (xy 182.874237 -281.745414) (xy 182.866797 -281.73799)
			(xy 182.866284 -281.732736) (xy 176.822074 -281.732736) (xy 176.821542 -281.737835) (xy 176.813989 -281.745419)
			(xy 176.808638 -281.745944) (xy 176.292764 -281.745944) (xy 176.284956 -281.746278) (xy 176.270084 -281.751049)
			(xy 176.263554 -281.755342) (xy 176.242442 -281.769706) (xy 176.196715 -281.79243) (xy 176.148039 -281.807856)
			(xy 176.09757 -281.815618) (xy 176.072038 -281.816048) (xy 176.046508 -281.815595) (xy 175.996045 -281.807825)
			(xy 175.947372 -281.7924) (xy 175.901644 -281.769688) (xy 175.880522 -281.755342) (xy 175.873982 -281.751065)
			(xy 175.859119 -281.746272) (xy 175.851312 -281.745944) (xy 175.335438 -281.745944) (xy 175.330004 -281.745594)
			(xy 175.322314 -281.737916) (xy 175.321976 -281.732482) (xy 169.277792 -281.732482) (xy 169.277269 -281.737777)
			(xy 169.269866 -281.745347) (xy 169.264584 -281.745944) (xy 167.791384 -281.745944) (xy 167.786128 -281.74542)
			(xy 167.778688 -281.737991) (xy 167.778176 -281.732736) (xy 60.178162 -281.732736) (xy 60.17764 -281.737838)
			(xy 60.17008 -281.745423) (xy 60.164726 -281.745944) (xy 58.691526 -281.745944) (xy 58.68609 -281.745602)
			(xy 58.678402 -281.737918) (xy 58.678064 -281.732482) (xy 52.63388 -281.732482) (xy 52.633367 -281.737779)
			(xy 52.625958 -281.74535) (xy 52.620672 -281.745944) (xy 52.104798 -281.745944) (xy 52.096987 -281.746249)
			(xy 52.082115 -281.75104) (xy 52.075588 -281.755342) (xy 52.054466 -281.769691) (xy 52.008743 -281.792418)
			(xy 51.960069 -281.807848) (xy 51.909603 -281.815615) (xy 51.884072 -281.816048) (xy 51.858541 -281.815628)
			(xy 51.808076 -281.807848) (xy 51.759404 -281.792414) (xy 51.713677 -281.769692) (xy 51.692556 -281.755342)
			(xy 51.686031 -281.751039) (xy 51.671156 -281.746263) (xy 51.663346 -281.745944) (xy 51.147472 -281.745944)
			(xy 51.142215 -281.745428) (xy 51.134775 -281.737993) (xy 51.134264 -281.732736) (xy 45.090054 -281.732736)
			(xy 45.08954 -281.73784) (xy 45.081974 -281.745425) (xy 45.076618 -281.745944) (xy 44.560744 -281.745944)
			(xy 44.552935 -281.746269) (xy 44.538063 -281.751047) (xy 44.531534 -281.755342) (xy 44.510428 -281.769715)
			(xy 44.464698 -281.792436) (xy 44.41602 -281.80786) (xy 44.36555 -281.815619) (xy 44.340018 -281.816048)
			(xy 44.314488 -281.815605) (xy 44.264024 -281.807832) (xy 44.215352 -281.792405) (xy 44.169624 -281.769689)
			(xy 44.148502 -281.755342) (xy 44.141967 -281.751057) (xy 44.1271 -281.746269) (xy 44.119292 -281.745944)
			(xy 43.603418 -281.745944) (xy 43.597981 -281.745607) (xy 43.590293 -281.737919) (xy 43.589956 -281.732482)
			(xy 37.545772 -281.732482) (xy 37.545266 -281.737781) (xy 37.537852 -281.745353) (xy 37.532564 -281.745944)
			(xy 37.01669 -281.745944) (xy 37.008879 -281.746246) (xy 36.994007 -281.751039) (xy 36.98748 -281.755342)
			(xy 36.966361 -281.769695) (xy 36.920636 -281.792421) (xy 36.871962 -281.80785) (xy 36.821495 -281.815616)
			(xy 36.795964 -281.816048) (xy 36.770433 -281.815632) (xy 36.719968 -281.807851) (xy 36.671296 -281.792415)
			(xy 36.625569 -281.769693) (xy 36.604448 -281.755342) (xy 36.597925 -281.751036) (xy 36.583048 -281.746262)
			(xy 36.575238 -281.745944) (xy 36.059364 -281.745944) (xy 36.054106 -281.745433) (xy 36.046667 -281.737994)
			(xy 36.046156 -281.732736) (xy 30.001948 -281.732736) (xy 30.001466 -281.737781) (xy 29.994052 -281.745353)
			(xy 29.988764 -281.745944) (xy 29.47289 -281.745944) (xy 29.465079 -281.746246) (xy 29.450207 -281.751039)
			(xy 29.44368 -281.755342) (xy 29.422561 -281.769695) (xy 29.376836 -281.792421) (xy 29.328162 -281.80785)
			(xy 29.277695 -281.815616) (xy 29.252164 -281.816048) (xy 29.226633 -281.815632) (xy 29.176168 -281.807851)
			(xy 29.127496 -281.792415) (xy 29.081769 -281.769693) (xy 29.060648 -281.755342) (xy 29.054125 -281.751036)
			(xy 29.039248 -281.746262) (xy 29.031438 -281.745944) (xy 28.515564 -281.745944) (xy 28.510306 -281.745433)
			(xy 28.502867 -281.737994) (xy 28.502356 -281.732736) (xy 22.458155 -281.732736) (xy 22.45781 -281.737912)
			(xy 22.450139 -281.745599) (xy 22.44471 -281.745944) (xy 21.928836 -281.745944) (xy 21.921027 -281.746266)
			(xy 21.906155 -281.751046) (xy 21.899626 -281.755342) (xy 21.878494 -281.769675) (xy 21.832774 -281.792406)
			(xy 21.784104 -281.80784) (xy 21.73364 -281.815612) (xy 21.70811 -281.816048) (xy 21.68258 -281.815609)
			(xy 21.632116 -281.807835) (xy 21.583443 -281.792406) (xy 21.537716 -281.76969) (xy 21.516594 -281.755342)
			(xy 21.510061 -281.751054) (xy 21.495192 -281.746268) (xy 21.487384 -281.745944) (xy 20.97151 -281.745944)
			(xy 20.966072 -281.745612) (xy 20.958384 -281.73792) (xy 20.958048 -281.732482) (xy 2.509012 -281.732482)
			(xy 2.509012 -282.582366) (xy 16.85798 -282.582366) (xy 16.85798 -282.087828) (xy 16.858344 -282.082502)
			(xy 16.865863 -282.07496) (xy 16.871188 -282.07462) (xy 16.871696 -282.07462) (xy 17.38757 -282.07462)
			(xy 17.39538 -282.074307) (xy 17.410252 -282.069522) (xy 17.41678 -282.065222) (xy 17.437869 -282.050873)
			(xy 17.48353 -282.028142) (xy 17.532136 -282.012683) (xy 17.582539 -282.00486) (xy 17.633545 -282.00486)
			(xy 17.683948 -282.012683) (xy 17.732554 -282.028142) (xy 17.778215 -282.050873) (xy 17.799304 -282.065222)
			(xy 17.80584 -282.069506) (xy 17.820706 -282.074295) (xy 17.828514 -282.07462) (xy 18.344642 -282.07462)
			(xy 18.349947 -282.075093) (xy 18.357514 -282.082533) (xy 18.358104 -282.087828) (xy 18.358104 -282.582366)
			(xy 18.358077 -282.58262) (xy 24.402288 -282.58262) (xy 24.402288 -282.582112) (xy 24.402288 -282.087828)
			(xy 24.402645 -282.0825) (xy 24.410169 -282.074958) (xy 24.415496 -282.07462) (xy 24.931624 -282.07462)
			(xy 24.939436 -282.07433) (xy 24.954308 -282.069529) (xy 24.960834 -282.065222) (xy 24.981923 -282.050873)
			(xy 25.027584 -282.028142) (xy 25.07619 -282.012683) (xy 25.126593 -282.00486) (xy 25.177599 -282.00486)
			(xy 25.228002 -282.012683) (xy 25.276608 -282.028142) (xy 25.322269 -282.050873) (xy 25.343358 -282.065222)
			(xy 25.349882 -282.069527) (xy 25.364758 -282.074303) (xy 25.372568 -282.07462) (xy 25.888696 -282.07462)
			(xy 25.894034 -282.074932) (xy 25.901577 -282.082489) (xy 25.901904 -282.087828) (xy 25.901904 -282.582366)
			(xy 25.901878 -282.58262) (xy 31.946088 -282.58262) (xy 31.946088 -282.582112) (xy 31.946088 -282.087828)
			(xy 31.946445 -282.0825) (xy 31.953969 -282.074958) (xy 31.959296 -282.07462) (xy 32.475424 -282.07462)
			(xy 32.483236 -282.07433) (xy 32.498108 -282.069529) (xy 32.504634 -282.065222) (xy 32.525723 -282.050873)
			(xy 32.571384 -282.028142) (xy 32.61999 -282.012683) (xy 32.670393 -282.00486) (xy 32.721399 -282.00486)
			(xy 32.771802 -282.012683) (xy 32.820408 -282.028142) (xy 32.866069 -282.050873) (xy 32.887158 -282.065222)
			(xy 32.893682 -282.069527) (xy 32.908558 -282.074303) (xy 32.916368 -282.07462) (xy 33.432496 -282.07462)
			(xy 33.437834 -282.074932) (xy 33.445377 -282.082489) (xy 33.445704 -282.087828) (xy 33.445704 -282.582366)
			(xy 39.489888 -282.582366) (xy 39.489888 -282.087828) (xy 39.490245 -282.0825) (xy 39.497769 -282.074958)
			(xy 39.503096 -282.07462) (xy 39.503604 -282.07462) (xy 40.019478 -282.07462) (xy 40.027289 -282.07431)
			(xy 40.042161 -282.069523) (xy 40.048688 -282.065222) (xy 40.069777 -282.050873) (xy 40.115438 -282.028142)
			(xy 40.164044 -282.012683) (xy 40.214447 -282.00486) (xy 40.265453 -282.00486) (xy 40.315856 -282.012683)
			(xy 40.364462 -282.028142) (xy 40.410123 -282.050873) (xy 40.431212 -282.065222) (xy 40.437746 -282.069509)
			(xy 40.452614 -282.074296) (xy 40.460422 -282.07462) (xy 40.97655 -282.07462) (xy 40.981844 -282.075154)
			(xy 40.989416 -282.082547) (xy 40.990012 -282.087828) (xy 40.990012 -282.582366) (xy 40.989984 -282.58262)
			(xy 47.034196 -282.58262) (xy 47.034196 -282.582112) (xy 47.034196 -282.087828) (xy 47.034546 -282.082498)
			(xy 47.042075 -282.074956) (xy 47.047404 -282.07462) (xy 47.563532 -282.07462) (xy 47.571341 -282.074291)
			(xy 47.586213 -282.069517) (xy 47.592742 -282.065222) (xy 47.613831 -282.050873) (xy 47.659492 -282.028142)
			(xy 47.708098 -282.012683) (xy 47.758501 -282.00486) (xy 47.809507 -282.00486) (xy 47.85991 -282.012683)
			(xy 47.908516 -282.028142) (xy 47.954177 -282.050873) (xy 47.975266 -282.065222) (xy 47.98181 -282.069492)
			(xy 47.99667 -282.074289) (xy 48.004476 -282.07462) (xy 48.520604 -282.07462) (xy 48.525944 -282.074927)
			(xy 48.533486 -282.082488) (xy 48.533812 -282.087828) (xy 48.533812 -282.582366) (xy 54.577996 -282.582366)
			(xy 54.577996 -282.087828) (xy 54.578346 -282.082498) (xy 54.585875 -282.074956) (xy 54.591204 -282.07462)
			(xy 56.064658 -282.07462) (xy 56.069953 -282.075149) (xy 56.077525 -282.082546) (xy 56.07812 -282.087828)
			(xy 56.07812 -282.1864) (xy 108.485149 -282.1864) (xy 108.48932 -282.136059) (xy 108.50172 -282.087092)
			(xy 108.522011 -282.040833) (xy 108.549639 -281.998544) (xy 108.58385 -281.96138) (xy 108.623712 -281.930354)
			(xy 108.668137 -281.906312) (xy 108.715913 -281.889909) (xy 108.765737 -281.881594) (xy 108.790994 -281.881072)
			(xy 109.731048 -281.881072) (xy 109.756299 -281.881637) (xy 109.806111 -281.889957) (xy 109.853875 -281.906361)
			(xy 109.898288 -281.930402) (xy 109.938139 -281.961425) (xy 109.97234 -281.998583) (xy 109.99996 -282.040863)
			(xy 110.020245 -282.087113) (xy 110.032641 -282.13607) (xy 110.036811 -282.1864) (xy 114.11882 -282.1864)
			(xy 114.122992 -282.136052) (xy 114.135394 -282.087078) (xy 114.155689 -282.040813) (xy 114.183321 -281.99852)
			(xy 114.217539 -281.961352) (xy 114.257407 -281.930323) (xy 114.301839 -281.906279) (xy 114.349622 -281.889877)
			(xy 114.399454 -281.881564) (xy 114.424714 -281.881072) (xy 115.364768 -281.881072) (xy 115.390026 -281.881602)
			(xy 115.439853 -281.889912) (xy 115.487633 -281.90631) (xy 115.532062 -281.93035) (xy 115.571927 -281.961375)
			(xy 115.606142 -281.998539) (xy 115.633773 -282.040827) (xy 115.654067 -282.087088) (xy 115.666468 -282.136057)
			(xy 115.67064 -282.1864) (xy 115.666468 -282.236743) (xy 115.654067 -282.285712) (xy 115.633773 -282.331973)
			(xy 115.606142 -282.374261) (xy 115.571927 -282.411425) (xy 115.532062 -282.44245) (xy 115.487633 -282.46649)
			(xy 115.439853 -282.482888) (xy 115.390026 -282.491198) (xy 115.364768 -282.491688) (xy 114.424714 -282.491688)
			(xy 114.399454 -282.491236) (xy 114.349622 -282.482923) (xy 114.301839 -282.466521) (xy 114.257407 -282.442477)
			(xy 114.217539 -282.411448) (xy 114.183321 -282.37428) (xy 114.155689 -282.331987) (xy 114.135394 -282.285722)
			(xy 114.122992 -282.236748) (xy 114.11882 -282.1864) (xy 110.036811 -282.1864) (xy 110.032641 -282.23673)
			(xy 110.020245 -282.285687) (xy 109.99996 -282.331937) (xy 109.97234 -282.374217) (xy 109.938139 -282.411375)
			(xy 109.898288 -282.442398) (xy 109.853875 -282.466439) (xy 109.806111 -282.482843) (xy 109.756299 -282.491163)
			(xy 109.731048 -282.491688) (xy 108.790994 -282.491688) (xy 108.765737 -282.491206) (xy 108.715913 -282.482891)
			(xy 108.668137 -282.466488) (xy 108.623712 -282.442446) (xy 108.58385 -282.41142) (xy 108.549639 -282.374256)
			(xy 108.522011 -282.331967) (xy 108.50172 -282.285708) (xy 108.48932 -282.236741) (xy 108.485149 -282.1864)
			(xy 56.07812 -282.1864) (xy 56.07812 -282.582366) (xy 56.078105 -282.58262) (xy 163.678108 -282.58262)
			(xy 163.678108 -282.582112) (xy 163.678108 -282.087828) (xy 163.678447 -282.082496) (xy 163.685984 -282.074952)
			(xy 163.691316 -282.07462) (xy 165.164516 -282.07462) (xy 165.169857 -282.074919) (xy 165.177399 -282.082486)
			(xy 165.177724 -282.087828) (xy 165.177724 -282.582366) (xy 171.221908 -282.582366) (xy 171.221908 -282.087828)
			(xy 171.222247 -282.082496) (xy 171.229784 -282.074952) (xy 171.235116 -282.07462) (xy 171.235624 -282.07462)
			(xy 171.751498 -282.07462) (xy 171.759309 -282.074319) (xy 171.774181 -282.069526) (xy 171.780708 -282.065222)
			(xy 171.801797 -282.050873) (xy 171.847458 -282.028142) (xy 171.896064 -282.012683) (xy 171.946467 -282.00486)
			(xy 171.997473 -282.00486) (xy 172.047876 -282.012683) (xy 172.096482 -282.028142) (xy 172.142143 -282.050873)
			(xy 172.163232 -282.065222) (xy 172.169762 -282.069517) (xy 172.184633 -282.074299) (xy 172.192442 -282.07462)
			(xy 172.70857 -282.07462) (xy 172.713866 -282.075141) (xy 172.721438 -282.082544) (xy 172.722032 -282.087828)
			(xy 172.722032 -282.582366) (xy 172.722016 -282.58262) (xy 178.766216 -282.58262) (xy 178.766216 -282.582112)
			(xy 178.766216 -282.087828) (xy 178.766548 -282.082494) (xy 178.77409 -282.074949) (xy 178.779424 -282.07462)
			(xy 179.295552 -282.07462) (xy 179.303362 -282.074299) (xy 179.318234 -282.06952) (xy 179.324762 -282.065222)
			(xy 179.345851 -282.050873) (xy 179.391512 -282.028142) (xy 179.440118 -282.012683) (xy 179.490521 -282.00486)
			(xy 179.541527 -282.00486) (xy 179.59193 -282.012683) (xy 179.640536 -282.028142) (xy 179.686197 -282.050873)
			(xy 179.707286 -282.065222) (xy 179.713826 -282.069499) (xy 179.728689 -282.074292) (xy 179.736496 -282.07462)
			(xy 180.252624 -282.07462) (xy 180.257966 -282.074914) (xy 180.265507 -282.082484) (xy 180.265832 -282.087828)
			(xy 180.265832 -282.582366) (xy 186.310016 -282.582366) (xy 186.310016 -282.087828) (xy 186.310348 -282.082494)
			(xy 186.31789 -282.074949) (xy 186.323224 -282.07462) (xy 186.323732 -282.07462) (xy 186.839606 -282.07462)
			(xy 186.847418 -282.074322) (xy 186.86229 -282.069527) (xy 186.868816 -282.065222) (xy 186.889905 -282.050873)
			(xy 186.935566 -282.028142) (xy 186.984172 -282.012683) (xy 187.034575 -282.00486) (xy 187.085581 -282.00486)
			(xy 187.135984 -282.012683) (xy 187.18459 -282.028142) (xy 187.230251 -282.050873) (xy 187.25134 -282.065222)
			(xy 187.257868 -282.06952) (xy 187.27274 -282.0743) (xy 187.28055 -282.07462) (xy 187.796678 -282.07462)
			(xy 187.801975 -282.075135) (xy 187.809546 -282.082543) (xy 187.81014 -282.087828) (xy 187.81014 -282.582366)
			(xy 187.810124 -282.58262) (xy 193.854324 -282.58262) (xy 193.854324 -282.582112) (xy 193.854324 -282.087828)
			(xy 193.854649 -282.082492) (xy 193.862196 -282.074947) (xy 193.867532 -282.07462) (xy 194.38366 -282.07462)
			(xy 194.39147 -282.074303) (xy 194.406342 -282.069521) (xy 194.41287 -282.065222) (xy 194.433959 -282.050873)
			(xy 194.47962 -282.028142) (xy 194.528226 -282.012683) (xy 194.578629 -282.00486) (xy 194.629635 -282.00486)
			(xy 194.680038 -282.012683) (xy 194.728644 -282.028142) (xy 194.774305 -282.050873) (xy 194.795394 -282.065222)
			(xy 194.801932 -282.069502) (xy 194.816797 -282.074294) (xy 194.824604 -282.07462) (xy 195.340732 -282.07462)
			(xy 195.346005 -282.075076) (xy 195.353448 -282.082552) (xy 195.35394 -282.087828) (xy 195.35394 -282.582366)
			(xy 195.353917 -282.58262) (xy 201.398124 -282.58262) (xy 201.398124 -282.582112) (xy 201.398124 -282.087828)
			(xy 201.398449 -282.082492) (xy 201.405996 -282.074947) (xy 201.411332 -282.07462) (xy 201.92746 -282.07462)
			(xy 201.93527 -282.074303) (xy 201.950142 -282.069521) (xy 201.95667 -282.065222) (xy 201.977759 -282.050873)
			(xy 202.02342 -282.028142) (xy 202.072026 -282.012683) (xy 202.122429 -282.00486) (xy 202.173435 -282.00486)
			(xy 202.223838 -282.012683) (xy 202.272444 -282.028142) (xy 202.318105 -282.050873) (xy 202.339194 -282.065222)
			(xy 202.345732 -282.069502) (xy 202.360597 -282.074294) (xy 202.368404 -282.07462) (xy 202.884532 -282.07462)
			(xy 202.889805 -282.075076) (xy 202.897248 -282.082552) (xy 202.89774 -282.087828) (xy 202.89774 -282.582112)
			(xy 264.798048 -282.582112) (xy 264.798048 -282.087574) (xy 264.798534 -282.082205) (xy 264.806139 -282.07462)
			(xy 264.81151 -282.074112) (xy 265.327638 -282.074112) (xy 265.335447 -282.073787) (xy 265.350319 -282.06901)
			(xy 265.356848 -282.064714) (xy 265.377937 -282.050365) (xy 265.423598 -282.027634) (xy 265.472204 -282.012175)
			(xy 265.522607 -282.004352) (xy 265.573613 -282.004352) (xy 265.624016 -282.012175) (xy 265.672622 -282.027634)
			(xy 265.718283 -282.050365) (xy 265.739372 -282.064714) (xy 265.745916 -282.068985) (xy 265.760776 -282.073782)
			(xy 265.768582 -282.074112) (xy 266.28471 -282.074112) (xy 266.290069 -282.074641) (xy 266.297652 -282.082216)
			(xy 266.298172 -282.087574) (xy 266.298172 -282.582112) (xy 272.342356 -282.582112) (xy 272.342356 -282.087574)
			(xy 272.342808 -282.082263) (xy 272.350261 -282.074693) (xy 272.355564 -282.074112) (xy 272.871692 -282.074112)
			(xy 272.879503 -282.07381) (xy 272.894375 -282.069017) (xy 272.900902 -282.064714) (xy 272.921991 -282.050365)
			(xy 272.967652 -282.027634) (xy 273.016258 -282.012175) (xy 273.066661 -282.004352) (xy 273.117667 -282.004352)
			(xy 273.16807 -282.012175) (xy 273.216676 -282.027634) (xy 273.262337 -282.050365) (xy 273.283426 -282.064714)
			(xy 273.289957 -282.069006) (xy 273.304827 -282.07379) (xy 273.312636 -282.074112) (xy 273.828764 -282.074112)
			(xy 273.834096 -282.074453) (xy 273.841641 -282.081988) (xy 273.841972 -282.08732) (xy 273.841972 -282.087828)
			(xy 273.841972 -282.582112) (xy 279.886156 -282.582112) (xy 279.886156 -282.087574) (xy 279.886608 -282.082263)
			(xy 279.894061 -282.074693) (xy 279.899364 -282.074112) (xy 280.415492 -282.074112) (xy 280.423303 -282.07381)
			(xy 280.438175 -282.069017) (xy 280.444702 -282.064714) (xy 280.465791 -282.050365) (xy 280.511452 -282.027634)
			(xy 280.560058 -282.012175) (xy 280.610461 -282.004352) (xy 280.661467 -282.004352) (xy 280.71187 -282.012175)
			(xy 280.760476 -282.027634) (xy 280.806137 -282.050365) (xy 280.827226 -282.064714) (xy 280.833757 -282.069006)
			(xy 280.848627 -282.07379) (xy 280.856436 -282.074112) (xy 281.372564 -282.074112) (xy 281.377896 -282.074453)
			(xy 281.385441 -282.081988) (xy 281.385772 -282.08732) (xy 281.385772 -282.087828) (xy 281.385772 -282.582112)
			(xy 287.429956 -282.582112) (xy 287.429956 -282.087574) (xy 287.430435 -282.082203) (xy 287.438045 -282.074618)
			(xy 287.443418 -282.074112) (xy 287.959546 -282.074112) (xy 287.967356 -282.07379) (xy 287.982228 -282.069011)
			(xy 287.988756 -282.064714) (xy 288.009845 -282.050365) (xy 288.055506 -282.027634) (xy 288.104112 -282.012175)
			(xy 288.154515 -282.004352) (xy 288.205521 -282.004352) (xy 288.255924 -282.012175) (xy 288.30453 -282.027634)
			(xy 288.350191 -282.050365) (xy 288.37128 -282.064714) (xy 288.377822 -282.068988) (xy 288.392684 -282.073783)
			(xy 288.40049 -282.074112) (xy 288.916618 -282.074112) (xy 288.921978 -282.074636) (xy 288.929561 -282.082214)
			(xy 288.93008 -282.087574) (xy 288.93008 -282.582112) (xy 294.974264 -282.582112) (xy 294.974264 -282.087574)
			(xy 294.974709 -282.082261) (xy 294.982167 -282.07469) (xy 294.987472 -282.074112) (xy 295.5036 -282.074112)
			(xy 295.511412 -282.073813) (xy 295.526284 -282.069018) (xy 295.53281 -282.064714) (xy 295.553899 -282.050365)
			(xy 295.59956 -282.027634) (xy 295.648166 -282.012175) (xy 295.698569 -282.004352) (xy 295.749575 -282.004352)
			(xy 295.799978 -282.012175) (xy 295.848584 -282.027634) (xy 295.894245 -282.050365) (xy 295.915334 -282.064714)
			(xy 295.921864 -282.069009) (xy 295.936735 -282.073791) (xy 295.944544 -282.074112) (xy 296.460672 -282.074112)
			(xy 296.466005 -282.074447) (xy 296.473549 -282.081987) (xy 296.47388 -282.08732) (xy 296.47388 -282.087828)
			(xy 296.47388 -282.582112) (xy 302.518064 -282.582112) (xy 302.518064 -282.087574) (xy 302.518536 -282.082201)
			(xy 302.526151 -282.074615) (xy 302.531526 -282.074112) (xy 304.004726 -282.074112) (xy 304.010087 -282.074631)
			(xy 304.017669 -282.082213) (xy 304.018188 -282.087574) (xy 304.018188 -282.1861) (xy 356.42504 -282.1861)
			(xy 356.429214 -282.135728) (xy 356.441621 -282.08673) (xy 356.461923 -282.040442) (xy 356.489566 -281.998127)
			(xy 356.523797 -281.960938) (xy 356.563681 -281.92989) (xy 356.608132 -281.90583) (xy 356.655936 -281.889414)
			(xy 356.70579 -281.881089) (xy 356.731062 -281.880564) (xy 357.671116 -281.880564) (xy 357.696394 -281.881035)
			(xy 357.746259 -281.889359) (xy 357.794074 -281.905776) (xy 357.838536 -281.929839) (xy 357.87843 -281.960892)
			(xy 357.912669 -281.998088) (xy 357.940319 -282.040411) (xy 357.960627 -282.086709) (xy 357.973037 -282.135717)
			(xy 357.977212 -282.1861) (xy 362.05874 -282.1861) (xy 362.062914 -282.135726) (xy 362.075322 -282.086726)
			(xy 362.095626 -282.040437) (xy 362.123271 -281.99812) (xy 362.157505 -281.960931) (xy 362.197392 -281.929883)
			(xy 362.241845 -281.905824) (xy 362.289652 -281.88941) (xy 362.339509 -281.881087) (xy 362.364782 -281.880564)
			(xy 363.304836 -281.880564) (xy 363.330113 -281.881037) (xy 363.379975 -281.889363) (xy 363.427788 -281.905782)
			(xy 363.472246 -281.929846) (xy 363.512138 -281.960899) (xy 363.546374 -281.998094) (xy 363.574022 -282.040417)
			(xy 363.594328 -282.086713) (xy 363.606737 -282.135719) (xy 363.610912 -282.1861) (xy 363.606737 -282.236481)
			(xy 363.594328 -282.285487) (xy 363.574022 -282.331783) (xy 363.546374 -282.374106) (xy 363.512138 -282.411301)
			(xy 363.472246 -282.442354) (xy 363.427788 -282.466418) (xy 363.379975 -282.482837) (xy 363.330113 -282.491163)
			(xy 363.304836 -282.491688) (xy 362.364782 -282.491688) (xy 362.339509 -282.491113) (xy 362.289652 -282.48279)
			(xy 362.241845 -282.466376) (xy 362.197392 -282.442317) (xy 362.157505 -282.411269) (xy 362.123271 -282.37408)
			(xy 362.095626 -282.331763) (xy 362.075322 -282.285474) (xy 362.062914 -282.236474) (xy 362.05874 -282.1861)
			(xy 357.977212 -282.1861) (xy 357.973037 -282.236483) (xy 357.960627 -282.285491) (xy 357.940319 -282.331789)
			(xy 357.912669 -282.374112) (xy 357.87843 -282.411308) (xy 357.838536 -282.442361) (xy 357.794074 -282.466424)
			(xy 357.746259 -282.482841) (xy 357.696394 -282.491165) (xy 357.671116 -282.491688) (xy 356.731062 -282.491688)
			(xy 356.70579 -282.491111) (xy 356.655936 -282.482786) (xy 356.608132 -282.46637) (xy 356.563681 -282.44231)
			(xy 356.523797 -282.411262) (xy 356.489566 -282.374073) (xy 356.461923 -282.331758) (xy 356.441621 -282.28547)
			(xy 356.429214 -282.236472) (xy 356.42504 -282.1861) (xy 304.018188 -282.1861) (xy 304.018188 -282.582112)
			(xy 411.618176 -282.582112) (xy 411.618176 -282.087574) (xy 411.61861 -282.082258) (xy 411.626076 -282.074687)
			(xy 411.631384 -282.074112) (xy 413.104584 -282.074112) (xy 413.109919 -282.07444) (xy 413.117462 -282.081985)
			(xy 413.117792 -282.08732) (xy 413.117792 -282.087828) (xy 413.117792 -282.582112) (xy 419.161976 -282.582112)
			(xy 419.161976 -282.087574) (xy 419.162265 -282.082126) (xy 419.169989 -282.07444) (xy 419.175438 -282.074112)
			(xy 419.691566 -282.074112) (xy 419.699376 -282.073799) (xy 419.714248 -282.069014) (xy 419.720776 -282.064714)
			(xy 419.741865 -282.050365) (xy 419.787526 -282.027634) (xy 419.836132 -282.012175) (xy 419.886535 -282.004352)
			(xy 419.937541 -282.004352) (xy 419.987944 -282.012175) (xy 420.03655 -282.027634) (xy 420.082211 -282.050365)
			(xy 420.1033 -282.064714) (xy 420.109837 -282.068996) (xy 420.124703 -282.073786) (xy 420.13251 -282.074112)
			(xy 420.648638 -282.074112) (xy 420.654 -282.074623) (xy 420.661582 -282.082211) (xy 420.6621 -282.087574)
			(xy 420.6621 -282.582112) (xy 426.706284 -282.582112) (xy 426.706284 -282.087574) (xy 426.706711 -282.082256)
			(xy 426.714182 -282.074684) (xy 426.719492 -282.074112) (xy 427.23562 -282.074112) (xy 427.243432 -282.073821)
			(xy 427.258304 -282.069021) (xy 427.26483 -282.064714) (xy 427.285919 -282.050365) (xy 427.33158 -282.027634)
			(xy 427.380186 -282.012175) (xy 427.430589 -282.004352) (xy 427.481595 -282.004352) (xy 427.531998 -282.012175)
			(xy 427.580604 -282.027634) (xy 427.626265 -282.050365) (xy 427.647354 -282.064714) (xy 427.653879 -282.069017)
			(xy 427.668754 -282.073794) (xy 427.676564 -282.074112) (xy 428.192692 -282.074112) (xy 428.198028 -282.074434)
			(xy 428.205571 -282.081984) (xy 428.2059 -282.08732) (xy 428.2059 -282.087828) (xy 428.2059 -282.582112)
			(xy 434.250084 -282.582112) (xy 434.250084 -282.087574) (xy 434.250366 -282.082124) (xy 434.258095 -282.074437)
			(xy 434.263546 -282.074112) (xy 434.779674 -282.074112) (xy 434.787485 -282.073802) (xy 434.802357 -282.069015)
			(xy 434.808884 -282.064714) (xy 434.829973 -282.050365) (xy 434.875634 -282.027634) (xy 434.92424 -282.012175)
			(xy 434.974643 -282.004352) (xy 435.025649 -282.004352) (xy 435.076052 -282.012175) (xy 435.124658 -282.027634)
			(xy 435.170319 -282.050365) (xy 435.191408 -282.064714) (xy 435.197943 -282.068999) (xy 435.21281 -282.073788)
			(xy 435.220618 -282.074112) (xy 435.736746 -282.074112) (xy 435.742109 -282.074617) (xy 435.749691 -282.08221)
			(xy 435.750208 -282.087574) (xy 435.750208 -282.582112) (xy 441.794392 -282.582112) (xy 441.794392 -282.087574)
			(xy 441.7949 -282.082278) (xy 441.802315 -282.074711) (xy 441.8076 -282.074112) (xy 442.323728 -282.074112)
			(xy 442.331541 -282.073825) (xy 442.346413 -282.069022) (xy 442.352938 -282.064714) (xy 442.374027 -282.050365)
			(xy 442.419688 -282.027634) (xy 442.468294 -282.012175) (xy 442.518697 -282.004352) (xy 442.569703 -282.004352)
			(xy 442.620106 -282.012175) (xy 442.668712 -282.027634) (xy 442.714373 -282.050365) (xy 442.735462 -282.064714)
			(xy 442.742008 -282.068981) (xy 442.756867 -282.073781) (xy 442.764672 -282.074112) (xy 443.2808 -282.074112)
			(xy 443.286137 -282.074429) (xy 443.293679 -282.081982) (xy 443.294008 -282.08732) (xy 443.294008 -282.087828)
			(xy 443.294008 -282.582112) (xy 449.338192 -282.582112) (xy 449.338192 -282.087574) (xy 449.3387 -282.082278)
			(xy 449.346115 -282.074711) (xy 449.3514 -282.074112) (xy 449.867528 -282.074112) (xy 449.875341 -282.073825)
			(xy 449.890213 -282.069022) (xy 449.896738 -282.064714) (xy 449.917827 -282.050365) (xy 449.963488 -282.027634)
			(xy 450.012094 -282.012175) (xy 450.062497 -282.004352) (xy 450.113503 -282.004352) (xy 450.163906 -282.012175)
			(xy 450.212512 -282.027634) (xy 450.258173 -282.050365) (xy 450.279262 -282.064714) (xy 450.285808 -282.068981)
			(xy 450.300667 -282.073781) (xy 450.308472 -282.074112) (xy 450.8246 -282.074112) (xy 450.829937 -282.074429)
			(xy 450.837479 -282.081982) (xy 450.837808 -282.08732) (xy 450.837808 -282.087828) (xy 450.837808 -282.582112)
			(xy 450.837313 -282.587376) (xy 450.829865 -282.594818) (xy 450.8246 -282.59532) (xy 450.308726 -282.59532)
			(xy 450.30085 -282.595589) (xy 450.285846 -282.600386) (xy 450.279262 -282.604718) (xy 450.258183 -282.619107)
			(xy 450.212539 -282.641937) (xy 450.163933 -282.657496) (xy 450.113517 -282.665415) (xy 450.088 -282.665932)
			(xy 450.062479 -282.665454) (xy 450.012052 -282.657555) (xy 449.963441 -282.641991) (xy 449.917803 -282.619134)
			(xy 449.896738 -282.604718) (xy 449.890139 -282.600417) (xy 449.875145 -282.595621) (xy 449.867274 -282.59532)
			(xy 449.3514 -282.59532) (xy 449.34614 -282.594806) (xy 449.338698 -282.587371) (xy 449.338192 -282.582112)
			(xy 443.294008 -282.582112) (xy 443.293513 -282.587376) (xy 443.286065 -282.594818) (xy 443.2808 -282.59532)
			(xy 442.764926 -282.59532) (xy 442.75705 -282.595589) (xy 442.742046 -282.600386) (xy 442.735462 -282.604718)
			(xy 442.714383 -282.619107) (xy 442.668739 -282.641937) (xy 442.620133 -282.657496) (xy 442.569717 -282.665415)
			(xy 442.5442 -282.665932) (xy 442.518679 -282.665454) (xy 442.468252 -282.657555) (xy 442.419641 -282.641991)
			(xy 442.374003 -282.619134) (xy 442.352938 -282.604718) (xy 442.346339 -282.600417) (xy 442.331345 -282.595621)
			(xy 442.323474 -282.59532) (xy 441.8076 -282.59532) (xy 441.80234 -282.594806) (xy 441.794898 -282.587371)
			(xy 441.794392 -282.582112) (xy 435.750208 -282.582112) (xy 435.749713 -282.587376) (xy 435.742265 -282.594818)
			(xy 435.737 -282.59532) (xy 435.736492 -282.59532) (xy 435.220872 -282.59532) (xy 435.212998 -282.595608)
			(xy 435.197994 -282.600392) (xy 435.191408 -282.604718) (xy 435.170344 -282.619131) (xy 435.124695 -282.641955)
			(xy 435.076084 -282.657507) (xy 435.025664 -282.665419) (xy 435.000146 -282.665932) (xy 434.974626 -282.665431)
			(xy 434.9242 -282.657539) (xy 434.875589 -282.641982) (xy 434.82995 -282.619131) (xy 434.808884 -282.604718)
			(xy 434.802297 -282.600396) (xy 434.787293 -282.595613) (xy 434.77942 -282.59532) (xy 434.263546 -282.59532)
			(xy 434.258238 -282.594841) (xy 434.250662 -282.58741) (xy 434.250084 -282.582112) (xy 428.2059 -282.582112)
			(xy 428.205412 -282.587378) (xy 428.197959 -282.59482) (xy 428.192692 -282.59532) (xy 427.676818 -282.59532)
			(xy 427.668945 -282.595628) (xy 427.653942 -282.600398) (xy 427.647354 -282.604718) (xy 427.626277 -282.619111)
			(xy 427.580633 -282.64194) (xy 427.532026 -282.657497) (xy 427.481609 -282.665416) (xy 427.456092 -282.665932)
			(xy 427.430573 -282.665407) (xy 427.380148 -282.657522) (xy 427.331536 -282.641973) (xy 427.285896 -282.619128)
			(xy 427.26483 -282.604718) (xy 427.258232 -282.600414) (xy 427.243237 -282.59562) (xy 427.235366 -282.59532)
			(xy 426.719492 -282.59532) (xy 426.714231 -282.594812) (xy 426.70679 -282.587373) (xy 426.706284 -282.582112)
			(xy 420.6621 -282.582112) (xy 420.661612 -282.587378) (xy 420.654159 -282.59482) (xy 420.648892 -282.59532)
			(xy 420.648384 -282.59532) (xy 420.132764 -282.59532) (xy 420.124889 -282.595605) (xy 420.109885 -282.600391)
			(xy 420.1033 -282.604718) (xy 420.082211 -282.619091) (xy 420.03657 -282.641924) (xy 419.987968 -282.657488)
			(xy 419.937554 -282.665412) (xy 419.912038 -282.665932) (xy 419.886518 -282.665435) (xy 419.836092 -282.657541)
			(xy 419.78748 -282.641984) (xy 419.741841 -282.619132) (xy 419.720776 -282.604718) (xy 419.71419 -282.600393)
			(xy 419.699186 -282.595612) (xy 419.691312 -282.59532) (xy 419.175438 -282.59532) (xy 419.170129 -282.594847)
			(xy 419.162554 -282.587411) (xy 419.161976 -282.582112) (xy 413.117792 -282.582112) (xy 413.11748 -282.58745)
			(xy 413.109922 -282.594991) (xy 413.104584 -282.59532) (xy 411.631384 -282.59532) (xy 411.626122 -282.594817)
			(xy 411.618681 -282.587374) (xy 411.618176 -282.582112) (xy 304.018188 -282.582112) (xy 304.017879 -282.587451)
			(xy 304.01032 -282.594992) (xy 304.00498 -282.59532) (xy 302.531526 -282.59532) (xy 302.526216 -282.594855)
			(xy 302.518641 -282.587413) (xy 302.518064 -282.582112) (xy 296.47388 -282.582112) (xy 296.473578 -282.587453)
			(xy 296.466014 -282.594995) (xy 296.460672 -282.59532) (xy 295.944798 -282.59532) (xy 295.936925 -282.59562)
			(xy 295.921921 -282.600396) (xy 295.915334 -282.604718) (xy 295.894263 -282.619119) (xy 295.848616 -282.641946)
			(xy 295.800008 -282.657502) (xy 295.749589 -282.665417) (xy 295.724072 -282.665932) (xy 295.698553 -282.665417)
			(xy 295.648127 -282.657529) (xy 295.599516 -282.641977) (xy 295.553876 -282.619129) (xy 295.53281 -282.604718)
			(xy 295.526217 -282.600406) (xy 295.511218 -282.595617) (xy 295.503346 -282.59532) (xy 294.987472 -282.59532)
			(xy 294.982209 -282.594825) (xy 294.974768 -282.587376) (xy 294.974264 -282.582112) (xy 288.93008 -282.582112)
			(xy 288.929778 -282.587453) (xy 288.922214 -282.594995) (xy 288.916872 -282.59532) (xy 288.916364 -282.59532)
			(xy 288.400744 -282.59532) (xy 288.392869 -282.595596) (xy 288.377865 -282.600388) (xy 288.37128 -282.604718)
			(xy 288.350196 -282.6191) (xy 288.304554 -282.641931) (xy 288.25595 -282.657492) (xy 288.205534 -282.665414)
			(xy 288.180018 -282.665932) (xy 288.154498 -282.665445) (xy 288.104071 -282.657548) (xy 288.05546 -282.641988)
			(xy 288.009821 -282.619133) (xy 287.988756 -282.604718) (xy 287.982175 -282.600385) (xy 287.967167 -282.595609)
			(xy 287.959292 -282.59532) (xy 287.443418 -282.59532) (xy 287.438107 -282.59486) (xy 287.430532 -282.587414)
			(xy 287.429956 -282.582112) (xy 281.385772 -282.582112) (xy 281.385478 -282.587455) (xy 281.377908 -282.594997)
			(xy 281.372564 -282.59532) (xy 280.85669 -282.59532) (xy 280.848816 -282.595616) (xy 280.833812 -282.600394)
			(xy 280.827226 -282.604718) (xy 280.806157 -282.619123) (xy 280.76051 -282.641949) (xy 280.711901 -282.657503)
			(xy 280.661482 -282.665418) (xy 280.635964 -282.665932) (xy 280.610445 -282.665421) (xy 280.560019 -282.657532)
			(xy 280.511407 -282.641978) (xy 280.465768 -282.61913) (xy 280.444702 -282.604718) (xy 280.438111 -282.600403)
			(xy 280.42311 -282.595616) (xy 280.415238 -282.59532) (xy 279.899364 -282.59532) (xy 279.8941 -282.59483)
			(xy 279.88666 -282.587377) (xy 279.886156 -282.582112) (xy 273.841972 -282.582112) (xy 273.841678 -282.587455)
			(xy 273.834108 -282.594997) (xy 273.828764 -282.59532) (xy 273.31289 -282.59532) (xy 273.305016 -282.595616)
			(xy 273.290012 -282.600394) (xy 273.283426 -282.604718) (xy 273.262357 -282.619123) (xy 273.21671 -282.641949)
			(xy 273.168101 -282.657503) (xy 273.117682 -282.665418) (xy 273.092164 -282.665932) (xy 273.066645 -282.665421)
			(xy 273.016219 -282.657532) (xy 272.967607 -282.641978) (xy 272.921968 -282.61913) (xy 272.900902 -282.604718)
			(xy 272.894311 -282.600403) (xy 272.87931 -282.595616) (xy 272.871438 -282.59532) (xy 272.355564 -282.59532)
			(xy 272.3503 -282.59483) (xy 272.34286 -282.587377) (xy 272.342356 -282.582112) (xy 266.298172 -282.582112)
			(xy 266.297878 -282.587455) (xy 266.290308 -282.594997) (xy 266.284964 -282.59532) (xy 266.284456 -282.59532)
			(xy 265.768836 -282.59532) (xy 265.76096 -282.595593) (xy 265.745957 -282.600387) (xy 265.739372 -282.604718)
			(xy 265.71829 -282.619103) (xy 265.672647 -282.641934) (xy 265.624043 -282.657494) (xy 265.573626 -282.665414)
			(xy 265.54811 -282.665932) (xy 265.52259 -282.665449) (xy 265.472163 -282.657551) (xy 265.423551 -282.641989)
			(xy 265.377913 -282.619133) (xy 265.356848 -282.604718) (xy 265.350269 -282.600382) (xy 265.335259 -282.595608)
			(xy 265.327384 -282.59532) (xy 264.81151 -282.59532) (xy 264.806198 -282.594865) (xy 264.798624 -282.587415)
			(xy 264.798048 -282.582112) (xy 202.89774 -282.582112) (xy 202.89774 -282.582366) (xy 202.897252 -282.587671)
			(xy 202.889826 -282.595245) (xy 202.884532 -282.595828) (xy 202.368658 -282.595828) (xy 202.36085 -282.596162)
			(xy 202.345978 -282.600934) (xy 202.339448 -282.605226) (xy 202.318336 -282.619591) (xy 202.272609 -282.642315)
			(xy 202.223933 -282.657741) (xy 202.173464 -282.665502) (xy 202.147932 -282.665932) (xy 202.122402 -282.665485)
			(xy 202.071938 -282.657713) (xy 202.023266 -282.642287) (xy 201.977538 -282.619573) (xy 201.956416 -282.605226)
			(xy 201.949879 -282.600945) (xy 201.935013 -282.596155) (xy 201.927206 -282.595828) (xy 201.411332 -282.595828)
			(xy 201.406009 -282.595454) (xy 201.398467 -282.587942) (xy 201.398124 -282.58262) (xy 195.353917 -282.58262)
			(xy 195.353452 -282.587671) (xy 195.346026 -282.595245) (xy 195.340732 -282.595828) (xy 194.824858 -282.595828)
			(xy 194.81705 -282.596162) (xy 194.802178 -282.600934) (xy 194.795648 -282.605226) (xy 194.774536 -282.619591)
			(xy 194.728809 -282.642315) (xy 194.680133 -282.657741) (xy 194.629664 -282.665502) (xy 194.604132 -282.665932)
			(xy 194.578602 -282.665485) (xy 194.528138 -282.657713) (xy 194.479466 -282.642287) (xy 194.433738 -282.619573)
			(xy 194.412616 -282.605226) (xy 194.406079 -282.600945) (xy 194.391213 -282.596155) (xy 194.383406 -282.595828)
			(xy 193.867532 -282.595828) (xy 193.862209 -282.595454) (xy 193.854667 -282.587942) (xy 193.854324 -282.58262)
			(xy 187.810124 -282.58262) (xy 187.809796 -282.587802) (xy 187.802113 -282.595491) (xy 187.796678 -282.595828)
			(xy 187.280804 -282.595828) (xy 187.272994 -282.596139) (xy 187.258122 -282.600926) (xy 187.251594 -282.605226)
			(xy 187.23047 -282.619571) (xy 187.184747 -282.642299) (xy 187.136075 -282.657731) (xy 187.085609 -282.665498)
			(xy 187.060078 -282.665932) (xy 187.034547 -282.665512) (xy 186.984082 -282.657732) (xy 186.93541 -282.642298)
			(xy 186.889683 -282.619576) (xy 186.868562 -282.605226) (xy 186.862037 -282.600924) (xy 186.847162 -282.596147)
			(xy 186.839352 -282.595828) (xy 186.323478 -282.595828) (xy 186.318032 -282.595532) (xy 186.310345 -282.587813)
			(xy 186.310016 -282.582366) (xy 180.265832 -282.582366) (xy 180.265351 -282.587673) (xy 180.25792 -282.595247)
			(xy 180.252624 -282.595828) (xy 179.73675 -282.595828) (xy 179.728941 -282.596158) (xy 179.71407 -282.600933)
			(xy 179.70754 -282.605226) (xy 179.686431 -282.619594) (xy 179.640703 -282.642317) (xy 179.592026 -282.657742)
			(xy 179.541556 -282.665503) (xy 179.516024 -282.665932) (xy 179.490494 -282.665489) (xy 179.44003 -282.657716)
			(xy 179.391357 -282.642289) (xy 179.34563 -282.619573) (xy 179.324508 -282.605226) (xy 179.317972 -282.600942)
			(xy 179.303106 -282.596154) (xy 179.295298 -282.595828) (xy 178.779424 -282.595828) (xy 178.7741 -282.595459)
			(xy 178.766559 -282.587943) (xy 178.766216 -282.58262) (xy 172.722016 -282.58262) (xy 172.721695 -282.587804)
			(xy 172.714007 -282.595493) (xy 172.70857 -282.595828) (xy 172.192696 -282.595828) (xy 172.184885 -282.596135)
			(xy 172.170014 -282.600925) (xy 172.163486 -282.605226) (xy 172.142364 -282.619574) (xy 172.09664 -282.642302)
			(xy 172.047967 -282.657733) (xy 171.997501 -282.665499) (xy 171.97197 -282.665932) (xy 171.946439 -282.665516)
			(xy 171.895974 -282.657735) (xy 171.847301 -282.6423) (xy 171.801575 -282.619577) (xy 171.780454 -282.605226)
			(xy 171.77393 -282.600921) (xy 171.759054 -282.596146) (xy 171.751244 -282.595828) (xy 171.23537 -282.595828)
			(xy 171.229923 -282.595537) (xy 171.222237 -282.587815) (xy 171.221908 -282.582366) (xy 165.177724 -282.582366)
			(xy 165.17725 -282.587674) (xy 165.169815 -282.595249) (xy 165.164516 -282.595828) (xy 163.691316 -282.595828)
			(xy 163.68606 -282.595297) (xy 163.678618 -282.587875) (xy 163.678108 -282.58262) (xy 56.078105 -282.58262)
			(xy 56.077794 -282.587806) (xy 56.070099 -282.595497) (xy 56.064658 -282.595828) (xy 54.591458 -282.595828)
			(xy 54.586081 -282.595374) (xy 54.578495 -282.587746) (xy 54.577996 -282.582366) (xy 48.533812 -282.582366)
			(xy 48.533348 -282.587677) (xy 48.525906 -282.595253) (xy 48.520604 -282.595828) (xy 48.00473 -282.595828)
			(xy 47.996921 -282.596149) (xy 47.982049 -282.600929) (xy 47.97552 -282.605226) (xy 47.954388 -282.61956)
			(xy 47.908668 -282.642291) (xy 47.859998 -282.657725) (xy 47.809534 -282.665497) (xy 47.784004 -282.665932)
			(xy 47.758474 -282.665499) (xy 47.708009 -282.657723) (xy 47.659337 -282.642293) (xy 47.613609 -282.619575)
			(xy 47.592488 -282.605226) (xy 47.585957 -282.600934) (xy 47.571087 -282.596151) (xy 47.563278 -282.595828)
			(xy 47.047404 -282.595828) (xy 47.042147 -282.595305) (xy 47.034705 -282.587877) (xy 47.034196 -282.58262)
			(xy 40.989984 -282.58262) (xy 40.989432 -282.587714) (xy 40.981894 -282.595298) (xy 40.97655 -282.595828)
			(xy 40.460676 -282.595828) (xy 40.452864 -282.596127) (xy 40.437993 -282.600922) (xy 40.431466 -282.605226)
			(xy 40.410349 -282.619583) (xy 40.364624 -282.642309) (xy 40.315949 -282.657737) (xy 40.265481 -282.665501)
			(xy 40.23995 -282.665932) (xy 40.21442 -282.665476) (xy 40.163957 -282.657707) (xy 40.115284 -282.642284)
			(xy 40.069556 -282.619572) (xy 40.048434 -282.605226) (xy 40.041893 -282.600952) (xy 40.02703 -282.596158)
			(xy 40.019224 -282.595828) (xy 39.50335 -282.595828) (xy 39.497972 -282.595379) (xy 39.490387 -282.587747)
			(xy 39.489888 -282.582366) (xy 33.445704 -282.582366) (xy 33.445159 -282.587656) (xy 33.437773 -282.595227)
			(xy 33.432496 -282.595828) (xy 32.916622 -282.595828) (xy 32.908812 -282.596146) (xy 32.893941 -282.600928)
			(xy 32.887412 -282.605226) (xy 32.866283 -282.619563) (xy 32.820562 -282.642293) (xy 32.771891 -282.657727)
			(xy 32.721426 -282.665497) (xy 32.695896 -282.665932) (xy 32.670365 -282.665503) (xy 32.619901 -282.657726)
			(xy 32.571228 -282.642295) (xy 32.525501 -282.619575) (xy 32.50438 -282.605226) (xy 32.497851 -282.600931)
			(xy 32.482979 -282.59615) (xy 32.47517 -282.595828) (xy 31.959296 -282.595828) (xy 31.954038 -282.59531)
			(xy 31.946596 -282.587878) (xy 31.946088 -282.58262) (xy 25.901878 -282.58262) (xy 25.901359 -282.587656)
			(xy 25.893973 -282.595227) (xy 25.888696 -282.595828) (xy 25.372822 -282.595828) (xy 25.365012 -282.596146)
			(xy 25.350141 -282.600928) (xy 25.343612 -282.605226) (xy 25.322483 -282.619563) (xy 25.276762 -282.642293)
			(xy 25.228091 -282.657727) (xy 25.177626 -282.665497) (xy 25.152096 -282.665932) (xy 25.126565 -282.665503)
			(xy 25.076101 -282.657726) (xy 25.027428 -282.642295) (xy 24.981701 -282.619575) (xy 24.96058 -282.605226)
			(xy 24.954051 -282.600931) (xy 24.939179 -282.59615) (xy 24.93137 -282.595828) (xy 24.415496 -282.595828)
			(xy 24.410238 -282.59531) (xy 24.402796 -282.587878) (xy 24.402288 -282.58262) (xy 18.358077 -282.58262)
			(xy 18.357531 -282.587716) (xy 18.349989 -282.595301) (xy 18.344642 -282.595828) (xy 17.828768 -282.595828)
			(xy 17.82096 -282.596166) (xy 17.806088 -282.600935) (xy 17.799558 -282.605226) (xy 17.778444 -282.619587)
			(xy 17.732717 -282.642311) (xy 17.684042 -282.657739) (xy 17.633574 -282.665501) (xy 17.608042 -282.665932)
			(xy 17.582512 -282.66548) (xy 17.532049 -282.65771) (xy 17.483376 -282.642285) (xy 17.437648 -282.619572)
			(xy 17.416526 -282.605226) (xy 17.409986 -282.600949) (xy 17.395123 -282.596157) (xy 17.387316 -282.595828)
			(xy 16.871442 -282.595828) (xy 16.866005 -282.595489) (xy 16.858314 -282.587803) (xy 16.85798 -282.582366)
			(xy 2.509012 -282.582366) (xy 2.509012 -283.432504) (xy 20.958048 -283.432504) (xy 20.958048 -282.937966)
			(xy 20.958529 -282.932596) (xy 20.966138 -282.925011) (xy 20.97151 -282.924504) (xy 21.487638 -282.924504)
			(xy 21.495446 -282.924163) (xy 21.510317 -282.919396) (xy 21.516848 -282.915106) (xy 21.537937 -282.900757)
			(xy 21.583598 -282.878026) (xy 21.632204 -282.862567) (xy 21.682607 -282.854744) (xy 21.733613 -282.854744)
			(xy 21.784016 -282.862567) (xy 21.832622 -282.878026) (xy 21.878283 -282.900757) (xy 21.899372 -282.915106)
			(xy 21.90591 -282.919386) (xy 21.920775 -282.924176) (xy 21.928582 -282.924504) (xy 22.44471 -282.924504)
			(xy 22.450067 -282.92504) (xy 22.45765 -282.93261) (xy 22.458172 -282.937966) (xy 22.458172 -283.432504)
			(xy 28.502356 -283.432504) (xy 28.502356 -282.937966) (xy 28.502802 -282.932654) (xy 28.51026 -282.925084)
			(xy 28.515564 -282.924504) (xy 29.031692 -282.924504) (xy 29.039502 -282.924186) (xy 29.054373 -282.919403)
			(xy 29.060902 -282.915106) (xy 29.081991 -282.900757) (xy 29.127652 -282.878026) (xy 29.176258 -282.862567)
			(xy 29.226661 -282.854744) (xy 29.277667 -282.854744) (xy 29.32807 -282.862567) (xy 29.376676 -282.878026)
			(xy 29.422337 -282.900757) (xy 29.443426 -282.915106) (xy 29.449952 -282.919407) (xy 29.464826 -282.924184)
			(xy 29.472636 -282.924504) (xy 29.988764 -282.924504) (xy 29.994094 -282.924852) (xy 30.001638 -282.932382)
			(xy 30.001972 -282.937712) (xy 30.001972 -282.93822) (xy 30.001972 -283.432504) (xy 36.046156 -283.432504)
			(xy 36.046156 -282.937966) (xy 36.046602 -282.932654) (xy 36.05406 -282.925084) (xy 36.059364 -282.924504)
			(xy 36.575492 -282.924504) (xy 36.583302 -282.924186) (xy 36.598173 -282.919403) (xy 36.604702 -282.915106)
			(xy 36.625791 -282.900757) (xy 36.671452 -282.878026) (xy 36.720058 -282.862567) (xy 36.770461 -282.854744)
			(xy 36.821467 -282.854744) (xy 36.87187 -282.862567) (xy 36.920476 -282.878026) (xy 36.966137 -282.900757)
			(xy 36.987226 -282.915106) (xy 36.993752 -282.919407) (xy 37.008626 -282.924184) (xy 37.016436 -282.924504)
			(xy 37.532564 -282.924504) (xy 37.537894 -282.924852) (xy 37.545438 -282.932382) (xy 37.545772 -282.937712)
			(xy 37.545772 -282.93822) (xy 37.545772 -283.432504) (xy 43.589956 -283.432504) (xy 43.589956 -282.937966)
			(xy 43.59043 -282.932594) (xy 43.598044 -282.925009) (xy 43.603418 -282.924504) (xy 44.119546 -282.924504)
			(xy 44.127354 -282.924167) (xy 44.142225 -282.919397) (xy 44.148756 -282.915106) (xy 44.169845 -282.900757)
			(xy 44.215506 -282.878026) (xy 44.264112 -282.862567) (xy 44.314515 -282.854744) (xy 44.365521 -282.854744)
			(xy 44.415924 -282.862567) (xy 44.46453 -282.878026) (xy 44.510191 -282.900757) (xy 44.53128 -282.915106)
			(xy 44.537816 -282.919389) (xy 44.552683 -282.924177) (xy 44.56049 -282.924504) (xy 45.076618 -282.924504)
			(xy 45.081976 -282.925035) (xy 45.089559 -282.932609) (xy 45.09008 -282.937966) (xy 45.09008 -283.432504)
			(xy 51.134264 -283.432504) (xy 51.134264 -282.937966) (xy 51.134703 -282.932652) (xy 51.142166 -282.925082)
			(xy 51.147472 -282.924504) (xy 51.6636 -282.924504) (xy 51.67141 -282.92419) (xy 51.686281 -282.919404)
			(xy 51.69281 -282.915106) (xy 51.713899 -282.900757) (xy 51.75956 -282.878026) (xy 51.808166 -282.862567)
			(xy 51.858569 -282.854744) (xy 51.909575 -282.854744) (xy 51.959978 -282.862567) (xy 52.008584 -282.878026)
			(xy 52.054245 -282.900757) (xy 52.075334 -282.915106) (xy 52.081858 -282.91941) (xy 52.096734 -282.924185)
			(xy 52.104544 -282.924504) (xy 52.620672 -282.924504) (xy 52.626003 -282.924847) (xy 52.633547 -282.932381)
			(xy 52.63388 -282.937712) (xy 52.63388 -282.93822) (xy 52.63388 -283.432504) (xy 58.678064 -283.432504)
			(xy 58.678064 -282.937966) (xy 58.67853 -282.932592) (xy 58.68615 -282.925006) (xy 58.691526 -282.924504)
			(xy 60.164726 -282.924504) (xy 60.170085 -282.92503) (xy 60.177667 -282.932607) (xy 60.178188 -282.937966)
			(xy 60.178188 -282.9964) (xy 97.674871 -282.9964) (xy 97.679047 -282.946012) (xy 97.691459 -282.896999)
			(xy 97.711769 -282.850697) (xy 97.739424 -282.808369) (xy 97.773668 -282.771171) (xy 97.813568 -282.740117)
			(xy 97.858035 -282.716053) (xy 97.905856 -282.699637) (xy 97.955728 -282.691316) (xy 97.981008 -282.690824)
			(xy 98.921062 -282.690824) (xy 98.946342 -282.691342) (xy 98.996212 -282.699658) (xy 99.044033 -282.71607)
			(xy 99.088501 -282.74013) (xy 99.128401 -282.771181) (xy 99.162646 -282.808377) (xy 99.190302 -282.850702)
			(xy 99.210613 -282.897002) (xy 99.223025 -282.946014) (xy 99.227201 -282.9964) (xy 100.4951 -282.9964)
			(xy 100.499275 -282.946021) (xy 100.511684 -282.897016) (xy 100.531989 -282.850721) (xy 100.559637 -282.8084)
			(xy 100.593873 -282.771206) (xy 100.633764 -282.740154) (xy 100.678221 -282.716091) (xy 100.726032 -282.699673)
			(xy 100.775894 -282.691348) (xy 100.80117 -282.690824) (xy 101.741224 -282.690824) (xy 101.766498 -282.691376)
			(xy 101.816356 -282.699699) (xy 101.864164 -282.716115) (xy 101.908618 -282.740176) (xy 101.948506 -282.771224)
			(xy 101.98274 -282.808415) (xy 102.010385 -282.850733) (xy 102.030689 -282.897024) (xy 102.043098 -282.946025)
			(xy 102.047272 -282.9964) (xy 103.315 -282.9964) (xy 103.319175 -282.94602) (xy 103.331584 -282.897014)
			(xy 103.35189 -282.850719) (xy 103.379539 -282.808397) (xy 103.413776 -282.771203) (xy 103.453668 -282.740151)
			(xy 103.498126 -282.716089) (xy 103.545939 -282.699672) (xy 103.595802 -282.691348) (xy 103.621078 -282.690824)
			(xy 104.561132 -282.690824) (xy 104.586405 -282.691376) (xy 104.636262 -282.699701) (xy 104.684069 -282.716117)
			(xy 104.728522 -282.740178) (xy 104.768409 -282.771227) (xy 104.802642 -282.808418) (xy 104.830287 -282.850735)
			(xy 104.85059 -282.897025) (xy 104.862998 -282.946026) (xy 104.867172 -282.9964) (xy 106.1349 -282.9964)
			(xy 106.139075 -282.946019) (xy 106.151485 -282.897012) (xy 106.171791 -282.850717) (xy 106.199441 -282.808394)
			(xy 106.233679 -282.7712) (xy 106.273572 -282.740149) (xy 106.318032 -282.716086) (xy 106.365846 -282.69967)
			(xy 106.415709 -282.691347) (xy 106.440986 -282.690824) (xy 107.38104 -282.690824) (xy 107.406313 -282.691377)
			(xy 107.456169 -282.699702) (xy 107.503975 -282.71612) (xy 107.548426 -282.740181) (xy 107.588312 -282.77123)
			(xy 107.622544 -282.80842) (xy 107.650188 -282.850737) (xy 107.67049 -282.897027) (xy 107.682898 -282.946026)
			(xy 107.687072 -282.9964) (xy 116.468571 -282.9964) (xy 116.472747 -282.946011) (xy 116.48516 -282.896996)
			(xy 116.505471 -282.850693) (xy 116.533127 -282.808365) (xy 116.567373 -282.771166) (xy 116.607275 -282.740112)
			(xy 116.651744 -282.716049) (xy 116.699568 -282.699634) (xy 116.749441 -282.691315) (xy 116.774722 -282.690824)
			(xy 117.714776 -282.690824) (xy 117.740055 -282.691343) (xy 117.789924 -282.699661) (xy 117.837743 -282.716074)
			(xy 117.882208 -282.740135) (xy 117.922107 -282.771186) (xy 117.95635 -282.808381) (xy 117.984004 -282.850706)
			(xy 118.004313 -282.897005) (xy 118.016725 -282.946015) (xy 118.020901 -282.9964) (xy 119.288471 -282.9964)
			(xy 119.292647 -282.94601) (xy 119.30506 -282.896994) (xy 119.325373 -282.850691) (xy 119.353029 -282.808362)
			(xy 119.387276 -282.771163) (xy 119.427179 -282.740109) (xy 119.47165 -282.716047) (xy 119.519474 -282.699633)
			(xy 119.569348 -282.691315) (xy 119.59463 -282.690824) (xy 120.534684 -282.690824) (xy 120.559962 -282.691344)
			(xy 120.60983 -282.699663) (xy 120.657648 -282.716077) (xy 120.702113 -282.740137) (xy 120.74201 -282.771189)
			(xy 120.776252 -282.808384) (xy 120.803905 -282.850708) (xy 120.824214 -282.897006) (xy 120.836625 -282.946016)
			(xy 120.840801 -282.9964) (xy 122.1087 -282.9964) (xy 122.112875 -282.946019) (xy 122.125285 -282.897011)
			(xy 122.145592 -282.850715) (xy 122.173242 -282.808392) (xy 122.207481 -282.771198) (xy 122.247375 -282.740147)
			(xy 122.291836 -282.716085) (xy 122.33965 -282.699669) (xy 122.389515 -282.691347) (xy 122.414792 -282.690824)
			(xy 123.354846 -282.690824) (xy 123.380119 -282.691377) (xy 123.429974 -282.699704) (xy 123.477779 -282.716122)
			(xy 123.52223 -282.740183) (xy 123.562114 -282.771232) (xy 123.596345 -282.808422) (xy 123.623989 -282.850739)
			(xy 123.644291 -282.897028) (xy 123.656698 -282.946027) (xy 123.660872 -282.9964) (xy 124.928601 -282.9964)
			(xy 124.932775 -282.946018) (xy 124.945186 -282.89701) (xy 124.965494 -282.850713) (xy 124.993144 -282.80839)
			(xy 125.027384 -282.771195) (xy 125.067279 -282.740144) (xy 125.111741 -282.716082) (xy 125.159557 -282.699667)
			(xy 125.209423 -282.691346) (xy 125.2347 -282.690824) (xy 126.174754 -282.690824) (xy 126.200034 -282.691341)
			(xy 126.249906 -282.699657) (xy 126.297728 -282.716068) (xy 126.342197 -282.740127) (xy 126.382098 -282.771178)
			(xy 126.416344 -282.808374) (xy 126.444 -282.850699) (xy 126.464312 -282.897) (xy 126.476725 -282.946013)
			(xy 126.480901 -282.9964) (xy 126.476725 -283.046787) (xy 126.464312 -283.0958) (xy 126.444 -283.142101)
			(xy 126.416344 -283.184426) (xy 126.382098 -283.221622) (xy 126.342197 -283.252673) (xy 126.297728 -283.276732)
			(xy 126.249906 -283.293143) (xy 126.200034 -283.301459) (xy 126.174754 -283.301948) (xy 125.2347 -283.301948)
			(xy 125.209423 -283.301454) (xy 125.159557 -283.293133) (xy 125.111741 -283.276718) (xy 125.067279 -283.252656)
			(xy 125.027384 -283.221605) (xy 124.993144 -283.18441) (xy 124.965494 -283.142087) (xy 124.945186 -283.09579)
			(xy 124.932775 -283.046782) (xy 124.928601 -282.9964) (xy 123.660872 -282.9964) (xy 123.656698 -283.046773)
			(xy 123.644291 -283.095772) (xy 123.623989 -283.142061) (xy 123.596345 -283.184378) (xy 123.562114 -283.221568)
			(xy 123.52223 -283.252617) (xy 123.477779 -283.276678) (xy 123.429974 -283.293096) (xy 123.380119 -283.301423)
			(xy 123.354846 -283.301948) (xy 122.414792 -283.301948) (xy 122.389515 -283.301453) (xy 122.33965 -283.293131)
			(xy 122.291836 -283.276715) (xy 122.247375 -283.252653) (xy 122.207481 -283.221602) (xy 122.173242 -283.184408)
			(xy 122.145592 -283.142085) (xy 122.125285 -283.095789) (xy 122.112875 -283.046781) (xy 122.1087 -282.9964)
			(xy 120.840801 -282.9964) (xy 120.836625 -283.046784) (xy 120.824214 -283.095794) (xy 120.803905 -283.142092)
			(xy 120.776252 -283.184416) (xy 120.74201 -283.221611) (xy 120.702113 -283.252663) (xy 120.657648 -283.276723)
			(xy 120.60983 -283.293137) (xy 120.559962 -283.301456) (xy 120.534684 -283.301948) (xy 119.59463 -283.301948)
			(xy 119.569348 -283.301485) (xy 119.519474 -283.293167) (xy 119.47165 -283.276753) (xy 119.427179 -283.252691)
			(xy 119.387276 -283.221637) (xy 119.353029 -283.184438) (xy 119.325373 -283.142109) (xy 119.30506 -283.095806)
			(xy 119.292647 -283.04679) (xy 119.288471 -282.9964) (xy 118.020901 -282.9964) (xy 118.016725 -283.046785)
			(xy 118.004313 -283.095795) (xy 117.984004 -283.142094) (xy 117.95635 -283.184419) (xy 117.922107 -283.221614)
			(xy 117.882208 -283.252665) (xy 117.837743 -283.276726) (xy 117.789924 -283.293139) (xy 117.740055 -283.301457)
			(xy 117.714776 -283.301948) (xy 116.774722 -283.301948) (xy 116.749441 -283.301485) (xy 116.699568 -283.293166)
			(xy 116.651744 -283.276751) (xy 116.607275 -283.252688) (xy 116.567373 -283.221634) (xy 116.533127 -283.184435)
			(xy 116.505471 -283.142107) (xy 116.48516 -283.095804) (xy 116.472747 -283.046789) (xy 116.468571 -282.9964)
			(xy 107.687072 -282.9964) (xy 107.682898 -283.046774) (xy 107.67049 -283.095773) (xy 107.650188 -283.142063)
			(xy 107.622544 -283.18438) (xy 107.588312 -283.22157) (xy 107.548426 -283.252619) (xy 107.503975 -283.27668)
			(xy 107.456169 -283.293098) (xy 107.406313 -283.301423) (xy 107.38104 -283.301948) (xy 106.440986 -283.301948)
			(xy 106.415709 -283.301453) (xy 106.365846 -283.29313) (xy 106.318032 -283.276714) (xy 106.273572 -283.252651)
			(xy 106.233679 -283.2216) (xy 106.199441 -283.184406) (xy 106.171791 -283.142083) (xy 106.151485 -283.095788)
			(xy 106.139075 -283.046781) (xy 106.1349 -282.9964) (xy 104.867172 -282.9964) (xy 104.862998 -283.046774)
			(xy 104.85059 -283.095775) (xy 104.830287 -283.142065) (xy 104.802642 -283.184382) (xy 104.768409 -283.221573)
			(xy 104.728522 -283.252622) (xy 104.684069 -283.276683) (xy 104.636262 -283.293099) (xy 104.586405 -283.301424)
			(xy 104.561132 -283.301948) (xy 103.621078 -283.301948) (xy 103.595802 -283.301452) (xy 103.545939 -283.293128)
			(xy 103.498126 -283.276711) (xy 103.453668 -283.252649) (xy 103.413776 -283.221597) (xy 103.379539 -283.184403)
			(xy 103.35189 -283.142081) (xy 103.331584 -283.095786) (xy 103.319175 -283.04678) (xy 103.315 -282.9964)
			(xy 102.047272 -282.9964) (xy 102.043098 -283.046775) (xy 102.030689 -283.095776) (xy 102.010385 -283.142067)
			(xy 101.98274 -283.184385) (xy 101.948506 -283.221576) (xy 101.908618 -283.252624) (xy 101.864164 -283.276685)
			(xy 101.816356 -283.293101) (xy 101.766498 -283.301424) (xy 101.741224 -283.301948) (xy 100.80117 -283.301948)
			(xy 100.775894 -283.301452) (xy 100.726032 -283.293127) (xy 100.678221 -283.276709) (xy 100.633764 -283.252646)
			(xy 100.593873 -283.221594) (xy 100.559637 -283.1844) (xy 100.531989 -283.142079) (xy 100.511684 -283.095784)
			(xy 100.499275 -283.046779) (xy 100.4951 -282.9964) (xy 99.227201 -282.9964) (xy 99.223025 -283.046786)
			(xy 99.210613 -283.095798) (xy 99.190302 -283.142098) (xy 99.162646 -283.184423) (xy 99.128401 -283.221619)
			(xy 99.088501 -283.25267) (xy 99.044033 -283.27673) (xy 98.996212 -283.293142) (xy 98.946342 -283.301458)
			(xy 98.921062 -283.301948) (xy 97.981008 -283.301948) (xy 97.955728 -283.301484) (xy 97.905856 -283.293163)
			(xy 97.858035 -283.276747) (xy 97.813568 -283.252683) (xy 97.773668 -283.221629) (xy 97.739424 -283.184431)
			(xy 97.711769 -283.142103) (xy 97.691459 -283.095801) (xy 97.679047 -283.046788) (xy 97.674871 -282.9964)
			(xy 60.178188 -282.9964) (xy 60.178188 -283.432504) (xy 167.778176 -283.432504) (xy 167.778176 -282.937966)
			(xy 167.778605 -282.932649) (xy 167.786075 -282.925078) (xy 167.791384 -282.924504) (xy 169.264584 -282.924504)
			(xy 169.269917 -282.924839) (xy 169.27746 -282.932379) (xy 169.277792 -282.937712) (xy 169.277792 -283.432504)
			(xy 175.321976 -283.432504) (xy 175.321976 -282.937966) (xy 175.32226 -282.932517) (xy 175.329988 -282.924831)
			(xy 175.335438 -282.924504) (xy 175.851566 -282.924504) (xy 175.859375 -282.924175) (xy 175.874246 -282.9194)
			(xy 175.880776 -282.915106) (xy 175.901865 -282.900757) (xy 175.947526 -282.878026) (xy 175.996132 -282.862567)
			(xy 176.046535 -282.854744) (xy 176.097541 -282.854744) (xy 176.147944 -282.862567) (xy 176.19655 -282.878026)
			(xy 176.242211 -282.900757) (xy 176.2633 -282.915106) (xy 176.269832 -282.919397) (xy 176.284702 -282.92418)
			(xy 176.29251 -282.924504) (xy 176.808638 -282.924504) (xy 176.813998 -282.925022) (xy 176.82158 -282.932606)
			(xy 176.8221 -282.937966) (xy 176.8221 -283.432504) (xy 182.866284 -283.432504) (xy 182.866284 -282.937966)
			(xy 182.866706 -282.932647) (xy 182.87418 -282.925076) (xy 182.879492 -282.924504) (xy 183.39562 -282.924504)
			(xy 183.403431 -282.924198) (xy 183.418302 -282.919407) (xy 183.42483 -282.915106) (xy 183.445919 -282.900757)
			(xy 183.49158 -282.878026) (xy 183.540186 -282.862567) (xy 183.590589 -282.854744) (xy 183.641595 -282.854744)
			(xy 183.691998 -282.862567) (xy 183.740604 -282.878026) (xy 183.786265 -282.900757) (xy 183.807354 -282.915106)
			(xy 183.813874 -282.919417) (xy 183.828753 -282.924188) (xy 183.836564 -282.924504) (xy 184.352692 -282.924504)
			(xy 184.358026 -282.924833) (xy 184.365568 -282.932378) (xy 184.3659 -282.937712) (xy 184.3659 -282.93822)
			(xy 184.3659 -283.432504) (xy 190.410084 -283.432504) (xy 190.410084 -282.937966) (xy 190.410361 -282.932515)
			(xy 190.418094 -282.924829) (xy 190.423546 -282.924504) (xy 190.939674 -282.924504) (xy 190.947483 -282.924179)
			(xy 190.962354 -282.919401) (xy 190.968884 -282.915106) (xy 190.989973 -282.900757) (xy 191.035634 -282.878026)
			(xy 191.08424 -282.862567) (xy 191.134643 -282.854744) (xy 191.185649 -282.854744) (xy 191.236052 -282.862567)
			(xy 191.284658 -282.878026) (xy 191.330319 -282.900757) (xy 191.351408 -282.915106) (xy 191.357938 -282.9194)
			(xy 191.372809 -282.924181) (xy 191.380618 -282.924504) (xy 191.896746 -282.924504) (xy 191.902107 -282.925016)
			(xy 191.909688 -282.932604) (xy 191.910208 -282.937966) (xy 191.910208 -283.432504) (xy 197.954392 -283.432504)
			(xy 197.954392 -282.937966) (xy 197.954895 -282.932669) (xy 197.962314 -282.925103) (xy 197.9676 -282.924504)
			(xy 198.483728 -282.924504) (xy 198.491539 -282.924201) (xy 198.50641 -282.919408) (xy 198.512938 -282.915106)
			(xy 198.534027 -282.900757) (xy 198.579688 -282.878026) (xy 198.628294 -282.862567) (xy 198.678697 -282.854744)
			(xy 198.729703 -282.854744) (xy 198.780106 -282.862567) (xy 198.828712 -282.878026) (xy 198.874373 -282.900757)
			(xy 198.895462 -282.915106) (xy 198.902002 -282.919382) (xy 198.916866 -282.924174) (xy 198.924672 -282.924504)
			(xy 199.4408 -282.924504) (xy 199.446135 -282.924828) (xy 199.453677 -282.932376) (xy 199.454008 -282.937712)
			(xy 199.454008 -282.93822) (xy 199.454008 -283.432504) (xy 205.498192 -283.432504) (xy 205.498192 -282.937966)
			(xy 205.498695 -282.932669) (xy 205.506114 -282.925103) (xy 205.5114 -282.924504) (xy 206.027528 -282.924504)
			(xy 206.035339 -282.924201) (xy 206.05021 -282.919408) (xy 206.056738 -282.915106) (xy 206.077827 -282.900757)
			(xy 206.123488 -282.878026) (xy 206.172094 -282.862567) (xy 206.222497 -282.854744) (xy 206.273503 -282.854744)
			(xy 206.323906 -282.862567) (xy 206.372512 -282.878026) (xy 206.418173 -282.900757) (xy 206.439262 -282.915106)
			(xy 206.445802 -282.919382) (xy 206.460666 -282.924174) (xy 206.468472 -282.924504) (xy 206.9846 -282.924504)
			(xy 206.989935 -282.924828) (xy 206.997477 -282.932376) (xy 206.997808 -282.937712) (xy 206.997808 -282.93822)
			(xy 206.997808 -283.43225) (xy 268.898116 -283.43225) (xy 268.898116 -282.937712) (xy 268.898437 -282.932376)
			(xy 268.905987 -282.924833) (xy 268.911324 -282.924504) (xy 268.911832 -282.924504) (xy 269.427706 -282.924504)
			(xy 269.435516 -282.924192) (xy 269.450388 -282.919405) (xy 269.456916 -282.915106) (xy 269.478005 -282.900757)
			(xy 269.523666 -282.878026) (xy 269.572272 -282.862567) (xy 269.622675 -282.854744) (xy 269.673681 -282.854744)
			(xy 269.724084 -282.862567) (xy 269.77269 -282.878026) (xy 269.818351 -282.900757) (xy 269.83944 -282.915106)
			(xy 269.845963 -282.919412) (xy 269.86084 -282.924186) (xy 269.86865 -282.924504) (xy 270.384778 -282.924504)
			(xy 270.390071 -282.925033) (xy 270.397642 -282.932431) (xy 270.39824 -282.937712) (xy 270.39824 -283.43225)
			(xy 270.398218 -283.432504) (xy 276.442424 -283.432504) (xy 276.442424 -283.431996) (xy 276.442424 -282.937712)
			(xy 276.442738 -282.932374) (xy 276.450293 -282.92483) (xy 276.455632 -282.924504) (xy 276.97176 -282.924504)
			(xy 276.979568 -282.924173) (xy 276.99444 -282.919399) (xy 277.00097 -282.915106) (xy 277.022059 -282.900757)
			(xy 277.06772 -282.878026) (xy 277.116326 -282.862567) (xy 277.166729 -282.854744) (xy 277.217735 -282.854744)
			(xy 277.268138 -282.862567) (xy 277.316744 -282.878026) (xy 277.362405 -282.900757) (xy 277.383494 -282.915106)
			(xy 277.390027 -282.919394) (xy 277.404896 -282.924179) (xy 277.412704 -282.924504) (xy 277.928832 -282.924504)
			(xy 277.934102 -282.924975) (xy 277.941543 -282.932441) (xy 277.94204 -282.937712) (xy 277.94204 -283.43225)
			(xy 277.942016 -283.432504) (xy 283.986224 -283.432504) (xy 283.986224 -283.431996) (xy 283.986224 -282.937712)
			(xy 283.986538 -282.932374) (xy 283.994093 -282.92483) (xy 283.999432 -282.924504) (xy 284.51556 -282.924504)
			(xy 284.523368 -282.924173) (xy 284.53824 -282.919399) (xy 284.54477 -282.915106) (xy 284.565859 -282.900757)
			(xy 284.61152 -282.878026) (xy 284.660126 -282.862567) (xy 284.710529 -282.854744) (xy 284.761535 -282.854744)
			(xy 284.811938 -282.862567) (xy 284.860544 -282.878026) (xy 284.906205 -282.900757) (xy 284.927294 -282.915106)
			(xy 284.933827 -282.919394) (xy 284.948696 -282.924179) (xy 284.956504 -282.924504) (xy 285.472632 -282.924504)
			(xy 285.477902 -282.924975) (xy 285.485343 -282.932441) (xy 285.48584 -282.937712) (xy 285.48584 -283.43225)
			(xy 291.530024 -283.43225) (xy 291.530024 -282.937712) (xy 291.530338 -282.932374) (xy 291.537893 -282.92483)
			(xy 291.543232 -282.924504) (xy 291.54374 -282.924504) (xy 292.059614 -282.924504) (xy 292.067425 -282.924196)
			(xy 292.082296 -282.919406) (xy 292.088824 -282.915106) (xy 292.109913 -282.900757) (xy 292.155574 -282.878026)
			(xy 292.20418 -282.862567) (xy 292.254583 -282.854744) (xy 292.305589 -282.854744) (xy 292.355992 -282.862567)
			(xy 292.404598 -282.878026) (xy 292.450259 -282.900757) (xy 292.471348 -282.915106) (xy 292.477869 -282.919415)
			(xy 292.492747 -282.924187) (xy 292.500558 -282.924504) (xy 293.016686 -282.924504) (xy 293.02198 -282.925028)
			(xy 293.02955 -282.93243) (xy 293.030148 -282.937712) (xy 293.030148 -283.43225) (xy 293.030126 -283.432504)
			(xy 299.074332 -283.432504) (xy 299.074332 -283.431996) (xy 299.074332 -282.937712) (xy 299.074639 -282.932372)
			(xy 299.082199 -282.924828) (xy 299.08754 -282.924504) (xy 299.603668 -282.924504) (xy 299.611477 -282.924176)
			(xy 299.626348 -282.9194) (xy 299.632878 -282.915106) (xy 299.653967 -282.900757) (xy 299.699628 -282.878026)
			(xy 299.748234 -282.862567) (xy 299.798637 -282.854744) (xy 299.849643 -282.854744) (xy 299.900046 -282.862567)
			(xy 299.948652 -282.878026) (xy 299.994313 -282.900757) (xy 300.015402 -282.915106) (xy 300.021933 -282.919397)
			(xy 300.036804 -282.92418) (xy 300.044612 -282.924504) (xy 300.56074 -282.924504) (xy 300.566011 -282.924969)
			(xy 300.573452 -282.93244) (xy 300.573948 -282.937712) (xy 300.573948 -283.43225) (xy 306.618132 -283.43225)
			(xy 306.618132 -282.937712) (xy 306.618439 -282.932372) (xy 306.625999 -282.924828) (xy 306.63134 -282.924504)
			(xy 306.631848 -282.924504) (xy 308.104794 -282.924504) (xy 308.110089 -282.925023) (xy 308.117659 -282.932429)
			(xy 308.118256 -282.937712) (xy 308.118256 -282.9961) (xy 345.615301 -282.9961) (xy 345.619471 -282.94577)
			(xy 345.631868 -282.896812) (xy 345.652154 -282.850562) (xy 345.679775 -282.808282) (xy 345.713979 -282.771125)
			(xy 345.753831 -282.740104) (xy 345.798246 -282.716065) (xy 345.846011 -282.699663) (xy 345.895825 -282.691347)
			(xy 345.921076 -282.690824) (xy 346.86113 -282.690824) (xy 346.886386 -282.691284) (xy 346.936209 -282.699603)
			(xy 346.983984 -282.716008) (xy 347.028407 -282.740052) (xy 347.068267 -282.77108) (xy 347.102477 -282.808245)
			(xy 347.130103 -282.850534) (xy 347.150393 -282.896792) (xy 347.162792 -282.94576) (xy 347.166963 -282.9961)
			(xy 348.435372 -282.9961) (xy 348.439544 -282.945758) (xy 348.451945 -282.89679) (xy 348.472238 -282.850531)
			(xy 348.499869 -282.808244) (xy 348.534083 -282.771081) (xy 348.573948 -282.740058) (xy 348.618376 -282.71602)
			(xy 348.666155 -282.699622) (xy 348.715981 -282.691314) (xy 348.741238 -282.690824) (xy 349.681292 -282.690824)
			(xy 349.706553 -282.691252) (xy 349.756386 -282.699567) (xy 349.80417 -282.71597) (xy 349.848603 -282.740015)
			(xy 349.888472 -282.771045) (xy 349.92269 -282.808215) (xy 349.950323 -282.850509) (xy 349.970617 -282.896775)
			(xy 349.98302 -282.945751) (xy 349.987192 -282.9961) (xy 351.255272 -282.9961) (xy 351.259444 -282.945758)
			(xy 351.271846 -282.896789) (xy 351.292139 -282.850529) (xy 351.319771 -282.808241) (xy 351.353986 -282.771079)
			(xy 351.393852 -282.740055) (xy 351.438281 -282.716017) (xy 351.486061 -282.699621) (xy 351.535888 -282.691313)
			(xy 351.561146 -282.690824) (xy 352.5012 -282.690824) (xy 352.526458 -282.691282) (xy 352.576285 -282.699596)
			(xy 352.624064 -282.715999) (xy 352.668491 -282.740042) (xy 352.708355 -282.771069) (xy 352.742569 -282.808235)
			(xy 352.770198 -282.850525) (xy 352.79049 -282.896786) (xy 352.802891 -282.945757) (xy 352.807063 -282.9961)
			(xy 354.075301 -282.9961) (xy 354.079471 -282.945772) (xy 354.091867 -282.896816) (xy 354.112151 -282.850569)
			(xy 354.13977 -282.80829) (xy 354.17397 -282.771133) (xy 354.213819 -282.740111) (xy 354.258231 -282.716071)
			(xy 354.305993 -282.699668) (xy 354.355804 -282.691349) (xy 354.381054 -282.690824) (xy 355.321108 -282.690824)
			(xy 355.346366 -282.691282) (xy 355.396191 -282.699598) (xy 355.443969 -282.716001) (xy 355.488395 -282.740045)
			(xy 355.528258 -282.771072) (xy 355.562471 -282.808238) (xy 355.5901 -282.850528) (xy 355.610391 -282.896788)
			(xy 355.622792 -282.945757) (xy 355.626963 -282.9961) (xy 364.409001 -282.9961) (xy 364.413172 -282.945768)
			(xy 364.425569 -282.896809) (xy 364.445856 -282.850559) (xy 364.473479 -282.808278) (xy 364.507684 -282.77112)
			(xy 364.547539 -282.740099) (xy 364.591955 -282.71606) (xy 364.639723 -282.69966) (xy 364.689538 -282.691346)
			(xy 364.71479 -282.690824) (xy 365.654844 -282.690824) (xy 365.6801 -282.691285) (xy 365.729921 -282.699605)
			(xy 365.777694 -282.716012) (xy 365.822115 -282.740057) (xy 365.861972 -282.771085) (xy 365.89618 -282.80825)
			(xy 365.923805 -282.850538) (xy 365.944094 -282.896795) (xy 365.956492 -282.945761) (xy 365.960663 -282.9961)
			(xy 367.228901 -282.9961) (xy 367.233072 -282.945767) (xy 367.24547 -282.896808) (xy 367.265758 -282.850556)
			(xy 367.293381 -282.808275) (xy 367.327587 -282.771117) (xy 367.367443 -282.740096) (xy 367.411861 -282.716058)
			(xy 367.459629 -282.699659) (xy 367.509445 -282.691346) (xy 367.534698 -282.690824) (xy 368.474752 -282.690824)
			(xy 368.500015 -282.691249) (xy 368.549853 -282.699558) (xy 368.597643 -282.715958) (xy 368.642082 -282.740001)
			(xy 368.681956 -282.771031) (xy 368.716179 -282.808201) (xy 368.743817 -282.850498) (xy 368.764115 -282.896767)
			(xy 368.776519 -282.945747) (xy 368.780692 -282.9961) (xy 370.049101 -282.9961) (xy 370.053271 -282.945771)
			(xy 370.065667 -282.896815) (xy 370.085952 -282.850567) (xy 370.113571 -282.808288) (xy 370.147772 -282.771131)
			(xy 370.187623 -282.740109) (xy 370.232035 -282.716069) (xy 370.279798 -282.699667) (xy 370.329609 -282.691349)
			(xy 370.35486 -282.690824) (xy 371.294914 -282.690824) (xy 371.320171 -282.691283) (xy 371.369996 -282.699599)
			(xy 371.417773 -282.716003) (xy 371.462199 -282.740047) (xy 371.502061 -282.771074) (xy 371.536273 -282.80824)
			(xy 371.563901 -282.850529) (xy 371.584191 -282.896789) (xy 371.596592 -282.945758) (xy 371.600763 -282.9961)
			(xy 372.869001 -282.9961) (xy 372.873171 -282.94577) (xy 372.885568 -282.896814) (xy 372.905853 -282.850565)
			(xy 372.933473 -282.808285) (xy 372.967676 -282.771128) (xy 373.007527 -282.740106) (xy 373.05194 -282.716067)
			(xy 373.099705 -282.699665) (xy 373.149517 -282.691348) (xy 373.174768 -282.690824) (xy 374.114822 -282.690824)
			(xy 374.140079 -282.691283) (xy 374.189903 -282.699601) (xy 374.237679 -282.716005) (xy 374.282103 -282.740049)
			(xy 374.321964 -282.771077) (xy 374.356175 -282.808242) (xy 374.383802 -282.850531) (xy 374.404092 -282.896791)
			(xy 374.416492 -282.945759) (xy 374.420663 -282.9961) (xy 374.416492 -283.046441) (xy 374.404092 -283.095409)
			(xy 374.383802 -283.141669) (xy 374.356175 -283.183958) (xy 374.321964 -283.221123) (xy 374.282103 -283.252151)
			(xy 374.237679 -283.276195) (xy 374.189903 -283.292599) (xy 374.140079 -283.300917) (xy 374.114822 -283.30144)
			(xy 373.174768 -283.30144) (xy 373.149517 -283.300852) (xy 373.099705 -283.292535) (xy 373.05194 -283.276133)
			(xy 373.007527 -283.252094) (xy 372.967676 -283.221072) (xy 372.933473 -283.183915) (xy 372.905853 -283.141635)
			(xy 372.885568 -283.095386) (xy 372.873171 -283.04643) (xy 372.869001 -282.9961) (xy 371.600763 -282.9961)
			(xy 371.596592 -283.046442) (xy 371.584191 -283.095411) (xy 371.563901 -283.141671) (xy 371.536273 -283.18396)
			(xy 371.502061 -283.221126) (xy 371.462199 -283.252153) (xy 371.417773 -283.276197) (xy 371.369996 -283.292601)
			(xy 371.320171 -283.300917) (xy 371.294914 -283.30144) (xy 370.35486 -283.30144) (xy 370.329609 -283.300851)
			(xy 370.279798 -283.292533) (xy 370.232035 -283.276131) (xy 370.187623 -283.252091) (xy 370.147772 -283.221069)
			(xy 370.113571 -283.183912) (xy 370.085952 -283.141633) (xy 370.065667 -283.095385) (xy 370.053271 -283.046429)
			(xy 370.049101 -282.9961) (xy 368.780692 -282.9961) (xy 368.776519 -283.046453) (xy 368.764115 -283.095433)
			(xy 368.743817 -283.141702) (xy 368.716179 -283.183999) (xy 368.681956 -283.221169) (xy 368.642082 -283.252199)
			(xy 368.597643 -283.276242) (xy 368.549853 -283.292642) (xy 368.500015 -283.300951) (xy 368.474752 -283.30144)
			(xy 367.534698 -283.30144) (xy 367.509445 -283.300854) (xy 367.459629 -283.292541) (xy 367.411861 -283.276142)
			(xy 367.367443 -283.252104) (xy 367.327587 -283.221083) (xy 367.293381 -283.183925) (xy 367.265758 -283.141644)
			(xy 367.24547 -283.095392) (xy 367.233072 -283.046433) (xy 367.228901 -282.9961) (xy 365.960663 -282.9961)
			(xy 365.956492 -283.046439) (xy 365.944094 -283.095405) (xy 365.923805 -283.141662) (xy 365.89618 -283.18395)
			(xy 365.861972 -283.221115) (xy 365.822115 -283.252143) (xy 365.777694 -283.276188) (xy 365.729921 -283.292595)
			(xy 365.6801 -283.300915) (xy 365.654844 -283.30144) (xy 364.71479 -283.30144) (xy 364.689538 -283.300854)
			(xy 364.639723 -283.29254) (xy 364.591955 -283.27614) (xy 364.547539 -283.252101) (xy 364.507684 -283.22108)
			(xy 364.473479 -283.183922) (xy 364.445856 -283.141641) (xy 364.425569 -283.095391) (xy 364.413172 -283.046432)
			(xy 364.409001 -282.9961) (xy 355.626963 -282.9961) (xy 355.622792 -283.046443) (xy 355.610391 -283.095412)
			(xy 355.5901 -283.141672) (xy 355.562471 -283.183962) (xy 355.528258 -283.221128) (xy 355.488395 -283.252155)
			(xy 355.443969 -283.276199) (xy 355.396191 -283.292602) (xy 355.346366 -283.300918) (xy 355.321108 -283.30144)
			(xy 354.381054 -283.30144) (xy 354.355804 -283.300851) (xy 354.305993 -283.292532) (xy 354.258231 -283.276129)
			(xy 354.213819 -283.252089) (xy 354.17397 -283.221067) (xy 354.13977 -283.18391) (xy 354.112151 -283.141631)
			(xy 354.091867 -283.095384) (xy 354.079471 -283.046428) (xy 354.075301 -282.9961) (xy 352.807063 -282.9961)
			(xy 352.802891 -283.046443) (xy 352.79049 -283.095414) (xy 352.770198 -283.141675) (xy 352.742569 -283.183965)
			(xy 352.708355 -283.221131) (xy 352.668491 -283.252158) (xy 352.624064 -283.276201) (xy 352.576285 -283.292604)
			(xy 352.526458 -283.300918) (xy 352.5012 -283.30144) (xy 351.561146 -283.30144) (xy 351.535888 -283.300887)
			(xy 351.486061 -283.292579) (xy 351.438281 -283.276183) (xy 351.393852 -283.252145) (xy 351.353986 -283.221121)
			(xy 351.319771 -283.183959) (xy 351.292139 -283.141671) (xy 351.271846 -283.095411) (xy 351.259444 -283.046442)
			(xy 351.255272 -282.9961) (xy 349.987192 -282.9961) (xy 349.98302 -283.046449) (xy 349.970617 -283.095425)
			(xy 349.950323 -283.141691) (xy 349.92269 -283.183985) (xy 349.888472 -283.221155) (xy 349.848603 -283.252185)
			(xy 349.80417 -283.27623) (xy 349.756386 -283.292633) (xy 349.706553 -283.300948) (xy 349.681292 -283.30144)
			(xy 348.741238 -283.30144) (xy 348.715981 -283.300886) (xy 348.666155 -283.292578) (xy 348.618376 -283.27618)
			(xy 348.573948 -283.252142) (xy 348.534083 -283.221119) (xy 348.499869 -283.183956) (xy 348.472238 -283.141669)
			(xy 348.451945 -283.09541) (xy 348.439544 -283.046442) (xy 348.435372 -282.9961) (xy 347.166963 -282.9961)
			(xy 347.162792 -283.04644) (xy 347.150393 -283.095408) (xy 347.130103 -283.141666) (xy 347.102477 -283.183955)
			(xy 347.068267 -283.22112) (xy 347.028407 -283.252148) (xy 346.983984 -283.276192) (xy 346.936209 -283.292597)
			(xy 346.886386 -283.300916) (xy 346.86113 -283.30144) (xy 345.921076 -283.30144) (xy 345.895825 -283.300853)
			(xy 345.846011 -283.292537) (xy 345.798246 -283.276135) (xy 345.753831 -283.252096) (xy 345.713979 -283.221075)
			(xy 345.679775 -283.183918) (xy 345.652154 -283.141638) (xy 345.631868 -283.095388) (xy 345.619471 -283.04643)
			(xy 345.615301 -282.9961) (xy 308.118256 -282.9961) (xy 308.118256 -283.43225) (xy 308.118234 -283.432504)
			(xy 415.718244 -283.432504) (xy 415.718244 -282.937712) (xy 415.718798 -282.932462) (xy 415.726205 -282.925022)
			(xy 415.731452 -282.924504) (xy 417.204652 -282.924504) (xy 417.209981 -282.924861) (xy 417.217525 -282.932384)
			(xy 417.21786 -282.937712) (xy 417.21786 -283.43225) (xy 423.262044 -283.43225) (xy 423.262044 -282.937712)
			(xy 423.262598 -282.932462) (xy 423.270005 -282.925022) (xy 423.275252 -282.924504) (xy 423.27576 -282.924504)
			(xy 423.791634 -282.924504) (xy 423.799441 -282.924162) (xy 423.814313 -282.919395) (xy 423.820844 -282.915106)
			(xy 423.841933 -282.900757) (xy 423.887594 -282.878026) (xy 423.9362 -282.862567) (xy 423.986603 -282.854744)
			(xy 424.037609 -282.854744) (xy 424.088012 -282.862567) (xy 424.136618 -282.878026) (xy 424.182279 -282.900757)
			(xy 424.203368 -282.915106) (xy 424.209907 -282.919384) (xy 424.224771 -282.924175) (xy 424.232578 -282.924504)
			(xy 424.748706 -282.924504) (xy 424.754003 -282.925015) (xy 424.761571 -282.932427) (xy 424.762168 -282.937712)
			(xy 424.762168 -283.43225) (xy 424.762145 -283.432504) (xy 430.806352 -283.432504) (xy 430.806352 -283.431996)
			(xy 430.806352 -282.937712) (xy 430.806899 -282.93246) (xy 430.81431 -282.925019) (xy 430.81956 -282.924504)
			(xy 431.335688 -282.924504) (xy 431.343498 -282.924185) (xy 431.358369 -282.919402) (xy 431.364898 -282.915106)
			(xy 431.385987 -282.900757) (xy 431.431648 -282.878026) (xy 431.480254 -282.862567) (xy 431.530657 -282.854744)
			(xy 431.581663 -282.854744) (xy 431.632066 -282.862567) (xy 431.680672 -282.878026) (xy 431.726333 -282.900757)
			(xy 431.747422 -282.915106) (xy 431.753949 -282.919405) (xy 431.768823 -282.924183) (xy 431.776632 -282.924504)
			(xy 432.29276 -282.924504) (xy 432.29809 -282.924855) (xy 432.305634 -282.932383) (xy 432.305968 -282.937712)
			(xy 432.305968 -283.43225) (xy 438.350152 -283.43225) (xy 438.350152 -282.937712) (xy 438.350699 -282.93246)
			(xy 438.35811 -282.925019) (xy 438.36336 -282.924504) (xy 438.363868 -282.924504) (xy 438.879742 -282.924504)
			(xy 438.88755 -282.924165) (xy 438.902421 -282.919396) (xy 438.908952 -282.915106) (xy 438.930041 -282.900757)
			(xy 438.975702 -282.878026) (xy 439.024308 -282.862567) (xy 439.074711 -282.854744) (xy 439.125717 -282.854744)
			(xy 439.17612 -282.862567) (xy 439.224726 -282.878026) (xy 439.270387 -282.900757) (xy 439.291476 -282.915106)
			(xy 439.298013 -282.919387) (xy 439.312879 -282.924176) (xy 439.320686 -282.924504) (xy 439.836814 -282.924504)
			(xy 439.842112 -282.925009) (xy 439.84968 -282.932425) (xy 439.850276 -282.937712) (xy 439.850276 -283.43225)
			(xy 439.850253 -283.432504) (xy 445.89446 -283.432504) (xy 445.89446 -283.431996) (xy 445.89446 -282.937712)
			(xy 445.895 -282.932458) (xy 445.902416 -282.925017) (xy 445.907668 -282.924504) (xy 446.423796 -282.924504)
			(xy 446.431606 -282.924188) (xy 446.446477 -282.919403) (xy 446.453006 -282.915106) (xy 446.474095 -282.900757)
			(xy 446.519756 -282.878026) (xy 446.568362 -282.862567) (xy 446.618765 -282.854744) (xy 446.669771 -282.854744)
			(xy 446.720174 -282.862567) (xy 446.76878 -282.878026) (xy 446.814441 -282.900757) (xy 446.83553 -282.915106)
			(xy 446.842055 -282.919408) (xy 446.85693 -282.924184) (xy 446.86474 -282.924504) (xy 447.380868 -282.924504)
			(xy 447.386199 -282.92485) (xy 447.393742 -282.932382) (xy 447.394076 -282.937712) (xy 447.394076 -283.43225)
			(xy 447.394051 -283.432504) (xy 453.43826 -283.432504) (xy 453.43826 -283.431996) (xy 453.43826 -282.937712)
			(xy 453.4388 -282.932458) (xy 453.446216 -282.925017) (xy 453.451468 -282.924504) (xy 453.967596 -282.924504)
			(xy 453.975406 -282.924188) (xy 453.990277 -282.919403) (xy 453.996806 -282.915106) (xy 454.017895 -282.900757)
			(xy 454.063556 -282.878026) (xy 454.112162 -282.862567) (xy 454.162565 -282.854744) (xy 454.213571 -282.854744)
			(xy 454.263974 -282.862567) (xy 454.31258 -282.878026) (xy 454.358241 -282.900757) (xy 454.37933 -282.915106)
			(xy 454.385855 -282.919408) (xy 454.40073 -282.924184) (xy 454.40854 -282.924504) (xy 454.924668 -282.924504)
			(xy 454.929999 -282.92485) (xy 454.937542 -282.932382) (xy 454.937876 -282.937712) (xy 454.937876 -283.43225)
			(xy 454.937345 -283.437544) (xy 454.92995 -283.445117) (xy 454.924668 -283.445712) (xy 454.408794 -283.445712)
			(xy 454.400983 -283.446021) (xy 454.386112 -283.45081) (xy 454.379584 -283.45511) (xy 454.358461 -283.469457)
			(xy 454.312738 -283.492186) (xy 454.264065 -283.507617) (xy 454.213599 -283.515383) (xy 454.188068 -283.515816)
			(xy 454.162538 -283.515386) (xy 454.112074 -283.507607) (xy 454.063402 -283.492175) (xy 454.017674 -283.469458)
			(xy 453.996552 -283.45511) (xy 453.99003 -283.450802) (xy 453.975153 -283.446029) (xy 453.967342 -283.445712)
			(xy 453.451468 -283.445712) (xy 453.446202 -283.445227) (xy 453.438762 -283.437771) (xy 453.43826 -283.432504)
			(xy 447.394051 -283.432504) (xy 447.393545 -283.437544) (xy 447.38615 -283.445117) (xy 447.380868 -283.445712)
			(xy 446.864994 -283.445712) (xy 446.857183 -283.446021) (xy 446.842312 -283.45081) (xy 446.835784 -283.45511)
			(xy 446.814661 -283.469457) (xy 446.768938 -283.492186) (xy 446.720265 -283.507617) (xy 446.669799 -283.515383)
			(xy 446.644268 -283.515816) (xy 446.618738 -283.515386) (xy 446.568274 -283.507607) (xy 446.519602 -283.492175)
			(xy 446.473874 -283.469458) (xy 446.452752 -283.45511) (xy 446.44623 -283.450802) (xy 446.431353 -283.446029)
			(xy 446.423542 -283.445712) (xy 445.907668 -283.445712) (xy 445.902402 -283.445227) (xy 445.894962 -283.437771)
			(xy 445.89446 -283.432504) (xy 439.850253 -283.432504) (xy 439.849784 -283.437617) (xy 439.842182 -283.445198)
			(xy 439.836814 -283.445712) (xy 439.32094 -283.445712) (xy 439.313131 -283.44604) (xy 439.29826 -283.450816)
			(xy 439.29173 -283.45511) (xy 439.270622 -283.469481) (xy 439.224894 -283.492204) (xy 439.176216 -283.507628)
			(xy 439.125746 -283.515387) (xy 439.100214 -283.515816) (xy 439.074684 -283.515363) (xy 439.024222 -283.507591)
			(xy 438.975549 -283.492166) (xy 438.929821 -283.469455) (xy 438.908698 -283.45511) (xy 438.902166 -283.45082)
			(xy 438.887296 -283.446036) (xy 438.879488 -283.445712) (xy 438.363614 -283.445712) (xy 438.358264 -283.445145)
			(xy 438.35068 -283.437598) (xy 438.350152 -283.43225) (xy 432.305968 -283.43225) (xy 432.305444 -283.437546)
			(xy 432.298044 -283.44512) (xy 432.29276 -283.445712) (xy 431.776886 -283.445712) (xy 431.769075 -283.446018)
			(xy 431.754204 -283.450809) (xy 431.747676 -283.45511) (xy 431.726555 -283.469461) (xy 431.680832 -283.492188)
			(xy 431.632158 -283.507618) (xy 431.581691 -283.515384) (xy 431.55616 -283.515816) (xy 431.530629 -283.51539)
			(xy 431.480166 -283.50761) (xy 431.431493 -283.492177) (xy 431.385766 -283.469458) (xy 431.364644 -283.45511)
			(xy 431.358124 -283.450799) (xy 431.343245 -283.446028) (xy 431.335434 -283.445712) (xy 430.81956 -283.445712)
			(xy 430.814293 -283.445232) (xy 430.806853 -283.437772) (xy 430.806352 -283.432504) (xy 424.762145 -283.432504)
			(xy 424.761683 -283.437619) (xy 424.754076 -283.445201) (xy 424.748706 -283.445712) (xy 424.232832 -283.445712)
			(xy 424.225023 -283.446037) (xy 424.210151 -283.450815) (xy 424.203622 -283.45511) (xy 424.182488 -283.469441)
			(xy 424.136769 -283.492173) (xy 424.0881 -283.507608) (xy 424.037636 -283.51538) (xy 424.012106 -283.515816)
			(xy 423.986576 -283.515367) (xy 423.936113 -283.507593) (xy 423.887441 -283.492168) (xy 423.841713 -283.469455)
			(xy 423.82059 -283.45511) (xy 423.814059 -283.450817) (xy 423.799189 -283.446035) (xy 423.79138 -283.445712)
			(xy 423.275506 -283.445712) (xy 423.270155 -283.445151) (xy 423.262571 -283.437599) (xy 423.262044 -283.43225)
			(xy 417.21786 -283.43225) (xy 417.217343 -283.437548) (xy 417.209938 -283.445122) (xy 417.204652 -283.445712)
			(xy 415.731452 -283.445712) (xy 415.726184 -283.445237) (xy 415.718745 -283.437773) (xy 415.718244 -283.432504)
			(xy 308.118234 -283.432504) (xy 308.117782 -283.437621) (xy 308.110167 -283.445204) (xy 308.104794 -283.445712)
			(xy 306.631594 -283.445712) (xy 306.626241 -283.445159) (xy 306.618659 -283.437601) (xy 306.618132 -283.43225)
			(xy 300.573948 -283.43225) (xy 300.573442 -283.437551) (xy 300.566029 -283.445125) (xy 300.56074 -283.445712)
			(xy 300.044866 -283.445712) (xy 300.037058 -283.446052) (xy 300.022187 -283.45082) (xy 300.015656 -283.45511)
			(xy 299.994541 -283.46947) (xy 299.948815 -283.492195) (xy 299.90014 -283.507623) (xy 299.849672 -283.515385)
			(xy 299.82414 -283.515816) (xy 299.798611 -283.51535) (xy 299.748149 -283.507582) (xy 299.699476 -283.492161)
			(xy 299.653747 -283.469453) (xy 299.632624 -283.45511) (xy 299.626086 -283.45083) (xy 299.611221 -283.44604)
			(xy 299.603414 -283.445712) (xy 299.08754 -283.445712) (xy 299.082214 -283.445347) (xy 299.074671 -283.437829)
			(xy 299.074332 -283.432504) (xy 293.030126 -283.432504) (xy 293.029681 -283.437623) (xy 293.022062 -283.445207)
			(xy 293.016686 -283.445712) (xy 292.500812 -283.445712) (xy 292.493002 -283.446029) (xy 292.478131 -283.450812)
			(xy 292.471602 -283.45511) (xy 292.450474 -283.46945) (xy 292.404753 -283.49218) (xy 292.356082 -283.507613)
			(xy 292.305616 -283.515382) (xy 292.280086 -283.515816) (xy 292.254556 -283.515377) (xy 292.204093 -283.5076)
			(xy 292.15542 -283.492172) (xy 292.109692 -283.469456) (xy 292.08857 -283.45511) (xy 292.082044 -283.450809)
			(xy 292.06717 -283.446032) (xy 292.05936 -283.445712) (xy 291.543486 -283.445712) (xy 291.538132 -283.445164)
			(xy 291.530551 -283.437602) (xy 291.530024 -283.43225) (xy 285.48584 -283.43225) (xy 285.485341 -283.437553)
			(xy 285.477924 -283.445128) (xy 285.472632 -283.445712) (xy 284.956758 -283.445712) (xy 284.94895 -283.446049)
			(xy 284.934078 -283.450819) (xy 284.927548 -283.45511) (xy 284.906435 -283.469473) (xy 284.860709 -283.492198)
			(xy 284.812033 -283.507624) (xy 284.761564 -283.515386) (xy 284.736032 -283.515816) (xy 284.710503 -283.515354)
			(xy 284.66004 -283.507584) (xy 284.611368 -283.492162) (xy 284.565639 -283.469453) (xy 284.544516 -283.45511)
			(xy 284.53798 -283.450827) (xy 284.523113 -283.446039) (xy 284.515306 -283.445712) (xy 283.999432 -283.445712)
			(xy 283.994105 -283.445352) (xy 283.986563 -283.43783) (xy 283.986224 -283.432504) (xy 277.942016 -283.432504)
			(xy 277.941541 -283.437553) (xy 277.934124 -283.445128) (xy 277.928832 -283.445712) (xy 277.412958 -283.445712)
			(xy 277.40515 -283.446049) (xy 277.390278 -283.450819) (xy 277.383748 -283.45511) (xy 277.362635 -283.469473)
			(xy 277.316909 -283.492198) (xy 277.268233 -283.507624) (xy 277.217764 -283.515386) (xy 277.192232 -283.515816)
			(xy 277.166703 -283.515354) (xy 277.11624 -283.507584) (xy 277.067568 -283.492162) (xy 277.021839 -283.469453)
			(xy 277.000716 -283.45511) (xy 276.99418 -283.450827) (xy 276.979313 -283.446039) (xy 276.971506 -283.445712)
			(xy 276.455632 -283.445712) (xy 276.450305 -283.445352) (xy 276.442763 -283.43783) (xy 276.442424 -283.432504)
			(xy 270.398218 -283.432504) (xy 270.39778 -283.437625) (xy 270.390156 -283.445209) (xy 270.384778 -283.445712)
			(xy 269.868904 -283.445712) (xy 269.861094 -283.446025) (xy 269.846222 -283.450811) (xy 269.839694 -283.45511)
			(xy 269.818568 -283.469453) (xy 269.772846 -283.492182) (xy 269.724174 -283.507614) (xy 269.673709 -283.515382)
			(xy 269.648178 -283.515816) (xy 269.622648 -283.515381) (xy 269.572184 -283.507603) (xy 269.523512 -283.492173)
			(xy 269.477784 -283.469457) (xy 269.456662 -283.45511) (xy 269.450138 -283.450806) (xy 269.435262 -283.446031)
			(xy 269.427452 -283.445712) (xy 268.911578 -283.445712) (xy 268.906223 -283.445169) (xy 268.898642 -283.437603)
			(xy 268.898116 -283.43225) (xy 206.997808 -283.43225) (xy 206.997808 -283.432504) (xy 206.997308 -283.437767)
			(xy 206.989863 -283.44521) (xy 206.9846 -283.445712) (xy 206.468726 -283.445712) (xy 206.46085 -283.445982)
			(xy 206.445846 -283.450778) (xy 206.439262 -283.45511) (xy 206.418182 -283.469498) (xy 206.372539 -283.492329)
			(xy 206.323933 -283.507888) (xy 206.273517 -283.515807) (xy 206.248 -283.516324) (xy 206.222479 -283.515847)
			(xy 206.172052 -283.507948) (xy 206.123441 -283.492384) (xy 206.077803 -283.469526) (xy 206.056738 -283.45511)
			(xy 206.050139 -283.450808) (xy 206.035145 -283.446013) (xy 206.027274 -283.445712) (xy 205.5114 -283.445712)
			(xy 205.506138 -283.445206) (xy 205.498696 -283.437766) (xy 205.498192 -283.432504) (xy 199.454008 -283.432504)
			(xy 199.453508 -283.437767) (xy 199.446063 -283.44521) (xy 199.4408 -283.445712) (xy 198.924926 -283.445712)
			(xy 198.91705 -283.445982) (xy 198.902046 -283.450778) (xy 198.895462 -283.45511) (xy 198.874382 -283.469498)
			(xy 198.828739 -283.492329) (xy 198.780133 -283.507888) (xy 198.729717 -283.515807) (xy 198.7042 -283.516324)
			(xy 198.678679 -283.515847) (xy 198.628252 -283.507948) (xy 198.579641 -283.492384) (xy 198.534003 -283.469526)
			(xy 198.512938 -283.45511) (xy 198.506339 -283.450808) (xy 198.491345 -283.446013) (xy 198.483474 -283.445712)
			(xy 197.9676 -283.445712) (xy 197.962338 -283.445206) (xy 197.954896 -283.437766) (xy 197.954392 -283.432504)
			(xy 191.910208 -283.432504) (xy 191.909708 -283.437767) (xy 191.902263 -283.44521) (xy 191.897 -283.445712)
			(xy 191.896492 -283.445712) (xy 191.380872 -283.445712) (xy 191.372998 -283.446001) (xy 191.357994 -283.450785)
			(xy 191.351408 -283.45511) (xy 191.330344 -283.469522) (xy 191.284694 -283.492347) (xy 191.236084 -283.507899)
			(xy 191.185664 -283.515811) (xy 191.160146 -283.516324) (xy 191.134626 -283.515824) (xy 191.0842 -283.507932)
			(xy 191.035588 -283.492375) (xy 190.98995 -283.469523) (xy 190.968884 -283.45511) (xy 190.962297 -283.450787)
			(xy 190.947294 -283.446005) (xy 190.93942 -283.445712) (xy 190.423546 -283.445712) (xy 190.418236 -283.44524)
			(xy 190.41066 -283.437804) (xy 190.410084 -283.432504) (xy 184.3659 -283.432504) (xy 184.365575 -283.437839)
			(xy 184.358027 -283.44538) (xy 184.352692 -283.445712) (xy 183.836818 -283.445712) (xy 183.828945 -283.446022)
			(xy 183.813942 -283.450791) (xy 183.807354 -283.45511) (xy 183.786277 -283.469502) (xy 183.740632 -283.492331)
			(xy 183.692026 -283.507889) (xy 183.641609 -283.515808) (xy 183.616092 -283.516324) (xy 183.590573 -283.515801)
			(xy 183.540148 -283.507916) (xy 183.491536 -283.492365) (xy 183.445896 -283.46952) (xy 183.42483 -283.45511)
			(xy 183.418233 -283.450805) (xy 183.403237 -283.446012) (xy 183.395366 -283.445712) (xy 182.879492 -283.445712)
			(xy 182.874229 -283.445211) (xy 182.866787 -283.437767) (xy 182.866284 -283.432504) (xy 176.8221 -283.432504)
			(xy 176.821775 -283.437839) (xy 176.814227 -283.44538) (xy 176.808892 -283.445712) (xy 176.808384 -283.445712)
			(xy 176.292764 -283.445712) (xy 176.284889 -283.445998) (xy 176.269886 -283.450783) (xy 176.2633 -283.45511)
			(xy 176.24221 -283.469482) (xy 176.19657 -283.492316) (xy 176.147968 -283.507879) (xy 176.097554 -283.515804)
			(xy 176.072038 -283.516324) (xy 176.046518 -283.515828) (xy 175.996092 -283.507935) (xy 175.94748 -283.492376)
			(xy 175.901841 -283.469524) (xy 175.880776 -283.45511) (xy 175.874191 -283.450784) (xy 175.859186 -283.446004)
			(xy 175.851312 -283.445712) (xy 175.335438 -283.445712) (xy 175.330127 -283.445246) (xy 175.322551 -283.437805)
			(xy 175.321976 -283.432504) (xy 169.277792 -283.432504) (xy 169.277474 -283.437841) (xy 169.269921 -283.445382)
			(xy 169.264584 -283.445712) (xy 167.791384 -283.445712) (xy 167.78612 -283.445217) (xy 167.778679 -283.437768)
			(xy 167.778176 -283.432504) (xy 60.178188 -283.432504) (xy 60.177874 -283.437842) (xy 60.170318 -283.445383)
			(xy 60.16498 -283.445712) (xy 60.164472 -283.445712) (xy 58.691526 -283.445712) (xy 58.686214 -283.445254)
			(xy 58.678638 -283.437807) (xy 58.678064 -283.432504) (xy 52.63388 -283.432504) (xy 52.633573 -283.437844)
			(xy 52.626012 -283.445386) (xy 52.620672 -283.445712) (xy 52.104798 -283.445712) (xy 52.096925 -283.446013)
			(xy 52.081921 -283.450788) (xy 52.075334 -283.45511) (xy 52.054262 -283.469511) (xy 52.008616 -283.492338)
			(xy 51.960008 -283.507893) (xy 51.909589 -283.515809) (xy 51.884072 -283.516324) (xy 51.858553 -283.515811)
			(xy 51.808127 -283.507923) (xy 51.759515 -283.49237) (xy 51.713876 -283.469522) (xy 51.69281 -283.45511)
			(xy 51.686217 -283.450797) (xy 51.671218 -283.446009) (xy 51.663346 -283.445712) (xy 51.147472 -283.445712)
			(xy 51.142207 -283.445224) (xy 51.134766 -283.43777) (xy 51.134264 -283.432504) (xy 45.09008 -283.432504)
			(xy 45.089773 -283.437844) (xy 45.082212 -283.445386) (xy 45.076872 -283.445712) (xy 45.076364 -283.445712)
			(xy 44.560744 -283.445712) (xy 44.552869 -283.44599) (xy 44.537865 -283.450781) (xy 44.53128 -283.45511)
			(xy 44.510195 -283.469491) (xy 44.464554 -283.492323) (xy 44.41595 -283.507884) (xy 44.365534 -283.515806)
			(xy 44.340018 -283.516324) (xy 44.314498 -283.515838) (xy 44.264071 -283.507942) (xy 44.215459 -283.49238)
			(xy 44.169821 -283.469525) (xy 44.148756 -283.45511) (xy 44.142176 -283.450776) (xy 44.127167 -283.446001)
			(xy 44.119292 -283.445712) (xy 43.603418 -283.445712) (xy 43.598105 -283.445259) (xy 43.59053 -283.437809)
			(xy 43.589956 -283.432504) (xy 37.545772 -283.432504) (xy 37.545472 -283.437846) (xy 37.537907 -283.445388)
			(xy 37.532564 -283.445712) (xy 37.01669 -283.445712) (xy 37.008816 -283.446009) (xy 36.993813 -283.450787)
			(xy 36.987226 -283.45511) (xy 36.966157 -283.469514) (xy 36.920509 -283.492341) (xy 36.871901 -283.507895)
			(xy 36.821481 -283.51581) (xy 36.795964 -283.516324) (xy 36.770445 -283.515815) (xy 36.720019 -283.507926)
			(xy 36.671407 -283.492371) (xy 36.625768 -283.469522) (xy 36.604702 -283.45511) (xy 36.598111 -283.450794)
			(xy 36.583111 -283.446008) (xy 36.575238 -283.445712) (xy 36.059364 -283.445712) (xy 36.054098 -283.445229)
			(xy 36.046658 -283.437771) (xy 36.046156 -283.432504) (xy 30.001972 -283.432504) (xy 30.001672 -283.437846)
			(xy 29.994107 -283.445388) (xy 29.988764 -283.445712) (xy 29.47289 -283.445712) (xy 29.465016 -283.446009)
			(xy 29.450013 -283.450787) (xy 29.443426 -283.45511) (xy 29.422357 -283.469514) (xy 29.376709 -283.492341)
			(xy 29.328101 -283.507895) (xy 29.277681 -283.51581) (xy 29.252164 -283.516324) (xy 29.226645 -283.515815)
			(xy 29.176219 -283.507926) (xy 29.127607 -283.492371) (xy 29.081968 -283.469522) (xy 29.060902 -283.45511)
			(xy 29.054311 -283.450794) (xy 29.039311 -283.446008) (xy 29.031438 -283.445712) (xy 28.515564 -283.445712)
			(xy 28.510298 -283.445229) (xy 28.502858 -283.437771) (xy 28.502356 -283.432504) (xy 22.458172 -283.432504)
			(xy 22.457872 -283.437846) (xy 22.450307 -283.445388) (xy 22.444964 -283.445712) (xy 22.444456 -283.445712)
			(xy 21.928836 -283.445712) (xy 21.92096 -283.445986) (xy 21.905957 -283.45078) (xy 21.899372 -283.45511)
			(xy 21.87829 -283.469494) (xy 21.832647 -283.492325) (xy 21.784042 -283.507885) (xy 21.733626 -283.515806)
			(xy 21.70811 -283.516324) (xy 21.68259 -283.515842) (xy 21.632163 -283.507944) (xy 21.583551 -283.492382)
			(xy 21.537913 -283.469526) (xy 21.516848 -283.45511) (xy 21.510269 -283.450773) (xy 21.495259 -283.446)
			(xy 21.487384 -283.445712) (xy 20.97151 -283.445712) (xy 20.966196 -283.445264) (xy 20.958622 -283.43781)
			(xy 20.958048 -283.432504) (xy 2.509012 -283.432504) (xy 2.509012 -284.282388) (xy 16.85798 -284.282388)
			(xy 16.85798 -283.78785) (xy 16.858422 -283.78247) (xy 16.866059 -283.774885) (xy 16.871442 -283.774388)
			(xy 17.38757 -283.774388) (xy 17.395379 -283.774064) (xy 17.410251 -283.769285) (xy 17.41678 -283.76499)
			(xy 17.437869 -283.750641) (xy 17.48353 -283.72791) (xy 17.532136 -283.712451) (xy 17.582539 -283.704628)
			(xy 17.633545 -283.704628) (xy 17.683948 -283.712451) (xy 17.732554 -283.72791) (xy 17.778215 -283.750641)
			(xy 17.799304 -283.76499) (xy 17.805836 -283.769281) (xy 17.820706 -283.774064) (xy 17.828514 -283.774388)
			(xy 18.344642 -283.774388) (xy 18.349999 -283.774917) (xy 18.35758 -283.782493) (xy 18.358104 -283.78785)
			(xy 18.358104 -284.282388) (xy 24.402288 -284.282388) (xy 24.402288 -283.78785) (xy 24.402762 -283.782541)
			(xy 24.410197 -283.774964) (xy 24.415496 -283.774388) (xy 24.931624 -283.774388) (xy 24.939435 -283.774087)
			(xy 24.954307 -283.769292) (xy 24.960834 -283.76499) (xy 24.981923 -283.750641) (xy 25.027584 -283.72791)
			(xy 25.07619 -283.712451) (xy 25.126593 -283.704628) (xy 25.177599 -283.704628) (xy 25.228002 -283.712451)
			(xy 25.276608 -283.72791) (xy 25.322269 -283.750641) (xy 25.343358 -283.76499) (xy 25.349878 -283.769301)
			(xy 25.364757 -283.774072) (xy 25.372568 -283.774388) (xy 25.888696 -283.774388) (xy 25.893957 -283.774897)
			(xy 25.9014 -283.782335) (xy 25.901904 -283.787596) (xy 25.901904 -283.788104) (xy 25.901904 -284.282388)
			(xy 31.946088 -284.282388) (xy 31.946088 -283.78785) (xy 31.946562 -283.782541) (xy 31.953997 -283.774964)
			(xy 31.959296 -283.774388) (xy 32.475424 -283.774388) (xy 32.483235 -283.774087) (xy 32.498107 -283.769292)
			(xy 32.504634 -283.76499) (xy 32.525723 -283.750641) (xy 32.571384 -283.72791) (xy 32.61999 -283.712451)
			(xy 32.670393 -283.704628) (xy 32.721399 -283.704628) (xy 32.771802 -283.712451) (xy 32.820408 -283.72791)
			(xy 32.866069 -283.750641) (xy 32.887158 -283.76499) (xy 32.893678 -283.769301) (xy 32.908557 -283.774072)
			(xy 32.916368 -283.774388) (xy 33.432496 -283.774388) (xy 33.437757 -283.774897) (xy 33.4452 -283.782335)
			(xy 33.445704 -283.787596) (xy 33.445704 -283.788104) (xy 33.445704 -284.282388) (xy 39.489888 -284.282388)
			(xy 39.489888 -283.78785) (xy 39.490412 -283.782492) (xy 39.497992 -283.774912) (xy 39.50335 -283.774388)
			(xy 40.019478 -283.774388) (xy 40.027287 -283.774067) (xy 40.042159 -283.769286) (xy 40.048688 -283.76499)
			(xy 40.069777 -283.750641) (xy 40.115438 -283.72791) (xy 40.164044 -283.712451) (xy 40.214447 -283.704628)
			(xy 40.265453 -283.704628) (xy 40.315856 -283.712451) (xy 40.364462 -283.72791) (xy 40.410123 -283.750641)
			(xy 40.431212 -283.76499) (xy 40.437742 -283.769284) (xy 40.452613 -283.774065) (xy 40.460422 -283.774388)
			(xy 40.97655 -283.774388) (xy 40.981908 -283.774912) (xy 40.989488 -283.782492) (xy 40.990012 -283.78785)
			(xy 40.990012 -284.282388) (xy 47.034196 -284.282388) (xy 47.034196 -283.78785) (xy 47.034752 -283.782562)
			(xy 47.04213 -283.774991) (xy 47.047404 -283.774388) (xy 47.563532 -283.774388) (xy 47.57134 -283.774047)
			(xy 47.586211 -283.76928) (xy 47.592742 -283.76499) (xy 47.613831 -283.750641) (xy 47.659492 -283.72791)
			(xy 47.708098 -283.712451) (xy 47.758501 -283.704628) (xy 47.809507 -283.704628) (xy 47.85991 -283.712451)
			(xy 47.908516 -283.72791) (xy 47.954177 -283.750641) (xy 47.975266 -283.76499) (xy 47.981806 -283.769266)
			(xy 47.99667 -283.774059) (xy 48.004476 -283.774388) (xy 48.520604 -283.774388) (xy 48.525866 -283.774891)
			(xy 48.533309 -283.782334) (xy 48.533812 -283.787596) (xy 48.533812 -283.788104) (xy 48.533812 -284.282388)
			(xy 54.577996 -284.282388) (xy 54.577996 -283.78785) (xy 54.578513 -283.78249) (xy 54.586098 -283.77491)
			(xy 54.591458 -283.774388) (xy 56.064658 -283.774388) (xy 56.070005 -283.774973) (xy 56.07759 -283.782507)
			(xy 56.07812 -283.78785) (xy 56.07812 -283.8064) (xy 108.485161 -283.8064) (xy 108.489332 -283.756061)
			(xy 108.501732 -283.707095) (xy 108.522022 -283.660838) (xy 108.549649 -283.618552) (xy 108.583859 -283.581389)
			(xy 108.623719 -283.550364) (xy 108.668142 -283.526323) (xy 108.715916 -283.509921) (xy 108.765738 -283.501606)
			(xy 108.790994 -283.501084) (xy 109.731048 -283.501084) (xy 109.7563 -283.501625) (xy 109.806114 -283.509945)
			(xy 109.85388 -283.52635) (xy 109.898295 -283.550392) (xy 109.938147 -283.581416) (xy 109.97235 -283.618576)
			(xy 109.999971 -283.660858) (xy 110.020256 -283.707109) (xy 110.032653 -283.756068) (xy 110.036823 -283.8064)
			(xy 114.118832 -283.8064) (xy 114.123004 -283.756054) (xy 114.135406 -283.707082) (xy 114.155699 -283.660819)
			(xy 114.183331 -283.618527) (xy 114.217547 -283.581361) (xy 114.257413 -283.550333) (xy 114.301844 -283.52629)
			(xy 114.349625 -283.509889) (xy 114.399455 -283.501576) (xy 114.424714 -283.501084) (xy 115.364768 -283.501084)
			(xy 115.390027 -283.50159) (xy 115.439856 -283.5099) (xy 115.487638 -283.526299) (xy 115.532068 -283.55034)
			(xy 115.571936 -283.581366) (xy 115.606152 -283.618531) (xy 115.633784 -283.660822) (xy 115.654078 -283.707084)
			(xy 115.66648 -283.756055) (xy 115.670652 -283.8064) (xy 115.66648 -283.856745) (xy 115.654078 -283.905716)
			(xy 115.633784 -283.951978) (xy 115.606152 -283.994269) (xy 115.571936 -284.031434) (xy 115.532068 -284.06246)
			(xy 115.487638 -284.086501) (xy 115.439856 -284.1029) (xy 115.390027 -284.11121) (xy 115.364768 -284.1117)
			(xy 114.424714 -284.1117) (xy 114.399455 -284.111224) (xy 114.349625 -284.102911) (xy 114.301844 -284.08651)
			(xy 114.257413 -284.062467) (xy 114.217547 -284.031439) (xy 114.183331 -283.994273) (xy 114.155699 -283.951981)
			(xy 114.135406 -283.905718) (xy 114.123004 -283.856746) (xy 114.118832 -283.8064) (xy 110.036823 -283.8064)
			(xy 110.032653 -283.856732) (xy 110.020256 -283.905691) (xy 109.999971 -283.951942) (xy 109.97235 -283.994224)
			(xy 109.938147 -284.031384) (xy 109.898295 -284.062408) (xy 109.85388 -284.08645) (xy 109.806114 -284.102855)
			(xy 109.7563 -284.111175) (xy 109.731048 -284.1117) (xy 108.790994 -284.1117) (xy 108.765738 -284.111194)
			(xy 108.715916 -284.102879) (xy 108.668142 -284.086477) (xy 108.623719 -284.062436) (xy 108.583859 -284.031411)
			(xy 108.549649 -283.994248) (xy 108.522022 -283.951962) (xy 108.501732 -283.905705) (xy 108.489332 -283.856739)
			(xy 108.485161 -283.8064) (xy 56.07812 -283.8064) (xy 56.07812 -284.282388) (xy 163.678108 -284.282388)
			(xy 163.678108 -283.78785) (xy 163.678653 -283.782559) (xy 163.686039 -283.774987) (xy 163.691316 -283.774388)
			(xy 165.164516 -283.774388) (xy 165.16978 -283.774883) (xy 165.177221 -283.782332) (xy 165.177724 -283.787596)
			(xy 165.177724 -283.788104) (xy 165.177724 -284.282388) (xy 171.221908 -284.282388) (xy 171.221908 -283.78785)
			(xy 171.222414 -283.782487) (xy 171.230007 -283.774906) (xy 171.23537 -283.774388) (xy 171.751498 -283.774388)
			(xy 171.759308 -283.774076) (xy 171.77418 -283.769289) (xy 171.780708 -283.76499) (xy 171.801797 -283.750641)
			(xy 171.847458 -283.72791) (xy 171.896064 -283.712451) (xy 171.946467 -283.704628) (xy 171.997473 -283.704628)
			(xy 172.047876 -283.712451) (xy 172.096482 -283.72791) (xy 172.142143 -283.750641) (xy 172.163232 -283.76499)
			(xy 172.169758 -283.769291) (xy 172.184632 -283.774068) (xy 172.192442 -283.774388) (xy 172.70857 -283.774388)
			(xy 172.713918 -283.774965) (xy 172.721503 -283.782505) (xy 172.722032 -283.78785) (xy 172.722032 -284.282388)
			(xy 178.766216 -284.282388) (xy 178.766216 -283.78785) (xy 178.766754 -283.782557) (xy 178.774145 -283.774985)
			(xy 178.779424 -283.774388) (xy 179.295552 -283.774388) (xy 179.30336 -283.774056) (xy 179.318232 -283.769283)
			(xy 179.324762 -283.76499) (xy 179.345851 -283.750641) (xy 179.391512 -283.72791) (xy 179.440118 -283.712451)
			(xy 179.490521 -283.704628) (xy 179.541527 -283.704628) (xy 179.59193 -283.712451) (xy 179.640536 -283.72791)
			(xy 179.686197 -283.750641) (xy 179.707286 -283.76499) (xy 179.713822 -283.769274) (xy 179.728689 -283.774062)
			(xy 179.736496 -283.774388) (xy 180.252624 -283.774388) (xy 180.257889 -283.774879) (xy 180.265329 -283.782331)
			(xy 180.265832 -283.787596) (xy 180.265832 -283.788104) (xy 180.265832 -284.282388) (xy 186.310016 -284.282388)
			(xy 186.310016 -283.78785) (xy 186.310515 -283.782485) (xy 186.318112 -283.774904) (xy 186.323478 -283.774388)
			(xy 186.839606 -283.774388) (xy 186.847417 -283.774079) (xy 186.862288 -283.76929) (xy 186.868816 -283.76499)
			(xy 186.889905 -283.750641) (xy 186.935566 -283.72791) (xy 186.984172 -283.712451) (xy 187.034575 -283.704628)
			(xy 187.085581 -283.704628) (xy 187.135984 -283.712451) (xy 187.18459 -283.72791) (xy 187.230251 -283.750641)
			(xy 187.25134 -283.76499) (xy 187.257864 -283.769294) (xy 187.27274 -283.77407) (xy 187.28055 -283.774388)
			(xy 187.796678 -283.774388) (xy 187.802027 -283.77496) (xy 187.809611 -283.782504) (xy 187.81014 -283.78785)
			(xy 187.81014 -284.282388) (xy 193.854324 -284.282388) (xy 193.854324 -283.78785) (xy 193.854855 -283.782556)
			(xy 193.86225 -283.774983) (xy 193.867532 -283.774388) (xy 194.38366 -283.774388) (xy 194.391469 -283.77406)
			(xy 194.40634 -283.769284) (xy 194.41287 -283.76499) (xy 194.433959 -283.750641) (xy 194.47962 -283.72791)
			(xy 194.528226 -283.712451) (xy 194.578629 -283.704628) (xy 194.629635 -283.704628) (xy 194.680038 -283.712451)
			(xy 194.728644 -283.72791) (xy 194.774305 -283.750641) (xy 194.795394 -283.76499) (xy 194.801928 -283.769277)
			(xy 194.816796 -283.774063) (xy 194.824604 -283.774388) (xy 195.340732 -283.774388) (xy 195.345998 -283.774873)
			(xy 195.353438 -283.782329) (xy 195.35394 -283.787596) (xy 195.35394 -283.788104) (xy 195.35394 -284.282388)
			(xy 201.398124 -284.282388) (xy 201.398124 -283.78785) (xy 201.398655 -283.782556) (xy 201.40605 -283.774983)
			(xy 201.411332 -283.774388) (xy 201.92746 -283.774388) (xy 201.935269 -283.77406) (xy 201.95014 -283.769284)
			(xy 201.95667 -283.76499) (xy 201.977759 -283.750641) (xy 202.02342 -283.72791) (xy 202.072026 -283.712451)
			(xy 202.122429 -283.704628) (xy 202.173435 -283.704628) (xy 202.223838 -283.712451) (xy 202.272444 -283.72791)
			(xy 202.318105 -283.750641) (xy 202.339194 -283.76499) (xy 202.345728 -283.769277) (xy 202.360596 -283.774063)
			(xy 202.368404 -283.774388) (xy 202.884532 -283.774388) (xy 202.889798 -283.774873) (xy 202.897238 -283.782329)
			(xy 202.89774 -283.787596) (xy 202.89774 -283.788104) (xy 202.89774 -284.282134) (xy 264.798048 -284.282134)
			(xy 264.798048 -283.787596) (xy 264.798587 -283.782343) (xy 264.806005 -283.774903) (xy 264.811256 -283.774388)
			(xy 264.811764 -283.774388) (xy 265.327638 -283.774388) (xy 265.335446 -283.77405) (xy 265.350317 -283.769281)
			(xy 265.356848 -283.76499) (xy 265.377937 -283.750641) (xy 265.423598 -283.72791) (xy 265.472204 -283.712451)
			(xy 265.522607 -283.704628) (xy 265.573613 -283.704628) (xy 265.624016 -283.712451) (xy 265.672622 -283.72791)
			(xy 265.718283 -283.750641) (xy 265.739372 -283.76499) (xy 265.745911 -283.769268) (xy 265.760775 -283.77406)
			(xy 265.768582 -283.774388) (xy 266.28471 -283.774388) (xy 266.290027 -283.774822) (xy 266.2976 -283.782287)
			(xy 266.298172 -283.787596) (xy 266.298172 -284.282134) (xy 266.298148 -284.282388) (xy 272.342356 -284.282388)
			(xy 272.342356 -284.28188) (xy 272.342356 -283.787596) (xy 272.342888 -283.782341) (xy 272.350311 -283.774901)
			(xy 272.355564 -283.774388) (xy 272.871692 -283.774388) (xy 272.879502 -283.774073) (xy 272.894373 -283.769288)
			(xy 272.900902 -283.76499) (xy 272.921991 -283.750641) (xy 272.967652 -283.72791) (xy 273.016258 -283.712451)
			(xy 273.066661 -283.704628) (xy 273.117667 -283.704628) (xy 273.16807 -283.712451) (xy 273.216676 -283.72791)
			(xy 273.262337 -283.750641) (xy 273.283426 -283.76499) (xy 273.289953 -283.769289) (xy 273.304826 -283.774067)
			(xy 273.312636 -283.774388) (xy 273.828764 -283.774388) (xy 273.834091 -283.774751) (xy 273.841633 -283.782271)
			(xy 273.841972 -283.787596) (xy 273.841972 -284.282134) (xy 273.841949 -284.282388) (xy 279.886156 -284.282388)
			(xy 279.886156 -284.28188) (xy 279.886156 -283.787596) (xy 279.886688 -283.782341) (xy 279.894111 -283.774901)
			(xy 279.899364 -283.774388) (xy 280.415492 -283.774388) (xy 280.423302 -283.774073) (xy 280.438173 -283.769288)
			(xy 280.444702 -283.76499) (xy 280.465791 -283.750641) (xy 280.511452 -283.72791) (xy 280.560058 -283.712451)
			(xy 280.610461 -283.704628) (xy 280.661467 -283.704628) (xy 280.71187 -283.712451) (xy 280.760476 -283.72791)
			(xy 280.806137 -283.750641) (xy 280.827226 -283.76499) (xy 280.833753 -283.769289) (xy 280.848626 -283.774067)
			(xy 280.856436 -283.774388) (xy 281.372564 -283.774388) (xy 281.377891 -283.774751) (xy 281.385433 -283.782271)
			(xy 281.385772 -283.787596) (xy 281.385772 -284.282134) (xy 287.429956 -284.282134) (xy 287.429956 -283.787596)
			(xy 287.430488 -283.782341) (xy 287.437911 -283.774901) (xy 287.443164 -283.774388) (xy 287.443672 -283.774388)
			(xy 287.959546 -283.774388) (xy 287.967354 -283.774054) (xy 287.982226 -283.769282) (xy 287.988756 -283.76499)
			(xy 288.009845 -283.750641) (xy 288.055506 -283.72791) (xy 288.104112 -283.712451) (xy 288.154515 -283.704628)
			(xy 288.205521 -283.704628) (xy 288.255924 -283.712451) (xy 288.30453 -283.72791) (xy 288.350191 -283.750641)
			(xy 288.37128 -283.76499) (xy 288.377817 -283.769271) (xy 288.392683 -283.774061) (xy 288.40049 -283.774388)
			(xy 288.916618 -283.774388) (xy 288.921936 -283.774817) (xy 288.929509 -283.782286) (xy 288.93008 -283.787596)
			(xy 288.93008 -284.282134) (xy 288.930056 -284.282388) (xy 294.974264 -284.282388) (xy 294.974264 -284.28188)
			(xy 294.974264 -283.787596) (xy 294.974789 -283.782339) (xy 294.982216 -283.774899) (xy 294.987472 -283.774388)
			(xy 295.5036 -283.774388) (xy 295.51141 -283.774076) (xy 295.526282 -283.769289) (xy 295.53281 -283.76499)
			(xy 295.553899 -283.750641) (xy 295.59956 -283.72791) (xy 295.648166 -283.712451) (xy 295.698569 -283.704628)
			(xy 295.749575 -283.704628) (xy 295.799978 -283.712451) (xy 295.848584 -283.72791) (xy 295.894245 -283.750641)
			(xy 295.915334 -283.76499) (xy 295.921859 -283.769292) (xy 295.936734 -283.774069) (xy 295.944544 -283.774388)
			(xy 296.460672 -283.774388) (xy 296.466 -283.774745) (xy 296.473542 -283.782269) (xy 296.47388 -283.787596)
			(xy 296.47388 -284.282134) (xy 302.518064 -284.282134) (xy 302.518064 -283.787596) (xy 302.518589 -283.782339)
			(xy 302.526016 -283.774899) (xy 302.531272 -283.774388) (xy 304.004726 -283.774388) (xy 304.010045 -283.774812)
			(xy 304.017617 -283.782285) (xy 304.018188 -283.787596) (xy 304.018188 -283.8061) (xy 356.425052 -283.8061)
			(xy 356.429226 -283.75573) (xy 356.441632 -283.706734) (xy 356.461934 -283.660448) (xy 356.489576 -283.618134)
			(xy 356.523805 -283.580947) (xy 356.563688 -283.5499) (xy 356.608136 -283.525841) (xy 356.655939 -283.509425)
			(xy 356.705791 -283.501101) (xy 356.731062 -283.500576) (xy 357.671116 -283.500576) (xy 357.696395 -283.501023)
			(xy 357.746262 -283.509347) (xy 357.794079 -283.525765) (xy 357.838542 -283.549829) (xy 357.878438 -283.580883)
			(xy 357.912679 -283.61808) (xy 357.94033 -283.660406) (xy 357.960638 -283.706705) (xy 357.973049 -283.755715)
			(xy 357.977224 -283.8061) (xy 362.058752 -283.8061) (xy 362.062926 -283.755728) (xy 362.075334 -283.70673)
			(xy 362.095637 -283.660442) (xy 362.123281 -283.618128) (xy 362.157513 -283.58094) (xy 362.197398 -283.549894)
			(xy 362.24185 -283.525835) (xy 362.289655 -283.509421) (xy 362.33951 -283.501099) (xy 362.364782 -283.500576)
			(xy 363.304836 -283.500576) (xy 363.330114 -283.501025) (xy 363.379978 -283.509351) (xy 363.427793 -283.525771)
			(xy 363.472253 -283.549836) (xy 363.512146 -283.58089) (xy 363.546384 -283.618087) (xy 363.574033 -283.660411)
			(xy 363.594339 -283.706709) (xy 363.606749 -283.755717) (xy 363.610924 -283.8061) (xy 363.606749 -283.856483)
			(xy 363.594339 -283.905491) (xy 363.574033 -283.951789) (xy 363.546384 -283.994113) (xy 363.512146 -284.03131)
			(xy 363.472253 -284.062364) (xy 363.427793 -284.086429) (xy 363.379978 -284.102849) (xy 363.330114 -284.111175)
			(xy 363.304836 -284.1117) (xy 362.364782 -284.1117) (xy 362.33951 -284.111101) (xy 362.289655 -284.102779)
			(xy 362.24185 -284.086365) (xy 362.197398 -284.062306) (xy 362.157513 -284.03126) (xy 362.123281 -283.994072)
			(xy 362.095637 -283.951758) (xy 362.075334 -283.90547) (xy 362.062926 -283.856472) (xy 362.058752 -283.8061)
			(xy 357.977224 -283.8061) (xy 357.973049 -283.856485) (xy 357.960638 -283.905495) (xy 357.94033 -283.951794)
			(xy 357.912679 -283.99412) (xy 357.878438 -284.031317) (xy 357.838542 -284.062371) (xy 357.794079 -284.086435)
			(xy 357.746262 -284.102853) (xy 357.696395 -284.111177) (xy 357.671116 -284.1117) (xy 356.731062 -284.1117)
			(xy 356.705791 -284.111099) (xy 356.655939 -284.102775) (xy 356.608136 -284.086359) (xy 356.563688 -284.0623)
			(xy 356.523805 -284.031253) (xy 356.489576 -283.994066) (xy 356.461934 -283.951752) (xy 356.441632 -283.905466)
			(xy 356.429226 -283.85647) (xy 356.425052 -283.8061) (xy 304.018188 -283.8061) (xy 304.018188 -284.282134)
			(xy 304.018164 -284.282388) (xy 411.618176 -284.282388) (xy 411.618176 -284.28188) (xy 411.618176 -283.787596)
			(xy 411.61869 -283.782337) (xy 411.626125 -283.774895) (xy 411.631384 -283.774388) (xy 413.104584 -283.774388)
			(xy 413.109913 -283.774737) (xy 413.117455 -283.782267) (xy 413.117792 -283.787596) (xy 413.117792 -284.282134)
			(xy 419.161976 -284.282134) (xy 419.161976 -283.787596) (xy 419.16249 -283.782337) (xy 419.169925 -283.774895)
			(xy 419.175184 -283.774388) (xy 419.175692 -283.774388) (xy 419.691566 -283.774388) (xy 419.699375 -283.774062)
			(xy 419.714247 -283.769285) (xy 419.720776 -283.76499) (xy 419.741865 -283.750641) (xy 419.787526 -283.72791)
			(xy 419.836132 -283.712451) (xy 419.886535 -283.704628) (xy 419.937541 -283.704628) (xy 419.987944 -283.712451)
			(xy 420.03655 -283.72791) (xy 420.082211 -283.750641) (xy 420.1033 -283.76499) (xy 420.109833 -283.769279)
			(xy 420.124702 -283.774064) (xy 420.13251 -283.774388) (xy 420.648638 -283.774388) (xy 420.653958 -283.774804)
			(xy 420.66153 -283.782283) (xy 420.6621 -283.787596) (xy 420.6621 -284.282134) (xy 420.662075 -284.282388)
			(xy 426.706284 -284.282388) (xy 426.706284 -284.28188) (xy 426.706284 -283.787596) (xy 426.706791 -283.782335)
			(xy 426.714231 -283.774893) (xy 426.719492 -283.774388) (xy 427.23562 -283.774388) (xy 427.243431 -283.774085)
			(xy 427.258302 -283.769292) (xy 427.26483 -283.76499) (xy 427.285919 -283.750641) (xy 427.33158 -283.72791)
			(xy 427.380186 -283.712451) (xy 427.430589 -283.704628) (xy 427.481595 -283.704628) (xy 427.531998 -283.712451)
			(xy 427.580604 -283.72791) (xy 427.626265 -283.750641) (xy 427.647354 -283.76499) (xy 427.653875 -283.7693)
			(xy 427.668753 -283.774072) (xy 427.676564 -283.774388) (xy 428.192692 -283.774388) (xy 428.198022 -283.774732)
			(xy 428.205563 -283.782266) (xy 428.2059 -283.787596) (xy 428.2059 -284.282134) (xy 434.250084 -284.282134)
			(xy 434.250084 -283.787596) (xy 434.250591 -283.782335) (xy 434.258031 -283.774893) (xy 434.263292 -283.774388)
			(xy 434.2638 -283.774388) (xy 434.779674 -283.774388) (xy 434.787483 -283.774065) (xy 434.802355 -283.769286)
			(xy 434.808884 -283.76499) (xy 434.829973 -283.750641) (xy 434.875634 -283.72791) (xy 434.92424 -283.712451)
			(xy 434.974643 -283.704628) (xy 435.025649 -283.704628) (xy 435.076052 -283.712451) (xy 435.124658 -283.72791)
			(xy 435.170319 -283.750641) (xy 435.191408 -283.76499) (xy 435.197939 -283.769282) (xy 435.212809 -283.774065)
			(xy 435.220618 -283.774388) (xy 435.736746 -283.774388) (xy 435.742055 -283.774865) (xy 435.749632 -283.782297)
			(xy 435.750208 -283.787596) (xy 435.750208 -284.282134) (xy 435.750183 -284.282388) (xy 441.794392 -284.282388)
			(xy 441.794392 -284.28188) (xy 441.794392 -283.787596) (xy 441.794892 -283.782333) (xy 441.802337 -283.77489)
			(xy 441.8076 -283.774388) (xy 442.323728 -283.774388) (xy 442.331539 -283.774088) (xy 442.346411 -283.769293)
			(xy 442.352938 -283.76499) (xy 442.374027 -283.750641) (xy 442.419688 -283.72791) (xy 442.468294 -283.712451)
			(xy 442.518697 -283.704628) (xy 442.569703 -283.704628) (xy 442.620106 -283.712451) (xy 442.668712 -283.72791)
			(xy 442.714373 -283.750641) (xy 442.735462 -283.76499) (xy 442.742003 -283.769265) (xy 442.756866 -283.774058)
			(xy 442.764672 -283.774388) (xy 443.2808 -283.774388) (xy 443.286062 -283.774894) (xy 443.293504 -283.782334)
			(xy 443.294008 -283.787596) (xy 443.294008 -284.282134) (xy 443.293984 -284.282388) (xy 449.338192 -284.282388)
			(xy 449.338192 -284.28188) (xy 449.338192 -283.787596) (xy 449.338692 -283.782333) (xy 449.346137 -283.77489)
			(xy 449.3514 -283.774388) (xy 449.867528 -283.774388) (xy 449.875339 -283.774088) (xy 449.890211 -283.769293)
			(xy 449.896738 -283.76499) (xy 449.917827 -283.750641) (xy 449.963488 -283.72791) (xy 450.012094 -283.712451)
			(xy 450.062497 -283.704628) (xy 450.113503 -283.704628) (xy 450.163906 -283.712451) (xy 450.212512 -283.72791)
			(xy 450.258173 -283.750641) (xy 450.279262 -283.76499) (xy 450.285803 -283.769265) (xy 450.300666 -283.774058)
			(xy 450.308472 -283.774388) (xy 450.8246 -283.774388) (xy 450.829862 -283.774894) (xy 450.837304 -283.782334)
			(xy 450.837808 -283.787596) (xy 450.837808 -284.282134) (xy 450.837305 -284.287431) (xy 450.829886 -284.294997)
			(xy 450.8246 -284.295596) (xy 450.308726 -284.295596) (xy 450.300917 -284.295921) (xy 450.286046 -284.300699)
			(xy 450.279516 -284.304994) (xy 450.258383 -284.319326) (xy 450.212664 -284.342058) (xy 450.163994 -284.357493)
			(xy 450.11353 -284.365265) (xy 450.088 -284.3657) (xy 450.06247 -284.365257) (xy 450.012007 -284.357482)
			(xy 449.963334 -284.342055) (xy 449.917606 -284.31934) (xy 449.896484 -284.304994) (xy 449.889956 -284.300697)
			(xy 449.875083 -284.295918) (xy 449.867274 -284.295596) (xy 449.3514 -284.295596) (xy 449.346065 -284.295272)
			(xy 449.338523 -284.287724) (xy 449.338192 -284.282388) (xy 443.293984 -284.282388) (xy 443.293505 -284.287431)
			(xy 443.286086 -284.294997) (xy 443.2808 -284.295596) (xy 442.764926 -284.295596) (xy 442.757117 -284.295921)
			(xy 442.742246 -284.300699) (xy 442.735716 -284.304994) (xy 442.714583 -284.319326) (xy 442.668864 -284.342058)
			(xy 442.620194 -284.357493) (xy 442.56973 -284.365265) (xy 442.5442 -284.3657) (xy 442.51867 -284.365257)
			(xy 442.468207 -284.357482) (xy 442.419534 -284.342055) (xy 442.373806 -284.31934) (xy 442.352684 -284.304994)
			(xy 442.346156 -284.300697) (xy 442.331283 -284.295918) (xy 442.323474 -284.295596) (xy 441.8076 -284.295596)
			(xy 441.802265 -284.295272) (xy 441.794723 -284.287724) (xy 441.794392 -284.282388) (xy 435.750183 -284.282388)
			(xy 435.749677 -284.287491) (xy 435.742103 -284.295072) (xy 435.736746 -284.295596) (xy 435.220872 -284.295596)
			(xy 435.213061 -284.295899) (xy 435.19819 -284.300692) (xy 435.191662 -284.304994) (xy 435.170544 -284.319349)
			(xy 435.124819 -284.342076) (xy 435.076145 -284.357505) (xy 435.025677 -284.365269) (xy 435.000146 -284.3657)
			(xy 434.974617 -284.365234) (xy 434.924155 -284.357466) (xy 434.875482 -284.342045) (xy 434.829753 -284.319337)
			(xy 434.80863 -284.304994) (xy 434.802091 -284.300715) (xy 434.787227 -284.295925) (xy 434.77942 -284.295596)
			(xy 434.263546 -284.295596) (xy 434.258125 -284.295193) (xy 434.250439 -284.287552) (xy 434.250084 -284.282134)
			(xy 428.2059 -284.282134) (xy 428.205404 -284.287433) (xy 428.197981 -284.295) (xy 428.192692 -284.295596)
			(xy 427.676818 -284.295596) (xy 427.669009 -284.295918) (xy 427.654137 -284.300698) (xy 427.647608 -284.304994)
			(xy 427.626477 -284.319329) (xy 427.580757 -284.342061) (xy 427.532087 -284.357495) (xy 427.481622 -284.365265)
			(xy 427.456092 -284.3657) (xy 427.430562 -284.365261) (xy 427.380098 -284.357485) (xy 427.331426 -284.342056)
			(xy 427.285698 -284.319341) (xy 427.264576 -284.304994) (xy 427.258049 -284.300694) (xy 427.243176 -284.295917)
			(xy 427.235366 -284.295596) (xy 426.719492 -284.295596) (xy 426.714156 -284.295278) (xy 426.706614 -284.287725)
			(xy 426.706284 -284.282388) (xy 420.662075 -284.282388) (xy 420.661576 -284.287493) (xy 420.653997 -284.295074)
			(xy 420.648638 -284.295596) (xy 420.132764 -284.295596) (xy 420.124956 -284.295937) (xy 420.110085 -284.300704)
			(xy 420.103554 -284.304994) (xy 420.082438 -284.319353) (xy 420.036713 -284.342079) (xy 419.988038 -284.357507)
			(xy 419.93757 -284.365269) (xy 419.912038 -284.3657) (xy 419.886509 -284.365238) (xy 419.836046 -284.357469)
			(xy 419.787374 -284.342047) (xy 419.741645 -284.319338) (xy 419.720522 -284.304994) (xy 419.713985 -284.300712)
			(xy 419.699119 -284.295923) (xy 419.691312 -284.295596) (xy 419.175438 -284.295596) (xy 419.170016 -284.295199)
			(xy 419.16233 -284.287554) (xy 419.161976 -284.282134) (xy 413.117792 -284.282134) (xy 413.117303 -284.287435)
			(xy 413.109875 -284.295002) (xy 413.104584 -284.295596) (xy 411.631384 -284.295596) (xy 411.626116 -284.295115)
			(xy 411.618674 -284.287657) (xy 411.618176 -284.282388) (xy 304.018164 -284.282388) (xy 304.017675 -284.287496)
			(xy 304.010088 -284.295078) (xy 304.004726 -284.295596) (xy 302.531526 -284.295596) (xy 302.526173 -284.295036)
			(xy 302.518588 -284.287484) (xy 302.518064 -284.282134) (xy 296.47388 -284.282134) (xy 296.473402 -284.287438)
			(xy 296.465966 -284.295006) (xy 296.460672 -284.295596) (xy 295.944798 -284.295596) (xy 295.936988 -284.295909)
			(xy 295.922117 -284.300696) (xy 295.915588 -284.304994) (xy 295.894463 -284.319338) (xy 295.848741 -284.342067)
			(xy 295.800069 -284.357499) (xy 295.749603 -284.365267) (xy 295.724072 -284.3657) (xy 295.698542 -284.365271)
			(xy 295.648078 -284.357492) (xy 295.599405 -284.34206) (xy 295.553678 -284.319342) (xy 295.532556 -284.304994)
			(xy 295.526034 -284.300687) (xy 295.511157 -284.295914) (xy 295.503346 -284.295596) (xy 294.987472 -284.295596)
			(xy 294.982203 -284.295123) (xy 294.974761 -284.287659) (xy 294.974264 -284.282388) (xy 288.930056 -284.282388)
			(xy 288.929574 -284.287498) (xy 288.921982 -284.29508) (xy 288.916618 -284.295596) (xy 288.400744 -284.295596)
			(xy 288.392936 -284.295929) (xy 288.378064 -284.300702) (xy 288.371534 -284.304994) (xy 288.350424 -284.319361)
			(xy 288.304696 -284.342085) (xy 288.25602 -284.357511) (xy 288.20555 -284.365271) (xy 288.180018 -284.3657)
			(xy 288.154488 -284.365248) (xy 288.104025 -284.357476) (xy 288.055353 -284.342051) (xy 288.009625 -284.319339)
			(xy 287.988502 -284.304994) (xy 287.98197 -284.300704) (xy 287.9671 -284.29592) (xy 287.959292 -284.295596)
			(xy 287.443418 -284.295596) (xy 287.438064 -284.295041) (xy 287.430479 -284.287486) (xy 287.429956 -284.282134)
			(xy 281.385772 -284.282134) (xy 281.385301 -284.28744) (xy 281.37786 -284.295008) (xy 281.372564 -284.295596)
			(xy 280.85669 -284.295596) (xy 280.84888 -284.295906) (xy 280.834008 -284.300695) (xy 280.82748 -284.304994)
			(xy 280.806357 -284.319341) (xy 280.760634 -284.34207) (xy 280.711961 -284.357501) (xy 280.661495 -284.365267)
			(xy 280.635964 -284.3657) (xy 280.610433 -284.365275) (xy 280.559969 -284.357495) (xy 280.511297 -284.342062)
			(xy 280.46557 -284.319343) (xy 280.444448 -284.304994) (xy 280.437928 -284.300683) (xy 280.423049 -284.295913)
			(xy 280.415238 -284.295596) (xy 279.899364 -284.295596) (xy 279.894094 -284.295128) (xy 279.886653 -284.28766)
			(xy 279.886156 -284.282388) (xy 273.841949 -284.282388) (xy 273.841501 -284.28744) (xy 273.83406 -284.295008)
			(xy 273.828764 -284.295596) (xy 273.31289 -284.295596) (xy 273.30508 -284.295906) (xy 273.290208 -284.300695)
			(xy 273.28368 -284.304994) (xy 273.262557 -284.319341) (xy 273.216834 -284.34207) (xy 273.168161 -284.357501)
			(xy 273.117695 -284.365267) (xy 273.092164 -284.3657) (xy 273.066633 -284.365275) (xy 273.016169 -284.357495)
			(xy 272.967497 -284.342062) (xy 272.92177 -284.319343) (xy 272.900648 -284.304994) (xy 272.894128 -284.300683)
			(xy 272.879249 -284.295913) (xy 272.871438 -284.295596) (xy 272.355564 -284.295596) (xy 272.350294 -284.295128)
			(xy 272.342853 -284.28766) (xy 272.342356 -284.282388) (xy 266.298148 -284.282388) (xy 266.297673 -284.2875)
			(xy 266.290076 -284.295083) (xy 266.28471 -284.295596) (xy 265.768836 -284.295596) (xy 265.761027 -284.295926)
			(xy 265.746156 -284.300701) (xy 265.739626 -284.304994) (xy 265.71849 -284.319321) (xy 265.672772 -284.342055)
			(xy 265.624103 -284.357491) (xy 265.57364 -284.365264) (xy 265.54811 -284.3657) (xy 265.52258 -284.365252)
			(xy 265.472117 -284.357479) (xy 265.423445 -284.342053) (xy 265.377717 -284.31934) (xy 265.356594 -284.304994)
			(xy 265.350063 -284.300701) (xy 265.335193 -284.295919) (xy 265.327384 -284.295596) (xy 264.81151 -284.295596)
			(xy 264.806155 -284.295046) (xy 264.798571 -284.287487) (xy 264.798048 -284.282134) (xy 202.89774 -284.282134)
			(xy 202.89774 -284.282388) (xy 202.8972 -284.287642) (xy 202.889784 -284.295083) (xy 202.884532 -284.295596)
			(xy 202.368658 -284.295596) (xy 202.360782 -284.295865) (xy 202.345777 -284.300661) (xy 202.339194 -284.304994)
			(xy 202.318112 -284.319379) (xy 202.272468 -284.342207) (xy 202.223864 -284.357767) (xy 202.173448 -284.365689)
			(xy 202.147932 -284.366208) (xy 202.122412 -284.365718) (xy 202.071985 -284.357823) (xy 202.023373 -284.342263)
			(xy 201.977735 -284.319409) (xy 201.95667 -284.304994) (xy 201.950087 -284.300664) (xy 201.93508 -284.295887)
			(xy 201.927206 -284.295596) (xy 201.411332 -284.295596) (xy 201.406001 -284.29525) (xy 201.398458 -284.287718)
			(xy 201.398124 -284.282388) (xy 195.35394 -284.282388) (xy 195.3534 -284.287642) (xy 195.345984 -284.295083)
			(xy 195.340732 -284.295596) (xy 194.824858 -284.295596) (xy 194.816982 -284.295865) (xy 194.801977 -284.300661)
			(xy 194.795394 -284.304994) (xy 194.774312 -284.319379) (xy 194.728668 -284.342207) (xy 194.680064 -284.357767)
			(xy 194.629648 -284.365689) (xy 194.604132 -284.366208) (xy 194.578612 -284.365718) (xy 194.528185 -284.357823)
			(xy 194.479573 -284.342263) (xy 194.433935 -284.319409) (xy 194.41287 -284.304994) (xy 194.406287 -284.300664)
			(xy 194.39128 -284.295887) (xy 194.383406 -284.295596) (xy 193.867532 -284.295596) (xy 193.862201 -284.29525)
			(xy 193.854658 -284.287718) (xy 193.854324 -284.282388) (xy 187.81014 -284.282388) (xy 187.8096 -284.287642)
			(xy 187.802184 -284.295083) (xy 187.796932 -284.295596) (xy 187.796424 -284.295596) (xy 187.280804 -284.295596)
			(xy 187.272929 -284.295885) (xy 187.257925 -284.300667) (xy 187.25134 -284.304994) (xy 187.230273 -284.319402)
			(xy 187.184624 -284.342225) (xy 187.136015 -284.357778) (xy 187.085596 -284.365693) (xy 187.060078 -284.366208)
			(xy 187.034559 -284.365695) (xy 186.984133 -284.357807) (xy 186.935521 -284.342254) (xy 186.889882 -284.319406)
			(xy 186.868816 -284.304994) (xy 186.862223 -284.300682) (xy 186.847224 -284.295893) (xy 186.839352 -284.295596)
			(xy 186.323478 -284.295596) (xy 186.31818 -284.295096) (xy 186.310612 -284.287676) (xy 186.310016 -284.282388)
			(xy 180.265832 -284.282388) (xy 180.2653 -284.287643) (xy 180.257878 -284.295085) (xy 180.252624 -284.295596)
			(xy 179.73675 -284.295596) (xy 179.728873 -284.295862) (xy 179.713869 -284.30066) (xy 179.707286 -284.304994)
			(xy 179.686206 -284.319382) (xy 179.640562 -284.34221) (xy 179.591957 -284.357768) (xy 179.54154 -284.365689)
			(xy 179.516024 -284.366208) (xy 179.490504 -284.365722) (xy 179.440077 -284.357826) (xy 179.391465 -284.342265)
			(xy 179.345827 -284.319409) (xy 179.324762 -284.304994) (xy 179.318181 -284.300661) (xy 179.303173 -284.295885)
			(xy 179.295298 -284.295596) (xy 178.779424 -284.295596) (xy 178.774092 -284.295256) (xy 178.766549 -284.28772)
			(xy 178.766216 -284.282388) (xy 172.722032 -284.282388) (xy 172.7215 -284.287643) (xy 172.714078 -284.295085)
			(xy 172.708824 -284.295596) (xy 172.708316 -284.295596) (xy 172.192696 -284.295596) (xy 172.184821 -284.295882)
			(xy 172.169817 -284.300666) (xy 172.163232 -284.304994) (xy 172.142168 -284.319405) (xy 172.096518 -284.342228)
			(xy 172.047908 -284.35778) (xy 171.997488 -284.365693) (xy 171.97197 -284.366208) (xy 171.946451 -284.365699)
			(xy 171.896025 -284.35781) (xy 171.847413 -284.342256) (xy 171.801774 -284.319406) (xy 171.780708 -284.304994)
			(xy 171.774117 -284.300679) (xy 171.759116 -284.295892) (xy 171.751244 -284.295596) (xy 171.23537 -284.295596)
			(xy 171.230071 -284.295101) (xy 171.222503 -284.287677) (xy 171.221908 -284.282388) (xy 165.177724 -284.282388)
			(xy 165.177199 -284.287645) (xy 165.169772 -284.295088) (xy 165.164516 -284.295596) (xy 163.691316 -284.295596)
			(xy 163.685983 -284.295261) (xy 163.67844 -284.287721) (xy 163.678108 -284.282388) (xy 56.07812 -284.282388)
			(xy 56.077598 -284.287646) (xy 56.070169 -284.295089) (xy 56.064912 -284.295596) (xy 54.591458 -284.295596)
			(xy 54.586157 -284.295109) (xy 54.57859 -284.287679) (xy 54.577996 -284.282388) (xy 48.533812 -284.282388)
			(xy 48.533465 -284.287718) (xy 48.525933 -284.295259) (xy 48.520604 -284.295596) (xy 48.00473 -284.295596)
			(xy 47.996853 -284.295854) (xy 47.981849 -284.300657) (xy 47.975266 -284.304994) (xy 47.954192 -284.319391)
			(xy 47.908545 -284.342217) (xy 47.859938 -284.357773) (xy 47.809521 -284.365691) (xy 47.784004 -284.366208)
			(xy 47.758483 -284.365732) (xy 47.708056 -284.357833) (xy 47.659444 -284.342269) (xy 47.613807 -284.319411)
			(xy 47.592742 -284.304994) (xy 47.586166 -284.300653) (xy 47.571154 -284.295882) (xy 47.563278 -284.295596)
			(xy 47.047404 -284.295596) (xy 47.042069 -284.295269) (xy 47.034528 -284.287723) (xy 47.034196 -284.282388)
			(xy 40.990012 -284.282388) (xy 40.989665 -284.287718) (xy 40.982133 -284.295259) (xy 40.976804 -284.295596)
			(xy 40.976296 -284.295596) (xy 40.460676 -284.295596) (xy 40.4528 -284.295873) (xy 40.437796 -284.300663)
			(xy 40.431212 -284.304994) (xy 40.410153 -284.319414) (xy 40.364501 -284.342235) (xy 40.315889 -284.357784)
			(xy 40.265468 -284.365695) (xy 40.23995 -284.366208) (xy 40.21443 -284.365709) (xy 40.164004 -284.357817)
			(xy 40.115392 -284.34226) (xy 40.069753 -284.319408) (xy 40.048688 -284.304994) (xy 40.042101 -284.300671)
			(xy 40.027098 -284.295889) (xy 40.019224 -284.295596) (xy 39.50335 -284.295596) (xy 39.49806 -284.295047)
			(xy 39.490489 -284.287664) (xy 39.489888 -284.282388) (xy 33.445704 -284.282388) (xy 33.445365 -284.28772)
			(xy 33.437827 -284.295261) (xy 33.432496 -284.295596) (xy 32.916622 -284.295596) (xy 32.908748 -284.295893)
			(xy 32.893744 -284.300669) (xy 32.887158 -284.304994) (xy 32.866086 -284.319394) (xy 32.820439 -284.342219)
			(xy 32.771831 -284.357774) (xy 32.721413 -284.365691) (xy 32.695896 -284.366208) (xy 32.670375 -284.365736)
			(xy 32.619948 -284.357836) (xy 32.571336 -284.342271) (xy 32.525698 -284.319411) (xy 32.504634 -284.304994)
			(xy 32.498037 -284.300689) (xy 32.483041 -284.295896) (xy 32.47517 -284.295596) (xy 31.959296 -284.295596)
			(xy 31.95396 -284.295275) (xy 31.946419 -284.287724) (xy 31.946088 -284.282388) (xy 25.901904 -284.282388)
			(xy 25.901565 -284.28772) (xy 25.894027 -284.295261) (xy 25.888696 -284.295596) (xy 25.372822 -284.295596)
			(xy 25.364948 -284.295893) (xy 25.349944 -284.300669) (xy 25.343358 -284.304994) (xy 25.322286 -284.319394)
			(xy 25.276639 -284.342219) (xy 25.228031 -284.357774) (xy 25.177613 -284.365691) (xy 25.152096 -284.366208)
			(xy 25.126575 -284.365736) (xy 25.076148 -284.357836) (xy 25.027536 -284.342271) (xy 24.981898 -284.319411)
			(xy 24.960834 -284.304994) (xy 24.954237 -284.300689) (xy 24.939241 -284.295896) (xy 24.93137 -284.295596)
			(xy 24.415496 -284.295596) (xy 24.41016 -284.295275) (xy 24.402619 -284.287724) (xy 24.402288 -284.282388)
			(xy 18.358104 -284.282388) (xy 18.357765 -284.28772) (xy 18.350227 -284.295261) (xy 18.344896 -284.295596)
			(xy 18.344388 -284.295596) (xy 17.828768 -284.295596) (xy 17.820892 -284.29587) (xy 17.805888 -284.300662)
			(xy 17.799304 -284.304994) (xy 17.778219 -284.319374) (xy 17.732577 -284.342204) (xy 17.683973 -284.357765)
			(xy 17.633558 -284.365688) (xy 17.608042 -284.366208) (xy 17.582522 -284.365713) (xy 17.532095 -284.35782)
			(xy 17.483484 -284.342261) (xy 17.437845 -284.319408) (xy 17.41678 -284.304994) (xy 17.410195 -284.300668)
			(xy 17.39519 -284.295888) (xy 17.387316 -284.295596) (xy 16.871442 -284.295596) (xy 16.866151 -284.295053)
			(xy 16.85858 -284.287665) (xy 16.85798 -284.282388) (xy 2.509012 -284.282388) (xy 2.509012 -285.132526)
			(xy 20.958048 -285.132526) (xy 20.958048 -284.637988) (xy 20.958582 -284.632734) (xy 20.966004 -284.625295)
			(xy 20.971256 -284.62478) (xy 20.971764 -284.62478) (xy 21.487638 -284.62478) (xy 21.495446 -284.624443)
			(xy 21.510318 -284.619673) (xy 21.516848 -284.615382) (xy 21.537937 -284.601033) (xy 21.583598 -284.578302)
			(xy 21.632204 -284.562843) (xy 21.682607 -284.55502) (xy 21.733613 -284.55502) (xy 21.784016 -284.562843)
			(xy 21.832622 -284.578302) (xy 21.878283 -284.601033) (xy 21.899372 -284.615382) (xy 21.905912 -284.619659)
			(xy 21.920775 -284.624451) (xy 21.928582 -284.62478) (xy 22.44471 -284.62478) (xy 22.450025 -284.625221)
			(xy 22.457598 -284.632681) (xy 22.458172 -284.637988) (xy 22.458172 -285.132526) (xy 22.458148 -285.13278)
			(xy 28.502356 -285.13278) (xy 28.502356 -285.132272) (xy 28.502356 -284.637988) (xy 28.502883 -284.632733)
			(xy 28.510309 -284.625293) (xy 28.515564 -284.62478) (xy 29.031692 -284.62478) (xy 29.039502 -284.624466)
			(xy 29.054374 -284.619681) (xy 29.060902 -284.615382) (xy 29.081991 -284.601033) (xy 29.127652 -284.578302)
			(xy 29.176258 -284.562843) (xy 29.226661 -284.55502) (xy 29.277667 -284.55502) (xy 29.32807 -284.562843)
			(xy 29.376676 -284.578302) (xy 29.422337 -284.601033) (xy 29.443426 -284.615382) (xy 29.449954 -284.61968)
			(xy 29.464827 -284.624459) (xy 29.472636 -284.62478) (xy 29.988764 -284.62478) (xy 29.994089 -284.62515)
			(xy 30.001631 -284.632665) (xy 30.001972 -284.637988) (xy 30.001972 -285.132526) (xy 30.001949 -285.13278)
			(xy 36.046156 -285.13278) (xy 36.046156 -285.132272) (xy 36.046156 -284.637988) (xy 36.046683 -284.632733)
			(xy 36.054109 -284.625293) (xy 36.059364 -284.62478) (xy 36.575492 -284.62478) (xy 36.583302 -284.624466)
			(xy 36.598174 -284.619681) (xy 36.604702 -284.615382) (xy 36.625791 -284.601033) (xy 36.671452 -284.578302)
			(xy 36.720058 -284.562843) (xy 36.770461 -284.55502) (xy 36.821467 -284.55502) (xy 36.87187 -284.562843)
			(xy 36.920476 -284.578302) (xy 36.966137 -284.601033) (xy 36.987226 -284.615382) (xy 36.993754 -284.61968)
			(xy 37.008627 -284.624459) (xy 37.016436 -284.62478) (xy 37.532564 -284.62478) (xy 37.537889 -284.62515)
			(xy 37.545431 -284.632665) (xy 37.545772 -284.637988) (xy 37.545772 -285.132526) (xy 43.589956 -285.132526)
			(xy 43.589956 -284.637988) (xy 43.590483 -284.632733) (xy 43.597909 -284.625293) (xy 43.603164 -284.62478)
			(xy 43.603672 -284.62478) (xy 44.119546 -284.62478) (xy 44.127354 -284.624447) (xy 44.142226 -284.619674)
			(xy 44.148756 -284.615382) (xy 44.169845 -284.601033) (xy 44.215506 -284.578302) (xy 44.264112 -284.562843)
			(xy 44.314515 -284.55502) (xy 44.365521 -284.55502) (xy 44.415924 -284.562843) (xy 44.46453 -284.578302)
			(xy 44.510191 -284.601033) (xy 44.53128 -284.615382) (xy 44.537818 -284.619662) (xy 44.552683 -284.624452)
			(xy 44.56049 -284.62478) (xy 45.076618 -284.62478) (xy 45.081934 -284.625216) (xy 45.089506 -284.63268)
			(xy 45.09008 -284.637988) (xy 45.09008 -285.132526) (xy 45.090056 -285.13278) (xy 51.134264 -285.13278)
			(xy 51.134264 -285.132272) (xy 51.134264 -284.637988) (xy 51.134784 -284.632731) (xy 51.142215 -284.62529)
			(xy 51.147472 -284.62478) (xy 51.6636 -284.62478) (xy 51.67141 -284.62447) (xy 51.686282 -284.619682)
			(xy 51.69281 -284.615382) (xy 51.713899 -284.601033) (xy 51.75956 -284.578302) (xy 51.808166 -284.562843)
			(xy 51.858569 -284.55502) (xy 51.909575 -284.55502) (xy 51.959978 -284.562843) (xy 52.008584 -284.578302)
			(xy 52.054245 -284.601033) (xy 52.075334 -284.615382) (xy 52.076879 -284.6164) (xy 97.674883 -284.6164)
			(xy 97.679059 -284.566014) (xy 97.69147 -284.517003) (xy 97.71178 -284.470702) (xy 97.739433 -284.428377)
			(xy 97.773676 -284.39118) (xy 97.813574 -284.360127) (xy 97.85804 -284.336064) (xy 97.905859 -284.319649)
			(xy 97.955729 -284.311328) (xy 97.981008 -284.310836) (xy 98.921062 -284.310836) (xy 98.946343 -284.31133)
			(xy 98.996215 -284.319647) (xy 99.044038 -284.336059) (xy 99.088508 -284.36012) (xy 99.12841 -284.391172)
			(xy 99.162656 -284.428369) (xy 99.190312 -284.470696) (xy 99.210624 -284.516998) (xy 99.223037 -284.566012)
			(xy 99.227213 -284.6164) (xy 100.495112 -284.6164) (xy 100.499287 -284.566023) (xy 100.511695 -284.51702)
			(xy 100.532 -284.470727) (xy 100.559646 -284.428407) (xy 100.593881 -284.391215) (xy 100.63377 -284.360164)
			(xy 100.678226 -284.336102) (xy 100.726035 -284.319685) (xy 100.775895 -284.31136) (xy 100.80117 -284.310836)
			(xy 101.741224 -284.310836) (xy 101.766499 -284.311364) (xy 101.816359 -284.319688) (xy 101.864169 -284.336104)
			(xy 101.908625 -284.360165) (xy 101.948514 -284.391216) (xy 101.982749 -284.428408) (xy 102.010396 -284.470727)
			(xy 102.030701 -284.51702) (xy 102.043109 -284.566023) (xy 102.047284 -284.6164) (xy 103.315012 -284.6164)
			(xy 103.319187 -284.566022) (xy 103.331596 -284.517018) (xy 103.351901 -284.470725) (xy 103.379548 -284.428404)
			(xy 103.413784 -284.391212) (xy 103.453674 -284.360161) (xy 103.498131 -284.3361) (xy 103.545942 -284.319683)
			(xy 103.595803 -284.31136) (xy 103.621078 -284.310836) (xy 104.561132 -284.310836) (xy 104.586406 -284.311364)
			(xy 104.636265 -284.319689) (xy 104.684074 -284.336106) (xy 104.728529 -284.360168) (xy 104.768417 -284.391218)
			(xy 104.802651 -284.42841) (xy 104.830297 -284.470729) (xy 104.850601 -284.517021) (xy 104.863009 -284.566024)
			(xy 104.867184 -284.6164) (xy 106.134912 -284.6164) (xy 106.139087 -284.566021) (xy 106.151496 -284.517016)
			(xy 106.171802 -284.470722) (xy 106.19945 -284.428402) (xy 106.233687 -284.391209) (xy 106.273579 -284.360159)
			(xy 106.318037 -284.336097) (xy 106.365849 -284.319682) (xy 106.41571 -284.311359) (xy 106.440986 -284.310836)
			(xy 107.38104 -284.310836) (xy 107.406314 -284.311365) (xy 107.456172 -284.319691) (xy 107.503979 -284.336109)
			(xy 107.548433 -284.360171) (xy 107.58832 -284.391221) (xy 107.622553 -284.428413) (xy 107.650198 -284.470731)
			(xy 107.670502 -284.517023) (xy 107.68291 -284.566024) (xy 107.687084 -284.6164) (xy 116.468583 -284.6164)
			(xy 116.472759 -284.566013) (xy 116.485171 -284.517) (xy 116.505482 -284.470699) (xy 116.533137 -284.428372)
			(xy 116.567381 -284.391175) (xy 116.607282 -284.360122) (xy 116.651749 -284.33606) (xy 116.699571 -284.319646)
			(xy 116.749442 -284.311327) (xy 116.774722 -284.310836) (xy 117.714776 -284.310836) (xy 117.740056 -284.311331)
			(xy 117.789927 -284.319649) (xy 117.837748 -284.336063) (xy 117.882215 -284.360125) (xy 117.922115 -284.391177)
			(xy 117.95636 -284.428374) (xy 117.984014 -284.4707) (xy 118.004325 -284.517001) (xy 118.016737 -284.566013)
			(xy 118.020913 -284.6164) (xy 119.288483 -284.6164) (xy 119.292659 -284.566012) (xy 119.305072 -284.516998)
			(xy 119.325383 -284.470696) (xy 119.353039 -284.428369) (xy 119.387285 -284.391172) (xy 119.427186 -284.360119)
			(xy 119.471655 -284.336058) (xy 119.519477 -284.319644) (xy 119.569349 -284.311327) (xy 119.59463 -284.310836)
			(xy 120.534684 -284.310836) (xy 120.559963 -284.311332) (xy 120.609833 -284.319651) (xy 120.657653 -284.336066)
			(xy 120.702119 -284.360127) (xy 120.742018 -284.39118) (xy 120.776262 -284.428376) (xy 120.803915 -284.470702)
			(xy 120.824225 -284.517002) (xy 120.836637 -284.566014) (xy 120.840813 -284.6164) (xy 122.108712 -284.6164)
			(xy 122.112887 -284.56602) (xy 122.125297 -284.517015) (xy 122.145603 -284.470721) (xy 122.173252 -284.4284)
			(xy 122.207489 -284.391207) (xy 122.247382 -284.360157) (xy 122.291841 -284.336096) (xy 122.339653 -284.31968)
			(xy 122.389516 -284.311359) (xy 122.414792 -284.310836) (xy 123.354846 -284.310836) (xy 123.38012 -284.311366)
			(xy 123.429977 -284.319692) (xy 123.477783 -284.336111) (xy 123.522236 -284.360173) (xy 123.562123 -284.391223)
			(xy 123.596355 -284.428415) (xy 123.623999 -284.470733) (xy 123.644302 -284.517024) (xy 123.65671 -284.566025)
			(xy 123.660884 -284.6164) (xy 124.928613 -284.6164) (xy 124.932787 -284.56602) (xy 124.945197 -284.517014)
			(xy 124.965504 -284.470718) (xy 124.993154 -284.428397) (xy 125.027393 -284.391204) (xy 125.067286 -284.360154)
			(xy 125.111746 -284.336093) (xy 125.15956 -284.319679) (xy 125.209423 -284.311358) (xy 125.2347 -284.310836)
			(xy 126.174754 -284.310836) (xy 126.200035 -284.311329) (xy 126.249909 -284.319645) (xy 126.297733 -284.336057)
			(xy 126.342203 -284.360117) (xy 126.382107 -284.391169) (xy 126.416354 -284.428366) (xy 126.444011 -284.470694)
			(xy 126.464323 -284.516996) (xy 126.476737 -284.566011) (xy 126.480913 -284.6164) (xy 126.476737 -284.666789)
			(xy 126.464323 -284.715804) (xy 126.444011 -284.762106) (xy 126.416354 -284.804434) (xy 126.382107 -284.841631)
			(xy 126.342203 -284.872683) (xy 126.297733 -284.896743) (xy 126.249909 -284.913155) (xy 126.200035 -284.921471)
			(xy 126.174754 -284.92196) (xy 125.2347 -284.92196) (xy 125.209423 -284.921442) (xy 125.15956 -284.913121)
			(xy 125.111746 -284.896707) (xy 125.067286 -284.872646) (xy 125.027393 -284.841596) (xy 124.993154 -284.804403)
			(xy 124.965504 -284.762082) (xy 124.945197 -284.715786) (xy 124.932787 -284.66678) (xy 124.928613 -284.6164)
			(xy 123.660884 -284.6164) (xy 123.65671 -284.666775) (xy 123.644302 -284.715776) (xy 123.623999 -284.762067)
			(xy 123.596355 -284.804385) (xy 123.562123 -284.841577) (xy 123.522236 -284.872627) (xy 123.477783 -284.896689)
			(xy 123.429977 -284.913108) (xy 123.38012 -284.921434) (xy 123.354846 -284.92196) (xy 122.414792 -284.92196)
			(xy 122.389516 -284.921441) (xy 122.339653 -284.91312) (xy 122.291841 -284.896704) (xy 122.247382 -284.872643)
			(xy 122.207489 -284.841593) (xy 122.173252 -284.8044) (xy 122.145603 -284.762079) (xy 122.125297 -284.715785)
			(xy 122.112887 -284.66678) (xy 122.108712 -284.6164) (xy 120.840813 -284.6164) (xy 120.836637 -284.666786)
			(xy 120.824225 -284.715798) (xy 120.803915 -284.762098) (xy 120.776262 -284.804424) (xy 120.742018 -284.84162)
			(xy 120.702119 -284.872673) (xy 120.657653 -284.896734) (xy 120.609833 -284.913149) (xy 120.559963 -284.921468)
			(xy 120.534684 -284.92196) (xy 119.59463 -284.92196) (xy 119.569349 -284.921473) (xy 119.519477 -284.913156)
			(xy 119.471655 -284.896742) (xy 119.427186 -284.872681) (xy 119.387285 -284.841628) (xy 119.353039 -284.804431)
			(xy 119.325383 -284.762104) (xy 119.305072 -284.715802) (xy 119.292659 -284.666788) (xy 119.288483 -284.6164)
			(xy 118.020913 -284.6164) (xy 118.016737 -284.666787) (xy 118.004325 -284.715799) (xy 117.984014 -284.7621)
			(xy 117.95636 -284.804426) (xy 117.922115 -284.841623) (xy 117.882215 -284.872675) (xy 117.837748 -284.896737)
			(xy 117.789927 -284.913151) (xy 117.740056 -284.921469) (xy 117.714776 -284.92196) (xy 116.774722 -284.92196)
			(xy 116.749442 -284.921473) (xy 116.699571 -284.913154) (xy 116.651749 -284.89674) (xy 116.607282 -284.872678)
			(xy 116.567381 -284.841625) (xy 116.533137 -284.804428) (xy 116.505482 -284.762101) (xy 116.485171 -284.7158)
			(xy 116.472759 -284.666787) (xy 116.468583 -284.6164) (xy 107.687084 -284.6164) (xy 107.68291 -284.666776)
			(xy 107.670502 -284.715777) (xy 107.650198 -284.762069) (xy 107.622553 -284.804387) (xy 107.58832 -284.841579)
			(xy 107.548433 -284.872629) (xy 107.503979 -284.896691) (xy 107.456172 -284.913109) (xy 107.406314 -284.921435)
			(xy 107.38104 -284.92196) (xy 106.440986 -284.92196) (xy 106.41571 -284.921441) (xy 106.365849 -284.913118)
			(xy 106.318037 -284.896703) (xy 106.273579 -284.872641) (xy 106.233687 -284.841591) (xy 106.19945 -284.804398)
			(xy 106.171802 -284.762078) (xy 106.151496 -284.715784) (xy 106.139087 -284.666779) (xy 106.134912 -284.6164)
			(xy 104.867184 -284.6164) (xy 104.863009 -284.666776) (xy 104.850601 -284.715779) (xy 104.830297 -284.762071)
			(xy 104.802651 -284.80439) (xy 104.768417 -284.841582) (xy 104.728529 -284.872632) (xy 104.684074 -284.896694)
			(xy 104.636265 -284.913111) (xy 104.586406 -284.921436) (xy 104.561132 -284.92196) (xy 103.621078 -284.92196)
			(xy 103.595803 -284.92144) (xy 103.545942 -284.913117) (xy 103.498131 -284.8967) (xy 103.453674 -284.872639)
			(xy 103.413784 -284.841588) (xy 103.379548 -284.804396) (xy 103.351901 -284.762075) (xy 103.331596 -284.715782)
			(xy 103.319187 -284.666778) (xy 103.315012 -284.6164) (xy 102.047284 -284.6164) (xy 102.043109 -284.666777)
			(xy 102.030701 -284.71578) (xy 102.010396 -284.762073) (xy 101.982749 -284.804392) (xy 101.948514 -284.841584)
			(xy 101.908625 -284.872635) (xy 101.864169 -284.896696) (xy 101.816359 -284.913112) (xy 101.766499 -284.921436)
			(xy 101.741224 -284.92196) (xy 100.80117 -284.92196) (xy 100.775895 -284.92144) (xy 100.726035 -284.913115)
			(xy 100.678226 -284.896698) (xy 100.63377 -284.872636) (xy 100.593881 -284.841585) (xy 100.559646 -284.804393)
			(xy 100.532 -284.762073) (xy 100.511695 -284.71578) (xy 100.499287 -284.666777) (xy 100.495112 -284.6164)
			(xy 99.227213 -284.6164) (xy 99.223037 -284.666788) (xy 99.210624 -284.715802) (xy 99.190312 -284.762104)
			(xy 99.162656 -284.804431) (xy 99.12841 -284.841628) (xy 99.088508 -284.87268) (xy 99.044038 -284.896741)
			(xy 98.996215 -284.913153) (xy 98.946343 -284.92147) (xy 98.921062 -284.92196) (xy 97.981008 -284.92196)
			(xy 97.955729 -284.921472) (xy 97.905859 -284.913151) (xy 97.85804 -284.896736) (xy 97.813574 -284.872673)
			(xy 97.773676 -284.84162) (xy 97.739433 -284.804423) (xy 97.71178 -284.762098) (xy 97.69147 -284.715797)
			(xy 97.679059 -284.666786) (xy 97.674883 -284.6164) (xy 52.076879 -284.6164) (xy 52.08186 -284.619683)
			(xy 52.096734 -284.62446) (xy 52.104544 -284.62478) (xy 52.620672 -284.62478) (xy 52.625998 -284.625144)
			(xy 52.63354 -284.632663) (xy 52.63388 -284.637988) (xy 52.63388 -285.132526) (xy 58.678064 -285.132526)
			(xy 58.678064 -284.637988) (xy 58.678584 -284.632731) (xy 58.686015 -284.62529) (xy 58.691272 -284.62478)
			(xy 58.69178 -284.62478) (xy 60.164726 -284.62478) (xy 60.170043 -284.625211) (xy 60.177614 -284.632679)
			(xy 60.178188 -284.637988) (xy 60.178188 -285.132526) (xy 60.177669 -285.137887) (xy 60.170087 -285.145469)
			(xy 60.164726 -285.145988) (xy 58.691526 -285.145988) (xy 58.686171 -285.145435) (xy 58.678586 -285.137879)
			(xy 58.678064 -285.132526) (xy 52.63388 -285.132526) (xy 52.633396 -285.137829) (xy 52.625965 -285.145397)
			(xy 52.620672 -285.145988) (xy 52.104798 -285.145988) (xy 52.096986 -285.146286) (xy 52.082114 -285.151081)
			(xy 52.075588 -285.155386) (xy 52.05447 -285.169741) (xy 52.008744 -285.192465) (xy 51.96007 -285.207893)
			(xy 51.909603 -285.215659) (xy 51.884072 -285.216092) (xy 51.858541 -285.215665) (xy 51.808077 -285.207885)
			(xy 51.759405 -285.192453) (xy 51.713678 -285.169734) (xy 51.692556 -285.155386) (xy 51.686029 -285.151087)
			(xy 51.671156 -285.146307) (xy 51.663346 -285.145988) (xy 51.147472 -285.145988) (xy 51.142201 -285.145522)
			(xy 51.134759 -285.138053) (xy 51.134264 -285.13278) (xy 45.090056 -285.13278) (xy 45.089569 -285.137889)
			(xy 45.081981 -285.145472) (xy 45.076618 -285.145988) (xy 44.560744 -285.145988) (xy 44.552934 -285.146306)
			(xy 44.538062 -285.151087) (xy 44.531534 -285.155386) (xy 44.510431 -285.169764) (xy 44.4647 -285.192483)
			(xy 44.416021 -285.207905) (xy 44.365551 -285.215663) (xy 44.340018 -285.216092) (xy 44.314488 -285.215641)
			(xy 44.264025 -285.207869) (xy 44.215353 -285.192444) (xy 44.169625 -285.169731) (xy 44.148502 -285.155386)
			(xy 44.141964 -285.151105) (xy 44.127099 -285.146314) (xy 44.119292 -285.145988) (xy 43.603418 -285.145988)
			(xy 43.598062 -285.14544) (xy 43.590477 -285.13788) (xy 43.589956 -285.132526) (xy 37.545772 -285.132526)
			(xy 37.545295 -285.13783) (xy 37.537859 -285.145399) (xy 37.532564 -285.145988) (xy 37.01669 -285.145988)
			(xy 37.008878 -285.146283) (xy 36.994006 -285.15108) (xy 36.98748 -285.155386) (xy 36.966364 -285.169744)
			(xy 36.920638 -285.192468) (xy 36.871963 -285.207895) (xy 36.821495 -285.21566) (xy 36.795964 -285.216092)
			(xy 36.770433 -285.215669) (xy 36.719969 -285.207888) (xy 36.671297 -285.192455) (xy 36.62557 -285.169735)
			(xy 36.604448 -285.155386) (xy 36.597922 -285.151084) (xy 36.583048 -285.146306) (xy 36.575238 -285.145988)
			(xy 36.059364 -285.145988) (xy 36.054092 -285.145527) (xy 36.046651 -285.138054) (xy 36.046156 -285.13278)
			(xy 30.001949 -285.13278) (xy 30.001495 -285.13783) (xy 29.994059 -285.145399) (xy 29.988764 -285.145988)
			(xy 29.47289 -285.145988) (xy 29.465078 -285.146283) (xy 29.450206 -285.15108) (xy 29.44368 -285.155386)
			(xy 29.422564 -285.169744) (xy 29.376838 -285.192468) (xy 29.328163 -285.207895) (xy 29.277695 -285.21566)
			(xy 29.252164 -285.216092) (xy 29.226633 -285.215669) (xy 29.176169 -285.207888) (xy 29.127497 -285.192455)
			(xy 29.08177 -285.169735) (xy 29.060648 -285.155386) (xy 29.054122 -285.151084) (xy 29.039248 -285.146306)
			(xy 29.031438 -285.145988) (xy 28.515564 -285.145988) (xy 28.510292 -285.145527) (xy 28.502851 -285.138054)
			(xy 28.502356 -285.13278) (xy 22.458148 -285.13278) (xy 22.457668 -285.137891) (xy 22.450075 -285.145474)
			(xy 22.44471 -285.145988) (xy 21.928836 -285.145988) (xy 21.921026 -285.146302) (xy 21.906154 -285.151086)
			(xy 21.899626 -285.155386) (xy 21.878497 -285.169724) (xy 21.832776 -285.192452) (xy 21.784105 -285.207885)
			(xy 21.73364 -285.215656) (xy 21.70811 -285.216092) (xy 21.68258 -285.215645) (xy 21.632117 -285.207872)
			(xy 21.583445 -285.192445) (xy 21.537717 -285.169732) (xy 21.516594 -285.155386) (xy 21.510058 -285.151102)
			(xy 21.495192 -285.146313) (xy 21.487384 -285.145988) (xy 20.97151 -285.145988) (xy 20.966154 -285.145445)
			(xy 20.958569 -285.137881) (xy 20.958048 -285.132526) (xy 2.509012 -285.132526) (xy 2.509012 -285.98241)
			(xy 16.85798 -285.98241) (xy 16.85798 -285.487872) (xy 16.858475 -285.482609) (xy 16.865924 -285.475168)
			(xy 16.871188 -285.474664) (xy 16.871696 -285.474664) (xy 17.38757 -285.474664) (xy 17.39538 -285.474343)
			(xy 17.410251 -285.469563) (xy 17.41678 -285.465266) (xy 17.437869 -285.450917) (xy 17.48353 -285.428186)
			(xy 17.532136 -285.412727) (xy 17.582539 -285.404904) (xy 17.633545 -285.404904) (xy 17.683948 -285.412727)
			(xy 17.732554 -285.428186) (xy 17.778215 -285.450917) (xy 17.799304 -285.465266) (xy 17.805837 -285.469554)
			(xy 17.820706 -285.47434) (xy 17.828514 -285.474664) (xy 18.344642 -285.474664) (xy 18.349957 -285.475098)
			(xy 18.357527 -285.482565) (xy 18.358104 -285.487872) (xy 18.358104 -285.98241) (xy 20.958048 -285.98241)
			(xy 20.958048 -285.487872) (xy 20.958571 -285.482616) (xy 20.966001 -285.475178) (xy 20.971256 -285.474664)
			(xy 20.971764 -285.474664) (xy 21.487638 -285.474664) (xy 21.495446 -285.47433) (xy 21.510318 -285.469558)
			(xy 21.516848 -285.465266) (xy 21.537937 -285.450917) (xy 21.583598 -285.428186) (xy 21.632204 -285.412727)
			(xy 21.682607 -285.404904) (xy 21.733613 -285.404904) (xy 21.784016 -285.412727) (xy 21.832622 -285.428186)
			(xy 21.878283 -285.450917) (xy 21.899372 -285.465266) (xy 21.905913 -285.469542) (xy 21.920776 -285.474335)
			(xy 21.928582 -285.474664) (xy 22.44471 -285.474664) (xy 22.450021 -285.475119) (xy 22.457593 -285.48257)
			(xy 22.458172 -285.487872) (xy 22.458172 -285.98241) (xy 22.458148 -285.982664) (xy 24.402288 -285.982664)
			(xy 24.402288 -285.982156) (xy 24.402288 -285.487872) (xy 24.402776 -285.482607) (xy 24.41023 -285.475166)
			(xy 24.415496 -285.474664) (xy 24.931624 -285.474664) (xy 24.939436 -285.474367) (xy 24.954307 -285.46957)
			(xy 24.960834 -285.465266) (xy 24.981923 -285.450917) (xy 25.027584 -285.428186) (xy 25.07619 -285.412727)
			(xy 25.126593 -285.404904) (xy 25.177599 -285.404904) (xy 25.228002 -285.412727) (xy 25.276608 -285.428186)
			(xy 25.322269 -285.450917) (xy 25.343358 -285.465266) (xy 25.349879 -285.469575) (xy 25.364757 -285.474347)
			(xy 25.372568 -285.474664) (xy 25.888696 -285.474664) (xy 25.893952 -285.475194) (xy 25.901393 -285.482618)
			(xy 25.901904 -285.487872) (xy 25.901904 -285.98241) (xy 25.901879 -285.982664) (xy 28.502356 -285.982664)
			(xy 28.502356 -285.982156) (xy 28.502356 -285.487872) (xy 28.502872 -285.482615) (xy 28.510307 -285.475175)
			(xy 28.515564 -285.474664) (xy 29.031692 -285.474664) (xy 29.039502 -285.474353) (xy 29.054374 -285.469566)
			(xy 29.060902 -285.465266) (xy 29.081991 -285.450917) (xy 29.127652 -285.428186) (xy 29.176258 -285.412727)
			(xy 29.226661 -285.404904) (xy 29.277667 -285.404904) (xy 29.32807 -285.412727) (xy 29.376676 -285.428186)
			(xy 29.422337 -285.450917) (xy 29.443426 -285.465266) (xy 29.449955 -285.469563) (xy 29.464827 -285.474343)
			(xy 29.472636 -285.474664) (xy 29.988764 -285.474664) (xy 29.994085 -285.475048) (xy 30.001626 -285.482553)
			(xy 30.001972 -285.487872) (xy 30.001972 -285.98241) (xy 30.001949 -285.982664) (xy 31.946088 -285.982664)
			(xy 31.946088 -285.982156) (xy 31.946088 -285.487872) (xy 31.946576 -285.482607) (xy 31.95403 -285.475166)
			(xy 31.959296 -285.474664) (xy 32.475424 -285.474664) (xy 32.483236 -285.474367) (xy 32.498107 -285.46957)
			(xy 32.504634 -285.465266) (xy 32.525723 -285.450917) (xy 32.571384 -285.428186) (xy 32.61999 -285.412727)
			(xy 32.670393 -285.404904) (xy 32.721399 -285.404904) (xy 32.771802 -285.412727) (xy 32.820408 -285.428186)
			(xy 32.866069 -285.450917) (xy 32.887158 -285.465266) (xy 32.893679 -285.469575) (xy 32.908557 -285.474347)
			(xy 32.916368 -285.474664) (xy 33.432496 -285.474664) (xy 33.437752 -285.475194) (xy 33.445193 -285.482618)
			(xy 33.445704 -285.487872) (xy 33.445704 -285.98241) (xy 33.445679 -285.982664) (xy 36.046156 -285.982664)
			(xy 36.046156 -285.982156) (xy 36.046156 -285.487872) (xy 36.046672 -285.482615) (xy 36.054107 -285.475175)
			(xy 36.059364 -285.474664) (xy 36.575492 -285.474664) (xy 36.583302 -285.474353) (xy 36.598174 -285.469566)
			(xy 36.604702 -285.465266) (xy 36.625791 -285.450917) (xy 36.671452 -285.428186) (xy 36.720058 -285.412727)
			(xy 36.770461 -285.404904) (xy 36.821467 -285.404904) (xy 36.87187 -285.412727) (xy 36.920476 -285.428186)
			(xy 36.966137 -285.450917) (xy 36.987226 -285.465266) (xy 36.993755 -285.469563) (xy 37.008627 -285.474343)
			(xy 37.016436 -285.474664) (xy 37.532564 -285.474664) (xy 37.537885 -285.475048) (xy 37.545426 -285.482553)
			(xy 37.545772 -285.487872) (xy 37.545772 -285.98241) (xy 39.489888 -285.98241) (xy 39.489888 -285.487872)
			(xy 39.490376 -285.482607) (xy 39.49783 -285.475166) (xy 39.503096 -285.474664) (xy 39.503604 -285.474664)
			(xy 40.019478 -285.474664) (xy 40.027288 -285.474347) (xy 40.042159 -285.469564) (xy 40.048688 -285.465266)
			(xy 40.069777 -285.450917) (xy 40.115438 -285.428186) (xy 40.164044 -285.412727) (xy 40.214447 -285.404904)
			(xy 40.265453 -285.404904) (xy 40.315856 -285.412727) (xy 40.364462 -285.428186) (xy 40.410123 -285.450917)
			(xy 40.431212 -285.465266) (xy 40.437744 -285.469557) (xy 40.452613 -285.474341) (xy 40.460422 -285.474664)
			(xy 40.97655 -285.474664) (xy 40.981854 -285.475159) (xy 40.989429 -285.482579) (xy 40.990012 -285.487872)
			(xy 40.990012 -285.98241) (xy 43.589956 -285.98241) (xy 43.589956 -285.487872) (xy 43.590472 -285.482615)
			(xy 43.597907 -285.475175) (xy 43.603164 -285.474664) (xy 43.603672 -285.474664) (xy 44.119546 -285.474664)
			(xy 44.127355 -285.474333) (xy 44.142226 -285.46956) (xy 44.148756 -285.465266) (xy 44.169845 -285.450917)
			(xy 44.215506 -285.428186) (xy 44.264112 -285.412727) (xy 44.314515 -285.404904) (xy 44.365521 -285.404904)
			(xy 44.415924 -285.412727) (xy 44.46453 -285.428186) (xy 44.510191 -285.450917) (xy 44.53128 -285.465266)
			(xy 44.537819 -285.469545) (xy 44.552683 -285.474336) (xy 44.56049 -285.474664) (xy 45.076618 -285.474664)
			(xy 45.08193 -285.475114) (xy 45.089502 -285.482568) (xy 45.09008 -285.487872) (xy 45.09008 -285.98241)
			(xy 45.090055 -285.982664) (xy 47.034196 -285.982664) (xy 47.034196 -285.982156) (xy 47.034196 -285.487872)
			(xy 47.034676 -285.482605) (xy 47.042136 -285.475164) (xy 47.047404 -285.474664) (xy 47.563532 -285.474664)
			(xy 47.57134 -285.474327) (xy 47.586212 -285.469558) (xy 47.592742 -285.465266) (xy 47.613831 -285.450917)
			(xy 47.659492 -285.428186) (xy 47.708098 -285.412727) (xy 47.758501 -285.404904) (xy 47.809507 -285.404904)
			(xy 47.85991 -285.412727) (xy 47.908516 -285.428186) (xy 47.954177 -285.450917) (xy 47.975266 -285.465266)
			(xy 47.981808 -285.46954) (xy 47.99667 -285.474334) (xy 48.004476 -285.474664) (xy 48.520604 -285.474664)
			(xy 48.525861 -285.475189) (xy 48.533301 -285.482616) (xy 48.533812 -285.487872) (xy 48.533812 -285.98241)
			(xy 48.533791 -285.982664) (xy 51.134264 -285.982664) (xy 51.134264 -285.982156) (xy 51.134264 -285.487872)
			(xy 51.134773 -285.482613) (xy 51.142213 -285.475173) (xy 51.147472 -285.474664) (xy 51.6636 -285.474664)
			(xy 51.671411 -285.474357) (xy 51.686282 -285.469567) (xy 51.69281 -285.465266) (xy 51.713899 -285.450917)
			(xy 51.75956 -285.428186) (xy 51.808166 -285.412727) (xy 51.858569 -285.404904) (xy 51.909575 -285.404904)
			(xy 51.959978 -285.412727) (xy 52.002968 -285.4264) (xy 108.485173 -285.4264) (xy 108.489344 -285.376063)
			(xy 108.501743 -285.327099) (xy 108.522032 -285.280844) (xy 108.549658 -285.238559) (xy 108.583867 -285.201398)
			(xy 108.623725 -285.170374) (xy 108.668147 -285.146334) (xy 108.715919 -285.129932) (xy 108.765739 -285.121618)
			(xy 108.790994 -285.121096) (xy 109.731048 -285.121096) (xy 109.756301 -285.121613) (xy 109.806117 -285.129933)
			(xy 109.853885 -285.146339) (xy 109.898301 -285.170382) (xy 109.938155 -285.201407) (xy 109.972359 -285.238568)
			(xy 109.999981 -285.280852) (xy 110.020267 -285.327105) (xy 110.032665 -285.376066) (xy 110.036835 -285.4264)
			(xy 114.118844 -285.4264) (xy 114.123016 -285.376056) (xy 114.135417 -285.327086) (xy 114.15571 -285.280825)
			(xy 114.18334 -285.238535) (xy 114.217555 -285.201369) (xy 114.25742 -285.170343) (xy 114.301849 -285.146301)
			(xy 114.349628 -285.1299) (xy 114.399456 -285.121588) (xy 114.424714 -285.121096) (xy 115.364768 -285.121096)
			(xy 115.390028 -285.121578) (xy 115.439859 -285.129889) (xy 115.448283 -285.13278) (xy 167.778176 -285.13278)
			(xy 167.778176 -284.637988) (xy 167.778685 -284.632728) (xy 167.786124 -284.625287) (xy 167.791384 -284.62478)
			(xy 169.264584 -284.62478) (xy 169.269911 -284.625136) (xy 169.277452 -284.632662) (xy 169.277792 -284.637988)
			(xy 169.277792 -285.132526) (xy 175.321976 -285.132526) (xy 175.321976 -284.637988) (xy 175.322485 -284.632728)
			(xy 175.329924 -284.625287) (xy 175.335184 -284.62478) (xy 175.335692 -284.62478) (xy 175.851566 -284.62478)
			(xy 175.859375 -284.624455) (xy 175.874247 -284.619677) (xy 175.880776 -284.615382) (xy 175.901865 -284.601033)
			(xy 175.947526 -284.578302) (xy 175.996132 -284.562843) (xy 176.046535 -284.55502) (xy 176.097541 -284.55502)
			(xy 176.147944 -284.562843) (xy 176.19655 -284.578302) (xy 176.242211 -284.601033) (xy 176.2633 -284.615382)
			(xy 176.269833 -284.61967) (xy 176.284702 -284.624455) (xy 176.29251 -284.62478) (xy 176.808638 -284.62478)
			(xy 176.813956 -284.625203) (xy 176.821527 -284.632677) (xy 176.8221 -284.637988) (xy 176.8221 -285.132526)
			(xy 176.822075 -285.13278) (xy 182.866284 -285.13278) (xy 182.866284 -285.132272) (xy 182.866284 -284.637988)
			(xy 182.866786 -284.632726) (xy 182.87423 -284.625284) (xy 182.879492 -284.62478) (xy 183.39562 -284.62478)
			(xy 183.403431 -284.624478) (xy 183.418303 -284.619684) (xy 183.42483 -284.615382) (xy 183.445919 -284.601033)
			(xy 183.49158 -284.578302) (xy 183.540186 -284.562843) (xy 183.590589 -284.55502) (xy 183.641595 -284.55502)
			(xy 183.691998 -284.562843) (xy 183.740604 -284.578302) (xy 183.786265 -284.601033) (xy 183.807354 -284.615382)
			(xy 183.813875 -284.619691) (xy 183.828753 -284.624463) (xy 183.836564 -284.62478) (xy 184.352692 -284.62478)
			(xy 184.357951 -284.625299) (xy 184.365393 -284.63273) (xy 184.3659 -284.637988) (xy 184.3659 -285.132526)
			(xy 190.410084 -285.132526) (xy 190.410084 -284.637988) (xy 190.410586 -284.632726) (xy 190.41803 -284.625284)
			(xy 190.423292 -284.62478) (xy 190.4238 -284.62478) (xy 190.939674 -284.62478) (xy 190.947483 -284.624459)
			(xy 190.962355 -284.619678) (xy 190.968884 -284.615382) (xy 190.989973 -284.601033) (xy 191.035634 -284.578302)
			(xy 191.08424 -284.562843) (xy 191.134643 -284.55502) (xy 191.185649 -284.55502) (xy 191.236052 -284.562843)
			(xy 191.284658 -284.578302) (xy 191.330319 -284.601033) (xy 191.351408 -284.615382) (xy 191.35794 -284.619673)
			(xy 191.37281 -284.624456) (xy 191.380618 -284.62478) (xy 191.896746 -284.62478) (xy 191.902053 -284.625264)
			(xy 191.90963 -284.632691) (xy 191.910208 -284.637988) (xy 191.910208 -285.132526) (xy 191.910183 -285.13278)
			(xy 197.954392 -285.13278) (xy 197.954392 -285.132272) (xy 197.954392 -284.637988) (xy 197.954887 -284.632724)
			(xy 197.962335 -284.625282) (xy 197.9676 -284.62478) (xy 198.483728 -284.62478) (xy 198.49154 -284.624482)
			(xy 198.506411 -284.619685) (xy 198.512938 -284.615382) (xy 198.534027 -284.601033) (xy 198.579688 -284.578302)
			(xy 198.628294 -284.562843) (xy 198.678697 -284.55502) (xy 198.729703 -284.55502) (xy 198.780106 -284.562843)
			(xy 198.828712 -284.578302) (xy 198.874373 -284.601033) (xy 198.895462 -284.615382) (xy 198.902004 -284.619655)
			(xy 198.916866 -284.62445) (xy 198.924672 -284.62478) (xy 199.4408 -284.62478) (xy 199.44606 -284.625294)
			(xy 199.453502 -284.632729) (xy 199.454008 -284.637988) (xy 199.454008 -285.132526) (xy 199.453984 -285.13278)
			(xy 205.498192 -285.13278) (xy 205.498192 -285.132272) (xy 205.498192 -284.637988) (xy 205.498687 -284.632724)
			(xy 205.506135 -284.625282) (xy 205.5114 -284.62478) (xy 206.027528 -284.62478) (xy 206.03534 -284.624482)
			(xy 206.050211 -284.619685) (xy 206.056738 -284.615382) (xy 206.077827 -284.601033) (xy 206.123488 -284.578302)
			(xy 206.172094 -284.562843) (xy 206.222497 -284.55502) (xy 206.273503 -284.55502) (xy 206.323906 -284.562843)
			(xy 206.372512 -284.578302) (xy 206.418173 -284.601033) (xy 206.439262 -284.615382) (xy 206.445804 -284.619655)
			(xy 206.460666 -284.62445) (xy 206.468472 -284.62478) (xy 206.9846 -284.62478) (xy 206.98986 -284.625294)
			(xy 206.997302 -284.632729) (xy 206.997808 -284.637988) (xy 206.997808 -285.132272) (xy 268.898116 -285.132272)
			(xy 268.898116 -284.637734) (xy 268.8985 -284.632309) (xy 268.906155 -284.624622) (xy 268.911578 -284.624272)
			(xy 269.427706 -284.624272) (xy 269.435517 -284.623966) (xy 269.450388 -284.619175) (xy 269.456916 -284.614874)
			(xy 269.478005 -284.600525) (xy 269.523666 -284.577794) (xy 269.572272 -284.562335) (xy 269.622675 -284.554512)
			(xy 269.673681 -284.554512) (xy 269.724084 -284.562335) (xy 269.77269 -284.577794) (xy 269.818351 -284.600525)
			(xy 269.83944 -284.614874) (xy 269.845965 -284.619177) (xy 269.86084 -284.623953) (xy 269.86865 -284.624272)
			(xy 270.384778 -284.624272) (xy 270.390218 -284.624598) (xy 270.397907 -284.632294) (xy 270.39824 -284.637734)
			(xy 270.39824 -285.132272) (xy 276.442424 -285.132272) (xy 276.442424 -284.637734) (xy 276.442944 -284.632438)
			(xy 276.450348 -284.624865) (xy 276.455632 -284.624272) (xy 276.97176 -284.624272) (xy 276.979569 -284.623946)
			(xy 276.994441 -284.619169) (xy 277.00097 -284.614874) (xy 277.022059 -284.600525) (xy 277.06772 -284.577794)
			(xy 277.116326 -284.562335) (xy 277.166729 -284.554512) (xy 277.217735 -284.554512) (xy 277.268138 -284.562335)
			(xy 277.316744 -284.577794) (xy 277.362405 -284.600525) (xy 277.383494 -284.614874) (xy 277.390029 -284.619159)
			(xy 277.404896 -284.623946) (xy 277.412704 -284.624272) (xy 277.928832 -284.624272) (xy 277.934094 -284.624771)
			(xy 277.941533 -284.632218) (xy 277.94204 -284.63748) (xy 277.94204 -284.637988) (xy 277.94204 -285.132272)
			(xy 283.986224 -285.132272) (xy 283.986224 -284.637734) (xy 283.986744 -284.632438) (xy 283.994148 -284.624865)
			(xy 283.999432 -284.624272) (xy 284.51556 -284.624272) (xy 284.523369 -284.623946) (xy 284.538241 -284.619169)
			(xy 284.54477 -284.614874) (xy 284.565859 -284.600525) (xy 284.61152 -284.577794) (xy 284.660126 -284.562335)
			(xy 284.710529 -284.554512) (xy 284.761535 -284.554512) (xy 284.811938 -284.562335) (xy 284.860544 -284.577794)
			(xy 284.906205 -284.600525) (xy 284.927294 -284.614874) (xy 284.933829 -284.619159) (xy 284.948696 -284.623946)
			(xy 284.956504 -284.624272) (xy 285.472632 -284.624272) (xy 285.477894 -284.624771) (xy 285.485333 -284.632218)
			(xy 285.48584 -284.63748) (xy 285.48584 -284.637988) (xy 285.48584 -285.132272) (xy 291.530024 -285.132272)
			(xy 291.530024 -284.637734) (xy 291.530401 -284.632307) (xy 291.53806 -284.62462) (xy 291.543486 -284.624272)
			(xy 292.059614 -284.624272) (xy 292.067425 -284.623969) (xy 292.082297 -284.619176) (xy 292.088824 -284.614874)
			(xy 292.109913 -284.600525) (xy 292.155574 -284.577794) (xy 292.20418 -284.562335) (xy 292.254583 -284.554512)
			(xy 292.305589 -284.554512) (xy 292.355992 -284.562335) (xy 292.404598 -284.577794) (xy 292.450259 -284.600525)
			(xy 292.471348 -284.614874) (xy 292.477871 -284.61918) (xy 292.492748 -284.623954) (xy 292.500558 -284.624272)
			(xy 293.016686 -284.624272) (xy 293.022127 -284.624592) (xy 293.029816 -284.632292) (xy 293.030148 -284.637734)
			(xy 293.030148 -285.132272) (xy 299.074332 -285.132272) (xy 299.074332 -284.637734) (xy 299.074845 -284.632436)
			(xy 299.082253 -284.624863) (xy 299.08754 -284.624272) (xy 299.603668 -284.624272) (xy 299.611477 -284.623949)
			(xy 299.626349 -284.61917) (xy 299.632878 -284.614874) (xy 299.653967 -284.600525) (xy 299.699628 -284.577794)
			(xy 299.748234 -284.562335) (xy 299.798637 -284.554512) (xy 299.849643 -284.554512) (xy 299.900046 -284.562335)
			(xy 299.948652 -284.577794) (xy 299.994313 -284.600525) (xy 300.015402 -284.614874) (xy 300.01727 -284.6161)
			(xy 345.615313 -284.6161) (xy 345.619483 -284.565772) (xy 345.63188 -284.516816) (xy 345.652165 -284.470568)
			(xy 345.679785 -284.42829) (xy 345.713987 -284.391134) (xy 345.753838 -284.360114) (xy 345.798251 -284.336076)
			(xy 345.846014 -284.319675) (xy 345.895826 -284.311359) (xy 345.921076 -284.310836) (xy 346.86113 -284.310836)
			(xy 346.886387 -284.311272) (xy 346.936213 -284.31959) (xy 346.983989 -284.335996) (xy 347.028414 -284.360042)
			(xy 347.068275 -284.391071) (xy 347.102487 -284.428237) (xy 347.130114 -284.470528) (xy 347.150404 -284.516788)
			(xy 347.162804 -284.565758) (xy 347.166976 -284.6161) (xy 348.435384 -284.6161) (xy 348.439556 -284.56576)
			(xy 348.451957 -284.516794) (xy 348.472249 -284.470537) (xy 348.499878 -284.428251) (xy 348.534091 -284.39109)
			(xy 348.573955 -284.360068) (xy 348.618381 -284.336031) (xy 348.666158 -284.319634) (xy 348.715982 -284.311326)
			(xy 348.741238 -284.310836) (xy 349.681292 -284.310836) (xy 349.706554 -284.31124) (xy 349.756388 -284.319555)
			(xy 349.804175 -284.335959) (xy 349.848609 -284.360005) (xy 349.88848 -284.391036) (xy 349.922699 -284.428207)
			(xy 349.950333 -284.470504) (xy 349.970629 -284.516772) (xy 349.983032 -284.565749) (xy 349.987204 -284.6161)
			(xy 351.255284 -284.6161) (xy 351.259456 -284.56576) (xy 351.271857 -284.516793) (xy 351.29215 -284.470535)
			(xy 351.31978 -284.428249) (xy 351.353994 -284.391087) (xy 351.393859 -284.360065) (xy 351.438286 -284.336028)
			(xy 351.486064 -284.319632) (xy 351.535889 -284.311325) (xy 351.561146 -284.310836) (xy 352.5012 -284.310836)
			(xy 352.526459 -284.311269) (xy 352.576288 -284.319584) (xy 352.624069 -284.335987) (xy 352.668498 -284.360031)
			(xy 352.708364 -284.39106) (xy 352.742579 -284.428227) (xy 352.770209 -284.470519) (xy 352.790502 -284.516782)
			(xy 352.802904 -284.565755) (xy 352.807076 -284.6161) (xy 354.075313 -284.6161) (xy 354.079483 -284.565774)
			(xy 354.091878 -284.51682) (xy 354.112161 -284.470574) (xy 354.139779 -284.428297) (xy 354.173978 -284.391142)
			(xy 354.213826 -284.360121) (xy 354.258236 -284.336082) (xy 354.305996 -284.31968) (xy 354.355805 -284.311361)
			(xy 354.381054 -284.310836) (xy 355.321108 -284.310836) (xy 355.346367 -284.31127) (xy 355.396195 -284.319586)
			(xy 355.443974 -284.33599) (xy 355.488402 -284.360034) (xy 355.528267 -284.391063) (xy 355.562481 -284.42823)
			(xy 355.590111 -284.470522) (xy 355.610403 -284.516784) (xy 355.622804 -284.565755) (xy 355.626976 -284.6161)
			(xy 364.409013 -284.6161) (xy 364.413183 -284.56577) (xy 364.425581 -284.516813) (xy 364.445867 -284.470564)
			(xy 364.473488 -284.428285) (xy 364.507692 -284.391129) (xy 364.547545 -284.360109) (xy 364.59196 -284.336071)
			(xy 364.639726 -284.319672) (xy 364.689539 -284.311358) (xy 364.71479 -284.310836) (xy 365.654844 -284.310836)
			(xy 365.680101 -284.311273) (xy 365.729924 -284.319593) (xy 365.777699 -284.336) (xy 365.822121 -284.360047)
			(xy 365.861981 -284.391076) (xy 365.89619 -284.428242) (xy 365.923816 -284.470532) (xy 365.944105 -284.516791)
			(xy 365.956505 -284.565759) (xy 365.960676 -284.6161) (xy 367.228913 -284.6161) (xy 367.233084 -284.565769)
			(xy 367.245481 -284.516812) (xy 367.265768 -284.470562) (xy 367.293391 -284.428282) (xy 367.327595 -284.391126)
			(xy 367.367449 -284.360106) (xy 367.411865 -284.336069) (xy 367.459632 -284.31967) (xy 367.509446 -284.311358)
			(xy 367.534698 -284.310836) (xy 368.474752 -284.310836) (xy 368.500016 -284.311237) (xy 368.549856 -284.319547)
			(xy 368.597648 -284.335947) (xy 368.642088 -284.359991) (xy 368.681965 -284.391022) (xy 368.716189 -284.428194)
			(xy 368.743827 -284.470492) (xy 368.764126 -284.516764) (xy 368.776531 -284.565745) (xy 368.780704 -284.6161)
			(xy 370.049113 -284.6161) (xy 370.053283 -284.565773) (xy 370.065679 -284.516819) (xy 370.085962 -284.470573)
			(xy 370.113581 -284.428295) (xy 370.147781 -284.391139) (xy 370.187629 -284.360119) (xy 370.23204 -284.33608)
			(xy 370.279801 -284.319678) (xy 370.32961 -284.311361) (xy 370.35486 -284.310836) (xy 371.294914 -284.310836)
			(xy 371.320172 -284.31127) (xy 371.369999 -284.319587) (xy 371.417778 -284.335992) (xy 371.462205 -284.360036)
			(xy 371.502069 -284.391065) (xy 371.536282 -284.428232) (xy 371.563912 -284.470523) (xy 371.584203 -284.516785)
			(xy 371.596604 -284.565756) (xy 371.600776 -284.6161) (xy 372.869013 -284.6161) (xy 372.873183 -284.565772)
			(xy 372.885579 -284.516818) (xy 372.905864 -284.47057) (xy 372.933483 -284.428292) (xy 372.967684 -284.391137)
			(xy 373.007533 -284.360116) (xy 373.051945 -284.336078) (xy 373.099708 -284.319677) (xy 373.149518 -284.31136)
			(xy 373.174768 -284.310836) (xy 374.114822 -284.310836) (xy 374.14008 -284.311271) (xy 374.189906 -284.319589)
			(xy 374.237684 -284.335994) (xy 374.28211 -284.360039) (xy 374.321972 -284.391068) (xy 374.356184 -284.428235)
			(xy 374.383813 -284.470525) (xy 374.404104 -284.516787) (xy 374.416504 -284.565757) (xy 374.420676 -284.6161)
			(xy 374.416504 -284.666443) (xy 374.404104 -284.715413) (xy 374.383813 -284.761675) (xy 374.356184 -284.803965)
			(xy 374.321972 -284.841132) (xy 374.28211 -284.872161) (xy 374.237684 -284.896206) (xy 374.189906 -284.912611)
			(xy 374.14008 -284.920929) (xy 374.114822 -284.921452) (xy 373.174768 -284.921452) (xy 373.149518 -284.92084)
			(xy 373.099708 -284.912523) (xy 373.051945 -284.896122) (xy 373.007533 -284.872084) (xy 372.967684 -284.841063)
			(xy 372.933483 -284.803908) (xy 372.905864 -284.76163) (xy 372.885579 -284.715382) (xy 372.873183 -284.666428)
			(xy 372.869013 -284.6161) (xy 371.600776 -284.6161) (xy 371.596604 -284.666444) (xy 371.584203 -284.715415)
			(xy 371.563912 -284.761677) (xy 371.536282 -284.803968) (xy 371.502069 -284.841135) (xy 371.462205 -284.872164)
			(xy 371.417778 -284.896208) (xy 371.369999 -284.912613) (xy 371.320172 -284.92093) (xy 371.294914 -284.921452)
			(xy 370.35486 -284.921452) (xy 370.32961 -284.920839) (xy 370.279801 -284.912522) (xy 370.23204 -284.89612)
			(xy 370.187629 -284.872081) (xy 370.147781 -284.841061) (xy 370.113581 -284.803905) (xy 370.085962 -284.761627)
			(xy 370.065679 -284.715381) (xy 370.053283 -284.666427) (xy 370.049113 -284.6161) (xy 368.780704 -284.6161)
			(xy 368.776531 -284.666455) (xy 368.764126 -284.715436) (xy 368.743827 -284.761708) (xy 368.716189 -284.804006)
			(xy 368.681965 -284.841178) (xy 368.642088 -284.872209) (xy 368.597648 -284.896253) (xy 368.549856 -284.912653)
			(xy 368.500016 -284.920963) (xy 368.474752 -284.921452) (xy 367.534698 -284.921452) (xy 367.509446 -284.920842)
			(xy 367.459632 -284.91253) (xy 367.411865 -284.896131) (xy 367.367449 -284.872094) (xy 367.327595 -284.841074)
			(xy 367.293391 -284.803918) (xy 367.265768 -284.761638) (xy 367.245481 -284.715388) (xy 367.233084 -284.666431)
			(xy 367.228913 -284.6161) (xy 365.960676 -284.6161) (xy 365.956505 -284.666441) (xy 365.944105 -284.715409)
			(xy 365.923816 -284.761668) (xy 365.89619 -284.803958) (xy 365.861981 -284.841124) (xy 365.822121 -284.872153)
			(xy 365.777699 -284.8962) (xy 365.729924 -284.912607) (xy 365.680101 -284.920927) (xy 365.654844 -284.921452)
			(xy 364.71479 -284.921452) (xy 364.689539 -284.920842) (xy 364.639726 -284.912528) (xy 364.59196 -284.896129)
			(xy 364.547545 -284.872091) (xy 364.507692 -284.841071) (xy 364.473489 -284.803915) (xy 364.445867 -284.761636)
			(xy 364.425581 -284.715387) (xy 364.413183 -284.66643) (xy 364.409013 -284.6161) (xy 355.626976 -284.6161)
			(xy 355.622804 -284.666445) (xy 355.610403 -284.715416) (xy 355.590111 -284.761678) (xy 355.562481 -284.80397)
			(xy 355.528267 -284.841137) (xy 355.488402 -284.872166) (xy 355.443974 -284.89621) (xy 355.396195 -284.912614)
			(xy 355.346367 -284.92093) (xy 355.321108 -284.921452) (xy 354.381054 -284.921452) (xy 354.355805 -284.920839)
			(xy 354.305996 -284.91252) (xy 354.258236 -284.896118) (xy 354.213826 -284.872079) (xy 354.173978 -284.841058)
			(xy 354.139779 -284.803903) (xy 354.112161 -284.761626) (xy 354.091878 -284.71538) (xy 354.079483 -284.666426)
			(xy 354.075313 -284.6161) (xy 352.807076 -284.6161) (xy 352.802904 -284.666445) (xy 352.790502 -284.715418)
			(xy 352.770209 -284.761681) (xy 352.742579 -284.803973) (xy 352.708364 -284.84114) (xy 352.668498 -284.872169)
			(xy 352.624069 -284.896213) (xy 352.576288 -284.912616) (xy 352.526459 -284.920931) (xy 352.5012 -284.921452)
			(xy 351.561146 -284.921452) (xy 351.535889 -284.920875) (xy 351.486064 -284.912568) (xy 351.438286 -284.896172)
			(xy 351.393859 -284.872135) (xy 351.353994 -284.841113) (xy 351.31978 -284.803951) (xy 351.29215 -284.761665)
			(xy 351.271857 -284.715407) (xy 351.259456 -284.66644) (xy 351.255284 -284.6161) (xy 349.987204 -284.6161)
			(xy 349.983032 -284.666451) (xy 349.970629 -284.715428) (xy 349.950333 -284.761696) (xy 349.922699 -284.803993)
			(xy 349.88848 -284.841164) (xy 349.848609 -284.872195) (xy 349.804175 -284.896241) (xy 349.756388 -284.912645)
			(xy 349.706554 -284.92096) (xy 349.681292 -284.921452) (xy 348.741238 -284.921452) (xy 348.715982 -284.920874)
			(xy 348.666158 -284.912566) (xy 348.618381 -284.896169) (xy 348.573955 -284.872132) (xy 348.534091 -284.84111)
			(xy 348.499878 -284.803949) (xy 348.472249 -284.761663) (xy 348.451957 -284.715406) (xy 348.439556 -284.66644)
			(xy 348.435384 -284.6161) (xy 347.166976 -284.6161) (xy 347.162804 -284.666442) (xy 347.150404 -284.715412)
			(xy 347.130114 -284.761672) (xy 347.102487 -284.803963) (xy 347.068275 -284.841129) (xy 347.028414 -284.872158)
			(xy 346.983989 -284.896204) (xy 346.936213 -284.91261) (xy 346.886387 -284.920928) (xy 346.86113 -284.921452)
			(xy 345.921076 -284.921452) (xy 345.895826 -284.920841) (xy 345.846014 -284.912525) (xy 345.798251 -284.896124)
			(xy 345.753838 -284.872086) (xy 345.713987 -284.841066) (xy 345.679785 -284.80391) (xy 345.652165 -284.761632)
			(xy 345.63188 -284.715384) (xy 345.619483 -284.666428) (xy 345.615313 -284.6161) (xy 300.01727 -284.6161)
			(xy 300.021935 -284.619162) (xy 300.036804 -284.623947) (xy 300.044612 -284.624272) (xy 300.56074 -284.624272)
			(xy 300.566003 -284.624766) (xy 300.573442 -284.632216) (xy 300.573948 -284.63748) (xy 300.573948 -284.637988)
			(xy 300.573948 -285.132272) (xy 306.618132 -285.132272) (xy 306.618132 -284.637734) (xy 306.618501 -284.632305)
			(xy 306.626166 -284.624618) (xy 306.631594 -284.624272) (xy 308.104794 -284.624272) (xy 308.110236 -284.624587)
			(xy 308.117925 -284.632291) (xy 308.118256 -284.637734) (xy 308.118256 -285.132272) (xy 308.117692 -285.13752)
			(xy 308.110293 -285.144961) (xy 308.105048 -285.14548) (xy 308.10454 -285.14548) (xy 306.631594 -285.14548)
			(xy 306.626294 -285.144983) (xy 306.618724 -285.137562) (xy 306.618132 -285.132272) (xy 300.573948 -285.132272)
			(xy 300.573391 -285.137522) (xy 300.565987 -285.144964) (xy 300.56074 -285.14548) (xy 300.044866 -285.14548)
			(xy 300.03699 -285.145756) (xy 300.021986 -285.150547) (xy 300.015402 -285.154878) (xy 299.994317 -285.169257)
			(xy 299.948674 -285.192088) (xy 299.900071 -285.207649) (xy 299.849656 -285.215572) (xy 299.82414 -285.216092)
			(xy 299.79862 -285.215601) (xy 299.748193 -285.207707) (xy 299.699581 -285.192147) (xy 299.653943 -285.169293)
			(xy 299.632878 -285.154878) (xy 299.626289 -285.150559) (xy 299.611287 -285.145773) (xy 299.603414 -285.14548)
			(xy 299.08754 -285.14548) (xy 299.082206 -285.145143) (xy 299.074661 -285.137605) (xy 299.074332 -285.132272)
			(xy 293.030148 -285.132272) (xy 293.029591 -285.137522) (xy 293.022187 -285.144964) (xy 293.01694 -285.14548)
			(xy 293.016432 -285.14548) (xy 292.500812 -285.14548) (xy 292.492938 -285.145775) (xy 292.477934 -285.150553)
			(xy 292.471348 -285.154878) (xy 292.450278 -285.169281) (xy 292.40463 -285.192106) (xy 292.356022 -285.20766)
			(xy 292.305603 -285.215576) (xy 292.280086 -285.216092) (xy 292.254567 -285.215578) (xy 292.204141 -285.207691)
			(xy 292.155529 -285.192138) (xy 292.10989 -285.16929) (xy 292.088824 -285.154878) (xy 292.082224 -285.150577)
			(xy 292.067231 -285.14578) (xy 292.05936 -285.14548) (xy 291.543486 -285.14548) (xy 291.538185 -285.144988)
			(xy 291.530616 -285.137563) (xy 291.530024 -285.132272) (xy 285.48584 -285.132272) (xy 285.48529 -285.137524)
			(xy 285.477881 -285.144966) (xy 285.472632 -285.14548) (xy 284.956758 -285.14548) (xy 284.948882 -285.145752)
			(xy 284.933878 -285.150546) (xy 284.927294 -285.154878) (xy 284.906211 -285.169261) (xy 284.860568 -285.19209)
			(xy 284.811964 -285.20765) (xy 284.761548 -285.215573) (xy 284.736032 -285.216092) (xy 284.710512 -285.215605)
			(xy 284.660085 -285.20771) (xy 284.611473 -285.192149) (xy 284.565835 -285.169294) (xy 284.54477 -285.154878)
			(xy 284.538182 -285.150556) (xy 284.52318 -285.145772) (xy 284.515306 -285.14548) (xy 283.999432 -285.14548)
			(xy 283.994097 -285.145149) (xy 283.986553 -285.137607) (xy 283.986224 -285.132272) (xy 277.94204 -285.132272)
			(xy 277.94149 -285.137524) (xy 277.934081 -285.144966) (xy 277.928832 -285.14548) (xy 277.412958 -285.14548)
			(xy 277.405082 -285.145752) (xy 277.390078 -285.150546) (xy 277.383494 -285.154878) (xy 277.362411 -285.169261)
			(xy 277.316768 -285.19209) (xy 277.268164 -285.20765) (xy 277.217748 -285.215573) (xy 277.192232 -285.216092)
			(xy 277.166712 -285.215605) (xy 277.116285 -285.20771) (xy 277.067673 -285.192149) (xy 277.022035 -285.169294)
			(xy 277.00097 -285.154878) (xy 276.994382 -285.150556) (xy 276.97938 -285.145772) (xy 276.971506 -285.14548)
			(xy 276.455632 -285.14548) (xy 276.450297 -285.145149) (xy 276.442753 -285.137607) (xy 276.442424 -285.132272)
			(xy 270.39824 -285.132272) (xy 270.39769 -285.137524) (xy 270.390281 -285.144966) (xy 270.385032 -285.14548)
			(xy 270.384524 -285.14548) (xy 269.868904 -285.14548) (xy 269.86103 -285.145772) (xy 269.846025 -285.150552)
			(xy 269.83944 -285.154878) (xy 269.818372 -285.169284) (xy 269.772723 -285.192108) (xy 269.724115 -285.207662)
			(xy 269.673695 -285.215577) (xy 269.648178 -285.216092) (xy 269.622659 -285.215582) (xy 269.572232 -285.207694)
			(xy 269.523621 -285.19214) (xy 269.477982 -285.169291) (xy 269.456916 -285.154878) (xy 269.450318 -285.150574)
			(xy 269.435323 -285.145779) (xy 269.427452 -285.14548) (xy 268.911578 -285.14548) (xy 268.906276 -285.144994)
			(xy 268.898707 -285.137564) (xy 268.898116 -285.132272) (xy 206.997808 -285.132272) (xy 206.997808 -285.132526)
			(xy 206.9973 -285.137822) (xy 206.989885 -285.145389) (xy 206.9846 -285.145988) (xy 206.468726 -285.145988)
			(xy 206.460915 -285.146298) (xy 206.446043 -285.151085) (xy 206.439516 -285.155386) (xy 206.41839 -285.169729)
			(xy 206.372667 -285.192456) (xy 206.323996 -285.207887) (xy 206.273531 -285.215657) (xy 206.248 -285.216092)
			(xy 206.22247 -285.21565) (xy 206.172007 -285.207875) (xy 206.123334 -285.192447) (xy 206.077606 -285.169733)
			(xy 206.056484 -285.155386) (xy 206.04995 -285.151098) (xy 206.035082 -285.146311) (xy 206.027274 -285.145988)
			(xy 205.5114 -285.145988) (xy 205.506063 -285.145671) (xy 205.498521 -285.138118) (xy 205.498192 -285.13278)
			(xy 199.453984 -285.13278) (xy 199.4535 -285.137822) (xy 199.446085 -285.145389) (xy 199.4408 -285.145988)
			(xy 198.924926 -285.145988) (xy 198.917115 -285.146298) (xy 198.902243 -285.151085) (xy 198.895716 -285.155386)
			(xy 198.87459 -285.169729) (xy 198.828867 -285.192456) (xy 198.780196 -285.207887) (xy 198.729731 -285.215657)
			(xy 198.7042 -285.216092) (xy 198.67867 -285.21565) (xy 198.628207 -285.207875) (xy 198.579534 -285.192447)
			(xy 198.533806 -285.169733) (xy 198.512684 -285.155386) (xy 198.50615 -285.151098) (xy 198.491282 -285.146311)
			(xy 198.483474 -285.145988) (xy 197.9676 -285.145988) (xy 197.962263 -285.145671) (xy 197.954721 -285.138118)
			(xy 197.954392 -285.13278) (xy 191.910183 -285.13278) (xy 191.909671 -285.137882) (xy 191.902101 -285.145463)
			(xy 191.896746 -285.145988) (xy 191.380872 -285.145988) (xy 191.373059 -285.146275) (xy 191.358187 -285.151078)
			(xy 191.351662 -285.155386) (xy 191.330551 -285.169752) (xy 191.284823 -285.192474) (xy 191.236147 -285.207899)
			(xy 191.185678 -285.215661) (xy 191.160146 -285.216092) (xy 191.134617 -285.215627) (xy 191.084154 -285.207859)
			(xy 191.035482 -285.192438) (xy 190.989753 -285.16973) (xy 190.96863 -285.155386) (xy 190.962086 -285.151116)
			(xy 190.947226 -285.146318) (xy 190.93942 -285.145988) (xy 190.423546 -285.145988) (xy 190.418123 -285.145593)
			(xy 190.410436 -285.137946) (xy 190.410084 -285.132526) (xy 184.3659 -285.132526) (xy 184.365399 -285.137824)
			(xy 184.357979 -285.145392) (xy 184.352692 -285.145988) (xy 183.836818 -285.145988) (xy 183.829007 -285.146295)
			(xy 183.814135 -285.151084) (xy 183.807608 -285.155386) (xy 183.786484 -285.169732) (xy 183.740761 -285.192458)
			(xy 183.692088 -285.207889) (xy 183.641623 -285.215658) (xy 183.616092 -285.216092) (xy 183.590562 -285.215655)
			(xy 183.540098 -285.207878) (xy 183.491426 -285.192449) (xy 183.445698 -285.169733) (xy 183.424576 -285.155386)
			(xy 183.418044 -285.151095) (xy 183.403175 -285.14631) (xy 183.395366 -285.145988) (xy 182.879492 -285.145988)
			(xy 182.874154 -285.145677) (xy 182.866612 -285.138119) (xy 182.866284 -285.13278) (xy 176.822075 -285.13278)
			(xy 176.821571 -285.137884) (xy 176.813995 -285.145466) (xy 176.808638 -285.145988) (xy 176.292764 -285.145988)
			(xy 176.284955 -285.146314) (xy 176.270083 -285.15109) (xy 176.263554 -285.155386) (xy 176.242445 -285.169755)
			(xy 176.196717 -285.192477) (xy 176.148039 -285.207901) (xy 176.09757 -285.215662) (xy 176.072038 -285.216092)
			(xy 176.046509 -285.215631) (xy 175.996046 -285.207862) (xy 175.947374 -285.19244) (xy 175.901645 -285.16973)
			(xy 175.880522 -285.155386) (xy 175.87398 -285.151113) (xy 175.859118 -285.146317) (xy 175.851312 -285.145988)
			(xy 175.335438 -285.145988) (xy 175.330014 -285.145598) (xy 175.322328 -285.137948) (xy 175.321976 -285.132526)
			(xy 169.277792 -285.132526) (xy 169.277298 -285.137826) (xy 169.269873 -285.145393) (xy 169.264584 -285.145988)
			(xy 167.791384 -285.145988) (xy 167.786045 -285.145682) (xy 167.778503 -285.13812) (xy 167.778176 -285.13278)
			(xy 115.448283 -285.13278) (xy 115.487643 -285.146288) (xy 115.532075 -285.17033) (xy 115.571944 -285.201357)
			(xy 115.606161 -285.238524) (xy 115.633795 -285.280816) (xy 115.654089 -285.32708) (xy 115.666492 -285.376053)
			(xy 115.670664 -285.4264) (xy 115.666492 -285.476747) (xy 115.654089 -285.52572) (xy 115.633795 -285.571984)
			(xy 115.606161 -285.614276) (xy 115.571944 -285.651443) (xy 115.532075 -285.68247) (xy 115.487643 -285.706512)
			(xy 115.439859 -285.722911) (xy 115.390028 -285.731222) (xy 115.364768 -285.731712) (xy 114.424714 -285.731712)
			(xy 114.399456 -285.731212) (xy 114.349628 -285.7229) (xy 114.301849 -285.706499) (xy 114.25742 -285.682457)
			(xy 114.217555 -285.651431) (xy 114.18334 -285.614265) (xy 114.15571 -285.571975) (xy 114.135417 -285.525714)
			(xy 114.123016 -285.476744) (xy 114.118844 -285.4264) (xy 110.036835 -285.4264) (xy 110.032665 -285.476734)
			(xy 110.020267 -285.525695) (xy 109.999981 -285.571948) (xy 109.972359 -285.614232) (xy 109.938155 -285.651393)
			(xy 109.898301 -285.682418) (xy 109.853885 -285.706461) (xy 109.806117 -285.722867) (xy 109.756301 -285.731187)
			(xy 109.731048 -285.731712) (xy 108.790994 -285.731712) (xy 108.765739 -285.731182) (xy 108.715919 -285.722868)
			(xy 108.668147 -285.706466) (xy 108.623725 -285.682426) (xy 108.583867 -285.651402) (xy 108.549658 -285.614241)
			(xy 108.522032 -285.571956) (xy 108.501743 -285.525701) (xy 108.489344 -285.476737) (xy 108.485173 -285.4264)
			(xy 52.002968 -285.4264) (xy 52.008584 -285.428186) (xy 52.054245 -285.450917) (xy 52.075334 -285.465266)
			(xy 52.081861 -285.469566) (xy 52.096734 -285.474344) (xy 52.104544 -285.474664) (xy 52.620672 -285.474664)
			(xy 52.625925 -285.47521) (xy 52.633367 -285.482622) (xy 52.63388 -285.487872) (xy 52.63388 -285.98241)
			(xy 54.577996 -285.98241) (xy 54.577996 -285.487872) (xy 54.578476 -285.482605) (xy 54.585936 -285.475164)
			(xy 54.591204 -285.474664) (xy 56.064658 -285.474664) (xy 56.069963 -285.475154) (xy 56.077538 -285.482578)
			(xy 56.07812 -285.487872) (xy 56.07812 -285.98241) (xy 58.678064 -285.98241) (xy 58.678064 -285.487872)
			(xy 58.678573 -285.482613) (xy 58.686013 -285.475173) (xy 58.691272 -285.474664) (xy 58.69178 -285.474664)
			(xy 60.164726 -285.474664) (xy 60.170039 -285.475109) (xy 60.17761 -285.482567) (xy 60.178188 -285.487872)
			(xy 60.178188 -285.98241) (xy 60.177659 -285.987769) (xy 60.170084 -285.995352) (xy 60.164726 -285.995872)
			(xy 58.691526 -285.995872) (xy 58.686097 -285.995504) (xy 58.67841 -285.987838) (xy 58.678064 -285.98241)
			(xy 56.07812 -285.98241) (xy 56.077823 -285.987856) (xy 56.070106 -285.995544) (xy 56.064658 -285.995872)
			(xy 54.591458 -285.995872) (xy 54.586091 -285.995379) (xy 54.578509 -285.987778) (xy 54.577996 -285.98241)
			(xy 52.63388 -285.98241) (xy 52.633386 -285.987711) (xy 52.625962 -285.99528) (xy 52.620672 -285.995872)
			(xy 52.104798 -285.995872) (xy 52.096987 -285.996173) (xy 52.082115 -286.000966) (xy 52.075588 -286.00527)
			(xy 52.054469 -286.019623) (xy 52.008744 -286.042348) (xy 51.96007 -286.057777) (xy 51.909603 -286.065543)
			(xy 51.884072 -286.065976) (xy 51.858541 -286.065551) (xy 51.808077 -286.057772) (xy 51.759405 -286.042339)
			(xy 51.713678 -286.019619) (xy 51.692556 -286.00527) (xy 51.686029 -286.00097) (xy 51.671156 -285.996191)
			(xy 51.663346 -285.995872) (xy 51.147472 -285.995872) (xy 51.142127 -285.995588) (xy 51.134586 -285.98801)
			(xy 51.134264 -285.982664) (xy 48.533791 -285.982664) (xy 48.533378 -285.987727) (xy 48.525913 -285.9953)
			(xy 48.520604 -285.995872) (xy 48.00473 -285.995872) (xy 47.99692 -285.996186) (xy 47.982048 -286.000971)
			(xy 47.97552 -286.00527) (xy 47.954392 -286.019609) (xy 47.90867 -286.042337) (xy 47.859999 -286.05777)
			(xy 47.809534 -286.065541) (xy 47.784004 -286.065976) (xy 47.758474 -286.065535) (xy 47.70801 -286.05776)
			(xy 47.659338 -286.042332) (xy 47.61361 -286.019617) (xy 47.592488 -286.00527) (xy 47.585954 -286.000982)
			(xy 47.571086 -285.996196) (xy 47.563278 -285.995872) (xy 47.047404 -285.995872) (xy 47.042064 -285.995567)
			(xy 47.03452 -285.988005) (xy 47.034196 -285.982664) (xy 45.090055 -285.982664) (xy 45.089558 -285.987771)
			(xy 45.081978 -285.995355) (xy 45.076618 -285.995872) (xy 44.560744 -285.995872) (xy 44.552934 -285.996192)
			(xy 44.538062 -286.000972) (xy 44.531534 -286.00527) (xy 44.51043 -286.019646) (xy 44.464699 -286.042366)
			(xy 44.416021 -286.057789) (xy 44.36555 -286.065547) (xy 44.340018 -286.065976) (xy 44.314488 -286.065528)
			(xy 44.264025 -286.057755) (xy 44.215352 -286.04233) (xy 44.169624 -286.019616) (xy 44.148502 -286.00527)
			(xy 44.141965 -286.000987) (xy 44.127099 -285.996198) (xy 44.119292 -285.995872) (xy 43.603418 -285.995872)
			(xy 43.597988 -285.99551) (xy 43.590301 -285.987839) (xy 43.589956 -285.98241) (xy 40.990012 -285.98241)
			(xy 40.989461 -285.987763) (xy 40.981902 -285.995345) (xy 40.97655 -285.995872) (xy 40.460676 -285.995872)
			(xy 40.452864 -285.996164) (xy 40.437992 -286.000964) (xy 40.431466 -286.00527) (xy 40.410353 -286.019632)
			(xy 40.364626 -286.042356) (xy 40.31595 -286.057782) (xy 40.265482 -286.065545) (xy 40.23995 -286.065976)
			(xy 40.214421 -286.065512) (xy 40.163958 -286.057744) (xy 40.115286 -286.042323) (xy 40.069557 -286.019614)
			(xy 40.048434 -286.00527) (xy 40.04189 -286.001) (xy 40.02703 -285.996202) (xy 40.019224 -285.995872)
			(xy 39.50335 -285.995872) (xy 39.497982 -285.995384) (xy 39.4904 -285.987779) (xy 39.489888 -285.98241)
			(xy 37.545772 -285.98241) (xy 37.545285 -285.987713) (xy 37.537856 -285.995282) (xy 37.532564 -285.995872)
			(xy 37.01669 -285.995872) (xy 37.008878 -285.996169) (xy 36.994007 -286.000965) (xy 36.98748 -286.00527)
			(xy 36.966363 -286.019626) (xy 36.920637 -286.042351) (xy 36.871963 -286.057779) (xy 36.821495 -286.065544)
			(xy 36.795964 -286.065976) (xy 36.770433 -286.065555) (xy 36.719969 -286.057774) (xy 36.671296 -286.04234)
			(xy 36.625569 -286.019619) (xy 36.604448 -286.00527) (xy 36.597923 -286.000967) (xy 36.583048 -285.99619)
			(xy 36.575238 -285.995872) (xy 36.059364 -285.995872) (xy 36.054088 -285.995425) (xy 36.046646 -285.987942)
			(xy 36.046156 -285.982664) (xy 33.445679 -285.982664) (xy 33.445189 -285.987705) (xy 33.43778 -285.995273)
			(xy 33.432496 -285.995872) (xy 32.916622 -285.995872) (xy 32.908811 -285.996183) (xy 32.89394 -286.00097)
			(xy 32.887412 -286.00527) (xy 32.866286 -286.019612) (xy 32.820564 -286.04234) (xy 32.771892 -286.057772)
			(xy 32.721427 -286.065541) (xy 32.695896 -286.065976) (xy 32.670366 -286.065539) (xy 32.619902 -286.057763)
			(xy 32.57123 -286.042334) (xy 32.525502 -286.019617) (xy 32.50438 -286.00527) (xy 32.497848 -286.000979)
			(xy 32.482979 -285.996195) (xy 32.47517 -285.995872) (xy 31.959296 -285.995872) (xy 31.953954 -285.995572)
			(xy 31.946412 -285.988007) (xy 31.946088 -285.982664) (xy 30.001949 -285.982664) (xy 30.001485 -285.987713)
			(xy 29.994056 -285.995282) (xy 29.988764 -285.995872) (xy 29.47289 -285.995872) (xy 29.465078 -285.996169)
			(xy 29.450207 -286.000965) (xy 29.44368 -286.00527) (xy 29.422563 -286.019626) (xy 29.376837 -286.042351)
			(xy 29.328163 -286.057779) (xy 29.277695 -286.065544) (xy 29.252164 -286.065976) (xy 29.226633 -286.065555)
			(xy 29.176169 -286.057774) (xy 29.127496 -286.04234) (xy 29.081769 -286.019619) (xy 29.060648 -286.00527)
			(xy 29.054123 -286.000967) (xy 29.039248 -285.99619) (xy 29.031438 -285.995872) (xy 28.515564 -285.995872)
			(xy 28.510288 -285.995425) (xy 28.502846 -285.987942) (xy 28.502356 -285.982664) (xy 25.901879 -285.982664)
			(xy 25.901389 -285.987705) (xy 25.89398 -285.995273) (xy 25.888696 -285.995872) (xy 25.372822 -285.995872)
			(xy 25.365011 -285.996183) (xy 25.35014 -286.00097) (xy 25.343612 -286.00527) (xy 25.322486 -286.019612)
			(xy 25.276764 -286.04234) (xy 25.228092 -286.057772) (xy 25.177627 -286.065541) (xy 25.152096 -286.065976)
			(xy 25.126566 -286.065539) (xy 25.076102 -286.057763) (xy 25.02743 -286.042334) (xy 24.981702 -286.019617)
			(xy 24.96058 -286.00527) (xy 24.954048 -286.000979) (xy 24.939179 -285.996195) (xy 24.93137 -285.995872)
			(xy 24.415496 -285.995872) (xy 24.410154 -285.995572) (xy 24.402612 -285.988007) (xy 24.402288 -285.982664)
			(xy 22.458148 -285.982664) (xy 22.457657 -285.987773) (xy 22.450073 -285.995357) (xy 22.44471 -285.995872)
			(xy 21.928836 -285.995872) (xy 21.921026 -285.996189) (xy 21.906154 -286.000971) (xy 21.899626 -286.00527)
			(xy 21.878496 -286.019606) (xy 21.832775 -286.042335) (xy 21.784104 -286.057769) (xy 21.73364 -286.06554)
			(xy 21.70811 -286.065976) (xy 21.68258 -286.065532) (xy 21.632117 -286.057758) (xy 21.583444 -286.042331)
			(xy 21.537716 -286.019616) (xy 21.516594 -286.00527) (xy 21.510059 -286.000984) (xy 21.495192 -285.996197)
			(xy 21.487384 -285.995872) (xy 20.97151 -285.995872) (xy 20.96615 -285.995344) (xy 20.958564 -285.987769)
			(xy 20.958048 -285.98241) (xy 18.358104 -285.98241) (xy 18.357561 -285.987765) (xy 18.349996 -285.995348)
			(xy 18.344642 -285.995872) (xy 17.828768 -285.995872) (xy 17.820959 -285.996202) (xy 17.806087 -286.000976)
			(xy 17.799558 -286.00527) (xy 17.778447 -286.019636) (xy 17.732719 -286.042358) (xy 17.684043 -286.057784)
			(xy 17.633574 -286.065545) (xy 17.608042 -286.065976) (xy 17.582513 -286.065516) (xy 17.53205 -286.057747)
			(xy 17.483377 -286.042325) (xy 17.437649 -286.019614) (xy 17.416526 -286.00527) (xy 17.409984 -286.000997)
			(xy 17.395122 -285.996201) (xy 17.387316 -285.995872) (xy 16.871442 -285.995872) (xy 16.866015 -285.995493)
			(xy 16.858327 -285.987835) (xy 16.85798 -285.98241) (xy 2.509012 -285.98241) (xy 2.509012 -286.2364)
			(xy 97.674895 -286.2364) (xy 97.679071 -286.186016) (xy 97.691482 -286.137006) (xy 97.71179 -286.090708)
			(xy 97.739443 -286.048384) (xy 97.773684 -286.011189) (xy 97.813581 -285.980137) (xy 97.858045 -285.956075)
			(xy 97.905862 -285.939661) (xy 97.95573 -285.93134) (xy 97.981008 -285.930848) (xy 98.921062 -285.930848)
			(xy 98.946344 -285.931318) (xy 98.996218 -285.939635) (xy 99.044043 -285.956048) (xy 99.088514 -285.98011)
			(xy 99.128418 -286.011163) (xy 99.162665 -286.048362) (xy 99.190323 -286.09069) (xy 99.210635 -286.136994)
			(xy 99.223049 -286.18601) (xy 99.227225 -286.2364) (xy 100.495124 -286.2364) (xy 100.499298 -286.186025)
			(xy 100.511706 -286.137023) (xy 100.53201 -286.090733) (xy 100.559656 -286.048415) (xy 100.593889 -286.011224)
			(xy 100.633777 -285.980174) (xy 100.678231 -285.956113) (xy 100.726038 -285.939697) (xy 100.775896 -285.931372)
			(xy 100.80117 -285.930848) (xy 101.741224 -285.930848) (xy 101.7665 -285.931352) (xy 101.816362 -285.939676)
			(xy 101.864173 -285.956093) (xy 101.908631 -285.980155) (xy 101.948522 -286.011207) (xy 101.982759 -286.0484)
			(xy 102.010407 -286.090721) (xy 102.030712 -286.137016) (xy 102.043121 -286.186021) (xy 102.047296 -286.2364)
			(xy 103.315024 -286.2364) (xy 103.319199 -286.186024) (xy 103.331607 -286.137022) (xy 103.351911 -286.09073)
			(xy 103.379558 -286.048412) (xy 103.413792 -286.011221) (xy 103.453681 -285.980171) (xy 103.498136 -285.956111)
			(xy 103.545945 -285.939695) (xy 103.595804 -285.931372) (xy 103.621078 -285.930848) (xy 104.561132 -285.930848)
			(xy 104.586407 -285.931352) (xy 104.636268 -285.939678) (xy 104.684079 -285.956095) (xy 104.728535 -285.980158)
			(xy 104.768425 -286.01121) (xy 104.802661 -286.048403) (xy 104.830308 -286.090724) (xy 104.850613 -286.137017)
			(xy 104.863021 -286.186022) (xy 104.867196 -286.2364) (xy 106.134924 -286.2364) (xy 106.139099 -286.186023)
			(xy 106.151508 -286.13702) (xy 106.171813 -286.090728) (xy 106.19946 -286.048409) (xy 106.233695 -286.011218)
			(xy 106.273585 -285.980169) (xy 106.318041 -285.956108) (xy 106.365851 -285.939693) (xy 106.415711 -285.931371)
			(xy 106.440986 -285.930848) (xy 107.38104 -285.930848) (xy 107.406315 -285.931353) (xy 107.456175 -285.939679)
			(xy 107.503984 -285.956098) (xy 107.54844 -285.980161) (xy 107.588328 -286.011213) (xy 107.622563 -286.048406)
			(xy 107.650209 -286.090726) (xy 107.670513 -286.137019) (xy 107.682921 -286.186022) (xy 107.687096 -286.2364)
			(xy 116.468595 -286.2364) (xy 116.472771 -286.186015) (xy 116.485183 -286.137004) (xy 116.505492 -286.090704)
			(xy 116.533146 -286.048379) (xy 116.56739 -286.011184) (xy 116.607288 -285.980132) (xy 116.651754 -285.956071)
			(xy 116.699574 -285.939658) (xy 116.749443 -285.931339) (xy 116.774722 -285.930848) (xy 117.714776 -285.930848)
			(xy 117.740057 -285.931319) (xy 117.789929 -285.939638) (xy 117.837753 -285.956052) (xy 117.882222 -285.980115)
			(xy 117.922123 -286.011168) (xy 117.956369 -286.048366) (xy 117.984025 -286.090694) (xy 118.004336 -286.136997)
			(xy 118.016749 -286.186011) (xy 118.020925 -286.2364) (xy 119.288495 -286.2364) (xy 119.292671 -286.186014)
			(xy 119.305083 -286.137002) (xy 119.325394 -286.090702) (xy 119.353048 -286.048377) (xy 119.387293 -286.011181)
			(xy 119.427193 -285.980129) (xy 119.47166 -285.956069) (xy 119.51948 -285.939656) (xy 119.56935 -285.931339)
			(xy 119.59463 -285.930848) (xy 120.534684 -285.930848) (xy 120.559964 -285.93132) (xy 120.609836 -285.93964)
			(xy 120.657658 -285.956055) (xy 120.702126 -285.980117) (xy 120.742026 -286.011171) (xy 120.776271 -286.048369)
			(xy 120.803926 -286.090696) (xy 120.824237 -286.136998) (xy 120.836649 -286.186012) (xy 120.840825 -286.2364)
			(xy 122.108724 -286.2364) (xy 122.112899 -286.186022) (xy 122.125308 -286.137019) (xy 122.145613 -286.090726)
			(xy 122.173261 -286.048407) (xy 122.207498 -286.011216) (xy 122.247388 -285.980167) (xy 122.291845 -285.956107)
			(xy 122.339656 -285.939692) (xy 122.389517 -285.931371) (xy 122.414792 -285.930848) (xy 123.354846 -285.930848)
			(xy 123.380121 -285.931354) (xy 123.42998 -285.93968) (xy 123.477788 -285.9561) (xy 123.522243 -285.980163)
			(xy 123.562131 -286.011215) (xy 123.596364 -286.048408) (xy 123.62401 -286.090727) (xy 123.644314 -286.13702)
			(xy 123.656722 -286.186023) (xy 123.660896 -286.2364) (xy 124.928625 -286.2364) (xy 124.932799 -286.186022)
			(xy 124.945209 -286.137017) (xy 124.965515 -286.090724) (xy 124.993163 -286.048405) (xy 125.027401 -286.011213)
			(xy 125.067293 -285.980164) (xy 125.111751 -285.956104) (xy 125.159563 -285.93969) (xy 125.209424 -285.93137)
			(xy 125.2347 -285.930848) (xy 126.174754 -285.930848) (xy 126.200036 -285.931317) (xy 126.249912 -285.939633)
			(xy 126.297738 -285.956046) (xy 126.34221 -285.980107) (xy 126.345496 -285.982664) (xy 163.678108 -285.982664)
			(xy 163.678108 -285.982156) (xy 163.678108 -285.487872) (xy 163.678578 -285.482602) (xy 163.686044 -285.47516)
			(xy 163.691316 -285.474664) (xy 165.164516 -285.474664) (xy 165.169774 -285.475181) (xy 165.177214 -285.482614)
			(xy 165.177724 -285.487872) (xy 165.177724 -285.98241) (xy 165.177703 -285.982664) (xy 167.778176 -285.982664)
			(xy 167.778176 -285.487872) (xy 167.778674 -285.48261) (xy 167.786121 -285.47517) (xy 167.791384 -285.474664)
			(xy 169.264584 -285.474664) (xy 169.269838 -285.475202) (xy 169.27728 -285.48262) (xy 169.277792 -285.487872)
			(xy 169.277792 -285.98241) (xy 171.221908 -285.98241) (xy 171.221908 -285.487872) (xy 171.222378 -285.482602)
			(xy 171.229844 -285.47516) (xy 171.235116 -285.474664) (xy 171.235624 -285.474664) (xy 171.751498 -285.474664)
			(xy 171.759309 -285.474356) (xy 171.77418 -285.469567) (xy 171.780708 -285.465266) (xy 171.801797 -285.450917)
			(xy 171.847458 -285.428186) (xy 171.896064 -285.412727) (xy 171.946467 -285.404904) (xy 171.997473 -285.404904)
			(xy 172.047876 -285.412727) (xy 172.096482 -285.428186) (xy 172.142143 -285.450917) (xy 172.163232 -285.465266)
			(xy 172.169759 -285.469565) (xy 172.184632 -285.474344) (xy 172.192442 -285.474664) (xy 172.70857 -285.474664)
			(xy 172.713876 -285.475146) (xy 172.72145 -285.482576) (xy 172.722032 -285.487872) (xy 172.722032 -285.98241)
			(xy 175.321976 -285.98241) (xy 175.321976 -285.487872) (xy 175.322474 -285.48261) (xy 175.329921 -285.47517)
			(xy 175.335184 -285.474664) (xy 175.335692 -285.474664) (xy 175.851566 -285.474664) (xy 175.859375 -285.474342)
			(xy 175.874247 -285.469562) (xy 175.880776 -285.465266) (xy 175.901865 -285.450917) (xy 175.947526 -285.428186)
			(xy 175.996132 -285.412727) (xy 176.046535 -285.404904) (xy 176.097541 -285.404904) (xy 176.147944 -285.412727)
			(xy 176.19655 -285.428186) (xy 176.242211 -285.450917) (xy 176.2633 -285.465266) (xy 176.269834 -285.469553)
			(xy 176.284702 -285.474339) (xy 176.29251 -285.474664) (xy 176.808638 -285.474664) (xy 176.813952 -285.475101)
			(xy 176.821523 -285.482565) (xy 176.8221 -285.487872) (xy 176.8221 -285.98241) (xy 176.822074 -285.982664)
			(xy 178.766216 -285.982664) (xy 178.766216 -285.982156) (xy 178.766216 -285.487872) (xy 178.766678 -285.4826)
			(xy 178.77415 -285.475158) (xy 178.779424 -285.474664) (xy 179.295552 -285.474664) (xy 179.303361 -285.474336)
			(xy 179.318233 -285.46956) (xy 179.324762 -285.465266) (xy 179.345851 -285.450917) (xy 179.391512 -285.428186)
			(xy 179.440118 -285.412727) (xy 179.490521 -285.404904) (xy 179.541527 -285.404904) (xy 179.59193 -285.412727)
			(xy 179.640536 -285.428186) (xy 179.686197 -285.450917) (xy 179.707286 -285.465266) (xy 179.713823 -285.469547)
			(xy 179.728689 -285.474337) (xy 179.736496 -285.474664) (xy 180.252624 -285.474664) (xy 180.257883 -285.475176)
			(xy 180.265322 -285.482613) (xy 180.265832 -285.487872) (xy 180.265832 -285.98241) (xy 180.26581 -285.982664)
			(xy 182.866284 -285.982664) (xy 182.866284 -285.982156) (xy 182.866284 -285.487872) (xy 182.866775 -285.482608)
			(xy 182.874227 -285.475167) (xy 182.879492 -285.474664) (xy 183.39562 -285.474664) (xy 183.403432 -285.474365)
			(xy 183.418303 -285.46957) (xy 183.42483 -285.465266) (xy 183.445919 -285.450917) (xy 183.49158 -285.428186)
			(xy 183.540186 -285.412727) (xy 183.590589 -285.404904) (xy 183.641595 -285.404904) (xy 183.691998 -285.412727)
			(xy 183.740604 -285.428186) (xy 183.786265 -285.450917) (xy 183.807354 -285.465266) (xy 183.813876 -285.469573)
			(xy 183.828753 -285.474347) (xy 183.836564 -285.474664) (xy 184.352692 -285.474664) (xy 184.357947 -285.475197)
			(xy 184.365389 -285.482618) (xy 184.3659 -285.487872) (xy 184.3659 -285.98241) (xy 186.310016 -285.98241)
			(xy 186.310016 -285.487872) (xy 186.310478 -285.4826) (xy 186.31795 -285.475158) (xy 186.323224 -285.474664)
			(xy 186.323732 -285.474664) (xy 186.839606 -285.474664) (xy 186.847417 -285.474359) (xy 186.862289 -285.469568)
			(xy 186.868816 -285.465266) (xy 186.889905 -285.450917) (xy 186.935566 -285.428186) (xy 186.984172 -285.412727)
			(xy 187.034575 -285.404904) (xy 187.085581 -285.404904) (xy 187.135984 -285.412727) (xy 187.18459 -285.428186)
			(xy 187.230251 -285.450917) (xy 187.25134 -285.465266) (xy 187.257865 -285.469568) (xy 187.27274 -285.474345)
			(xy 187.28055 -285.474664) (xy 187.796678 -285.474664) (xy 187.801985 -285.475141) (xy 187.809559 -285.482575)
			(xy 187.81014 -285.487872) (xy 187.81014 -285.98241) (xy 190.410084 -285.98241) (xy 190.410084 -285.487872)
			(xy 190.410575 -285.482608) (xy 190.418027 -285.475167) (xy 190.423292 -285.474664) (xy 190.4238 -285.474664)
			(xy 190.939674 -285.474664) (xy 190.947484 -285.474345) (xy 190.962355 -285.469563) (xy 190.968884 -285.465266)
			(xy 190.989973 -285.450917) (xy 191.035634 -285.428186) (xy 191.08424 -285.412727) (xy 191.134643 -285.404904)
			(xy 191.185649 -285.404904) (xy 191.236052 -285.412727) (xy 191.284658 -285.428186) (xy 191.330319 -285.450917)
			(xy 191.351408 -285.465266) (xy 191.357941 -285.469556) (xy 191.37281 -285.47434) (xy 191.380618 -285.474664)
			(xy 191.896746 -285.474664) (xy 191.902049 -285.475162) (xy 191.909625 -285.48258) (xy 191.910208 -285.487872)
			(xy 191.910208 -285.98241) (xy 191.910182 -285.982664) (xy 193.854324 -285.982664) (xy 193.854324 -285.982156)
			(xy 193.854324 -285.487872) (xy 193.854611 -285.482528) (xy 193.862187 -285.474987) (xy 193.867532 -285.474664)
			(xy 194.38366 -285.474664) (xy 194.391469 -285.474339) (xy 194.406341 -285.469561) (xy 194.41287 -285.465266)
			(xy 194.433959 -285.450917) (xy 194.47962 -285.428186) (xy 194.528226 -285.412727) (xy 194.578629 -285.404904)
			(xy 194.629635 -285.404904) (xy 194.680038 -285.412727) (xy 194.728644 -285.428186) (xy 194.774305 -285.450917)
			(xy 194.795394 -285.465266) (xy 194.80193 -285.46955) (xy 194.816796 -285.474338) (xy 194.824604 -285.474664)
			(xy 195.340732 -285.474664) (xy 195.345992 -285.475171) (xy 195.353431 -285.482612) (xy 195.35394 -285.487872)
			(xy 195.35394 -285.98241) (xy 195.353918 -285.982664) (xy 197.954392 -285.982664) (xy 197.954392 -285.982156)
			(xy 197.954392 -285.487872) (xy 197.954876 -285.482606) (xy 197.962333 -285.475165) (xy 197.9676 -285.474664)
			(xy 198.483728 -285.474664) (xy 198.49154 -285.474368) (xy 198.506411 -285.469571) (xy 198.512938 -285.465266)
			(xy 198.534027 -285.450917) (xy 198.579688 -285.428186) (xy 198.628294 -285.412727) (xy 198.678697 -285.404904)
			(xy 198.729703 -285.404904) (xy 198.780106 -285.412727) (xy 198.828712 -285.428186) (xy 198.874373 -285.450917)
			(xy 198.895462 -285.465266) (xy 198.902005 -285.469538) (xy 198.916866 -285.474333) (xy 198.924672 -285.474664)
			(xy 199.4408 -285.474664) (xy 199.446056 -285.475192) (xy 199.453497 -285.482617) (xy 199.454008 -285.487872)
			(xy 199.454008 -285.98241) (xy 199.453983 -285.982664) (xy 201.398124 -285.982664) (xy 201.398124 -285.982156)
			(xy 201.398124 -285.487872) (xy 201.398411 -285.482528) (xy 201.405987 -285.474987) (xy 201.411332 -285.474664)
			(xy 201.92746 -285.474664) (xy 201.935269 -285.474339) (xy 201.950141 -285.469561) (xy 201.95667 -285.465266)
			(xy 201.977759 -285.450917) (xy 202.02342 -285.428186) (xy 202.072026 -285.412727) (xy 202.122429 -285.404904)
			(xy 202.173435 -285.404904) (xy 202.223838 -285.412727) (xy 202.272444 -285.428186) (xy 202.318105 -285.450917)
			(xy 202.339194 -285.465266) (xy 202.34573 -285.46955) (xy 202.360596 -285.474338) (xy 202.368404 -285.474664)
			(xy 202.884532 -285.474664) (xy 202.889792 -285.475171) (xy 202.897231 -285.482612) (xy 202.89774 -285.487872)
			(xy 202.89774 -285.98241) (xy 202.897718 -285.982664) (xy 205.498192 -285.982664) (xy 205.498192 -285.982156)
			(xy 205.498192 -285.487872) (xy 205.498676 -285.482606) (xy 205.506133 -285.475165) (xy 205.5114 -285.474664)
			(xy 206.027528 -285.474664) (xy 206.03534 -285.474368) (xy 206.050211 -285.469571) (xy 206.056738 -285.465266)
			(xy 206.077827 -285.450917) (xy 206.123488 -285.428186) (xy 206.172094 -285.412727) (xy 206.222497 -285.404904)
			(xy 206.273503 -285.404904) (xy 206.323906 -285.412727) (xy 206.372512 -285.428186) (xy 206.418173 -285.450917)
			(xy 206.439262 -285.465266) (xy 206.445805 -285.469538) (xy 206.460666 -285.474333) (xy 206.468472 -285.474664)
			(xy 206.9846 -285.474664) (xy 206.989856 -285.475192) (xy 206.997297 -285.482617) (xy 206.997808 -285.487872)
			(xy 206.997808 -285.982156) (xy 264.798048 -285.982156) (xy 264.798048 -285.487618) (xy 264.798392 -285.482183)
			(xy 264.806075 -285.474495) (xy 264.81151 -285.474156) (xy 265.327638 -285.474156) (xy 265.335446 -285.473823)
			(xy 265.350318 -285.469051) (xy 265.356848 -285.464758) (xy 265.377937 -285.450409) (xy 265.423598 -285.427678)
			(xy 265.472204 -285.412219) (xy 265.522607 -285.404396) (xy 265.573613 -285.404396) (xy 265.624016 -285.412219)
			(xy 265.672622 -285.427678) (xy 265.718283 -285.450409) (xy 265.739372 -285.464758) (xy 265.745913 -285.469033)
			(xy 265.760776 -285.473827) (xy 265.768582 -285.474156) (xy 266.28471 -285.474156) (xy 266.290151 -285.474474)
			(xy 266.297837 -285.482177) (xy 266.298172 -285.487618) (xy 266.298172 -285.982156) (xy 268.898116 -285.982156)
			(xy 268.898116 -285.487618) (xy 268.89866 -285.482261) (xy 268.906223 -285.474676) (xy 268.911578 -285.474156)
			(xy 269.427706 -285.474156) (xy 269.435517 -285.473852) (xy 269.450389 -285.46906) (xy 269.456916 -285.464758)
			(xy 269.478005 -285.450409) (xy 269.523666 -285.427678) (xy 269.572272 -285.412219) (xy 269.622675 -285.404396)
			(xy 269.673681 -285.404396) (xy 269.724084 -285.412219) (xy 269.77269 -285.427678) (xy 269.818351 -285.450409)
			(xy 269.83944 -285.464758) (xy 269.845966 -285.469059) (xy 269.86084 -285.473837) (xy 269.86865 -285.474156)
			(xy 270.384778 -285.474156) (xy 270.390214 -285.474496) (xy 270.397902 -285.482182) (xy 270.39824 -285.487618)
			(xy 270.39824 -285.982156) (xy 272.342356 -285.982156) (xy 272.342356 -285.487618) (xy 272.342837 -285.482312)
			(xy 272.350268 -285.474739) (xy 272.355564 -285.474156) (xy 272.871692 -285.474156) (xy 272.879503 -285.473847)
			(xy 272.894374 -285.469059) (xy 272.900902 -285.464758) (xy 272.921991 -285.450409) (xy 272.967652 -285.427678)
			(xy 273.016258 -285.412219) (xy 273.066661 -285.404396) (xy 273.117667 -285.404396) (xy 273.16807 -285.412219)
			(xy 273.216676 -285.427678) (xy 273.262337 -285.450409) (xy 273.283426 -285.464758) (xy 273.289955 -285.469054)
			(xy 273.304827 -285.473835) (xy 273.312636 -285.474156) (xy 273.828764 -285.474156) (xy 273.834014 -285.474715)
			(xy 273.841456 -285.482117) (xy 273.841972 -285.487364) (xy 273.841972 -285.487872) (xy 273.841972 -285.982156)
			(xy 276.442424 -285.982156) (xy 276.442424 -285.487618) (xy 276.442933 -285.48232) (xy 276.450345 -285.474748)
			(xy 276.455632 -285.474156) (xy 276.97176 -285.474156) (xy 276.979569 -285.473833) (xy 276.994441 -285.469054)
			(xy 277.00097 -285.464758) (xy 277.022059 -285.450409) (xy 277.06772 -285.427678) (xy 277.116326 -285.412219)
			(xy 277.166729 -285.404396) (xy 277.217735 -285.404396) (xy 277.268138 -285.412219) (xy 277.316744 -285.427678)
			(xy 277.362405 -285.450409) (xy 277.383494 -285.464758) (xy 277.39003 -285.469042) (xy 277.404896 -285.47383)
			(xy 277.412704 -285.474156) (xy 277.928832 -285.474156) (xy 277.93409 -285.47467) (xy 277.941529 -285.482106)
			(xy 277.94204 -285.487364) (xy 277.94204 -285.487872) (xy 277.94204 -285.982156) (xy 279.886156 -285.982156)
			(xy 279.886156 -285.487618) (xy 279.886637 -285.482312) (xy 279.894068 -285.474739) (xy 279.899364 -285.474156)
			(xy 280.415492 -285.474156) (xy 280.423303 -285.473847) (xy 280.438174 -285.469059) (xy 280.444702 -285.464758)
			(xy 280.465791 -285.450409) (xy 280.511452 -285.427678) (xy 280.560058 -285.412219) (xy 280.610461 -285.404396)
			(xy 280.661467 -285.404396) (xy 280.71187 -285.412219) (xy 280.760476 -285.427678) (xy 280.806137 -285.450409)
			(xy 280.827226 -285.464758) (xy 280.833755 -285.469054) (xy 280.848627 -285.473835) (xy 280.856436 -285.474156)
			(xy 281.372564 -285.474156) (xy 281.377814 -285.474715) (xy 281.385256 -285.482117) (xy 281.385772 -285.487364)
			(xy 281.385772 -285.487872) (xy 281.385772 -285.982156) (xy 283.986224 -285.982156) (xy 283.986224 -285.487618)
			(xy 283.986733 -285.48232) (xy 283.994145 -285.474748) (xy 283.999432 -285.474156) (xy 284.51556 -285.474156)
			(xy 284.523369 -285.473833) (xy 284.538241 -285.469054) (xy 284.54477 -285.464758) (xy 284.565859 -285.450409)
			(xy 284.61152 -285.427678) (xy 284.660126 -285.412219) (xy 284.710529 -285.404396) (xy 284.761535 -285.404396)
			(xy 284.811938 -285.412219) (xy 284.860544 -285.427678) (xy 284.906205 -285.450409) (xy 284.927294 -285.464758)
			(xy 284.93383 -285.469042) (xy 284.948696 -285.47383) (xy 284.956504 -285.474156) (xy 285.472632 -285.474156)
			(xy 285.47789 -285.47467) (xy 285.485329 -285.482106) (xy 285.48584 -285.487364) (xy 285.48584 -285.487872)
			(xy 285.48584 -285.982156) (xy 287.429956 -285.982156) (xy 287.429956 -285.487618) (xy 287.430293 -285.482181)
			(xy 287.437981 -285.474493) (xy 287.443418 -285.474156) (xy 287.959546 -285.474156) (xy 287.967355 -285.473827)
			(xy 287.982227 -285.469052) (xy 287.988756 -285.464758) (xy 288.009845 -285.450409) (xy 288.055506 -285.427678)
			(xy 288.104112 -285.412219) (xy 288.154515 -285.404396) (xy 288.205521 -285.404396) (xy 288.255924 -285.412219)
			(xy 288.30453 -285.427678) (xy 288.350191 -285.450409) (xy 288.37128 -285.464758) (xy 288.377819 -285.469036)
			(xy 288.392683 -285.473828) (xy 288.40049 -285.474156) (xy 288.916618 -285.474156) (xy 288.921989 -285.47464)
			(xy 288.929574 -285.482246) (xy 288.93008 -285.487618) (xy 288.93008 -285.982156) (xy 291.530024 -285.982156)
			(xy 291.530024 -285.487618) (xy 291.53039 -285.482189) (xy 291.538058 -285.474503) (xy 291.543486 -285.474156)
			(xy 292.059614 -285.474156) (xy 292.067425 -285.473856) (xy 292.082297 -285.469061) (xy 292.088824 -285.464758)
			(xy 292.109913 -285.450409) (xy 292.155574 -285.427678) (xy 292.20418 -285.412219) (xy 292.254583 -285.404396)
			(xy 292.305589 -285.404396) (xy 292.355992 -285.412219) (xy 292.404598 -285.427678) (xy 292.450259 -285.450409)
			(xy 292.471348 -285.464758) (xy 292.477872 -285.469062) (xy 292.492748 -285.473838) (xy 292.500558 -285.474156)
			(xy 293.016686 -285.474156) (xy 293.022123 -285.47449) (xy 293.029811 -285.482181) (xy 293.030148 -285.487618)
			(xy 293.030148 -285.982156) (xy 294.974264 -285.982156) (xy 294.974264 -285.487618) (xy 294.974738 -285.48231)
			(xy 294.982174 -285.474737) (xy 294.987472 -285.474156) (xy 295.5036 -285.474156) (xy 295.511411 -285.47385)
			(xy 295.526283 -285.46906) (xy 295.53281 -285.464758) (xy 295.553899 -285.450409) (xy 295.59956 -285.427678)
			(xy 295.648166 -285.412219) (xy 295.698569 -285.404396) (xy 295.749575 -285.404396) (xy 295.799978 -285.412219)
			(xy 295.848584 -285.427678) (xy 295.894245 -285.450409) (xy 295.915334 -285.464758) (xy 295.921861 -285.469057)
			(xy 295.936734 -285.473836) (xy 295.944544 -285.474156) (xy 296.460672 -285.474156) (xy 296.465923 -285.47471)
			(xy 296.473365 -285.482116) (xy 296.47388 -285.487364) (xy 296.47388 -285.487872) (xy 296.47388 -285.982156)
			(xy 299.074332 -285.982156) (xy 299.074332 -285.487618) (xy 299.074834 -285.482318) (xy 299.082251 -285.474746)
			(xy 299.08754 -285.474156) (xy 299.603668 -285.474156) (xy 299.611478 -285.473836) (xy 299.626349 -285.469055)
			(xy 299.632878 -285.464758) (xy 299.653967 -285.450409) (xy 299.699628 -285.427678) (xy 299.748234 -285.412219)
			(xy 299.798637 -285.404396) (xy 299.849643 -285.404396) (xy 299.900046 -285.412219) (xy 299.94369 -285.4261)
			(xy 356.425064 -285.4261) (xy 356.429238 -285.375732) (xy 356.441644 -285.326738) (xy 356.461944 -285.280454)
			(xy 356.489585 -285.238142) (xy 356.523813 -285.200956) (xy 356.563694 -285.16991) (xy 356.608141 -285.145852)
			(xy 356.655942 -285.129437) (xy 356.705792 -285.121113) (xy 356.731062 -285.120588) (xy 357.671116 -285.120588)
			(xy 357.696396 -285.121011) (xy 357.746265 -285.129335) (xy 357.794084 -285.145754) (xy 357.838549 -285.169819)
			(xy 357.878446 -285.200875) (xy 357.912688 -285.238073) (xy 357.940341 -285.2804) (xy 357.960649 -285.326701)
			(xy 357.97306 -285.375713) (xy 357.977236 -285.4261) (xy 362.058764 -285.4261) (xy 362.062938 -285.37573)
			(xy 362.075345 -285.326734) (xy 362.095647 -285.280448) (xy 362.12329 -285.238135) (xy 362.157521 -285.200949)
			(xy 362.197405 -285.169904) (xy 362.241855 -285.145846) (xy 362.289658 -285.129433) (xy 362.339511 -285.121111)
			(xy 362.364782 -285.120588) (xy 363.304836 -285.120588) (xy 363.330115 -285.121013) (xy 363.379981 -285.12934)
			(xy 363.388519 -285.132272) (xy 415.718244 -285.132272) (xy 415.718244 -284.637734) (xy 415.718746 -284.632433)
			(xy 415.726162 -284.62486) (xy 415.731452 -284.624272) (xy 417.204652 -284.624272) (xy 417.209973 -284.624657)
			(xy 417.217515 -284.632161) (xy 417.21786 -284.63748) (xy 417.21786 -285.132272) (xy 423.262044 -285.132272)
			(xy 423.262044 -284.637734) (xy 423.262403 -284.632302) (xy 423.270075 -284.624614) (xy 423.275506 -284.624272)
			(xy 423.791634 -284.624272) (xy 423.799442 -284.623935) (xy 423.814314 -284.619165) (xy 423.820844 -284.614874)
			(xy 423.841933 -284.600525) (xy 423.887594 -284.577794) (xy 423.9362 -284.562335) (xy 423.986603 -284.554512)
			(xy 424.037609 -284.554512) (xy 424.088012 -284.562335) (xy 424.136618 -284.577794) (xy 424.182279 -284.600525)
			(xy 424.203368 -284.614874) (xy 424.209909 -284.619149) (xy 424.224772 -284.623942) (xy 424.232578 -284.624272)
			(xy 424.748706 -284.624272) (xy 424.75415 -284.624579) (xy 424.761837 -284.632289) (xy 424.762168 -284.637734)
			(xy 424.762168 -285.132272) (xy 430.806352 -285.132272) (xy 430.806352 -284.637734) (xy 430.806847 -284.632431)
			(xy 430.814268 -284.624857) (xy 430.81956 -284.624272) (xy 431.335688 -284.624272) (xy 431.343498 -284.623958)
			(xy 431.35837 -284.619173) (xy 431.364898 -284.614874) (xy 431.385987 -284.600525) (xy 431.431648 -284.577794)
			(xy 431.480254 -284.562335) (xy 431.530657 -284.554512) (xy 431.581663 -284.554512) (xy 431.632066 -284.562335)
			(xy 431.680672 -284.577794) (xy 431.726333 -284.600525) (xy 431.747422 -284.614874) (xy 431.753951 -284.61917)
			(xy 431.768823 -284.62395) (xy 431.776632 -284.624272) (xy 432.29276 -284.624272) (xy 432.298082 -284.624652)
			(xy 432.305624 -284.63216) (xy 432.305968 -284.63748) (xy 432.305968 -284.637988) (xy 432.305968 -285.132272)
			(xy 438.350152 -285.132272) (xy 438.350152 -284.637734) (xy 438.350503 -284.6323) (xy 438.358181 -284.624612)
			(xy 438.363614 -284.624272) (xy 438.879742 -284.624272) (xy 438.88755 -284.623938) (xy 438.902422 -284.619166)
			(xy 438.908952 -284.614874) (xy 438.930041 -284.600525) (xy 438.975702 -284.577794) (xy 439.024308 -284.562335)
			(xy 439.074711 -284.554512) (xy 439.125717 -284.554512) (xy 439.17612 -284.562335) (xy 439.224726 -284.577794)
			(xy 439.270387 -284.600525) (xy 439.291476 -284.614874) (xy 439.298015 -284.619152) (xy 439.312879 -284.623944)
			(xy 439.320686 -284.624272) (xy 439.836814 -284.624272) (xy 439.842259 -284.624573) (xy 439.849946 -284.632288)
			(xy 439.850276 -284.637734) (xy 439.850276 -285.132272) (xy 445.89446 -285.132272) (xy 445.89446 -284.637734)
			(xy 445.894948 -284.632429) (xy 445.902374 -284.624855) (xy 445.907668 -284.624272) (xy 446.423796 -284.624272)
			(xy 446.431606 -284.623961) (xy 446.446478 -284.619174) (xy 446.453006 -284.614874) (xy 446.474095 -284.600525)
			(xy 446.519756 -284.577794) (xy 446.568362 -284.562335) (xy 446.618765 -284.554512) (xy 446.669771 -284.554512)
			(xy 446.720174 -284.562335) (xy 446.76878 -284.577794) (xy 446.814441 -284.600525) (xy 446.83553 -284.614874)
			(xy 446.842057 -284.619173) (xy 446.85693 -284.623951) (xy 446.86474 -284.624272) (xy 447.380868 -284.624272)
			(xy 447.386191 -284.624646) (xy 447.393733 -284.632158) (xy 447.394076 -284.63748) (xy 447.394076 -284.637988)
			(xy 447.394076 -285.132272) (xy 453.43826 -285.132272) (xy 453.43826 -284.637734) (xy 453.438748 -284.632429)
			(xy 453.446174 -284.624855) (xy 453.451468 -284.624272) (xy 453.967596 -284.624272) (xy 453.975406 -284.623961)
			(xy 453.990278 -284.619174) (xy 453.996806 -284.614874) (xy 454.017895 -284.600525) (xy 454.063556 -284.577794)
			(xy 454.112162 -284.562335) (xy 454.162565 -284.554512) (xy 454.213571 -284.554512) (xy 454.263974 -284.562335)
			(xy 454.31258 -284.577794) (xy 454.358241 -284.600525) (xy 454.37933 -284.614874) (xy 454.385857 -284.619173)
			(xy 454.40073 -284.623951) (xy 454.40854 -284.624272) (xy 454.924668 -284.624272) (xy 454.929991 -284.624646)
			(xy 454.937533 -284.632158) (xy 454.937876 -284.63748) (xy 454.937876 -284.637988) (xy 454.937876 -285.132272)
			(xy 454.937551 -285.137608) (xy 454.930004 -285.145153) (xy 454.924668 -285.14548) (xy 454.408794 -285.14548)
			(xy 454.400919 -285.145768) (xy 454.385915 -285.150551) (xy 454.37933 -285.154878) (xy 454.358265 -285.169288)
			(xy 454.312615 -285.192112) (xy 454.264006 -285.207664) (xy 454.213586 -285.215577) (xy 454.188068 -285.216092)
			(xy 454.162548 -285.215587) (xy 454.112122 -285.207697) (xy 454.06351 -285.192142) (xy 454.017871 -285.169291)
			(xy 453.996806 -285.154878) (xy 453.99021 -285.15057) (xy 453.975214 -285.145777) (xy 453.967342 -285.14548)
			(xy 453.451468 -285.14548) (xy 453.446195 -285.145024) (xy 453.438752 -285.137548) (xy 453.43826 -285.132272)
			(xy 447.394076 -285.132272) (xy 447.393751 -285.137608) (xy 447.386204 -285.145153) (xy 447.380868 -285.14548)
			(xy 446.864994 -285.14548) (xy 446.857119 -285.145768) (xy 446.842115 -285.150551) (xy 446.83553 -285.154878)
			(xy 446.814465 -285.169288) (xy 446.768815 -285.192112) (xy 446.720206 -285.207664) (xy 446.669786 -285.215577)
			(xy 446.644268 -285.216092) (xy 446.618748 -285.215587) (xy 446.568322 -285.207697) (xy 446.51971 -285.192142)
			(xy 446.474071 -285.169291) (xy 446.453006 -285.154878) (xy 446.44641 -285.15057) (xy 446.431414 -285.145777)
			(xy 446.423542 -285.14548) (xy 445.907668 -285.14548) (xy 445.902395 -285.145024) (xy 445.894952 -285.137548)
			(xy 445.89446 -285.132272) (xy 439.850276 -285.132272) (xy 439.849951 -285.137608) (xy 439.842404 -285.145153)
			(xy 439.837068 -285.14548) (xy 439.83656 -285.14548) (xy 439.32094 -285.14548) (xy 439.313063 -285.145745)
			(xy 439.298059 -285.150544) (xy 439.291476 -285.154878) (xy 439.270398 -285.169268) (xy 439.224753 -285.192096)
			(xy 439.176147 -285.207654) (xy 439.125731 -285.215574) (xy 439.100214 -285.216092) (xy 439.074693 -285.215614)
			(xy 439.024266 -285.207716) (xy 438.975654 -285.192153) (xy 438.930016 -285.169295) (xy 438.908952 -285.154878)
			(xy 438.902368 -285.150549) (xy 438.887362 -285.145769) (xy 438.879488 -285.14548) (xy 438.363614 -285.14548)
			(xy 438.358316 -285.14497) (xy 438.350746 -285.137558) (xy 438.350152 -285.132272) (xy 432.305968 -285.132272)
			(xy 432.305651 -285.13761) (xy 432.298099 -285.145155) (xy 432.29276 -285.14548) (xy 431.776886 -285.14548)
			(xy 431.769011 -285.145764) (xy 431.754007 -285.15055) (xy 431.747422 -285.154878) (xy 431.726359 -285.169292)
			(xy 431.680709 -285.192114) (xy 431.632098 -285.207666) (xy 431.581678 -285.215578) (xy 431.55616 -285.216092)
			(xy 431.53064 -285.215591) (xy 431.480214 -285.2077) (xy 431.431602 -285.192143) (xy 431.385963 -285.169292)
			(xy 431.364898 -285.154878) (xy 431.358304 -285.150567) (xy 431.343306 -285.145776) (xy 431.335434 -285.14548)
			(xy 430.81956 -285.14548) (xy 430.814286 -285.145029) (xy 430.806844 -285.137549) (xy 430.806352 -285.132272)
			(xy 424.762168 -285.132272) (xy 424.761851 -285.13761) (xy 424.754299 -285.145155) (xy 424.74896 -285.14548)
			(xy 424.748452 -285.14548) (xy 424.232832 -285.14548) (xy 424.224955 -285.145741) (xy 424.209951 -285.150543)
			(xy 424.203368 -285.154878) (xy 424.182292 -285.169272) (xy 424.136646 -285.192099) (xy 424.08804 -285.207656)
			(xy 424.037623 -285.215575) (xy 424.012106 -285.216092) (xy 423.986585 -285.215618) (xy 423.936158 -285.207719)
			(xy 423.887546 -285.192154) (xy 423.841908 -285.169295) (xy 423.820844 -285.154878) (xy 423.814262 -285.150546)
			(xy 423.799255 -285.145768) (xy 423.79138 -285.14548) (xy 423.275506 -285.14548) (xy 423.270207 -285.144975)
			(xy 423.262637 -285.13756) (xy 423.262044 -285.132272) (xy 417.21786 -285.132272) (xy 417.21755 -285.137612)
			(xy 417.209993 -285.145158) (xy 417.204652 -285.14548) (xy 415.731452 -285.14548) (xy 415.726177 -285.145034)
			(xy 415.718735 -285.13755) (xy 415.718244 -285.132272) (xy 363.388519 -285.132272) (xy 363.427798 -285.14576)
			(xy 363.472259 -285.169826) (xy 363.512154 -285.200882) (xy 363.546393 -285.23808) (xy 363.574044 -285.280406)
			(xy 363.594351 -285.326705) (xy 363.606761 -285.375716) (xy 363.610936 -285.4261) (xy 363.606761 -285.476485)
			(xy 363.594351 -285.525495) (xy 363.574044 -285.571794) (xy 363.546393 -285.61412) (xy 363.512154 -285.651318)
			(xy 363.472259 -285.682374) (xy 363.427798 -285.70644) (xy 363.379981 -285.72286) (xy 363.330115 -285.731187)
			(xy 363.304836 -285.731712) (xy 362.364782 -285.731712) (xy 362.339511 -285.731089) (xy 362.289658 -285.722767)
			(xy 362.241855 -285.706354) (xy 362.197405 -285.682296) (xy 362.157521 -285.651251) (xy 362.12329 -285.614065)
			(xy 362.095647 -285.571752) (xy 362.075345 -285.525466) (xy 362.062938 -285.47647) (xy 362.058764 -285.4261)
			(xy 357.977236 -285.4261) (xy 357.97306 -285.476487) (xy 357.960649 -285.525499) (xy 357.940341 -285.5718)
			(xy 357.912688 -285.614127) (xy 357.878446 -285.651325) (xy 357.838549 -285.682381) (xy 357.794084 -285.706446)
			(xy 357.746265 -285.722865) (xy 357.696396 -285.731189) (xy 357.671116 -285.731712) (xy 356.731062 -285.731712)
			(xy 356.705792 -285.731087) (xy 356.655942 -285.722763) (xy 356.608141 -285.706348) (xy 356.563694 -285.68229)
			(xy 356.523813 -285.651244) (xy 356.489585 -285.614058) (xy 356.461944 -285.571746) (xy 356.441644 -285.525462)
			(xy 356.429238 -285.476468) (xy 356.425064 -285.4261) (xy 299.94369 -285.4261) (xy 299.948652 -285.427678)
			(xy 299.994313 -285.450409) (xy 300.015402 -285.464758) (xy 300.021936 -285.469045) (xy 300.036804 -285.473831)
			(xy 300.044612 -285.474156) (xy 300.56074 -285.474156) (xy 300.565999 -285.474664) (xy 300.573437 -285.482105)
			(xy 300.573948 -285.487364) (xy 300.573948 -285.487872) (xy 300.573948 -285.982156) (xy 302.518064 -285.982156)
			(xy 302.518064 -285.487618) (xy 302.518394 -285.482179) (xy 302.526087 -285.474491) (xy 302.531526 -285.474156)
			(xy 304.004726 -285.474156) (xy 304.010097 -285.474635) (xy 304.017682 -285.482245) (xy 304.018188 -285.487618)
			(xy 304.018188 -285.982156) (xy 306.618132 -285.982156) (xy 306.618132 -285.487618) (xy 306.618491 -285.482187)
			(xy 306.626164 -285.4745) (xy 306.631594 -285.474156) (xy 308.104794 -285.474156) (xy 308.110232 -285.474485)
			(xy 308.11792 -285.482179) (xy 308.118256 -285.487618) (xy 308.118256 -285.982156) (xy 308.117681 -285.987402)
			(xy 308.11029 -285.994844) (xy 308.105048 -285.995364) (xy 308.10454 -285.995364) (xy 306.631594 -285.995364)
			(xy 306.62629 -285.994881) (xy 306.618719 -285.98745) (xy 306.618132 -285.982156) (xy 304.018188 -285.982156)
			(xy 304.017842 -285.987487) (xy 304.010311 -285.995032) (xy 304.00498 -285.995364) (xy 302.531526 -285.995364)
			(xy 302.526226 -285.99486) (xy 302.518654 -285.987445) (xy 302.518064 -285.982156) (xy 300.573948 -285.982156)
			(xy 300.573548 -285.987473) (xy 300.566054 -285.995014) (xy 300.56074 -285.995364) (xy 300.044866 -285.995364)
			(xy 300.036991 -285.995642) (xy 300.021987 -286.000432) (xy 300.015402 -286.004762) (xy 299.994315 -286.019139)
			(xy 299.948674 -286.041971) (xy 299.900071 -286.057532) (xy 299.849656 -286.065456) (xy 299.82414 -286.065976)
			(xy 299.79862 -286.065488) (xy 299.748193 -286.057593) (xy 299.699581 -286.042033) (xy 299.653943 -286.019178)
			(xy 299.632878 -286.004762) (xy 299.62629 -286.000442) (xy 299.611287 -285.995657) (xy 299.603414 -285.995364)
			(xy 299.08754 -285.995364) (xy 299.082202 -285.995042) (xy 299.074657 -285.987494) (xy 299.074332 -285.982156)
			(xy 296.47388 -285.982156) (xy 296.473541 -285.987489) (xy 296.466005 -285.995034) (xy 296.460672 -285.995364)
			(xy 295.944798 -285.995364) (xy 295.936924 -285.995656) (xy 295.92192 -286.000436) (xy 295.915334 -286.004762)
			(xy 295.894266 -286.019169) (xy 295.848618 -286.041993) (xy 295.800009 -286.057547) (xy 295.74959 -286.065461)
			(xy 295.724072 -286.065976) (xy 295.698552 -286.065472) (xy 295.648126 -286.057582) (xy 295.599514 -286.042027)
			(xy 295.553875 -286.019176) (xy 295.53281 -286.004762) (xy 295.526214 -286.000454) (xy 295.511218 -285.995662)
			(xy 295.503346 -285.995364) (xy 294.987472 -285.995364) (xy 294.982125 -285.995088) (xy 294.974583 -285.987505)
			(xy 294.974264 -285.982156) (xy 293.030148 -285.982156) (xy 293.029748 -285.987473) (xy 293.022254 -285.995014)
			(xy 293.01694 -285.995364) (xy 293.016432 -285.995364) (xy 292.500812 -285.995364) (xy 292.492938 -285.995662)
			(xy 292.477934 -286.000438) (xy 292.471348 -286.004762) (xy 292.450277 -286.019163) (xy 292.404629 -286.041989)
			(xy 292.356022 -286.057544) (xy 292.305603 -286.06546) (xy 292.280086 -286.065976) (xy 292.254567 -286.065465)
			(xy 292.20414 -286.057577) (xy 292.155529 -286.042024) (xy 292.109889 -286.019175) (xy 292.088824 -286.004762)
			(xy 292.082225 -286.000459) (xy 292.067231 -285.995664) (xy 292.05936 -285.995364) (xy 291.543486 -285.995364)
			(xy 291.538181 -285.994886) (xy 291.530611 -285.987451) (xy 291.530024 -285.982156) (xy 288.93008 -285.982156)
			(xy 288.929741 -285.987489) (xy 288.922205 -285.995034) (xy 288.916872 -285.995364) (xy 288.916364 -285.995364)
			(xy 288.400744 -285.995364) (xy 288.392868 -285.995633) (xy 288.377864 -286.000429) (xy 288.37128 -286.004762)
			(xy 288.3502 -286.019149) (xy 288.304556 -286.041978) (xy 288.255951 -286.057537) (xy 288.205534 -286.065458)
			(xy 288.180018 -286.065976) (xy 288.154497 -286.065499) (xy 288.10407 -286.057601) (xy 288.055458 -286.042038)
			(xy 288.00982 -286.019179) (xy 287.988756 -286.004762) (xy 287.982172 -286.000433) (xy 287.967166 -285.995654)
			(xy 287.959292 -285.995364) (xy 287.443418 -285.995364) (xy 287.438117 -285.994865) (xy 287.430545 -285.987446)
			(xy 287.429956 -285.982156) (xy 285.48584 -285.982156) (xy 285.485447 -285.987475) (xy 285.477949 -285.995016)
			(xy 285.472632 -285.995364) (xy 284.956758 -285.995364) (xy 284.948882 -285.995639) (xy 284.933878 -286.000431)
			(xy 284.927294 -286.004762) (xy 284.90621 -286.019143) (xy 284.860567 -286.041973) (xy 284.811963 -286.057534)
			(xy 284.761548 -286.065457) (xy 284.736032 -286.065976) (xy 284.710512 -286.065492) (xy 284.660084 -286.057596)
			(xy 284.611473 -286.042035) (xy 284.565835 -286.019178) (xy 284.54477 -286.004762) (xy 284.538183 -286.000439)
			(xy 284.52318 -285.995656) (xy 284.515306 -285.995364) (xy 283.999432 -285.995364) (xy 283.994093 -285.995047)
			(xy 283.986548 -285.987495) (xy 283.986224 -285.982156) (xy 281.385772 -285.982156) (xy 281.38544 -285.987491)
			(xy 281.377899 -285.995037) (xy 281.372564 -285.995364) (xy 280.85669 -285.995364) (xy 280.848816 -285.995653)
			(xy 280.833811 -286.000435) (xy 280.827226 -286.004762) (xy 280.806161 -286.019172) (xy 280.760511 -286.041996)
			(xy 280.711902 -286.057548) (xy 280.661482 -286.065462) (xy 280.635964 -286.065976) (xy 280.610444 -286.065476)
			(xy 280.560018 -286.057585) (xy 280.511406 -286.042028) (xy 280.465767 -286.019176) (xy 280.444702 -286.004762)
			(xy 280.438108 -286.000451) (xy 280.42311 -285.995661) (xy 280.415238 -285.995364) (xy 279.899364 -285.995364)
			(xy 279.894016 -285.995093) (xy 279.886475 -285.987506) (xy 279.886156 -285.982156) (xy 277.94204 -285.982156)
			(xy 277.941647 -285.987475) (xy 277.934149 -285.995016) (xy 277.928832 -285.995364) (xy 277.412958 -285.995364)
			(xy 277.405082 -285.995639) (xy 277.390078 -286.000431) (xy 277.383494 -286.004762) (xy 277.36241 -286.019143)
			(xy 277.316767 -286.041973) (xy 277.268163 -286.057534) (xy 277.217748 -286.065457) (xy 277.192232 -286.065976)
			(xy 277.166712 -286.065492) (xy 277.116284 -286.057596) (xy 277.067673 -286.042035) (xy 277.022035 -286.019178)
			(xy 277.00097 -286.004762) (xy 276.994383 -286.000439) (xy 276.97938 -285.995656) (xy 276.971506 -285.995364)
			(xy 276.455632 -285.995364) (xy 276.450293 -285.995047) (xy 276.442748 -285.987495) (xy 276.442424 -285.982156)
			(xy 273.841972 -285.982156) (xy 273.84164 -285.987491) (xy 273.834099 -285.995037) (xy 273.828764 -285.995364)
			(xy 273.31289 -285.995364) (xy 273.305016 -285.995653) (xy 273.290011 -286.000435) (xy 273.283426 -286.004762)
			(xy 273.262361 -286.019172) (xy 273.216711 -286.041996) (xy 273.168102 -286.057548) (xy 273.117682 -286.065462)
			(xy 273.092164 -286.065976) (xy 273.066644 -286.065476) (xy 273.016218 -286.057585) (xy 272.967606 -286.042028)
			(xy 272.921967 -286.019176) (xy 272.900902 -286.004762) (xy 272.894308 -286.000451) (xy 272.87931 -285.995661)
			(xy 272.871438 -285.995364) (xy 272.355564 -285.995364) (xy 272.350216 -285.995093) (xy 272.342675 -285.987506)
			(xy 272.342356 -285.982156) (xy 270.39824 -285.982156) (xy 270.397847 -285.987475) (xy 270.390349 -285.995016)
			(xy 270.385032 -285.995364) (xy 270.384524 -285.995364) (xy 269.868904 -285.995364) (xy 269.86103 -285.995659)
			(xy 269.846026 -286.000437) (xy 269.83944 -286.004762) (xy 269.818371 -286.019166) (xy 269.772723 -286.041991)
			(xy 269.724114 -286.057545) (xy 269.673695 -286.065461) (xy 269.648178 -286.065976) (xy 269.622658 -286.065469)
			(xy 269.572232 -286.05758) (xy 269.52362 -286.042026) (xy 269.477981 -286.019175) (xy 269.456916 -286.004762)
			(xy 269.450319 -286.000456) (xy 269.435323 -285.995663) (xy 269.427452 -285.995364) (xy 268.911578 -285.995364)
			(xy 268.906272 -285.994892) (xy 268.898702 -285.987452) (xy 268.898116 -285.982156) (xy 266.298172 -285.982156)
			(xy 266.29784 -285.987491) (xy 266.290299 -285.995037) (xy 266.284964 -285.995364) (xy 266.284456 -285.995364)
			(xy 265.768836 -285.995364) (xy 265.760959 -285.99563) (xy 265.745956 -286.000428) (xy 265.739372 -286.004762)
			(xy 265.718294 -286.019152) (xy 265.672649 -286.041981) (xy 265.624043 -286.057539) (xy 265.573627 -286.065458)
			(xy 265.54811 -286.065976) (xy 265.522589 -286.065503) (xy 265.472161 -286.057604) (xy 265.42355 -286.042039)
			(xy 265.377912 -286.01918) (xy 265.356848 -286.004762) (xy 265.350266 -286.00043) (xy 265.335259 -285.995653)
			(xy 265.327384 -285.995364) (xy 264.81151 -285.995364) (xy 264.806208 -285.994871) (xy 264.798636 -285.987448)
			(xy 264.798048 -285.982156) (xy 206.997808 -285.982156) (xy 206.997808 -285.98241) (xy 206.997289 -285.987704)
			(xy 206.989882 -285.995272) (xy 206.9846 -285.995872) (xy 206.468726 -285.995872) (xy 206.460916 -285.996185)
			(xy 206.446044 -286.00097) (xy 206.439516 -286.00527) (xy 206.418389 -286.019611) (xy 206.372667 -286.042339)
			(xy 206.323995 -286.057771) (xy 206.27353 -286.065541) (xy 206.248 -286.065976) (xy 206.22247 -286.065537)
			(xy 206.172006 -286.057762) (xy 206.123334 -286.042333) (xy 206.077606 -286.019617) (xy 206.056484 -286.00527)
			(xy 206.049951 -286.000981) (xy 206.035082 -285.996195) (xy 206.027274 -285.995872) (xy 205.5114 -285.995872)
			(xy 205.506059 -285.99557) (xy 205.498516 -285.988006) (xy 205.498192 -285.982664) (xy 202.897718 -285.982664)
			(xy 202.897281 -285.98772) (xy 202.889833 -285.995292) (xy 202.884532 -285.995872) (xy 202.368658 -285.995872)
			(xy 202.360849 -285.996198) (xy 202.345977 -286.000974) (xy 202.339448 -286.00527) (xy 202.31834 -286.01964)
			(xy 202.272611 -286.042362) (xy 202.223934 -286.057786) (xy 202.173464 -286.065546) (xy 202.147932 -286.065976)
			(xy 202.122402 -286.065521) (xy 202.071939 -286.057751) (xy 202.023267 -286.042327) (xy 201.977539 -286.019615)
			(xy 201.956416 -286.00527) (xy 201.949876 -286.000993) (xy 201.935013 -285.9962) (xy 201.927206 -285.995872)
			(xy 201.411332 -285.995872) (xy 201.405995 -285.995548) (xy 201.39845 -285.988001) (xy 201.398124 -285.982664)
			(xy 199.453983 -285.982664) (xy 199.453489 -285.987704) (xy 199.446082 -285.995272) (xy 199.4408 -285.995872)
			(xy 198.924926 -285.995872) (xy 198.917116 -285.996185) (xy 198.902244 -286.00097) (xy 198.895716 -286.00527)
			(xy 198.874589 -286.019611) (xy 198.828867 -286.042339) (xy 198.780195 -286.057771) (xy 198.72973 -286.065541)
			(xy 198.7042 -286.065976) (xy 198.67867 -286.065537) (xy 198.628206 -286.057762) (xy 198.579534 -286.042333)
			(xy 198.533806 -286.019617) (xy 198.512684 -286.00527) (xy 198.506151 -286.000981) (xy 198.491282 -285.996195)
			(xy 198.483474 -285.995872) (xy 197.9676 -285.995872) (xy 197.962259 -285.99557) (xy 197.954716 -285.988006)
			(xy 197.954392 -285.982664) (xy 195.353918 -285.982664) (xy 195.353481 -285.98772) (xy 195.346033 -285.995292)
			(xy 195.340732 -285.995872) (xy 194.824858 -285.995872) (xy 194.817049 -285.996198) (xy 194.802177 -286.000974)
			(xy 194.795648 -286.00527) (xy 194.77454 -286.01964) (xy 194.728811 -286.042362) (xy 194.680134 -286.057786)
			(xy 194.629664 -286.065546) (xy 194.604132 -286.065976) (xy 194.578602 -286.065521) (xy 194.528139 -286.057751)
			(xy 194.479467 -286.042327) (xy 194.433739 -286.019615) (xy 194.412616 -286.00527) (xy 194.406076 -286.000993)
			(xy 194.391213 -285.9962) (xy 194.383406 -285.995872) (xy 193.867532 -285.995872) (xy 193.862195 -285.995548)
			(xy 193.85465 -285.988001) (xy 193.854324 -285.982664) (xy 191.910182 -285.982664) (xy 191.909661 -285.987764)
			(xy 191.902099 -285.995347) (xy 191.896746 -285.995872) (xy 191.380872 -285.995872) (xy 191.37306 -285.996162)
			(xy 191.358188 -286.000963) (xy 191.351662 -286.00527) (xy 191.33055 -286.019634) (xy 191.284822 -286.042357)
			(xy 191.236146 -286.057783) (xy 191.185678 -286.065545) (xy 191.160146 -286.065976) (xy 191.134617 -286.065514)
			(xy 191.084154 -286.057746) (xy 191.035482 -286.042324) (xy 190.989753 -286.019614) (xy 190.96863 -286.00527)
			(xy 190.962087 -286.000998) (xy 190.947226 -285.996202) (xy 190.93942 -285.995872) (xy 190.423546 -285.995872)
			(xy 190.41812 -285.995491) (xy 190.410432 -285.987835) (xy 190.410084 -285.98241) (xy 187.81014 -285.98241)
			(xy 187.809825 -285.987852) (xy 187.80212 -285.995538) (xy 187.796678 -285.995872) (xy 187.280804 -285.995872)
			(xy 187.272993 -285.996175) (xy 187.258121 -286.000967) (xy 187.251594 -286.00527) (xy 187.230473 -286.01962)
			(xy 187.184749 -286.042346) (xy 187.136075 -286.057776) (xy 187.085609 -286.065543) (xy 187.060078 -286.065976)
			(xy 187.034547 -286.065548) (xy 186.984083 -286.057769) (xy 186.935411 -286.042338) (xy 186.889684 -286.019619)
			(xy 186.868562 -286.00527) (xy 186.862034 -286.000972) (xy 186.847161 -285.996192) (xy 186.839352 -285.995872)
			(xy 186.323478 -285.995872) (xy 186.318114 -285.995365) (xy 186.31053 -285.987775) (xy 186.310016 -285.98241)
			(xy 184.3659 -285.98241) (xy 184.365388 -285.987706) (xy 184.357977 -285.995274) (xy 184.352692 -285.995872)
			(xy 183.836818 -285.995872) (xy 183.829007 -285.996181) (xy 183.814135 -286.000969) (xy 183.807608 -286.00527)
			(xy 183.786483 -286.019614) (xy 183.74076 -286.042341) (xy 183.692088 -286.057773) (xy 183.641623 -286.065542)
			(xy 183.616092 -286.065976) (xy 183.590562 -286.065541) (xy 183.540098 -286.057765) (xy 183.491426 -286.042335)
			(xy 183.445698 -286.019618) (xy 183.424576 -286.00527) (xy 183.418045 -286.000978) (xy 183.403175 -285.996194)
			(xy 183.395366 -285.995872) (xy 182.879492 -285.995872) (xy 182.87415 -285.995575) (xy 182.866607 -285.988007)
			(xy 182.866284 -285.982664) (xy 180.26581 -285.982664) (xy 180.26538 -285.987722) (xy 180.257927 -285.995294)
			(xy 180.252624 -285.995872) (xy 179.73675 -285.995872) (xy 179.728941 -285.996195) (xy 179.714069 -286.000973)
			(xy 179.70754 -286.00527) (xy 179.686434 -286.019644) (xy 179.640704 -286.042364) (xy 179.592026 -286.057787)
			(xy 179.541556 -286.065547) (xy 179.516024 -286.065976) (xy 179.490494 -286.065525) (xy 179.440031 -286.057753)
			(xy 179.391359 -286.042328) (xy 179.345631 -286.019616) (xy 179.324508 -286.00527) (xy 179.31797 -286.00099)
			(xy 179.303105 -285.996199) (xy 179.295298 -285.995872) (xy 178.779424 -285.995872) (xy 178.774086 -285.995553)
			(xy 178.766542 -285.988002) (xy 178.766216 -285.982664) (xy 176.822074 -285.982664) (xy 176.82156 -285.987766)
			(xy 176.813993 -285.995349) (xy 176.808638 -285.995872) (xy 176.292764 -285.995872) (xy 176.284955 -285.996201)
			(xy 176.270083 -286.000975) (xy 176.263554 -286.00527) (xy 176.242444 -286.019637) (xy 176.196716 -286.04236)
			(xy 176.148039 -286.057784) (xy 176.09757 -286.065546) (xy 176.072038 -286.065976) (xy 176.046509 -286.065518)
			(xy 175.996046 -286.057749) (xy 175.947373 -286.042325) (xy 175.901645 -286.019615) (xy 175.880522 -286.00527)
			(xy 175.873981 -286.000995) (xy 175.859118 -285.996201) (xy 175.851312 -285.995872) (xy 175.335438 -285.995872)
			(xy 175.330011 -285.995496) (xy 175.322323 -285.987836) (xy 175.321976 -285.98241) (xy 172.722032 -285.98241)
			(xy 172.721725 -285.987854) (xy 172.714015 -285.995541) (xy 172.70857 -285.995872) (xy 172.192696 -285.995872)
			(xy 172.184884 -285.996172) (xy 172.170013 -286.000966) (xy 172.163486 -286.00527) (xy 172.142367 -286.019624)
			(xy 172.096642 -286.042349) (xy 172.047968 -286.057778) (xy 171.997501 -286.065543) (xy 171.97197 -286.065976)
			(xy 171.946439 -286.065552) (xy 171.895975 -286.057772) (xy 171.847303 -286.042339) (xy 171.801576 -286.019619)
			(xy 171.780454 -286.00527) (xy 171.773928 -286.000969) (xy 171.759054 -285.996191) (xy 171.751244 -285.995872)
			(xy 171.23537 -285.995872) (xy 171.230005 -285.995371) (xy 171.222421 -285.987776) (xy 171.221908 -285.98241)
			(xy 169.277792 -285.98241) (xy 169.277287 -285.987708) (xy 169.269871 -285.995277) (xy 169.264584 -285.995872)
			(xy 167.791384 -285.995872) (xy 167.786041 -285.995581) (xy 167.778498 -285.988009) (xy 167.778176 -285.982664)
			(xy 165.177703 -285.982664) (xy 165.177279 -285.987724) (xy 165.169822 -285.995296) (xy 165.164516 -285.995872)
			(xy 163.691316 -285.995872) (xy 163.685977 -285.995559) (xy 163.678433 -285.988003) (xy 163.678108 -285.982664)
			(xy 126.345496 -285.982664) (xy 126.382115 -286.01116) (xy 126.416363 -286.048359) (xy 126.444022 -286.090688)
			(xy 126.464335 -286.136992) (xy 126.476749 -286.186009) (xy 126.480908 -286.2362) (xy 345.615224 -286.2362)
			(xy 345.619396 -286.185857) (xy 345.631796 -286.136887) (xy 345.652087 -286.090626) (xy 345.679715 -286.048335)
			(xy 345.713927 -286.011169) (xy 345.753789 -285.98014) (xy 345.798215 -285.956094) (xy 345.845992 -285.939689)
			(xy 345.895818 -285.931371) (xy 345.921076 -285.930848) (xy 346.86113 -285.930848) (xy 346.88638 -285.93146)
			(xy 346.936191 -285.939776) (xy 346.983954 -285.956177) (xy 347.028366 -285.980216) (xy 347.068216 -286.011236)
			(xy 347.102417 -286.048392) (xy 347.130036 -286.09067) (xy 347.150321 -286.136917) (xy 347.162717 -286.185872)
			(xy 347.166887 -286.2362) (xy 348.435296 -286.2362) (xy 348.439469 -286.185846) (xy 348.451873 -286.136866)
			(xy 348.472171 -286.090595) (xy 348.499809 -286.048297) (xy 348.534032 -286.011126) (xy 348.573906 -285.980094)
			(xy 348.618345 -285.95605) (xy 348.666136 -285.939649) (xy 348.715975 -285.931338) (xy 348.741238 -285.930848)
			(xy 349.681292 -285.930848) (xy 349.706547 -285.931428) (xy 349.756367 -285.93974) (xy 349.804139 -285.956139)
			(xy 349.848561 -285.980178) (xy 349.88842 -286.011201) (xy 349.92263 -286.048361) (xy 349.950256 -286.090645)
			(xy 349.970545 -286.1369) (xy 349.982945 -286.185864) (xy 349.987116 -286.2362) (xy 351.255196 -286.2362)
			(xy 351.259369 -286.185845) (xy 351.271774 -286.136864) (xy 351.292072 -286.090593) (xy 351.319711 -286.048295)
			(xy 351.353935 -286.011123) (xy 351.393811 -285.980092) (xy 351.438251 -285.956048) (xy 351.486043 -285.939647)
			(xy 351.535882 -285.931337) (xy 351.561146 -285.930848) (xy 352.5012 -285.930848) (xy 352.526452 -285.931457)
			(xy 352.576266 -285.93977) (xy 352.624033 -285.956168) (xy 352.66845 -285.980205) (xy 352.708304 -286.011225)
			(xy 352.742509 -286.048382) (xy 352.770132 -286.090661) (xy 352.790419 -286.136911) (xy 352.802816 -286.185869)
			(xy 352.806987 -286.2362) (xy 354.075224 -286.2362) (xy 354.079395 -286.185859) (xy 354.091795 -286.136892)
			(xy 354.112084 -286.090632) (xy 354.139709 -286.048343) (xy 354.173918 -286.011177) (xy 354.213778 -285.980147)
			(xy 354.2582 -285.956101) (xy 354.305974 -285.939694) (xy 354.355797 -285.931373) (xy 354.381054 -285.930848)
			(xy 355.321108 -285.930848) (xy 355.346359 -285.931458) (xy 355.396173 -285.939772) (xy 355.443939 -285.956171)
			(xy 355.488354 -285.980208) (xy 355.528207 -286.011228) (xy 355.562411 -286.048384) (xy 355.590033 -286.090664)
			(xy 355.610319 -286.136913) (xy 355.622717 -286.18587) (xy 355.626887 -286.2362) (xy 364.408924 -286.2362)
			(xy 364.413096 -286.185856) (xy 364.425497 -286.136884) (xy 364.445789 -286.090622) (xy 364.473419 -286.048331)
			(xy 364.507632 -286.011164) (xy 364.547497 -285.980135) (xy 364.591924 -285.95609) (xy 364.639704 -285.939686)
			(xy 364.689532 -285.93137) (xy 364.71479 -285.930848) (xy 365.654844 -285.930848) (xy 365.680093 -285.931461)
			(xy 365.729902 -285.939779) (xy 365.777663 -285.956181) (xy 365.822073 -285.980221) (xy 365.861921 -286.011241)
			(xy 365.89612 -286.048396) (xy 365.923738 -286.090674) (xy 365.944022 -286.13692) (xy 365.956417 -286.185874)
			(xy 365.960587 -286.2362) (xy 367.228824 -286.2362) (xy 367.232996 -286.185855) (xy 367.245398 -286.136883)
			(xy 367.26569 -286.09062) (xy 367.293321 -286.048328) (xy 367.327535 -286.011161) (xy 367.367401 -285.980132)
			(xy 367.41183 -285.956088) (xy 367.45961 -285.939685) (xy 367.509439 -285.931369) (xy 367.534698 -285.930848)
			(xy 368.474752 -285.930848) (xy 368.500009 -285.931425) (xy 368.549834 -285.939732) (xy 368.597612 -285.956128)
			(xy 368.64204 -285.980164) (xy 368.681905 -286.011187) (xy 368.716119 -286.048348) (xy 368.74375 -286.090634)
			(xy 368.764043 -286.136892) (xy 368.776444 -286.185859) (xy 368.780616 -286.2362) (xy 370.049024 -286.2362)
			(xy 370.053196 -286.185859) (xy 370.065595 -286.13689) (xy 370.085885 -286.09063) (xy 370.113511 -286.048341)
			(xy 370.147721 -286.011174) (xy 370.187581 -285.980145) (xy 370.232004 -285.956099) (xy 370.279779 -285.939692)
			(xy 370.329603 -285.931372) (xy 370.35486 -285.930848) (xy 371.294914 -285.930848) (xy 371.320165 -285.931459)
			(xy 371.369978 -285.939773) (xy 371.417743 -285.956173) (xy 371.462157 -285.98021) (xy 371.502009 -286.01123)
			(xy 371.536213 -286.048386) (xy 371.563834 -286.090665) (xy 371.58412 -286.136914) (xy 371.596517 -286.185871)
			(xy 371.600687 -286.2362) (xy 372.868924 -286.2362) (xy 372.873096 -286.185858) (xy 372.885495 -286.136889)
			(xy 372.905786 -286.090628) (xy 372.933413 -286.048338) (xy 372.967624 -286.011172) (xy 373.007485 -285.980142)
			(xy 373.05191 -285.956097) (xy 373.099686 -285.939691) (xy 373.149511 -285.931372) (xy 373.174768 -285.930848)
			(xy 374.114822 -285.930848) (xy 374.140072 -285.931459) (xy 374.189884 -285.939775) (xy 374.237648 -285.956175)
			(xy 374.282061 -285.980213) (xy 374.284557 -285.982156) (xy 411.618176 -285.982156) (xy 411.618176 -285.487618)
			(xy 411.618639 -285.482308) (xy 411.626083 -285.474733) (xy 411.631384 -285.474156) (xy 413.104584 -285.474156)
			(xy 413.109836 -285.474702) (xy 413.117278 -285.482114) (xy 413.117792 -285.487364) (xy 413.117792 -285.487872)
			(xy 413.117792 -285.982156) (xy 415.718244 -285.982156) (xy 415.718244 -285.487618) (xy 415.718736 -285.482315)
			(xy 415.72616 -285.474743) (xy 415.731452 -285.474156) (xy 417.204652 -285.474156) (xy 417.209969 -285.474556)
			(xy 417.21751 -285.482049) (xy 417.21786 -285.487364) (xy 417.21786 -285.982156) (xy 419.161976 -285.982156)
			(xy 419.161976 -285.487618) (xy 419.162295 -285.482176) (xy 419.169996 -285.474487) (xy 419.175438 -285.474156)
			(xy 419.691566 -285.474156) (xy 419.699376 -285.473835) (xy 419.714247 -285.469055) (xy 419.720776 -285.464758)
			(xy 419.741865 -285.450409) (xy 419.787526 -285.427678) (xy 419.836132 -285.412219) (xy 419.886535 -285.404396)
			(xy 419.937541 -285.404396) (xy 419.987944 -285.412219) (xy 420.03655 -285.427678) (xy 420.082211 -285.450409)
			(xy 420.1033 -285.464758) (xy 420.109835 -285.469044) (xy 420.124702 -285.473831) (xy 420.13251 -285.474156)
			(xy 420.648638 -285.474156) (xy 420.654011 -285.474627) (xy 420.661595 -285.482243) (xy 420.6621 -285.487618)
			(xy 420.6621 -285.982156) (xy 423.262044 -285.982156) (xy 423.262044 -285.487618) (xy 423.262392 -285.482184)
			(xy 423.270072 -285.474497) (xy 423.275506 -285.474156) (xy 423.791634 -285.474156) (xy 423.799442 -285.473822)
			(xy 423.814314 -285.469051) (xy 423.820844 -285.464758) (xy 423.841933 -285.450409) (xy 423.887594 -285.427678)
			(xy 423.9362 -285.412219) (xy 423.986603 -285.404396) (xy 424.037609 -285.404396) (xy 424.088012 -285.412219)
			(xy 424.136618 -285.427678) (xy 424.182279 -285.450409) (xy 424.203368 -285.464758) (xy 424.20991 -285.469032)
			(xy 424.224772 -285.473826) (xy 424.232578 -285.474156) (xy 424.748706 -285.474156) (xy 424.754146 -285.474477)
			(xy 424.761833 -285.482177) (xy 424.762168 -285.487618) (xy 424.762168 -285.982156) (xy 426.706284 -285.982156)
			(xy 426.706284 -285.487618) (xy 426.70674 -285.482306) (xy 426.714189 -285.474731) (xy 426.719492 -285.474156)
			(xy 427.23562 -285.474156) (xy 427.243432 -285.473858) (xy 427.258303 -285.469062) (xy 427.26483 -285.464758)
			(xy 427.285919 -285.450409) (xy 427.33158 -285.427678) (xy 427.380186 -285.412219) (xy 427.430589 -285.404396)
			(xy 427.481595 -285.404396) (xy 427.531998 -285.412219) (xy 427.580604 -285.427678) (xy 427.626265 -285.450409)
			(xy 427.647354 -285.464758) (xy 427.653877 -285.469065) (xy 427.668753 -285.473839) (xy 427.676564 -285.474156)
			(xy 428.192692 -285.474156) (xy 428.197945 -285.474696) (xy 428.205386 -285.482113) (xy 428.2059 -285.487364)
			(xy 428.2059 -285.487872) (xy 428.2059 -285.982156) (xy 430.806352 -285.982156) (xy 430.806352 -285.487618)
			(xy 430.806836 -285.482313) (xy 430.814265 -285.47474) (xy 430.81956 -285.474156) (xy 431.335688 -285.474156)
			(xy 431.343498 -285.473844) (xy 431.35837 -285.469058) (xy 431.364898 -285.464758) (xy 431.385987 -285.450409)
			(xy 431.431648 -285.427678) (xy 431.480254 -285.412219) (xy 431.530657 -285.404396) (xy 431.581663 -285.404396)
			(xy 431.632066 -285.412219) (xy 431.680672 -285.427678) (xy 431.726333 -285.450409) (xy 431.747422 -285.464758)
			(xy 431.753952 -285.469052) (xy 431.768823 -285.473834) (xy 431.776632 -285.474156) (xy 432.29276 -285.474156)
			(xy 432.298078 -285.47455) (xy 432.305619 -285.482048) (xy 432.305968 -285.487364) (xy 432.305968 -285.487872)
			(xy 432.305968 -285.982156) (xy 434.250084 -285.982156) (xy 434.250084 -285.487618) (xy 434.250396 -285.482174)
			(xy 434.258102 -285.474484) (xy 434.263546 -285.474156) (xy 434.779674 -285.474156) (xy 434.787484 -285.473838)
			(xy 434.802356 -285.469056) (xy 434.808884 -285.464758) (xy 434.829973 -285.450409) (xy 434.875634 -285.427678)
			(xy 434.92424 -285.412219) (xy 434.974643 -285.404396) (xy 435.025649 -285.404396) (xy 435.076052 -285.412219)
			(xy 435.124658 -285.427678) (xy 435.170319 -285.450409) (xy 435.191408 -285.464758) (xy 435.197941 -285.469047)
			(xy 435.21281 -285.473832) (xy 435.220618 -285.474156) (xy 435.736746 -285.474156) (xy 435.74212 -285.474622)
			(xy 435.749704 -285.482242) (xy 435.750208 -285.487618) (xy 435.750208 -285.982156) (xy 438.350152 -285.982156)
			(xy 438.350152 -285.487618) (xy 438.350493 -285.482182) (xy 438.358178 -285.474494) (xy 438.363614 -285.474156)
			(xy 438.879742 -285.474156) (xy 438.887551 -285.473825) (xy 438.902422 -285.469052) (xy 438.908952 -285.464758)
			(xy 438.930041 -285.450409) (xy 438.975702 -285.427678) (xy 439.024308 -285.412219) (xy 439.074711 -285.404396)
			(xy 439.125717 -285.404396) (xy 439.17612 -285.412219) (xy 439.224726 -285.427678) (xy 439.270387 -285.450409)
			(xy 439.291476 -285.464758) (xy 439.298016 -285.469035) (xy 439.312879 -285.473827) (xy 439.320686 -285.474156)
			(xy 439.836814 -285.474156) (xy 439.842255 -285.474472) (xy 439.849941 -285.482176) (xy 439.850276 -285.487618)
			(xy 439.850276 -285.982156) (xy 441.794392 -285.982156) (xy 441.794392 -285.487618) (xy 441.794929 -285.482327)
			(xy 441.802322 -285.474758) (xy 441.8076 -285.474156) (xy 442.323728 -285.474156) (xy 442.33154 -285.473862)
			(xy 442.346412 -285.469063) (xy 442.352938 -285.464758) (xy 442.374027 -285.450409) (xy 442.419688 -285.427678)
			(xy 442.468294 -285.412219) (xy 442.518697 -285.404396) (xy 442.569703 -285.404396) (xy 442.620106 -285.412219)
			(xy 442.668712 -285.427678) (xy 442.714373 -285.450409) (xy 442.735462 -285.464758) (xy 442.742005 -285.469029)
			(xy 442.756866 -285.473825) (xy 442.764672 -285.474156) (xy 443.2808 -285.474156) (xy 443.286054 -285.474691)
			(xy 443.293494 -285.482111) (xy 443.294008 -285.487364) (xy 443.294008 -285.487872) (xy 443.294008 -285.982156)
			(xy 445.89446 -285.982156) (xy 445.89446 -285.487618) (xy 445.894937 -285.482311) (xy 445.902371 -285.474738)
			(xy 445.907668 -285.474156) (xy 446.423796 -285.474156) (xy 446.431607 -285.473848) (xy 446.446478 -285.469059)
			(xy 446.453006 -285.464758) (xy 446.474095 -285.450409) (xy 446.519756 -285.427678) (xy 446.568362 -285.412219)
			(xy 446.618765 -285.404396) (xy 446.669771 -285.404396) (xy 446.720174 -285.412219) (xy 446.76878 -285.427678)
			(xy 446.814441 -285.450409) (xy 446.83553 -285.464758) (xy 446.842058 -285.469055) (xy 446.856931 -285.473835)
			(xy 446.86474 -285.474156) (xy 447.380868 -285.474156) (xy 447.386118 -285.474712) (xy 447.393561 -285.482116)
			(xy 447.394076 -285.487364) (xy 447.394076 -285.487872) (xy 447.394076 -285.982156) (xy 449.338192 -285.982156)
			(xy 449.338192 -285.487618) (xy 449.338729 -285.482327) (xy 449.346122 -285.474758) (xy 449.3514 -285.474156)
			(xy 449.867528 -285.474156) (xy 449.87534 -285.473862) (xy 449.890212 -285.469063) (xy 449.896738 -285.464758)
			(xy 449.917827 -285.450409) (xy 449.963488 -285.427678) (xy 450.012094 -285.412219) (xy 450.062497 -285.404396)
			(xy 450.113503 -285.404396) (xy 450.163906 -285.412219) (xy 450.212512 -285.427678) (xy 450.258173 -285.450409)
			(xy 450.279262 -285.464758) (xy 450.285805 -285.469029) (xy 450.300666 -285.473825) (xy 450.308472 -285.474156)
			(xy 450.8246 -285.474156) (xy 450.829854 -285.474691) (xy 450.837294 -285.482111) (xy 450.837808 -285.487364)
			(xy 450.837808 -285.487872) (xy 450.837808 -285.982156) (xy 453.43826 -285.982156) (xy 453.43826 -285.487618)
			(xy 453.438737 -285.482311) (xy 453.446171 -285.474738) (xy 453.451468 -285.474156) (xy 453.967596 -285.474156)
			(xy 453.975407 -285.473848) (xy 453.990278 -285.469059) (xy 453.996806 -285.464758) (xy 454.017895 -285.450409)
			(xy 454.063556 -285.427678) (xy 454.112162 -285.412219) (xy 454.162565 -285.404396) (xy 454.213571 -285.404396)
			(xy 454.263974 -285.412219) (xy 454.31258 -285.427678) (xy 454.358241 -285.450409) (xy 454.37933 -285.464758)
			(xy 454.385858 -285.469055) (xy 454.400731 -285.473835) (xy 454.40854 -285.474156) (xy 454.924668 -285.474156)
			(xy 454.929918 -285.474712) (xy 454.937361 -285.482116) (xy 454.937876 -285.487364) (xy 454.937876 -285.487872)
			(xy 454.937876 -285.982156) (xy 454.93754 -285.98749) (xy 454.930002 -285.995036) (xy 454.924668 -285.995364)
			(xy 454.408794 -285.995364) (xy 454.40092 -285.995654) (xy 454.385916 -286.000436) (xy 454.37933 -286.004762)
			(xy 454.358264 -286.01917) (xy 454.312615 -286.041995) (xy 454.264005 -286.057548) (xy 454.213586 -286.065461)
			(xy 454.188068 -286.065976) (xy 454.162548 -286.065474) (xy 454.112122 -286.057584) (xy 454.06351 -286.042028)
			(xy 454.017871 -286.019176) (xy 453.996806 -286.004762) (xy 453.990211 -286.000452) (xy 453.975214 -285.995661)
			(xy 453.967342 -285.995364) (xy 453.451468 -285.995364) (xy 453.446121 -285.99509) (xy 453.438579 -285.987505)
			(xy 453.43826 -285.982156) (xy 450.837808 -285.982156) (xy 450.837444 -285.987482) (xy 450.829925 -285.995026)
			(xy 450.8246 -285.995364) (xy 450.308726 -285.995364) (xy 450.300849 -285.995625) (xy 450.285845 -286.000427)
			(xy 450.279262 -286.004762) (xy 450.258187 -286.019157) (xy 450.212541 -286.041984) (xy 450.163934 -286.057541)
			(xy 450.113517 -286.065459) (xy 450.088 -286.065976) (xy 450.062479 -286.065508) (xy 450.012051 -286.057607)
			(xy 449.963439 -286.042041) (xy 449.917802 -286.01918) (xy 449.896738 -286.004762) (xy 449.890136 -286.000465)
			(xy 449.875144 -285.995666) (xy 449.867274 -285.995364) (xy 449.3514 -285.995364) (xy 449.346057 -285.995069)
			(xy 449.338513 -285.9875) (xy 449.338192 -285.982156) (xy 447.394076 -285.982156) (xy 447.39374 -285.98749)
			(xy 447.386202 -285.995036) (xy 447.380868 -285.995364) (xy 446.864994 -285.995364) (xy 446.85712 -285.995654)
			(xy 446.842116 -286.000436) (xy 446.83553 -286.004762) (xy 446.814464 -286.01917) (xy 446.768815 -286.041995)
			(xy 446.720205 -286.057548) (xy 446.669786 -286.065461) (xy 446.644268 -286.065976) (xy 446.618748 -286.065474)
			(xy 446.568322 -286.057584) (xy 446.51971 -286.042028) (xy 446.474071 -286.019176) (xy 446.453006 -286.004762)
			(xy 446.446411 -286.000452) (xy 446.431414 -285.995661) (xy 446.423542 -285.995364) (xy 445.907668 -285.995364)
			(xy 445.902321 -285.99509) (xy 445.894779 -285.987505) (xy 445.89446 -285.982156) (xy 443.294008 -285.982156)
			(xy 443.293644 -285.987482) (xy 443.286125 -285.995026) (xy 443.2808 -285.995364) (xy 442.764926 -285.995364)
			(xy 442.757049 -285.995625) (xy 442.742045 -286.000427) (xy 442.735462 -286.004762) (xy 442.714387 -286.019157)
			(xy 442.668741 -286.041984) (xy 442.620134 -286.057541) (xy 442.569717 -286.065459) (xy 442.5442 -286.065976)
			(xy 442.518679 -286.065508) (xy 442.468251 -286.057607) (xy 442.419639 -286.042041) (xy 442.374002 -286.01918)
			(xy 442.352938 -286.004762) (xy 442.346336 -286.000465) (xy 442.331344 -285.995666) (xy 442.323474 -285.995364)
			(xy 441.8076 -285.995364) (xy 441.802257 -285.995069) (xy 441.794713 -285.9875) (xy 441.794392 -285.982156)
			(xy 439.850276 -285.982156) (xy 439.84994 -285.98749) (xy 439.842402 -285.995036) (xy 439.837068 -285.995364)
			(xy 439.83656 -285.995364) (xy 439.32094 -285.995364) (xy 439.313064 -285.995631) (xy 439.29806 -286.000429)
			(xy 439.291476 -286.004762) (xy 439.270397 -286.019151) (xy 439.224752 -286.041979) (xy 439.176147 -286.057538)
			(xy 439.12573 -286.065458) (xy 439.100214 -286.065976) (xy 439.074693 -286.065501) (xy 439.024265 -286.057603)
			(xy 438.975654 -286.042038) (xy 438.930016 -286.019179) (xy 438.908952 -286.004762) (xy 438.902369 -286.000432)
			(xy 438.887363 -285.995653) (xy 438.879488 -285.995364) (xy 438.363614 -285.995364) (xy 438.358312 -285.994868)
			(xy 438.350741 -285.987447) (xy 438.350152 -285.982156) (xy 435.750208 -285.982156) (xy 435.749844 -285.987482)
			(xy 435.742325 -285.995026) (xy 435.737 -285.995364) (xy 435.736492 -285.995364) (xy 435.220872 -285.995364)
			(xy 435.212997 -285.995645) (xy 435.197993 -286.000433) (xy 435.191408 -286.004762) (xy 435.170348 -286.01918)
			(xy 435.124697 -286.042002) (xy 435.076085 -286.057552) (xy 435.025664 -286.065463) (xy 435.000146 -286.065976)
			(xy 434.974626 -286.065485) (xy 434.924199 -286.057591) (xy 434.875587 -286.042032) (xy 434.829949 -286.019177)
			(xy 434.808884 -286.004762) (xy 434.802294 -286.000444) (xy 434.787293 -285.995658) (xy 434.77942 -285.995364)
			(xy 434.263546 -285.995364) (xy 434.258248 -285.994847) (xy 434.250675 -285.987442) (xy 434.250084 -285.982156)
			(xy 432.305968 -285.982156) (xy 432.30564 -285.987492) (xy 432.298096 -285.995038) (xy 432.29276 -285.995364)
			(xy 431.776886 -285.995364) (xy 431.769011 -285.995651) (xy 431.754007 -286.000435) (xy 431.747422 -286.004762)
			(xy 431.726358 -286.019174) (xy 431.680708 -286.041997) (xy 431.632098 -286.057549) (xy 431.581678 -286.065462)
			(xy 431.55616 -286.065976) (xy 431.53064 -286.065478) (xy 431.480213 -286.057586) (xy 431.431602 -286.042029)
			(xy 431.385963 -286.019176) (xy 431.364898 -286.004762) (xy 431.358305 -286.000449) (xy 431.343306 -285.99566)
			(xy 431.335434 -285.995364) (xy 430.81956 -285.995364) (xy 430.814211 -285.995096) (xy 430.80667 -285.987506)
			(xy 430.806352 -285.982156) (xy 428.2059 -285.982156) (xy 428.205543 -285.987484) (xy 428.198019 -285.995028)
			(xy 428.192692 -285.995364) (xy 427.676818 -285.995364) (xy 427.668945 -285.995665) (xy 427.65394 -286.000439)
			(xy 427.647354 -286.004762) (xy 427.626281 -286.01916) (xy 427.580634 -286.041987) (xy 427.532027 -286.057542)
			(xy 427.481609 -286.06546) (xy 427.456092 -286.065976) (xy 427.430573 -286.065462) (xy 427.380147 -286.057575)
			(xy 427.331535 -286.042023) (xy 427.285896 -286.019174) (xy 427.26483 -286.004762) (xy 427.25823 -286.000462)
			(xy 427.243237 -285.995665) (xy 427.235366 -285.995364) (xy 426.719492 -285.995364) (xy 426.714148 -285.995074)
			(xy 426.706605 -285.987501) (xy 426.706284 -285.982156) (xy 424.762168 -285.982156) (xy 424.76184 -285.987492)
			(xy 424.754296 -285.995038) (xy 424.74896 -285.995364) (xy 424.748452 -285.995364) (xy 424.232832 -285.995364)
			(xy 424.224955 -285.995627) (xy 424.209951 -286.000427) (xy 424.203368 -286.004762) (xy 424.182291 -286.019154)
			(xy 424.136646 -286.041982) (xy 424.08804 -286.057539) (xy 424.037623 -286.065459) (xy 424.012106 -286.065976)
			(xy 423.986585 -286.065505) (xy 423.936157 -286.057605) (xy 423.887546 -286.04204) (xy 423.841908 -286.01918)
			(xy 423.820844 -286.004762) (xy 423.814263 -286.000428) (xy 423.799255 -285.995652) (xy 423.79138 -285.995364)
			(xy 423.275506 -285.995364) (xy 423.270203 -285.994873) (xy 423.262632 -285.987448) (xy 423.262044 -285.982156)
			(xy 420.6621 -285.982156) (xy 420.661743 -285.987484) (xy 420.654219 -285.995028) (xy 420.648892 -285.995364)
			(xy 420.648384 -285.995364) (xy 420.132764 -285.995364) (xy 420.124889 -285.995642) (xy 420.109885 -286.000432)
			(xy 420.1033 -286.004762) (xy 420.082214 -286.01914) (xy 420.036572 -286.041971) (xy 419.987969 -286.057533)
			(xy 419.937554 -286.065456) (xy 419.912038 -286.065976) (xy 419.886518 -286.065489) (xy 419.83609 -286.057594)
			(xy 419.787479 -286.042034) (xy 419.741841 -286.019178) (xy 419.720776 -286.004762) (xy 419.714188 -286.000441)
			(xy 419.699185 -285.995657) (xy 419.691312 -285.995364) (xy 419.175438 -285.995364) (xy 419.170139 -285.994852)
			(xy 419.162566 -285.987443) (xy 419.161976 -285.982156) (xy 417.21786 -285.982156) (xy 417.217539 -285.987494)
			(xy 417.20999 -285.995041) (xy 417.204652 -285.995364) (xy 415.731452 -285.995364) (xy 415.726173 -285.994933)
			(xy 415.718731 -285.987438) (xy 415.718244 -285.982156) (xy 413.117792 -285.982156) (xy 413.117442 -285.987486)
			(xy 413.109914 -285.995031) (xy 413.104584 -285.995364) (xy 411.631384 -285.995364) (xy 411.626039 -285.99508)
			(xy 411.618496 -285.987503) (xy 411.618176 -285.982156) (xy 374.284557 -285.982156) (xy 374.321912 -286.011233)
			(xy 374.356115 -286.048389) (xy 374.383735 -286.090668) (xy 374.40402 -286.136916) (xy 374.416417 -286.185871)
			(xy 374.420587 -286.2362) (xy 374.416417 -286.286529) (xy 374.40402 -286.335484) (xy 374.383735 -286.381732)
			(xy 374.356115 -286.424011) (xy 374.321912 -286.461167) (xy 374.282061 -286.492187) (xy 374.237648 -286.516225)
			(xy 374.189884 -286.532625) (xy 374.140072 -286.540941) (xy 374.114822 -286.541464) (xy 373.174768 -286.541464)
			(xy 373.149511 -286.541028) (xy 373.099686 -286.532709) (xy 373.05191 -286.516303) (xy 373.007485 -286.492258)
			(xy 372.967624 -286.461228) (xy 372.933413 -286.424062) (xy 372.905786 -286.381772) (xy 372.885495 -286.335511)
			(xy 372.873096 -286.286542) (xy 372.868924 -286.2362) (xy 371.600687 -286.2362) (xy 371.596517 -286.286529)
			(xy 371.58412 -286.335486) (xy 371.563834 -286.381735) (xy 371.536213 -286.424014) (xy 371.502009 -286.46117)
			(xy 371.462157 -286.49219) (xy 371.417743 -286.516227) (xy 371.369978 -286.532627) (xy 371.320165 -286.540941)
			(xy 371.294914 -286.541464) (xy 370.35486 -286.541464) (xy 370.329603 -286.541028) (xy 370.279779 -286.532708)
			(xy 370.232004 -286.516301) (xy 370.187581 -286.492255) (xy 370.147721 -286.461226) (xy 370.113511 -286.424059)
			(xy 370.085884 -286.38177) (xy 370.065595 -286.33551) (xy 370.053196 -286.286541) (xy 370.049024 -286.2362)
			(xy 368.780616 -286.2362) (xy 368.776444 -286.286541) (xy 368.764043 -286.335508) (xy 368.74375 -286.381766)
			(xy 368.716119 -286.424052) (xy 368.681905 -286.461213) (xy 368.64204 -286.492236) (xy 368.597612 -286.516272)
			(xy 368.549834 -286.532668) (xy 368.500009 -286.540975) (xy 368.474752 -286.541464) (xy 367.534698 -286.541464)
			(xy 367.509439 -286.541031) (xy 367.45961 -286.532715) (xy 367.41183 -286.516312) (xy 367.367401 -286.492268)
			(xy 367.327535 -286.461239) (xy 367.293321 -286.424072) (xy 367.26569 -286.38178) (xy 367.245398 -286.335517)
			(xy 367.232996 -286.286545) (xy 367.228824 -286.2362) (xy 365.960587 -286.2362) (xy 365.956417 -286.286526)
			(xy 365.944022 -286.33548) (xy 365.923738 -286.381726) (xy 365.89612 -286.424004) (xy 365.861921 -286.461159)
			(xy 365.822073 -286.492179) (xy 365.777663 -286.516219) (xy 365.729902 -286.532621) (xy 365.680093 -286.540939)
			(xy 365.654844 -286.541464) (xy 364.71479 -286.541464) (xy 364.689532 -286.54103) (xy 364.639704 -286.532714)
			(xy 364.591924 -286.51631) (xy 364.547497 -286.492265) (xy 364.507632 -286.461236) (xy 364.473419 -286.424069)
			(xy 364.445789 -286.381778) (xy 364.425497 -286.335516) (xy 364.413096 -286.286544) (xy 364.408924 -286.2362)
			(xy 355.626887 -286.2362) (xy 355.622717 -286.28653) (xy 355.610319 -286.335487) (xy 355.590033 -286.381736)
			(xy 355.562411 -286.424016) (xy 355.528207 -286.461172) (xy 355.488354 -286.492192) (xy 355.443939 -286.516229)
			(xy 355.396173 -286.532628) (xy 355.346359 -286.540942) (xy 355.321108 -286.541464) (xy 354.381054 -286.541464)
			(xy 354.355797 -286.541027) (xy 354.305974 -286.532706) (xy 354.2582 -286.516299) (xy 354.213778 -286.492253)
			(xy 354.173918 -286.461223) (xy 354.139709 -286.424057) (xy 354.112084 -286.381768) (xy 354.091795 -286.335508)
			(xy 354.079395 -286.286541) (xy 354.075224 -286.2362) (xy 352.806987 -286.2362) (xy 352.802816 -286.286531)
			(xy 352.790419 -286.335489) (xy 352.770132 -286.381739) (xy 352.742509 -286.424018) (xy 352.708304 -286.461175)
			(xy 352.66845 -286.492195) (xy 352.624033 -286.516232) (xy 352.576266 -286.53263) (xy 352.526452 -286.540943)
			(xy 352.5012 -286.541464) (xy 351.561146 -286.541464) (xy 351.535882 -286.541063) (xy 351.486043 -286.532753)
			(xy 351.438251 -286.516352) (xy 351.393811 -286.492309) (xy 351.353935 -286.461277) (xy 351.319711 -286.424105)
			(xy 351.292072 -286.381807) (xy 351.271774 -286.335536) (xy 351.259369 -286.286555) (xy 351.255196 -286.2362)
			(xy 349.987116 -286.2362) (xy 349.982945 -286.286536) (xy 349.970545 -286.3355) (xy 349.950256 -286.381755)
			(xy 349.92263 -286.424039) (xy 349.88842 -286.461199) (xy 349.848561 -286.492222) (xy 349.804139 -286.516261)
			(xy 349.756367 -286.53266) (xy 349.706547 -286.540972) (xy 349.681292 -286.541464) (xy 348.741238 -286.541464)
			(xy 348.715975 -286.541062) (xy 348.666136 -286.532751) (xy 348.618345 -286.51635) (xy 348.573907 -286.492306)
			(xy 348.534032 -286.461274) (xy 348.499809 -286.424103) (xy 348.472171 -286.381805) (xy 348.451873 -286.335534)
			(xy 348.439469 -286.286554) (xy 348.435296 -286.2362) (xy 347.166887 -286.2362) (xy 347.162717 -286.286528)
			(xy 347.150321 -286.335483) (xy 347.130036 -286.38173) (xy 347.102417 -286.424008) (xy 347.068216 -286.461164)
			(xy 347.028366 -286.492184) (xy 346.983954 -286.516223) (xy 346.936191 -286.532624) (xy 346.88638 -286.54094)
			(xy 346.86113 -286.541464) (xy 345.921076 -286.541464) (xy 345.895818 -286.541029) (xy 345.845992 -286.532711)
			(xy 345.798215 -286.516306) (xy 345.753789 -286.49226) (xy 345.713927 -286.461231) (xy 345.679715 -286.424065)
			(xy 345.652087 -286.381774) (xy 345.631796 -286.335513) (xy 345.619396 -286.286543) (xy 345.615224 -286.2362)
			(xy 126.480908 -286.2362) (xy 126.480925 -286.2364) (xy 126.476749 -286.286791) (xy 126.464335 -286.335808)
			(xy 126.444022 -286.382112) (xy 126.416363 -286.424441) (xy 126.382115 -286.46164) (xy 126.34221 -286.492693)
			(xy 126.297738 -286.516754) (xy 126.249912 -286.533167) (xy 126.200036 -286.541483) (xy 126.174754 -286.541972)
			(xy 125.2347 -286.541972) (xy 125.209424 -286.54143) (xy 125.159563 -286.53311) (xy 125.111751 -286.516696)
			(xy 125.067293 -286.492636) (xy 125.027401 -286.461587) (xy 124.993163 -286.424395) (xy 124.965515 -286.382076)
			(xy 124.945209 -286.335783) (xy 124.932799 -286.286778) (xy 124.928625 -286.2364) (xy 123.660896 -286.2364)
			(xy 123.656722 -286.286777) (xy 123.644314 -286.33578) (xy 123.62401 -286.382073) (xy 123.596364 -286.424392)
			(xy 123.562131 -286.461585) (xy 123.522243 -286.492637) (xy 123.477788 -286.5167) (xy 123.42998 -286.53312)
			(xy 123.380121 -286.541446) (xy 123.354846 -286.541972) (xy 122.414792 -286.541972) (xy 122.389517 -286.541429)
			(xy 122.339656 -286.533108) (xy 122.291845 -286.516693) (xy 122.247388 -286.492633) (xy 122.207498 -286.461584)
			(xy 122.173261 -286.424393) (xy 122.145613 -286.382074) (xy 122.125308 -286.335781) (xy 122.112899 -286.286778)
			(xy 122.108724 -286.2364) (xy 120.840825 -286.2364) (xy 120.836649 -286.286788) (xy 120.824237 -286.335802)
			(xy 120.803926 -286.382104) (xy 120.776271 -286.424431) (xy 120.742026 -286.461629) (xy 120.702126 -286.492683)
			(xy 120.657658 -286.516745) (xy 120.609836 -286.53316) (xy 120.559964 -286.54148) (xy 120.534684 -286.541972)
			(xy 119.59463 -286.541972) (xy 119.56935 -286.541461) (xy 119.51948 -286.533144) (xy 119.47166 -286.516731)
			(xy 119.427193 -286.492671) (xy 119.387293 -286.461619) (xy 119.353048 -286.424423) (xy 119.325394 -286.382098)
			(xy 119.305083 -286.335798) (xy 119.292671 -286.286786) (xy 119.288495 -286.2364) (xy 118.020925 -286.2364)
			(xy 118.016749 -286.286789) (xy 118.004336 -286.335803) (xy 117.984025 -286.382106) (xy 117.956369 -286.424434)
			(xy 117.922123 -286.461632) (xy 117.882222 -286.492685) (xy 117.837753 -286.516748) (xy 117.789929 -286.533162)
			(xy 117.740057 -286.541481) (xy 117.714776 -286.541972) (xy 116.774722 -286.541972) (xy 116.749443 -286.541461)
			(xy 116.699574 -286.533142) (xy 116.651754 -286.516729) (xy 116.607288 -286.492668) (xy 116.56739 -286.461616)
			(xy 116.533146 -286.424421) (xy 116.505492 -286.382096) (xy 116.485183 -286.335796) (xy 116.472771 -286.286785)
			(xy 116.468595 -286.2364) (xy 107.687096 -286.2364) (xy 107.682921 -286.286778) (xy 107.670513 -286.335781)
			(xy 107.650209 -286.382074) (xy 107.622563 -286.424394) (xy 107.588328 -286.461587) (xy 107.54844 -286.492639)
			(xy 107.503984 -286.516702) (xy 107.456175 -286.533121) (xy 107.406315 -286.541447) (xy 107.38104 -286.541972)
			(xy 106.440986 -286.541972) (xy 106.415711 -286.541429) (xy 106.365851 -286.533107) (xy 106.318041 -286.516692)
			(xy 106.273585 -286.492631) (xy 106.233695 -286.461582) (xy 106.19946 -286.424391) (xy 106.171813 -286.382072)
			(xy 106.151508 -286.33578) (xy 106.139099 -286.286777) (xy 106.134924 -286.2364) (xy 104.867196 -286.2364)
			(xy 104.863021 -286.286778) (xy 104.850613 -286.335783) (xy 104.830308 -286.382076) (xy 104.802661 -286.424397)
			(xy 104.768425 -286.46159) (xy 104.728535 -286.492642) (xy 104.684079 -286.516705) (xy 104.636268 -286.533122)
			(xy 104.586407 -286.541448) (xy 104.561132 -286.541972) (xy 103.621078 -286.541972) (xy 103.595804 -286.541428)
			(xy 103.545945 -286.533105) (xy 103.498136 -286.516689) (xy 103.453681 -286.492629) (xy 103.413792 -286.461579)
			(xy 103.379558 -286.424388) (xy 103.351911 -286.38207) (xy 103.331607 -286.335778) (xy 103.319199 -286.286776)
			(xy 103.315024 -286.2364) (xy 102.047296 -286.2364) (xy 102.043121 -286.286779) (xy 102.030712 -286.335784)
			(xy 102.010407 -286.382079) (xy 101.982759 -286.4244) (xy 101.948522 -286.461593) (xy 101.908631 -286.492645)
			(xy 101.864173 -286.516707) (xy 101.816362 -286.533124) (xy 101.7665 -286.541448) (xy 101.741224 -286.541972)
			(xy 100.80117 -286.541972) (xy 100.775896 -286.541428) (xy 100.726038 -286.533103) (xy 100.678231 -286.516687)
			(xy 100.633777 -286.492626) (xy 100.593889 -286.461576) (xy 100.559656 -286.424385) (xy 100.53201 -286.382067)
			(xy 100.511706 -286.335777) (xy 100.499298 -286.286775) (xy 100.495124 -286.2364) (xy 99.227225 -286.2364)
			(xy 99.223049 -286.28679) (xy 99.210635 -286.335806) (xy 99.190323 -286.38211) (xy 99.162665 -286.424438)
			(xy 99.128418 -286.461637) (xy 99.088514 -286.49269) (xy 99.044043 -286.516752) (xy 98.996218 -286.533165)
			(xy 98.946344 -286.541482) (xy 98.921062 -286.541972) (xy 97.981008 -286.541972) (xy 97.95573 -286.54146)
			(xy 97.905862 -286.533139) (xy 97.858045 -286.516725) (xy 97.813581 -286.492663) (xy 97.773684 -286.461611)
			(xy 97.739443 -286.424416) (xy 97.71179 -286.382092) (xy 97.691482 -286.335794) (xy 97.679071 -286.286784)
			(xy 97.674895 -286.2364) (xy 2.509012 -286.2364) (xy 2.509012 -286.832548) (xy 16.85798 -286.832548)
			(xy 16.85798 -286.33801) (xy 16.85829 -286.332566) (xy 16.865997 -286.324877) (xy 16.871442 -286.324548)
			(xy 17.38757 -286.324548) (xy 17.39538 -286.32423) (xy 17.410252 -286.319448) (xy 17.41678 -286.31515)
			(xy 17.437869 -286.300801) (xy 17.48353 -286.27807) (xy 17.532136 -286.262611) (xy 17.582539 -286.254788)
			(xy 17.633545 -286.254788) (xy 17.683948 -286.262611) (xy 17.732554 -286.27807) (xy 17.778215 -286.300801)
			(xy 17.799304 -286.31515) (xy 17.805838 -286.319437) (xy 17.820706 -286.324223) (xy 17.828514 -286.324548)
			(xy 18.344642 -286.324548) (xy 18.350014 -286.325023) (xy 18.357597 -286.332637) (xy 18.358104 -286.33801)
			(xy 18.358104 -286.832548) (xy 24.402288 -286.832548) (xy 24.402288 -286.33801) (xy 24.402736 -286.332696)
			(xy 24.41019 -286.325122) (xy 24.415496 -286.324548) (xy 24.931624 -286.324548) (xy 24.939436 -286.324253)
			(xy 24.954308 -286.319455) (xy 24.960834 -286.31515) (xy 24.981923 -286.300801) (xy 25.027584 -286.27807)
			(xy 25.07619 -286.262611) (xy 25.126593 -286.254788) (xy 25.177599 -286.254788) (xy 25.228002 -286.262611)
			(xy 25.276608 -286.27807) (xy 25.322269 -286.300801) (xy 25.343358 -286.31515) (xy 25.34988 -286.319457)
			(xy 25.364757 -286.324231) (xy 25.372568 -286.324548) (xy 25.888696 -286.324548) (xy 25.893948 -286.325093)
			(xy 25.901388 -286.332506) (xy 25.901904 -286.337756) (xy 25.901904 -286.338264) (xy 25.901904 -286.832548)
			(xy 31.946088 -286.832548) (xy 31.946088 -286.33801) (xy 31.946536 -286.332696) (xy 31.95399 -286.325122)
			(xy 31.959296 -286.324548) (xy 32.475424 -286.324548) (xy 32.483236 -286.324253) (xy 32.498108 -286.319455)
			(xy 32.504634 -286.31515) (xy 32.525723 -286.300801) (xy 32.571384 -286.27807) (xy 32.61999 -286.262611)
			(xy 32.670393 -286.254788) (xy 32.721399 -286.254788) (xy 32.771802 -286.262611) (xy 32.820408 -286.27807)
			(xy 32.866069 -286.300801) (xy 32.887158 -286.31515) (xy 32.89368 -286.319457) (xy 32.908557 -286.324231)
			(xy 32.916368 -286.324548) (xy 33.432496 -286.324548) (xy 33.437748 -286.325093) (xy 33.445188 -286.332506)
			(xy 33.445704 -286.337756) (xy 33.445704 -286.338264) (xy 33.445704 -286.832548) (xy 39.489888 -286.832548)
			(xy 39.489888 -286.33801) (xy 39.490452 -286.332659) (xy 39.498002 -286.325076) (xy 39.50335 -286.324548)
			(xy 40.019478 -286.324548) (xy 40.027288 -286.324234) (xy 40.04216 -286.319449) (xy 40.048688 -286.31515)
			(xy 40.069777 -286.300801) (xy 40.115438 -286.27807) (xy 40.164044 -286.262611) (xy 40.214447 -286.254788)
			(xy 40.265453 -286.254788) (xy 40.315856 -286.262611) (xy 40.364462 -286.27807) (xy 40.410123 -286.300801)
			(xy 40.431212 -286.31515) (xy 40.437745 -286.31944) (xy 40.452614 -286.324225) (xy 40.460422 -286.324548)
			(xy 40.97655 -286.324548) (xy 40.981922 -286.325018) (xy 40.989506 -286.332636) (xy 40.990012 -286.33801)
			(xy 40.990012 -286.832548) (xy 47.034196 -286.832548) (xy 47.034196 -286.33801) (xy 47.034724 -286.332717)
			(xy 47.042123 -286.325148) (xy 47.047404 -286.324548) (xy 47.563532 -286.324548) (xy 47.57134 -286.324214)
			(xy 47.586212 -286.319443) (xy 47.592742 -286.31515) (xy 47.613831 -286.300801) (xy 47.659492 -286.27807)
			(xy 47.708098 -286.262611) (xy 47.758501 -286.254788) (xy 47.809507 -286.254788) (xy 47.85991 -286.262611)
			(xy 47.908516 -286.27807) (xy 47.954177 -286.300801) (xy 47.975266 -286.31515) (xy 47.981809 -286.319422)
			(xy 47.99667 -286.324218) (xy 48.004476 -286.324548) (xy 48.520604 -286.324548) (xy 48.525857 -286.325087)
			(xy 48.533297 -286.332505) (xy 48.533812 -286.337756) (xy 48.533812 -286.338264) (xy 48.533812 -286.832548)
			(xy 54.577996 -286.832548) (xy 54.577996 -286.33801) (xy 54.578553 -286.332657) (xy 54.586107 -286.325074)
			(xy 54.591458 -286.324548) (xy 56.064658 -286.324548) (xy 56.07009 -286.324909) (xy 56.077779 -286.332579)
			(xy 56.07812 -286.33801) (xy 56.07812 -286.832548) (xy 56.077638 -286.837814) (xy 56.070179 -286.845253)
			(xy 56.064912 -286.845756) (xy 54.591458 -286.845756) (xy 54.586148 -286.845304) (xy 54.578579 -286.83785)
			(xy 54.577996 -286.832548) (xy 48.533812 -286.832548) (xy 48.533337 -286.837816) (xy 48.525873 -286.845255)
			(xy 48.520604 -286.845756) (xy 48.00473 -286.845756) (xy 47.996853 -286.84602) (xy 47.981849 -286.85082)
			(xy 47.975266 -286.855154) (xy 47.954189 -286.869546) (xy 47.908544 -286.892374) (xy 47.859938 -286.907932)
			(xy 47.809521 -286.915851) (xy 47.784004 -286.916368) (xy 47.758483 -286.915899) (xy 47.708055 -286.907999)
			(xy 47.659443 -286.892433) (xy 47.613806 -286.869572) (xy 47.592742 -286.855154) (xy 47.586162 -286.850819)
			(xy 47.571153 -286.846044) (xy 47.563278 -286.845756) (xy 47.047404 -286.845756) (xy 47.042153 -286.845208)
			(xy 47.034713 -286.837797) (xy 47.034196 -286.832548) (xy 40.990012 -286.832548) (xy 40.989537 -286.837816)
			(xy 40.982073 -286.845255) (xy 40.976804 -286.845756) (xy 40.976296 -286.845756) (xy 40.460676 -286.845756)
			(xy 40.452801 -286.84604) (xy 40.437797 -286.850826) (xy 40.431212 -286.855154) (xy 40.41015 -286.869569)
			(xy 40.3645 -286.892392) (xy 40.315889 -286.907943) (xy 40.265468 -286.915855) (xy 40.23995 -286.916368)
			(xy 40.21443 -286.915876) (xy 40.164003 -286.907983) (xy 40.115391 -286.892424) (xy 40.069753 -286.869569)
			(xy 40.048688 -286.855154) (xy 40.042098 -286.850837) (xy 40.027097 -286.84605) (xy 40.019224 -286.845756)
			(xy 39.50335 -286.845756) (xy 39.498051 -286.845243) (xy 39.490477 -286.837835) (xy 39.489888 -286.832548)
			(xy 33.445704 -286.832548) (xy 33.445237 -286.837818) (xy 33.437767 -286.845257) (xy 33.432496 -286.845756)
			(xy 32.916622 -286.845756) (xy 32.908749 -286.84606) (xy 32.893745 -286.850832) (xy 32.887158 -286.855154)
			(xy 32.866083 -286.869549) (xy 32.820437 -286.892377) (xy 32.771831 -286.907933) (xy 32.721413 -286.915851)
			(xy 32.695896 -286.916368) (xy 32.670375 -286.915903) (xy 32.619947 -286.908002) (xy 32.571335 -286.892435)
			(xy 32.525698 -286.869573) (xy 32.504634 -286.855154) (xy 32.498033 -286.850855) (xy 32.48304 -286.846057)
			(xy 32.47517 -286.845756) (xy 31.959296 -286.845756) (xy 31.954044 -286.845213) (xy 31.946605 -286.837798)
			(xy 31.946088 -286.832548) (xy 25.901904 -286.832548) (xy 25.901437 -286.837818) (xy 25.893967 -286.845257)
			(xy 25.888696 -286.845756) (xy 25.372822 -286.845756) (xy 25.364949 -286.84606) (xy 25.349945 -286.850832)
			(xy 25.343358 -286.855154) (xy 25.322283 -286.869549) (xy 25.276637 -286.892377) (xy 25.228031 -286.907933)
			(xy 25.177613 -286.915851) (xy 25.152096 -286.916368) (xy 25.126575 -286.915903) (xy 25.076147 -286.908002)
			(xy 25.027535 -286.892435) (xy 24.981898 -286.869573) (xy 24.960834 -286.855154) (xy 24.954233 -286.850855)
			(xy 24.93924 -286.846057) (xy 24.93137 -286.845756) (xy 24.415496 -286.845756) (xy 24.410244 -286.845213)
			(xy 24.402805 -286.837798) (xy 24.402288 -286.832548) (xy 18.358104 -286.832548) (xy 18.357637 -286.837818)
			(xy 18.350167 -286.845257) (xy 18.344896 -286.845756) (xy 18.344388 -286.845756) (xy 17.828768 -286.845756)
			(xy 17.820893 -286.846037) (xy 17.805889 -286.850825) (xy 17.799304 -286.855154) (xy 17.778216 -286.86953)
			(xy 17.732575 -286.892361) (xy 17.683972 -286.907924) (xy 17.633558 -286.915848) (xy 17.608042 -286.916368)
			(xy 17.582522 -286.91588) (xy 17.532094 -286.907986) (xy 17.483483 -286.892426) (xy 17.437845 -286.86957)
			(xy 17.41678 -286.855154) (xy 17.410192 -286.850834) (xy 17.395189 -286.846049) (xy 17.387316 -286.845756)
			(xy 16.871442 -286.845756) (xy 16.866142 -286.845248) (xy 16.858568 -286.837837) (xy 16.85798 -286.832548)
			(xy 2.509012 -286.832548) (xy 2.509012 -287.0462) (xy 108.484876 -287.0462) (xy 108.489052 -286.995814)
			(xy 108.501463 -286.946803) (xy 108.521772 -286.900503) (xy 108.549424 -286.858177) (xy 108.583666 -286.82098)
			(xy 108.623563 -286.789926) (xy 108.668028 -286.765862) (xy 108.715846 -286.749445) (xy 108.765715 -286.741123)
			(xy 108.790994 -286.7406) (xy 109.731048 -286.7406) (xy 109.756319 -286.741202) (xy 109.806169 -286.749527)
			(xy 109.85397 -286.765944) (xy 109.898418 -286.790004) (xy 109.938299 -286.821051) (xy 109.972527 -286.858238)
			(xy 110.000168 -286.900551) (xy 110.020468 -286.946836) (xy 110.032874 -286.995831) (xy 110.037048 -287.0462)
			(xy 114.118547 -287.0462) (xy 114.122723 -286.995807) (xy 114.135137 -286.94679) (xy 114.155449 -286.900484)
			(xy 114.183106 -286.858153) (xy 114.217354 -286.820951) (xy 114.257258 -286.789895) (xy 114.301729 -286.76583)
			(xy 114.349555 -286.749413) (xy 114.399431 -286.741092) (xy 114.424714 -286.7406) (xy 115.364768 -286.7406)
			(xy 115.390045 -286.741166) (xy 115.439911 -286.749483) (xy 115.487728 -286.765894) (xy 115.532191 -286.789952)
			(xy 115.572088 -286.821001) (xy 115.582719 -286.832548) (xy 163.678108 -286.832548) (xy 163.678108 -286.33801)
			(xy 163.678626 -286.332714) (xy 163.686032 -286.325144) (xy 163.691316 -286.324548) (xy 165.164516 -286.324548)
			(xy 165.16977 -286.325079) (xy 165.177209 -286.332503) (xy 165.177724 -286.337756) (xy 165.177724 -286.338264)
			(xy 165.177724 -286.832548) (xy 171.221908 -286.832548) (xy 171.221908 -286.33801) (xy 171.222454 -286.332655)
			(xy 171.230016 -286.32507) (xy 171.23537 -286.324548) (xy 171.751498 -286.324548) (xy 171.759309 -286.324242)
			(xy 171.774181 -286.319452) (xy 171.780708 -286.31515) (xy 171.801797 -286.300801) (xy 171.847458 -286.27807)
			(xy 171.896064 -286.262611) (xy 171.946467 -286.254788) (xy 171.997473 -286.254788) (xy 172.047876 -286.262611)
			(xy 172.096482 -286.27807) (xy 172.142143 -286.300801) (xy 172.163232 -286.31515) (xy 172.16976 -286.319447)
			(xy 172.184633 -286.324227) (xy 172.192442 -286.324548) (xy 172.70857 -286.324548) (xy 172.714003 -286.324901)
			(xy 172.721691 -286.332577) (xy 172.722032 -286.33801) (xy 172.722032 -286.832548) (xy 178.766216 -286.832548)
			(xy 178.766216 -286.33801) (xy 178.766727 -286.332713) (xy 178.774138 -286.325142) (xy 178.779424 -286.324548)
			(xy 179.295552 -286.324548) (xy 179.303361 -286.324223) (xy 179.318233 -286.319446) (xy 179.324762 -286.31515)
			(xy 179.345851 -286.300801) (xy 179.391512 -286.27807) (xy 179.440118 -286.262611) (xy 179.490521 -286.254788)
			(xy 179.541527 -286.254788) (xy 179.59193 -286.262611) (xy 179.640536 -286.27807) (xy 179.686197 -286.300801)
			(xy 179.707286 -286.31515) (xy 179.713824 -286.31943) (xy 179.728689 -286.324221) (xy 179.736496 -286.324548)
			(xy 180.252624 -286.324548) (xy 180.257879 -286.325074) (xy 180.265318 -286.332502) (xy 180.265832 -286.337756)
			(xy 180.265832 -286.338264) (xy 180.265832 -286.832548) (xy 186.310016 -286.832548) (xy 186.310016 -286.33801)
			(xy 186.310555 -286.332653) (xy 186.318122 -286.325068) (xy 186.323478 -286.324548) (xy 186.839606 -286.324548)
			(xy 186.847417 -286.324246) (xy 186.862289 -286.319453) (xy 186.868816 -286.31515) (xy 186.889905 -286.300801)
			(xy 186.935566 -286.27807) (xy 186.984172 -286.262611) (xy 187.034575 -286.254788) (xy 187.085581 -286.254788)
			(xy 187.135984 -286.262611) (xy 187.18459 -286.27807) (xy 187.230251 -286.300801) (xy 187.25134 -286.31515)
			(xy 187.257866 -286.31945) (xy 187.27274 -286.324229) (xy 187.28055 -286.324548) (xy 187.796678 -286.324548)
			(xy 187.802112 -286.324895) (xy 187.8098 -286.332576) (xy 187.81014 -286.33801) (xy 187.81014 -286.832548)
			(xy 193.854324 -286.832548) (xy 193.854324 -286.33801) (xy 193.854828 -286.332711) (xy 193.862244 -286.32514)
			(xy 193.867532 -286.324548) (xy 194.38366 -286.324548) (xy 194.391469 -286.324226) (xy 194.406341 -286.319447)
			(xy 194.41287 -286.31515) (xy 194.433959 -286.300801) (xy 194.47962 -286.27807) (xy 194.528226 -286.262611)
			(xy 194.578629 -286.254788) (xy 194.629635 -286.254788) (xy 194.680038 -286.262611) (xy 194.728644 -286.27807)
			(xy 194.774305 -286.300801) (xy 194.795394 -286.31515) (xy 194.801931 -286.319433) (xy 194.816797 -286.324222)
			(xy 194.824604 -286.324548) (xy 195.340732 -286.324548) (xy 195.345988 -286.325069) (xy 195.353426 -286.3325)
			(xy 195.35394 -286.337756) (xy 195.35394 -286.338264) (xy 195.35394 -286.832548) (xy 201.398124 -286.832548)
			(xy 201.398124 -286.33801) (xy 201.398628 -286.332711) (xy 201.406044 -286.32514) (xy 201.411332 -286.324548)
			(xy 201.92746 -286.324548) (xy 201.935269 -286.324226) (xy 201.950141 -286.319447) (xy 201.95667 -286.31515)
			(xy 201.977759 -286.300801) (xy 202.02342 -286.27807) (xy 202.072026 -286.262611) (xy 202.122429 -286.254788)
			(xy 202.173435 -286.254788) (xy 202.223838 -286.262611) (xy 202.272444 -286.27807) (xy 202.318105 -286.300801)
			(xy 202.339194 -286.31515) (xy 202.345731 -286.319433) (xy 202.360597 -286.324222) (xy 202.368404 -286.324548)
			(xy 202.884532 -286.324548) (xy 202.889788 -286.325069) (xy 202.897226 -286.3325) (xy 202.89774 -286.337756)
			(xy 202.89774 -286.338264) (xy 202.89774 -286.832294) (xy 264.798048 -286.832294) (xy 264.798048 -286.337756)
			(xy 264.798561 -286.332499) (xy 264.805999 -286.325061) (xy 264.811256 -286.324548) (xy 264.811764 -286.324548)
			(xy 265.327638 -286.324548) (xy 265.335447 -286.324217) (xy 265.350318 -286.319444) (xy 265.356848 -286.31515)
			(xy 265.377937 -286.300801) (xy 265.423598 -286.27807) (xy 265.472204 -286.262611) (xy 265.522607 -286.254788)
			(xy 265.573613 -286.254788) (xy 265.624016 -286.262611) (xy 265.672622 -286.27807) (xy 265.718283 -286.300801)
			(xy 265.739372 -286.31515) (xy 265.745913 -286.319424) (xy 265.760776 -286.324219) (xy 265.768582 -286.324548)
			(xy 266.28471 -286.324548) (xy 266.290017 -286.325017) (xy 266.297588 -286.332458) (xy 266.298172 -286.337756)
			(xy 266.298172 -286.832294) (xy 266.298147 -286.832548) (xy 272.342356 -286.832548) (xy 272.342356 -286.83204)
			(xy 272.342356 -286.337756) (xy 272.342862 -286.332497) (xy 272.350304 -286.325059) (xy 272.355564 -286.324548)
			(xy 272.871692 -286.324548) (xy 272.879503 -286.324239) (xy 272.894374 -286.319451) (xy 272.900902 -286.31515)
			(xy 272.921991 -286.300801) (xy 272.967652 -286.27807) (xy 273.016258 -286.262611) (xy 273.066661 -286.254788)
			(xy 273.117667 -286.254788) (xy 273.16807 -286.262611) (xy 273.216676 -286.27807) (xy 273.262337 -286.300801)
			(xy 273.283426 -286.31515) (xy 273.289955 -286.319445) (xy 273.304827 -286.324227) (xy 273.312636 -286.324548)
			(xy 273.828764 -286.324548) (xy 273.834012 -286.325114) (xy 273.841454 -286.332511) (xy 273.841972 -286.337756)
			(xy 273.841972 -286.832294) (xy 273.841948 -286.832548) (xy 279.886156 -286.832548) (xy 279.886156 -286.83204)
			(xy 279.886156 -286.337756) (xy 279.886662 -286.332497) (xy 279.894104 -286.325059) (xy 279.899364 -286.324548)
			(xy 280.415492 -286.324548) (xy 280.423303 -286.324239) (xy 280.438174 -286.319451) (xy 280.444702 -286.31515)
			(xy 280.465791 -286.300801) (xy 280.511452 -286.27807) (xy 280.560058 -286.262611) (xy 280.610461 -286.254788)
			(xy 280.661467 -286.254788) (xy 280.71187 -286.262611) (xy 280.760476 -286.27807) (xy 280.806137 -286.300801)
			(xy 280.827226 -286.31515) (xy 280.833755 -286.319445) (xy 280.848627 -286.324227) (xy 280.856436 -286.324548)
			(xy 281.372564 -286.324548) (xy 281.377812 -286.325114) (xy 281.385254 -286.332511) (xy 281.385772 -286.337756)
			(xy 281.385772 -286.832294) (xy 287.429956 -286.832294) (xy 287.429956 -286.337756) (xy 287.430462 -286.332497)
			(xy 287.437904 -286.325059) (xy 287.443164 -286.324548) (xy 287.443672 -286.324548) (xy 287.959546 -286.324548)
			(xy 287.967355 -286.32422) (xy 287.982227 -286.319445) (xy 287.988756 -286.31515) (xy 288.009845 -286.300801)
			(xy 288.055506 -286.27807) (xy 288.104112 -286.262611) (xy 288.154515 -286.254788) (xy 288.205521 -286.254788)
			(xy 288.255924 -286.262611) (xy 288.30453 -286.27807) (xy 288.350191 -286.300801) (xy 288.37128 -286.31515)
			(xy 288.37782 -286.319427) (xy 288.392683 -286.32422) (xy 288.40049 -286.324548) (xy 288.916618 -286.324548)
			(xy 288.921926 -286.325012) (xy 288.929497 -286.332457) (xy 288.93008 -286.337756) (xy 288.93008 -286.832294)
			(xy 288.930055 -286.832548) (xy 294.974264 -286.832548) (xy 294.974264 -286.83204) (xy 294.974264 -286.337756)
			(xy 294.974763 -286.332495) (xy 294.98221 -286.325056) (xy 294.987472 -286.324548) (xy 295.5036 -286.324548)
			(xy 295.511411 -286.324243) (xy 295.526283 -286.319452) (xy 295.53281 -286.31515) (xy 295.553899 -286.300801)
			(xy 295.59956 -286.27807) (xy 295.648166 -286.262611) (xy 295.698569 -286.254788) (xy 295.749575 -286.254788)
			(xy 295.799978 -286.262611) (xy 295.848584 -286.27807) (xy 295.894245 -286.300801) (xy 295.915334 -286.31515)
			(xy 295.921862 -286.319448) (xy 295.936735 -286.324228) (xy 295.944544 -286.324548) (xy 296.460672 -286.324548)
			(xy 296.465921 -286.325109) (xy 296.473362 -286.33251) (xy 296.47388 -286.337756) (xy 296.47388 -286.832294)
			(xy 302.518064 -286.832294) (xy 302.518064 -286.337756) (xy 302.518563 -286.332495) (xy 302.52601 -286.325056)
			(xy 302.531272 -286.324548) (xy 304.004726 -286.324548) (xy 304.010035 -286.325007) (xy 304.017605 -286.332456)
			(xy 304.018188 -286.337756) (xy 304.018188 -286.832294) (xy 304.017648 -286.837651) (xy 304.010082 -286.845236)
			(xy 304.004726 -286.845756) (xy 302.531526 -286.845756) (xy 302.526093 -286.845403) (xy 302.518405 -286.837726)
			(xy 302.518064 -286.832294) (xy 296.47388 -286.832294) (xy 296.473375 -286.837593) (xy 296.46596 -286.845163)
			(xy 296.460672 -286.845756) (xy 295.944798 -286.845756) (xy 295.936987 -286.84606) (xy 295.922115 -286.850852)
			(xy 295.915588 -286.855154) (xy 295.894467 -286.869505) (xy 295.848743 -286.892231) (xy 295.80007 -286.907661)
			(xy 295.749603 -286.915427) (xy 295.724072 -286.91586) (xy 295.698541 -286.915438) (xy 295.648077 -286.907658)
			(xy 295.599404 -286.892225) (xy 295.553677 -286.869504) (xy 295.532556 -286.855154) (xy 295.52603 -286.850852)
			(xy 295.511156 -286.846075) (xy 295.503346 -286.845756) (xy 294.987472 -286.845756) (xy 294.982217 -286.845229)
			(xy 294.974779 -286.837802) (xy 294.974264 -286.832548) (xy 288.930055 -286.832548) (xy 288.929548 -286.837653)
			(xy 288.921976 -286.845238) (xy 288.916618 -286.845756) (xy 288.400744 -286.845756) (xy 288.392935 -286.846079)
			(xy 288.378063 -286.850858) (xy 288.371534 -286.855154) (xy 288.350429 -286.869528) (xy 288.304699 -286.892249)
			(xy 288.256021 -286.907672) (xy 288.20555 -286.915431) (xy 288.180018 -286.91586) (xy 288.154488 -286.915415)
			(xy 288.104025 -286.907642) (xy 288.055352 -286.892215) (xy 288.009624 -286.869501) (xy 287.988502 -286.855154)
			(xy 287.981966 -286.85087) (xy 287.9671 -286.846082) (xy 287.959292 -286.845756) (xy 287.443418 -286.845756)
			(xy 287.437984 -286.845408) (xy 287.430297 -286.837728) (xy 287.429956 -286.832294) (xy 281.385772 -286.832294)
			(xy 281.385274 -286.837595) (xy 281.377854 -286.845165) (xy 281.372564 -286.845756) (xy 280.85669 -286.845756)
			(xy 280.848878 -286.846056) (xy 280.834007 -286.85085) (xy 280.82748 -286.855154) (xy 280.806362 -286.869508)
			(xy 280.760637 -286.892234) (xy 280.711962 -286.907662) (xy 280.661495 -286.915428) (xy 280.635964 -286.91586)
			(xy 280.610433 -286.915442) (xy 280.559968 -286.907661) (xy 280.511296 -286.892226) (xy 280.465569 -286.869504)
			(xy 280.444448 -286.855154) (xy 280.437924 -286.850849) (xy 280.423048 -286.846074) (xy 280.415238 -286.845756)
			(xy 279.899364 -286.845756) (xy 279.894109 -286.845234) (xy 279.886671 -286.837803) (xy 279.886156 -286.832548)
			(xy 273.841948 -286.832548) (xy 273.841474 -286.837595) (xy 273.834054 -286.845165) (xy 273.828764 -286.845756)
			(xy 273.31289 -286.845756) (xy 273.305078 -286.846056) (xy 273.290207 -286.85085) (xy 273.28368 -286.855154)
			(xy 273.262562 -286.869508) (xy 273.216837 -286.892234) (xy 273.168162 -286.907662) (xy 273.117695 -286.915428)
			(xy 273.092164 -286.91586) (xy 273.066633 -286.915442) (xy 273.016168 -286.907661) (xy 272.967496 -286.892226)
			(xy 272.921769 -286.869504) (xy 272.900648 -286.855154) (xy 272.894124 -286.850849) (xy 272.879248 -286.846074)
			(xy 272.871438 -286.845756) (xy 272.355564 -286.845756) (xy 272.350309 -286.845234) (xy 272.342871 -286.837803)
			(xy 272.342356 -286.832548) (xy 266.298147 -286.832548) (xy 266.297647 -286.837655) (xy 266.29007 -286.84524)
			(xy 266.28471 -286.845756) (xy 265.768836 -286.845756) (xy 265.761026 -286.846076) (xy 265.746155 -286.850857)
			(xy 265.739626 -286.855154) (xy 265.718495 -286.869488) (xy 265.672774 -286.892218) (xy 265.624104 -286.907653)
			(xy 265.57364 -286.915424) (xy 265.54811 -286.91586) (xy 265.52258 -286.915419) (xy 265.472116 -286.907645)
			(xy 265.423444 -286.892217) (xy 265.377716 -286.869501) (xy 265.356594 -286.855154) (xy 265.35006 -286.850867)
			(xy 265.335192 -286.84608) (xy 265.327384 -286.845756) (xy 264.81151 -286.845756) (xy 264.806075 -286.845414)
			(xy 264.798388 -286.837729) (xy 264.798048 -286.832294) (xy 202.89774 -286.832294) (xy 202.89774 -286.832548)
			(xy 202.89724 -286.837809) (xy 202.889793 -286.845247) (xy 202.884532 -286.845756) (xy 202.368658 -286.845756)
			(xy 202.360782 -286.846032) (xy 202.345779 -286.850824) (xy 202.339194 -286.855154) (xy 202.318109 -286.869534)
			(xy 202.272467 -286.892365) (xy 202.223863 -286.907926) (xy 202.173448 -286.915849) (xy 202.147932 -286.916368)
			(xy 202.122411 -286.915885) (xy 202.071984 -286.90799) (xy 202.023372 -286.892428) (xy 201.977734 -286.869571)
			(xy 201.95667 -286.855154) (xy 201.950084 -286.85083) (xy 201.93508 -286.846048) (xy 201.927206 -286.845756)
			(xy 201.411332 -286.845756) (xy 201.406084 -286.845189) (xy 201.398643 -286.837792) (xy 201.398124 -286.832548)
			(xy 195.35394 -286.832548) (xy 195.35344 -286.837809) (xy 195.345993 -286.845247) (xy 195.340732 -286.845756)
			(xy 194.824858 -286.845756) (xy 194.816982 -286.846032) (xy 194.801979 -286.850824) (xy 194.795394 -286.855154)
			(xy 194.774309 -286.869534) (xy 194.728667 -286.892365) (xy 194.680063 -286.907926) (xy 194.629648 -286.915849)
			(xy 194.604132 -286.916368) (xy 194.578611 -286.915885) (xy 194.528184 -286.90799) (xy 194.479572 -286.892428)
			(xy 194.433934 -286.869571) (xy 194.41287 -286.855154) (xy 194.406284 -286.85083) (xy 194.39128 -286.846048)
			(xy 194.383406 -286.845756) (xy 193.867532 -286.845756) (xy 193.862284 -286.845189) (xy 193.854843 -286.837792)
			(xy 193.854324 -286.832548) (xy 187.81014 -286.832548) (xy 187.80964 -286.837809) (xy 187.802193 -286.845247)
			(xy 187.796932 -286.845756) (xy 187.796424 -286.845756) (xy 187.280804 -286.845756) (xy 187.27293 -286.846052)
			(xy 187.257926 -286.85083) (xy 187.25134 -286.855154) (xy 187.23027 -286.869557) (xy 187.184622 -286.892383)
			(xy 187.136014 -286.907937) (xy 187.085595 -286.915853) (xy 187.060078 -286.916368) (xy 187.034558 -286.915862)
			(xy 186.984132 -286.907973) (xy 186.93552 -286.892418) (xy 186.889881 -286.869568) (xy 186.868816 -286.855154)
			(xy 186.862219 -286.850848) (xy 186.847223 -286.846055) (xy 186.839352 -286.845756) (xy 186.323478 -286.845756)
			(xy 186.31817 -286.845291) (xy 186.3106 -286.837847) (xy 186.310016 -286.832548) (xy 180.265832 -286.832548)
			(xy 180.265339 -286.837811) (xy 180.257888 -286.845249) (xy 180.252624 -286.845756) (xy 179.73675 -286.845756)
			(xy 179.728874 -286.846029) (xy 179.71387 -286.850823) (xy 179.707286 -286.855154) (xy 179.686203 -286.869537)
			(xy 179.64056 -286.892367) (xy 179.591956 -286.907927) (xy 179.54154 -286.915849) (xy 179.516024 -286.916368)
			(xy 179.490503 -286.915889) (xy 179.440076 -286.907992) (xy 179.391464 -286.892429) (xy 179.345826 -286.869571)
			(xy 179.324762 -286.855154) (xy 179.318178 -286.850827) (xy 179.303172 -286.846047) (xy 179.295298 -286.845756)
			(xy 178.779424 -286.845756) (xy 178.774176 -286.845194) (xy 178.766735 -286.837793) (xy 178.766216 -286.832548)
			(xy 172.722032 -286.832548) (xy 172.721539 -286.837811) (xy 172.714088 -286.845249) (xy 172.708824 -286.845756)
			(xy 172.708316 -286.845756) (xy 172.192696 -286.845756) (xy 172.184822 -286.846049) (xy 172.169818 -286.850829)
			(xy 172.163232 -286.855154) (xy 172.142164 -286.869561) (xy 172.096516 -286.892385) (xy 172.047907 -286.907939)
			(xy 171.997488 -286.915853) (xy 171.97197 -286.916368) (xy 171.94645 -286.915866) (xy 171.896024 -286.907976)
			(xy 171.847412 -286.89242) (xy 171.801773 -286.869568) (xy 171.780708 -286.855154) (xy 171.774113 -286.850845)
			(xy 171.759116 -286.846053) (xy 171.751244 -286.845756) (xy 171.23537 -286.845756) (xy 171.230061 -286.845296)
			(xy 171.222491 -286.837848) (xy 171.221908 -286.832548) (xy 165.177724 -286.832548) (xy 165.177239 -286.837813)
			(xy 165.169782 -286.845251) (xy 165.164516 -286.845756) (xy 163.691316 -286.845756) (xy 163.686067 -286.8452)
			(xy 163.678626 -286.837795) (xy 163.678108 -286.832548) (xy 115.582719 -286.832548) (xy 115.606329 -286.858193)
			(xy 115.633981 -286.900515) (xy 115.65429 -286.946811) (xy 115.666701 -286.995818) (xy 115.670852 -287.0459)
			(xy 356.425277 -287.0459) (xy 356.429447 -286.995567) (xy 356.441845 -286.946607) (xy 356.462131 -286.900355)
			(xy 356.489753 -286.858072) (xy 356.523957 -286.820912) (xy 356.563811 -286.789888) (xy 356.608227 -286.765847)
			(xy 356.655994 -286.749443) (xy 356.705809 -286.741125) (xy 356.731062 -286.7406) (xy 357.671116 -286.7406)
			(xy 357.696371 -286.741107) (xy 357.746192 -286.749423) (xy 357.793965 -286.765826) (xy 357.838387 -286.789867)
			(xy 357.878245 -286.820893) (xy 357.912454 -286.858055) (xy 357.94008 -286.900341) (xy 357.960369 -286.946597)
			(xy 357.972768 -286.995562) (xy 357.976939 -287.0459) (xy 362.058977 -287.0459) (xy 362.063148 -286.995565)
			(xy 362.075546 -286.946603) (xy 362.095834 -286.900349) (xy 362.123458 -286.858066) (xy 362.157665 -286.820905)
			(xy 362.197521 -286.789881) (xy 362.24194 -286.765841) (xy 362.28971 -286.749439) (xy 362.339528 -286.741123)
			(xy 362.364782 -286.7406) (xy 363.304836 -286.7406) (xy 363.33009 -286.741108) (xy 363.379908 -286.749427)
			(xy 363.427678 -286.765831) (xy 363.472097 -286.789874) (xy 363.511953 -286.8209) (xy 363.522674 -286.832548)
			(xy 411.618176 -286.832548) (xy 411.618176 -286.83204) (xy 411.618176 -286.337756) (xy 411.618664 -286.332492)
			(xy 411.626119 -286.325053) (xy 411.631384 -286.324548) (xy 413.104584 -286.324548) (xy 413.109834 -286.325101)
			(xy 413.117275 -286.332508) (xy 413.117792 -286.337756) (xy 413.117792 -286.832294) (xy 419.161976 -286.832294)
			(xy 419.161976 -286.337756) (xy 419.162464 -286.332492) (xy 419.169919 -286.325053) (xy 419.175184 -286.324548)
			(xy 419.175692 -286.324548) (xy 419.691566 -286.324548) (xy 419.699376 -286.324228) (xy 419.714247 -286.319447)
			(xy 419.720776 -286.31515) (xy 419.741865 -286.300801) (xy 419.787526 -286.27807) (xy 419.836132 -286.262611)
			(xy 419.886535 -286.254788) (xy 419.937541 -286.254788) (xy 419.987944 -286.262611) (xy 420.03655 -286.27807)
			(xy 420.082211 -286.300801) (xy 420.1033 -286.31515) (xy 420.109835 -286.319435) (xy 420.124702 -286.324223)
			(xy 420.13251 -286.324548) (xy 420.648638 -286.324548) (xy 420.653949 -286.324999) (xy 420.661518 -286.332454)
			(xy 420.6621 -286.337756) (xy 420.6621 -286.832294) (xy 420.662074 -286.832548) (xy 426.706284 -286.832548)
			(xy 426.706284 -286.83204) (xy 426.706284 -286.337756) (xy 426.706765 -286.33249) (xy 426.714225 -286.32505)
			(xy 426.719492 -286.324548) (xy 427.23562 -286.324548) (xy 427.243432 -286.324252) (xy 427.258304 -286.319455)
			(xy 427.26483 -286.31515) (xy 427.285919 -286.300801) (xy 427.33158 -286.27807) (xy 427.380186 -286.262611)
			(xy 427.430589 -286.254788) (xy 427.481595 -286.254788) (xy 427.531998 -286.262611) (xy 427.580604 -286.27807)
			(xy 427.626265 -286.300801) (xy 427.647354 -286.31515) (xy 427.653877 -286.319456) (xy 427.668753 -286.324231)
			(xy 427.676564 -286.324548) (xy 428.192692 -286.324548) (xy 428.197943 -286.325095) (xy 428.205384 -286.332507)
			(xy 428.2059 -286.337756) (xy 428.2059 -286.832294) (xy 434.250084 -286.832294) (xy 434.250084 -286.337756)
			(xy 434.250565 -286.33249) (xy 434.258025 -286.32505) (xy 434.263292 -286.324548) (xy 434.2638 -286.324548)
			(xy 434.779674 -286.324548) (xy 434.787484 -286.324232) (xy 434.802356 -286.319448) (xy 434.808884 -286.31515)
			(xy 434.829973 -286.300801) (xy 434.875634 -286.27807) (xy 434.92424 -286.262611) (xy 434.974643 -286.254788)
			(xy 435.025649 -286.254788) (xy 435.076052 -286.262611) (xy 435.124658 -286.27807) (xy 435.170319 -286.300801)
			(xy 435.191408 -286.31515) (xy 435.197941 -286.319438) (xy 435.21281 -286.324224) (xy 435.220618 -286.324548)
			(xy 435.736746 -286.324548) (xy 435.742046 -286.32506) (xy 435.74962 -286.332468) (xy 435.750208 -286.337756)
			(xy 435.750208 -286.832294) (xy 435.750182 -286.832548) (xy 441.794392 -286.832548) (xy 441.794392 -286.83204)
			(xy 441.794392 -286.337756) (xy 441.794866 -286.332488) (xy 441.80233 -286.325048) (xy 441.8076 -286.324548)
			(xy 442.323728 -286.324548) (xy 442.33154 -286.324255) (xy 442.346412 -286.319456) (xy 442.352938 -286.31515)
			(xy 442.374027 -286.300801) (xy 442.419688 -286.27807) (xy 442.468294 -286.262611) (xy 442.518697 -286.254788)
			(xy 442.569703 -286.254788) (xy 442.620106 -286.262611) (xy 442.668712 -286.27807) (xy 442.714373 -286.300801)
			(xy 442.735462 -286.31515) (xy 442.742006 -286.319421) (xy 442.756866 -286.324217) (xy 442.764672 -286.324548)
			(xy 443.2808 -286.324548) (xy 443.286052 -286.32509) (xy 443.293492 -286.332506) (xy 443.294008 -286.337756)
			(xy 443.294008 -286.832294) (xy 443.293983 -286.832548) (xy 449.338192 -286.832548) (xy 449.338192 -286.83204)
			(xy 449.338192 -286.337756) (xy 449.338666 -286.332488) (xy 449.34613 -286.325048) (xy 449.3514 -286.324548)
			(xy 449.867528 -286.324548) (xy 449.87534 -286.324255) (xy 449.890212 -286.319456) (xy 449.896738 -286.31515)
			(xy 449.917827 -286.300801) (xy 449.963488 -286.27807) (xy 450.012094 -286.262611) (xy 450.062497 -286.254788)
			(xy 450.113503 -286.254788) (xy 450.163906 -286.262611) (xy 450.212512 -286.27807) (xy 450.258173 -286.300801)
			(xy 450.279262 -286.31515) (xy 450.285806 -286.319421) (xy 450.300666 -286.324217) (xy 450.308472 -286.324548)
			(xy 450.8246 -286.324548) (xy 450.829852 -286.32509) (xy 450.837292 -286.332506) (xy 450.837808 -286.337756)
			(xy 450.837808 -286.832294) (xy 450.837279 -286.837586) (xy 450.82988 -286.845155) (xy 450.8246 -286.845756)
			(xy 450.308726 -286.845756) (xy 450.300916 -286.846071) (xy 450.286044 -286.850855) (xy 450.279516 -286.855154)
			(xy 450.258388 -286.869493) (xy 450.212666 -286.892222) (xy 450.163995 -286.907655) (xy 450.11353 -286.915425)
			(xy 450.088 -286.91586) (xy 450.06247 -286.915424) (xy 450.012006 -286.907648) (xy 449.963333 -286.892219)
			(xy 449.917606 -286.869502) (xy 449.896484 -286.855154) (xy 449.889952 -286.850863) (xy 449.875083 -286.846079)
			(xy 449.867274 -286.845756) (xy 449.3514 -286.845756) (xy 449.346149 -286.84521) (xy 449.338709 -286.837797)
			(xy 449.338192 -286.832548) (xy 443.293983 -286.832548) (xy 443.293479 -286.837586) (xy 443.28608 -286.845155)
			(xy 443.2808 -286.845756) (xy 442.764926 -286.845756) (xy 442.757116 -286.846071) (xy 442.742244 -286.850855)
			(xy 442.735716 -286.855154) (xy 442.714588 -286.869493) (xy 442.668866 -286.892222) (xy 442.620195 -286.907655)
			(xy 442.56973 -286.915425) (xy 442.5442 -286.91586) (xy 442.51867 -286.915424) (xy 442.468206 -286.907648)
			(xy 442.419533 -286.892219) (xy 442.373806 -286.869502) (xy 442.352684 -286.855154) (xy 442.346152 -286.850863)
			(xy 442.331283 -286.846079) (xy 442.323474 -286.845756) (xy 441.8076 -286.845756) (xy 441.802349 -286.84521)
			(xy 441.794909 -286.837797) (xy 441.794392 -286.832548) (xy 435.750182 -286.832548) (xy 435.74965 -286.837646)
			(xy 435.742096 -286.84523) (xy 435.736746 -286.845756) (xy 435.220872 -286.845756) (xy 435.21306 -286.846048)
			(xy 435.198188 -286.850848) (xy 435.191662 -286.855154) (xy 435.170549 -286.869516) (xy 435.124822 -286.89224)
			(xy 435.076146 -286.907666) (xy 435.025678 -286.915429) (xy 435.000146 -286.91586) (xy 434.974617 -286.915401)
			(xy 434.924154 -286.907632) (xy 434.875481 -286.89221) (xy 434.829753 -286.869499) (xy 434.80863 -286.855154)
			(xy 434.802088 -286.850881) (xy 434.787226 -286.846086) (xy 434.77942 -286.845756) (xy 434.263546 -286.845756)
			(xy 434.258116 -286.845389) (xy 434.250427 -286.837723) (xy 434.250084 -286.832294) (xy 428.2059 -286.832294)
			(xy 428.205378 -286.837588) (xy 428.197974 -286.845157) (xy 428.192692 -286.845756) (xy 427.676818 -286.845756)
			(xy 427.669008 -286.846068) (xy 427.654136 -286.850854) (xy 427.647608 -286.855154) (xy 427.626482 -286.869496)
			(xy 427.58076 -286.892224) (xy 427.532088 -286.907656) (xy 427.481623 -286.915426) (xy 427.456092 -286.91586)
			(xy 427.430562 -286.915428) (xy 427.380097 -286.907651) (xy 427.331425 -286.892221) (xy 427.285698 -286.869502)
			(xy 427.264576 -286.855154) (xy 427.258046 -286.85086) (xy 427.243175 -286.846078) (xy 427.235366 -286.845756)
			(xy 426.719492 -286.845756) (xy 426.71424 -286.845216) (xy 426.7068 -286.837799) (xy 426.706284 -286.832548)
			(xy 420.662074 -286.832548) (xy 420.66155 -286.837648) (xy 420.65399 -286.845232) (xy 420.648638 -286.845756)
			(xy 420.132764 -286.845756) (xy 420.124955 -286.846088) (xy 420.110083 -286.85086) (xy 420.103554 -286.855154)
			(xy 420.082443 -286.86952) (xy 420.036715 -286.892243) (xy 419.988039 -286.907668) (xy 419.93757 -286.91543)
			(xy 419.912038 -286.91586) (xy 419.886508 -286.915405) (xy 419.836045 -286.907635) (xy 419.787373 -286.892211)
			(xy 419.741645 -286.869499) (xy 419.720522 -286.855154) (xy 419.713982 -286.850878) (xy 419.699119 -286.846085)
			(xy 419.691312 -286.845756) (xy 419.175438 -286.845756) (xy 419.170007 -286.845395) (xy 419.162318 -286.837724)
			(xy 419.161976 -286.832294) (xy 413.117792 -286.832294) (xy 413.117277 -286.83759) (xy 413.109868 -286.84516)
			(xy 413.104584 -286.845756) (xy 411.631384 -286.845756) (xy 411.626131 -286.845221) (xy 411.618692 -286.8378)
			(xy 411.618176 -286.832548) (xy 363.522674 -286.832548) (xy 363.546159 -286.858062) (xy 363.573783 -286.900347)
			(xy 363.59407 -286.946601) (xy 363.606468 -286.995564) (xy 363.610639 -287.0459) (xy 363.606468 -287.096236)
			(xy 363.59407 -287.145199) (xy 363.573783 -287.191453) (xy 363.546159 -287.233738) (xy 363.511953 -287.2709)
			(xy 363.472097 -287.301926) (xy 363.427678 -287.325969) (xy 363.379908 -287.342373) (xy 363.33009 -287.350692)
			(xy 363.304836 -287.351216) (xy 362.364782 -287.351216) (xy 362.339528 -287.350677) (xy 362.28971 -287.342361)
			(xy 362.24194 -287.325959) (xy 362.197521 -287.301919) (xy 362.157665 -287.270895) (xy 362.123458 -287.233734)
			(xy 362.095834 -287.191451) (xy 362.075546 -287.145197) (xy 362.063148 -287.096235) (xy 362.058977 -287.0459)
			(xy 357.976939 -287.0459) (xy 357.972768 -287.096238) (xy 357.960369 -287.145203) (xy 357.94008 -287.191459)
			(xy 357.912454 -287.233745) (xy 357.878245 -287.270907) (xy 357.838387 -287.301933) (xy 357.793965 -287.325974)
			(xy 357.746192 -287.342377) (xy 357.696371 -287.350693) (xy 357.671116 -287.351216) (xy 356.731062 -287.351216)
			(xy 356.705809 -287.350675) (xy 356.655994 -287.342357) (xy 356.608227 -287.325953) (xy 356.563811 -287.301912)
			(xy 356.523957 -287.270888) (xy 356.489753 -287.233728) (xy 356.462131 -287.191445) (xy 356.441845 -287.145193)
			(xy 356.429447 -287.096233) (xy 356.425277 -287.0459) (xy 115.670852 -287.0459) (xy 115.670877 -287.0462)
			(xy 115.666701 -287.096582) (xy 115.65429 -287.145589) (xy 115.633981 -287.191885) (xy 115.606329 -287.234207)
			(xy 115.572088 -287.271399) (xy 115.532191 -287.302448) (xy 115.487728 -287.326506) (xy 115.439911 -287.342917)
			(xy 115.390045 -287.351234) (xy 115.364768 -287.351724) (xy 114.424714 -287.351724) (xy 114.399431 -287.351308)
			(xy 114.349555 -287.342987) (xy 114.301729 -287.32657) (xy 114.257258 -287.302505) (xy 114.217354 -287.271449)
			(xy 114.183106 -287.234247) (xy 114.155449 -287.191916) (xy 114.135137 -287.14561) (xy 114.122723 -287.096593)
			(xy 114.118547 -287.0462) (xy 110.037048 -287.0462) (xy 110.032874 -287.096569) (xy 110.020468 -287.145564)
			(xy 110.000168 -287.191849) (xy 109.972527 -287.234162) (xy 109.938299 -287.271349) (xy 109.898418 -287.302396)
			(xy 109.85397 -287.326456) (xy 109.806169 -287.342873) (xy 109.756319 -287.351198) (xy 109.731048 -287.351724)
			(xy 108.790994 -287.351724) (xy 108.765715 -287.351277) (xy 108.715846 -287.342955) (xy 108.668028 -287.326538)
			(xy 108.623563 -287.302474) (xy 108.583666 -287.27142) (xy 108.549424 -287.234223) (xy 108.521772 -287.191897)
			(xy 108.501463 -287.145597) (xy 108.489052 -287.096586) (xy 108.484876 -287.0462) (xy 2.509012 -287.0462)
			(xy 2.509012 -287.682432) (xy 20.958048 -287.682432) (xy 20.958048 -287.187894) (xy 20.958376 -287.182456)
			(xy 20.966072 -287.17477) (xy 20.97151 -287.174432) (xy 21.487638 -287.174432) (xy 21.495447 -287.174103)
			(xy 21.510319 -287.169329) (xy 21.516848 -287.165034) (xy 21.537937 -287.150685) (xy 21.583598 -287.127954)
			(xy 21.632204 -287.112495) (xy 21.682607 -287.104672) (xy 21.733613 -287.104672) (xy 21.784016 -287.112495)
			(xy 21.832622 -287.127954) (xy 21.878283 -287.150685) (xy 21.899372 -287.165034) (xy 21.905914 -287.169307)
			(xy 21.920776 -287.174102) (xy 21.928582 -287.174432) (xy 22.44471 -287.174432) (xy 22.450074 -287.174943)
			(xy 22.457658 -287.18253) (xy 22.458172 -287.187894) (xy 22.458172 -287.682432) (xy 28.502356 -287.682432)
			(xy 28.502356 -287.187894) (xy 28.502821 -287.182585) (xy 28.510264 -287.175014) (xy 28.515564 -287.174432)
			(xy 29.031692 -287.174432) (xy 29.039503 -287.174126) (xy 29.054375 -287.169336) (xy 29.060902 -287.165034)
			(xy 29.081991 -287.150685) (xy 29.127652 -287.127954) (xy 29.176258 -287.112495) (xy 29.226661 -287.104672)
			(xy 29.277667 -287.104672) (xy 29.32807 -287.112495) (xy 29.376676 -287.127954) (xy 29.422337 -287.150685)
			(xy 29.443426 -287.165034) (xy 29.449956 -287.169328) (xy 29.464827 -287.17411) (xy 29.472636 -287.174432)
			(xy 29.988764 -287.174432) (xy 29.994101 -287.174755) (xy 30.001647 -287.182303) (xy 30.001972 -287.18764)
			(xy 30.001972 -287.188148) (xy 30.001972 -287.682432) (xy 36.046156 -287.682432) (xy 36.046156 -287.187894)
			(xy 36.046621 -287.182585) (xy 36.054064 -287.175014) (xy 36.059364 -287.174432) (xy 36.575492 -287.174432)
			(xy 36.583303 -287.174126) (xy 36.598175 -287.169336) (xy 36.604702 -287.165034) (xy 36.625791 -287.150685)
			(xy 36.671452 -287.127954) (xy 36.720058 -287.112495) (xy 36.770461 -287.104672) (xy 36.821467 -287.104672)
			(xy 36.87187 -287.112495) (xy 36.920476 -287.127954) (xy 36.966137 -287.150685) (xy 36.987226 -287.165034)
			(xy 36.993756 -287.169328) (xy 37.008627 -287.17411) (xy 37.016436 -287.174432) (xy 37.532564 -287.174432)
			(xy 37.537901 -287.174755) (xy 37.545447 -287.182303) (xy 37.545772 -287.18764) (xy 37.545772 -287.188148)
			(xy 37.545772 -287.682432) (xy 43.589956 -287.682432) (xy 43.589956 -287.187894) (xy 43.590277 -287.182454)
			(xy 43.597977 -287.174767) (xy 43.603418 -287.174432) (xy 44.119546 -287.174432) (xy 44.127355 -287.174107)
			(xy 44.142227 -287.16933) (xy 44.148756 -287.165034) (xy 44.169845 -287.150685) (xy 44.215506 -287.127954)
			(xy 44.264112 -287.112495) (xy 44.314515 -287.104672) (xy 44.365521 -287.104672) (xy 44.415924 -287.112495)
			(xy 44.46453 -287.127954) (xy 44.510191 -287.150685) (xy 44.53128 -287.165034) (xy 44.537821 -287.16931)
			(xy 44.552683 -287.174104) (xy 44.56049 -287.174432) (xy 45.076618 -287.174432) (xy 45.081983 -287.174938)
			(xy 45.089567 -287.182529) (xy 45.09008 -287.187894) (xy 45.09008 -287.682432) (xy 51.134264 -287.682432)
			(xy 51.134264 -287.187894) (xy 51.134722 -287.182583) (xy 51.14217 -287.175011) (xy 51.147472 -287.174432)
			(xy 51.6636 -287.174432) (xy 51.671411 -287.17413) (xy 51.686283 -287.169337) (xy 51.69281 -287.165034)
			(xy 51.713899 -287.150685) (xy 51.75956 -287.127954) (xy 51.808166 -287.112495) (xy 51.858569 -287.104672)
			(xy 51.909575 -287.104672) (xy 51.959978 -287.112495) (xy 52.008584 -287.127954) (xy 52.054245 -287.150685)
			(xy 52.075334 -287.165034) (xy 52.081863 -287.169331) (xy 52.096735 -287.174112) (xy 52.104544 -287.174432)
			(xy 52.620672 -287.174432) (xy 52.62601 -287.174749) (xy 52.633555 -287.182301) (xy 52.63388 -287.18764)
			(xy 52.63388 -287.188148) (xy 52.63388 -287.682432) (xy 58.678064 -287.682432) (xy 58.678064 -287.187894)
			(xy 58.678378 -287.182452) (xy 58.686083 -287.174765) (xy 58.691526 -287.174432) (xy 60.164726 -287.174432)
			(xy 60.170092 -287.174933) (xy 60.177675 -287.182528) (xy 60.178188 -287.187894) (xy 60.178188 -287.682432)
			(xy 60.177725 -287.687703) (xy 60.170253 -287.695145) (xy 60.16498 -287.69564) (xy 60.164472 -287.69564)
			(xy 58.691526 -287.69564) (xy 58.68622 -287.695157) (xy 58.678647 -287.687727) (xy 58.678064 -287.682432)
			(xy 52.63388 -287.682432) (xy 52.633424 -287.687705) (xy 52.625948 -287.695148) (xy 52.620672 -287.69564)
			(xy 52.104798 -287.69564) (xy 52.096924 -287.695936) (xy 52.08192 -287.700714) (xy 52.075334 -287.705038)
			(xy 52.054265 -287.719442) (xy 52.008617 -287.742268) (xy 51.960008 -287.757822) (xy 51.909589 -287.765737)
			(xy 51.884072 -287.766252) (xy 51.858553 -287.765734) (xy 51.808128 -287.757846) (xy 51.759516 -287.742294)
			(xy 51.713876 -287.719449) (xy 51.69281 -287.705038) (xy 51.686216 -287.700728) (xy 51.671218 -287.695937)
			(xy 51.663346 -287.69564) (xy 51.147472 -287.69564) (xy 51.142214 -287.695127) (xy 51.134774 -287.68769)
			(xy 51.134264 -287.682432) (xy 45.09008 -287.682432) (xy 45.089624 -287.687705) (xy 45.082148 -287.695148)
			(xy 45.076872 -287.69564) (xy 45.076364 -287.69564) (xy 44.560744 -287.69564) (xy 44.552868 -287.695913)
			(xy 44.537864 -287.700707) (xy 44.53128 -287.705038) (xy 44.510198 -287.719422) (xy 44.464555 -287.742252)
			(xy 44.41595 -287.757812) (xy 44.365534 -287.765734) (xy 44.340018 -287.766252) (xy 44.314498 -287.765761)
			(xy 44.264072 -287.757865) (xy 44.21546 -287.742305) (xy 44.169821 -287.719452) (xy 44.148756 -287.705038)
			(xy 44.142174 -287.700707) (xy 44.127167 -287.69593) (xy 44.119292 -287.69564) (xy 43.603418 -287.69564)
			(xy 43.598111 -287.695163) (xy 43.590538 -287.687729) (xy 43.589956 -287.682432) (xy 37.545772 -287.682432)
			(xy 37.545491 -287.687777) (xy 37.537911 -287.695318) (xy 37.532564 -287.69564) (xy 37.01669 -287.69564)
			(xy 37.008816 -287.695933) (xy 36.993812 -287.700713) (xy 36.987226 -287.705038) (xy 36.966159 -287.719445)
			(xy 36.92051 -287.74227) (xy 36.871901 -287.757824) (xy 36.821482 -287.765738) (xy 36.795964 -287.766252)
			(xy 36.770445 -287.765738) (xy 36.720019 -287.757849) (xy 36.671408 -287.742296) (xy 36.625768 -287.719449)
			(xy 36.604702 -287.705038) (xy 36.598109 -287.700725) (xy 36.58311 -287.695936) (xy 36.575238 -287.69564)
			(xy 36.059364 -287.69564) (xy 36.054105 -287.695132) (xy 36.046666 -287.687691) (xy 36.046156 -287.682432)
			(xy 30.001972 -287.682432) (xy 30.001691 -287.687777) (xy 29.994111 -287.695318) (xy 29.988764 -287.69564)
			(xy 29.47289 -287.69564) (xy 29.465016 -287.695933) (xy 29.450012 -287.700713) (xy 29.443426 -287.705038)
			(xy 29.422359 -287.719445) (xy 29.37671 -287.74227) (xy 29.328101 -287.757824) (xy 29.277682 -287.765738)
			(xy 29.252164 -287.766252) (xy 29.226645 -287.765738) (xy 29.176219 -287.757849) (xy 29.127608 -287.742296)
			(xy 29.081968 -287.719449) (xy 29.060902 -287.705038) (xy 29.054309 -287.700725) (xy 29.03931 -287.695936)
			(xy 29.031438 -287.69564) (xy 28.515564 -287.69564) (xy 28.510305 -287.695132) (xy 28.502866 -287.687691)
			(xy 28.502356 -287.682432) (xy 22.458172 -287.682432) (xy 22.457891 -287.687777) (xy 22.450311 -287.695318)
			(xy 22.444964 -287.69564) (xy 22.444456 -287.69564) (xy 21.928836 -287.69564) (xy 21.92096 -287.695909)
			(xy 21.905956 -287.700706) (xy 21.899372 -287.705038) (xy 21.878292 -287.719425) (xy 21.832648 -287.742255)
			(xy 21.784043 -287.757814) (xy 21.733626 -287.765734) (xy 21.70811 -287.766252) (xy 21.68259 -287.765765)
			(xy 21.632163 -287.757868) (xy 21.583552 -287.742307) (xy 21.537913 -287.719453) (xy 21.516848 -287.705038)
			(xy 21.510268 -287.700704) (xy 21.495259 -287.695928) (xy 21.487384 -287.69564) (xy 20.97151 -287.69564)
			(xy 20.966202 -287.695168) (xy 20.958629 -287.68773) (xy 20.958048 -287.682432) (xy 2.509012 -287.682432)
			(xy 2.509012 -287.8564) (xy 97.674907 -287.8564) (xy 97.679082 -287.806018) (xy 97.691493 -287.75701)
			(xy 97.711801 -287.710714) (xy 97.739452 -287.668391) (xy 97.773692 -287.631198) (xy 97.813588 -287.600147)
			(xy 97.858049 -287.576086) (xy 97.905865 -287.559672) (xy 97.955731 -287.551352) (xy 97.981008 -287.55086)
			(xy 98.921062 -287.55086) (xy 98.946345 -287.551306) (xy 98.996221 -287.559623) (xy 99.044048 -287.576037)
			(xy 99.088521 -287.6001) (xy 99.128426 -287.631154) (xy 99.162675 -287.668354) (xy 99.190333 -287.710685)
			(xy 99.210647 -287.75699) (xy 99.223061 -287.806008) (xy 99.227237 -287.8564) (xy 100.495136 -287.8564)
			(xy 100.49931 -287.806027) (xy 100.511718 -287.757027) (xy 100.532021 -287.710738) (xy 100.559665 -287.668422)
			(xy 100.593897 -287.631232) (xy 100.633783 -287.600184) (xy 100.678235 -287.576124) (xy 100.726041 -287.559708)
			(xy 100.775897 -287.551384) (xy 100.80117 -287.55086) (xy 101.741224 -287.55086) (xy 101.766501 -287.55134)
			(xy 101.816365 -287.559664) (xy 101.864178 -287.576082) (xy 101.908638 -287.600145) (xy 101.94853 -287.631198)
			(xy 101.982768 -287.668393) (xy 102.010417 -287.710716) (xy 102.030723 -287.757012) (xy 102.043133 -287.806019)
			(xy 102.047308 -287.8564) (xy 103.315036 -287.8564) (xy 103.31921 -287.806026) (xy 103.331618 -287.757026)
			(xy 103.351922 -287.710736) (xy 103.379567 -287.668419) (xy 103.4138 -287.63123) (xy 103.453687 -287.600182)
			(xy 103.498141 -287.576122) (xy 103.545948 -287.559707) (xy 103.595805 -287.551384) (xy 103.621078 -287.55086)
			(xy 104.561132 -287.55086) (xy 104.586408 -287.551341) (xy 104.636271 -287.559666) (xy 104.684084 -287.576084)
			(xy 104.728542 -287.600148) (xy 104.768433 -287.631201) (xy 104.80267 -287.668396) (xy 104.830318 -287.710718)
			(xy 104.850624 -287.757013) (xy 104.863033 -287.80602) (xy 104.867208 -287.8564) (xy 106.134936 -287.8564)
			(xy 106.139111 -287.806025) (xy 106.151519 -287.757024) (xy 106.171823 -287.710734) (xy 106.199469 -287.668417)
			(xy 106.233703 -287.631227) (xy 106.273592 -287.600179) (xy 106.318046 -287.576119) (xy 106.365854 -287.559705)
			(xy 106.415712 -287.551383) (xy 106.440986 -287.55086) (xy 107.38104 -287.55086) (xy 107.406316 -287.551341)
			(xy 107.456178 -287.559668) (xy 107.503989 -287.576087) (xy 107.548446 -287.600151) (xy 107.588336 -287.631204)
			(xy 107.622572 -287.668398) (xy 107.65022 -287.71072) (xy 107.670524 -287.757015) (xy 107.682933 -287.806021)
			(xy 107.687108 -287.8564) (xy 116.468607 -287.8564) (xy 116.472783 -287.806017) (xy 116.485194 -287.757008)
			(xy 116.505503 -287.71071) (xy 116.533156 -287.668387) (xy 116.567398 -287.631193) (xy 116.607295 -287.600142)
			(xy 116.651759 -287.576082) (xy 116.699577 -287.559669) (xy 116.749444 -287.551351) (xy 116.774722 -287.55086)
			(xy 117.714776 -287.55086) (xy 117.740058 -287.551307) (xy 117.789932 -287.559626) (xy 117.837757 -287.576041)
			(xy 117.882228 -287.600104) (xy 117.922131 -287.631159) (xy 117.956378 -287.668359) (xy 117.984035 -287.710688)
			(xy 118.004348 -287.756993) (xy 118.016761 -287.806009) (xy 118.020937 -287.8564) (xy 119.288507 -287.8564)
			(xy 119.292683 -287.806016) (xy 119.305094 -287.757006) (xy 119.325404 -287.710708) (xy 119.353058 -287.668384)
			(xy 119.387301 -287.63119) (xy 119.427199 -287.600139) (xy 119.471664 -287.57608) (xy 119.519483 -287.559668)
			(xy 119.569351 -287.551351) (xy 119.59463 -287.55086) (xy 120.534684 -287.55086) (xy 120.559965 -287.551308)
			(xy 120.609839 -287.559628) (xy 120.657663 -287.576044) (xy 120.702132 -287.600107) (xy 120.742034 -287.631162)
			(xy 120.776281 -287.668362) (xy 120.803937 -287.710691) (xy 120.824248 -287.756994) (xy 120.836661 -287.80601)
			(xy 120.840837 -287.8564) (xy 122.108736 -287.8564) (xy 122.112911 -287.806024) (xy 122.125319 -287.757023)
			(xy 122.145624 -287.710732) (xy 122.173271 -287.668415) (xy 122.207506 -287.631225) (xy 122.247395 -287.600177)
			(xy 122.29185 -287.576118) (xy 122.339659 -287.559704) (xy 122.389518 -287.551382) (xy 122.414792 -287.55086)
			(xy 123.354846 -287.55086) (xy 123.380122 -287.551342) (xy 123.429983 -287.559669) (xy 123.477793 -287.576089)
			(xy 123.522249 -287.600153) (xy 123.562139 -287.631206) (xy 123.596374 -287.6684) (xy 123.62402 -287.710722)
			(xy 123.644325 -287.757016) (xy 123.656733 -287.806021) (xy 123.660908 -287.8564) (xy 124.928637 -287.8564)
			(xy 124.932811 -287.806024) (xy 124.94522 -287.757021) (xy 124.965525 -287.71073) (xy 124.993173 -287.668412)
			(xy 125.027409 -287.631222) (xy 125.067299 -287.600174) (xy 125.111756 -287.576115) (xy 125.159566 -287.559702)
			(xy 125.209425 -287.551382) (xy 125.2347 -287.55086) (xy 126.174754 -287.55086) (xy 126.200037 -287.551306)
			(xy 126.249914 -287.559622) (xy 126.297743 -287.576035) (xy 126.342216 -287.600097) (xy 126.382123 -287.631152)
			(xy 126.416373 -287.668352) (xy 126.425573 -287.682432) (xy 167.778176 -287.682432) (xy 167.778176 -287.187894)
			(xy 167.778623 -287.182581) (xy 167.786079 -287.175008) (xy 167.791384 -287.174432) (xy 169.264584 -287.174432)
			(xy 169.269924 -287.174741) (xy 169.277468 -287.1823) (xy 169.277792 -287.18764) (xy 169.277792 -287.682432)
			(xy 175.321976 -287.682432) (xy 175.321976 -287.187894) (xy 175.322279 -287.182449) (xy 175.329992 -287.174761)
			(xy 175.335438 -287.174432) (xy 175.851566 -287.174432) (xy 175.859376 -287.174115) (xy 175.874248 -287.169333)
			(xy 175.880776 -287.165034) (xy 175.901865 -287.150685) (xy 175.947526 -287.127954) (xy 175.996132 -287.112495)
			(xy 176.046535 -287.104672) (xy 176.097541 -287.104672) (xy 176.147944 -287.112495) (xy 176.19655 -287.127954)
			(xy 176.242211 -287.150685) (xy 176.2633 -287.165034) (xy 176.269836 -287.169318) (xy 176.284702 -287.174107)
			(xy 176.29251 -287.174432) (xy 176.808638 -287.174432) (xy 176.814005 -287.174925) (xy 176.821588 -287.182526)
			(xy 176.8221 -287.187894) (xy 176.8221 -287.682432) (xy 182.866284 -287.682432) (xy 182.866284 -287.187894)
			(xy 182.866724 -287.182579) (xy 182.874185 -287.175005) (xy 182.879492 -287.174432) (xy 183.39562 -287.174432)
			(xy 183.403432 -287.174138) (xy 183.418304 -287.16934) (xy 183.42483 -287.165034) (xy 183.445919 -287.150685)
			(xy 183.49158 -287.127954) (xy 183.540186 -287.112495) (xy 183.590589 -287.104672) (xy 183.641595 -287.104672)
			(xy 183.691998 -287.112495) (xy 183.740604 -287.127954) (xy 183.786265 -287.150685) (xy 183.807354 -287.165034)
			(xy 183.813878 -287.169338) (xy 183.828754 -287.174114) (xy 183.836564 -287.174432) (xy 184.352692 -287.174432)
			(xy 184.358033 -287.174736) (xy 184.365577 -287.182298) (xy 184.3659 -287.18764) (xy 184.3659 -287.188148)
			(xy 184.3659 -287.682432) (xy 190.410084 -287.682432) (xy 190.410084 -287.187894) (xy 190.41038 -287.182447)
			(xy 190.418098 -287.174759) (xy 190.423546 -287.174432) (xy 190.939674 -287.174432) (xy 190.947484 -287.174119)
			(xy 190.962356 -287.169334) (xy 190.968884 -287.165034) (xy 190.989973 -287.150685) (xy 191.035634 -287.127954)
			(xy 191.08424 -287.112495) (xy 191.134643 -287.104672) (xy 191.185649 -287.104672) (xy 191.236052 -287.112495)
			(xy 191.284658 -287.127954) (xy 191.330319 -287.150685) (xy 191.351408 -287.165034) (xy 191.357942 -287.169321)
			(xy 191.37281 -287.174108) (xy 191.380618 -287.174432) (xy 191.896746 -287.174432) (xy 191.902114 -287.174919)
			(xy 191.909697 -287.182525) (xy 191.910208 -287.187894) (xy 191.910208 -287.682432) (xy 197.954392 -287.682432)
			(xy 197.954392 -287.187894) (xy 197.954913 -287.1826) (xy 197.962318 -287.175032) (xy 197.9676 -287.174432)
			(xy 198.483728 -287.174432) (xy 198.49154 -287.174142) (xy 198.506412 -287.169341) (xy 198.512938 -287.165034)
			(xy 198.534027 -287.150685) (xy 198.579688 -287.127954) (xy 198.628294 -287.112495) (xy 198.678697 -287.104672)
			(xy 198.729703 -287.104672) (xy 198.780106 -287.112495) (xy 198.828712 -287.127954) (xy 198.874373 -287.150685)
			(xy 198.895462 -287.165034) (xy 198.902007 -287.169303) (xy 198.916866 -287.174101) (xy 198.924672 -287.174432)
			(xy 199.4408 -287.174432) (xy 199.446142 -287.174731) (xy 199.453685 -287.182297) (xy 199.454008 -287.18764)
			(xy 199.454008 -287.188148) (xy 199.454008 -287.682432) (xy 205.498192 -287.682432) (xy 205.498192 -287.187894)
			(xy 205.498713 -287.1826) (xy 205.506118 -287.175032) (xy 205.5114 -287.174432) (xy 206.027528 -287.174432)
			(xy 206.03534 -287.174142) (xy 206.050212 -287.169341) (xy 206.056738 -287.165034) (xy 206.077827 -287.150685)
			(xy 206.123488 -287.127954) (xy 206.172094 -287.112495) (xy 206.222497 -287.104672) (xy 206.273503 -287.104672)
			(xy 206.323906 -287.112495) (xy 206.372512 -287.127954) (xy 206.418173 -287.150685) (xy 206.439262 -287.165034)
			(xy 206.445807 -287.169303) (xy 206.460666 -287.174101) (xy 206.468472 -287.174432) (xy 206.9846 -287.174432)
			(xy 206.989942 -287.174731) (xy 206.997485 -287.182297) (xy 206.997808 -287.18764) (xy 206.997808 -287.188148)
			(xy 206.997808 -287.682178) (xy 268.898116 -287.682178) (xy 268.898116 -287.18764) (xy 268.898456 -287.182307)
			(xy 268.905992 -287.174763) (xy 268.911324 -287.174432) (xy 268.911832 -287.174432) (xy 269.427706 -287.174432)
			(xy 269.435518 -287.174132) (xy 269.450389 -287.169338) (xy 269.456916 -287.165034) (xy 269.478005 -287.150685)
			(xy 269.523666 -287.127954) (xy 269.572272 -287.112495) (xy 269.622675 -287.104672) (xy 269.673681 -287.104672)
			(xy 269.724084 -287.112495) (xy 269.77269 -287.127954) (xy 269.818351 -287.150685) (xy 269.83944 -287.165034)
			(xy 269.845967 -287.169333) (xy 269.86084 -287.174112) (xy 269.86865 -287.174432) (xy 270.384778 -287.174432)
			(xy 270.390078 -287.174937) (xy 270.39765 -287.182351) (xy 270.39824 -287.18764) (xy 270.39824 -287.682178)
			(xy 270.398224 -287.682432) (xy 276.442424 -287.682432) (xy 276.442424 -287.681924) (xy 276.442424 -287.18764)
			(xy 276.442757 -287.182305) (xy 276.450298 -287.17476) (xy 276.455632 -287.174432) (xy 276.97176 -287.174432)
			(xy 276.97957 -287.174113) (xy 276.994442 -287.169332) (xy 277.00097 -287.165034) (xy 277.022059 -287.150685)
			(xy 277.06772 -287.127954) (xy 277.116326 -287.112495) (xy 277.166729 -287.104672) (xy 277.217735 -287.104672)
			(xy 277.268138 -287.112495) (xy 277.316744 -287.127954) (xy 277.362405 -287.150685) (xy 277.383494 -287.165034)
			(xy 277.390031 -287.169315) (xy 277.404897 -287.174106) (xy 277.412704 -287.174432) (xy 277.928832 -287.174432)
			(xy 277.934178 -287.174709) (xy 277.94172 -287.182292) (xy 277.94204 -287.18764) (xy 277.94204 -287.682178)
			(xy 277.942017 -287.682432) (xy 283.986224 -287.682432) (xy 283.986224 -287.681924) (xy 283.986224 -287.18764)
			(xy 283.986557 -287.182305) (xy 283.994098 -287.17476) (xy 283.999432 -287.174432) (xy 284.51556 -287.174432)
			(xy 284.52337 -287.174113) (xy 284.538242 -287.169332) (xy 284.54477 -287.165034) (xy 284.565859 -287.150685)
			(xy 284.61152 -287.127954) (xy 284.660126 -287.112495) (xy 284.710529 -287.104672) (xy 284.761535 -287.104672)
			(xy 284.811938 -287.112495) (xy 284.860544 -287.127954) (xy 284.906205 -287.150685) (xy 284.927294 -287.165034)
			(xy 284.933831 -287.169315) (xy 284.948697 -287.174106) (xy 284.956504 -287.174432) (xy 285.472632 -287.174432)
			(xy 285.477978 -287.174709) (xy 285.48552 -287.182292) (xy 285.48584 -287.18764) (xy 285.48584 -287.682178)
			(xy 291.530024 -287.682178) (xy 291.530024 -287.18764) (xy 291.530357 -287.182305) (xy 291.537898 -287.17476)
			(xy 291.543232 -287.174432) (xy 291.54374 -287.174432) (xy 292.059614 -287.174432) (xy 292.067426 -287.174136)
			(xy 292.082298 -287.169339) (xy 292.088824 -287.165034) (xy 292.109913 -287.150685) (xy 292.155574 -287.127954)
			(xy 292.20418 -287.112495) (xy 292.254583 -287.104672) (xy 292.305589 -287.104672) (xy 292.355992 -287.112495)
			(xy 292.404598 -287.127954) (xy 292.450259 -287.150685) (xy 292.471348 -287.165034) (xy 292.477873 -287.169336)
			(xy 292.492748 -287.174114) (xy 292.500558 -287.174432) (xy 293.016686 -287.174432) (xy 293.021987 -287.174932)
			(xy 293.029558 -287.18235) (xy 293.030148 -287.18764) (xy 293.030148 -287.682178) (xy 293.030132 -287.682432)
			(xy 299.074332 -287.682432) (xy 299.074332 -287.681924) (xy 299.074332 -287.18764) (xy 299.074658 -287.182303)
			(xy 299.082203 -287.174758) (xy 299.08754 -287.174432) (xy 299.603668 -287.174432) (xy 299.611478 -287.174116)
			(xy 299.62635 -287.169333) (xy 299.632878 -287.165034) (xy 299.653967 -287.150685) (xy 299.699628 -287.127954)
			(xy 299.748234 -287.112495) (xy 299.798637 -287.104672) (xy 299.849643 -287.104672) (xy 299.900046 -287.112495)
			(xy 299.948652 -287.127954) (xy 299.994313 -287.150685) (xy 300.015402 -287.165034) (xy 300.021938 -287.169318)
			(xy 300.036804 -287.174107) (xy 300.044612 -287.174432) (xy 300.56074 -287.174432) (xy 300.566017 -287.174872)
			(xy 300.57346 -287.18236) (xy 300.573948 -287.18764) (xy 300.573948 -287.682178) (xy 306.618132 -287.682178)
			(xy 306.618132 -287.18764) (xy 306.618458 -287.182303) (xy 306.626003 -287.174758) (xy 306.63134 -287.174432)
			(xy 306.631848 -287.174432) (xy 308.104794 -287.174432) (xy 308.110096 -287.174926) (xy 308.117667 -287.182349)
			(xy 308.118256 -287.18764) (xy 308.118256 -287.682178) (xy 308.117905 -287.687611) (xy 308.110227 -287.695299)
			(xy 308.104794 -287.69564) (xy 306.631594 -287.69564) (xy 306.626153 -287.695322) (xy 306.618466 -287.68762)
			(xy 306.618132 -287.682178) (xy 300.573948 -287.682178) (xy 300.573461 -287.687482) (xy 300.566034 -287.695056)
			(xy 300.56074 -287.69564) (xy 300.044866 -287.69564) (xy 300.037058 -287.695975) (xy 300.022186 -287.700746)
			(xy 300.015656 -287.705038) (xy 299.994543 -287.719401) (xy 299.948816 -287.742125) (xy 299.90014 -287.757551)
			(xy 299.849672 -287.765313) (xy 299.82414 -287.765744) (xy 299.79861 -287.765291) (xy 299.748147 -287.757521)
			(xy 299.699474 -287.742096) (xy 299.653746 -287.719384) (xy 299.632624 -287.705038) (xy 299.626084 -287.700761)
			(xy 299.611221 -287.695969) (xy 299.603414 -287.69564) (xy 299.08754 -287.69564) (xy 299.082221 -287.695249)
			(xy 299.07468 -287.687749) (xy 299.074332 -287.682432) (xy 293.030132 -287.682432) (xy 293.029804 -287.687613)
			(xy 293.022121 -287.695301) (xy 293.016686 -287.69564) (xy 292.500812 -287.69564) (xy 292.493002 -287.695952)
			(xy 292.47813 -287.700738) (xy 292.471602 -287.705038) (xy 292.450476 -287.719381) (xy 292.404754 -287.742109)
			(xy 292.356082 -287.757541) (xy 292.305617 -287.76531) (xy 292.280086 -287.765744) (xy 292.254555 -287.765318)
			(xy 292.204091 -287.75754) (xy 292.155418 -287.742107) (xy 292.109691 -287.719387) (xy 292.08857 -287.705038)
			(xy 292.082042 -287.70074) (xy 292.067169 -287.695961) (xy 292.05936 -287.69564) (xy 291.543486 -287.69564)
			(xy 291.538044 -287.695328) (xy 291.530358 -287.687621) (xy 291.530024 -287.682178) (xy 285.48584 -287.682178)
			(xy 285.48536 -287.687484) (xy 285.477928 -287.695058) (xy 285.472632 -287.69564) (xy 284.956758 -287.69564)
			(xy 284.948949 -287.695972) (xy 284.934078 -287.700745) (xy 284.927548 -287.705038) (xy 284.906437 -287.719404)
			(xy 284.86071 -287.742128) (xy 284.812033 -287.757553) (xy 284.761564 -287.765314) (xy 284.736032 -287.765744)
			(xy 284.710502 -287.765295) (xy 284.660039 -287.757524) (xy 284.611366 -287.742098) (xy 284.565638 -287.719384)
			(xy 284.544516 -287.705038) (xy 284.537978 -287.700758) (xy 284.523113 -287.695967) (xy 284.515306 -287.69564)
			(xy 283.999432 -287.69564) (xy 283.994181 -287.695087) (xy 283.986738 -287.687681) (xy 283.986224 -287.682432)
			(xy 277.942017 -287.682432) (xy 277.94156 -287.687484) (xy 277.934128 -287.695058) (xy 277.928832 -287.69564)
			(xy 277.412958 -287.69564) (xy 277.405149 -287.695972) (xy 277.390278 -287.700745) (xy 277.383748 -287.705038)
			(xy 277.362637 -287.719404) (xy 277.31691 -287.742128) (xy 277.268233 -287.757553) (xy 277.217764 -287.765314)
			(xy 277.192232 -287.765744) (xy 277.166702 -287.765295) (xy 277.116239 -287.757524) (xy 277.067566 -287.742098)
			(xy 277.021838 -287.719384) (xy 277.000716 -287.705038) (xy 276.994178 -287.700758) (xy 276.979313 -287.695967)
			(xy 276.971506 -287.69564) (xy 276.455632 -287.69564) (xy 276.450381 -287.695087) (xy 276.442938 -287.687681)
			(xy 276.442424 -287.682432) (xy 270.398224 -287.682432) (xy 270.397904 -287.687615) (xy 270.390215 -287.695304)
			(xy 270.384778 -287.69564) (xy 269.868904 -287.69564) (xy 269.861093 -287.695948) (xy 269.846222 -287.700737)
			(xy 269.839694 -287.705038) (xy 269.818571 -287.719384) (xy 269.772847 -287.742112) (xy 269.724175 -287.757543)
			(xy 269.673709 -287.765311) (xy 269.648178 -287.765744) (xy 269.622647 -287.765322) (xy 269.572183 -287.757542)
			(xy 269.52351 -287.742109) (xy 269.477783 -287.719388) (xy 269.456662 -287.705038) (xy 269.450136 -287.700737)
			(xy 269.435262 -287.69596) (xy 269.427452 -287.69564) (xy 268.911578 -287.69564) (xy 268.906206 -287.695162)
			(xy 268.89862 -287.687552) (xy 268.898116 -287.682178) (xy 206.997808 -287.682178) (xy 206.997808 -287.682432)
			(xy 206.997327 -287.687699) (xy 206.989868 -287.695139) (xy 206.9846 -287.69564) (xy 206.468726 -287.69564)
			(xy 206.460849 -287.695905) (xy 206.445846 -287.700704) (xy 206.439262 -287.705038) (xy 206.418185 -287.71943)
			(xy 206.37254 -287.742258) (xy 206.323934 -287.757816) (xy 206.273517 -287.765735) (xy 206.248 -287.766252)
			(xy 206.22248 -287.76577) (xy 206.172053 -287.757872) (xy 206.123441 -287.742309) (xy 206.077803 -287.719453)
			(xy 206.056738 -287.705038) (xy 206.050137 -287.700739) (xy 206.035144 -287.695942) (xy 206.027274 -287.69564)
			(xy 205.5114 -287.69564) (xy 205.506145 -287.695108) (xy 205.498704 -287.687686) (xy 205.498192 -287.682432)
			(xy 199.454008 -287.682432) (xy 199.453527 -287.687699) (xy 199.446068 -287.695139) (xy 199.4408 -287.69564)
			(xy 198.924926 -287.69564) (xy 198.917049 -287.695905) (xy 198.902046 -287.700704) (xy 198.895462 -287.705038)
			(xy 198.874385 -287.71943) (xy 198.82874 -287.742258) (xy 198.780134 -287.757816) (xy 198.729717 -287.765735)
			(xy 198.7042 -287.766252) (xy 198.67868 -287.76577) (xy 198.628253 -287.757872) (xy 198.579641 -287.742309)
			(xy 198.534003 -287.719453) (xy 198.512938 -287.705038) (xy 198.506337 -287.700739) (xy 198.491344 -287.695942)
			(xy 198.483474 -287.69564) (xy 197.9676 -287.69564) (xy 197.962345 -287.695108) (xy 197.954904 -287.687686)
			(xy 197.954392 -287.682432) (xy 191.910208 -287.682432) (xy 191.909727 -287.687699) (xy 191.902268 -287.695139)
			(xy 191.897 -287.69564) (xy 191.896492 -287.69564) (xy 191.380872 -287.69564) (xy 191.372997 -287.695925)
			(xy 191.357993 -287.700711) (xy 191.351408 -287.705038) (xy 191.330346 -287.719453) (xy 191.284696 -287.742276)
			(xy 191.236085 -287.757828) (xy 191.185664 -287.765739) (xy 191.160146 -287.766252) (xy 191.134627 -287.765747)
			(xy 191.084201 -287.757855) (xy 191.035589 -287.7423) (xy 190.98995 -287.71945) (xy 190.968884 -287.705038)
			(xy 190.962296 -287.700718) (xy 190.947293 -287.695934) (xy 190.93942 -287.69564) (xy 190.423546 -287.69564)
			(xy 190.418243 -287.695144) (xy 190.410668 -287.687724) (xy 190.410084 -287.682432) (xy 184.3659 -287.682432)
			(xy 184.365426 -287.687701) (xy 184.357962 -287.695142) (xy 184.352692 -287.69564) (xy 183.836818 -287.69564)
			(xy 183.828945 -287.695945) (xy 183.813941 -287.700717) (xy 183.807354 -287.705038) (xy 183.786279 -287.719433)
			(xy 183.740633 -287.742261) (xy 183.692027 -287.757818) (xy 183.641609 -287.765736) (xy 183.616092 -287.766252)
			(xy 183.590573 -287.765724) (xy 183.540149 -287.757839) (xy 183.491537 -287.74229) (xy 183.445897 -287.719447)
			(xy 183.42483 -287.705038) (xy 183.418231 -287.700736) (xy 183.403237 -287.69594) (xy 183.395366 -287.69564)
			(xy 182.879492 -287.69564) (xy 182.874236 -287.695114) (xy 182.866796 -287.687687) (xy 182.866284 -287.682432)
			(xy 176.8221 -287.682432) (xy 176.821626 -287.687701) (xy 176.814162 -287.695142) (xy 176.808892 -287.69564)
			(xy 176.808384 -287.69564) (xy 176.292764 -287.69564) (xy 176.284889 -287.695921) (xy 176.269885 -287.700709)
			(xy 176.2633 -287.705038) (xy 176.242212 -287.719413) (xy 176.196571 -287.742246) (xy 176.147968 -287.757808)
			(xy 176.097554 -287.765732) (xy 176.072038 -287.766252) (xy 176.046518 -287.765751) (xy 175.996092 -287.757858)
			(xy 175.947481 -287.742301) (xy 175.901842 -287.719451) (xy 175.880776 -287.705038) (xy 175.874189 -287.700715)
			(xy 175.859186 -287.695932) (xy 175.851312 -287.69564) (xy 175.335438 -287.69564) (xy 175.330134 -287.695149)
			(xy 175.322559 -287.687726) (xy 175.321976 -287.682432) (xy 169.277792 -287.682432) (xy 169.277325 -287.687702)
			(xy 169.269856 -287.695144) (xy 169.264584 -287.69564) (xy 167.791384 -287.69564) (xy 167.786127 -287.695119)
			(xy 167.778687 -287.687688) (xy 167.778176 -287.682432) (xy 126.425573 -287.682432) (xy 126.444032 -287.710682)
			(xy 126.464346 -287.756988) (xy 126.47676 -287.806007) (xy 126.48092 -287.8562) (xy 345.615237 -287.8562)
			(xy 345.619408 -287.805859) (xy 345.631808 -287.756891) (xy 345.652098 -287.710632) (xy 345.679725 -287.668343)
			(xy 345.713935 -287.631178) (xy 345.753796 -287.60015) (xy 345.79822 -287.576106) (xy 345.845995 -287.559701)
			(xy 345.895819 -287.551384) (xy 345.921076 -287.55086) (xy 346.86113 -287.55086) (xy 346.886381 -287.551448)
			(xy 346.936194 -287.559765) (xy 346.983958 -287.576166) (xy 347.028372 -287.600206) (xy 347.068224 -287.631227)
			(xy 347.102426 -287.668384) (xy 347.130047 -287.710664) (xy 347.150332 -287.756913) (xy 347.162729 -287.80587)
			(xy 347.166899 -287.8562) (xy 348.435308 -287.8562) (xy 348.439481 -287.805848) (xy 348.451885 -287.756869)
			(xy 348.472182 -287.710601) (xy 348.499818 -287.668305) (xy 348.53404 -287.631134) (xy 348.573913 -287.600104)
			(xy 348.61835 -287.576061) (xy 348.666139 -287.55966) (xy 348.715976 -287.55135) (xy 348.741238 -287.55086)
			(xy 349.681292 -287.55086) (xy 349.706548 -287.551416) (xy 349.75637 -287.559729) (xy 349.804144 -287.576129)
			(xy 349.848568 -287.600168) (xy 349.888429 -287.631192) (xy 349.922639 -287.668354) (xy 349.950266 -287.71064)
			(xy 349.970557 -287.756896) (xy 349.982957 -287.805862) (xy 349.987128 -287.8562) (xy 351.255208 -287.8562)
			(xy 351.259381 -287.805847) (xy 351.271785 -287.756868) (xy 351.292083 -287.710599) (xy 351.31972 -287.668302)
			(xy 351.353943 -287.631132) (xy 351.393817 -287.600102) (xy 351.438256 -287.576059) (xy 351.486046 -287.559659)
			(xy 351.535883 -287.551349) (xy 351.561146 -287.55086) (xy 352.5012 -287.55086) (xy 352.526453 -287.551445)
			(xy 352.576269 -287.559758) (xy 352.624038 -287.576157) (xy 352.668456 -287.600195) (xy 352.708312 -287.631216)
			(xy 352.742518 -287.668374) (xy 352.770142 -287.710656) (xy 352.79043 -287.756907) (xy 352.802828 -287.805867)
			(xy 352.806999 -287.8562) (xy 354.075237 -287.8562) (xy 354.079408 -287.805861) (xy 354.091806 -287.756896)
			(xy 354.112095 -287.710638) (xy 354.139719 -287.66835) (xy 354.173927 -287.631186) (xy 354.213784 -287.600158)
			(xy 354.258205 -287.576112) (xy 354.305977 -287.559706) (xy 354.355799 -287.551385) (xy 354.381054 -287.55086)
			(xy 355.321108 -287.55086) (xy 355.34636 -287.551446) (xy 355.396176 -287.55976) (xy 355.443943 -287.57616)
			(xy 355.48836 -287.600198) (xy 355.528215 -287.631219) (xy 355.56242 -287.668377) (xy 355.590043 -287.710658)
			(xy 355.610331 -287.756909) (xy 355.622728 -287.805868) (xy 355.626899 -287.8562) (xy 364.408937 -287.8562)
			(xy 364.413108 -287.805858) (xy 364.425509 -287.756888) (xy 364.4458 -287.710628) (xy 364.473429 -287.668338)
			(xy 364.507641 -287.631173) (xy 364.547503 -287.600145) (xy 364.591929 -287.576102) (xy 364.639707 -287.559698)
			(xy 364.689533 -287.551382) (xy 364.71479 -287.55086) (xy 365.654844 -287.55086) (xy 365.680094 -287.551449)
			(xy 365.729905 -287.559767) (xy 365.777668 -287.57617) (xy 365.822079 -287.600211) (xy 365.861929 -287.631232)
			(xy 365.89613 -287.668389) (xy 365.923749 -287.710668) (xy 365.944033 -287.756916) (xy 365.956429 -287.805872)
			(xy 365.960599 -287.8562) (xy 367.228837 -287.8562) (xy 367.233009 -287.805857) (xy 367.245409 -287.756887)
			(xy 367.265701 -287.710626) (xy 367.293331 -287.668336) (xy 367.327544 -287.63117) (xy 367.367408 -287.600142)
			(xy 367.411835 -287.576099) (xy 367.459613 -287.559697) (xy 367.50944 -287.551382) (xy 367.534698 -287.55086)
			(xy 368.474752 -287.55086) (xy 368.50001 -287.551413) (xy 368.549837 -287.55972) (xy 368.597617 -287.576117)
			(xy 368.642047 -287.600154) (xy 368.681913 -287.631178) (xy 368.716129 -287.668341) (xy 368.74376 -287.710629)
			(xy 368.764054 -287.756888) (xy 368.776456 -287.805857) (xy 368.780628 -287.8562) (xy 370.049037 -287.8562)
			(xy 370.053208 -287.805861) (xy 370.065607 -287.756894) (xy 370.085895 -287.710636) (xy 370.113521 -287.668348)
			(xy 370.147729 -287.631184) (xy 370.187588 -287.600156) (xy 370.232009 -287.576111) (xy 370.279782 -287.559705)
			(xy 370.329604 -287.551385) (xy 370.35486 -287.55086) (xy 371.294914 -287.55086) (xy 371.320166 -287.551447)
			(xy 371.369981 -287.559761) (xy 371.417748 -287.576162) (xy 371.462164 -287.6002) (xy 371.502017 -287.631221)
			(xy 371.536222 -287.668379) (xy 371.563844 -287.71066) (xy 371.584131 -287.75691) (xy 371.596529 -287.805869)
			(xy 371.600699 -287.8562) (xy 372.868937 -287.8562) (xy 372.873108 -287.80586) (xy 372.885507 -287.756893)
			(xy 372.905797 -287.710634) (xy 372.933423 -287.668346) (xy 372.967632 -287.631181) (xy 373.007492 -287.600153)
			(xy 373.051915 -287.576108) (xy 373.099689 -287.559703) (xy 373.149512 -287.551384) (xy 373.174768 -287.55086)
			(xy 374.114822 -287.55086) (xy 374.140073 -287.551447) (xy 374.189887 -287.559763) (xy 374.237653 -287.576164)
			(xy 374.282068 -287.600203) (xy 374.321921 -287.631224) (xy 374.356124 -287.668382) (xy 374.365303 -287.682432)
			(xy 415.718244 -287.682432) (xy 415.718244 -287.18764) (xy 415.718816 -287.182393) (xy 415.726209 -287.174951)
			(xy 415.731452 -287.174432) (xy 417.204652 -287.174432) (xy 417.209987 -287.174763) (xy 417.217534 -287.182305)
			(xy 417.21786 -287.18764) (xy 417.21786 -287.682178) (xy 423.262044 -287.682178) (xy 423.262044 -287.18764)
			(xy 423.262616 -287.182393) (xy 423.270009 -287.174951) (xy 423.275252 -287.174432) (xy 423.27576 -287.174432)
			(xy 423.791634 -287.174432) (xy 423.799443 -287.174102) (xy 423.814315 -287.169328) (xy 423.820844 -287.165034)
			(xy 423.841933 -287.150685) (xy 423.887594 -287.127954) (xy 423.9362 -287.112495) (xy 423.986603 -287.104672)
			(xy 424.037609 -287.104672) (xy 424.088012 -287.112495) (xy 424.136618 -287.127954) (xy 424.182279 -287.150685)
			(xy 424.203368 -287.165034) (xy 424.209911 -287.169305) (xy 424.224772 -287.174102) (xy 424.232578 -287.174432)
			(xy 424.748706 -287.174432) (xy 424.754009 -287.174918) (xy 424.761579 -287.182347) (xy 424.762168 -287.18764)
			(xy 424.762168 -287.682178) (xy 424.762151 -287.682432) (xy 430.806352 -287.682432) (xy 430.806352 -287.681924)
			(xy 430.806352 -287.18764) (xy 430.806917 -287.182392) (xy 430.814315 -287.174949) (xy 430.81956 -287.174432)
			(xy 431.335688 -287.174432) (xy 431.343499 -287.174125) (xy 431.358371 -287.169335) (xy 431.364898 -287.165034)
			(xy 431.385987 -287.150685) (xy 431.431648 -287.127954) (xy 431.480254 -287.112495) (xy 431.530657 -287.104672)
			(xy 431.581663 -287.104672) (xy 431.632066 -287.112495) (xy 431.680672 -287.127954) (xy 431.726333 -287.150685)
			(xy 431.747422 -287.165034) (xy 431.753953 -287.169326) (xy 431.768823 -287.17411) (xy 431.776632 -287.174432)
			(xy 432.29276 -287.174432) (xy 432.298097 -287.174758) (xy 432.305642 -287.182303) (xy 432.305968 -287.18764)
			(xy 432.305968 -287.682178) (xy 438.350152 -287.682178) (xy 438.350152 -287.18764) (xy 438.350717 -287.182392)
			(xy 438.358115 -287.174949) (xy 438.36336 -287.174432) (xy 438.363868 -287.174432) (xy 438.879742 -287.174432)
			(xy 438.887551 -287.174105) (xy 438.902423 -287.169329) (xy 438.908952 -287.165034) (xy 438.930041 -287.150685)
			(xy 438.975702 -287.127954) (xy 439.024308 -287.112495) (xy 439.074711 -287.104672) (xy 439.125717 -287.104672)
			(xy 439.17612 -287.112495) (xy 439.224726 -287.127954) (xy 439.270387 -287.150685) (xy 439.291476 -287.165034)
			(xy 439.298017 -287.169308) (xy 439.31288 -287.174103) (xy 439.320686 -287.174432) (xy 439.836814 -287.174432)
			(xy 439.842118 -287.174913) (xy 439.849688 -287.182346) (xy 439.850276 -287.18764) (xy 439.850276 -287.682178)
			(xy 439.850259 -287.682432) (xy 445.89446 -287.682432) (xy 445.89446 -287.681924) (xy 445.89446 -287.18764)
			(xy 445.894851 -287.182321) (xy 445.902351 -287.17478) (xy 445.907668 -287.174432) (xy 446.423796 -287.174432)
			(xy 446.431607 -287.174128) (xy 446.446479 -287.169336) (xy 446.453006 -287.165034) (xy 446.474095 -287.150685)
			(xy 446.519756 -287.127954) (xy 446.568362 -287.112495) (xy 446.618765 -287.104672) (xy 446.669771 -287.104672)
			(xy 446.720174 -287.112495) (xy 446.76878 -287.127954) (xy 446.814441 -287.150685) (xy 446.83553 -287.165034)
			(xy 446.842059 -287.169329) (xy 446.856931 -287.174111) (xy 446.86474 -287.174432) (xy 447.380868 -287.174432)
			(xy 447.386206 -287.174752) (xy 447.393751 -287.182302) (xy 447.394076 -287.18764) (xy 447.394076 -287.682178)
			(xy 447.394051 -287.682432) (xy 453.43826 -287.682432) (xy 453.43826 -287.681924) (xy 453.43826 -287.18764)
			(xy 453.438651 -287.182321) (xy 453.446151 -287.17478) (xy 453.451468 -287.174432) (xy 453.967596 -287.174432)
			(xy 453.975407 -287.174128) (xy 453.990279 -287.169336) (xy 453.996806 -287.165034) (xy 454.017895 -287.150685)
			(xy 454.063556 -287.127954) (xy 454.112162 -287.112495) (xy 454.162565 -287.104672) (xy 454.213571 -287.104672)
			(xy 454.263974 -287.112495) (xy 454.31258 -287.127954) (xy 454.358241 -287.150685) (xy 454.37933 -287.165034)
			(xy 454.385859 -287.169329) (xy 454.400731 -287.174111) (xy 454.40854 -287.174432) (xy 454.924668 -287.174432)
			(xy 454.930006 -287.174752) (xy 454.937551 -287.182302) (xy 454.937876 -287.18764) (xy 454.937876 -287.682178)
			(xy 454.937364 -287.687476) (xy 454.929954 -287.695047) (xy 454.924668 -287.69564) (xy 454.408794 -287.69564)
			(xy 454.400983 -287.695944) (xy 454.386111 -287.700736) (xy 454.379584 -287.705038) (xy 454.358463 -287.719389)
			(xy 454.312739 -287.742116) (xy 454.264066 -287.757545) (xy 454.213599 -287.765311) (xy 454.188068 -287.765744)
			(xy 454.162537 -287.765327) (xy 454.112072 -287.757546) (xy 454.0634 -287.742111) (xy 454.017673 -287.719388)
			(xy 453.996552 -287.705038) (xy 453.990028 -287.700733) (xy 453.975152 -287.695958) (xy 453.967342 -287.69564)
			(xy 453.451468 -287.69564) (xy 453.446209 -287.69513) (xy 453.43877 -287.687691) (xy 453.43826 -287.682432)
			(xy 447.394051 -287.682432) (xy 447.393564 -287.687476) (xy 447.386154 -287.695047) (xy 447.380868 -287.69564)
			(xy 446.864994 -287.69564) (xy 446.857183 -287.695944) (xy 446.842311 -287.700736) (xy 446.835784 -287.705038)
			(xy 446.814663 -287.719389) (xy 446.768939 -287.742116) (xy 446.720266 -287.757545) (xy 446.669799 -287.765311)
			(xy 446.644268 -287.765744) (xy 446.618737 -287.765327) (xy 446.568272 -287.757546) (xy 446.5196 -287.742111)
			(xy 446.473873 -287.719388) (xy 446.452752 -287.705038) (xy 446.446228 -287.700733) (xy 446.431352 -287.695958)
			(xy 446.423542 -287.69564) (xy 445.907668 -287.69564) (xy 445.902409 -287.69513) (xy 445.89497 -287.687691)
			(xy 445.89446 -287.682432) (xy 439.850259 -287.682432) (xy 439.849907 -287.687606) (xy 439.842241 -287.695293)
			(xy 439.836814 -287.69564) (xy 439.32094 -287.69564) (xy 439.313131 -287.695964) (xy 439.298259 -287.700742)
			(xy 439.29173 -287.705038) (xy 439.270624 -287.719412) (xy 439.224895 -287.742134) (xy 439.176217 -287.757557)
			(xy 439.125746 -287.765315) (xy 439.100214 -287.765744) (xy 439.074684 -287.765304) (xy 439.02422 -287.75753)
			(xy 438.975547 -287.742102) (xy 438.92982 -287.719386) (xy 438.908698 -287.705038) (xy 438.902164 -287.700751)
			(xy 438.887296 -287.695965) (xy 438.879488 -287.69564) (xy 438.363614 -287.69564) (xy 438.358176 -287.695309)
			(xy 438.350488 -287.687616) (xy 438.350152 -287.682178) (xy 432.305968 -287.682178) (xy 432.305463 -287.687478)
			(xy 432.298049 -287.69505) (xy 432.29276 -287.69564) (xy 431.776886 -287.69564) (xy 431.769075 -287.695941)
			(xy 431.754203 -287.700735) (xy 431.747676 -287.705038) (xy 431.726558 -287.719392) (xy 431.680833 -287.742118)
			(xy 431.632158 -287.757547) (xy 431.581691 -287.765312) (xy 431.55616 -287.765744) (xy 431.530629 -287.765331)
			(xy 431.480164 -287.757549) (xy 431.431491 -287.742113) (xy 431.385765 -287.719389) (xy 431.364644 -287.705038)
			(xy 431.358122 -287.70073) (xy 431.343245 -287.695957) (xy 431.335434 -287.69564) (xy 430.81956 -287.69564)
			(xy 430.8143 -287.695135) (xy 430.806862 -287.687692) (xy 430.806352 -287.682432) (xy 424.762151 -287.682432)
			(xy 424.761806 -287.687608) (xy 424.754136 -287.695295) (xy 424.748706 -287.69564) (xy 424.232832 -287.69564)
			(xy 424.225022 -287.695961) (xy 424.210151 -287.700741) (xy 424.203622 -287.705038) (xy 424.182491 -287.719372)
			(xy 424.13677 -287.742103) (xy 424.0881 -287.757537) (xy 424.037636 -287.765308) (xy 424.012106 -287.765744)
			(xy 423.986576 -287.765308) (xy 423.936112 -287.757533) (xy 423.887439 -287.742103) (xy 423.841712 -287.719386)
			(xy 423.82059 -287.705038) (xy 423.814058 -287.700748) (xy 423.799188 -287.695964) (xy 423.79138 -287.69564)
			(xy 423.275506 -287.69564) (xy 423.270067 -287.695315) (xy 423.262379 -287.687618) (xy 423.262044 -287.682178)
			(xy 417.21786 -287.682178) (xy 417.217362 -287.68748) (xy 417.209943 -287.695052) (xy 417.204652 -287.69564)
			(xy 415.731452 -287.69564) (xy 415.726191 -287.69514) (xy 415.718753 -287.687693) (xy 415.718244 -287.682432)
			(xy 374.365303 -287.682432) (xy 374.383746 -287.710662) (xy 374.404031 -287.756912) (xy 374.416429 -287.805869)
			(xy 374.420599 -287.8562) (xy 374.416429 -287.906531) (xy 374.404031 -287.955488) (xy 374.383746 -288.001738)
			(xy 374.356124 -288.044018) (xy 374.321921 -288.081176) (xy 374.282068 -288.112197) (xy 374.237653 -288.136236)
			(xy 374.189887 -288.152637) (xy 374.140073 -288.160953) (xy 374.114822 -288.161476) (xy 373.174768 -288.161476)
			(xy 373.149512 -288.161016) (xy 373.099689 -288.152697) (xy 373.051915 -288.136292) (xy 373.007492 -288.112247)
			(xy 372.967632 -288.081219) (xy 372.933423 -288.044054) (xy 372.905797 -288.001766) (xy 372.885507 -287.955507)
			(xy 372.873108 -287.90654) (xy 372.868937 -287.8562) (xy 371.600699 -287.8562) (xy 371.596529 -287.906531)
			(xy 371.584131 -287.95549) (xy 371.563844 -288.00174) (xy 371.536222 -288.044021) (xy 371.502017 -288.081179)
			(xy 371.462164 -288.1122) (xy 371.417748 -288.136238) (xy 371.369981 -288.152639) (xy 371.320166 -288.160953)
			(xy 371.294914 -288.161476) (xy 370.35486 -288.161476) (xy 370.329604 -288.161015) (xy 370.279782 -288.152695)
			(xy 370.232009 -288.136289) (xy 370.187588 -288.112244) (xy 370.147729 -288.081216) (xy 370.113521 -288.044052)
			(xy 370.085895 -288.001764) (xy 370.065607 -287.955506) (xy 370.053208 -287.906539) (xy 370.049037 -287.8562)
			(xy 368.780628 -287.8562) (xy 368.776456 -287.906543) (xy 368.764054 -287.955512) (xy 368.74376 -288.001771)
			(xy 368.716129 -288.044059) (xy 368.681913 -288.081222) (xy 368.642047 -288.112246) (xy 368.597617 -288.136283)
			(xy 368.549837 -288.15268) (xy 368.50001 -288.160987) (xy 368.474752 -288.161476) (xy 367.534698 -288.161476)
			(xy 367.50944 -288.161018) (xy 367.459613 -288.152703) (xy 367.411835 -288.136301) (xy 367.367408 -288.112258)
			(xy 367.327544 -288.08123) (xy 367.293331 -288.044064) (xy 367.265701 -288.001774) (xy 367.245409 -287.955513)
			(xy 367.233009 -287.906543) (xy 367.228837 -287.8562) (xy 365.960599 -287.8562) (xy 365.956429 -287.906528)
			(xy 365.944033 -287.955484) (xy 365.923749 -288.001732) (xy 365.89613 -288.044011) (xy 365.861929 -288.081168)
			(xy 365.82208 -288.112189) (xy 365.777668 -288.13623) (xy 365.729905 -288.152633) (xy 365.680094 -288.160951)
			(xy 365.654844 -288.161476) (xy 364.71479 -288.161476) (xy 364.689533 -288.161018) (xy 364.639707 -288.152702)
			(xy 364.591929 -288.136298) (xy 364.547503 -288.112255) (xy 364.507641 -288.081227) (xy 364.473429 -288.044062)
			(xy 364.4458 -288.001772) (xy 364.425509 -287.955512) (xy 364.413108 -287.906542) (xy 364.408937 -287.8562)
			(xy 355.626899 -287.8562) (xy 355.622728 -287.906532) (xy 355.610331 -287.955491) (xy 355.590043 -288.001742)
			(xy 355.56242 -288.044023) (xy 355.528215 -288.081181) (xy 355.48836 -288.112202) (xy 355.443943 -288.13624)
			(xy 355.396176 -288.15264) (xy 355.34636 -288.160954) (xy 355.321108 -288.161476) (xy 354.381054 -288.161476)
			(xy 354.355799 -288.161015) (xy 354.305977 -288.152694) (xy 354.258205 -288.136288) (xy 354.213784 -288.112242)
			(xy 354.173927 -288.081214) (xy 354.139719 -288.04405) (xy 354.112095 -288.001762) (xy 354.091806 -287.955504)
			(xy 354.079408 -287.906539) (xy 354.075237 -287.8562) (xy 352.806999 -287.8562) (xy 352.802828 -287.906533)
			(xy 352.79043 -287.955493) (xy 352.770142 -288.001744) (xy 352.742518 -288.044026) (xy 352.708312 -288.081184)
			(xy 352.668456 -288.112205) (xy 352.624038 -288.136243) (xy 352.576269 -288.152642) (xy 352.526453 -288.160955)
			(xy 352.5012 -288.161476) (xy 351.561146 -288.161476) (xy 351.535883 -288.161051) (xy 351.486046 -288.152741)
			(xy 351.438256 -288.136341) (xy 351.393817 -288.112298) (xy 351.353943 -288.081268) (xy 351.31972 -288.044098)
			(xy 351.292083 -288.001801) (xy 351.271785 -287.955532) (xy 351.259381 -287.906553) (xy 351.255208 -287.8562)
			(xy 349.987128 -287.8562) (xy 349.982957 -287.906538) (xy 349.970557 -287.955504) (xy 349.950266 -288.00176)
			(xy 349.922639 -288.044046) (xy 349.888429 -288.081208) (xy 349.848568 -288.112232) (xy 349.804144 -288.136271)
			(xy 349.75637 -288.152671) (xy 349.706548 -288.160984) (xy 349.681292 -288.161476) (xy 348.741238 -288.161476)
			(xy 348.715976 -288.16105) (xy 348.666139 -288.15274) (xy 348.61835 -288.136339) (xy 348.573913 -288.112296)
			(xy 348.53404 -288.081266) (xy 348.499818 -288.044095) (xy 348.472182 -288.001799) (xy 348.451885 -287.955531)
			(xy 348.439481 -287.906552) (xy 348.435308 -287.8562) (xy 347.166899 -287.8562) (xy 347.162729 -287.90653)
			(xy 347.150332 -287.955487) (xy 347.130047 -288.001736) (xy 347.102426 -288.044016) (xy 347.068224 -288.081173)
			(xy 347.028372 -288.112194) (xy 346.983958 -288.136234) (xy 346.936194 -288.152635) (xy 346.886381 -288.160952)
			(xy 346.86113 -288.161476) (xy 345.921076 -288.161476) (xy 345.895819 -288.161016) (xy 345.845995 -288.152699)
			(xy 345.79822 -288.136294) (xy 345.753796 -288.11225) (xy 345.713935 -288.081222) (xy 345.679725 -288.044057)
			(xy 345.652098 -288.001768) (xy 345.631808 -287.955509) (xy 345.619408 -287.906541) (xy 345.615237 -287.8562)
			(xy 126.48092 -287.8562) (xy 126.480937 -287.8564) (xy 126.47676 -287.906793) (xy 126.464346 -287.955812)
			(xy 126.444032 -288.002118) (xy 126.416373 -288.044448) (xy 126.382123 -288.081648) (xy 126.342216 -288.112703)
			(xy 126.297743 -288.136765) (xy 126.249914 -288.153178) (xy 126.200037 -288.161494) (xy 126.174754 -288.161984)
			(xy 125.2347 -288.161984) (xy 125.209425 -288.161418) (xy 125.159566 -288.153098) (xy 125.111756 -288.136685)
			(xy 125.067299 -288.112626) (xy 125.027409 -288.081578) (xy 124.993173 -288.044388) (xy 124.965525 -288.00207)
			(xy 124.94522 -287.955779) (xy 124.932811 -287.906776) (xy 124.928637 -287.8564) (xy 123.660908 -287.8564)
			(xy 123.656733 -287.906779) (xy 123.644325 -287.955784) (xy 123.62402 -288.002078) (xy 123.596374 -288.0444)
			(xy 123.562139 -288.081594) (xy 123.522249 -288.112647) (xy 123.477793 -288.136711) (xy 123.429983 -288.153131)
			(xy 123.380122 -288.161458) (xy 123.354846 -288.161984) (xy 122.414792 -288.161984) (xy 122.389518 -288.161418)
			(xy 122.339659 -288.153096) (xy 122.29185 -288.136682) (xy 122.247395 -288.112623) (xy 122.207506 -288.081575)
			(xy 122.173271 -288.044385) (xy 122.145624 -288.002068) (xy 122.125319 -287.955777) (xy 122.112911 -287.906776)
			(xy 122.108736 -287.8564) (xy 120.840837 -287.8564) (xy 120.836661 -287.90679) (xy 120.824248 -287.955806)
			(xy 120.803937 -288.002109) (xy 120.776281 -288.044438) (xy 120.742034 -288.081638) (xy 120.702132 -288.112693)
			(xy 120.657663 -288.136756) (xy 120.609839 -288.153172) (xy 120.559965 -288.161492) (xy 120.534684 -288.161984)
			(xy 119.59463 -288.161984) (xy 119.569351 -288.161449) (xy 119.519483 -288.153132) (xy 119.471664 -288.13672)
			(xy 119.427199 -288.112661) (xy 119.387301 -288.08161) (xy 119.353058 -288.044416) (xy 119.325404 -288.002092)
			(xy 119.305094 -287.955794) (xy 119.292683 -287.906784) (xy 119.288507 -287.8564) (xy 118.020937 -287.8564)
			(xy 118.016761 -287.906791) (xy 118.004348 -287.955807) (xy 117.984035 -288.002112) (xy 117.956378 -288.044441)
			(xy 117.922131 -288.081641) (xy 117.882228 -288.112696) (xy 117.837757 -288.136759) (xy 117.789932 -288.153174)
			(xy 117.740058 -288.161493) (xy 117.714776 -288.161984) (xy 116.774722 -288.161984) (xy 116.749444 -288.161449)
			(xy 116.699577 -288.153131) (xy 116.651759 -288.136718) (xy 116.607295 -288.112658) (xy 116.567398 -288.081607)
			(xy 116.533156 -288.044413) (xy 116.505503 -288.00209) (xy 116.485194 -287.955792) (xy 116.472783 -287.906783)
			(xy 116.468607 -287.8564) (xy 107.687108 -287.8564) (xy 107.682933 -287.906779) (xy 107.670524 -287.955785)
			(xy 107.65022 -288.00208) (xy 107.622572 -288.044402) (xy 107.588336 -288.081596) (xy 107.548446 -288.112649)
			(xy 107.503989 -288.136713) (xy 107.456178 -288.153132) (xy 107.406316 -288.161459) (xy 107.38104 -288.161984)
			(xy 106.440986 -288.161984) (xy 106.415712 -288.161417) (xy 106.365854 -288.153095) (xy 106.318046 -288.136681)
			(xy 106.273592 -288.112621) (xy 106.233703 -288.081573) (xy 106.199469 -288.044383) (xy 106.171823 -288.002066)
			(xy 106.151519 -287.955776) (xy 106.139111 -287.906775) (xy 106.134936 -287.8564) (xy 104.867208 -287.8564)
			(xy 104.863033 -287.90678) (xy 104.850624 -287.955787) (xy 104.830318 -288.002082) (xy 104.80267 -288.044404)
			(xy 104.768433 -288.081599) (xy 104.728542 -288.112652) (xy 104.684084 -288.136716) (xy 104.636271 -288.153134)
			(xy 104.586408 -288.161459) (xy 104.561132 -288.161984) (xy 103.621078 -288.161984) (xy 103.595805 -288.161416)
			(xy 103.545948 -288.153093) (xy 103.498141 -288.136678) (xy 103.453687 -288.112618) (xy 103.4138 -288.08157)
			(xy 103.379567 -288.044381) (xy 103.351922 -288.002064) (xy 103.331618 -287.955774) (xy 103.31921 -287.906774)
			(xy 103.315036 -287.8564) (xy 102.047308 -287.8564) (xy 102.043133 -287.906781) (xy 102.030723 -287.955788)
			(xy 102.010417 -288.002084) (xy 101.982768 -288.044407) (xy 101.94853 -288.081602) (xy 101.908638 -288.112655)
			(xy 101.864178 -288.136718) (xy 101.816365 -288.153136) (xy 101.766501 -288.16146) (xy 101.741224 -288.161984)
			(xy 100.80117 -288.161984) (xy 100.775897 -288.161416) (xy 100.726041 -288.153092) (xy 100.678235 -288.136676)
			(xy 100.633783 -288.112616) (xy 100.593897 -288.081568) (xy 100.559665 -288.044378) (xy 100.532021 -288.002062)
			(xy 100.511718 -287.955773) (xy 100.49931 -287.906773) (xy 100.495136 -287.8564) (xy 99.227237 -287.8564)
			(xy 99.223061 -287.906792) (xy 99.210647 -287.95581) (xy 99.190333 -288.002115) (xy 99.162675 -288.044446)
			(xy 99.128426 -288.081646) (xy 99.088521 -288.1127) (xy 99.044048 -288.136763) (xy 98.996221 -288.153177)
			(xy 98.946345 -288.161494) (xy 98.921062 -288.161984) (xy 97.981008 -288.161984) (xy 97.955731 -288.161448)
			(xy 97.905865 -288.153128) (xy 97.858049 -288.136714) (xy 97.813588 -288.112653) (xy 97.773692 -288.081602)
			(xy 97.739452 -288.044409) (xy 97.711801 -288.002086) (xy 97.691493 -287.95579) (xy 97.679082 -287.906782)
			(xy 97.674907 -287.8564) (xy 2.509012 -287.8564) (xy 2.509012 -288.53257) (xy 16.85798 -288.53257)
			(xy 16.85798 -288.038032) (xy 16.858347 -288.032707) (xy 16.865864 -288.025165) (xy 16.871188 -288.024824)
			(xy 16.871696 -288.024824) (xy 17.38757 -288.024824) (xy 17.39538 -288.02451) (xy 17.410252 -288.019726)
			(xy 17.41678 -288.015426) (xy 17.437869 -288.001077) (xy 17.48353 -287.978346) (xy 17.532136 -287.962887)
			(xy 17.582539 -287.955064) (xy 17.633545 -287.955064) (xy 17.683948 -287.962887) (xy 17.732554 -287.978346)
			(xy 17.778215 -288.001077) (xy 17.799304 -288.015426) (xy 17.80584 -288.01971) (xy 17.820706 -288.024499)
			(xy 17.828514 -288.024824) (xy 18.344642 -288.024824) (xy 18.349948 -288.025293) (xy 18.357515 -288.032736)
			(xy 18.358104 -288.038032) (xy 18.358104 -288.53257) (xy 18.358077 -288.532824) (xy 24.402288 -288.532824)
			(xy 24.402288 -288.532316) (xy 24.402288 -288.038032) (xy 24.402648 -288.032705) (xy 24.41017 -288.025163)
			(xy 24.415496 -288.024824) (xy 24.931624 -288.024824) (xy 24.939436 -288.024533) (xy 24.954308 -288.019733)
			(xy 24.960834 -288.015426) (xy 24.981923 -288.001077) (xy 25.027584 -287.978346) (xy 25.07619 -287.962887)
			(xy 25.126593 -287.955064) (xy 25.177599 -287.955064) (xy 25.228002 -287.962887) (xy 25.276608 -287.978346)
			(xy 25.322269 -288.001077) (xy 25.343358 -288.015426) (xy 25.349882 -288.019731) (xy 25.364758 -288.024507)
			(xy 25.372568 -288.024824) (xy 25.888696 -288.024824) (xy 25.894035 -288.025133) (xy 25.901578 -288.032692)
			(xy 25.901904 -288.038032) (xy 25.901904 -288.53257) (xy 25.901878 -288.532824) (xy 31.946088 -288.532824)
			(xy 31.946088 -288.532316) (xy 31.946088 -288.038032) (xy 31.946448 -288.032705) (xy 31.95397 -288.025163)
			(xy 31.959296 -288.024824) (xy 32.475424 -288.024824) (xy 32.483236 -288.024533) (xy 32.498108 -288.019733)
			(xy 32.504634 -288.015426) (xy 32.525723 -288.001077) (xy 32.571384 -287.978346) (xy 32.61999 -287.962887)
			(xy 32.670393 -287.955064) (xy 32.721399 -287.955064) (xy 32.771802 -287.962887) (xy 32.820408 -287.978346)
			(xy 32.866069 -288.001077) (xy 32.887158 -288.015426) (xy 32.893682 -288.019731) (xy 32.908558 -288.024507)
			(xy 32.916368 -288.024824) (xy 33.432496 -288.024824) (xy 33.437835 -288.025133) (xy 33.445378 -288.032692)
			(xy 33.445704 -288.038032) (xy 33.445704 -288.53257) (xy 39.489888 -288.53257) (xy 39.489888 -288.038032)
			(xy 39.490248 -288.032705) (xy 39.49777 -288.025163) (xy 39.503096 -288.024824) (xy 39.503604 -288.024824)
			(xy 40.019478 -288.024824) (xy 40.027289 -288.024514) (xy 40.042161 -288.019727) (xy 40.048688 -288.015426)
			(xy 40.069777 -288.001077) (xy 40.115438 -287.978346) (xy 40.164044 -287.962887) (xy 40.214447 -287.955064)
			(xy 40.265453 -287.955064) (xy 40.315856 -287.962887) (xy 40.364462 -287.978346) (xy 40.410123 -288.001077)
			(xy 40.431212 -288.015426) (xy 40.437746 -288.019714) (xy 40.452614 -288.0245) (xy 40.460422 -288.024824)
			(xy 40.97655 -288.024824) (xy 40.981844 -288.025355) (xy 40.989417 -288.03275) (xy 40.990012 -288.038032)
			(xy 40.990012 -288.53257) (xy 40.989985 -288.532824) (xy 47.034196 -288.532824) (xy 47.034196 -288.532316)
			(xy 47.034196 -288.038032) (xy 47.034549 -288.032703) (xy 47.042076 -288.02516) (xy 47.047404 -288.024824)
			(xy 47.563532 -288.024824) (xy 47.571341 -288.024494) (xy 47.586213 -288.019721) (xy 47.592742 -288.015426)
			(xy 47.613831 -288.001077) (xy 47.659492 -287.978346) (xy 47.708098 -287.962887) (xy 47.758501 -287.955064)
			(xy 47.809507 -287.955064) (xy 47.85991 -287.962887) (xy 47.908516 -287.978346) (xy 47.954177 -288.001077)
			(xy 47.975266 -288.015426) (xy 47.98181 -288.019696) (xy 47.99667 -288.024494) (xy 48.004476 -288.024824)
			(xy 48.520604 -288.024824) (xy 48.525945 -288.025127) (xy 48.533487 -288.032691) (xy 48.533812 -288.038032)
			(xy 48.533812 -288.53257) (xy 54.577996 -288.53257) (xy 54.577996 -288.038032) (xy 54.578349 -288.032703)
			(xy 54.585876 -288.02516) (xy 54.591204 -288.024824) (xy 56.064658 -288.024824) (xy 56.069953 -288.025349)
			(xy 56.077526 -288.032749) (xy 56.07812 -288.038032) (xy 56.07812 -288.53257) (xy 56.077796 -288.538011)
			(xy 56.070099 -288.545701) (xy 56.064658 -288.546032) (xy 54.591458 -288.546032) (xy 54.586082 -288.545575)
			(xy 54.578497 -288.537949) (xy 54.577996 -288.53257) (xy 48.533812 -288.53257) (xy 48.533351 -288.537882)
			(xy 48.525907 -288.545457) (xy 48.520604 -288.546032) (xy 48.00473 -288.546032) (xy 47.996921 -288.546353)
			(xy 47.982049 -288.551134) (xy 47.97552 -288.55543) (xy 47.954389 -288.569764) (xy 47.908669 -288.592495)
			(xy 47.859998 -288.607929) (xy 47.809534 -288.615701) (xy 47.784004 -288.616136) (xy 47.758474 -288.615703)
			(xy 47.708009 -288.607927) (xy 47.659337 -288.592497) (xy 47.61361 -288.569778) (xy 47.592488 -288.55543)
			(xy 47.585957 -288.551139) (xy 47.571087 -288.546355) (xy 47.563278 -288.546032) (xy 47.047404 -288.546032)
			(xy 47.042148 -288.545505) (xy 47.034706 -288.538079) (xy 47.034196 -288.532824) (xy 40.989985 -288.532824)
			(xy 40.989435 -288.537918) (xy 40.981895 -288.545503) (xy 40.97655 -288.546032) (xy 40.460676 -288.546032)
			(xy 40.452864 -288.54633) (xy 40.437993 -288.551126) (xy 40.431466 -288.55543) (xy 40.41035 -288.569788)
			(xy 40.364624 -288.592513) (xy 40.315949 -288.607941) (xy 40.265481 -288.615705) (xy 40.23995 -288.616136)
			(xy 40.21442 -288.61568) (xy 40.163957 -288.607911) (xy 40.115285 -288.592487) (xy 40.069556 -288.569776)
			(xy 40.048434 -288.55543) (xy 40.041892 -288.551156) (xy 40.02703 -288.546362) (xy 40.019224 -288.546032)
			(xy 39.50335 -288.546032) (xy 39.497973 -288.54558) (xy 39.490388 -288.53795) (xy 39.489888 -288.53257)
			(xy 33.445704 -288.53257) (xy 33.445162 -288.53786) (xy 33.437773 -288.545431) (xy 33.432496 -288.546032)
			(xy 32.916622 -288.546032) (xy 32.908812 -288.546349) (xy 32.89394 -288.551132) (xy 32.887412 -288.55543)
			(xy 32.866283 -288.569768) (xy 32.820562 -288.592498) (xy 32.771891 -288.607931) (xy 32.721426 -288.615701)
			(xy 32.695896 -288.616136) (xy 32.670365 -288.615707) (xy 32.619901 -288.607929) (xy 32.571229 -288.592498)
			(xy 32.525501 -288.569779) (xy 32.50438 -288.55543) (xy 32.49785 -288.551135) (xy 32.482979 -288.546354)
			(xy 32.47517 -288.546032) (xy 31.959296 -288.546032) (xy 31.954038 -288.545511) (xy 31.946597 -288.538081)
			(xy 31.946088 -288.532824) (xy 25.901878 -288.532824) (xy 25.901362 -288.53786) (xy 25.893973 -288.545431)
			(xy 25.888696 -288.546032) (xy 25.372822 -288.546032) (xy 25.365012 -288.546349) (xy 25.35014 -288.551132)
			(xy 25.343612 -288.55543) (xy 25.322483 -288.569768) (xy 25.276762 -288.592498) (xy 25.228091 -288.607931)
			(xy 25.177626 -288.615701) (xy 25.152096 -288.616136) (xy 25.126565 -288.615707) (xy 25.076101 -288.607929)
			(xy 25.027429 -288.592498) (xy 24.981701 -288.569779) (xy 24.96058 -288.55543) (xy 24.95405 -288.551135)
			(xy 24.939179 -288.546354) (xy 24.93137 -288.546032) (xy 24.415496 -288.546032) (xy 24.410238 -288.545511)
			(xy 24.402797 -288.538081) (xy 24.402288 -288.532824) (xy 18.358077 -288.532824) (xy 18.357534 -288.53792)
			(xy 18.349989 -288.545505) (xy 18.344642 -288.546032) (xy 17.828768 -288.546032) (xy 17.82096 -288.546369)
			(xy 17.806088 -288.551139) (xy 17.799558 -288.55543) (xy 17.778444 -288.569791) (xy 17.732718 -288.592516)
			(xy 17.684042 -288.607943) (xy 17.633574 -288.615705) (xy 17.608042 -288.616136) (xy 17.582512 -288.615684)
			(xy 17.532049 -288.607913) (xy 17.483376 -288.592489) (xy 17.437648 -288.569776) (xy 17.416526 -288.55543)
			(xy 17.409986 -288.551153) (xy 17.395123 -288.546361) (xy 17.387316 -288.546032) (xy 16.871442 -288.546032)
			(xy 16.866006 -288.54569) (xy 16.858315 -288.538006) (xy 16.85798 -288.53257) (xy 2.509012 -288.53257)
			(xy 2.509012 -288.6662) (xy 108.484888 -288.6662) (xy 108.489063 -288.615816) (xy 108.501474 -288.566807)
			(xy 108.521782 -288.520509) (xy 108.549433 -288.478184) (xy 108.583674 -288.440989) (xy 108.62357 -288.409936)
			(xy 108.668032 -288.385873) (xy 108.715849 -288.369457) (xy 108.765716 -288.361134) (xy 108.790994 -288.360612)
			(xy 109.731048 -288.360612) (xy 109.75632 -288.36119) (xy 109.806172 -288.369516) (xy 109.853975 -288.385933)
			(xy 109.898424 -288.409994) (xy 109.938307 -288.441042) (xy 109.972536 -288.47823) (xy 110.000179 -288.520545)
			(xy 110.02048 -288.566832) (xy 110.032886 -288.615829) (xy 110.03706 -288.6662) (xy 114.118559 -288.6662)
			(xy 114.122735 -288.615809) (xy 114.135148 -288.566794) (xy 114.15546 -288.520489) (xy 114.183116 -288.47816)
			(xy 114.217362 -288.44096) (xy 114.257264 -288.409905) (xy 114.301734 -288.385841) (xy 114.349558 -288.369424)
			(xy 114.399432 -288.361104) (xy 114.424714 -288.360612) (xy 115.364768 -288.360612) (xy 115.390046 -288.361154)
			(xy 115.439914 -288.369471) (xy 115.487733 -288.385883) (xy 115.532198 -288.409942) (xy 115.572096 -288.440992)
			(xy 115.606339 -288.478186) (xy 115.633992 -288.520509) (xy 115.639394 -288.532824) (xy 163.678108 -288.532824)
			(xy 163.678108 -288.532316) (xy 163.678108 -288.038032) (xy 163.67845 -288.0327) (xy 163.685985 -288.025156)
			(xy 163.691316 -288.024824) (xy 165.164516 -288.024824) (xy 165.169858 -288.025119) (xy 165.1774 -288.032688)
			(xy 165.177724 -288.038032) (xy 165.177724 -288.53257) (xy 171.221908 -288.53257) (xy 171.221908 -288.038032)
			(xy 171.22225 -288.0327) (xy 171.229785 -288.025156) (xy 171.235116 -288.024824) (xy 171.235624 -288.024824)
			(xy 171.751498 -288.024824) (xy 171.759309 -288.024522) (xy 171.774181 -288.019729) (xy 171.780708 -288.015426)
			(xy 171.801797 -288.001077) (xy 171.847458 -287.978346) (xy 171.896064 -287.962887) (xy 171.946467 -287.955064)
			(xy 171.997473 -287.955064) (xy 172.047876 -287.962887) (xy 172.096482 -287.978346) (xy 172.142143 -288.001077)
			(xy 172.163232 -288.015426) (xy 172.169761 -288.019721) (xy 172.184633 -288.024503) (xy 172.192442 -288.024824)
			(xy 172.70857 -288.024824) (xy 172.713867 -288.025341) (xy 172.721439 -288.032747) (xy 172.722032 -288.038032)
			(xy 172.722032 -288.53257) (xy 172.722016 -288.532824) (xy 178.766216 -288.532824) (xy 178.766216 -288.532316)
			(xy 178.766216 -288.038032) (xy 178.766551 -288.032698) (xy 178.77409 -288.025154) (xy 178.779424 -288.024824)
			(xy 179.295552 -288.024824) (xy 179.303362 -288.024503) (xy 179.318234 -288.019723) (xy 179.324762 -288.015426)
			(xy 179.345851 -288.001077) (xy 179.391512 -287.978346) (xy 179.440118 -287.962887) (xy 179.490521 -287.955064)
			(xy 179.541527 -287.955064) (xy 179.59193 -287.962887) (xy 179.640536 -287.978346) (xy 179.686197 -288.001077)
			(xy 179.707286 -288.015426) (xy 179.713826 -288.019704) (xy 179.728689 -288.024496) (xy 179.736496 -288.024824)
			(xy 180.252624 -288.024824) (xy 180.257967 -288.025114) (xy 180.265509 -288.032687) (xy 180.265832 -288.038032)
			(xy 180.265832 -288.53257) (xy 186.310016 -288.53257) (xy 186.310016 -288.038032) (xy 186.310351 -288.032698)
			(xy 186.31789 -288.025154) (xy 186.323224 -288.024824) (xy 186.323732 -288.024824) (xy 186.839606 -288.024824)
			(xy 186.847418 -288.024526) (xy 186.862289 -288.01973) (xy 186.868816 -288.015426) (xy 186.889905 -288.001077)
			(xy 186.935566 -287.978346) (xy 186.984172 -287.962887) (xy 187.034575 -287.955064) (xy 187.085581 -287.955064)
			(xy 187.135984 -287.962887) (xy 187.18459 -287.978346) (xy 187.230251 -288.001077) (xy 187.25134 -288.015426)
			(xy 187.257868 -288.019724) (xy 187.27274 -288.024504) (xy 187.28055 -288.024824) (xy 187.796678 -288.024824)
			(xy 187.801976 -288.025336) (xy 187.809547 -288.032746) (xy 187.81014 -288.038032) (xy 187.81014 -288.53257)
			(xy 187.810124 -288.532824) (xy 193.854324 -288.532824) (xy 193.854324 -288.532316) (xy 193.854324 -288.038032)
			(xy 193.854652 -288.032696) (xy 193.862196 -288.025152) (xy 193.867532 -288.024824) (xy 194.38366 -288.024824)
			(xy 194.39147 -288.024506) (xy 194.406342 -288.019724) (xy 194.41287 -288.015426) (xy 194.433959 -288.001077)
			(xy 194.47962 -287.978346) (xy 194.528226 -287.962887) (xy 194.578629 -287.955064) (xy 194.629635 -287.955064)
			(xy 194.680038 -287.962887) (xy 194.728644 -287.978346) (xy 194.774305 -288.001077) (xy 194.795394 -288.015426)
			(xy 194.801932 -288.019707) (xy 194.816797 -288.024498) (xy 194.824604 -288.024824) (xy 195.340732 -288.024824)
			(xy 195.346006 -288.025277) (xy 195.353449 -288.032755) (xy 195.35394 -288.038032) (xy 195.35394 -288.53257)
			(xy 195.353917 -288.532824) (xy 201.398124 -288.532824) (xy 201.398124 -288.532316) (xy 201.398124 -288.038032)
			(xy 201.398452 -288.032696) (xy 201.405996 -288.025152) (xy 201.411332 -288.024824) (xy 201.92746 -288.024824)
			(xy 201.93527 -288.024506) (xy 201.950142 -288.019724) (xy 201.95667 -288.015426) (xy 201.977759 -288.001077)
			(xy 202.02342 -287.978346) (xy 202.072026 -287.962887) (xy 202.122429 -287.955064) (xy 202.173435 -287.955064)
			(xy 202.223838 -287.962887) (xy 202.272444 -287.978346) (xy 202.318105 -288.001077) (xy 202.339194 -288.015426)
			(xy 202.345732 -288.019707) (xy 202.360597 -288.024498) (xy 202.368404 -288.024824) (xy 202.884532 -288.024824)
			(xy 202.889806 -288.025277) (xy 202.897249 -288.032755) (xy 202.89774 -288.038032) (xy 202.89774 -288.532316)
			(xy 264.798048 -288.532316) (xy 264.798048 -288.037778) (xy 264.798537 -288.032409) (xy 264.80614 -288.024824)
			(xy 264.81151 -288.024316) (xy 265.327638 -288.024316) (xy 265.335447 -288.02399) (xy 265.350319 -288.019214)
			(xy 265.356848 -288.014918) (xy 265.377937 -288.000569) (xy 265.423598 -287.977838) (xy 265.472204 -287.962379)
			(xy 265.522607 -287.954556) (xy 265.573613 -287.954556) (xy 265.624016 -287.962379) (xy 265.672622 -287.977838)
			(xy 265.718283 -288.000569) (xy 265.739372 -288.014918) (xy 265.745915 -288.019189) (xy 265.760776 -288.023986)
			(xy 265.768582 -288.024316) (xy 266.28471 -288.024316) (xy 266.29007 -288.024842) (xy 266.297654 -288.032419)
			(xy 266.298172 -288.037778) (xy 266.298172 -288.532316) (xy 272.342356 -288.532316) (xy 272.342356 -288.037778)
			(xy 272.34281 -288.032467) (xy 272.350262 -288.024897) (xy 272.355564 -288.024316) (xy 272.871692 -288.024316)
			(xy 272.879503 -288.024013) (xy 272.894375 -288.019221) (xy 272.900902 -288.014918) (xy 272.921991 -288.000569)
			(xy 272.967652 -287.977838) (xy 273.016258 -287.962379) (xy 273.066661 -287.954556) (xy 273.117667 -287.954556)
			(xy 273.16807 -287.962379) (xy 273.216676 -287.977838) (xy 273.262337 -288.000569) (xy 273.283426 -288.014918)
			(xy 273.289957 -288.01921) (xy 273.304827 -288.023994) (xy 273.312636 -288.024316) (xy 273.828764 -288.024316)
			(xy 273.834097 -288.024653) (xy 273.841642 -288.032191) (xy 273.841972 -288.037524) (xy 273.841972 -288.038032)
			(xy 273.841972 -288.532316) (xy 279.886156 -288.532316) (xy 279.886156 -288.037778) (xy 279.88661 -288.032467)
			(xy 279.894062 -288.024897) (xy 279.899364 -288.024316) (xy 280.415492 -288.024316) (xy 280.423303 -288.024013)
			(xy 280.438175 -288.019221) (xy 280.444702 -288.014918) (xy 280.465791 -288.000569) (xy 280.511452 -287.977838)
			(xy 280.560058 -287.962379) (xy 280.610461 -287.954556) (xy 280.661467 -287.954556) (xy 280.71187 -287.962379)
			(xy 280.760476 -287.977838) (xy 280.806137 -288.000569) (xy 280.827226 -288.014918) (xy 280.833757 -288.01921)
			(xy 280.848627 -288.023994) (xy 280.856436 -288.024316) (xy 281.372564 -288.024316) (xy 281.377897 -288.024653)
			(xy 281.385442 -288.032191) (xy 281.385772 -288.037524) (xy 281.385772 -288.038032) (xy 281.385772 -288.532316)
			(xy 287.429956 -288.532316) (xy 287.429956 -288.037778) (xy 287.430438 -288.032407) (xy 287.438046 -288.024822)
			(xy 287.443418 -288.024316) (xy 287.959546 -288.024316) (xy 287.967356 -288.023994) (xy 287.982228 -288.019215)
			(xy 287.988756 -288.014918) (xy 288.009845 -288.000569) (xy 288.055506 -287.977838) (xy 288.104112 -287.962379)
			(xy 288.154515 -287.954556) (xy 288.205521 -287.954556) (xy 288.255924 -287.962379) (xy 288.30453 -287.977838)
			(xy 288.350191 -288.000569) (xy 288.37128 -288.014918) (xy 288.377821 -288.019193) (xy 288.392684 -288.023987)
			(xy 288.40049 -288.024316) (xy 288.916618 -288.024316) (xy 288.921979 -288.024836) (xy 288.929562 -288.032417)
			(xy 288.93008 -288.037778) (xy 288.93008 -288.532316) (xy 294.974264 -288.532316) (xy 294.974264 -288.037778)
			(xy 294.974711 -288.032466) (xy 294.982168 -288.024894) (xy 294.987472 -288.024316) (xy 295.5036 -288.024316)
			(xy 295.511412 -288.024016) (xy 295.526283 -288.019222) (xy 295.53281 -288.014918) (xy 295.553899 -288.000569)
			(xy 295.59956 -287.977838) (xy 295.648166 -287.962379) (xy 295.698569 -287.954556) (xy 295.749575 -287.954556)
			(xy 295.799978 -287.962379) (xy 295.848584 -287.977838) (xy 295.894245 -288.000569) (xy 295.915334 -288.014918)
			(xy 295.921863 -288.019213) (xy 295.936735 -288.023995) (xy 295.944544 -288.024316) (xy 296.460672 -288.024316)
			(xy 296.466006 -288.024648) (xy 296.473551 -288.03219) (xy 296.47388 -288.037524) (xy 296.47388 -288.038032)
			(xy 296.47388 -288.532316) (xy 302.518064 -288.532316) (xy 302.518064 -288.037778) (xy 302.518367 -288.032334)
			(xy 302.526081 -288.024648) (xy 302.531526 -288.024316) (xy 304.004726 -288.024316) (xy 304.010088 -288.024831)
			(xy 304.017671 -288.032416) (xy 304.018188 -288.037778) (xy 304.018188 -288.532316) (xy 304.017882 -288.537655)
			(xy 304.01032 -288.545197) (xy 304.00498 -288.545524) (xy 302.531526 -288.545524) (xy 302.526217 -288.545055)
			(xy 302.518642 -288.537616) (xy 302.518064 -288.532316) (xy 296.47388 -288.532316) (xy 296.473581 -288.537657)
			(xy 296.466014 -288.545199) (xy 296.460672 -288.545524) (xy 295.944798 -288.545524) (xy 295.936925 -288.545823)
			(xy 295.921921 -288.550599) (xy 295.915334 -288.554922) (xy 295.894263 -288.569324) (xy 295.848616 -288.592151)
			(xy 295.800008 -288.607706) (xy 295.749589 -288.615621) (xy 295.724072 -288.616136) (xy 295.698553 -288.615621)
			(xy 295.648127 -288.607733) (xy 295.599516 -288.59218) (xy 295.553876 -288.569333) (xy 295.53281 -288.554922)
			(xy 295.526217 -288.55061) (xy 295.511218 -288.545821) (xy 295.503346 -288.545524) (xy 294.987472 -288.545524)
			(xy 294.98221 -288.545026) (xy 294.97477 -288.537579) (xy 294.974264 -288.532316) (xy 288.93008 -288.532316)
			(xy 288.929781 -288.537657) (xy 288.922214 -288.545199) (xy 288.916872 -288.545524) (xy 288.916364 -288.545524)
			(xy 288.400744 -288.545524) (xy 288.392868 -288.545799) (xy 288.377865 -288.550592) (xy 288.37128 -288.554922)
			(xy 288.350196 -288.569304) (xy 288.304554 -288.592135) (xy 288.25595 -288.607696) (xy 288.205534 -288.615618)
			(xy 288.180018 -288.616136) (xy 288.154498 -288.615648) (xy 288.104071 -288.607752) (xy 288.05546 -288.592191)
			(xy 288.009821 -288.569337) (xy 287.988756 -288.554922) (xy 287.982175 -288.55059) (xy 287.967167 -288.545813)
			(xy 287.959292 -288.545524) (xy 287.443418 -288.545524) (xy 287.438108 -288.545061) (xy 287.430533 -288.537617)
			(xy 287.429956 -288.532316) (xy 281.385772 -288.532316) (xy 281.385481 -288.537659) (xy 281.377909 -288.545202)
			(xy 281.372564 -288.545524) (xy 280.85669 -288.545524) (xy 280.848816 -288.545819) (xy 280.833812 -288.550598)
			(xy 280.827226 -288.554922) (xy 280.806157 -288.569327) (xy 280.76051 -288.592153) (xy 280.711901 -288.607707)
			(xy 280.661482 -288.615622) (xy 280.635964 -288.616136) (xy 280.610445 -288.615625) (xy 280.560019 -288.607736)
			(xy 280.511408 -288.592182) (xy 280.465768 -288.569334) (xy 280.444702 -288.554922) (xy 280.43811 -288.550607)
			(xy 280.42311 -288.54582) (xy 280.415238 -288.545524) (xy 279.899364 -288.545524) (xy 279.894101 -288.545031)
			(xy 279.886661 -288.53758) (xy 279.886156 -288.532316) (xy 273.841972 -288.532316) (xy 273.841681 -288.537659)
			(xy 273.834109 -288.545202) (xy 273.828764 -288.545524) (xy 273.31289 -288.545524) (xy 273.305016 -288.545819)
			(xy 273.290012 -288.550598) (xy 273.283426 -288.554922) (xy 273.262357 -288.569327) (xy 273.21671 -288.592153)
			(xy 273.168101 -288.607707) (xy 273.117682 -288.615622) (xy 273.092164 -288.616136) (xy 273.066645 -288.615625)
			(xy 273.016219 -288.607736) (xy 272.967608 -288.592182) (xy 272.921968 -288.569334) (xy 272.900902 -288.554922)
			(xy 272.89431 -288.550607) (xy 272.87931 -288.54582) (xy 272.871438 -288.545524) (xy 272.355564 -288.545524)
			(xy 272.350301 -288.545031) (xy 272.342861 -288.53758) (xy 272.342356 -288.532316) (xy 266.298172 -288.532316)
			(xy 266.297881 -288.537659) (xy 266.290309 -288.545202) (xy 266.284964 -288.545524) (xy 266.284456 -288.545524)
			(xy 265.768836 -288.545524) (xy 265.76096 -288.545796) (xy 265.745956 -288.550591) (xy 265.739372 -288.554922)
			(xy 265.718291 -288.569308) (xy 265.672647 -288.592138) (xy 265.624043 -288.607698) (xy 265.573626 -288.615618)
			(xy 265.54811 -288.616136) (xy 265.52259 -288.615652) (xy 265.472163 -288.607755) (xy 265.423551 -288.592193)
			(xy 265.377913 -288.569337) (xy 265.356848 -288.554922) (xy 265.350268 -288.550586) (xy 265.335259 -288.545812)
			(xy 265.327384 -288.545524) (xy 264.81151 -288.545524) (xy 264.806199 -288.545066) (xy 264.798625 -288.537618)
			(xy 264.798048 -288.532316) (xy 202.89774 -288.532316) (xy 202.89774 -288.53257) (xy 202.897255 -288.537875)
			(xy 202.889827 -288.545449) (xy 202.884532 -288.546032) (xy 202.368658 -288.546032) (xy 202.36085 -288.546365)
			(xy 202.345978 -288.551137) (xy 202.339448 -288.55543) (xy 202.318337 -288.569795) (xy 202.272609 -288.592519)
			(xy 202.223933 -288.607945) (xy 202.173464 -288.615706) (xy 202.147932 -288.616136) (xy 202.122402 -288.615689)
			(xy 202.071938 -288.607917) (xy 202.023266 -288.592491) (xy 201.977538 -288.569777) (xy 201.956416 -288.55543)
			(xy 201.949878 -288.551149) (xy 201.935013 -288.546359) (xy 201.927206 -288.546032) (xy 201.411332 -288.546032)
			(xy 201.40601 -288.545654) (xy 201.398469 -288.538145) (xy 201.398124 -288.532824) (xy 195.353917 -288.532824)
			(xy 195.353455 -288.537875) (xy 195.346027 -288.545449) (xy 195.340732 -288.546032) (xy 194.824858 -288.546032)
			(xy 194.81705 -288.546365) (xy 194.802178 -288.551137) (xy 194.795648 -288.55543) (xy 194.774537 -288.569795)
			(xy 194.728809 -288.592519) (xy 194.680133 -288.607945) (xy 194.629664 -288.615706) (xy 194.604132 -288.616136)
			(xy 194.578602 -288.615689) (xy 194.528138 -288.607917) (xy 194.479466 -288.592491) (xy 194.433738 -288.569777)
			(xy 194.412616 -288.55543) (xy 194.406078 -288.551149) (xy 194.391213 -288.546359) (xy 194.383406 -288.546032)
			(xy 193.867532 -288.546032) (xy 193.86221 -288.545654) (xy 193.854669 -288.538145) (xy 193.854324 -288.532824)
			(xy 187.810124 -288.532824) (xy 187.809798 -288.538006) (xy 187.802114 -288.545695) (xy 187.796678 -288.546032)
			(xy 187.280804 -288.546032) (xy 187.272993 -288.546342) (xy 187.258122 -288.55113) (xy 187.251594 -288.55543)
			(xy 187.23047 -288.569775) (xy 187.184747 -288.592504) (xy 187.136075 -288.607935) (xy 187.085609 -288.615702)
			(xy 187.060078 -288.616136) (xy 187.034547 -288.615716) (xy 186.984082 -288.607936) (xy 186.93541 -288.592502)
			(xy 186.889683 -288.56978) (xy 186.868562 -288.55543) (xy 186.862036 -288.551129) (xy 186.847162 -288.546351)
			(xy 186.839352 -288.546032) (xy 186.323478 -288.546032) (xy 186.318033 -288.545732) (xy 186.310346 -288.538016)
			(xy 186.310016 -288.53257) (xy 180.265832 -288.53257) (xy 180.265354 -288.537877) (xy 180.257921 -288.545452)
			(xy 180.252624 -288.546032) (xy 179.73675 -288.546032) (xy 179.728941 -288.546362) (xy 179.71407 -288.551136)
			(xy 179.70754 -288.55543) (xy 179.686431 -288.569799) (xy 179.640703 -288.592522) (xy 179.592026 -288.607946)
			(xy 179.541556 -288.615707) (xy 179.516024 -288.616136) (xy 179.490494 -288.615693) (xy 179.44003 -288.60792)
			(xy 179.391358 -288.592493) (xy 179.34563 -288.569777) (xy 179.324508 -288.55543) (xy 179.317972 -288.551146)
			(xy 179.303106 -288.546358) (xy 179.295298 -288.546032) (xy 178.779424 -288.546032) (xy 178.77417 -288.545492)
			(xy 178.766727 -288.538076) (xy 178.766216 -288.532824) (xy 172.722016 -288.532824) (xy 172.721697 -288.538008)
			(xy 172.714008 -288.545697) (xy 172.70857 -288.546032) (xy 172.192696 -288.546032) (xy 172.184885 -288.546338)
			(xy 172.170014 -288.551129) (xy 172.163486 -288.55543) (xy 172.142364 -288.569779) (xy 172.096641 -288.592506)
			(xy 172.047967 -288.607937) (xy 171.997501 -288.615703) (xy 171.97197 -288.616136) (xy 171.946439 -288.61572)
			(xy 171.895974 -288.607938) (xy 171.847302 -288.592504) (xy 171.801575 -288.569781) (xy 171.780454 -288.55543)
			(xy 171.77393 -288.551125) (xy 171.759054 -288.54635) (xy 171.751244 -288.546032) (xy 171.23537 -288.546032)
			(xy 171.229995 -288.545567) (xy 171.222409 -288.537947) (xy 171.221908 -288.53257) (xy 165.177724 -288.53257)
			(xy 165.177253 -288.537879) (xy 165.169815 -288.545454) (xy 165.164516 -288.546032) (xy 163.691316 -288.546032)
			(xy 163.686061 -288.545497) (xy 163.678619 -288.538078) (xy 163.678108 -288.532824) (xy 115.639394 -288.532824)
			(xy 115.654302 -288.566807) (xy 115.666713 -288.615816) (xy 115.670864 -288.6659) (xy 356.425289 -288.6659)
			(xy 356.429459 -288.615569) (xy 356.441856 -288.566611) (xy 356.462142 -288.520361) (xy 356.489762 -288.47808)
			(xy 356.523965 -288.440921) (xy 356.563817 -288.409898) (xy 356.608231 -288.385858) (xy 356.655997 -288.369455)
			(xy 356.70581 -288.361136) (xy 356.731062 -288.360612) (xy 357.671116 -288.360612) (xy 357.696372 -288.361095)
			(xy 357.746195 -288.369411) (xy 357.79397 -288.385815) (xy 357.838393 -288.409857) (xy 357.878253 -288.440884)
			(xy 357.912464 -288.478048) (xy 357.94009 -288.520335) (xy 357.96038 -288.566594) (xy 357.97278 -288.61556)
			(xy 357.976951 -288.6659) (xy 362.058989 -288.6659) (xy 362.06316 -288.615567) (xy 362.075557 -288.566607)
			(xy 362.095845 -288.520355) (xy 362.123467 -288.478073) (xy 362.157673 -288.440914) (xy 362.197528 -288.409892)
			(xy 362.241945 -288.385852) (xy 362.289713 -288.36945) (xy 362.339529 -288.361135) (xy 362.364782 -288.360612)
			(xy 363.304836 -288.360612) (xy 363.330091 -288.361096) (xy 363.379911 -288.369415) (xy 363.427683 -288.38582)
			(xy 363.472104 -288.409864) (xy 363.511961 -288.440891) (xy 363.546169 -288.478054) (xy 363.573793 -288.520341)
			(xy 363.579045 -288.532316) (xy 411.618176 -288.532316) (xy 411.618176 -288.037778) (xy 411.618613 -288.032463)
			(xy 411.626076 -288.024891) (xy 411.631384 -288.024316) (xy 413.104584 -288.024316) (xy 413.10992 -288.02464)
			(xy 413.117463 -288.032188) (xy 413.117792 -288.037524) (xy 413.117792 -288.038032) (xy 413.117792 -288.532316)
			(xy 419.161976 -288.532316) (xy 419.161976 -288.037778) (xy 419.162268 -288.032331) (xy 419.169989 -288.024644)
			(xy 419.175438 -288.024316) (xy 419.691566 -288.024316) (xy 419.699376 -288.024002) (xy 419.714248 -288.019218)
			(xy 419.720776 -288.014918) (xy 419.741865 -288.000569) (xy 419.787526 -287.977838) (xy 419.836132 -287.962379)
			(xy 419.886535 -287.954556) (xy 419.937541 -287.954556) (xy 419.987944 -287.962379) (xy 420.03655 -287.977838)
			(xy 420.082211 -288.000569) (xy 420.1033 -288.014918) (xy 420.109837 -288.0192) (xy 420.124703 -288.02399)
			(xy 420.13251 -288.024316) (xy 420.648638 -288.024316) (xy 420.654001 -288.024823) (xy 420.661583 -288.032414)
			(xy 420.6621 -288.037778) (xy 420.6621 -288.532316) (xy 426.706284 -288.532316) (xy 426.706284 -288.037778)
			(xy 426.706714 -288.032461) (xy 426.714182 -288.024888) (xy 426.719492 -288.024316) (xy 427.23562 -288.024316)
			(xy 427.243432 -288.024025) (xy 427.258304 -288.019225) (xy 427.26483 -288.014918) (xy 427.285919 -288.000569)
			(xy 427.33158 -287.977838) (xy 427.380186 -287.962379) (xy 427.430589 -287.954556) (xy 427.481595 -287.954556)
			(xy 427.531998 -287.962379) (xy 427.580604 -287.977838) (xy 427.626265 -288.000569) (xy 427.647354 -288.014918)
			(xy 427.653879 -288.019221) (xy 427.668754 -288.023998) (xy 427.676564 -288.024316) (xy 428.192692 -288.024316)
			(xy 428.198029 -288.024634) (xy 428.205572 -288.032187) (xy 428.2059 -288.037524) (xy 428.2059 -288.038032)
			(xy 428.2059 -288.532316) (xy 434.250084 -288.532316) (xy 434.250084 -288.037778) (xy 434.250369 -288.032329)
			(xy 434.258095 -288.024642) (xy 434.263546 -288.024316) (xy 434.779674 -288.024316) (xy 434.787485 -288.024005)
			(xy 434.802357 -288.019219) (xy 434.808884 -288.014918) (xy 434.829973 -288.000569) (xy 434.875634 -287.977838)
			(xy 434.92424 -287.962379) (xy 434.974643 -287.954556) (xy 435.025649 -287.954556) (xy 435.076052 -287.962379)
			(xy 435.124658 -287.977838) (xy 435.170319 -288.000569) (xy 435.191408 -288.014918) (xy 435.197943 -288.019203)
			(xy 435.21281 -288.023992) (xy 435.220618 -288.024316) (xy 435.736746 -288.024316) (xy 435.74211 -288.024818)
			(xy 435.749692 -288.032413) (xy 435.750208 -288.037778) (xy 435.750208 -288.532316) (xy 441.794392 -288.532316)
			(xy 441.794392 -288.037778) (xy 441.794903 -288.032482) (xy 441.802316 -288.024915) (xy 441.8076 -288.024316)
			(xy 442.323728 -288.024316) (xy 442.331541 -288.024028) (xy 442.346412 -288.019226) (xy 442.352938 -288.014918)
			(xy 442.374027 -288.000569) (xy 442.419688 -287.977838) (xy 442.468294 -287.962379) (xy 442.518697 -287.954556)
			(xy 442.569703 -287.954556) (xy 442.620106 -287.962379) (xy 442.668712 -287.977838) (xy 442.714373 -288.000569)
			(xy 442.735462 -288.014918) (xy 442.742008 -288.019186) (xy 442.756867 -288.023985) (xy 442.764672 -288.024316)
			(xy 443.2808 -288.024316) (xy 443.286138 -288.024629) (xy 443.293681 -288.032185) (xy 443.294008 -288.037524)
			(xy 443.294008 -288.038032) (xy 443.294008 -288.532316) (xy 449.338192 -288.532316) (xy 449.338192 -288.037778)
			(xy 449.338703 -288.032482) (xy 449.346116 -288.024915) (xy 449.3514 -288.024316) (xy 449.867528 -288.024316)
			(xy 449.875341 -288.024028) (xy 449.890212 -288.019226) (xy 449.896738 -288.014918) (xy 449.917827 -288.000569)
			(xy 449.963488 -287.977838) (xy 450.012094 -287.962379) (xy 450.062497 -287.954556) (xy 450.113503 -287.954556)
			(xy 450.163906 -287.962379) (xy 450.212512 -287.977838) (xy 450.258173 -288.000569) (xy 450.279262 -288.014918)
			(xy 450.285808 -288.019186) (xy 450.300667 -288.023985) (xy 450.308472 -288.024316) (xy 450.8246 -288.024316)
			(xy 450.829938 -288.024629) (xy 450.837481 -288.032185) (xy 450.837808 -288.037524) (xy 450.837808 -288.038032)
			(xy 450.837808 -288.532316) (xy 450.837316 -288.537581) (xy 450.829865 -288.545022) (xy 450.8246 -288.545524)
			(xy 450.308726 -288.545524) (xy 450.30085 -288.545792) (xy 450.285846 -288.55059) (xy 450.279262 -288.554922)
			(xy 450.258183 -288.569312) (xy 450.212539 -288.592141) (xy 450.163934 -288.6077) (xy 450.113517 -288.615619)
			(xy 450.088 -288.616136) (xy 450.062479 -288.615657) (xy 450.012052 -288.607758) (xy 449.963441 -288.592195)
			(xy 449.917803 -288.569338) (xy 449.896738 -288.554922) (xy 449.890138 -288.550621) (xy 449.875145 -288.545825)
			(xy 449.867274 -288.545524) (xy 449.3514 -288.545524) (xy 449.346141 -288.545007) (xy 449.3387 -288.537574)
			(xy 449.338192 -288.532316) (xy 443.294008 -288.532316) (xy 443.293516 -288.537581) (xy 443.286065 -288.545022)
			(xy 443.2808 -288.545524) (xy 442.764926 -288.545524) (xy 442.75705 -288.545792) (xy 442.742046 -288.55059)
			(xy 442.735462 -288.554922) (xy 442.714383 -288.569312) (xy 442.668739 -288.592141) (xy 442.620134 -288.6077)
			(xy 442.569717 -288.615619) (xy 442.5442 -288.616136) (xy 442.518679 -288.615657) (xy 442.468252 -288.607758)
			(xy 442.419641 -288.592195) (xy 442.374003 -288.569338) (xy 442.352938 -288.554922) (xy 442.346338 -288.550621)
			(xy 442.331345 -288.545825) (xy 442.323474 -288.545524) (xy 441.8076 -288.545524) (xy 441.802341 -288.545007)
			(xy 441.7949 -288.537574) (xy 441.794392 -288.532316) (xy 435.750208 -288.532316) (xy 435.749716 -288.537581)
			(xy 435.742265 -288.545022) (xy 435.737 -288.545524) (xy 435.736492 -288.545524) (xy 435.220872 -288.545524)
			(xy 435.212998 -288.545811) (xy 435.197994 -288.550596) (xy 435.191408 -288.554922) (xy 435.170345 -288.569335)
			(xy 435.124695 -288.592159) (xy 435.076085 -288.607711) (xy 435.025664 -288.615623) (xy 435.000146 -288.616136)
			(xy 434.974626 -288.615634) (xy 434.9242 -288.607742) (xy 434.875589 -288.592185) (xy 434.82995 -288.569335)
			(xy 434.808884 -288.554922) (xy 434.802296 -288.5506) (xy 434.787293 -288.545817) (xy 434.77942 -288.545524)
			(xy 434.263546 -288.545524) (xy 434.258239 -288.545042) (xy 434.250663 -288.537613) (xy 434.250084 -288.532316)
			(xy 428.2059 -288.532316) (xy 428.205415 -288.537583) (xy 428.19796 -288.545025) (xy 428.192692 -288.545524)
			(xy 427.676818 -288.545524) (xy 427.668945 -288.545832) (xy 427.653941 -288.550602) (xy 427.647354 -288.554922)
			(xy 427.626278 -288.569315) (xy 427.580633 -288.592144) (xy 427.532026 -288.607702) (xy 427.481609 -288.61562)
			(xy 427.456092 -288.616136) (xy 427.430573 -288.615611) (xy 427.380148 -288.607726) (xy 427.331537 -288.592176)
			(xy 427.285897 -288.569332) (xy 427.26483 -288.554922) (xy 427.258232 -288.550618) (xy 427.243237 -288.545824)
			(xy 427.235366 -288.545524) (xy 426.719492 -288.545524) (xy 426.714232 -288.545012) (xy 426.706791 -288.537576)
			(xy 426.706284 -288.532316) (xy 420.6621 -288.532316) (xy 420.661615 -288.537583) (xy 420.65416 -288.545025)
			(xy 420.648892 -288.545524) (xy 420.648384 -288.545524) (xy 420.132764 -288.545524) (xy 420.124889 -288.545808)
			(xy 420.109885 -288.550595) (xy 420.1033 -288.554922) (xy 420.082211 -288.569296) (xy 420.03657 -288.592129)
			(xy 419.987968 -288.607692) (xy 419.937554 -288.615616) (xy 419.912038 -288.616136) (xy 419.886518 -288.615638)
			(xy 419.836092 -288.607745) (xy 419.78748 -288.592187) (xy 419.741842 -288.569335) (xy 419.720776 -288.554922)
			(xy 419.71419 -288.550597) (xy 419.699186 -288.545816) (xy 419.691312 -288.545524) (xy 419.175438 -288.545524)
			(xy 419.17013 -288.545047) (xy 419.162555 -288.537614) (xy 419.161976 -288.532316) (xy 413.117792 -288.532316)
			(xy 413.117315 -288.537585) (xy 413.109854 -288.545027) (xy 413.104584 -288.545524) (xy 411.631384 -288.545524)
			(xy 411.626123 -288.545018) (xy 411.618682 -288.537577) (xy 411.618176 -288.532316) (xy 363.579045 -288.532316)
			(xy 363.594082 -288.566598) (xy 363.60648 -288.615562) (xy 363.610651 -288.6659) (xy 363.60648 -288.716238)
			(xy 363.594082 -288.765202) (xy 363.573793 -288.811459) (xy 363.546169 -288.853746) (xy 363.511961 -288.890909)
			(xy 363.472104 -288.921936) (xy 363.427683 -288.94598) (xy 363.379911 -288.962385) (xy 363.330091 -288.970704)
			(xy 363.304836 -288.971228) (xy 362.364782 -288.971228) (xy 362.339529 -288.970665) (xy 362.289713 -288.96235)
			(xy 362.241945 -288.945948) (xy 362.197528 -288.921908) (xy 362.157673 -288.890886) (xy 362.123467 -288.853727)
			(xy 362.095845 -288.811445) (xy 362.075557 -288.765193) (xy 362.06316 -288.716233) (xy 362.058989 -288.6659)
			(xy 357.976951 -288.6659) (xy 357.97278 -288.71624) (xy 357.96038 -288.765206) (xy 357.94009 -288.811465)
			(xy 357.912464 -288.853752) (xy 357.878253 -288.890916) (xy 357.838393 -288.921943) (xy 357.79397 -288.945985)
			(xy 357.746195 -288.962389) (xy 357.696372 -288.970705) (xy 357.671116 -288.971228) (xy 356.731062 -288.971228)
			(xy 356.70581 -288.970664) (xy 356.655997 -288.962345) (xy 356.608231 -288.945942) (xy 356.563817 -288.921902)
			(xy 356.523965 -288.890879) (xy 356.489762 -288.85372) (xy 356.462142 -288.811439) (xy 356.441856 -288.765189)
			(xy 356.429459 -288.716231) (xy 356.425289 -288.6659) (xy 115.670864 -288.6659) (xy 115.670889 -288.6662)
			(xy 115.666713 -288.716584) (xy 115.654302 -288.765593) (xy 115.633992 -288.811891) (xy 115.606339 -288.854214)
			(xy 115.572096 -288.891408) (xy 115.532198 -288.922458) (xy 115.487733 -288.946517) (xy 115.439914 -288.962929)
			(xy 115.390046 -288.971246) (xy 115.364768 -288.971736) (xy 114.424714 -288.971736) (xy 114.399432 -288.971296)
			(xy 114.349558 -288.962976) (xy 114.301734 -288.946559) (xy 114.257264 -288.922495) (xy 114.217362 -288.89144)
			(xy 114.183116 -288.85424) (xy 114.15546 -288.811911) (xy 114.135148 -288.765606) (xy 114.122735 -288.716591)
			(xy 114.118559 -288.6662) (xy 110.03706 -288.6662) (xy 110.032886 -288.716571) (xy 110.02048 -288.765568)
			(xy 110.000179 -288.811855) (xy 109.972536 -288.85417) (xy 109.938307 -288.891358) (xy 109.898424 -288.922406)
			(xy 109.853975 -288.946467) (xy 109.806172 -288.962884) (xy 109.75632 -288.97121) (xy 109.731048 -288.971736)
			(xy 108.790994 -288.971736) (xy 108.765716 -288.971266) (xy 108.715849 -288.962943) (xy 108.668032 -288.946527)
			(xy 108.62357 -288.922464) (xy 108.583674 -288.891411) (xy 108.549433 -288.854216) (xy 108.521782 -288.811891)
			(xy 108.501474 -288.765593) (xy 108.489063 -288.716584) (xy 108.484888 -288.6662) (xy 2.509012 -288.6662)
			(xy 2.509012 -289.382454) (xy 20.958048 -289.382454) (xy 20.958048 -288.887916) (xy 20.958601 -288.882666)
			(xy 20.966008 -288.875225) (xy 20.971256 -288.874708) (xy 20.971764 -288.874708) (xy 21.487638 -288.874708)
			(xy 21.495446 -288.874367) (xy 21.510317 -288.8696) (xy 21.516848 -288.86531) (xy 21.537937 -288.850961)
			(xy 21.583598 -288.82823) (xy 21.632204 -288.812771) (xy 21.682607 -288.804948) (xy 21.733613 -288.804948)
			(xy 21.784016 -288.812771) (xy 21.832622 -288.82823) (xy 21.878283 -288.850961) (xy 21.899372 -288.86531)
			(xy 21.90591 -288.86959) (xy 21.920775 -288.87438) (xy 21.928582 -288.874708) (xy 22.44471 -288.874708)
			(xy 22.450008 -288.875213) (xy 22.457577 -288.882629) (xy 22.458172 -288.887916) (xy 22.458172 -289.382454)
			(xy 22.458154 -289.382708) (xy 28.502356 -289.382708) (xy 28.502356 -289.3822) (xy 28.502356 -288.887916)
			(xy 28.502902 -288.882664) (xy 28.510314 -288.875222) (xy 28.515564 -288.874708) (xy 29.031692 -288.874708)
			(xy 29.039502 -288.87439) (xy 29.054373 -288.869607) (xy 29.060902 -288.86531) (xy 29.081991 -288.850961)
			(xy 29.127652 -288.82823) (xy 29.176258 -288.812771) (xy 29.226661 -288.804948) (xy 29.277667 -288.804948)
			(xy 29.32807 -288.812771) (xy 29.376676 -288.82823) (xy 29.422337 -288.850961) (xy 29.443426 -288.86531)
			(xy 29.449952 -288.869611) (xy 29.464826 -288.874388) (xy 29.472636 -288.874708) (xy 29.988764 -288.874708)
			(xy 29.994095 -288.875053) (xy 30.001639 -288.882585) (xy 30.001972 -288.887916) (xy 30.001972 -289.382454)
			(xy 30.001947 -289.382708) (xy 36.046156 -289.382708) (xy 36.046156 -289.3822) (xy 36.046156 -288.887916)
			(xy 36.046702 -288.882664) (xy 36.054114 -288.875222) (xy 36.059364 -288.874708) (xy 36.575492 -288.874708)
			(xy 36.583302 -288.87439) (xy 36.598173 -288.869607) (xy 36.604702 -288.86531) (xy 36.625791 -288.850961)
			(xy 36.671452 -288.82823) (xy 36.720058 -288.812771) (xy 36.770461 -288.804948) (xy 36.821467 -288.804948)
			(xy 36.87187 -288.812771) (xy 36.920476 -288.82823) (xy 36.966137 -288.850961) (xy 36.987226 -288.86531)
			(xy 36.993752 -288.869611) (xy 37.008626 -288.874388) (xy 37.016436 -288.874708) (xy 37.532564 -288.874708)
			(xy 37.537895 -288.875053) (xy 37.545439 -288.882585) (xy 37.545772 -288.887916) (xy 37.545772 -289.382454)
			(xy 43.589956 -289.382454) (xy 43.589956 -288.887916) (xy 43.590502 -288.882664) (xy 43.597914 -288.875222)
			(xy 43.603164 -288.874708) (xy 43.603672 -288.874708) (xy 44.119546 -288.874708) (xy 44.127354 -288.87437)
			(xy 44.142225 -288.869601) (xy 44.148756 -288.86531) (xy 44.169845 -288.850961) (xy 44.215506 -288.82823)
			(xy 44.264112 -288.812771) (xy 44.314515 -288.804948) (xy 44.365521 -288.804948) (xy 44.415924 -288.812771)
			(xy 44.46453 -288.82823) (xy 44.510191 -288.850961) (xy 44.53128 -288.86531) (xy 44.537816 -288.869593)
			(xy 44.552683 -288.874381) (xy 44.56049 -288.874708) (xy 45.076618 -288.874708) (xy 45.081917 -288.875207)
			(xy 45.089485 -288.882628) (xy 45.09008 -288.887916) (xy 45.09008 -289.382454) (xy 45.090062 -289.382708)
			(xy 51.134264 -289.382708) (xy 51.134264 -289.3822) (xy 51.134264 -288.887916) (xy 51.134802 -288.882662)
			(xy 51.14222 -288.87522) (xy 51.147472 -288.874708) (xy 51.6636 -288.874708) (xy 51.67141 -288.874393)
			(xy 51.686281 -288.869608) (xy 51.69281 -288.86531) (xy 51.713899 -288.850961) (xy 51.75956 -288.82823)
			(xy 51.808166 -288.812771) (xy 51.858569 -288.804948) (xy 51.909575 -288.804948) (xy 51.959978 -288.812771)
			(xy 52.008584 -288.82823) (xy 52.054245 -288.850961) (xy 52.075334 -288.86531) (xy 52.081858 -288.869614)
			(xy 52.096734 -288.874389) (xy 52.104544 -288.874708) (xy 52.620672 -288.874708) (xy 52.626004 -288.875047)
			(xy 52.633548 -288.882584) (xy 52.63388 -288.887916) (xy 52.63388 -289.382454) (xy 58.678064 -289.382454)
			(xy 58.678064 -288.887916) (xy 58.678602 -288.882662) (xy 58.68602 -288.87522) (xy 58.691272 -288.874708)
			(xy 58.69178 -288.874708) (xy 60.164726 -288.874708) (xy 60.170026 -288.875202) (xy 60.177593 -288.882627)
			(xy 60.178188 -288.887916) (xy 60.178188 -289.382454) (xy 60.177793 -289.387877) (xy 60.170146 -289.395564)
			(xy 60.164726 -289.395916) (xy 58.691526 -289.395916) (xy 58.686083 -289.395599) (xy 58.678393 -289.387897)
			(xy 58.678064 -289.382454) (xy 52.63388 -289.382454) (xy 52.633349 -289.387748) (xy 52.625953 -289.395321)
			(xy 52.620672 -289.395916) (xy 52.104798 -289.395916) (xy 52.096988 -289.396226) (xy 52.082116 -289.401014)
			(xy 52.075588 -289.405314) (xy 52.054464 -289.41966) (xy 52.008742 -289.442389) (xy 51.960069 -289.45782)
			(xy 51.909603 -289.465587) (xy 51.884072 -289.46602) (xy 51.858541 -289.465606) (xy 51.808076 -289.457824)
			(xy 51.759403 -289.442389) (xy 51.713677 -289.419665) (xy 51.692556 -289.405314) (xy 51.686033 -289.401008)
			(xy 51.671156 -289.396234) (xy 51.663346 -289.395916) (xy 51.147472 -289.395916) (xy 51.142208 -289.395425)
			(xy 51.134767 -289.387973) (xy 51.134264 -289.382708) (xy 45.090062 -289.382708) (xy 45.089692 -289.387878)
			(xy 45.082041 -289.395566) (xy 45.076618 -289.395916) (xy 44.560744 -289.395916) (xy 44.552935 -289.396245)
			(xy 44.538064 -289.40102) (xy 44.531534 -289.405314) (xy 44.510425 -289.419684) (xy 44.464697 -289.442407)
			(xy 44.41602 -289.457831) (xy 44.36555 -289.465591) (xy 44.340018 -289.46602) (xy 44.314488 -289.465582)
			(xy 44.264024 -289.457808) (xy 44.215351 -289.44238) (xy 44.169624 -289.419662) (xy 44.148502 -289.405314)
			(xy 44.141969 -289.401026) (xy 44.1271 -289.396241) (xy 44.119292 -289.395916) (xy 43.603418 -289.395916)
			(xy 43.597974 -289.395604) (xy 43.590284 -289.387898) (xy 43.589956 -289.382454) (xy 37.545772 -289.382454)
			(xy 37.545248 -289.38775) (xy 37.537848 -289.395323) (xy 37.532564 -289.395916) (xy 37.01669 -289.395916)
			(xy 37.008879 -289.396223) (xy 36.994008 -289.401013) (xy 36.98748 -289.405314) (xy 36.966359 -289.419664)
			(xy 36.920635 -289.442391) (xy 36.871962 -289.457822) (xy 36.821495 -289.465588) (xy 36.795964 -289.46602)
			(xy 36.770433 -289.46561) (xy 36.719967 -289.457827) (xy 36.671295 -289.44239) (xy 36.625569 -289.419666)
			(xy 36.604448 -289.405314) (xy 36.597927 -289.401005) (xy 36.583049 -289.396233) (xy 36.575238 -289.395916)
			(xy 36.059364 -289.395916) (xy 36.054099 -289.39543) (xy 36.046659 -289.387974) (xy 36.046156 -289.382708)
			(xy 30.001947 -289.382708) (xy 30.001448 -289.38775) (xy 29.994048 -289.395323) (xy 29.988764 -289.395916)
			(xy 29.47289 -289.395916) (xy 29.465079 -289.396223) (xy 29.450208 -289.401013) (xy 29.44368 -289.405314)
			(xy 29.422559 -289.419664) (xy 29.376835 -289.442391) (xy 29.328162 -289.457822) (xy 29.277695 -289.465588)
			(xy 29.252164 -289.46602) (xy 29.226633 -289.46561) (xy 29.176167 -289.457827) (xy 29.127495 -289.44239)
			(xy 29.081769 -289.419666) (xy 29.060648 -289.405314) (xy 29.054127 -289.401005) (xy 29.039249 -289.396233)
			(xy 29.031438 -289.395916) (xy 28.515564 -289.395916) (xy 28.510299 -289.39543) (xy 28.502859 -289.387974)
			(xy 28.502356 -289.382708) (xy 22.458154 -289.382708) (xy 22.457791 -289.38788) (xy 22.450135 -289.395568)
			(xy 22.44471 -289.395916) (xy 21.928836 -289.395916) (xy 21.921027 -289.396242) (xy 21.906155 -289.401019)
			(xy 21.899626 -289.405314) (xy 21.878492 -289.419644) (xy 21.832773 -289.442376) (xy 21.784103 -289.457812)
			(xy 21.73364 -289.465584) (xy 21.70811 -289.46602) (xy 21.68258 -289.465586) (xy 21.632115 -289.457811)
			(xy 21.583443 -289.442381) (xy 21.537715 -289.419663) (xy 21.516594 -289.405314) (xy 21.510062 -289.401023)
			(xy 21.495192 -289.396239) (xy 21.487384 -289.395916) (xy 20.97151 -289.395916) (xy 20.966065 -289.39561)
			(xy 20.958376 -289.3879) (xy 20.958048 -289.382454) (xy 2.509012 -289.382454) (xy 2.509012 -289.4762)
			(xy 97.67512 -289.4762) (xy 97.679292 -289.425853) (xy 97.691694 -289.376879) (xy 97.711988 -289.330615)
			(xy 97.73962 -289.288322) (xy 97.773836 -289.251154) (xy 97.813704 -289.220125) (xy 97.858135 -289.196081)
			(xy 97.905917 -289.179678) (xy 97.955748 -289.171364) (xy 97.981008 -289.170872) (xy 98.921062 -289.170872)
			(xy 98.94632 -289.171402) (xy 98.996148 -289.179711) (xy 99.043929 -289.196109) (xy 99.088359 -289.220148)
			(xy 99.128225 -289.251173) (xy 99.162441 -289.288337) (xy 99.190073 -289.330626) (xy 99.210366 -289.376886)
			(xy 99.222768 -289.425856) (xy 99.22694 -289.4762) (xy 100.495349 -289.4762) (xy 100.49952 -289.425862)
			(xy 100.511919 -289.376896) (xy 100.532208 -289.330639) (xy 100.559833 -289.288352) (xy 100.594041 -289.251189)
			(xy 100.633899 -289.220162) (xy 100.678321 -289.196119) (xy 100.726093 -289.179714) (xy 100.775915 -289.171396)
			(xy 100.80117 -289.170872) (xy 101.741224 -289.170872) (xy 101.766476 -289.171435) (xy 101.816292 -289.179752)
			(xy 101.864059 -289.196154) (xy 101.908475 -289.220194) (xy 101.948329 -289.251216) (xy 101.982534 -289.288375)
			(xy 102.010156 -289.330657) (xy 102.030443 -289.376908) (xy 102.042841 -289.425868) (xy 102.047011 -289.4762)
			(xy 103.315249 -289.4762) (xy 103.31942 -289.425861) (xy 103.331819 -289.376895) (xy 103.352109 -289.330637)
			(xy 103.379735 -289.28835) (xy 103.413944 -289.251186) (xy 103.453804 -289.220159) (xy 103.498226 -289.196116)
			(xy 103.546 -289.179713) (xy 103.595822 -289.171395) (xy 103.621078 -289.170872) (xy 104.561132 -289.170872)
			(xy 104.586384 -289.171436) (xy 104.636198 -289.179753) (xy 104.683965 -289.196156) (xy 104.72838 -289.220196)
			(xy 104.768233 -289.251219) (xy 104.802436 -289.288378) (xy 104.830058 -289.330659) (xy 104.850344 -289.37691)
			(xy 104.862741 -289.425868) (xy 104.866911 -289.4762) (xy 106.135149 -289.4762) (xy 106.13932 -289.42586)
			(xy 106.15172 -289.376893) (xy 106.17201 -289.330635) (xy 106.199637 -289.288347) (xy 106.233847 -289.251183)
			(xy 106.273708 -289.220157) (xy 106.318132 -289.196114) (xy 106.365907 -289.179711) (xy 106.41573 -289.171395)
			(xy 106.440986 -289.170872) (xy 107.38104 -289.170872) (xy 107.406291 -289.171437) (xy 107.456105 -289.179755)
			(xy 107.50387 -289.196158) (xy 107.548284 -289.220199) (xy 107.588136 -289.251222) (xy 107.622338 -289.28838)
			(xy 107.649959 -289.330661) (xy 107.670244 -289.376911) (xy 107.682641 -289.425869) (xy 107.686811 -289.4762)
			(xy 116.46882 -289.4762) (xy 116.472992 -289.425852) (xy 116.485395 -289.376877) (xy 116.50569 -289.330611)
			(xy 116.533323 -289.288317) (xy 116.567542 -289.251149) (xy 116.607411 -289.22012) (xy 116.651844 -289.196077)
			(xy 116.699629 -289.179675) (xy 116.749461 -289.171363) (xy 116.774722 -289.170872) (xy 117.714776 -289.170872)
			(xy 117.740033 -289.171403) (xy 117.78986 -289.179714) (xy 117.837638 -289.196113) (xy 117.882066 -289.220153)
			(xy 117.92193 -289.251178) (xy 117.956145 -289.288341) (xy 117.983775 -289.33063) (xy 118.004067 -289.376889)
			(xy 118.016468 -289.425858) (xy 118.02064 -289.4762) (xy 119.28872 -289.4762) (xy 119.292892 -289.425851)
			(xy 119.305295 -289.376875) (xy 119.325591 -289.330609) (xy 119.353225 -289.288315) (xy 119.387445 -289.251146)
			(xy 119.427315 -289.220117) (xy 119.47175 -289.196074) (xy 119.519535 -289.179674) (xy 119.569369 -289.171362)
			(xy 119.59463 -289.170872) (xy 120.534684 -289.170872) (xy 120.559941 -289.171403) (xy 120.609766 -289.179715)
			(xy 120.657544 -289.196115) (xy 120.70197 -289.220155) (xy 120.741834 -289.25118) (xy 120.776047 -289.288344)
			(xy 120.803676 -289.330632) (xy 120.823968 -289.376891) (xy 120.836368 -289.425859) (xy 120.84054 -289.4762)
			(xy 122.108949 -289.4762) (xy 122.11312 -289.425859) (xy 122.12552 -289.376892) (xy 122.145811 -289.330633)
			(xy 122.173439 -289.288345) (xy 122.20765 -289.251181) (xy 122.247511 -289.220155) (xy 122.291936 -289.196112)
			(xy 122.339711 -289.17971) (xy 122.389535 -289.171394) (xy 122.414792 -289.170872) (xy 123.354846 -289.170872)
			(xy 123.380097 -289.171437) (xy 123.42991 -289.179756) (xy 123.477674 -289.19616) (xy 123.522087 -289.220201)
			(xy 123.561938 -289.251224) (xy 123.59614 -289.288382) (xy 123.62376 -289.330663) (xy 123.644044 -289.376913)
			(xy 123.656441 -289.42587) (xy 123.660611 -289.4762) (xy 124.928849 -289.4762) (xy 124.93302 -289.425859)
			(xy 124.945421 -289.37689) (xy 124.965712 -289.330631) (xy 124.993341 -289.288342) (xy 125.027553 -289.251178)
			(xy 125.067415 -289.220152) (xy 125.111841 -289.19611) (xy 125.159618 -289.179708) (xy 125.209443 -289.171394)
			(xy 125.2347 -289.170872) (xy 126.174754 -289.170872) (xy 126.200013 -289.171401) (xy 126.249842 -289.179709)
			(xy 126.297623 -289.196106) (xy 126.342054 -289.220145) (xy 126.381922 -289.25117) (xy 126.416139 -289.288334)
			(xy 126.443771 -289.330623) (xy 126.464066 -289.376885) (xy 126.465541 -289.382708) (xy 167.778176 -289.382708)
			(xy 167.778176 -288.887916) (xy 167.778704 -288.882659) (xy 167.786128 -288.875216) (xy 167.791384 -288.874708)
			(xy 169.264584 -288.874708) (xy 169.269918 -288.875039) (xy 169.277461 -288.882582) (xy 169.277792 -288.887916)
			(xy 169.277792 -289.382454) (xy 175.321976 -289.382454) (xy 175.321976 -288.887916) (xy 175.322504 -288.882659)
			(xy 175.329928 -288.875216) (xy 175.335184 -288.874708) (xy 175.335692 -288.874708) (xy 175.851566 -288.874708)
			(xy 175.859375 -288.874379) (xy 175.874246 -288.869603) (xy 175.880776 -288.86531) (xy 175.901865 -288.850961)
			(xy 175.947526 -288.82823) (xy 175.996132 -288.812771) (xy 176.046535 -288.804948) (xy 176.097541 -288.804948)
			(xy 176.147944 -288.812771) (xy 176.19655 -288.82823) (xy 176.242211 -288.850961) (xy 176.2633 -288.86531)
			(xy 176.269832 -288.869601) (xy 176.284702 -288.874384) (xy 176.29251 -288.874708) (xy 176.808638 -288.874708)
			(xy 176.813939 -288.875194) (xy 176.821506 -288.882625) (xy 176.8221 -288.887916) (xy 176.8221 -289.382454)
			(xy 176.822081 -289.382708) (xy 182.866284 -289.382708) (xy 182.866284 -289.3822) (xy 182.866284 -288.887916)
			(xy 182.866637 -288.882588) (xy 182.874164 -288.875046) (xy 182.879492 -288.874708) (xy 183.39562 -288.874708)
			(xy 183.403431 -288.874401) (xy 183.418302 -288.86961) (xy 183.42483 -288.86531) (xy 183.445919 -288.850961)
			(xy 183.49158 -288.82823) (xy 183.540186 -288.812771) (xy 183.590589 -288.804948) (xy 183.641595 -288.804948)
			(xy 183.691998 -288.812771) (xy 183.740604 -288.82823) (xy 183.786265 -288.850961) (xy 183.807354 -288.86531)
			(xy 183.813874 -288.869622) (xy 183.828753 -288.874392) (xy 183.836564 -288.874708) (xy 184.352692 -288.874708)
			(xy 184.358027 -288.875034) (xy 184.36557 -288.882581) (xy 184.3659 -288.887916) (xy 184.3659 -289.382454)
			(xy 190.410084 -289.382454) (xy 190.410084 -288.887916) (xy 190.410437 -288.882588) (xy 190.417964 -288.875046)
			(xy 190.423292 -288.874708) (xy 190.4238 -288.874708) (xy 190.939674 -288.874708) (xy 190.947483 -288.874382)
			(xy 190.962354 -288.869604) (xy 190.968884 -288.86531) (xy 190.989973 -288.850961) (xy 191.035634 -288.82823)
			(xy 191.08424 -288.812771) (xy 191.134643 -288.804948) (xy 191.185649 -288.804948) (xy 191.236052 -288.812771)
			(xy 191.284658 -288.82823) (xy 191.330319 -288.850961) (xy 191.351408 -288.86531) (xy 191.357938 -288.869604)
			(xy 191.372809 -288.874385) (xy 191.380618 -288.874708) (xy 191.896746 -288.874708) (xy 191.902036 -288.875256)
			(xy 191.909609 -288.882639) (xy 191.910208 -288.887916) (xy 191.910208 -289.382454) (xy 191.91018 -289.382708)
			(xy 197.954392 -289.382708) (xy 197.954392 -289.3822) (xy 197.954392 -288.887916) (xy 197.954738 -288.882586)
			(xy 197.96227 -288.875044) (xy 197.9676 -288.874708) (xy 198.483728 -288.874708) (xy 198.491539 -288.874405)
			(xy 198.50641 -288.869611) (xy 198.512938 -288.86531) (xy 198.534027 -288.850961) (xy 198.579688 -288.82823)
			(xy 198.628294 -288.812771) (xy 198.678697 -288.804948) (xy 198.729703 -288.804948) (xy 198.780106 -288.812771)
			(xy 198.828712 -288.82823) (xy 198.874373 -288.850961) (xy 198.895462 -288.86531) (xy 198.902002 -288.869586)
			(xy 198.916866 -288.874378) (xy 198.924672 -288.874708) (xy 199.4408 -288.874708) (xy 199.446136 -288.875028)
			(xy 199.453678 -288.882579) (xy 199.454008 -288.887916) (xy 199.454008 -289.382454) (xy 199.453981 -289.382708)
			(xy 205.498192 -289.382708) (xy 205.498192 -289.3822) (xy 205.498192 -288.887916) (xy 205.498538 -288.882586)
			(xy 205.50607 -288.875044) (xy 205.5114 -288.874708) (xy 206.027528 -288.874708) (xy 206.035339 -288.874405)
			(xy 206.05021 -288.869611) (xy 206.056738 -288.86531) (xy 206.077827 -288.850961) (xy 206.123488 -288.82823)
			(xy 206.172094 -288.812771) (xy 206.222497 -288.804948) (xy 206.273503 -288.804948) (xy 206.323906 -288.812771)
			(xy 206.372512 -288.82823) (xy 206.418173 -288.850961) (xy 206.439262 -288.86531) (xy 206.445802 -288.869586)
			(xy 206.460666 -288.874378) (xy 206.468472 -288.874708) (xy 206.9846 -288.874708) (xy 206.989936 -288.875028)
			(xy 206.997478 -288.882579) (xy 206.997808 -288.887916) (xy 206.997808 -289.3822) (xy 268.898116 -289.3822)
			(xy 268.898116 -288.887662) (xy 268.898623 -288.882299) (xy 268.906214 -288.874717) (xy 268.911578 -288.8742)
			(xy 269.427706 -288.8742) (xy 269.435516 -288.873889) (xy 269.450388 -288.869101) (xy 269.456916 -288.864802)
			(xy 269.478005 -288.850453) (xy 269.523666 -288.827722) (xy 269.572272 -288.812263) (xy 269.622675 -288.80444)
			(xy 269.673681 -288.80444) (xy 269.724084 -288.812263) (xy 269.77269 -288.827722) (xy 269.818351 -288.850453)
			(xy 269.83944 -288.864802) (xy 269.845963 -288.869108) (xy 269.86084 -288.873882) (xy 269.86865 -288.8742)
			(xy 270.384778 -288.8742) (xy 270.39013 -288.874761) (xy 270.397715 -288.882312) (xy 270.39824 -288.887662)
			(xy 270.39824 -289.3822) (xy 276.442424 -289.3822) (xy 276.442424 -288.887662) (xy 276.442896 -288.882357)
			(xy 276.450336 -288.874789) (xy 276.455632 -288.8742) (xy 276.97176 -288.8742) (xy 276.979569 -288.873869)
			(xy 276.99444 -288.869095) (xy 277.00097 -288.864802) (xy 277.022059 -288.850453) (xy 277.06772 -288.827722)
			(xy 277.116326 -288.812263) (xy 277.166729 -288.80444) (xy 277.217735 -288.80444) (xy 277.268138 -288.812263)
			(xy 277.316744 -288.827722) (xy 277.362405 -288.850453) (xy 277.383494 -288.864802) (xy 277.390027 -288.86909)
			(xy 277.404896 -288.873875) (xy 277.412704 -288.8742) (xy 277.928832 -288.8742) (xy 277.934101 -288.874674)
			(xy 277.941542 -288.882138) (xy 277.94204 -288.887408) (xy 277.94204 -288.887916) (xy 277.94204 -289.3822)
			(xy 283.986224 -289.3822) (xy 283.986224 -288.887662) (xy 283.986696 -288.882357) (xy 283.994136 -288.874789)
			(xy 283.999432 -288.8742) (xy 284.51556 -288.8742) (xy 284.523369 -288.873869) (xy 284.53824 -288.869095)
			(xy 284.54477 -288.864802) (xy 284.565859 -288.850453) (xy 284.61152 -288.827722) (xy 284.660126 -288.812263)
			(xy 284.710529 -288.80444) (xy 284.761535 -288.80444) (xy 284.811938 -288.812263) (xy 284.860544 -288.827722)
			(xy 284.906205 -288.850453) (xy 284.927294 -288.864802) (xy 284.933827 -288.86909) (xy 284.948696 -288.873875)
			(xy 284.956504 -288.8742) (xy 285.472632 -288.8742) (xy 285.477901 -288.874674) (xy 285.485342 -288.882138)
			(xy 285.48584 -288.887408) (xy 285.48584 -288.887916) (xy 285.48584 -289.3822) (xy 291.530024 -289.3822)
			(xy 291.530024 -288.887662) (xy 291.530524 -288.882297) (xy 291.53812 -288.874714) (xy 291.543486 -288.8742)
			(xy 292.059614 -288.8742) (xy 292.067425 -288.873892) (xy 292.082296 -288.869102) (xy 292.088824 -288.864802)
			(xy 292.109913 -288.850453) (xy 292.155574 -288.827722) (xy 292.20418 -288.812263) (xy 292.254583 -288.80444)
			(xy 292.305589 -288.80444) (xy 292.355992 -288.812263) (xy 292.404598 -288.827722) (xy 292.450259 -288.850453)
			(xy 292.471348 -288.864802) (xy 292.477869 -288.869111) (xy 292.492747 -288.873883) (xy 292.500558 -288.8742)
			(xy 293.016686 -288.8742) (xy 293.022039 -288.874756) (xy 293.029623 -288.882311) (xy 293.030148 -288.887662)
			(xy 293.030148 -289.3822) (xy 299.074332 -289.3822) (xy 299.074332 -288.887662) (xy 299.074797 -288.882355)
			(xy 299.082242 -288.874787) (xy 299.08754 -288.8742) (xy 299.603668 -288.8742) (xy 299.611477 -288.873873)
			(xy 299.626348 -288.869096) (xy 299.632878 -288.864802) (xy 299.653967 -288.850453) (xy 299.699628 -288.827722)
			(xy 299.748234 -288.812263) (xy 299.798637 -288.80444) (xy 299.849643 -288.80444) (xy 299.900046 -288.812263)
			(xy 299.948652 -288.827722) (xy 299.994313 -288.850453) (xy 300.015402 -288.864802) (xy 300.021934 -288.869093)
			(xy 300.036804 -288.873876) (xy 300.044612 -288.8742) (xy 300.56074 -288.8742) (xy 300.56601 -288.874669)
			(xy 300.57345 -288.882137) (xy 300.573948 -288.887408) (xy 300.573948 -288.887916) (xy 300.573948 -289.3822)
			(xy 306.618132 -289.3822) (xy 306.618132 -288.887662) (xy 306.618625 -288.882295) (xy 306.626226 -288.874712)
			(xy 306.631594 -288.8742) (xy 308.104794 -288.8742) (xy 308.110148 -288.87475) (xy 308.117732 -288.88231)
			(xy 308.118256 -288.887662) (xy 308.118256 -289.3822) (xy 308.11771 -289.387451) (xy 308.110297 -289.394891)
			(xy 308.105048 -289.395408) (xy 308.10454 -289.395408) (xy 306.631594 -289.395408) (xy 306.6263 -289.394887)
			(xy 306.618732 -289.387482) (xy 306.618132 -289.3822) (xy 300.573948 -289.3822) (xy 300.573409 -289.387453)
			(xy 300.565992 -289.394893) (xy 300.56074 -289.395408) (xy 300.044866 -289.395408) (xy 300.036992 -289.395696)
			(xy 300.021988 -289.40048) (xy 300.015402 -289.404806) (xy 299.994311 -289.419177) (xy 299.948671 -289.442011)
			(xy 299.90007 -289.457575) (xy 299.849656 -289.4655) (xy 299.82414 -289.46602) (xy 299.79862 -289.465524)
			(xy 299.748194 -289.457631) (xy 299.699582 -289.442072) (xy 299.653943 -289.41922) (xy 299.632878 -289.404806)
			(xy 299.626293 -289.40048) (xy 299.611288 -289.3957) (xy 299.603414 -289.395408) (xy 299.08754 -289.395408)
			(xy 299.082213 -289.395046) (xy 299.07467 -289.387526) (xy 299.074332 -289.3822) (xy 293.030148 -289.3822)
			(xy 293.029609 -289.387453) (xy 293.022192 -289.394893) (xy 293.01694 -289.395408) (xy 293.016432 -289.395408)
			(xy 292.500812 -289.395408) (xy 292.492939 -289.395715) (xy 292.477935 -289.400486) (xy 292.471348 -289.404806)
			(xy 292.450272 -289.4192) (xy 292.404627 -289.442029) (xy 292.356021 -289.457586) (xy 292.305603 -289.465504)
			(xy 292.280086 -289.46602) (xy 292.254567 -289.465501) (xy 292.204141 -289.457614) (xy 292.15553 -289.442063)
			(xy 292.10989 -289.419217) (xy 292.088824 -289.404806) (xy 292.082229 -289.400498) (xy 292.067232 -289.395707)
			(xy 292.05936 -289.395408) (xy 291.543486 -289.395408) (xy 291.538191 -289.394892) (xy 291.530624 -289.387483)
			(xy 291.530024 -289.3822) (xy 285.48584 -289.3822) (xy 285.485308 -289.387455) (xy 285.477886 -289.394896)
			(xy 285.472632 -289.395408) (xy 284.956758 -289.395408) (xy 284.948883 -289.395692) (xy 284.93388 -289.400479)
			(xy 284.927294 -289.404806) (xy 284.906205 -289.41918) (xy 284.860565 -289.442014) (xy 284.811962 -289.457577)
			(xy 284.761548 -289.4655) (xy 284.736032 -289.46602) (xy 284.710512 -289.465528) (xy 284.660085 -289.457633)
			(xy 284.611474 -289.442074) (xy 284.565835 -289.41922) (xy 284.54477 -289.404806) (xy 284.538187 -289.400477)
			(xy 284.52318 -289.395699) (xy 284.515306 -289.395408) (xy 283.999432 -289.395408) (xy 283.994104 -289.395052)
			(xy 283.986561 -289.387527) (xy 283.986224 -289.3822) (xy 277.94204 -289.3822) (xy 277.941508 -289.387455)
			(xy 277.934086 -289.394896) (xy 277.928832 -289.395408) (xy 277.412958 -289.395408) (xy 277.405083 -289.395692)
			(xy 277.39008 -289.400479) (xy 277.383494 -289.404806) (xy 277.362405 -289.41918) (xy 277.316765 -289.442014)
			(xy 277.268162 -289.457577) (xy 277.217748 -289.4655) (xy 277.192232 -289.46602) (xy 277.166712 -289.465528)
			(xy 277.116285 -289.457633) (xy 277.067674 -289.442074) (xy 277.022035 -289.41922) (xy 277.00097 -289.404806)
			(xy 276.994387 -289.400477) (xy 276.97938 -289.395699) (xy 276.971506 -289.395408) (xy 276.455632 -289.395408)
			(xy 276.450304 -289.395052) (xy 276.442761 -289.387527) (xy 276.442424 -289.3822) (xy 270.39824 -289.3822)
			(xy 270.397708 -289.387455) (xy 270.390286 -289.394896) (xy 270.385032 -289.395408) (xy 270.384524 -289.395408)
			(xy 269.868904 -289.395408) (xy 269.861031 -289.395712) (xy 269.846027 -289.400485) (xy 269.83944 -289.404806)
			(xy 269.818366 -289.419203) (xy 269.772721 -289.442032) (xy 269.724113 -289.457588) (xy 269.673695 -289.465505)
			(xy 269.648178 -289.46602) (xy 269.622659 -289.465505) (xy 269.572233 -289.457617) (xy 269.523622 -289.442065)
			(xy 269.477982 -289.419217) (xy 269.456916 -289.404806) (xy 269.450322 -289.400495) (xy 269.435324 -289.395706)
			(xy 269.427452 -289.395408) (xy 268.911578 -289.395408) (xy 268.906282 -289.394897) (xy 268.898715 -289.387484)
			(xy 268.898116 -289.3822) (xy 206.997808 -289.3822) (xy 206.997808 -289.382454) (xy 206.997252 -289.387742)
			(xy 206.989874 -289.395313) (xy 206.9846 -289.395916) (xy 206.468726 -289.395916) (xy 206.460917 -289.396238)
			(xy 206.446045 -289.401018) (xy 206.439516 -289.405314) (xy 206.418384 -289.419648) (xy 206.372665 -289.442379)
			(xy 206.323994 -289.457814) (xy 206.27353 -289.465585) (xy 206.248 -289.46602) (xy 206.222469 -289.465591)
			(xy 206.172005 -289.457814) (xy 206.123332 -289.442383) (xy 206.077605 -289.419663) (xy 206.056484 -289.405314)
			(xy 206.049955 -289.401019) (xy 206.035083 -289.396238) (xy 206.027274 -289.395916) (xy 205.5114 -289.395916)
			(xy 205.506139 -289.395406) (xy 205.498697 -289.387968) (xy 205.498192 -289.382708) (xy 199.453981 -289.382708)
			(xy 199.453452 -289.387742) (xy 199.446074 -289.395313) (xy 199.4408 -289.395916) (xy 198.924926 -289.395916)
			(xy 198.917117 -289.396238) (xy 198.902245 -289.401018) (xy 198.895716 -289.405314) (xy 198.874584 -289.419648)
			(xy 198.828865 -289.442379) (xy 198.780194 -289.457814) (xy 198.72973 -289.465585) (xy 198.7042 -289.46602)
			(xy 198.678669 -289.465591) (xy 198.628205 -289.457814) (xy 198.579532 -289.442383) (xy 198.533805 -289.419663)
			(xy 198.512684 -289.405314) (xy 198.506155 -289.401019) (xy 198.491283 -289.396238) (xy 198.483474 -289.395916)
			(xy 197.9676 -289.395916) (xy 197.962339 -289.395406) (xy 197.954897 -289.387968) (xy 197.954392 -289.382708)
			(xy 191.91018 -289.382708) (xy 191.909623 -289.387801) (xy 191.90209 -289.395387) (xy 191.896746 -289.395916)
			(xy 191.380872 -289.395916) (xy 191.373061 -289.396215) (xy 191.358189 -289.401011) (xy 191.351662 -289.405314)
			(xy 191.330546 -289.419671) (xy 191.28482 -289.442397) (xy 191.236145 -289.457825) (xy 191.185677 -289.465589)
			(xy 191.160146 -289.46602) (xy 191.134616 -289.465568) (xy 191.084153 -289.457798) (xy 191.03548 -289.442374)
			(xy 190.989752 -289.41966) (xy 190.96863 -289.405314) (xy 190.96209 -289.401037) (xy 190.947227 -289.396245)
			(xy 190.93942 -289.395916) (xy 190.423546 -289.395916) (xy 190.418106 -289.395585) (xy 190.410415 -289.387894)
			(xy 190.410084 -289.382454) (xy 184.3659 -289.382454) (xy 184.365351 -289.387744) (xy 184.357968 -289.395315)
			(xy 184.352692 -289.395916) (xy 183.836818 -289.395916) (xy 183.829008 -289.396234) (xy 183.814137 -289.401017)
			(xy 183.807608 -289.405314) (xy 183.786479 -289.419652) (xy 183.740758 -289.442382) (xy 183.692087 -289.457816)
			(xy 183.641622 -289.465585) (xy 183.616092 -289.46602) (xy 183.590561 -289.465595) (xy 183.540097 -289.457817)
			(xy 183.491424 -289.442385) (xy 183.445697 -289.419664) (xy 183.424576 -289.405314) (xy 183.418048 -289.401016)
			(xy 183.403175 -289.396237) (xy 183.395366 -289.395916) (xy 182.879492 -289.395916) (xy 182.87423 -289.395411)
			(xy 182.866789 -289.38797) (xy 182.866284 -289.382708) (xy 176.822081 -289.382708) (xy 176.821694 -289.387874)
			(xy 176.814055 -289.39556) (xy 176.808638 -289.395916) (xy 176.292764 -289.395916) (xy 176.284956 -289.396254)
			(xy 176.270085 -289.401023) (xy 176.263554 -289.405314) (xy 176.24244 -289.419675) (xy 176.196714 -289.4424)
			(xy 176.148038 -289.457827) (xy 176.09757 -289.465589) (xy 176.072038 -289.46602) (xy 176.046508 -289.465572)
			(xy 175.996044 -289.457801) (xy 175.947372 -289.442375) (xy 175.901644 -289.419661) (xy 175.880522 -289.405314)
			(xy 175.873984 -289.401034) (xy 175.859119 -289.396244) (xy 175.851312 -289.395916) (xy 175.335438 -289.395916)
			(xy 175.329997 -289.395591) (xy 175.322306 -289.387895) (xy 175.321976 -289.382454) (xy 169.277792 -289.382454)
			(xy 169.27725 -289.387745) (xy 169.269862 -289.395317) (xy 169.264584 -289.395916) (xy 167.791384 -289.395916)
			(xy 167.786121 -289.395417) (xy 167.77868 -289.387971) (xy 167.778176 -289.382708) (xy 126.465541 -289.382708)
			(xy 126.476468 -289.425856) (xy 126.480615 -289.4759) (xy 345.61504 -289.4759) (xy 345.619214 -289.425527)
			(xy 345.631622 -289.376527) (xy 345.651925 -289.330238) (xy 345.67957 -289.287922) (xy 345.713802 -289.250733)
			(xy 345.753689 -289.219686) (xy 345.798141 -289.195626) (xy 345.845947 -289.179211) (xy 345.895803 -289.170888)
			(xy 345.921076 -289.170364) (xy 346.86113 -289.170364) (xy 346.886407 -289.170836) (xy 346.93627 -289.179162)
			(xy 346.984084 -289.19558) (xy 347.028543 -289.219644) (xy 347.068435 -289.250697) (xy 347.102673 -289.287892)
			(xy 347.130322 -289.330215) (xy 347.150628 -289.376512) (xy 347.163037 -289.425519) (xy 347.167212 -289.4759)
			(xy 348.435111 -289.4759) (xy 348.439287 -289.425516) (xy 348.451699 -289.376506) (xy 348.472009 -289.330207)
			(xy 348.499663 -289.287884) (xy 348.533907 -289.25069) (xy 348.573806 -289.21964) (xy 348.618271 -289.195581)
			(xy 348.666091 -289.17917) (xy 348.715959 -289.170854) (xy 348.741238 -289.170364) (xy 349.681292 -289.170364)
			(xy 349.706573 -289.170804) (xy 349.756447 -289.179126) (xy 349.80427 -289.195542) (xy 349.848739 -289.219607)
			(xy 349.88864 -289.250662) (xy 349.922886 -289.287862) (xy 349.950541 -289.330191) (xy 349.970852 -289.376495)
			(xy 349.983265 -289.42551) (xy 349.987441 -289.4759) (xy 351.255011 -289.4759) (xy 351.259187 -289.425515)
			(xy 351.271599 -289.376504) (xy 351.29191 -289.330205) (xy 351.319565 -289.287881) (xy 351.35381 -289.250687)
			(xy 351.39371 -289.219637) (xy 351.438177 -289.195579) (xy 351.485997 -289.179168) (xy 351.535867 -289.170853)
			(xy 351.561146 -289.170364) (xy 352.5012 -289.170364) (xy 352.526478 -289.170834) (xy 352.576346 -289.179155)
			(xy 352.624164 -289.195571) (xy 352.668627 -289.219634) (xy 352.708524 -289.250686) (xy 352.742765 -289.287882)
			(xy 352.770417 -289.330207) (xy 352.790726 -289.376506) (xy 352.803137 -289.425516) (xy 352.807312 -289.4759)
			(xy 354.07504 -289.4759) (xy 354.079214 -289.425529) (xy 354.09162 -289.376532) (xy 354.111922 -289.330245)
			(xy 354.139564 -289.28793) (xy 354.173794 -289.250741) (xy 354.213677 -289.219693) (xy 354.258126 -289.195633)
			(xy 354.305929 -289.179215) (xy 354.355782 -289.170889) (xy 354.381054 -289.170364) (xy 355.321108 -289.170364)
			(xy 355.346386 -289.170835) (xy 355.396252 -289.179157) (xy 355.444069 -289.195574) (xy 355.488531 -289.219636)
			(xy 355.528427 -289.250689) (xy 355.562667 -289.287885) (xy 355.590318 -289.330209) (xy 355.610626 -289.376507)
			(xy 355.623037 -289.425517) (xy 355.627212 -289.4759) (xy 364.40874 -289.4759) (xy 364.412915 -289.425525)
			(xy 364.425323 -289.376525) (xy 364.445627 -289.330235) (xy 364.473273 -289.287918) (xy 364.507508 -289.250728)
			(xy 364.547396 -289.219681) (xy 364.591851 -289.195622) (xy 364.639659 -289.179208) (xy 364.689516 -289.170887)
			(xy 364.71479 -289.170364) (xy 365.654844 -289.170364) (xy 365.68012 -289.170837) (xy 365.729982 -289.179165)
			(xy 365.777793 -289.195584) (xy 365.82225 -289.219649) (xy 365.862141 -289.250702) (xy 365.896376 -289.287897)
			(xy 365.924024 -289.330219) (xy 365.944329 -289.376515) (xy 365.956737 -289.42552) (xy 365.960912 -289.4759)
			(xy 367.22864 -289.4759) (xy 367.232815 -289.425524) (xy 367.245224 -289.376523) (xy 367.265528 -289.330232)
			(xy 367.293176 -289.287915) (xy 367.327411 -289.250725) (xy 367.3673 -289.219678) (xy 367.411756 -289.195619)
			(xy 367.459565 -289.179206) (xy 367.509424 -289.170886) (xy 367.534698 -289.170364) (xy 368.474752 -289.170364)
			(xy 368.500035 -289.170801) (xy 368.549914 -289.179117) (xy 368.597743 -289.19553) (xy 368.642218 -289.219593)
			(xy 368.682125 -289.250648) (xy 368.716375 -289.287849) (xy 368.744035 -289.33018) (xy 368.76435 -289.376487)
			(xy 368.776764 -289.425506) (xy 368.780941 -289.4759) (xy 370.04884 -289.4759) (xy 370.053014 -289.425528)
			(xy 370.065421 -289.376531) (xy 370.085723 -289.330243) (xy 370.113366 -289.287928) (xy 370.147596 -289.250739)
			(xy 370.18748 -289.219691) (xy 370.23193 -289.195631) (xy 370.279734 -289.179214) (xy 370.329588 -289.170889)
			(xy 370.35486 -289.170364) (xy 371.294914 -289.170364) (xy 371.320192 -289.170835) (xy 371.370057 -289.179158)
			(xy 371.417873 -289.195575) (xy 371.462335 -289.219639) (xy 371.502229 -289.250691) (xy 371.536469 -289.287887)
			(xy 371.564119 -289.330211) (xy 371.584426 -289.376509) (xy 371.596837 -289.425517) (xy 371.601012 -289.4759)
			(xy 372.86874 -289.4759) (xy 372.872914 -289.425528) (xy 372.885321 -289.376529) (xy 372.905624 -289.330241)
			(xy 372.933268 -289.287925) (xy 372.967499 -289.250736) (xy 373.007384 -289.219688) (xy 373.051836 -289.195628)
			(xy 373.099641 -289.179212) (xy 373.149496 -289.170888) (xy 373.174768 -289.170364) (xy 374.114822 -289.170364)
			(xy 374.140099 -289.170836) (xy 374.189964 -289.17916) (xy 374.237778 -289.195578) (xy 374.282239 -289.219641)
			(xy 374.322132 -289.250694) (xy 374.356371 -289.28789) (xy 374.38402 -289.330213) (xy 374.404327 -289.37651)
			(xy 374.405768 -289.3822) (xy 415.718244 -289.3822) (xy 415.718244 -288.887662) (xy 415.718699 -288.882352)
			(xy 415.726151 -288.874783) (xy 415.731452 -288.8742) (xy 417.204652 -288.8742) (xy 417.20998 -288.87456)
			(xy 417.217524 -288.882081) (xy 417.21786 -288.887408) (xy 417.21786 -289.3822) (xy 423.262044 -289.3822)
			(xy 423.262044 -288.887662) (xy 423.262526 -288.882292) (xy 423.270135 -288.874708) (xy 423.275506 -288.8742)
			(xy 423.791634 -288.8742) (xy 423.799442 -288.873858) (xy 423.814313 -288.869092) (xy 423.820844 -288.864802)
			(xy 423.841933 -288.850453) (xy 423.887594 -288.827722) (xy 423.9362 -288.812263) (xy 423.986603 -288.80444)
			(xy 424.037609 -288.80444) (xy 424.088012 -288.812263) (xy 424.136618 -288.827722) (xy 424.182279 -288.850453)
			(xy 424.203368 -288.864802) (xy 424.209907 -288.86908) (xy 424.224771 -288.873871) (xy 424.232578 -288.8742)
			(xy 424.748706 -288.8742) (xy 424.754062 -288.874742) (xy 424.761645 -288.882308) (xy 424.762168 -288.887662)
			(xy 424.762168 -289.3822) (xy 430.806352 -289.3822) (xy 430.806352 -288.887662) (xy 430.8068 -288.88235)
			(xy 430.814257 -288.874781) (xy 430.81956 -288.8742) (xy 431.335688 -288.8742) (xy 431.343498 -288.873881)
			(xy 431.358369 -288.869099) (xy 431.364898 -288.864802) (xy 431.385987 -288.850453) (xy 431.431648 -288.827722)
			(xy 431.480254 -288.812263) (xy 431.530657 -288.80444) (xy 431.581663 -288.80444) (xy 431.632066 -288.812263)
			(xy 431.680672 -288.827722) (xy 431.726333 -288.850453) (xy 431.747422 -288.864802) (xy 431.753949 -288.869101)
			(xy 431.768823 -288.873879) (xy 431.776632 -288.8742) (xy 432.29276 -288.8742) (xy 432.298089 -288.874555)
			(xy 432.305632 -288.88208) (xy 432.305968 -288.887408) (xy 432.305968 -288.887916) (xy 432.305968 -289.3822)
			(xy 438.350152 -289.3822) (xy 438.350152 -288.887662) (xy 438.350627 -288.88229) (xy 438.35824 -288.874706)
			(xy 438.363614 -288.8742) (xy 438.879742 -288.8742) (xy 438.88755 -288.873862) (xy 438.902421 -288.869093)
			(xy 438.908952 -288.864802) (xy 438.930041 -288.850453) (xy 438.975702 -288.827722) (xy 439.024308 -288.812263)
			(xy 439.074711 -288.80444) (xy 439.125717 -288.80444) (xy 439.17612 -288.812263) (xy 439.224726 -288.827722)
			(xy 439.270387 -288.850453) (xy 439.291476 -288.864802) (xy 439.298013 -288.869083) (xy 439.312879 -288.873872)
			(xy 439.320686 -288.8742) (xy 439.836814 -288.8742) (xy 439.84217 -288.874737) (xy 439.849753 -288.882307)
			(xy 439.850276 -288.887662) (xy 439.850276 -289.3822) (xy 445.89446 -289.3822) (xy 445.89446 -288.887662)
			(xy 445.8949 -288.882349) (xy 445.902362 -288.874779) (xy 445.907668 -288.8742) (xy 446.423796 -288.8742)
			(xy 446.431606 -288.873885) (xy 446.446477 -288.8691) (xy 446.453006 -288.864802) (xy 446.474095 -288.850453)
			(xy 446.519756 -288.827722) (xy 446.568362 -288.812263) (xy 446.618765 -288.80444) (xy 446.669771 -288.80444)
			(xy 446.720174 -288.812263) (xy 446.76878 -288.827722) (xy 446.814441 -288.850453) (xy 446.83553 -288.864802)
			(xy 446.842055 -288.869104) (xy 446.85693 -288.87388) (xy 446.86474 -288.8742) (xy 447.380868 -288.8742)
			(xy 447.386198 -288.874549) (xy 447.393741 -288.882079) (xy 447.394076 -288.887408) (xy 447.394076 -288.887916)
			(xy 447.394076 -289.3822) (xy 453.43826 -289.3822) (xy 453.43826 -288.887662) (xy 453.4387 -288.882349)
			(xy 453.446162 -288.874779) (xy 453.451468 -288.8742) (xy 453.967596 -288.8742) (xy 453.975406 -288.873885)
			(xy 453.990277 -288.8691) (xy 453.996806 -288.864802) (xy 454.017895 -288.850453) (xy 454.063556 -288.827722)
			(xy 454.112162 -288.812263) (xy 454.162565 -288.80444) (xy 454.213571 -288.80444) (xy 454.263974 -288.812263)
			(xy 454.31258 -288.827722) (xy 454.358241 -288.850453) (xy 454.37933 -288.864802) (xy 454.385855 -288.869104)
			(xy 454.40073 -288.87388) (xy 454.40854 -288.8742) (xy 454.924668 -288.8742) (xy 454.929998 -288.874549)
			(xy 454.937541 -288.882079) (xy 454.937876 -288.887408) (xy 454.937876 -288.887916) (xy 454.937876 -289.3822)
			(xy 454.93757 -289.38754) (xy 454.930009 -289.395083) (xy 454.924668 -289.395408) (xy 454.408794 -289.395408)
			(xy 454.400921 -289.395708) (xy 454.385917 -289.400484) (xy 454.37933 -289.404806) (xy 454.358259 -289.419208)
			(xy 454.312612 -289.442035) (xy 454.264004 -289.45759) (xy 454.213585 -289.465505) (xy 454.188068 -289.46602)
			(xy 454.162549 -289.46551) (xy 454.112123 -289.457621) (xy 454.063511 -289.442067) (xy 454.017872 -289.419218)
			(xy 453.996806 -289.404806) (xy 453.990215 -289.400491) (xy 453.975214 -289.395704) (xy 453.967342 -289.395408)
			(xy 453.451468 -289.395408) (xy 453.446201 -289.394927) (xy 453.438761 -289.387468) (xy 453.43826 -289.3822)
			(xy 447.394076 -289.3822) (xy 447.39377 -289.38754) (xy 447.386209 -289.395083) (xy 447.380868 -289.395408)
			(xy 446.864994 -289.395408) (xy 446.857121 -289.395708) (xy 446.842117 -289.400484) (xy 446.83553 -289.404806)
			(xy 446.814459 -289.419208) (xy 446.768812 -289.442035) (xy 446.720204 -289.45759) (xy 446.669785 -289.465505)
			(xy 446.644268 -289.46602) (xy 446.618749 -289.46551) (xy 446.568323 -289.457621) (xy 446.519711 -289.442067)
			(xy 446.474072 -289.419218) (xy 446.453006 -289.404806) (xy 446.446415 -289.400491) (xy 446.431414 -289.395704)
			(xy 446.423542 -289.395408) (xy 445.907668 -289.395408) (xy 445.902401 -289.394927) (xy 445.894961 -289.387468)
			(xy 445.89446 -289.3822) (xy 439.850276 -289.3822) (xy 439.84997 -289.38754) (xy 439.842409 -289.395083)
			(xy 439.837068 -289.395408) (xy 439.83656 -289.395408) (xy 439.32094 -289.395408) (xy 439.313065 -289.395685)
			(xy 439.298061 -289.400477) (xy 439.291476 -289.404806) (xy 439.270392 -289.419188) (xy 439.22475 -289.44202)
			(xy 439.176146 -289.45758) (xy 439.12573 -289.465502) (xy 439.100214 -289.46602) (xy 439.074694 -289.465537)
			(xy 439.024267 -289.45764) (xy 438.975655 -289.442078) (xy 438.930017 -289.419222) (xy 438.908952 -289.404806)
			(xy 438.902373 -289.40047) (xy 438.887363 -289.395696) (xy 438.879488 -289.395408) (xy 438.363614 -289.395408)
			(xy 438.358323 -289.394873) (xy 438.350754 -289.387479) (xy 438.350152 -289.3822) (xy 432.305968 -289.3822)
			(xy 432.305669 -289.387542) (xy 432.298103 -289.395085) (xy 432.29276 -289.395408) (xy 431.776886 -289.395408)
			(xy 431.769012 -289.395704) (xy 431.754009 -289.400483) (xy 431.747422 -289.404806) (xy 431.726353 -289.419211)
			(xy 431.680706 -289.442038) (xy 431.632097 -289.457592) (xy 431.581678 -289.465506) (xy 431.55616 -289.46602)
			(xy 431.530641 -289.465514) (xy 431.480214 -289.457624) (xy 431.431603 -289.442068) (xy 431.385964 -289.419219)
			(xy 431.364898 -289.404806) (xy 431.358308 -289.400488) (xy 431.343307 -289.395703) (xy 431.335434 -289.395408)
			(xy 430.81956 -289.395408) (xy 430.814292 -289.394932) (xy 430.806852 -289.387469) (xy 430.806352 -289.3822)
			(xy 424.762168 -289.3822) (xy 424.761869 -289.387542) (xy 424.754303 -289.395085) (xy 424.74896 -289.395408)
			(xy 424.748452 -289.395408) (xy 424.232832 -289.395408) (xy 424.224956 -289.395681) (xy 424.209953 -289.400476)
			(xy 424.203368 -289.404806) (xy 424.182286 -289.419191) (xy 424.136644 -289.442022) (xy 424.088039 -289.457582)
			(xy 424.037622 -289.465502) (xy 424.012106 -289.46602) (xy 423.986585 -289.465541) (xy 423.936158 -289.457642)
			(xy 423.887547 -289.442079) (xy 423.841909 -289.419222) (xy 423.820844 -289.404806) (xy 423.814266 -289.400467)
			(xy 423.799256 -289.395695) (xy 423.79138 -289.395408) (xy 423.275506 -289.395408) (xy 423.270214 -289.394879)
			(xy 423.262645 -289.38748) (xy 423.262044 -289.3822) (xy 417.21786 -289.3822) (xy 417.217569 -289.387544)
			(xy 417.209997 -289.395088) (xy 417.204652 -289.395408) (xy 415.731452 -289.395408) (xy 415.726183 -289.394937)
			(xy 415.718744 -289.38747) (xy 415.718244 -289.3822) (xy 374.405768 -289.3822) (xy 374.416737 -289.425518)
			(xy 374.420912 -289.4759) (xy 374.416737 -289.526282) (xy 374.404327 -289.57529) (xy 374.38402 -289.621587)
			(xy 374.356371 -289.66391) (xy 374.322132 -289.701106) (xy 374.282239 -289.732159) (xy 374.237778 -289.756222)
			(xy 374.189964 -289.77264) (xy 374.140099 -289.780964) (xy 374.114822 -289.781488) (xy 373.174768 -289.781488)
			(xy 373.149496 -289.780912) (xy 373.099641 -289.772588) (xy 373.051836 -289.756172) (xy 373.007384 -289.732112)
			(xy 372.967499 -289.701064) (xy 372.933268 -289.663875) (xy 372.905624 -289.621559) (xy 372.885321 -289.575271)
			(xy 372.872914 -289.526272) (xy 372.86874 -289.4759) (xy 371.601012 -289.4759) (xy 371.596837 -289.526283)
			(xy 371.584426 -289.575291) (xy 371.564119 -289.621589) (xy 371.536469 -289.663913) (xy 371.502229 -289.701109)
			(xy 371.462335 -289.732161) (xy 371.417873 -289.756225) (xy 371.370057 -289.772642) (xy 371.320192 -289.780965)
			(xy 371.294914 -289.781488) (xy 370.35486 -289.781488) (xy 370.329588 -289.780911) (xy 370.279734 -289.772586)
			(xy 370.23193 -289.756169) (xy 370.18748 -289.732109) (xy 370.147596 -289.701061) (xy 370.113366 -289.663872)
			(xy 370.085723 -289.621557) (xy 370.065421 -289.575269) (xy 370.053014 -289.526272) (xy 370.04884 -289.4759)
			(xy 368.780941 -289.4759) (xy 368.776764 -289.526294) (xy 368.76435 -289.575313) (xy 368.744035 -289.62162)
			(xy 368.716375 -289.663951) (xy 368.682125 -289.701152) (xy 368.642218 -289.732207) (xy 368.597743 -289.75627)
			(xy 368.549914 -289.772683) (xy 368.500035 -289.780999) (xy 368.474752 -289.781488) (xy 367.534698 -289.781488)
			(xy 367.509424 -289.780914) (xy 367.459565 -289.772594) (xy 367.411756 -289.756181) (xy 367.3673 -289.732122)
			(xy 367.327411 -289.701075) (xy 367.293176 -289.663885) (xy 367.265528 -289.621568) (xy 367.245224 -289.575277)
			(xy 367.232815 -289.526276) (xy 367.22864 -289.4759) (xy 365.960912 -289.4759) (xy 365.956737 -289.52628)
			(xy 365.944329 -289.575285) (xy 365.924024 -289.621581) (xy 365.896376 -289.663903) (xy 365.862141 -289.701098)
			(xy 365.82225 -289.732151) (xy 365.777793 -289.756216) (xy 365.729982 -289.772635) (xy 365.68012 -289.780963)
			(xy 365.654844 -289.781488) (xy 364.71479 -289.781488) (xy 364.689516 -289.780913) (xy 364.639659 -289.772592)
			(xy 364.591851 -289.756178) (xy 364.547396 -289.732119) (xy 364.507508 -289.701072) (xy 364.473273 -289.663882)
			(xy 364.445627 -289.621565) (xy 364.425323 -289.575275) (xy 364.412915 -289.526275) (xy 364.40874 -289.4759)
			(xy 355.627212 -289.4759) (xy 355.623037 -289.526283) (xy 355.610626 -289.575293) (xy 355.590318 -289.621591)
			(xy 355.562667 -289.663915) (xy 355.528427 -289.701111) (xy 355.488531 -289.732164) (xy 355.444069 -289.756226)
			(xy 355.396252 -289.772643) (xy 355.346386 -289.780965) (xy 355.321108 -289.781488) (xy 354.381054 -289.781488)
			(xy 354.355782 -289.780911) (xy 354.305929 -289.772585) (xy 354.258126 -289.756167) (xy 354.213677 -289.732107)
			(xy 354.173794 -289.701059) (xy 354.139564 -289.66387) (xy 354.111922 -289.621555) (xy 354.09162 -289.575268)
			(xy 354.079214 -289.526271) (xy 354.07504 -289.4759) (xy 352.807312 -289.4759) (xy 352.803137 -289.526284)
			(xy 352.790726 -289.575294) (xy 352.770417 -289.621593) (xy 352.742765 -289.663918) (xy 352.708524 -289.701114)
			(xy 352.668627 -289.732166) (xy 352.624164 -289.756229) (xy 352.576346 -289.772645) (xy 352.526478 -289.780966)
			(xy 352.5012 -289.781488) (xy 351.561146 -289.781488) (xy 351.535867 -289.780947) (xy 351.485997 -289.772632)
			(xy 351.438177 -289.756221) (xy 351.39371 -289.732163) (xy 351.35381 -289.701113) (xy 351.319565 -289.663919)
			(xy 351.29191 -289.621595) (xy 351.271599 -289.575296) (xy 351.259187 -289.526285) (xy 351.255011 -289.4759)
			(xy 349.987441 -289.4759) (xy 349.983265 -289.52629) (xy 349.970852 -289.575305) (xy 349.950541 -289.621609)
			(xy 349.922886 -289.663938) (xy 349.88864 -289.701138) (xy 349.848739 -289.732193) (xy 349.80427 -289.756258)
			(xy 349.756447 -289.772674) (xy 349.706573 -289.780996) (xy 349.681292 -289.781488) (xy 348.741238 -289.781488)
			(xy 348.715959 -289.780946) (xy 348.666091 -289.77263) (xy 348.618271 -289.756219) (xy 348.573806 -289.73216)
			(xy 348.533907 -289.70111) (xy 348.499663 -289.663916) (xy 348.472009 -289.621593) (xy 348.451699 -289.575294)
			(xy 348.439287 -289.526284) (xy 348.435111 -289.4759) (xy 347.167212 -289.4759) (xy 347.163037 -289.526281)
			(xy 347.150628 -289.575288) (xy 347.130322 -289.621585) (xy 347.102673 -289.663908) (xy 347.068435 -289.701103)
			(xy 347.028543 -289.732156) (xy 346.984084 -289.75622) (xy 346.93627 -289.772638) (xy 346.886407 -289.780964)
			(xy 346.86113 -289.781488) (xy 345.921076 -289.781488) (xy 345.895803 -289.780912) (xy 345.845947 -289.772589)
			(xy 345.798141 -289.756174) (xy 345.753689 -289.732114) (xy 345.713802 -289.701067) (xy 345.67957 -289.663878)
			(xy 345.651925 -289.621562) (xy 345.631622 -289.575273) (xy 345.619214 -289.526273) (xy 345.61504 -289.4759)
			(xy 126.480615 -289.4759) (xy 126.48064 -289.4762) (xy 126.476468 -289.526544) (xy 126.464066 -289.575515)
			(xy 126.443771 -289.621777) (xy 126.416139 -289.664066) (xy 126.381922 -289.70123) (xy 126.342054 -289.732255)
			(xy 126.297623 -289.756294) (xy 126.249842 -289.772691) (xy 126.200013 -289.780999) (xy 126.174754 -289.781488)
			(xy 125.2347 -289.781488) (xy 125.209443 -289.781006) (xy 125.159618 -289.772692) (xy 125.111841 -289.75629)
			(xy 125.067415 -289.732248) (xy 125.027553 -289.701222) (xy 124.993341 -289.664058) (xy 124.965712 -289.621769)
			(xy 124.945421 -289.57551) (xy 124.93302 -289.526541) (xy 124.928849 -289.4762) (xy 123.660611 -289.4762)
			(xy 123.656441 -289.52653) (xy 123.644044 -289.575487) (xy 123.62376 -289.621737) (xy 123.59614 -289.664018)
			(xy 123.561938 -289.701176) (xy 123.522087 -289.732199) (xy 123.477674 -289.75624) (xy 123.42991 -289.772644)
			(xy 123.380097 -289.780963) (xy 123.354846 -289.781488) (xy 122.414792 -289.781488) (xy 122.389535 -289.781006)
			(xy 122.339711 -289.77269) (xy 122.291936 -289.756288) (xy 122.247511 -289.732245) (xy 122.20765 -289.701219)
			(xy 122.173439 -289.664055) (xy 122.145811 -289.621767) (xy 122.12552 -289.575508) (xy 122.11312 -289.526541)
			(xy 122.108949 -289.4762) (xy 120.84054 -289.4762) (xy 120.836368 -289.526541) (xy 120.823968 -289.575509)
			(xy 120.803676 -289.621768) (xy 120.776047 -289.664056) (xy 120.741834 -289.70122) (xy 120.70197 -289.732245)
			(xy 120.657544 -289.756285) (xy 120.609766 -289.772685) (xy 120.559941 -289.780997) (xy 120.534684 -289.781488)
			(xy 119.59463 -289.781488) (xy 119.569369 -289.781038) (xy 119.519535 -289.772726) (xy 119.47175 -289.756326)
			(xy 119.427315 -289.732283) (xy 119.387445 -289.701254) (xy 119.353225 -289.664085) (xy 119.325591 -289.621791)
			(xy 119.305295 -289.575525) (xy 119.292892 -289.526549) (xy 119.28872 -289.4762) (xy 118.02064 -289.4762)
			(xy 118.016468 -289.526542) (xy 118.004067 -289.575511) (xy 117.983775 -289.62177) (xy 117.956145 -289.664059)
			(xy 117.92193 -289.701222) (xy 117.882066 -289.732247) (xy 117.837638 -289.756287) (xy 117.78986 -289.772686)
			(xy 117.740033 -289.780997) (xy 117.714776 -289.781488) (xy 116.774722 -289.781488) (xy 116.749461 -289.781037)
			(xy 116.699629 -289.772725) (xy 116.651844 -289.756323) (xy 116.607411 -289.73228) (xy 116.567542 -289.701251)
			(xy 116.533323 -289.664083) (xy 116.50569 -289.621789) (xy 116.485395 -289.575523) (xy 116.472992 -289.526548)
			(xy 116.46882 -289.4762) (xy 107.686811 -289.4762) (xy 107.682641 -289.526531) (xy 107.670244 -289.575489)
			(xy 107.649959 -289.621739) (xy 107.622338 -289.66402) (xy 107.588136 -289.701178) (xy 107.548284 -289.732201)
			(xy 107.50387 -289.756242) (xy 107.456105 -289.772645) (xy 107.406292 -289.780963) (xy 107.38104 -289.781488)
			(xy 106.440986 -289.781488) (xy 106.41573 -289.781005) (xy 106.365907 -289.772689) (xy 106.318132 -289.756286)
			(xy 106.273708 -289.732243) (xy 106.233847 -289.701217) (xy 106.199637 -289.664053) (xy 106.17201 -289.621765)
			(xy 106.15172 -289.575507) (xy 106.13932 -289.52654) (xy 106.135149 -289.4762) (xy 104.866911 -289.4762)
			(xy 104.862741 -289.526532) (xy 104.850344 -289.57549) (xy 104.830058 -289.621741) (xy 104.802436 -289.664022)
			(xy 104.768233 -289.701181) (xy 104.72838 -289.732204) (xy 104.683965 -289.756244) (xy 104.636198 -289.772647)
			(xy 104.586384 -289.780964) (xy 104.561132 -289.781488) (xy 103.621078 -289.781488) (xy 103.595822 -289.781005)
			(xy 103.546 -289.772687) (xy 103.498226 -289.756284) (xy 103.453804 -289.732241) (xy 103.413944 -289.701214)
			(xy 103.379735 -289.66405) (xy 103.352109 -289.621763) (xy 103.331819 -289.575505) (xy 103.31942 -289.526539)
			(xy 103.315249 -289.4762) (xy 102.047011 -289.4762) (xy 102.042841 -289.526532) (xy 102.030443 -289.575492)
			(xy 102.010156 -289.621743) (xy 101.982534 -289.664025) (xy 101.948329 -289.701184) (xy 101.908475 -289.732206)
			(xy 101.864059 -289.756246) (xy 101.816292 -289.772648) (xy 101.766476 -289.780965) (xy 101.741224 -289.781488)
			(xy 100.80117 -289.781488) (xy 100.775915 -289.781004) (xy 100.726093 -289.772686) (xy 100.678321 -289.756281)
			(xy 100.633899 -289.732238) (xy 100.594041 -289.701211) (xy 100.559833 -289.664048) (xy 100.532208 -289.621761)
			(xy 100.511919 -289.575504) (xy 100.49952 -289.526538) (xy 100.495349 -289.4762) (xy 99.22694 -289.4762)
			(xy 99.222768 -289.526544) (xy 99.210366 -289.575514) (xy 99.190073 -289.621774) (xy 99.162441 -289.664063)
			(xy 99.128225 -289.701227) (xy 99.088358 -289.732252) (xy 99.043929 -289.756291) (xy 98.996148 -289.772689)
			(xy 98.94632 -289.780998) (xy 98.921062 -289.781488) (xy 97.981008 -289.781488) (xy 97.955748 -289.781036)
			(xy 97.905917 -289.772722) (xy 97.858135 -289.756319) (xy 97.813704 -289.732275) (xy 97.773836 -289.701246)
			(xy 97.73962 -289.664078) (xy 97.711988 -289.621785) (xy 97.691694 -289.575521) (xy 97.679292 -289.526547)
			(xy 97.67512 -289.4762) (xy 2.509012 -289.4762) (xy 2.509012 -290.232592) (xy 16.85798 -290.232592)
			(xy 16.85798 -289.738054) (xy 16.858424 -289.732674) (xy 16.866059 -289.725089) (xy 16.871442 -289.724592)
			(xy 17.38757 -289.724592) (xy 17.395379 -289.724267) (xy 17.410251 -289.719489) (xy 17.41678 -289.715194)
			(xy 17.437869 -289.700845) (xy 17.48353 -289.678114) (xy 17.532136 -289.662655) (xy 17.582539 -289.654832)
			(xy 17.633545 -289.654832) (xy 17.683948 -289.662655) (xy 17.732554 -289.678114) (xy 17.778215 -289.700845)
			(xy 17.799304 -289.715194) (xy 17.805836 -289.719485) (xy 17.820706 -289.724268) (xy 17.828514 -289.724592)
			(xy 18.344642 -289.724592) (xy 18.35 -289.725118) (xy 18.357581 -289.732696) (xy 18.358104 -289.738054)
			(xy 18.358104 -290.232592) (xy 24.402288 -290.232592) (xy 24.402288 -289.738054) (xy 24.402765 -289.732745)
			(xy 24.410197 -289.725168) (xy 24.415496 -289.724592) (xy 24.931624 -289.724592) (xy 24.939435 -289.72429)
			(xy 24.954306 -289.719496) (xy 24.960834 -289.715194) (xy 24.981923 -289.700845) (xy 25.027584 -289.678114)
			(xy 25.07619 -289.662655) (xy 25.126593 -289.654832) (xy 25.177599 -289.654832) (xy 25.228002 -289.662655)
			(xy 25.276608 -289.678114) (xy 25.322269 -289.700845) (xy 25.343358 -289.715194) (xy 25.349878 -289.719506)
			(xy 25.364757 -289.724276) (xy 25.372568 -289.724592) (xy 25.888696 -289.724592) (xy 25.894028 -289.72493)
			(xy 25.901569 -289.732468) (xy 25.901904 -289.7378) (xy 25.901904 -289.738308) (xy 25.901904 -290.232592)
			(xy 31.946088 -290.232592) (xy 31.946088 -289.738054) (xy 31.946565 -289.732745) (xy 31.953997 -289.725168)
			(xy 31.959296 -289.724592) (xy 32.475424 -289.724592) (xy 32.483235 -289.72429) (xy 32.498106 -289.719496)
			(xy 32.504634 -289.715194) (xy 32.525723 -289.700845) (xy 32.571384 -289.678114) (xy 32.61999 -289.662655)
			(xy 32.670393 -289.654832) (xy 32.721399 -289.654832) (xy 32.771802 -289.662655) (xy 32.820408 -289.678114)
			(xy 32.866069 -289.700845) (xy 32.887158 -289.715194) (xy 32.893678 -289.719506) (xy 32.908557 -289.724276)
			(xy 32.916368 -289.724592) (xy 33.432496 -289.724592) (xy 33.437828 -289.72493) (xy 33.445369 -289.732468)
			(xy 33.445704 -289.7378) (xy 33.445704 -289.738308) (xy 33.445704 -290.232592) (xy 39.489888 -290.232592)
			(xy 39.489888 -289.738054) (xy 39.490415 -289.732697) (xy 39.497993 -289.725116) (xy 39.50335 -289.724592)
			(xy 40.019478 -289.724592) (xy 40.027287 -289.72427) (xy 40.042159 -289.71949) (xy 40.048688 -289.715194)
			(xy 40.069777 -289.700845) (xy 40.115438 -289.678114) (xy 40.164044 -289.662655) (xy 40.214447 -289.654832)
			(xy 40.265453 -289.654832) (xy 40.315856 -289.662655) (xy 40.364462 -289.678114) (xy 40.410123 -289.700845)
			(xy 40.431212 -289.715194) (xy 40.437742 -289.719488) (xy 40.452613 -289.724269) (xy 40.460422 -289.724592)
			(xy 40.97655 -289.724592) (xy 40.981909 -289.725113) (xy 40.989489 -289.732695) (xy 40.990012 -289.738054)
			(xy 40.990012 -290.232592) (xy 47.034196 -290.232592) (xy 47.034196 -289.738054) (xy 47.034754 -289.732766)
			(xy 47.042131 -289.725195) (xy 47.047404 -289.724592) (xy 47.563532 -289.724592) (xy 47.57134 -289.724251)
			(xy 47.586211 -289.719484) (xy 47.592742 -289.715194) (xy 47.613831 -289.700845) (xy 47.659492 -289.678114)
			(xy 47.708098 -289.662655) (xy 47.758501 -289.654832) (xy 47.809507 -289.654832) (xy 47.85991 -289.662655)
			(xy 47.908516 -289.678114) (xy 47.954177 -289.700845) (xy 47.975266 -289.715194) (xy 47.981806 -289.71947)
			(xy 47.99667 -289.724263) (xy 48.004476 -289.724592) (xy 48.520604 -289.724592) (xy 48.525867 -289.725092)
			(xy 48.53331 -289.732537) (xy 48.533812 -289.7378) (xy 48.533812 -289.738308) (xy 48.533812 -290.232592)
			(xy 54.577996 -290.232592) (xy 54.577996 -289.738054) (xy 54.578516 -289.732695) (xy 54.586098 -289.725114)
			(xy 54.591458 -289.724592) (xy 56.064658 -289.724592) (xy 56.070006 -289.725174) (xy 56.077591 -289.73271)
			(xy 56.07812 -289.738054) (xy 56.07812 -290.232592) (xy 56.077601 -290.237851) (xy 56.07017 -290.245293)
			(xy 56.064912 -290.2458) (xy 54.591458 -290.2458) (xy 54.586158 -290.24531) (xy 54.578592 -290.237882)
			(xy 54.577996 -290.232592) (xy 48.533812 -290.232592) (xy 48.533468 -290.237922) (xy 48.525934 -290.245463)
			(xy 48.520604 -290.2458) (xy 48.00473 -290.2458) (xy 47.996854 -290.246074) (xy 47.981851 -290.250868)
			(xy 47.975266 -290.255198) (xy 47.954184 -290.269583) (xy 47.920966 -290.2862) (xy 108.4849 -290.2862)
			(xy 108.489075 -290.235818) (xy 108.501485 -290.186811) (xy 108.521793 -290.140514) (xy 108.549443 -290.098192)
			(xy 108.583682 -290.060997) (xy 108.623576 -290.029946) (xy 108.668037 -290.005884) (xy 108.715852 -289.989468)
			(xy 108.765717 -289.981146) (xy 108.790994 -289.980624) (xy 109.731048 -289.980624) (xy 109.756321 -289.981178)
			(xy 109.806175 -289.989504) (xy 109.85398 -290.005922) (xy 109.898431 -290.029984) (xy 109.938315 -290.061033)
			(xy 109.972546 -290.098223) (xy 110.000189 -290.140539) (xy 110.020491 -290.186828) (xy 110.032898 -290.235827)
			(xy 110.037072 -290.2862) (xy 114.118571 -290.2862) (xy 114.122747 -290.235811) (xy 114.135159 -290.186797)
			(xy 114.15547 -290.140495) (xy 114.183125 -290.098167) (xy 114.21737 -290.060969) (xy 114.257271 -290.029915)
			(xy 114.301739 -290.005852) (xy 114.349561 -289.989436) (xy 114.399433 -289.981116) (xy 114.424714 -289.980624)
			(xy 115.364768 -289.980624) (xy 115.390047 -289.981142) (xy 115.439917 -289.989459) (xy 115.487738 -290.005872)
			(xy 115.532204 -290.029932) (xy 115.572104 -290.060983) (xy 115.606348 -290.098179) (xy 115.634003 -290.140503)
			(xy 115.654313 -290.186803) (xy 115.665909 -290.232592) (xy 163.678108 -290.232592) (xy 163.678108 -289.738054)
			(xy 163.678656 -289.732764) (xy 163.686039 -289.725191) (xy 163.691316 -289.724592) (xy 165.164516 -289.724592)
			(xy 165.169781 -289.725084) (xy 165.177222 -289.732535) (xy 165.177724 -289.7378) (xy 165.177724 -289.738308)
			(xy 165.177724 -290.232592) (xy 171.221908 -290.232592) (xy 171.221908 -289.738054) (xy 171.222417 -289.732692)
			(xy 171.230007 -289.72511) (xy 171.23537 -289.724592) (xy 171.751498 -289.724592) (xy 171.759308 -289.724279)
			(xy 171.77418 -289.719493) (xy 171.780708 -289.715194) (xy 171.801797 -289.700845) (xy 171.847458 -289.678114)
			(xy 171.896064 -289.662655) (xy 171.946467 -289.654832) (xy 171.997473 -289.654832) (xy 172.047876 -289.662655)
			(xy 172.096482 -289.678114) (xy 172.142143 -289.700845) (xy 172.163232 -289.715194) (xy 172.169757 -289.719496)
			(xy 172.184632 -289.724272) (xy 172.192442 -289.724592) (xy 172.70857 -289.724592) (xy 172.713919 -289.725166)
			(xy 172.721504 -289.732708) (xy 172.722032 -289.738054) (xy 172.722032 -290.232592) (xy 178.766216 -290.232592)
			(xy 178.766216 -289.738054) (xy 178.766756 -289.732762) (xy 178.774145 -289.725189) (xy 178.779424 -289.724592)
			(xy 179.295552 -289.724592) (xy 179.30336 -289.724259) (xy 179.318232 -289.719487) (xy 179.324762 -289.715194)
			(xy 179.345851 -289.700845) (xy 179.391512 -289.678114) (xy 179.440118 -289.662655) (xy 179.490521 -289.654832)
			(xy 179.541527 -289.654832) (xy 179.59193 -289.662655) (xy 179.640536 -289.678114) (xy 179.686197 -289.700845)
			(xy 179.707286 -289.715194) (xy 179.713822 -289.719478) (xy 179.728688 -289.724266) (xy 179.736496 -289.724592)
			(xy 180.252624 -289.724592) (xy 180.25789 -289.725079) (xy 180.265331 -289.732534) (xy 180.265832 -289.7378)
			(xy 180.265832 -289.738308) (xy 180.265832 -290.232592) (xy 186.310016 -290.232592) (xy 186.310016 -289.738054)
			(xy 186.310518 -289.73269) (xy 186.318113 -289.725108) (xy 186.323478 -289.724592) (xy 186.839606 -289.724592)
			(xy 186.847416 -289.724282) (xy 186.862288 -289.719494) (xy 186.868816 -289.715194) (xy 186.889905 -289.700845)
			(xy 186.935566 -289.678114) (xy 186.984172 -289.662655) (xy 187.034575 -289.654832) (xy 187.085581 -289.654832)
			(xy 187.135984 -289.662655) (xy 187.18459 -289.678114) (xy 187.230251 -289.700845) (xy 187.25134 -289.715194)
			(xy 187.257864 -289.719499) (xy 187.27274 -289.724274) (xy 187.28055 -289.724592) (xy 187.796678 -289.724592)
			(xy 187.802028 -289.725161) (xy 187.809612 -289.732706) (xy 187.81014 -289.738054) (xy 187.81014 -290.232592)
			(xy 193.854324 -290.232592) (xy 193.854324 -289.738054) (xy 193.854857 -289.73276) (xy 193.862251 -289.725187)
			(xy 193.867532 -289.724592) (xy 194.38366 -289.724592) (xy 194.391469 -289.724263) (xy 194.40634 -289.719488)
			(xy 194.41287 -289.715194) (xy 194.433959 -289.700845) (xy 194.47962 -289.678114) (xy 194.528226 -289.662655)
			(xy 194.578629 -289.654832) (xy 194.629635 -289.654832) (xy 194.680038 -289.662655) (xy 194.728644 -289.678114)
			(xy 194.774305 -289.700845) (xy 194.795394 -289.715194) (xy 194.801928 -289.719481) (xy 194.816796 -289.724267)
			(xy 194.824604 -289.724592) (xy 195.340732 -289.724592) (xy 195.345999 -289.725073) (xy 195.353439 -289.732532)
			(xy 195.35394 -289.7378) (xy 195.35394 -289.738308) (xy 195.35394 -290.232592) (xy 201.398124 -290.232592)
			(xy 201.398124 -289.738054) (xy 201.398657 -289.73276) (xy 201.406051 -289.725187) (xy 201.411332 -289.724592)
			(xy 201.92746 -289.724592) (xy 201.935269 -289.724263) (xy 201.95014 -289.719488) (xy 201.95667 -289.715194)
			(xy 201.977759 -289.700845) (xy 202.02342 -289.678114) (xy 202.072026 -289.662655) (xy 202.122429 -289.654832)
			(xy 202.173435 -289.654832) (xy 202.223838 -289.662655) (xy 202.272444 -289.678114) (xy 202.318105 -289.700845)
			(xy 202.339194 -289.715194) (xy 202.345728 -289.719481) (xy 202.360596 -289.724267) (xy 202.368404 -289.724592)
			(xy 202.884532 -289.724592) (xy 202.889799 -289.725073) (xy 202.897239 -289.732532) (xy 202.89774 -289.7378)
			(xy 202.89774 -289.738308) (xy 202.89774 -290.232338) (xy 264.798048 -290.232338) (xy 264.798048 -289.7378)
			(xy 264.79859 -289.732548) (xy 264.806006 -289.725108) (xy 264.811256 -289.724592) (xy 264.811764 -289.724592)
			(xy 265.327638 -289.724592) (xy 265.335446 -289.724253) (xy 265.350317 -289.719484) (xy 265.356848 -289.715194)
			(xy 265.377937 -289.700845) (xy 265.423598 -289.678114) (xy 265.472204 -289.662655) (xy 265.522607 -289.654832)
			(xy 265.573613 -289.654832) (xy 265.624016 -289.662655) (xy 265.672622 -289.678114) (xy 265.718283 -289.700845)
			(xy 265.739372 -289.715194) (xy 265.745911 -289.719473) (xy 265.760775 -289.724264) (xy 265.768582 -289.724592)
			(xy 266.28471 -289.724592) (xy 266.290004 -289.725111) (xy 266.297572 -289.732518) (xy 266.298172 -289.7378)
			(xy 266.298172 -290.232338) (xy 266.298149 -290.232592) (xy 272.342356 -290.232592) (xy 272.342356 -290.232084)
			(xy 272.342356 -289.7378) (xy 272.342891 -289.732546) (xy 272.350311 -289.725106) (xy 272.355564 -289.724592)
			(xy 272.871692 -289.724592) (xy 272.879502 -289.724276) (xy 272.894373 -289.719492) (xy 272.900902 -289.715194)
			(xy 272.921991 -289.700845) (xy 272.967652 -289.678114) (xy 273.016258 -289.662655) (xy 273.066661 -289.654832)
			(xy 273.117667 -289.654832) (xy 273.16807 -289.662655) (xy 273.216676 -289.678114) (xy 273.262337 -289.700845)
			(xy 273.283426 -289.715194) (xy 273.289953 -289.719493) (xy 273.304826 -289.724272) (xy 273.312636 -289.724592)
			(xy 273.828764 -289.724592) (xy 273.834092 -289.724951) (xy 273.841635 -289.732473) (xy 273.841972 -289.7378)
			(xy 273.841972 -290.232338) (xy 273.84195 -290.232592) (xy 279.886156 -290.232592) (xy 279.886156 -290.232084)
			(xy 279.886156 -289.7378) (xy 279.886691 -289.732546) (xy 279.894111 -289.725106) (xy 279.899364 -289.724592)
			(xy 280.415492 -289.724592) (xy 280.423302 -289.724276) (xy 280.438173 -289.719492) (xy 280.444702 -289.715194)
			(xy 280.465791 -289.700845) (xy 280.511452 -289.678114) (xy 280.560058 -289.662655) (xy 280.610461 -289.654832)
			(xy 280.661467 -289.654832) (xy 280.71187 -289.662655) (xy 280.760476 -289.678114) (xy 280.806137 -289.700845)
			(xy 280.827226 -289.715194) (xy 280.833753 -289.719493) (xy 280.848626 -289.724272) (xy 280.856436 -289.724592)
			(xy 281.372564 -289.724592) (xy 281.377892 -289.724951) (xy 281.385435 -289.732473) (xy 281.385772 -289.7378)
			(xy 281.385772 -290.232338) (xy 287.429956 -290.232338) (xy 287.429956 -289.7378) (xy 287.430491 -289.732546)
			(xy 287.437911 -289.725106) (xy 287.443164 -289.724592) (xy 287.443672 -289.724592) (xy 287.959546 -289.724592)
			(xy 287.967354 -289.724257) (xy 287.982226 -289.719486) (xy 287.988756 -289.715194) (xy 288.009845 -289.700845)
			(xy 288.055506 -289.678114) (xy 288.104112 -289.662655) (xy 288.154515 -289.654832) (xy 288.205521 -289.654832)
			(xy 288.255924 -289.662655) (xy 288.30453 -289.678114) (xy 288.350191 -289.700845) (xy 288.37128 -289.715194)
			(xy 288.377817 -289.719476) (xy 288.392683 -289.724265) (xy 288.40049 -289.724592) (xy 288.916618 -289.724592)
			(xy 288.921913 -289.725105) (xy 288.929481 -289.732516) (xy 288.93008 -289.7378) (xy 288.93008 -290.232338)
			(xy 288.930056 -290.232592) (xy 294.974264 -290.232592) (xy 294.974264 -290.232084) (xy 294.974264 -289.7378)
			(xy 294.974792 -289.732544) (xy 294.982217 -289.725103) (xy 294.987472 -289.724592) (xy 295.5036 -289.724592)
			(xy 295.51141 -289.72428) (xy 295.526282 -289.719493) (xy 295.53281 -289.715194) (xy 295.553899 -289.700845)
			(xy 295.59956 -289.678114) (xy 295.648166 -289.662655) (xy 295.698569 -289.654832) (xy 295.749575 -289.654832)
			(xy 295.799978 -289.662655) (xy 295.848584 -289.678114) (xy 295.894245 -289.700845) (xy 295.915334 -289.715194)
			(xy 295.921859 -289.719497) (xy 295.936734 -289.724273) (xy 295.944544 -289.724592) (xy 296.460672 -289.724592)
			(xy 296.466001 -289.724945) (xy 296.473543 -289.732472) (xy 296.47388 -289.7378) (xy 296.47388 -290.232338)
			(xy 302.518064 -290.232338) (xy 302.518064 -289.7378) (xy 302.518592 -289.732544) (xy 302.526017 -289.725103)
			(xy 302.531272 -289.724592) (xy 304.004726 -289.724592) (xy 304.010022 -289.7251) (xy 304.017589 -289.732515)
			(xy 304.018188 -289.7378) (xy 304.018188 -290.232338) (xy 304.017677 -290.2377) (xy 304.010089 -290.245282)
			(xy 304.004726 -290.2458) (xy 302.531526 -290.2458) (xy 302.526174 -290.245236) (xy 302.518589 -290.237687)
			(xy 302.518064 -290.232338) (xy 296.47388 -290.232338) (xy 296.473404 -290.237642) (xy 296.465967 -290.24521)
			(xy 296.460672 -290.2458) (xy 295.944798 -290.2458) (xy 295.936988 -290.246113) (xy 295.922116 -290.250899)
			(xy 295.915588 -290.255198) (xy 295.894463 -290.269542) (xy 295.861558 -290.2859) (xy 356.425301 -290.2859)
			(xy 356.429471 -290.235571) (xy 356.441867 -290.186615) (xy 356.462152 -290.140366) (xy 356.489772 -290.098087)
			(xy 356.523973 -290.06093) (xy 356.563824 -290.029908) (xy 356.608236 -290.005869) (xy 356.656 -289.989466)
			(xy 356.705811 -289.981148) (xy 356.731062 -289.980624) (xy 357.671116 -289.980624) (xy 357.696373 -289.981083)
			(xy 357.746198 -289.9894) (xy 357.793975 -290.005804) (xy 357.8384 -290.029847) (xy 357.878262 -290.060875)
			(xy 357.912473 -290.09804) (xy 357.940101 -290.14033) (xy 357.960392 -290.18659) (xy 357.972792 -290.235558)
			(xy 357.976963 -290.2859) (xy 362.059001 -290.2859) (xy 362.063171 -290.235569) (xy 362.075569 -290.186611)
			(xy 362.095855 -290.140361) (xy 362.123477 -290.09808) (xy 362.157681 -290.060923) (xy 362.197534 -290.029902)
			(xy 362.24195 -290.005863) (xy 362.289716 -289.989462) (xy 362.33953 -289.981147) (xy 362.364782 -289.980624)
			(xy 363.304836 -289.980624) (xy 363.330092 -289.981084) (xy 363.379914 -289.989404) (xy 363.427688 -290.005809)
			(xy 363.47211 -290.029854) (xy 363.511969 -290.060882) (xy 363.546178 -290.098047) (xy 363.573804 -290.140335)
			(xy 363.594093 -290.186594) (xy 363.60574 -290.232592) (xy 411.618176 -290.232592) (xy 411.618176 -290.232084)
			(xy 411.618176 -289.7378) (xy 411.618693 -289.732541) (xy 411.626126 -289.7251) (xy 411.631384 -289.724592)
			(xy 413.104584 -289.724592) (xy 413.109914 -289.724938) (xy 413.117456 -289.73247) (xy 413.117792 -289.7378)
			(xy 413.117792 -290.232338) (xy 419.161976 -290.232338) (xy 419.161976 -289.7378) (xy 419.162493 -289.732541)
			(xy 419.169926 -289.7251) (xy 419.175184 -289.724592) (xy 419.175692 -289.724592) (xy 419.691566 -289.724592)
			(xy 419.699375 -289.724265) (xy 419.714246 -289.719488) (xy 419.720776 -289.715194) (xy 419.741865 -289.700845)
			(xy 419.787526 -289.678114) (xy 419.836132 -289.662655) (xy 419.886535 -289.654832) (xy 419.937541 -289.654832)
			(xy 419.987944 -289.662655) (xy 420.03655 -289.678114) (xy 420.082211 -289.700845) (xy 420.1033 -289.715194)
			(xy 420.109833 -289.719484) (xy 420.124702 -289.724268) (xy 420.13251 -289.724592) (xy 420.648638 -289.724592)
			(xy 420.653936 -289.725092) (xy 420.661502 -289.732513) (xy 420.6621 -289.7378) (xy 420.6621 -290.232338)
			(xy 420.662075 -290.232592) (xy 426.706284 -290.232592) (xy 426.706284 -290.232084) (xy 426.706284 -289.7378)
			(xy 426.706794 -289.732539) (xy 426.714232 -289.725097) (xy 426.719492 -289.724592) (xy 427.23562 -289.724592)
			(xy 427.243431 -289.724288) (xy 427.258302 -289.719495) (xy 427.26483 -289.715194) (xy 427.285919 -289.700845)
			(xy 427.33158 -289.678114) (xy 427.380186 -289.662655) (xy 427.430589 -289.654832) (xy 427.481595 -289.654832)
			(xy 427.531998 -289.662655) (xy 427.580604 -289.678114) (xy 427.626265 -289.700845) (xy 427.647354 -289.715194)
			(xy 427.653875 -289.719504) (xy 427.668753 -289.724276) (xy 427.676564 -289.724592) (xy 428.192692 -289.724592)
			(xy 428.198023 -289.724932) (xy 428.205565 -289.732469) (xy 428.2059 -289.7378) (xy 428.2059 -290.232338)
			(xy 434.250084 -290.232338) (xy 434.250084 -289.7378) (xy 434.250594 -289.732539) (xy 434.258032 -289.725097)
			(xy 434.263292 -289.724592) (xy 434.2638 -289.724592) (xy 434.779674 -289.724592) (xy 434.787483 -289.724269)
			(xy 434.802355 -289.71949) (xy 434.808884 -289.715194) (xy 434.829973 -289.700845) (xy 434.875634 -289.678114)
			(xy 434.92424 -289.662655) (xy 434.974643 -289.654832) (xy 435.025649 -289.654832) (xy 435.076052 -289.662655)
			(xy 435.124658 -289.678114) (xy 435.170319 -289.700845) (xy 435.191408 -289.715194) (xy 435.197939 -289.719487)
			(xy 435.212809 -289.724269) (xy 435.220618 -289.724592) (xy 435.736746 -289.724592) (xy 435.742033 -289.725154)
			(xy 435.749604 -289.732528) (xy 435.750208 -289.7378) (xy 435.750208 -290.232338) (xy 435.750183 -290.232592)
			(xy 441.794392 -290.232592) (xy 441.794392 -290.232084) (xy 441.794392 -289.7378) (xy 441.794895 -289.732537)
			(xy 441.802337 -289.725095) (xy 441.8076 -289.724592) (xy 442.323728 -289.724592) (xy 442.331539 -289.724292)
			(xy 442.346411 -289.719497) (xy 442.352938 -289.715194) (xy 442.374027 -289.700845) (xy 442.419688 -289.678114)
			(xy 442.468294 -289.662655) (xy 442.518697 -289.654832) (xy 442.569703 -289.654832) (xy 442.620106 -289.662655)
			(xy 442.668712 -289.678114) (xy 442.714373 -289.700845) (xy 442.735462 -289.715194) (xy 442.742003 -289.719469)
			(xy 442.756866 -289.724262) (xy 442.764672 -289.724592) (xy 443.2808 -289.724592) (xy 443.286063 -289.725095)
			(xy 443.293505 -289.732537) (xy 443.294008 -289.7378) (xy 443.294008 -290.232338) (xy 443.293984 -290.232592)
			(xy 449.338192 -290.232592) (xy 449.338192 -290.232084) (xy 449.338192 -289.7378) (xy 449.338695 -289.732537)
			(xy 449.346137 -289.725095) (xy 449.3514 -289.724592) (xy 449.867528 -289.724592) (xy 449.875339 -289.724292)
			(xy 449.890211 -289.719497) (xy 449.896738 -289.715194) (xy 449.917827 -289.700845) (xy 449.963488 -289.678114)
			(xy 450.012094 -289.662655) (xy 450.062497 -289.654832) (xy 450.113503 -289.654832) (xy 450.163906 -289.662655)
			(xy 450.212512 -289.678114) (xy 450.258173 -289.700845) (xy 450.279262 -289.715194) (xy 450.285803 -289.719469)
			(xy 450.300666 -289.724262) (xy 450.308472 -289.724592) (xy 450.8246 -289.724592) (xy 450.829863 -289.725095)
			(xy 450.837305 -289.732537) (xy 450.837808 -289.7378) (xy 450.837808 -290.232338) (xy 450.837308 -290.237636)
			(xy 450.829887 -290.245202) (xy 450.8246 -290.2458) (xy 450.308726 -290.2458) (xy 450.300917 -290.246125)
			(xy 450.286045 -290.250903) (xy 450.279516 -290.255198) (xy 450.258383 -290.26953) (xy 450.212664 -290.292262)
			(xy 450.163994 -290.307697) (xy 450.11353 -290.315469) (xy 450.088 -290.315904) (xy 450.06247 -290.31546)
			(xy 450.012007 -290.307685) (xy 449.963335 -290.292258) (xy 449.917607 -290.269544) (xy 449.896484 -290.255198)
			(xy 449.889955 -290.250902) (xy 449.875083 -290.246122) (xy 449.867274 -290.2458) (xy 449.3514 -290.2458)
			(xy 449.346066 -290.245473) (xy 449.338524 -290.237926) (xy 449.338192 -290.232592) (xy 443.293984 -290.232592)
			(xy 443.293508 -290.237636) (xy 443.286087 -290.245202) (xy 443.2808 -290.2458) (xy 442.764926 -290.2458)
			(xy 442.757117 -290.246125) (xy 442.742245 -290.250903) (xy 442.735716 -290.255198) (xy 442.714583 -290.26953)
			(xy 442.668864 -290.292262) (xy 442.620194 -290.307697) (xy 442.56973 -290.315469) (xy 442.5442 -290.315904)
			(xy 442.51867 -290.31546) (xy 442.468207 -290.307685) (xy 442.419535 -290.292258) (xy 442.373807 -290.269544)
			(xy 442.352684 -290.255198) (xy 442.346155 -290.250902) (xy 442.331283 -290.246122) (xy 442.323474 -290.2458)
			(xy 441.8076 -290.2458) (xy 441.802266 -290.245473) (xy 441.794724 -290.237926) (xy 441.794392 -290.232592)
			(xy 435.750183 -290.232592) (xy 435.749679 -290.237695) (xy 435.742103 -290.245276) (xy 435.736746 -290.2458)
			(xy 435.220872 -290.2458) (xy 435.213061 -290.246102) (xy 435.19819 -290.250896) (xy 435.191662 -290.255198)
			(xy 435.170544 -290.269554) (xy 435.12482 -290.29228) (xy 435.076145 -290.307709) (xy 435.025677 -290.315473)
			(xy 435.000146 -290.315904) (xy 434.974617 -290.315437) (xy 434.924155 -290.307669) (xy 434.875482 -290.292249)
			(xy 434.829753 -290.269541) (xy 434.80863 -290.255198) (xy 434.802091 -290.250919) (xy 434.787227 -290.246129)
			(xy 434.77942 -290.2458) (xy 434.263546 -290.2458) (xy 434.258126 -290.245394) (xy 434.25044 -290.237755)
			(xy 434.250084 -290.232338) (xy 428.2059 -290.232338) (xy 428.205407 -290.237638) (xy 428.197981 -290.245204)
			(xy 428.192692 -290.2458) (xy 427.676818 -290.2458) (xy 427.669009 -290.246121) (xy 427.654137 -290.250902)
			(xy 427.647608 -290.255198) (xy 427.626477 -290.269534) (xy 427.580757 -290.292265) (xy 427.532087 -290.307699)
			(xy 427.481622 -290.315469) (xy 427.456092 -290.315904) (xy 427.430562 -290.315464) (xy 427.380099 -290.307688)
			(xy 427.331426 -290.29226) (xy 427.285698 -290.269545) (xy 427.264576 -290.255198) (xy 427.258049 -290.250899)
			(xy 427.243176 -290.246121) (xy 427.235366 -290.2458) (xy 426.719492 -290.2458) (xy 426.714226 -290.24531)
			(xy 426.706784 -290.237858) (xy 426.706284 -290.232592) (xy 420.662075 -290.232592) (xy 420.661579 -290.237697)
			(xy 420.653997 -290.245279) (xy 420.648638 -290.2458) (xy 420.132764 -290.2458) (xy 420.124956 -290.246141)
			(xy 420.110085 -290.250908) (xy 420.103554 -290.255198) (xy 420.082439 -290.269557) (xy 420.036713 -290.292283)
			(xy 419.988038 -290.307711) (xy 419.93757 -290.315473) (xy 419.912038 -290.315904) (xy 419.886509 -290.315441)
			(xy 419.836046 -290.307672) (xy 419.787374 -290.29225) (xy 419.741645 -290.269542) (xy 419.720522 -290.255198)
			(xy 419.713985 -290.250916) (xy 419.699119 -290.246127) (xy 419.691312 -290.2458) (xy 419.175438 -290.2458)
			(xy 419.170088 -290.245228) (xy 419.162502 -290.237685) (xy 419.161976 -290.232338) (xy 413.117792 -290.232338)
			(xy 413.117306 -290.237639) (xy 413.109875 -290.245206) (xy 413.104584 -290.2458) (xy 411.631384 -290.2458)
			(xy 411.626117 -290.245315) (xy 411.618675 -290.23786) (xy 411.618176 -290.232592) (xy 363.60574 -290.232592)
			(xy 363.606492 -290.23556) (xy 363.610663 -290.2859) (xy 363.606492 -290.33624) (xy 363.594093 -290.385206)
			(xy 363.573804 -290.431465) (xy 363.546178 -290.473753) (xy 363.511969 -290.510918) (xy 363.47211 -290.541946)
			(xy 363.427688 -290.565991) (xy 363.379914 -290.582396) (xy 363.330092 -290.590716) (xy 363.304836 -290.59124)
			(xy 362.364782 -290.59124) (xy 362.33953 -290.590653) (xy 362.289716 -290.582338) (xy 362.24195 -290.565937)
			(xy 362.197534 -290.541898) (xy 362.157681 -290.510877) (xy 362.123477 -290.47372) (xy 362.095855 -290.431439)
			(xy 362.075569 -290.385189) (xy 362.063171 -290.336231) (xy 362.059001 -290.2859) (xy 357.976963 -290.2859)
			(xy 357.972792 -290.336242) (xy 357.960392 -290.38521) (xy 357.940101 -290.43147) (xy 357.912473 -290.47376)
			(xy 357.878262 -290.510925) (xy 357.8384 -290.541953) (xy 357.793975 -290.565996) (xy 357.746198 -290.5824)
			(xy 357.696373 -290.590717) (xy 357.671116 -290.59124) (xy 356.731062 -290.59124) (xy 356.705811 -290.590652)
			(xy 356.656 -290.582334) (xy 356.608236 -290.565931) (xy 356.563824 -290.541892) (xy 356.523973 -290.51087)
			(xy 356.489772 -290.473713) (xy 356.462152 -290.431434) (xy 356.441867 -290.385185) (xy 356.429471 -290.336229)
			(xy 356.425301 -290.2859) (xy 295.861558 -290.2859) (xy 295.848741 -290.292272) (xy 295.800069 -290.307703)
			(xy 295.749603 -290.315471) (xy 295.724072 -290.315904) (xy 295.698542 -290.315474) (xy 295.648078 -290.307695)
			(xy 295.599406 -290.292264) (xy 295.553678 -290.269546) (xy 295.532556 -290.255198) (xy 295.526034 -290.250891)
			(xy 295.511157 -290.246118) (xy 295.503346 -290.2458) (xy 294.987472 -290.2458) (xy 294.982204 -290.245323)
			(xy 294.974762 -290.237861) (xy 294.974264 -290.232592) (xy 288.930056 -290.232592) (xy 288.929576 -290.237702)
			(xy 288.921983 -290.245284) (xy 288.916618 -290.2458) (xy 288.400744 -290.2458) (xy 288.392936 -290.246132)
			(xy 288.378064 -290.250905) (xy 288.371534 -290.255198) (xy 288.350424 -290.269566) (xy 288.304697 -290.29229)
			(xy 288.25602 -290.307715) (xy 288.20555 -290.315475) (xy 288.180018 -290.315904) (xy 288.154488 -290.315451)
			(xy 288.104026 -290.307679) (xy 288.055353 -290.292255) (xy 288.009625 -290.269543) (xy 287.988502 -290.255198)
			(xy 287.981969 -290.250909) (xy 287.9671 -290.246124) (xy 287.959292 -290.2458) (xy 287.443418 -290.2458)
			(xy 287.438065 -290.245242) (xy 287.430481 -290.237689) (xy 287.429956 -290.232338) (xy 281.385772 -290.232338)
			(xy 281.385303 -290.237644) (xy 281.377861 -290.245212) (xy 281.372564 -290.2458) (xy 280.85669 -290.2458)
			(xy 280.84888 -290.246109) (xy 280.834008 -290.250898) (xy 280.82748 -290.255198) (xy 280.806357 -290.269546)
			(xy 280.760634 -290.292274) (xy 280.711961 -290.307705) (xy 280.661495 -290.315471) (xy 280.635964 -290.315904)
			(xy 280.610433 -290.315478) (xy 280.559969 -290.307698) (xy 280.511297 -290.292265) (xy 280.46557 -290.269546)
			(xy 280.444448 -290.255198) (xy 280.437927 -290.250888) (xy 280.423049 -290.246117) (xy 280.415238 -290.2458)
			(xy 279.899364 -290.2458) (xy 279.894095 -290.245328) (xy 279.886654 -290.237863) (xy 279.886156 -290.232592)
			(xy 273.84195 -290.232592) (xy 273.841503 -290.237644) (xy 273.834061 -290.245212) (xy 273.828764 -290.2458)
			(xy 273.31289 -290.2458) (xy 273.30508 -290.246109) (xy 273.290208 -290.250898) (xy 273.28368 -290.255198)
			(xy 273.262557 -290.269546) (xy 273.216834 -290.292274) (xy 273.168161 -290.307705) (xy 273.117695 -290.315471)
			(xy 273.092164 -290.315904) (xy 273.066633 -290.315478) (xy 273.016169 -290.307698) (xy 272.967497 -290.292265)
			(xy 272.92177 -290.269546) (xy 272.900648 -290.255198) (xy 272.894127 -290.250888) (xy 272.879249 -290.246117)
			(xy 272.871438 -290.2458) (xy 272.355564 -290.2458) (xy 272.350295 -290.245328) (xy 272.342854 -290.237863)
			(xy 272.342356 -290.232592) (xy 266.298149 -290.232592) (xy 266.297676 -290.237704) (xy 266.290077 -290.245287)
			(xy 266.28471 -290.2458) (xy 265.768836 -290.2458) (xy 265.761027 -290.246129) (xy 265.746156 -290.250904)
			(xy 265.739626 -290.255198) (xy 265.71849 -290.269526) (xy 265.672772 -290.292259) (xy 265.624103 -290.307695)
			(xy 265.57364 -290.315468) (xy 265.54811 -290.315904) (xy 265.52258 -290.315455) (xy 265.472117 -290.307682)
			(xy 265.423445 -290.292256) (xy 265.377717 -290.269543) (xy 265.356594 -290.255198) (xy 265.350063 -290.250905)
			(xy 265.335193 -290.246123) (xy 265.327384 -290.2458) (xy 264.81151 -290.2458) (xy 264.806156 -290.245247)
			(xy 264.798572 -290.23769) (xy 264.798048 -290.232338) (xy 202.89774 -290.232338) (xy 202.89774 -290.232592)
			(xy 202.897203 -290.237846) (xy 202.889785 -290.245287) (xy 202.884532 -290.2458) (xy 202.368658 -290.2458)
			(xy 202.360783 -290.246086) (xy 202.34578 -290.250872) (xy 202.339194 -290.255198) (xy 202.318105 -290.269571)
			(xy 202.272465 -290.292405) (xy 202.223862 -290.307968) (xy 202.173448 -290.315892) (xy 202.147932 -290.316412)
			(xy 202.122412 -290.315921) (xy 202.071985 -290.308027) (xy 202.023374 -290.292467) (xy 201.977735 -290.269613)
			(xy 201.95667 -290.255198) (xy 201.950087 -290.250868) (xy 201.93508 -290.246091) (xy 201.927206 -290.2458)
			(xy 201.411332 -290.2458) (xy 201.406002 -290.245451) (xy 201.398459 -290.237921) (xy 201.398124 -290.232592)
			(xy 195.35394 -290.232592) (xy 195.353403 -290.237846) (xy 195.345985 -290.245287) (xy 195.340732 -290.2458)
			(xy 194.824858 -290.2458) (xy 194.816983 -290.246086) (xy 194.80198 -290.250872) (xy 194.795394 -290.255198)
			(xy 194.774305 -290.269571) (xy 194.728665 -290.292405) (xy 194.680062 -290.307968) (xy 194.629648 -290.315892)
			(xy 194.604132 -290.316412) (xy 194.578612 -290.315921) (xy 194.528185 -290.308027) (xy 194.479574 -290.292467)
			(xy 194.433935 -290.269613) (xy 194.41287 -290.255198) (xy 194.406287 -290.250868) (xy 194.39128 -290.246091)
			(xy 194.383406 -290.2458) (xy 193.867532 -290.2458) (xy 193.862202 -290.245451) (xy 193.854659 -290.237921)
			(xy 193.854324 -290.232592) (xy 187.81014 -290.232592) (xy 187.809603 -290.237846) (xy 187.802185 -290.245287)
			(xy 187.796932 -290.2458) (xy 187.796424 -290.2458) (xy 187.280804 -290.2458) (xy 187.272931 -290.246105)
			(xy 187.257927 -290.250878) (xy 187.25134 -290.255198) (xy 187.230266 -290.269594) (xy 187.18462 -290.292423)
			(xy 187.136013 -290.30798) (xy 187.085595 -290.315897) (xy 187.060078 -290.316412) (xy 187.034559 -290.315898)
			(xy 186.984133 -290.308011) (xy 186.935521 -290.292458) (xy 186.889882 -290.26961) (xy 186.868816 -290.255198)
			(xy 186.862223 -290.250886) (xy 186.847224 -290.246097) (xy 186.839352 -290.2458) (xy 186.323478 -290.2458)
			(xy 186.318181 -290.245296) (xy 186.310613 -290.237879) (xy 186.310016 -290.232592) (xy 180.265832 -290.232592)
			(xy 180.265303 -290.237848) (xy 180.257879 -290.24529) (xy 180.252624 -290.2458) (xy 179.73675 -290.2458)
			(xy 179.728875 -290.246082) (xy 179.713872 -290.250871) (xy 179.707286 -290.255198) (xy 179.686199 -290.269575)
			(xy 179.640558 -290.292408) (xy 179.591955 -290.30797) (xy 179.54154 -290.315893) (xy 179.516024 -290.316412)
			(xy 179.490504 -290.315925) (xy 179.440077 -290.308029) (xy 179.391465 -290.292469) (xy 179.345827 -290.269613)
			(xy 179.324762 -290.255198) (xy 179.318181 -290.250865) (xy 179.303173 -290.246089) (xy 179.295298 -290.2458)
			(xy 178.779424 -290.2458) (xy 178.774093 -290.245456) (xy 178.76655 -290.237923) (xy 178.766216 -290.232592)
			(xy 172.722032 -290.232592) (xy 172.721503 -290.237848) (xy 172.714079 -290.24529) (xy 172.708824 -290.2458)
			(xy 172.708316 -290.2458) (xy 172.192696 -290.2458) (xy 172.184823 -290.246102) (xy 172.169819 -290.250877)
			(xy 172.163232 -290.255198) (xy 172.14216 -290.269598) (xy 172.096514 -290.292426) (xy 172.047906 -290.307982)
			(xy 171.997487 -290.315897) (xy 171.97197 -290.316412) (xy 171.946451 -290.315902) (xy 171.896025 -290.308013)
			(xy 171.847413 -290.292459) (xy 171.801774 -290.26961) (xy 171.780708 -290.255198) (xy 171.774117 -290.250883)
			(xy 171.759116 -290.246096) (xy 171.751244 -290.2458) (xy 171.23537 -290.2458) (xy 171.230071 -290.245302)
			(xy 171.222504 -290.23788) (xy 171.221908 -290.232592) (xy 165.177724 -290.232592) (xy 165.177202 -290.23785)
			(xy 165.169773 -290.245292) (xy 165.164516 -290.2458) (xy 163.691316 -290.2458) (xy 163.685984 -290.245462)
			(xy 163.678442 -290.237924) (xy 163.678108 -290.232592) (xy 115.665909 -290.232592) (xy 115.666725 -290.235814)
			(xy 115.670901 -290.2862) (xy 115.666725 -290.336586) (xy 115.654313 -290.385597) (xy 115.634003 -290.431897)
			(xy 115.606348 -290.474221) (xy 115.572104 -290.511417) (xy 115.532204 -290.542468) (xy 115.487738 -290.566528)
			(xy 115.439917 -290.582941) (xy 115.390047 -290.591258) (xy 115.364768 -290.591748) (xy 114.424714 -290.591748)
			(xy 114.399433 -290.591284) (xy 114.349561 -290.582964) (xy 114.301739 -290.566548) (xy 114.257271 -290.542485)
			(xy 114.21737 -290.511431) (xy 114.183125 -290.474233) (xy 114.15547 -290.431905) (xy 114.135159 -290.385603)
			(xy 114.122747 -290.336589) (xy 114.118571 -290.2862) (xy 110.037072 -290.2862) (xy 110.032898 -290.336573)
			(xy 110.020491 -290.385572) (xy 110.000189 -290.431861) (xy 109.972546 -290.474177) (xy 109.938315 -290.511367)
			(xy 109.898431 -290.542416) (xy 109.85398 -290.566478) (xy 109.806175 -290.582896) (xy 109.756321 -290.591222)
			(xy 109.731048 -290.591748) (xy 108.790994 -290.591748) (xy 108.765717 -290.591254) (xy 108.715852 -290.582932)
			(xy 108.668037 -290.566516) (xy 108.623576 -290.542454) (xy 108.583682 -290.511403) (xy 108.549443 -290.474208)
			(xy 108.521793 -290.431886) (xy 108.501485 -290.385589) (xy 108.489075 -290.336582) (xy 108.4849 -290.2862)
			(xy 47.920966 -290.2862) (xy 47.908542 -290.292415) (xy 47.859937 -290.307974) (xy 47.80952 -290.315895)
			(xy 47.784004 -290.316412) (xy 47.758483 -290.315935) (xy 47.708056 -290.308036) (xy 47.659444 -290.292473)
			(xy 47.613807 -290.269615) (xy 47.592742 -290.255198) (xy 47.586165 -290.250857) (xy 47.571154 -290.246087)
			(xy 47.563278 -290.2458) (xy 47.047404 -290.2458) (xy 47.04207 -290.24547) (xy 47.034529 -290.237926)
			(xy 47.034196 -290.232592) (xy 40.990012 -290.232592) (xy 40.989668 -290.237922) (xy 40.982134 -290.245463)
			(xy 40.976804 -290.2458) (xy 40.976296 -290.2458) (xy 40.460676 -290.2458) (xy 40.452802 -290.246093)
			(xy 40.437798 -290.250874) (xy 40.431212 -290.255198) (xy 40.410146 -290.269607) (xy 40.364497 -290.292432)
			(xy 40.315888 -290.307986) (xy 40.265468 -290.315899) (xy 40.23995 -290.316412) (xy 40.21443 -290.315912)
			(xy 40.164004 -290.30802) (xy 40.115392 -290.292463) (xy 40.069753 -290.269612) (xy 40.048688 -290.255198)
			(xy 40.042101 -290.250875) (xy 40.027097 -290.246093) (xy 40.019224 -290.2458) (xy 39.50335 -290.2458)
			(xy 39.498061 -290.245248) (xy 39.49049 -290.237867) (xy 39.489888 -290.232592) (xy 33.445704 -290.232592)
			(xy 33.445368 -290.237924) (xy 33.437828 -290.245466) (xy 33.432496 -290.2458) (xy 32.916622 -290.2458)
			(xy 32.90875 -290.246113) (xy 32.893746 -290.25088) (xy 32.887158 -290.255198) (xy 32.866079 -290.269587)
			(xy 32.820435 -290.292417) (xy 32.771829 -290.307976) (xy 32.721413 -290.315895) (xy 32.695896 -290.316412)
			(xy 32.670375 -290.315939) (xy 32.619948 -290.308039) (xy 32.571336 -290.292474) (xy 32.525698 -290.269615)
			(xy 32.504634 -290.255198) (xy 32.498037 -290.250893) (xy 32.483041 -290.2461) (xy 32.47517 -290.2458)
			(xy 31.959296 -290.2458) (xy 31.953961 -290.245475) (xy 31.94642 -290.237927) (xy 31.946088 -290.232592)
			(xy 25.901904 -290.232592) (xy 25.901568 -290.237924) (xy 25.894028 -290.245466) (xy 25.888696 -290.2458)
			(xy 25.372822 -290.2458) (xy 25.36495 -290.246113) (xy 25.349946 -290.25088) (xy 25.343358 -290.255198)
			(xy 25.322279 -290.269587) (xy 25.276635 -290.292417) (xy 25.228029 -290.307976) (xy 25.177613 -290.315895)
			(xy 25.152096 -290.316412) (xy 25.126575 -290.315939) (xy 25.076148 -290.308039) (xy 25.027536 -290.292474)
			(xy 24.981898 -290.269615) (xy 24.960834 -290.255198) (xy 24.954237 -290.250893) (xy 24.939241 -290.2461)
			(xy 24.93137 -290.2458) (xy 24.415496 -290.2458) (xy 24.410161 -290.245475) (xy 24.40262 -290.237927)
			(xy 24.402288 -290.232592) (xy 18.358104 -290.232592) (xy 18.357768 -290.237924) (xy 18.350228 -290.245466)
			(xy 18.344896 -290.2458) (xy 18.344388 -290.2458) (xy 17.828768 -290.2458) (xy 17.820894 -290.24609)
			(xy 17.80589 -290.250873) (xy 17.799304 -290.255198) (xy 17.778212 -290.269567) (xy 17.732573 -290.292402)
			(xy 17.683971 -290.307966) (xy 17.633557 -290.315892) (xy 17.608042 -290.316412) (xy 17.582522 -290.315916)
			(xy 17.532096 -290.308023) (xy 17.483484 -290.292465) (xy 17.437845 -290.269612) (xy 17.41678 -290.255198)
			(xy 17.410195 -290.250872) (xy 17.39519 -290.246092) (xy 17.387316 -290.2458) (xy 16.871442 -290.2458)
			(xy 16.866152 -290.245253) (xy 16.858581 -290.237868) (xy 16.85798 -290.232592) (xy 2.509012 -290.232592)
			(xy 2.509012 -291.082476) (xy 20.958048 -291.082476) (xy 20.958048 -290.587938) (xy 20.958406 -290.582506)
			(xy 20.966079 -290.574817) (xy 20.97151 -290.574476) (xy 21.487638 -290.574476) (xy 21.495446 -290.57414)
			(xy 21.510318 -290.56937) (xy 21.516848 -290.565078) (xy 21.537937 -290.550729) (xy 21.583598 -290.527998)
			(xy 21.632204 -290.512539) (xy 21.682607 -290.504716) (xy 21.733613 -290.504716) (xy 21.784016 -290.512539)
			(xy 21.832622 -290.527998) (xy 21.878283 -290.550729) (xy 21.899372 -290.565078) (xy 21.905912 -290.569355)
			(xy 21.920775 -290.574147) (xy 21.928582 -290.574476) (xy 22.44471 -290.574476) (xy 22.450155 -290.574776)
			(xy 22.457843 -290.582491) (xy 22.458172 -290.587938) (xy 22.458172 -291.082476) (xy 28.502356 -291.082476)
			(xy 28.502356 -290.587938) (xy 28.50285 -290.582635) (xy 28.510272 -290.575061) (xy 28.515564 -290.574476)
			(xy 29.031692 -290.574476) (xy 29.039502 -290.574163) (xy 29.054374 -290.569377) (xy 29.060902 -290.565078)
			(xy 29.081991 -290.550729) (xy 29.127652 -290.527998) (xy 29.176258 -290.512539) (xy 29.226661 -290.504716)
			(xy 29.277667 -290.504716) (xy 29.32807 -290.512539) (xy 29.376676 -290.527998) (xy 29.422337 -290.550729)
			(xy 29.443426 -290.565078) (xy 29.449954 -290.569376) (xy 29.464827 -290.574155) (xy 29.472636 -290.574476)
			(xy 29.988764 -290.574476) (xy 29.994088 -290.574849) (xy 30.00163 -290.582362) (xy 30.001972 -290.587684)
			(xy 30.001972 -290.588192) (xy 30.001972 -291.082476) (xy 36.046156 -291.082476) (xy 36.046156 -290.587938)
			(xy 36.04665 -290.582635) (xy 36.054072 -290.575061) (xy 36.059364 -290.574476) (xy 36.575492 -290.574476)
			(xy 36.583302 -290.574163) (xy 36.598174 -290.569377) (xy 36.604702 -290.565078) (xy 36.625791 -290.550729)
			(xy 36.671452 -290.527998) (xy 36.720058 -290.512539) (xy 36.770461 -290.504716) (xy 36.821467 -290.504716)
			(xy 36.87187 -290.512539) (xy 36.920476 -290.527998) (xy 36.966137 -290.550729) (xy 36.987226 -290.565078)
			(xy 36.993754 -290.569376) (xy 37.008627 -290.574155) (xy 37.016436 -290.574476) (xy 37.532564 -290.574476)
			(xy 37.537888 -290.574849) (xy 37.54543 -290.582362) (xy 37.545772 -290.587684) (xy 37.545772 -290.588192)
			(xy 37.545772 -291.082476) (xy 43.589956 -291.082476) (xy 43.589956 -290.587938) (xy 43.590306 -290.582504)
			(xy 43.597984 -290.574814) (xy 43.603418 -290.574476) (xy 44.119546 -290.574476) (xy 44.127354 -290.574143)
			(xy 44.142226 -290.569371) (xy 44.148756 -290.565078) (xy 44.169845 -290.550729) (xy 44.215506 -290.527998)
			(xy 44.264112 -290.512539) (xy 44.314515 -290.504716) (xy 44.365521 -290.504716) (xy 44.415924 -290.512539)
			(xy 44.46453 -290.527998) (xy 44.510191 -290.550729) (xy 44.53128 -290.565078) (xy 44.537818 -290.569358)
			(xy 44.552683 -290.574148) (xy 44.56049 -290.574476) (xy 45.076618 -290.574476) (xy 45.082065 -290.574771)
			(xy 45.089752 -290.58249) (xy 45.09008 -290.587938) (xy 45.09008 -291.082476) (xy 51.134264 -291.082476)
			(xy 51.134264 -290.587938) (xy 51.134751 -290.582633) (xy 51.142177 -290.575058) (xy 51.147472 -290.574476)
			(xy 51.6636 -290.574476) (xy 51.671411 -290.574166) (xy 51.686282 -290.569378) (xy 51.69281 -290.565078)
			(xy 51.713899 -290.550729) (xy 51.75956 -290.527998) (xy 51.808166 -290.512539) (xy 51.858569 -290.504716)
			(xy 51.909575 -290.504716) (xy 51.959978 -290.512539) (xy 52.008584 -290.527998) (xy 52.054245 -290.550729)
			(xy 52.075334 -290.565078) (xy 52.08186 -290.569379) (xy 52.096734 -290.574156) (xy 52.104544 -290.574476)
			(xy 52.620672 -290.574476) (xy 52.625997 -290.574844) (xy 52.633538 -290.58236) (xy 52.63388 -290.587684)
			(xy 52.63388 -290.588192) (xy 52.63388 -291.082476) (xy 58.678064 -291.082476) (xy 58.678064 -290.587938)
			(xy 58.678407 -290.582502) (xy 58.68609 -290.574812) (xy 58.691526 -290.574476) (xy 60.164726 -290.574476)
			(xy 60.170174 -290.574765) (xy 60.17786 -290.582489) (xy 60.178188 -290.587938) (xy 60.178188 -291.082476)
			(xy 60.177855 -291.08781) (xy 60.170314 -291.095353) (xy 60.16498 -291.095684) (xy 60.164472 -291.095684)
			(xy 58.691526 -291.095684) (xy 58.686231 -291.095162) (xy 58.678659 -291.087759) (xy 58.678064 -291.082476)
			(xy 52.63388 -291.082476) (xy 52.633554 -291.087812) (xy 52.626008 -291.095356) (xy 52.620672 -291.095684)
			(xy 52.104798 -291.095684) (xy 52.096923 -291.095973) (xy 52.096211 -291.0962) (xy 97.675132 -291.0962)
			(xy 97.679304 -291.045855) (xy 97.691705 -290.996883) (xy 97.711998 -290.950621) (xy 97.739629 -290.908329)
			(xy 97.773844 -290.871163) (xy 97.81371 -290.840135) (xy 97.85814 -290.816092) (xy 97.90592 -290.79969)
			(xy 97.955749 -290.791376) (xy 97.981008 -290.790884) (xy 98.921062 -290.790884) (xy 98.946321 -290.79139)
			(xy 98.996151 -290.799699) (xy 99.043934 -290.816098) (xy 99.088365 -290.840138) (xy 99.128233 -290.871164)
			(xy 99.16245 -290.908329) (xy 99.190083 -290.95062) (xy 99.210377 -290.996882) (xy 99.22278 -291.045854)
			(xy 99.226952 -291.0962) (xy 100.495361 -291.0962) (xy 100.499532 -291.045864) (xy 100.51193 -290.9969)
			(xy 100.532218 -290.950645) (xy 100.559842 -290.90836) (xy 100.594049 -290.871198) (xy 100.633906 -290.840172)
			(xy 100.678326 -290.81613) (xy 100.726096 -290.799726) (xy 100.775916 -290.791408) (xy 100.80117 -290.790884)
			(xy 101.741224 -290.790884) (xy 101.766477 -290.791423) (xy 101.816295 -290.79974) (xy 101.864064 -290.816143)
			(xy 101.908482 -290.840184) (xy 101.948338 -290.871207) (xy 101.982544 -290.908368) (xy 102.010167 -290.950651)
			(xy 102.030454 -290.996904) (xy 102.042852 -291.045866) (xy 102.047023 -291.0962) (xy 103.315261 -291.0962)
			(xy 103.319432 -291.045863) (xy 103.331831 -290.996899) (xy 103.352119 -290.950643) (xy 103.379744 -290.908357)
			(xy 103.413952 -290.871195) (xy 103.45381 -290.840169) (xy 103.498231 -290.816127) (xy 103.546003 -290.799724)
			(xy 103.595823 -290.791407) (xy 103.621078 -290.790884) (xy 104.561132 -290.790884) (xy 104.586385 -290.791424)
			(xy 104.636201 -290.799742) (xy 104.683969 -290.816145) (xy 104.728386 -290.840186) (xy 104.768241 -290.87121)
			(xy 104.802446 -290.90837) (xy 104.830068 -290.950653) (xy 104.850355 -290.996906) (xy 104.862753 -291.045867)
			(xy 104.866923 -291.0962) (xy 106.135161 -291.0962) (xy 106.139332 -291.045862) (xy 106.151731 -290.996897)
			(xy 106.172021 -290.950641) (xy 106.199646 -290.908354) (xy 106.233855 -290.871192) (xy 106.273715 -290.840167)
			(xy 106.318136 -290.816125) (xy 106.36591 -290.799722) (xy 106.415731 -290.791407) (xy 106.440986 -290.790884)
			(xy 107.38104 -290.790884) (xy 107.406292 -290.791425) (xy 107.456108 -290.799743) (xy 107.503875 -290.816147)
			(xy 107.548291 -290.840189) (xy 107.588144 -290.871213) (xy 107.622348 -290.908373) (xy 107.649969 -290.950655)
			(xy 107.670255 -290.996907) (xy 107.682653 -291.045867) (xy 107.686823 -291.0962) (xy 116.468832 -291.0962)
			(xy 116.473004 -291.045853) (xy 116.485406 -290.99688) (xy 116.5057 -290.950617) (xy 116.533333 -290.908325)
			(xy 116.56755 -290.871158) (xy 116.607418 -290.84013) (xy 116.651849 -290.816088) (xy 116.699632 -290.799687)
			(xy 116.749462 -290.791375) (xy 116.774722 -290.790884) (xy 117.714776 -290.790884) (xy 117.740034 -290.791391)
			(xy 117.789863 -290.799702) (xy 117.837643 -290.816102) (xy 117.882072 -290.840143) (xy 117.921939 -290.871169)
			(xy 117.956154 -290.908334) (xy 117.983785 -290.950624) (xy 118.004078 -290.996885) (xy 118.01648 -291.045856)
			(xy 118.020652 -291.0962) (xy 119.288732 -291.0962) (xy 119.292904 -291.045853) (xy 119.305307 -290.996879)
			(xy 119.325602 -290.950615) (xy 119.353235 -290.908322) (xy 119.387453 -290.871155) (xy 119.427322 -290.840127)
			(xy 119.471755 -290.816085) (xy 119.519538 -290.799685) (xy 119.56937 -290.791374) (xy 119.59463 -290.790884)
			(xy 120.534684 -290.790884) (xy 120.559942 -290.791391) (xy 120.609769 -290.799704) (xy 120.657549 -290.816104)
			(xy 120.701977 -290.840145) (xy 120.741842 -290.871172) (xy 120.776056 -290.908336) (xy 120.803686 -290.950626)
			(xy 120.823979 -290.996887) (xy 120.83638 -291.045857) (xy 120.840552 -291.0962) (xy 122.108961 -291.0962)
			(xy 122.113132 -291.045861) (xy 122.125532 -290.996896) (xy 122.145821 -290.950639) (xy 122.173448 -290.908352)
			(xy 122.207658 -290.87119) (xy 122.247518 -290.840165) (xy 122.29194 -290.816123) (xy 122.339714 -290.799721)
			(xy 122.389536 -290.791406) (xy 122.414792 -290.790884) (xy 123.354846 -290.790884) (xy 123.380098 -290.791425)
			(xy 123.429913 -290.799745) (xy 123.477679 -290.816149) (xy 123.522094 -290.840191) (xy 123.561946 -290.871215)
			(xy 123.596149 -290.908375) (xy 123.62377 -290.950657) (xy 123.644056 -290.996909) (xy 123.656453 -291.045868)
			(xy 123.660623 -291.0962) (xy 124.928861 -291.0962) (xy 124.933032 -291.045861) (xy 124.945432 -290.996894)
			(xy 124.965723 -290.950637) (xy 124.99335 -290.90835) (xy 125.027561 -290.871187) (xy 125.067422 -290.840162)
			(xy 125.111846 -290.816121) (xy 125.159621 -290.79972) (xy 125.209444 -290.791406) (xy 125.2347 -290.790884)
			(xy 126.174754 -290.790884) (xy 126.200014 -290.791389) (xy 126.249845 -290.799697) (xy 126.297628 -290.816095)
			(xy 126.342061 -290.840135) (xy 126.38193 -290.871161) (xy 126.416148 -290.908327) (xy 126.443782 -290.950618)
			(xy 126.464077 -290.996881) (xy 126.47648 -291.045854) (xy 126.479515 -291.082476) (xy 167.778176 -291.082476)
			(xy 167.778176 -290.587938) (xy 167.778653 -290.58263) (xy 167.786086 -290.575055) (xy 167.791384 -290.574476)
			(xy 169.264584 -290.574476) (xy 169.269841 -290.575004) (xy 169.277284 -290.582428) (xy 169.277792 -290.587684)
			(xy 169.277792 -291.082476) (xy 175.321976 -291.082476) (xy 175.321976 -290.587938) (xy 175.322308 -290.582499)
			(xy 175.329999 -290.574808) (xy 175.335438 -290.574476) (xy 175.851566 -290.574476) (xy 175.859375 -290.574152)
			(xy 175.874247 -290.569374) (xy 175.880776 -290.565078) (xy 175.901865 -290.550729) (xy 175.947526 -290.527998)
			(xy 175.996132 -290.512539) (xy 176.046535 -290.504716) (xy 176.097541 -290.504716) (xy 176.147944 -290.512539)
			(xy 176.19655 -290.527998) (xy 176.242211 -290.550729) (xy 176.2633 -290.565078) (xy 176.269834 -290.569366)
			(xy 176.284702 -290.574151) (xy 176.29251 -290.574476) (xy 176.808638 -290.574476) (xy 176.814016 -290.574929)
			(xy 176.821601 -290.582558) (xy 176.8221 -290.587938) (xy 176.8221 -291.082476) (xy 182.866284 -291.082476)
			(xy 182.866284 -290.587938) (xy 182.866754 -290.582628) (xy 182.874192 -290.575052) (xy 182.879492 -290.574476)
			(xy 183.39562 -290.574476) (xy 183.403431 -290.574175) (xy 183.418303 -290.569381) (xy 183.42483 -290.565078)
			(xy 183.445919 -290.550729) (xy 183.49158 -290.527998) (xy 183.540186 -290.512539) (xy 183.590589 -290.504716)
			(xy 183.641595 -290.504716) (xy 183.691998 -290.512539) (xy 183.740604 -290.527998) (xy 183.786265 -290.550729)
			(xy 183.807354 -290.565078) (xy 183.813876 -290.569386) (xy 183.828753 -290.574159) (xy 183.836564 -290.574476)
			(xy 184.352692 -290.574476) (xy 184.35795 -290.574998) (xy 184.365392 -290.582427) (xy 184.3659 -290.587684)
			(xy 184.3659 -290.588192) (xy 184.3659 -291.082476) (xy 190.410084 -291.082476) (xy 190.410084 -290.587938)
			(xy 190.410409 -290.582497) (xy 190.418105 -290.574806) (xy 190.423546 -290.574476) (xy 190.939674 -290.574476)
			(xy 190.947484 -290.574156) (xy 190.962355 -290.569375) (xy 190.968884 -290.565078) (xy 190.989973 -290.550729)
			(xy 191.035634 -290.527998) (xy 191.08424 -290.512539) (xy 191.134643 -290.504716) (xy 191.185649 -290.504716)
			(xy 191.236052 -290.512539) (xy 191.284658 -290.527998) (xy 191.330319 -290.550729) (xy 191.351408 -290.565078)
			(xy 191.35794 -290.569369) (xy 191.37281 -290.574152) (xy 191.380618 -290.574476) (xy 191.896746 -290.574476)
			(xy 191.902125 -290.574924) (xy 191.90971 -290.582556) (xy 191.910208 -290.587938) (xy 191.910208 -291.082476)
			(xy 197.954392 -291.082476) (xy 197.954392 -290.587938) (xy 197.954943 -290.58265) (xy 197.962325 -290.575079)
			(xy 197.9676 -290.574476) (xy 198.483728 -290.574476) (xy 198.49154 -290.574178) (xy 198.506411 -290.569382)
			(xy 198.512938 -290.565078) (xy 198.534027 -290.550729) (xy 198.579688 -290.527998) (xy 198.628294 -290.512539)
			(xy 198.678697 -290.504716) (xy 198.729703 -290.504716) (xy 198.780106 -290.512539) (xy 198.828712 -290.527998)
			(xy 198.874373 -290.550729) (xy 198.895462 -290.565078) (xy 198.902004 -290.569351) (xy 198.916866 -290.574146)
			(xy 198.924672 -290.574476) (xy 199.4408 -290.574476) (xy 199.446059 -290.574993) (xy 199.4535 -290.582426)
			(xy 199.454008 -290.587684) (xy 199.454008 -290.588192) (xy 199.454008 -291.082476) (xy 205.498192 -291.082476)
			(xy 205.498192 -290.587938) (xy 205.498743 -290.58265) (xy 205.506125 -290.575079) (xy 205.5114 -290.574476)
			(xy 206.027528 -290.574476) (xy 206.03534 -290.574178) (xy 206.050211 -290.569382) (xy 206.056738 -290.565078)
			(xy 206.077827 -290.550729) (xy 206.123488 -290.527998) (xy 206.172094 -290.512539) (xy 206.222497 -290.504716)
			(xy 206.273503 -290.504716) (xy 206.323906 -290.512539) (xy 206.372512 -290.527998) (xy 206.418173 -290.550729)
			(xy 206.439262 -290.565078) (xy 206.445804 -290.569351) (xy 206.460666 -290.574146) (xy 206.468472 -290.574476)
			(xy 206.9846 -290.574476) (xy 206.989859 -290.574993) (xy 206.9973 -290.582426) (xy 206.997808 -290.587684)
			(xy 206.997808 -290.588192) (xy 206.997808 -291.082222) (xy 268.898116 -291.082222) (xy 268.898116 -290.587684)
			(xy 268.898418 -290.582344) (xy 268.905983 -290.574802) (xy 268.911324 -290.574476) (xy 268.911832 -290.574476)
			(xy 269.427706 -290.574476) (xy 269.435517 -290.574169) (xy 269.450388 -290.569379) (xy 269.456916 -290.565078)
			(xy 269.478005 -290.550729) (xy 269.523666 -290.527998) (xy 269.572272 -290.512539) (xy 269.622675 -290.504716)
			(xy 269.673681 -290.504716) (xy 269.724084 -290.512539) (xy 269.77269 -290.527998) (xy 269.818351 -290.550729)
			(xy 269.83944 -290.565078) (xy 269.845965 -290.569381) (xy 269.86084 -290.574157) (xy 269.86865 -290.574476)
			(xy 270.384778 -290.574476) (xy 270.390088 -290.574942) (xy 270.397662 -290.582384) (xy 270.39824 -290.587684)
			(xy 270.39824 -291.082222) (xy 270.398217 -291.082476) (xy 276.442424 -291.082476) (xy 276.442424 -291.081968)
			(xy 276.442424 -290.587684) (xy 276.442719 -290.582342) (xy 276.450288 -290.5748) (xy 276.455632 -290.574476)
			(xy 276.97176 -290.574476) (xy 276.979569 -290.574149) (xy 276.99444 -290.569372) (xy 277.00097 -290.565078)
			(xy 277.022059 -290.550729) (xy 277.06772 -290.527998) (xy 277.116326 -290.512539) (xy 277.166729 -290.504716)
			(xy 277.217735 -290.504716) (xy 277.268138 -290.512539) (xy 277.316744 -290.527998) (xy 277.362405 -290.550729)
			(xy 277.383494 -290.565078) (xy 277.390029 -290.569363) (xy 277.404896 -290.57415) (xy 277.412704 -290.574476)
			(xy 277.928832 -290.574476) (xy 277.934095 -290.574972) (xy 277.941535 -290.582421) (xy 277.94204 -290.587684)
			(xy 277.94204 -291.082222) (xy 277.942018 -291.082476) (xy 283.986224 -291.082476) (xy 283.986224 -291.081968)
			(xy 283.986224 -290.587684) (xy 283.986519 -290.582342) (xy 283.994088 -290.5748) (xy 283.999432 -290.574476)
			(xy 284.51556 -290.574476) (xy 284.523369 -290.574149) (xy 284.53824 -290.569372) (xy 284.54477 -290.565078)
			(xy 284.565859 -290.550729) (xy 284.61152 -290.527998) (xy 284.660126 -290.512539) (xy 284.710529 -290.504716)
			(xy 284.761535 -290.504716) (xy 284.811938 -290.512539) (xy 284.860544 -290.527998) (xy 284.906205 -290.550729)
			(xy 284.927294 -290.565078) (xy 284.933829 -290.569363) (xy 284.948696 -290.57415) (xy 284.956504 -290.574476)
			(xy 285.472632 -290.574476) (xy 285.477895 -290.574972) (xy 285.485335 -290.582421) (xy 285.48584 -290.587684)
			(xy 285.48584 -291.082222) (xy 291.530024 -291.082222) (xy 291.530024 -290.587684) (xy 291.530319 -290.582342)
			(xy 291.537888 -290.5748) (xy 291.543232 -290.574476) (xy 291.54374 -290.574476) (xy 292.059614 -290.574476)
			(xy 292.067425 -290.574172) (xy 292.082297 -290.56938) (xy 292.088824 -290.565078) (xy 292.109913 -290.550729)
			(xy 292.155574 -290.527998) (xy 292.20418 -290.512539) (xy 292.254583 -290.504716) (xy 292.305589 -290.504716)
			(xy 292.355992 -290.512539) (xy 292.404598 -290.527998) (xy 292.450259 -290.550729) (xy 292.471348 -290.565078)
			(xy 292.477871 -290.569384) (xy 292.492748 -290.574158) (xy 292.500558 -290.574476) (xy 293.016686 -290.574476)
			(xy 293.021997 -290.574937) (xy 293.029571 -290.582382) (xy 293.030148 -290.587684) (xy 293.030148 -291.082222)
			(xy 293.030125 -291.082476) (xy 299.074332 -291.082476) (xy 299.074332 -291.081968) (xy 299.074332 -290.587684)
			(xy 299.07462 -290.58234) (xy 299.082194 -290.574797) (xy 299.08754 -290.574476) (xy 299.603668 -290.574476)
			(xy 299.611477 -290.574153) (xy 299.626349 -290.569374) (xy 299.632878 -290.565078) (xy 299.653967 -290.550729)
			(xy 299.699628 -290.527998) (xy 299.748234 -290.512539) (xy 299.798637 -290.504716) (xy 299.849643 -290.504716)
			(xy 299.900046 -290.512539) (xy 299.948652 -290.527998) (xy 299.994313 -290.550729) (xy 300.015402 -290.565078)
			(xy 300.021935 -290.569366) (xy 300.036804 -290.574151) (xy 300.044612 -290.574476) (xy 300.56074 -290.574476)
			(xy 300.566004 -290.574966) (xy 300.573443 -290.582419) (xy 300.573948 -290.587684) (xy 300.573948 -291.082222)
			(xy 306.618132 -291.082222) (xy 306.618132 -290.587684) (xy 306.61842 -290.58234) (xy 306.625994 -290.574797)
			(xy 306.63134 -290.574476) (xy 306.631848 -290.574476) (xy 308.104794 -290.574476) (xy 308.110106 -290.574931)
			(xy 308.11768 -290.582381) (xy 308.118256 -290.587684) (xy 308.118256 -291.082222) (xy 308.117764 -291.08759)
			(xy 308.110163 -291.095175) (xy 308.104794 -291.095684) (xy 306.631594 -291.095684) (xy 306.626235 -291.095156)
			(xy 306.61865 -291.087581) (xy 306.618132 -291.082222) (xy 300.573948 -291.082222) (xy 300.57349 -291.087532)
			(xy 300.566041 -291.095102) (xy 300.56074 -291.095684) (xy 300.044866 -291.095684) (xy 300.039723 -291.0959)
			(xy 345.615052 -291.0959) (xy 345.619226 -291.045529) (xy 345.631633 -290.996531) (xy 345.651936 -290.950244)
			(xy 345.679579 -290.90793) (xy 345.71381 -290.870742) (xy 345.753695 -290.839696) (xy 345.798146 -290.815637)
			(xy 345.84595 -290.799222) (xy 345.895804 -290.7909) (xy 345.921076 -290.790376) (xy 346.86113 -290.790376)
			(xy 346.886408 -290.790824) (xy 346.936273 -290.79915) (xy 346.984089 -290.815569) (xy 347.02855 -290.839634)
			(xy 347.068443 -290.870688) (xy 347.102682 -290.907885) (xy 347.130332 -290.95021) (xy 347.150639 -290.996508)
			(xy 347.163049 -291.045517) (xy 347.167224 -291.0959) (xy 348.435123 -291.0959) (xy 348.439299 -291.045518)
			(xy 348.45171 -290.99651) (xy 348.472019 -290.950213) (xy 348.499672 -290.907891) (xy 348.533915 -290.870699)
			(xy 348.573812 -290.83965) (xy 348.618276 -290.815592) (xy 348.666094 -290.799181) (xy 348.71596 -290.790866)
			(xy 348.741238 -290.790376) (xy 349.681292 -290.790376) (xy 349.706574 -290.790793) (xy 349.756449 -290.799114)
			(xy 349.804275 -290.815531) (xy 349.848745 -290.839597) (xy 349.888648 -290.870653) (xy 349.922895 -290.907855)
			(xy 349.950552 -290.950185) (xy 349.970864 -290.996491) (xy 349.983277 -291.045508) (xy 349.987453 -291.0959)
			(xy 351.255023 -291.0959) (xy 351.259199 -291.045517) (xy 351.271611 -290.996508) (xy 351.291921 -290.950211)
			(xy 351.319575 -290.907889) (xy 351.353818 -290.870696) (xy 351.393716 -290.839647) (xy 351.438182 -290.81559)
			(xy 351.486 -290.79918) (xy 351.535868 -290.790865) (xy 351.561146 -290.790376) (xy 352.5012 -290.790376)
			(xy 352.526479 -290.790822) (xy 352.576349 -290.799144) (xy 352.624168 -290.81556) (xy 352.668634 -290.839624)
			(xy 352.708532 -290.870678) (xy 352.742774 -290.907875) (xy 352.770428 -290.950201) (xy 352.790737 -290.996502)
			(xy 352.803148 -291.045514) (xy 352.807324 -291.0959) (xy 354.075052 -291.0959) (xy 354.079226 -291.045531)
			(xy 354.091632 -290.996536) (xy 354.111932 -290.95025) (xy 354.139574 -290.907937) (xy 354.173802 -290.87075)
			(xy 354.213684 -290.839703) (xy 354.258131 -290.815644) (xy 354.305932 -290.799227) (xy 354.355783 -290.790901)
			(xy 354.381054 -290.790376) (xy 355.321108 -290.790376) (xy 355.346387 -290.790823) (xy 355.396255 -290.799145)
			(xy 355.444074 -290.815563) (xy 355.488538 -290.839626) (xy 355.528435 -290.87068) (xy 355.562677 -290.907878)
			(xy 355.590329 -290.950204) (xy 355.610637 -290.996503) (xy 355.623049 -291.045515) (xy 355.627224 -291.0959)
			(xy 364.408752 -291.0959) (xy 364.412926 -291.045527) (xy 364.425334 -290.996529) (xy 364.445638 -290.95024)
			(xy 364.473283 -290.907925) (xy 364.507516 -290.870737) (xy 364.547403 -290.839691) (xy 364.591855 -290.815633)
			(xy 364.639662 -290.79922) (xy 364.689517 -290.790899) (xy 364.71479 -290.790376) (xy 365.654844 -290.790376)
			(xy 365.680121 -290.790826) (xy 365.729985 -290.799153) (xy 365.777798 -290.815573) (xy 365.822257 -290.839639)
			(xy 365.862149 -290.870693) (xy 365.896386 -290.90789) (xy 365.924034 -290.950214) (xy 365.94434 -290.996511)
			(xy 365.956749 -291.045518) (xy 365.960924 -291.0959) (xy 367.228652 -291.0959) (xy 367.232827 -291.045526)
			(xy 367.245235 -290.996527) (xy 367.265539 -290.950238) (xy 367.293185 -290.907922) (xy 367.327419 -290.870734)
			(xy 367.367307 -290.839688) (xy 367.411761 -290.81563) (xy 367.459568 -290.799218) (xy 367.509425 -290.790898)
			(xy 367.534698 -290.790376) (xy 368.474752 -290.790376) (xy 368.500036 -290.790789) (xy 368.549917 -290.799106)
			(xy 368.597748 -290.815519) (xy 368.642224 -290.839583) (xy 368.682133 -290.870639) (xy 368.716385 -290.907841)
			(xy 368.744046 -290.950174) (xy 368.764361 -290.996483) (xy 368.776776 -291.045504) (xy 368.780953 -291.0959)
			(xy 370.048852 -291.0959) (xy 370.053026 -291.04553) (xy 370.065432 -290.996535) (xy 370.085733 -290.950249)
			(xy 370.113375 -290.907935) (xy 370.147604 -290.870748) (xy 370.187487 -290.839701) (xy 370.231935 -290.815642)
			(xy 370.279737 -290.799226) (xy 370.329589 -290.790901) (xy 370.35486 -290.790376) (xy 371.294914 -290.790376)
			(xy 371.320193 -290.790823) (xy 371.37006 -290.799147) (xy 371.417878 -290.815564) (xy 371.462341 -290.839629)
			(xy 371.502237 -290.870683) (xy 371.536478 -290.90788) (xy 371.56413 -290.950205) (xy 371.584438 -290.996505)
			(xy 371.596849 -291.045515) (xy 371.601024 -291.0959) (xy 372.868752 -291.0959) (xy 372.872926 -291.04553)
			(xy 372.885333 -290.996533) (xy 372.905634 -290.950246) (xy 372.933277 -290.907932) (xy 372.967507 -290.870745)
			(xy 373.007391 -290.839698) (xy 373.05184 -290.815639) (xy 373.099644 -290.799224) (xy 373.149497 -290.7909)
			(xy 373.174768 -290.790376) (xy 374.114822 -290.790376) (xy 374.1401 -290.790824) (xy 374.189967 -290.799148)
			(xy 374.237783 -290.815567) (xy 374.282245 -290.839631) (xy 374.32214 -290.870685) (xy 374.35638 -290.907882)
			(xy 374.384031 -290.950207) (xy 374.404338 -290.996506) (xy 374.416749 -291.045516) (xy 374.419812 -291.082476)
			(xy 415.718244 -291.082476) (xy 415.718244 -290.587684) (xy 415.718779 -290.582431) (xy 415.7262 -290.574992)
			(xy 415.731452 -290.574476) (xy 417.204652 -290.574476) (xy 417.209974 -290.574858) (xy 417.217517 -290.582364)
			(xy 417.21786 -290.587684) (xy 417.21786 -291.082222) (xy 423.262044 -291.082222) (xy 423.262044 -290.587684)
			(xy 423.262579 -290.582431) (xy 423.27 -290.574992) (xy 423.275252 -290.574476) (xy 423.27576 -290.574476)
			(xy 423.791634 -290.574476) (xy 423.799442 -290.574138) (xy 423.814314 -290.569369) (xy 423.820844 -290.565078)
			(xy 423.841933 -290.550729) (xy 423.887594 -290.527998) (xy 423.9362 -290.512539) (xy 423.986603 -290.504716)
			(xy 424.037609 -290.504716) (xy 424.088012 -290.512539) (xy 424.136618 -290.527998) (xy 424.182279 -290.550729)
			(xy 424.203368 -290.565078) (xy 424.209909 -290.569353) (xy 424.224772 -290.574146) (xy 424.232578 -290.574476)
			(xy 424.748706 -290.574476) (xy 424.754019 -290.574923) (xy 424.761592 -290.582379) (xy 424.762168 -290.587684)
			(xy 424.762168 -291.082222) (xy 424.762144 -291.082476) (xy 430.806352 -291.082476) (xy 430.806352 -291.081968)
			(xy 430.806352 -290.587684) (xy 430.80688 -290.582429) (xy 430.814306 -290.574989) (xy 430.81956 -290.574476)
			(xy 431.335688 -290.574476) (xy 431.343498 -290.574161) (xy 431.35837 -290.569377) (xy 431.364898 -290.565078)
			(xy 431.385987 -290.550729) (xy 431.431648 -290.527998) (xy 431.480254 -290.512539) (xy 431.530657 -290.504716)
			(xy 431.581663 -290.504716) (xy 431.632066 -290.512539) (xy 431.680672 -290.527998) (xy 431.726333 -290.550729)
			(xy 431.747422 -290.565078) (xy 431.753951 -290.569374) (xy 431.768823 -290.574154) (xy 431.776632 -290.574476)
			(xy 432.29276 -290.574476) (xy 432.298083 -290.574852) (xy 432.305625 -290.582363) (xy 432.305968 -290.587684)
			(xy 432.305968 -291.082222) (xy 438.350152 -291.082222) (xy 438.350152 -290.587684) (xy 438.35068 -290.582429)
			(xy 438.358106 -290.574989) (xy 438.36336 -290.574476) (xy 438.363868 -290.574476) (xy 438.879742 -290.574476)
			(xy 438.88755 -290.574141) (xy 438.902422 -290.56937) (xy 438.908952 -290.565078) (xy 438.930041 -290.550729)
			(xy 438.975702 -290.527998) (xy 439.024308 -290.512539) (xy 439.074711 -290.504716) (xy 439.125717 -290.504716)
			(xy 439.17612 -290.512539) (xy 439.224726 -290.527998) (xy 439.270387 -290.550729) (xy 439.291476 -290.565078)
			(xy 439.298015 -290.569356) (xy 439.312879 -290.574148) (xy 439.320686 -290.574476) (xy 439.836814 -290.574476)
			(xy 439.842128 -290.574918) (xy 439.849701 -290.582378) (xy 439.850276 -290.587684) (xy 439.850276 -291.082222)
			(xy 439.850252 -291.082476) (xy 445.89446 -291.082476) (xy 445.89446 -291.081968) (xy 445.89446 -290.587684)
			(xy 445.894981 -290.582427) (xy 445.902412 -290.574987) (xy 445.907668 -290.574476) (xy 446.423796 -290.574476)
			(xy 446.431606 -290.574165) (xy 446.446478 -290.569378) (xy 446.453006 -290.565078) (xy 446.474095 -290.550729)
			(xy 446.519756 -290.527998) (xy 446.568362 -290.512539) (xy 446.618765 -290.504716) (xy 446.669771 -290.504716)
			(xy 446.720174 -290.512539) (xy 446.76878 -290.527998) (xy 446.814441 -290.550729) (xy 446.83553 -290.565078)
			(xy 446.842057 -290.569377) (xy 446.85693 -290.574155) (xy 446.86474 -290.574476) (xy 447.380868 -290.574476)
			(xy 447.386192 -290.574847) (xy 447.393734 -290.582361) (xy 447.394076 -290.587684) (xy 447.394076 -291.082222)
			(xy 447.394053 -291.082476) (xy 453.43826 -291.082476) (xy 453.43826 -291.081968) (xy 453.43826 -290.587684)
			(xy 453.438781 -290.582427) (xy 453.446212 -290.574987) (xy 453.451468 -290.574476) (xy 453.967596 -290.574476)
			(xy 453.975406 -290.574165) (xy 453.990278 -290.569378) (xy 453.996806 -290.565078) (xy 454.017895 -290.550729)
			(xy 454.063556 -290.527998) (xy 454.112162 -290.512539) (xy 454.162565 -290.504716) (xy 454.213571 -290.504716)
			(xy 454.263974 -290.512539) (xy 454.31258 -290.527998) (xy 454.358241 -290.550729) (xy 454.37933 -290.565078)
			(xy 454.385857 -290.569377) (xy 454.40073 -290.574155) (xy 454.40854 -290.574476) (xy 454.924668 -290.574476)
			(xy 454.929992 -290.574847) (xy 454.937534 -290.582361) (xy 454.937876 -290.587684) (xy 454.937876 -291.082222)
			(xy 454.937393 -291.087525) (xy 454.929961 -291.095094) (xy 454.924668 -291.095684) (xy 454.408794 -291.095684)
			(xy 454.400982 -291.095981) (xy 454.38611 -291.100777) (xy 454.379584 -291.105082) (xy 454.358467 -291.119438)
			(xy 454.312741 -291.142162) (xy 454.264066 -291.15759) (xy 454.213599 -291.165355) (xy 454.188068 -291.165788)
			(xy 454.162537 -291.165363) (xy 454.112073 -291.157583) (xy 454.063401 -291.14215) (xy 454.017674 -291.119431)
			(xy 453.996552 -291.105082) (xy 453.990026 -291.100781) (xy 453.975152 -291.096003) (xy 453.967342 -291.095684)
			(xy 453.451468 -291.095684) (xy 453.446196 -291.095224) (xy 453.438753 -291.08775) (xy 453.43826 -291.082476)
			(xy 447.394053 -291.082476) (xy 447.393593 -291.087525) (xy 447.386161 -291.095094) (xy 447.380868 -291.095684)
			(xy 446.864994 -291.095684) (xy 446.857182 -291.095981) (xy 446.84231 -291.100777) (xy 446.835784 -291.105082)
			(xy 446.814667 -291.119438) (xy 446.768941 -291.142162) (xy 446.720266 -291.15759) (xy 446.669799 -291.165355)
			(xy 446.644268 -291.165788) (xy 446.618737 -291.165363) (xy 446.568273 -291.157583) (xy 446.519601 -291.14215)
			(xy 446.473874 -291.119431) (xy 446.452752 -291.105082) (xy 446.446226 -291.100781) (xy 446.431352 -291.096003)
			(xy 446.423542 -291.095684) (xy 445.907668 -291.095684) (xy 445.902396 -291.095224) (xy 445.894953 -291.08775)
			(xy 445.89446 -291.082476) (xy 439.850252 -291.082476) (xy 439.849766 -291.087585) (xy 439.842177 -291.095169)
			(xy 439.836814 -291.095684) (xy 439.32094 -291.095684) (xy 439.31313 -291.096001) (xy 439.298258 -291.100783)
			(xy 439.29173 -291.105082) (xy 439.270628 -291.119461) (xy 439.224897 -291.14218) (xy 439.176217 -291.157602)
			(xy 439.125747 -291.165359) (xy 439.100214 -291.165788) (xy 439.074684 -291.16534) (xy 439.024221 -291.157567)
			(xy 438.975549 -291.142141) (xy 438.929821 -291.119428) (xy 438.908698 -291.105082) (xy 438.902161 -291.100799)
			(xy 438.887296 -291.096009) (xy 438.879488 -291.095684) (xy 438.363614 -291.095684) (xy 438.358257 -291.095143)
			(xy 438.350672 -291.087578) (xy 438.350152 -291.082222) (xy 432.305968 -291.082222) (xy 432.305492 -291.087527)
			(xy 432.298055 -291.095096) (xy 432.29276 -291.095684) (xy 431.776886 -291.095684) (xy 431.769074 -291.095978)
			(xy 431.754202 -291.100776) (xy 431.747676 -291.105082) (xy 431.726561 -291.119441) (xy 431.680834 -291.142165)
			(xy 431.632159 -291.157592) (xy 431.581691 -291.165356) (xy 431.55616 -291.165788) (xy 431.530629 -291.165367)
			(xy 431.480165 -291.157586) (xy 431.431493 -291.142152) (xy 431.385766 -291.119431) (xy 431.364644 -291.105082)
			(xy 431.358119 -291.100778) (xy 431.343244 -291.096001) (xy 431.335434 -291.095684) (xy 430.81956 -291.095684)
			(xy 430.814287 -291.09523) (xy 430.806845 -291.087752) (xy 430.806352 -291.082476) (xy 424.762144 -291.082476)
			(xy 424.761665 -291.087587) (xy 424.754072 -291.095171) (xy 424.748706 -291.095684) (xy 424.232832 -291.095684)
			(xy 424.225022 -291.095997) (xy 424.21015 -291.100782) (xy 424.203622 -291.105082) (xy 424.182494 -291.119421)
			(xy 424.136772 -291.14215) (xy 424.088101 -291.157582) (xy 424.037636 -291.165353) (xy 424.012106 -291.165788)
			(xy 423.986576 -291.165344) (xy 423.936113 -291.15757) (xy 423.88744 -291.142143) (xy 423.841712 -291.119428)
			(xy 423.82059 -291.105082) (xy 423.814055 -291.100796) (xy 423.799188 -291.096008) (xy 423.79138 -291.095684)
			(xy 423.275506 -291.095684) (xy 423.270148 -291.095148) (xy 423.262563 -291.087579) (xy 423.262044 -291.082222)
			(xy 417.21786 -291.082222) (xy 417.217391 -291.087529) (xy 417.20995 -291.095099) (xy 417.204652 -291.095684)
			(xy 415.731452 -291.095684) (xy 415.726178 -291.095235) (xy 415.718737 -291.087753) (xy 415.718244 -291.082476)
			(xy 374.419812 -291.082476) (xy 374.420924 -291.0959) (xy 374.416749 -291.146284) (xy 374.404338 -291.195294)
			(xy 374.384031 -291.241593) (xy 374.35638 -291.283918) (xy 374.32214 -291.321115) (xy 374.282245 -291.352169)
			(xy 374.237783 -291.376233) (xy 374.189967 -291.392652) (xy 374.1401 -291.400976) (xy 374.114822 -291.4015)
			(xy 373.174768 -291.4015) (xy 373.149497 -291.4009) (xy 373.099644 -291.392576) (xy 373.05184 -291.376161)
			(xy 373.007391 -291.352102) (xy 372.967507 -291.321055) (xy 372.933277 -291.283868) (xy 372.905634 -291.241554)
			(xy 372.885333 -291.195267) (xy 372.872926 -291.14627) (xy 372.868752 -291.0959) (xy 371.601024 -291.0959)
			(xy 371.596849 -291.146285) (xy 371.584438 -291.195295) (xy 371.56413 -291.241595) (xy 371.536478 -291.28392)
			(xy 371.502237 -291.321117) (xy 371.462341 -291.352171) (xy 371.417878 -291.376236) (xy 371.37006 -291.392653)
			(xy 371.320193 -291.400977) (xy 371.294914 -291.4015) (xy 370.35486 -291.4015) (xy 370.329589 -291.400899)
			(xy 370.279737 -291.392574) (xy 370.231935 -291.376158) (xy 370.187487 -291.352099) (xy 370.147604 -291.321052)
			(xy 370.113375 -291.283865) (xy 370.085733 -291.241551) (xy 370.065432 -291.195265) (xy 370.053026 -291.14627)
			(xy 370.048852 -291.0959) (xy 368.780953 -291.0959) (xy 368.776776 -291.146296) (xy 368.764361 -291.195317)
			(xy 368.744046 -291.241626) (xy 368.716385 -291.283959) (xy 368.682133 -291.321161) (xy 368.642224 -291.352217)
			(xy 368.597748 -291.376281) (xy 368.549917 -291.392694) (xy 368.500036 -291.401011) (xy 368.474752 -291.4015)
			(xy 367.534698 -291.4015) (xy 367.509425 -291.400902) (xy 367.459568 -291.392582) (xy 367.411761 -291.37617)
			(xy 367.367307 -291.352112) (xy 367.327419 -291.321066) (xy 367.293185 -291.283878) (xy 367.265539 -291.241562)
			(xy 367.245235 -291.195273) (xy 367.232827 -291.146274) (xy 367.228652 -291.0959) (xy 365.960924 -291.0959)
			(xy 365.956749 -291.146282) (xy 365.94434 -291.195289) (xy 365.924034 -291.241586) (xy 365.896386 -291.28391)
			(xy 365.862149 -291.321107) (xy 365.822257 -291.352161) (xy 365.777798 -291.376227) (xy 365.729985 -291.392647)
			(xy 365.680121 -291.400974) (xy 365.654844 -291.4015) (xy 364.71479 -291.4015) (xy 364.689517 -291.400901)
			(xy 364.639662 -291.39258) (xy 364.591855 -291.376167) (xy 364.547403 -291.352109) (xy 364.507516 -291.321063)
			(xy 364.473283 -291.283875) (xy 364.445638 -291.24156) (xy 364.425334 -291.195271) (xy 364.412926 -291.146273)
			(xy 364.408752 -291.0959) (xy 355.627224 -291.0959) (xy 355.623049 -291.146285) (xy 355.610637 -291.195297)
			(xy 355.590329 -291.241596) (xy 355.562677 -291.283922) (xy 355.528435 -291.32112) (xy 355.488538 -291.352174)
			(xy 355.444074 -291.376237) (xy 355.396255 -291.392655) (xy 355.346387 -291.400977) (xy 355.321108 -291.4015)
			(xy 354.381054 -291.4015) (xy 354.355783 -291.400899) (xy 354.305932 -291.392573) (xy 354.258131 -291.376157)
			(xy 354.213684 -291.352097) (xy 354.173802 -291.32105) (xy 354.139574 -291.283863) (xy 354.111932 -291.24155)
			(xy 354.091632 -291.195264) (xy 354.079226 -291.146269) (xy 354.075052 -291.0959) (xy 352.807324 -291.0959)
			(xy 352.803148 -291.146286) (xy 352.790737 -291.195298) (xy 352.770428 -291.241599) (xy 352.742774 -291.283925)
			(xy 352.708532 -291.321122) (xy 352.668634 -291.352176) (xy 352.624168 -291.37624) (xy 352.576349 -291.392656)
			(xy 352.526479 -291.400978) (xy 352.5012 -291.4015) (xy 351.561146 -291.4015) (xy 351.535868 -291.400935)
			(xy 351.486 -291.39262) (xy 351.438182 -291.37621) (xy 351.393716 -291.352153) (xy 351.353818 -291.321104)
			(xy 351.319575 -291.283911) (xy 351.291921 -291.241589) (xy 351.271611 -291.195292) (xy 351.259199 -291.146283)
			(xy 351.255023 -291.0959) (xy 349.987453 -291.0959) (xy 349.983277 -291.146292) (xy 349.970864 -291.195309)
			(xy 349.950552 -291.241615) (xy 349.922895 -291.283945) (xy 349.888648 -291.321147) (xy 349.848745 -291.352203)
			(xy 349.804275 -291.376269) (xy 349.756449 -291.392686) (xy 349.706574 -291.401007) (xy 349.681292 -291.4015)
			(xy 348.741238 -291.4015) (xy 348.71596 -291.400934) (xy 348.666094 -291.392619) (xy 348.618276 -291.376208)
			(xy 348.573812 -291.35215) (xy 348.533915 -291.321101) (xy 348.499672 -291.283909) (xy 348.472019 -291.241587)
			(xy 348.45171 -291.19529) (xy 348.439299 -291.146282) (xy 348.435123 -291.0959) (xy 347.167224 -291.0959)
			(xy 347.163049 -291.146283) (xy 347.150639 -291.195292) (xy 347.130332 -291.24159) (xy 347.102682 -291.283915)
			(xy 347.068443 -291.321112) (xy 347.02855 -291.352166) (xy 346.984089 -291.376231) (xy 346.936273 -291.39265)
			(xy 346.886408 -291.400976) (xy 346.86113 -291.4015) (xy 345.921076 -291.4015) (xy 345.895804 -291.4009)
			(xy 345.84595 -291.392578) (xy 345.798146 -291.376163) (xy 345.753695 -291.352104) (xy 345.71381 -291.321058)
			(xy 345.679579 -291.28387) (xy 345.651936 -291.241556) (xy 345.631633 -291.195269) (xy 345.619226 -291.146271)
			(xy 345.615052 -291.0959) (xy 300.039723 -291.0959) (xy 300.037057 -291.096012) (xy 300.022185 -291.100786)
			(xy 300.015656 -291.105082) (xy 299.994547 -291.11945) (xy 299.948818 -291.142172) (xy 299.900141 -291.157596)
			(xy 299.849672 -291.165357) (xy 299.82414 -291.165788) (xy 299.798611 -291.165327) (xy 299.748148 -291.157558)
			(xy 299.699476 -291.142136) (xy 299.653747 -291.119426) (xy 299.632624 -291.105082) (xy 299.626082 -291.100809)
			(xy 299.61122 -291.096013) (xy 299.603414 -291.095684) (xy 299.08754 -291.095684) (xy 299.082207 -291.095344)
			(xy 299.074663 -291.087808) (xy 299.074332 -291.082476) (xy 293.030125 -291.082476) (xy 293.029663 -291.087592)
			(xy 293.022057 -291.095177) (xy 293.016686 -291.095684) (xy 292.500812 -291.095684) (xy 292.493001 -291.095989)
			(xy 292.478129 -291.100779) (xy 292.471602 -291.105082) (xy 292.45048 -291.11943) (xy 292.404756 -291.142156)
			(xy 292.356083 -291.157586) (xy 292.305617 -291.165354) (xy 292.280086 -291.165788) (xy 292.254556 -291.165354)
			(xy 292.204092 -291.157577) (xy 292.15542 -291.142147) (xy 292.109692 -291.11943) (xy 292.08857 -291.105082)
			(xy 292.08204 -291.100788) (xy 292.067169 -291.096005) (xy 292.05936 -291.095684) (xy 291.543486 -291.095684)
			(xy 291.538126 -291.095161) (xy 291.530542 -291.087582) (xy 291.530024 -291.082222) (xy 285.48584 -291.082222)
			(xy 285.485389 -291.087534) (xy 285.477935 -291.095105) (xy 285.472632 -291.095684) (xy 284.956758 -291.095684)
			(xy 284.948949 -291.096008) (xy 284.934077 -291.100785) (xy 284.927548 -291.105082) (xy 284.906441 -291.119453)
			(xy 284.860711 -291.142174) (xy 284.812034 -291.157598) (xy 284.761564 -291.165358) (xy 284.736032 -291.165788)
			(xy 284.710503 -291.165331) (xy 284.66004 -291.157561) (xy 284.611367 -291.142137) (xy 284.565639 -291.119427)
			(xy 284.544516 -291.105082) (xy 284.537975 -291.100806) (xy 284.523113 -291.096012) (xy 284.515306 -291.095684)
			(xy 283.999432 -291.095684) (xy 283.994098 -291.095349) (xy 283.986554 -291.08781) (xy 283.986224 -291.082476)
			(xy 277.942018 -291.082476) (xy 277.941589 -291.087534) (xy 277.934135 -291.095105) (xy 277.928832 -291.095684)
			(xy 277.412958 -291.095684) (xy 277.405149 -291.096008) (xy 277.390277 -291.100785) (xy 277.383748 -291.105082)
			(xy 277.362641 -291.119453) (xy 277.316911 -291.142174) (xy 277.268234 -291.157598) (xy 277.217764 -291.165358)
			(xy 277.192232 -291.165788) (xy 277.166703 -291.165331) (xy 277.11624 -291.157561) (xy 277.067567 -291.142137)
			(xy 277.021839 -291.119427) (xy 277.000716 -291.105082) (xy 276.994175 -291.100806) (xy 276.979313 -291.096012)
			(xy 276.971506 -291.095684) (xy 276.455632 -291.095684) (xy 276.450298 -291.095349) (xy 276.442754 -291.08781)
			(xy 276.442424 -291.082476) (xy 270.398217 -291.082476) (xy 270.397762 -291.087594) (xy 270.390152 -291.09518)
			(xy 270.384778 -291.095684) (xy 269.868904 -291.095684) (xy 269.861093 -291.095985) (xy 269.846221 -291.100778)
			(xy 269.839694 -291.105082) (xy 269.818574 -291.119434) (xy 269.772849 -291.142159) (xy 269.724176 -291.157588)
			(xy 269.673709 -291.165355) (xy 269.648178 -291.165788) (xy 269.622648 -291.165358) (xy 269.572184 -291.15758)
			(xy 269.523511 -291.142148) (xy 269.477784 -291.11943) (xy 269.456662 -291.105082) (xy 269.450133 -291.100785)
			(xy 269.435261 -291.096004) (xy 269.427452 -291.095684) (xy 268.911578 -291.095684) (xy 268.906217 -291.095166)
			(xy 268.898634 -291.087583) (xy 268.898116 -291.082222) (xy 206.997808 -291.082222) (xy 206.997808 -291.082476)
			(xy 206.997457 -291.087805) (xy 206.989928 -291.095347) (xy 206.9846 -291.095684) (xy 206.468726 -291.095684)
			(xy 206.460849 -291.095942) (xy 206.445845 -291.100745) (xy 206.439262 -291.105082) (xy 206.418188 -291.119479)
			(xy 206.372542 -291.142305) (xy 206.323935 -291.157861) (xy 206.273517 -291.165779) (xy 206.248 -291.166296)
			(xy 206.222479 -291.165824) (xy 206.172051 -291.157924) (xy 206.12344 -291.142359) (xy 206.077802 -291.119499)
			(xy 206.056738 -291.105082) (xy 206.050141 -291.100777) (xy 206.035145 -291.095985) (xy 206.027274 -291.095684)
			(xy 205.5114 -291.095684) (xy 205.506062 -291.095371) (xy 205.498519 -291.087815) (xy 205.498192 -291.082476)
			(xy 199.454008 -291.082476) (xy 199.453657 -291.087805) (xy 199.446128 -291.095347) (xy 199.4408 -291.095684)
			(xy 198.924926 -291.095684) (xy 198.917049 -291.095942) (xy 198.902045 -291.100745) (xy 198.895462 -291.105082)
			(xy 198.874388 -291.119479) (xy 198.828742 -291.142305) (xy 198.780135 -291.157861) (xy 198.729717 -291.165779)
			(xy 198.7042 -291.166296) (xy 198.678679 -291.165824) (xy 198.628251 -291.157924) (xy 198.57964 -291.142359)
			(xy 198.534002 -291.119499) (xy 198.512938 -291.105082) (xy 198.506341 -291.100777) (xy 198.491345 -291.095985)
			(xy 198.483474 -291.095684) (xy 197.9676 -291.095684) (xy 197.962262 -291.095371) (xy 197.954719 -291.087815)
			(xy 197.954392 -291.082476) (xy 191.910208 -291.082476) (xy 191.909857 -291.087805) (xy 191.902328 -291.095347)
			(xy 191.897 -291.095684) (xy 191.896492 -291.095684) (xy 191.380872 -291.095684) (xy 191.372996 -291.095962)
			(xy 191.357992 -291.100752) (xy 191.351408 -291.105082) (xy 191.330349 -291.119502) (xy 191.284697 -291.142323)
			(xy 191.236086 -291.157873) (xy 191.185664 -291.165783) (xy 191.160146 -291.166296) (xy 191.134626 -291.165801)
			(xy 191.084199 -291.157908) (xy 191.035588 -291.14235) (xy 190.989949 -291.119496) (xy 190.968884 -291.105082)
			(xy 190.962299 -291.100756) (xy 190.947294 -291.095977) (xy 190.93942 -291.095684) (xy 190.423546 -291.095684)
			(xy 190.418253 -291.095149) (xy 190.41068 -291.087756) (xy 190.410084 -291.082476) (xy 184.3659 -291.082476)
			(xy 184.365556 -291.087807) (xy 184.358023 -291.09535) (xy 184.352692 -291.095684) (xy 183.836818 -291.095684)
			(xy 183.828944 -291.095981) (xy 183.81394 -291.100758) (xy 183.807354 -291.105082) (xy 183.786282 -291.119482)
			(xy 183.740635 -291.142308) (xy 183.692027 -291.157863) (xy 183.641609 -291.16578) (xy 183.616092 -291.166296)
			(xy 183.590573 -291.165778) (xy 183.540147 -291.157892) (xy 183.491535 -291.14234) (xy 183.445896 -291.119494)
			(xy 183.42483 -291.105082) (xy 183.418235 -291.100774) (xy 183.403237 -291.095983) (xy 183.395366 -291.095684)
			(xy 182.879492 -291.095684) (xy 182.874153 -291.095376) (xy 182.866611 -291.087816) (xy 182.866284 -291.082476)
			(xy 176.8221 -291.082476) (xy 176.821756 -291.087807) (xy 176.814223 -291.09535) (xy 176.808892 -291.095684)
			(xy 176.808384 -291.095684) (xy 176.292764 -291.095684) (xy 176.284888 -291.095958) (xy 176.269884 -291.10075)
			(xy 176.2633 -291.105082) (xy 176.242216 -291.119463) (xy 176.196573 -291.142293) (xy 176.147969 -291.157853)
			(xy 176.097554 -291.165776) (xy 176.072038 -291.166296) (xy 176.046518 -291.165805) (xy 175.996091 -291.157911)
			(xy 175.947479 -291.142351) (xy 175.901841 -291.119497) (xy 175.880776 -291.105082) (xy 175.874193 -291.100753)
			(xy 175.859186 -291.095975) (xy 175.851312 -291.095684) (xy 175.335438 -291.095684) (xy 175.330144 -291.095154)
			(xy 175.322572 -291.087757) (xy 175.321976 -291.082476) (xy 169.277792 -291.082476) (xy 169.277455 -291.087809)
			(xy 169.269917 -291.095352) (xy 169.264584 -291.095684) (xy 167.791384 -291.095684) (xy 167.786044 -291.095382)
			(xy 167.778502 -291.087817) (xy 167.778176 -291.082476) (xy 126.479515 -291.082476) (xy 126.480652 -291.0962)
			(xy 126.47648 -291.146546) (xy 126.464077 -291.195519) (xy 126.443782 -291.241782) (xy 126.416148 -291.284074)
			(xy 126.38193 -291.321239) (xy 126.342061 -291.352265) (xy 126.297628 -291.376305) (xy 126.249845 -291.392703)
			(xy 126.200014 -291.401011) (xy 126.174754 -291.4015) (xy 125.2347 -291.4015) (xy 125.209444 -291.400994)
			(xy 125.159621 -291.39268) (xy 125.111846 -291.376279) (xy 125.067422 -291.352238) (xy 125.027561 -291.321213)
			(xy 124.99335 -291.28405) (xy 124.965723 -291.241763) (xy 124.945432 -291.195506) (xy 124.933032 -291.146539)
			(xy 124.928861 -291.0962) (xy 123.660623 -291.0962) (xy 123.656453 -291.146532) (xy 123.644056 -291.195491)
			(xy 123.62377 -291.241743) (xy 123.596149 -291.284025) (xy 123.561946 -291.321185) (xy 123.522094 -291.352209)
			(xy 123.477679 -291.376251) (xy 123.429913 -291.392655) (xy 123.380098 -291.400975) (xy 123.354846 -291.4015)
			(xy 122.414792 -291.4015) (xy 122.389536 -291.400994) (xy 122.339714 -291.392679) (xy 122.29194 -291.376277)
			(xy 122.247518 -291.352235) (xy 122.207658 -291.32121) (xy 122.173448 -291.284048) (xy 122.145821 -291.241761)
			(xy 122.125532 -291.195504) (xy 122.113132 -291.146539) (xy 122.108961 -291.0962) (xy 120.840552 -291.0962)
			(xy 120.83638 -291.146543) (xy 120.823979 -291.195513) (xy 120.803686 -291.241774) (xy 120.776056 -291.284064)
			(xy 120.741842 -291.321228) (xy 120.701977 -291.352255) (xy 120.657549 -291.376296) (xy 120.609769 -291.392696)
			(xy 120.559942 -291.401009) (xy 120.534684 -291.4015) (xy 119.59463 -291.4015) (xy 119.56937 -291.401026)
			(xy 119.519538 -291.392715) (xy 119.471755 -291.376315) (xy 119.427322 -291.352273) (xy 119.387453 -291.321245)
			(xy 119.353235 -291.284078) (xy 119.325602 -291.241785) (xy 119.305307 -291.195521) (xy 119.292904 -291.146547)
			(xy 119.288732 -291.0962) (xy 118.020652 -291.0962) (xy 118.01648 -291.146544) (xy 118.004078 -291.195515)
			(xy 117.983785 -291.241776) (xy 117.956154 -291.284066) (xy 117.921939 -291.321231) (xy 117.882072 -291.352257)
			(xy 117.837643 -291.376298) (xy 117.789863 -291.392698) (xy 117.740034 -291.401009) (xy 117.714776 -291.4015)
			(xy 116.774722 -291.4015) (xy 116.749462 -291.401025) (xy 116.699632 -291.392713) (xy 116.651849 -291.376312)
			(xy 116.607418 -291.35227) (xy 116.56755 -291.321242) (xy 116.533333 -291.284075) (xy 116.5057 -291.241783)
			(xy 116.485406 -291.19552) (xy 116.473004 -291.146547) (xy 116.468832 -291.0962) (xy 107.686823 -291.0962)
			(xy 107.682653 -291.146533) (xy 107.670255 -291.195493) (xy 107.649969 -291.241745) (xy 107.622348 -291.284027)
			(xy 107.588144 -291.321187) (xy 107.548291 -291.352211) (xy 107.503875 -291.376253) (xy 107.456108 -291.392657)
			(xy 107.406292 -291.400975) (xy 107.38104 -291.4015) (xy 106.440986 -291.4015) (xy 106.415731 -291.400993)
			(xy 106.36591 -291.392678) (xy 106.318136 -291.376275) (xy 106.273715 -291.352233) (xy 106.233855 -291.321208)
			(xy 106.199646 -291.284046) (xy 106.172021 -291.241759) (xy 106.151731 -291.195503) (xy 106.139332 -291.146538)
			(xy 106.135161 -291.0962) (xy 104.866923 -291.0962) (xy 104.862753 -291.146533) (xy 104.850355 -291.195494)
			(xy 104.830068 -291.241747) (xy 104.802446 -291.28403) (xy 104.768241 -291.32119) (xy 104.728386 -291.352214)
			(xy 104.683969 -291.376255) (xy 104.636201 -291.392658) (xy 104.586385 -291.400976) (xy 104.561132 -291.4015)
			(xy 103.621078 -291.4015) (xy 103.595823 -291.400993) (xy 103.546003 -291.392676) (xy 103.498231 -291.376273)
			(xy 103.45381 -291.352231) (xy 103.413952 -291.321205) (xy 103.379744 -291.284043) (xy 103.352119 -291.241757)
			(xy 103.331831 -291.195501) (xy 103.319432 -291.146537) (xy 103.315261 -291.0962) (xy 102.047023 -291.0962)
			(xy 102.042852 -291.146534) (xy 102.030454 -291.195496) (xy 102.010167 -291.241749) (xy 101.982544 -291.284032)
			(xy 101.948338 -291.321193) (xy 101.908482 -291.352216) (xy 101.864064 -291.376257) (xy 101.816295 -291.39266)
			(xy 101.766477 -291.400977) (xy 101.741224 -291.4015) (xy 100.80117 -291.4015) (xy 100.775916 -291.400992)
			(xy 100.726096 -291.392674) (xy 100.678326 -291.37627) (xy 100.633906 -291.352228) (xy 100.594049 -291.321202)
			(xy 100.559842 -291.28404) (xy 100.532218 -291.241755) (xy 100.51193 -291.1955) (xy 100.499532 -291.146536)
			(xy 100.495361 -291.0962) (xy 99.226952 -291.0962) (xy 99.22278 -291.146546) (xy 99.210377 -291.195518)
			(xy 99.190083 -291.24178) (xy 99.16245 -291.284071) (xy 99.128233 -291.321236) (xy 99.088365 -291.352262)
			(xy 99.043934 -291.376302) (xy 98.996151 -291.392701) (xy 98.946321 -291.40101) (xy 98.921062 -291.4015)
			(xy 97.981008 -291.4015) (xy 97.955749 -291.401024) (xy 97.90592 -291.39271) (xy 97.85814 -291.376308)
			(xy 97.81371 -291.352265) (xy 97.773844 -291.321237) (xy 97.739629 -291.284071) (xy 97.711998 -291.241779)
			(xy 97.691705 -291.195517) (xy 97.679304 -291.146545) (xy 97.675132 -291.0962) (xy 52.096211 -291.0962)
			(xy 52.081919 -291.100755) (xy 52.075334 -291.105082) (xy 52.054268 -291.119491) (xy 52.008619 -291.142314)
			(xy 51.960009 -291.157867) (xy 51.90959 -291.165781) (xy 51.884072 -291.166296) (xy 51.858553 -291.165788)
			(xy 51.808126 -291.157899) (xy 51.759515 -291.142345) (xy 51.713876 -291.119495) (xy 51.69281 -291.105082)
			(xy 51.686219 -291.100766) (xy 51.671218 -291.09598) (xy 51.663346 -291.095684) (xy 51.147472 -291.095684)
			(xy 51.1422 -291.095222) (xy 51.134758 -291.08775) (xy 51.134264 -291.082476) (xy 45.09008 -291.082476)
			(xy 45.089754 -291.087812) (xy 45.082208 -291.095356) (xy 45.076872 -291.095684) (xy 45.076364 -291.095684)
			(xy 44.560744 -291.095684) (xy 44.552867 -291.09595) (xy 44.537863 -291.100748) (xy 44.53128 -291.105082)
			(xy 44.510201 -291.119471) (xy 44.464556 -291.142299) (xy 44.415951 -291.157857) (xy 44.365534 -291.165778)
			(xy 44.340018 -291.166296) (xy 44.314497 -291.165815) (xy 44.26407 -291.157918) (xy 44.215459 -291.142356)
			(xy 44.169821 -291.119498) (xy 44.148756 -291.105082) (xy 44.142177 -291.100745) (xy 44.127167 -291.095972)
			(xy 44.119292 -291.095684) (xy 43.603418 -291.095684) (xy 43.598122 -291.095168) (xy 43.590551 -291.087761)
			(xy 43.589956 -291.082476) (xy 37.545772 -291.082476) (xy 37.545453 -291.087814) (xy 37.537902 -291.095358)
			(xy 37.532564 -291.095684) (xy 37.01669 -291.095684) (xy 37.008815 -291.095969) (xy 36.993811 -291.100754)
			(xy 36.987226 -291.105082) (xy 36.966162 -291.119494) (xy 36.920512 -291.142317) (xy 36.871902 -291.157869)
			(xy 36.821482 -291.165782) (xy 36.795964 -291.166296) (xy 36.770444 -291.165792) (xy 36.720018 -291.157902)
			(xy 36.671406 -291.142346) (xy 36.625767 -291.119495) (xy 36.604702 -291.105082) (xy 36.598113 -291.100763)
			(xy 36.583111 -291.095979) (xy 36.575238 -291.095684) (xy 36.059364 -291.095684) (xy 36.054091 -291.095227)
			(xy 36.046649 -291.087751) (xy 36.046156 -291.082476) (xy 30.001972 -291.082476) (xy 30.001653 -291.087814)
			(xy 29.994102 -291.095358) (xy 29.988764 -291.095684) (xy 29.47289 -291.095684) (xy 29.465015 -291.095969)
			(xy 29.450011 -291.100754) (xy 29.443426 -291.105082) (xy 29.422362 -291.119494) (xy 29.376712 -291.142317)
			(xy 29.328102 -291.157869) (xy 29.277682 -291.165782) (xy 29.252164 -291.166296) (xy 29.226644 -291.165792)
			(xy 29.176218 -291.157902) (xy 29.127606 -291.142346) (xy 29.081967 -291.119495) (xy 29.060902 -291.105082)
			(xy 29.054313 -291.100763) (xy 29.039311 -291.095979) (xy 29.031438 -291.095684) (xy 28.515564 -291.095684)
			(xy 28.510291 -291.095227) (xy 28.502849 -291.087751) (xy 28.502356 -291.082476) (xy 22.458172 -291.082476)
			(xy 22.457853 -291.087814) (xy 22.450302 -291.095358) (xy 22.444964 -291.095684) (xy 22.444456 -291.095684)
			(xy 21.928836 -291.095684) (xy 21.920959 -291.095946) (xy 21.905955 -291.100747) (xy 21.899372 -291.105082)
			(xy 21.878295 -291.119475) (xy 21.83265 -291.142302) (xy 21.784044 -291.157859) (xy 21.733627 -291.165778)
			(xy 21.70811 -291.166296) (xy 21.682589 -291.165819) (xy 21.632162 -291.157921) (xy 21.58355 -291.142357)
			(xy 21.537912 -291.119499) (xy 21.516848 -291.105082) (xy 21.510271 -291.100742) (xy 21.49526 -291.095971)
			(xy 21.487384 -291.095684) (xy 20.97151 -291.095684) (xy 20.966213 -291.095173) (xy 20.958642 -291.087762)
			(xy 20.958048 -291.082476) (xy 2.509012 -291.082476) (xy 2.509012 -291.93236) (xy 16.85798 -291.93236)
			(xy 16.85798 -291.437822) (xy 16.858298 -291.43238) (xy 16.865999 -291.42469) (xy 16.871442 -291.42436)
			(xy 17.38757 -291.42436) (xy 17.39538 -291.42404) (xy 17.410251 -291.419259) (xy 17.41678 -291.414962)
			(xy 17.437869 -291.400613) (xy 17.48353 -291.377882) (xy 17.532136 -291.362423) (xy 17.582539 -291.3546)
			(xy 17.633545 -291.3546) (xy 17.683948 -291.362423) (xy 17.732554 -291.377882) (xy 17.778215 -291.400613)
			(xy 17.799304 -291.414962) (xy 17.805838 -291.41925) (xy 17.820706 -291.424035) (xy 17.828514 -291.42436)
			(xy 18.344642 -291.42436) (xy 18.350016 -291.424825) (xy 18.357601 -291.432445) (xy 18.358104 -291.437822)
			(xy 18.358104 -291.93236) (xy 24.402288 -291.93236) (xy 24.402288 -291.437822) (xy 24.402744 -291.432509)
			(xy 24.410192 -291.424934) (xy 24.415496 -291.42436) (xy 24.931624 -291.42436) (xy 24.939436 -291.424063)
			(xy 24.954307 -291.419266) (xy 24.960834 -291.414962) (xy 24.981923 -291.400613) (xy 25.027584 -291.377882)
			(xy 25.07619 -291.362423) (xy 25.126593 -291.3546) (xy 25.177599 -291.3546) (xy 25.228002 -291.362423)
			(xy 25.276608 -291.377882) (xy 25.322269 -291.400613) (xy 25.343358 -291.414962) (xy 25.34988 -291.41927)
			(xy 25.364757 -291.424043) (xy 25.372568 -291.42436) (xy 25.888696 -291.42436) (xy 25.893951 -291.424894)
			(xy 25.901392 -291.432315) (xy 25.901904 -291.437568) (xy 25.901904 -291.438076) (xy 25.901904 -291.93236)
			(xy 31.946088 -291.93236) (xy 31.946088 -291.437822) (xy 31.946544 -291.432509) (xy 31.953992 -291.424934)
			(xy 31.959296 -291.42436) (xy 32.475424 -291.42436) (xy 32.483236 -291.424063) (xy 32.498107 -291.419266)
			(xy 32.504634 -291.414962) (xy 32.525723 -291.400613) (xy 32.571384 -291.377882) (xy 32.61999 -291.362423)
			(xy 32.670393 -291.3546) (xy 32.721399 -291.3546) (xy 32.771802 -291.362423) (xy 32.820408 -291.377882)
			(xy 32.866069 -291.400613) (xy 32.887158 -291.414962) (xy 32.89368 -291.41927) (xy 32.908557 -291.424043)
			(xy 32.916368 -291.42436) (xy 33.432496 -291.42436) (xy 33.437751 -291.424894) (xy 33.445192 -291.432315)
			(xy 33.445704 -291.437568) (xy 33.445704 -291.438076) (xy 33.445704 -291.93236) (xy 39.489888 -291.93236)
			(xy 39.489888 -291.437822) (xy 39.49046 -291.432473) (xy 39.498004 -291.424889) (xy 39.50335 -291.42436)
			(xy 40.019478 -291.42436) (xy 40.027288 -291.424043) (xy 40.04216 -291.41926) (xy 40.048688 -291.414962)
			(xy 40.069777 -291.400613) (xy 40.115438 -291.377882) (xy 40.164044 -291.362423) (xy 40.214447 -291.3546)
			(xy 40.265453 -291.3546) (xy 40.315856 -291.362423) (xy 40.364462 -291.377882) (xy 40.410123 -291.400613)
			(xy 40.431212 -291.414962) (xy 40.437744 -291.419253) (xy 40.452614 -291.424037) (xy 40.460422 -291.42436)
			(xy 40.97655 -291.42436) (xy 40.981925 -291.42482) (xy 40.989509 -291.432444) (xy 40.990012 -291.437822)
			(xy 40.990012 -291.93236) (xy 47.034196 -291.93236) (xy 47.034196 -291.437822) (xy 47.034732 -291.432531)
			(xy 47.042125 -291.424961) (xy 47.047404 -291.42436) (xy 47.563532 -291.42436) (xy 47.57134 -291.424024)
			(xy 47.586212 -291.419254) (xy 47.592742 -291.414962) (xy 47.613831 -291.400613) (xy 47.659492 -291.377882)
			(xy 47.708098 -291.362423) (xy 47.758501 -291.3546) (xy 47.809507 -291.3546) (xy 47.85991 -291.362423)
			(xy 47.908516 -291.377882) (xy 47.954177 -291.400613) (xy 47.975266 -291.414962) (xy 47.981808 -291.419235)
			(xy 47.99667 -291.42403) (xy 48.004476 -291.42436) (xy 48.520604 -291.42436) (xy 48.52586 -291.424889)
			(xy 48.5333 -291.432313) (xy 48.533812 -291.437568) (xy 48.533812 -291.438076) (xy 48.533812 -291.93236)
			(xy 54.577996 -291.93236) (xy 54.577996 -291.437822) (xy 54.578561 -291.432471) (xy 54.586109 -291.424886)
			(xy 54.591458 -291.42436) (xy 56.064658 -291.42436) (xy 56.070093 -291.42471) (xy 56.077782 -291.432388)
			(xy 56.07812 -291.437822) (xy 56.07812 -291.93236) (xy 163.678108 -291.93236) (xy 163.678108 -291.437822)
			(xy 163.678634 -291.432528) (xy 163.686034 -291.424957) (xy 163.691316 -291.42436) (xy 165.164516 -291.42436)
			(xy 165.169773 -291.424881) (xy 165.177213 -291.432312) (xy 165.177724 -291.437568) (xy 165.177724 -291.438076)
			(xy 165.177724 -291.93236) (xy 171.221908 -291.93236) (xy 171.221908 -291.437822) (xy 171.222462 -291.432468)
			(xy 171.230018 -291.424883) (xy 171.23537 -291.42436) (xy 171.751498 -291.42436) (xy 171.759309 -291.424052)
			(xy 171.77418 -291.419263) (xy 171.780708 -291.414962) (xy 171.801797 -291.400613) (xy 171.847458 -291.377882)
			(xy 171.896064 -291.362423) (xy 171.946467 -291.3546) (xy 171.997473 -291.3546) (xy 172.047876 -291.362423)
			(xy 172.096482 -291.377882) (xy 172.142143 -291.400613) (xy 172.163232 -291.414962) (xy 172.169759 -291.41926)
			(xy 172.184633 -291.42404) (xy 172.192442 -291.42436) (xy 172.70857 -291.42436) (xy 172.714006 -291.424702)
			(xy 172.721695 -291.432386) (xy 172.722032 -291.437822) (xy 172.722032 -291.93236) (xy 178.766216 -291.93236)
			(xy 178.766216 -291.437822) (xy 178.766735 -291.432526) (xy 178.77414 -291.424955) (xy 178.779424 -291.42436)
			(xy 179.295552 -291.42436) (xy 179.303361 -291.424032) (xy 179.318233 -291.419257) (xy 179.324762 -291.414962)
			(xy 179.345851 -291.400613) (xy 179.391512 -291.377882) (xy 179.440118 -291.362423) (xy 179.490521 -291.3546)
			(xy 179.541527 -291.3546) (xy 179.59193 -291.362423) (xy 179.640536 -291.377882) (xy 179.686197 -291.400613)
			(xy 179.707286 -291.414962) (xy 179.713824 -291.419243) (xy 179.728689 -291.424033) (xy 179.736496 -291.42436)
			(xy 180.252624 -291.42436) (xy 180.257882 -291.424876) (xy 180.265321 -291.43231) (xy 180.265832 -291.437568)
			(xy 180.265832 -291.438076) (xy 180.265832 -291.93236) (xy 186.310016 -291.93236) (xy 186.310016 -291.437822)
			(xy 186.310563 -291.432466) (xy 186.318124 -291.42488) (xy 186.323478 -291.42436) (xy 186.839606 -291.42436)
			(xy 186.847417 -291.424056) (xy 186.862289 -291.419264) (xy 186.868816 -291.414962) (xy 186.889905 -291.400613)
			(xy 186.935566 -291.377882) (xy 186.984172 -291.362423) (xy 187.034575 -291.3546) (xy 187.085581 -291.3546)
			(xy 187.135984 -291.362423) (xy 187.18459 -291.377882) (xy 187.230251 -291.400613) (xy 187.25134 -291.414962)
			(xy 187.257866 -291.419264) (xy 187.27274 -291.424041) (xy 187.28055 -291.42436) (xy 187.796678 -291.42436)
			(xy 187.802115 -291.424696) (xy 187.809804 -291.432385) (xy 187.81014 -291.437822) (xy 187.81014 -291.93236)
			(xy 193.854324 -291.93236) (xy 193.854324 -291.437822) (xy 193.854836 -291.432524) (xy 193.862246 -291.424953)
			(xy 193.867532 -291.42436) (xy 194.38366 -291.42436) (xy 194.391469 -291.424036) (xy 194.406341 -291.419258)
			(xy 194.41287 -291.414962) (xy 194.433959 -291.400613) (xy 194.47962 -291.377882) (xy 194.528226 -291.362423)
			(xy 194.578629 -291.3546) (xy 194.629635 -291.3546) (xy 194.680038 -291.362423) (xy 194.728644 -291.377882)
			(xy 194.774305 -291.400613) (xy 194.795394 -291.414962) (xy 194.80193 -291.419246) (xy 194.816796 -291.424034)
			(xy 194.824604 -291.42436) (xy 195.340732 -291.42436) (xy 195.345991 -291.42487) (xy 195.35343 -291.432309)
			(xy 195.35394 -291.437568) (xy 195.35394 -291.438076) (xy 195.35394 -291.93236) (xy 201.398124 -291.93236)
			(xy 201.398124 -291.437822) (xy 201.398636 -291.432524) (xy 201.406046 -291.424953) (xy 201.411332 -291.42436)
			(xy 201.92746 -291.42436) (xy 201.935269 -291.424036) (xy 201.950141 -291.419258) (xy 201.95667 -291.414962)
			(xy 201.977759 -291.400613) (xy 202.02342 -291.377882) (xy 202.072026 -291.362423) (xy 202.122429 -291.3546)
			(xy 202.173435 -291.3546) (xy 202.223838 -291.362423) (xy 202.272444 -291.377882) (xy 202.318105 -291.400613)
			(xy 202.339194 -291.414962) (xy 202.34573 -291.419246) (xy 202.360596 -291.424034) (xy 202.368404 -291.42436)
			(xy 202.884532 -291.42436) (xy 202.889791 -291.42487) (xy 202.89723 -291.432309) (xy 202.89774 -291.437568)
			(xy 202.89774 -291.438076) (xy 202.89774 -291.932106) (xy 264.798048 -291.932106) (xy 264.798048 -291.437568)
			(xy 264.798569 -291.432312) (xy 264.806 -291.424874) (xy 264.811256 -291.42436) (xy 264.811764 -291.42436)
			(xy 265.327638 -291.42436) (xy 265.335446 -291.424027) (xy 265.350318 -291.419255) (xy 265.356848 -291.414962)
			(xy 265.377937 -291.400613) (xy 265.423598 -291.377882) (xy 265.472204 -291.362423) (xy 265.522607 -291.3546)
			(xy 265.573613 -291.3546) (xy 265.624016 -291.362423) (xy 265.672622 -291.377882) (xy 265.718283 -291.400613)
			(xy 265.739372 -291.414962) (xy 265.745913 -291.419237) (xy 265.760776 -291.424031) (xy 265.768582 -291.42436)
			(xy 266.28471 -291.42436) (xy 266.29002 -291.424819) (xy 266.297592 -291.432267) (xy 266.298172 -291.437568)
			(xy 266.298172 -291.932106) (xy 266.298148 -291.93236) (xy 272.342356 -291.93236) (xy 272.342356 -291.931852)
			(xy 272.342356 -291.437568) (xy 272.34287 -291.43231) (xy 272.350306 -291.424871) (xy 272.355564 -291.42436)
			(xy 272.871692 -291.42436) (xy 272.879503 -291.42405) (xy 272.894374 -291.419262) (xy 272.900902 -291.414962)
			(xy 272.921991 -291.400613) (xy 272.967652 -291.377882) (xy 273.016258 -291.362423) (xy 273.066661 -291.3546)
			(xy 273.117667 -291.3546) (xy 273.16807 -291.362423) (xy 273.216676 -291.377882) (xy 273.262337 -291.400613)
			(xy 273.283426 -291.414962) (xy 273.289955 -291.419258) (xy 273.304827 -291.424039) (xy 273.312636 -291.42436)
			(xy 273.828764 -291.42436) (xy 273.834084 -291.424748) (xy 273.841625 -291.43225) (xy 273.841972 -291.437568)
			(xy 273.841972 -291.932106) (xy 273.841949 -291.93236) (xy 279.886156 -291.93236) (xy 279.886156 -291.931852)
			(xy 279.886156 -291.437568) (xy 279.88667 -291.43231) (xy 279.894106 -291.424871) (xy 279.899364 -291.42436)
			(xy 280.415492 -291.42436) (xy 280.423303 -291.42405) (xy 280.438174 -291.419262) (xy 280.444702 -291.414962)
			(xy 280.465791 -291.400613) (xy 280.511452 -291.377882) (xy 280.560058 -291.362423) (xy 280.610461 -291.3546)
			(xy 280.661467 -291.3546) (xy 280.71187 -291.362423) (xy 280.760476 -291.377882) (xy 280.806137 -291.400613)
			(xy 280.827226 -291.414962) (xy 280.833755 -291.419258) (xy 280.848627 -291.424039) (xy 280.856436 -291.42436)
			(xy 281.372564 -291.42436) (xy 281.377884 -291.424748) (xy 281.385425 -291.43225) (xy 281.385772 -291.437568)
			(xy 281.385772 -291.932106) (xy 287.429956 -291.932106) (xy 287.429956 -291.437568) (xy 287.43047 -291.43231)
			(xy 287.437906 -291.424871) (xy 287.443164 -291.42436) (xy 287.443672 -291.42436) (xy 287.959546 -291.42436)
			(xy 287.967355 -291.42403) (xy 287.982226 -291.419256) (xy 287.988756 -291.414962) (xy 288.009845 -291.400613)
			(xy 288.055506 -291.377882) (xy 288.104112 -291.362423) (xy 288.154515 -291.3546) (xy 288.205521 -291.3546)
			(xy 288.255924 -291.362423) (xy 288.30453 -291.377882) (xy 288.350191 -291.400613) (xy 288.37128 -291.414962)
			(xy 288.377819 -291.419241) (xy 288.392683 -291.424032) (xy 288.40049 -291.42436) (xy 288.916618 -291.42436)
			(xy 288.921929 -291.424813) (xy 288.9295 -291.432265) (xy 288.93008 -291.437568) (xy 288.93008 -291.932106)
			(xy 288.930055 -291.93236) (xy 294.974264 -291.93236) (xy 294.974264 -291.931852) (xy 294.974264 -291.437568)
			(xy 294.974771 -291.432308) (xy 294.982212 -291.424869) (xy 294.987472 -291.42436) (xy 295.5036 -291.42436)
			(xy 295.511411 -291.424053) (xy 295.526283 -291.419263) (xy 295.53281 -291.414962) (xy 295.553899 -291.400613)
			(xy 295.59956 -291.377882) (xy 295.648166 -291.362423) (xy 295.698569 -291.3546) (xy 295.749575 -291.3546)
			(xy 295.799978 -291.362423) (xy 295.848584 -291.377882) (xy 295.894245 -291.400613) (xy 295.915334 -291.414962)
			(xy 295.921861 -291.419261) (xy 295.936734 -291.42404) (xy 295.944544 -291.42436) (xy 296.460672 -291.42436)
			(xy 296.465924 -291.42491) (xy 296.473366 -291.432319) (xy 296.47388 -291.437568) (xy 296.47388 -291.932106)
			(xy 302.518064 -291.932106) (xy 302.518064 -291.437568) (xy 302.518571 -291.432308) (xy 302.526012 -291.424869)
			(xy 302.531272 -291.42436) (xy 304.004726 -291.42436) (xy 304.010038 -291.424808) (xy 304.017609 -291.432264)
			(xy 304.018188 -291.437568) (xy 304.018188 -291.932106) (xy 304.018163 -291.93236) (xy 411.618176 -291.93236)
			(xy 411.618176 -291.931852) (xy 411.618176 -291.437568) (xy 411.618672 -291.432305) (xy 411.626121 -291.424865)
			(xy 411.631384 -291.42436) (xy 413.104584 -291.42436) (xy 413.109837 -291.424902) (xy 413.117279 -291.432317)
			(xy 413.117792 -291.437568) (xy 413.117792 -291.932106) (xy 419.161976 -291.932106) (xy 419.161976 -291.437568)
			(xy 419.162472 -291.432305) (xy 419.169921 -291.424865) (xy 419.175184 -291.42436) (xy 419.175692 -291.42436)
			(xy 419.691566 -291.42436) (xy 419.699375 -291.424038) (xy 419.714247 -291.419258) (xy 419.720776 -291.414962)
			(xy 419.741865 -291.400613) (xy 419.787526 -291.377882) (xy 419.836132 -291.362423) (xy 419.886535 -291.3546)
			(xy 419.937541 -291.3546) (xy 419.987944 -291.362423) (xy 420.03655 -291.377882) (xy 420.082211 -291.400613)
			(xy 420.1033 -291.414962) (xy 420.109835 -291.419248) (xy 420.124702 -291.424035) (xy 420.13251 -291.42436)
			(xy 420.648638 -291.42436) (xy 420.653951 -291.4248) (xy 420.661521 -291.432262) (xy 420.6621 -291.437568)
			(xy 420.6621 -291.932106) (xy 420.662074 -291.93236) (xy 426.706284 -291.93236) (xy 426.706284 -291.931852)
			(xy 426.706284 -291.437568) (xy 426.706773 -291.432303) (xy 426.714226 -291.424863) (xy 426.719492 -291.42436)
			(xy 427.23562 -291.42436) (xy 427.243432 -291.424062) (xy 427.258303 -291.419266) (xy 427.26483 -291.414962)
			(xy 427.285919 -291.400613) (xy 427.33158 -291.377882) (xy 427.380186 -291.362423) (xy 427.430589 -291.3546)
			(xy 427.481595 -291.3546) (xy 427.531998 -291.362423) (xy 427.580604 -291.377882) (xy 427.626265 -291.400613)
			(xy 427.647354 -291.414962) (xy 427.653877 -291.419269) (xy 427.668753 -291.424043) (xy 427.676564 -291.42436)
			(xy 428.192692 -291.42436) (xy 428.197946 -291.424897) (xy 428.205387 -291.432315) (xy 428.2059 -291.437568)
			(xy 428.2059 -291.932106) (xy 434.250084 -291.932106) (xy 434.250084 -291.437568) (xy 434.250573 -291.432303)
			(xy 434.258026 -291.424863) (xy 434.263292 -291.42436) (xy 434.2638 -291.42436) (xy 434.779674 -291.42436)
			(xy 434.787484 -291.424042) (xy 434.802355 -291.419259) (xy 434.808884 -291.414962) (xy 434.829973 -291.400613)
			(xy 434.875634 -291.377882) (xy 434.92424 -291.362423) (xy 434.974643 -291.3546) (xy 435.025649 -291.3546)
			(xy 435.076052 -291.362423) (xy 435.124658 -291.377882) (xy 435.170319 -291.400613) (xy 435.191408 -291.414962)
			(xy 435.197941 -291.419251) (xy 435.21281 -291.424036) (xy 435.220618 -291.42436) (xy 435.736746 -291.42436)
			(xy 435.742048 -291.424861) (xy 435.749624 -291.432277) (xy 435.750208 -291.437568) (xy 435.750208 -291.932106)
			(xy 435.750182 -291.93236) (xy 441.794392 -291.93236) (xy 441.794392 -291.931852) (xy 441.794392 -291.437568)
			(xy 441.794873 -291.432301) (xy 441.802332 -291.424861) (xy 441.8076 -291.42436) (xy 442.323728 -291.42436)
			(xy 442.33154 -291.424065) (xy 442.346411 -291.419267) (xy 442.352938 -291.414962) (xy 442.374027 -291.400613)
			(xy 442.419688 -291.377882) (xy 442.468294 -291.362423) (xy 442.518697 -291.3546) (xy 442.569703 -291.3546)
			(xy 442.620106 -291.362423) (xy 442.668712 -291.377882) (xy 442.714373 -291.400613) (xy 442.735462 -291.414962)
			(xy 442.742005 -291.419234) (xy 442.756866 -291.424029) (xy 442.764672 -291.42436) (xy 443.2808 -291.42436)
			(xy 443.286055 -291.424892) (xy 443.293496 -291.432314) (xy 443.294008 -291.437568) (xy 443.294008 -291.932106)
			(xy 443.293983 -291.93236) (xy 449.338192 -291.93236) (xy 449.338192 -291.931852) (xy 449.338192 -291.437568)
			(xy 449.338673 -291.432301) (xy 449.346132 -291.424861) (xy 449.3514 -291.42436) (xy 449.867528 -291.42436)
			(xy 449.87534 -291.424065) (xy 449.890211 -291.419267) (xy 449.896738 -291.414962) (xy 449.917827 -291.400613)
			(xy 449.963488 -291.377882) (xy 450.012094 -291.362423) (xy 450.062497 -291.3546) (xy 450.113503 -291.3546)
			(xy 450.163906 -291.362423) (xy 450.212512 -291.377882) (xy 450.258173 -291.400613) (xy 450.279262 -291.414962)
			(xy 450.285805 -291.419234) (xy 450.300666 -291.424029) (xy 450.308472 -291.42436) (xy 450.8246 -291.42436)
			(xy 450.829855 -291.424892) (xy 450.837296 -291.432314) (xy 450.837808 -291.437568) (xy 450.837808 -291.932106)
			(xy 450.837287 -291.9374) (xy 450.829882 -291.944968) (xy 450.8246 -291.945568) (xy 450.308726 -291.945568)
			(xy 450.300916 -291.945881) (xy 450.286044 -291.950666) (xy 450.279516 -291.954966) (xy 450.258389 -291.969306)
			(xy 450.212667 -291.992035) (xy 450.163995 -292.007467) (xy 450.11353 -292.015237) (xy 450.088 -292.015672)
			(xy 450.06247 -292.015234) (xy 450.012006 -292.007458) (xy 449.963334 -291.99203) (xy 449.917606 -291.969313)
			(xy 449.896484 -291.954966) (xy 449.889951 -291.950676) (xy 449.875082 -291.945891) (xy 449.867274 -291.945568)
			(xy 449.3514 -291.945568) (xy 449.346058 -291.945269) (xy 449.338515 -291.937703) (xy 449.338192 -291.93236)
			(xy 443.293983 -291.93236) (xy 443.293487 -291.9374) (xy 443.286082 -291.944968) (xy 443.2808 -291.945568)
			(xy 442.764926 -291.945568) (xy 442.757116 -291.945881) (xy 442.742244 -291.950666) (xy 442.735716 -291.954966)
			(xy 442.714589 -291.969306) (xy 442.668867 -291.992035) (xy 442.620195 -292.007467) (xy 442.56973 -292.015237)
			(xy 442.5442 -292.015672) (xy 442.51867 -292.015234) (xy 442.468206 -292.007458) (xy 442.419534 -291.99203)
			(xy 442.373806 -291.969313) (xy 442.352684 -291.954966) (xy 442.346151 -291.950676) (xy 442.331282 -291.945891)
			(xy 442.323474 -291.945568) (xy 441.8076 -291.945568) (xy 441.802258 -291.945269) (xy 441.794715 -291.937703)
			(xy 441.794392 -291.93236) (xy 435.750182 -291.93236) (xy 435.749658 -291.93746) (xy 435.742098 -291.945042)
			(xy 435.736746 -291.945568) (xy 435.220872 -291.945568) (xy 435.21306 -291.945858) (xy 435.198188 -291.950659)
			(xy 435.191662 -291.954966) (xy 435.17055 -291.96933) (xy 435.124822 -291.992053) (xy 435.076146 -292.007479)
			(xy 435.025678 -292.015241) (xy 435.000146 -292.015672) (xy 434.974617 -292.015211) (xy 434.924154 -292.007442)
			(xy 434.875481 -291.99202) (xy 434.829753 -291.96931) (xy 434.80863 -291.954966) (xy 434.802087 -291.950694)
			(xy 434.787226 -291.945898) (xy 434.77942 -291.945568) (xy 434.263546 -291.945568) (xy 434.258119 -291.945191)
			(xy 434.25043 -291.937532) (xy 434.250084 -291.932106) (xy 428.2059 -291.932106) (xy 428.205386 -291.937402)
			(xy 428.197976 -291.94497) (xy 428.192692 -291.945568) (xy 427.676818 -291.945568) (xy 427.669007 -291.945878)
			(xy 427.654136 -291.950665) (xy 427.647608 -291.954966) (xy 427.626483 -291.96931) (xy 427.58076 -291.992037)
			(xy 427.532088 -292.007469) (xy 427.481623 -292.015238) (xy 427.456092 -292.015672) (xy 427.430562 -292.015238)
			(xy 427.380098 -292.007461) (xy 427.331425 -291.992031) (xy 427.285698 -291.969314) (xy 427.264576 -291.954966)
			(xy 427.258045 -291.950673) (xy 427.243175 -291.94589) (xy 427.235366 -291.945568) (xy 426.719492 -291.945568)
			(xy 426.714149 -291.945275) (xy 426.706606 -291.937704) (xy 426.706284 -291.93236) (xy 420.662074 -291.93236)
			(xy 420.661558 -291.937462) (xy 420.653992 -291.945045) (xy 420.648638 -291.945568) (xy 420.132764 -291.945568)
			(xy 420.124955 -291.945897) (xy 420.110083 -291.950671) (xy 420.103554 -291.954966) (xy 420.082444 -291.969333)
			(xy 420.036716 -291.992055) (xy 419.988039 -292.00748) (xy 419.93757 -292.015242) (xy 419.912038 -292.015672)
			(xy 419.886509 -292.015215) (xy 419.836046 -292.007445) (xy 419.787373 -291.992022) (xy 419.741645 -291.969311)
			(xy 419.720522 -291.954966) (xy 419.713981 -291.950691) (xy 419.699118 -291.945897) (xy 419.691312 -291.945568)
			(xy 419.175438 -291.945568) (xy 419.17001 -291.945196) (xy 419.162322 -291.937533) (xy 419.161976 -291.932106)
			(xy 413.117792 -291.932106) (xy 413.117285 -291.937403) (xy 413.10987 -291.944972) (xy 413.104584 -291.945568)
			(xy 411.631384 -291.945568) (xy 411.62604 -291.94528) (xy 411.618497 -291.937706) (xy 411.618176 -291.93236)
			(xy 304.018163 -291.93236) (xy 304.017656 -291.937464) (xy 304.010084 -291.945048) (xy 304.004726 -291.945568)
			(xy 302.531526 -291.945568) (xy 302.526096 -291.945204) (xy 302.518409 -291.937535) (xy 302.518064 -291.932106)
			(xy 296.47388 -291.932106) (xy 296.473383 -291.937406) (xy 296.465962 -291.944976) (xy 296.460672 -291.945568)
			(xy 295.944798 -291.945568) (xy 295.936987 -291.94587) (xy 295.922115 -291.950663) (xy 295.915588 -291.954966)
			(xy 295.894468 -291.969318) (xy 295.848744 -291.992044) (xy 295.80007 -292.007473) (xy 295.749603 -292.015239)
			(xy 295.724072 -292.015672) (xy 295.698541 -292.015248) (xy 295.648077 -292.007468) (xy 295.599405 -291.992035)
			(xy 295.553678 -291.969315) (xy 295.532556 -291.954966) (xy 295.52603 -291.950665) (xy 295.511156 -291.945887)
			(xy 295.503346 -291.945568) (xy 294.987472 -291.945568) (xy 294.982126 -291.945288) (xy 294.974584 -291.937708)
			(xy 294.974264 -291.93236) (xy 288.930055 -291.93236) (xy 288.929556 -291.937466) (xy 288.921978 -291.945051)
			(xy 288.916618 -291.945568) (xy 288.400744 -291.945568) (xy 288.392934 -291.945889) (xy 288.378062 -291.950669)
			(xy 288.371534 -291.954966) (xy 288.350429 -291.969342) (xy 288.304699 -291.992062) (xy 288.256021 -292.007485)
			(xy 288.20555 -292.015243) (xy 288.180018 -292.015672) (xy 288.154488 -292.015225) (xy 288.104025 -292.007452)
			(xy 288.055352 -291.992026) (xy 288.009624 -291.969312) (xy 287.988502 -291.954966) (xy 287.981965 -291.950683)
			(xy 287.967099 -291.945894) (xy 287.959292 -291.945568) (xy 287.443418 -291.945568) (xy 287.437987 -291.945209)
			(xy 287.4303 -291.937536) (xy 287.429956 -291.932106) (xy 281.385772 -291.932106) (xy 281.385282 -291.937408)
			(xy 281.377856 -291.944978) (xy 281.372564 -291.945568) (xy 280.85669 -291.945568) (xy 280.848878 -291.945866)
			(xy 280.834007 -291.950662) (xy 280.82748 -291.954966) (xy 280.806363 -291.969322) (xy 280.760637 -291.992047)
			(xy 280.711963 -292.007475) (xy 280.661495 -292.01524) (xy 280.635964 -292.015672) (xy 280.610433 -292.015252)
			(xy 280.559969 -292.007471) (xy 280.511296 -291.992037) (xy 280.465569 -291.969316) (xy 280.444448 -291.954966)
			(xy 280.437923 -291.950662) (xy 280.423048 -291.945886) (xy 280.415238 -291.945568) (xy 279.899364 -291.945568)
			(xy 279.894017 -291.945293) (xy 279.886476 -291.937709) (xy 279.886156 -291.93236) (xy 273.841949 -291.93236)
			(xy 273.841482 -291.937408) (xy 273.834056 -291.944978) (xy 273.828764 -291.945568) (xy 273.31289 -291.945568)
			(xy 273.305078 -291.945866) (xy 273.290207 -291.950662) (xy 273.28368 -291.954966) (xy 273.262563 -291.969322)
			(xy 273.216837 -291.992047) (xy 273.168163 -292.007475) (xy 273.117695 -292.01524) (xy 273.092164 -292.015672)
			(xy 273.066633 -292.015252) (xy 273.016169 -292.007471) (xy 272.967496 -291.992037) (xy 272.921769 -291.969316)
			(xy 272.900648 -291.954966) (xy 272.894123 -291.950662) (xy 272.879248 -291.945886) (xy 272.871438 -291.945568)
			(xy 272.355564 -291.945568) (xy 272.350217 -291.945293) (xy 272.342676 -291.937709) (xy 272.342356 -291.93236)
			(xy 266.298148 -291.93236) (xy 266.297655 -291.937468) (xy 266.290072 -291.945053) (xy 266.28471 -291.945568)
			(xy 265.768836 -291.945568) (xy 265.761026 -291.945886) (xy 265.746154 -291.950668) (xy 265.739626 -291.954966)
			(xy 265.718496 -291.969302) (xy 265.672775 -291.992031) (xy 265.624104 -292.007465) (xy 265.57364 -292.015236)
			(xy 265.54811 -292.015672) (xy 265.52258 -292.015229) (xy 265.472116 -292.007455) (xy 265.423444 -291.992028)
			(xy 265.377716 -291.969313) (xy 265.356594 -291.954966) (xy 265.350059 -291.95068) (xy 265.335192 -291.945893)
			(xy 265.327384 -291.945568) (xy 264.81151 -291.945568) (xy 264.806078 -291.945215) (xy 264.798392 -291.937538)
			(xy 264.798048 -291.932106) (xy 202.89774 -291.932106) (xy 202.89774 -291.93236) (xy 202.897349 -291.937679)
			(xy 202.889849 -291.94522) (xy 202.884532 -291.945568) (xy 202.368658 -291.945568) (xy 202.360782 -291.945842)
			(xy 202.345778 -291.950635) (xy 202.339194 -291.954966) (xy 202.31811 -291.969347) (xy 202.272467 -291.992178)
			(xy 202.223863 -292.007738) (xy 202.173448 -292.015661) (xy 202.147932 -292.01618) (xy 202.122412 -292.015695)
			(xy 202.071984 -292.0078) (xy 202.023373 -291.992238) (xy 201.977735 -291.969382) (xy 201.95667 -291.954966)
			(xy 201.950083 -291.950643) (xy 201.93508 -291.94586) (xy 201.927206 -291.945568) (xy 201.411332 -291.945568)
			(xy 201.405994 -291.945248) (xy 201.398449 -291.937698) (xy 201.398124 -291.93236) (xy 195.35394 -291.93236)
			(xy 195.353549 -291.937679) (xy 195.346049 -291.94522) (xy 195.340732 -291.945568) (xy 194.824858 -291.945568)
			(xy 194.816982 -291.945842) (xy 194.801978 -291.950635) (xy 194.795394 -291.954966) (xy 194.77431 -291.969347)
			(xy 194.728667 -291.992178) (xy 194.680063 -292.007738) (xy 194.629648 -292.015661) (xy 194.604132 -292.01618)
			(xy 194.578612 -292.015695) (xy 194.528184 -292.0078) (xy 194.479573 -291.992238) (xy 194.433935 -291.969382)
			(xy 194.41287 -291.954966) (xy 194.406283 -291.950643) (xy 194.39128 -291.94586) (xy 194.383406 -291.945568)
			(xy 193.867532 -291.945568) (xy 193.862194 -291.945248) (xy 193.854649 -291.937698) (xy 193.854324 -291.93236)
			(xy 187.81014 -291.93236) (xy 187.809749 -291.937679) (xy 187.802249 -291.94522) (xy 187.796932 -291.945568)
			(xy 187.796424 -291.945568) (xy 187.280804 -291.945568) (xy 187.27293 -291.945862) (xy 187.257926 -291.950641)
			(xy 187.25134 -291.954966) (xy 187.230271 -291.969371) (xy 187.184623 -291.992195) (xy 187.136014 -292.00775)
			(xy 187.085595 -292.015665) (xy 187.060078 -292.01618) (xy 187.034559 -292.015672) (xy 186.984132 -292.007784)
			(xy 186.93552 -291.992229) (xy 186.889881 -291.969379) (xy 186.868816 -291.954966) (xy 186.862219 -291.950661)
			(xy 186.847223 -291.945867) (xy 186.839352 -291.945568) (xy 186.323478 -291.945568) (xy 186.318173 -291.945092)
			(xy 186.310604 -291.937655) (xy 186.310016 -291.93236) (xy 180.265832 -291.93236) (xy 180.265449 -291.937681)
			(xy 180.257943 -291.945223) (xy 180.252624 -291.945568) (xy 179.73675 -291.945568) (xy 179.728874 -291.945839)
			(xy 179.71387 -291.950634) (xy 179.707286 -291.954966) (xy 179.686204 -291.969351) (xy 179.640561 -291.99218)
			(xy 179.591956 -292.00774) (xy 179.54154 -292.015661) (xy 179.516024 -292.01618) (xy 179.490503 -292.015699)
			(xy 179.440076 -292.007802) (xy 179.391464 -291.99224) (xy 179.345826 -291.969383) (xy 179.324762 -291.954966)
			(xy 179.318177 -291.95064) (xy 179.303172 -291.945859) (xy 179.295298 -291.945568) (xy 178.779424 -291.945568)
			(xy 178.774085 -291.945253) (xy 178.766541 -291.937699) (xy 178.766216 -291.93236) (xy 172.722032 -291.93236)
			(xy 172.721649 -291.937681) (xy 172.714143 -291.945223) (xy 172.708824 -291.945568) (xy 172.708316 -291.945568)
			(xy 172.192696 -291.945568) (xy 172.184822 -291.945859) (xy 172.169818 -291.95064) (xy 172.163232 -291.954966)
			(xy 172.142165 -291.969374) (xy 172.096516 -291.992198) (xy 172.047907 -292.007751) (xy 171.997488 -292.015665)
			(xy 171.97197 -292.01618) (xy 171.94645 -292.015676) (xy 171.896024 -292.007786) (xy 171.847412 -291.992231)
			(xy 171.801773 -291.96938) (xy 171.780708 -291.954966) (xy 171.774113 -291.950658) (xy 171.759116 -291.945865)
			(xy 171.751244 -291.945568) (xy 171.23537 -291.945568) (xy 171.230064 -291.945098) (xy 171.222495 -291.937657)
			(xy 171.221908 -291.93236) (xy 165.177724 -291.93236) (xy 165.177348 -291.937683) (xy 165.169837 -291.945225)
			(xy 165.164516 -291.945568) (xy 163.691316 -291.945568) (xy 163.685976 -291.945259) (xy 163.678432 -291.9377)
			(xy 163.678108 -291.93236) (xy 56.07812 -291.93236) (xy 56.077747 -291.937684) (xy 56.070235 -291.945226)
			(xy 56.064912 -291.945568) (xy 54.591458 -291.945568) (xy 54.58615 -291.945106) (xy 54.578582 -291.937659)
			(xy 54.577996 -291.93236) (xy 48.533812 -291.93236) (xy 48.533447 -291.937686) (xy 48.525929 -291.945229)
			(xy 48.520604 -291.945568) (xy 48.00473 -291.945568) (xy 47.996853 -291.94583) (xy 47.981849 -291.950631)
			(xy 47.975266 -291.954966) (xy 47.95419 -291.969359) (xy 47.908544 -291.992187) (xy 47.859938 -292.007744)
			(xy 47.809521 -292.015663) (xy 47.784004 -292.01618) (xy 47.758483 -292.015709) (xy 47.708055 -292.007809)
			(xy 47.659444 -291.992244) (xy 47.613806 -291.969384) (xy 47.592742 -291.954966) (xy 47.586161 -291.950632)
			(xy 47.571153 -291.945856) (xy 47.563278 -291.945568) (xy 47.047404 -291.945568) (xy 47.042063 -291.945266)
			(xy 47.034519 -291.937702) (xy 47.034196 -291.93236) (xy 40.990012 -291.93236) (xy 40.989647 -291.937686)
			(xy 40.982129 -291.945229) (xy 40.976804 -291.945568) (xy 40.976296 -291.945568) (xy 40.460676 -291.945568)
			(xy 40.452801 -291.94585) (xy 40.437797 -291.950637) (xy 40.431212 -291.954966) (xy 40.410151 -291.969383)
			(xy 40.3645 -291.992205) (xy 40.315889 -292.007755) (xy 40.265468 -292.015667) (xy 40.23995 -292.01618)
			(xy 40.21443 -292.015686) (xy 40.164003 -292.007793) (xy 40.115391 -291.992235) (xy 40.069753 -291.969381)
			(xy 40.048688 -291.954966) (xy 40.042097 -291.95065) (xy 40.027097 -291.945863) (xy 40.019224 -291.945568)
			(xy 39.50335 -291.945568) (xy 39.498054 -291.945044) (xy 39.49048 -291.937644) (xy 39.489888 -291.93236)
			(xy 33.445704 -291.93236) (xy 33.445346 -291.937688) (xy 33.437823 -291.945231) (xy 33.432496 -291.945568)
			(xy 32.916622 -291.945568) (xy 32.908749 -291.94587) (xy 32.893744 -291.950643) (xy 32.887158 -291.954966)
			(xy 32.866084 -291.969363) (xy 32.820438 -291.992189) (xy 32.771831 -292.007746) (xy 32.721413 -292.015663)
			(xy 32.695896 -292.01618) (xy 32.670375 -292.015713) (xy 32.619947 -292.007812) (xy 32.571335 -291.992246)
			(xy 32.525698 -291.969384) (xy 32.504634 -291.954966) (xy 32.498033 -291.950668) (xy 32.48304 -291.945869)
			(xy 32.47517 -291.945568) (xy 31.959296 -291.945568) (xy 31.953953 -291.945272) (xy 31.94641 -291.937704)
			(xy 31.946088 -291.93236) (xy 25.901904 -291.93236) (xy 25.901546 -291.937688) (xy 25.894023 -291.945231)
			(xy 25.888696 -291.945568) (xy 25.372822 -291.945568) (xy 25.364949 -291.94587) (xy 25.349944 -291.950643)
			(xy 25.343358 -291.954966) (xy 25.322284 -291.969363) (xy 25.276638 -291.992189) (xy 25.228031 -292.007746)
			(xy 25.177613 -292.015663) (xy 25.152096 -292.01618) (xy 25.126575 -292.015713) (xy 25.076147 -292.007812)
			(xy 25.027535 -291.992246) (xy 24.981898 -291.969384) (xy 24.960834 -291.954966) (xy 24.954233 -291.950668)
			(xy 24.93924 -291.945869) (xy 24.93137 -291.945568) (xy 24.415496 -291.945568) (xy 24.410153 -291.945272)
			(xy 24.40261 -291.937704) (xy 24.402288 -291.93236) (xy 18.358104 -291.93236) (xy 18.357746 -291.937688)
			(xy 18.350223 -291.945231) (xy 18.344896 -291.945568) (xy 18.344388 -291.945568) (xy 17.828768 -291.945568)
			(xy 17.820893 -291.945847) (xy 17.805889 -291.950636) (xy 17.799304 -291.954966) (xy 17.778217 -291.969343)
			(xy 17.732576 -291.992174) (xy 17.683972 -292.007736) (xy 17.633558 -292.01566) (xy 17.608042 -292.01618)
			(xy 17.582522 -292.01569) (xy 17.532095 -292.007796) (xy 17.483483 -291.992236) (xy 17.437845 -291.969381)
			(xy 17.41678 -291.954966) (xy 17.410191 -291.950647) (xy 17.395189 -291.945861) (xy 17.387316 -291.945568)
			(xy 16.871442 -291.945568) (xy 16.866145 -291.94505) (xy 16.858572 -291.937645) (xy 16.85798 -291.93236)
			(xy 2.509012 -291.93236) (xy 2.509012 -292.782498) (xy 20.958048 -292.782498) (xy 20.958048 -292.28796)
			(xy 20.958564 -292.282703) (xy 20.965999 -292.275265) (xy 20.971256 -292.274752) (xy 20.971764 -292.274752)
			(xy 21.487638 -292.274752) (xy 21.495447 -292.27442) (xy 21.510318 -292.269647) (xy 21.516848 -292.265354)
			(xy 21.537937 -292.251005) (xy 21.583598 -292.228274) (xy 21.632204 -292.212815) (xy 21.682607 -292.204992)
			(xy 21.733613 -292.204992) (xy 21.784016 -292.212815) (xy 21.832622 -292.228274) (xy 21.878283 -292.251005)
			(xy 21.899372 -292.265354) (xy 21.905913 -292.269629) (xy 21.920776 -292.274423) (xy 21.928582 -292.274752)
			(xy 22.44471 -292.274752) (xy 22.450018 -292.275218) (xy 22.457589 -292.282661) (xy 22.458172 -292.28796)
			(xy 22.458172 -292.782498) (xy 22.458147 -292.782752) (xy 28.502356 -292.782752) (xy 28.502356 -292.782244)
			(xy 28.502356 -292.28796) (xy 28.502864 -292.282701) (xy 28.510305 -292.275263) (xy 28.515564 -292.274752)
			(xy 29.031692 -292.274752) (xy 29.039503 -292.274443) (xy 29.054374 -292.269654) (xy 29.060902 -292.265354)
			(xy 29.081991 -292.251005) (xy 29.127652 -292.228274) (xy 29.176258 -292.212815) (xy 29.226661 -292.204992)
			(xy 29.277667 -292.204992) (xy 29.32807 -292.212815) (xy 29.376676 -292.228274) (xy 29.422337 -292.251005)
			(xy 29.443426 -292.265354) (xy 29.449955 -292.269649) (xy 29.464827 -292.274431) (xy 29.472636 -292.274752)
			(xy 29.988764 -292.274752) (xy 29.994013 -292.275315) (xy 30.001455 -292.282714) (xy 30.001972 -292.28796)
			(xy 30.001972 -292.782498) (xy 30.001948 -292.782752) (xy 36.046156 -292.782752) (xy 36.046156 -292.782244)
			(xy 36.046156 -292.28796) (xy 36.046664 -292.282701) (xy 36.054105 -292.275263) (xy 36.059364 -292.274752)
			(xy 36.575492 -292.274752) (xy 36.583303 -292.274443) (xy 36.598174 -292.269654) (xy 36.604702 -292.265354)
			(xy 36.625791 -292.251005) (xy 36.671452 -292.228274) (xy 36.720058 -292.212815) (xy 36.770461 -292.204992)
			(xy 36.821467 -292.204992) (xy 36.87187 -292.212815) (xy 36.920476 -292.228274) (xy 36.966137 -292.251005)
			(xy 36.987226 -292.265354) (xy 36.993755 -292.269649) (xy 37.008627 -292.274431) (xy 37.016436 -292.274752)
			(xy 37.532564 -292.274752) (xy 37.537813 -292.275315) (xy 37.545255 -292.282714) (xy 37.545772 -292.28796)
			(xy 37.545772 -292.782498) (xy 43.589956 -292.782498) (xy 43.589956 -292.28796) (xy 43.590464 -292.282701)
			(xy 43.597905 -292.275263) (xy 43.603164 -292.274752) (xy 43.603672 -292.274752) (xy 44.119546 -292.274752)
			(xy 44.127355 -292.274423) (xy 44.142227 -292.269648) (xy 44.148756 -292.265354) (xy 44.169845 -292.251005)
			(xy 44.215506 -292.228274) (xy 44.264112 -292.212815) (xy 44.314515 -292.204992) (xy 44.365521 -292.204992)
			(xy 44.415924 -292.212815) (xy 44.46453 -292.228274) (xy 44.510191 -292.251005) (xy 44.53128 -292.265354)
			(xy 44.537819 -292.269632) (xy 44.552683 -292.274424) (xy 44.56049 -292.274752) (xy 45.076618 -292.274752)
			(xy 45.081927 -292.275212) (xy 45.089498 -292.28266) (xy 45.09008 -292.28796) (xy 45.09008 -292.782498)
			(xy 45.090055 -292.782752) (xy 51.134264 -292.782752) (xy 51.134264 -292.782244) (xy 51.134264 -292.28796)
			(xy 51.134765 -292.282699) (xy 51.142211 -292.27526) (xy 51.147472 -292.274752) (xy 51.6636 -292.274752)
			(xy 51.671411 -292.274447) (xy 51.686283 -292.269656) (xy 51.69281 -292.265354) (xy 51.713899 -292.251005)
			(xy 51.75956 -292.228274) (xy 51.808166 -292.212815) (xy 51.858569 -292.204992) (xy 51.909575 -292.204992)
			(xy 51.959978 -292.212815) (xy 52.008584 -292.228274) (xy 52.054245 -292.251005) (xy 52.075334 -292.265354)
			(xy 52.081861 -292.269652) (xy 52.096734 -292.274432) (xy 52.104544 -292.274752) (xy 52.620672 -292.274752)
			(xy 52.625922 -292.275309) (xy 52.633364 -292.282713) (xy 52.63388 -292.28796) (xy 52.63388 -292.782498)
			(xy 58.678064 -292.782498) (xy 58.678064 -292.28796) (xy 58.678565 -292.282699) (xy 58.686011 -292.27526)
			(xy 58.691272 -292.274752) (xy 58.69178 -292.274752) (xy 60.164726 -292.274752) (xy 60.170036 -292.275207)
			(xy 60.177606 -292.282659) (xy 60.178188 -292.28796) (xy 60.178188 -292.7162) (xy 97.675144 -292.7162)
			(xy 97.679316 -292.665857) (xy 97.691717 -292.616887) (xy 97.712009 -292.570626) (xy 97.739639 -292.528337)
			(xy 97.773852 -292.491172) (xy 97.813717 -292.460145) (xy 97.858144 -292.436103) (xy 97.905923 -292.419701)
			(xy 97.95575 -292.411388) (xy 97.981008 -292.410896) (xy 98.921062 -292.410896) (xy 98.946322 -292.411378)
			(xy 98.996154 -292.419687) (xy 99.043938 -292.436087) (xy 99.088372 -292.460128) (xy 99.128241 -292.491155)
			(xy 99.16246 -292.528322) (xy 99.190094 -292.570614) (xy 99.210389 -292.616879) (xy 99.222792 -292.665852)
			(xy 99.226964 -292.7162) (xy 100.495373 -292.7162) (xy 100.499544 -292.665866) (xy 100.511941 -292.616904)
			(xy 100.532229 -292.570651) (xy 100.559852 -292.528367) (xy 100.594057 -292.491206) (xy 100.633913 -292.460182)
			(xy 100.67833 -292.436141) (xy 100.726099 -292.419737) (xy 100.775917 -292.41142) (xy 100.80117 -292.410896)
			(xy 101.741224 -292.410896) (xy 101.766478 -292.411411) (xy 101.816298 -292.419728) (xy 101.864069 -292.436132)
			(xy 101.908489 -292.460173) (xy 101.948346 -292.491198) (xy 101.982553 -292.52836) (xy 102.010177 -292.570645)
			(xy 102.030466 -292.6169) (xy 102.042864 -292.665864) (xy 102.047035 -292.7162) (xy 103.315273 -292.7162)
			(xy 103.319444 -292.665865) (xy 103.331842 -292.616903) (xy 103.35213 -292.570649) (xy 103.379754 -292.528364)
			(xy 103.41396 -292.491204) (xy 103.453817 -292.460179) (xy 103.498236 -292.436138) (xy 103.546006 -292.419736)
			(xy 103.595824 -292.411419) (xy 103.621078 -292.410896) (xy 104.561132 -292.410896) (xy 104.586386 -292.411412)
			(xy 104.636204 -292.41973) (xy 104.683974 -292.436134) (xy 104.728393 -292.460176) (xy 104.768249 -292.491201)
			(xy 104.802455 -292.528363) (xy 104.830079 -292.570648) (xy 104.850366 -292.616902) (xy 104.862764 -292.665865)
			(xy 104.866935 -292.7162) (xy 106.135173 -292.7162) (xy 106.139344 -292.665864) (xy 106.151743 -292.616901)
			(xy 106.172031 -292.570646) (xy 106.199656 -292.528362) (xy 106.233864 -292.491201) (xy 106.273721 -292.460177)
			(xy 106.318141 -292.436136) (xy 106.365912 -292.419734) (xy 106.415732 -292.411419) (xy 106.440986 -292.410896)
			(xy 107.38104 -292.410896) (xy 107.406293 -292.411413) (xy 107.456111 -292.419732) (xy 107.50388 -292.436136)
			(xy 107.548297 -292.460179) (xy 107.588152 -292.491204) (xy 107.622357 -292.528366) (xy 107.64998 -292.57065)
			(xy 107.670267 -292.616904) (xy 107.682665 -292.665865) (xy 107.686835 -292.7162) (xy 107.682665 -292.766535)
			(xy 107.678558 -292.782752) (xy 167.778176 -292.782752) (xy 167.778176 -292.28796) (xy 167.778666 -292.282696)
			(xy 167.786119 -292.275257) (xy 167.791384 -292.274752) (xy 169.264584 -292.274752) (xy 169.269835 -292.275301)
			(xy 169.277276 -292.282711) (xy 169.277792 -292.28796) (xy 169.277792 -292.782498) (xy 175.321976 -292.782498)
			(xy 175.321976 -292.28796) (xy 175.322466 -292.282696) (xy 175.329919 -292.275257) (xy 175.335184 -292.274752)
			(xy 175.335692 -292.274752) (xy 175.851566 -292.274752) (xy 175.859376 -292.274432) (xy 175.874247 -292.269651)
			(xy 175.880776 -292.265354) (xy 175.901865 -292.251005) (xy 175.947526 -292.228274) (xy 175.996132 -292.212815)
			(xy 176.046535 -292.204992) (xy 176.097541 -292.204992) (xy 176.147944 -292.212815) (xy 176.19655 -292.228274)
			(xy 176.242211 -292.251005) (xy 176.2633 -292.265354) (xy 176.269835 -292.269639) (xy 176.284702 -292.274427)
			(xy 176.29251 -292.274752) (xy 176.808638 -292.274752) (xy 176.81395 -292.2752) (xy 176.821519 -292.282657)
			(xy 176.8221 -292.28796) (xy 176.8221 -292.782498) (xy 176.822074 -292.782752) (xy 182.866284 -292.782752)
			(xy 182.866284 -292.782244) (xy 182.866284 -292.28796) (xy 182.866767 -292.282694) (xy 182.874225 -292.275254)
			(xy 182.879492 -292.274752) (xy 183.39562 -292.274752) (xy 183.403432 -292.274455) (xy 183.418303 -292.269659)
			(xy 183.42483 -292.265354) (xy 183.445919 -292.251005) (xy 183.49158 -292.228274) (xy 183.540186 -292.212815)
			(xy 183.590589 -292.204992) (xy 183.641595 -292.204992) (xy 183.691998 -292.212815) (xy 183.740604 -292.228274)
			(xy 183.786265 -292.251005) (xy 183.807354 -292.265354) (xy 183.813877 -292.26966) (xy 183.828753 -292.274435)
			(xy 183.836564 -292.274752) (xy 184.352692 -292.274752) (xy 184.357944 -292.275296) (xy 184.365385 -292.28271)
			(xy 184.3659 -292.28796) (xy 184.3659 -292.782498) (xy 190.410084 -292.782498) (xy 190.410084 -292.28796)
			(xy 190.410567 -292.282694) (xy 190.418025 -292.275254) (xy 190.423292 -292.274752) (xy 190.4238 -292.274752)
			(xy 190.939674 -292.274752) (xy 190.947484 -292.274435) (xy 190.962356 -292.269652) (xy 190.968884 -292.265354)
			(xy 190.989973 -292.251005) (xy 191.035634 -292.228274) (xy 191.08424 -292.212815) (xy 191.134643 -292.204992)
			(xy 191.185649 -292.204992) (xy 191.236052 -292.212815) (xy 191.284658 -292.228274) (xy 191.330319 -292.251005)
			(xy 191.351408 -292.265354) (xy 191.357941 -292.269643) (xy 191.37281 -292.274428) (xy 191.380618 -292.274752)
			(xy 191.896746 -292.274752) (xy 191.902047 -292.275261) (xy 191.909621 -292.282671) (xy 191.910208 -292.28796)
			(xy 191.910208 -292.782498) (xy 191.910182 -292.782752) (xy 197.954392 -292.782752) (xy 197.954392 -292.782244)
			(xy 197.954392 -292.28796) (xy 197.954868 -292.282692) (xy 197.962331 -292.275252) (xy 197.9676 -292.274752)
			(xy 198.483728 -292.274752) (xy 198.49154 -292.274458) (xy 198.506412 -292.26966) (xy 198.512938 -292.265354)
			(xy 198.534027 -292.251005) (xy 198.579688 -292.228274) (xy 198.628294 -292.212815) (xy 198.678697 -292.204992)
			(xy 198.729703 -292.204992) (xy 198.780106 -292.212815) (xy 198.828712 -292.228274) (xy 198.874373 -292.251005)
			(xy 198.895462 -292.265354) (xy 198.902005 -292.269625) (xy 198.916866 -292.274421) (xy 198.924672 -292.274752)
			(xy 199.4408 -292.274752) (xy 199.446053 -292.275291) (xy 199.453493 -292.282708) (xy 199.454008 -292.28796)
			(xy 199.454008 -292.782498) (xy 199.453983 -292.782752) (xy 205.498192 -292.782752) (xy 205.498192 -292.782244)
			(xy 205.498192 -292.28796) (xy 205.498668 -292.282692) (xy 205.506131 -292.275252) (xy 205.5114 -292.274752)
			(xy 206.027528 -292.274752) (xy 206.03534 -292.274458) (xy 206.050212 -292.26966) (xy 206.056738 -292.265354)
			(xy 206.077827 -292.251005) (xy 206.123488 -292.228274) (xy 206.172094 -292.212815) (xy 206.222497 -292.204992)
			(xy 206.273503 -292.204992) (xy 206.323906 -292.212815) (xy 206.372512 -292.228274) (xy 206.418173 -292.251005)
			(xy 206.439262 -292.265354) (xy 206.445805 -292.269625) (xy 206.460666 -292.274421) (xy 206.468472 -292.274752)
			(xy 206.9846 -292.274752) (xy 206.989853 -292.275291) (xy 206.997293 -292.282708) (xy 206.997808 -292.28796)
			(xy 206.997808 -292.782244) (xy 268.898116 -292.782244) (xy 268.898116 -292.287706) (xy 268.898652 -292.282348)
			(xy 268.906221 -292.274763) (xy 268.911578 -292.274244) (xy 269.427706 -292.274244) (xy 269.435517 -292.273942)
			(xy 269.450389 -292.269149) (xy 269.456916 -292.264846) (xy 269.478005 -292.250497) (xy 269.523666 -292.227766)
			(xy 269.572272 -292.212307) (xy 269.622675 -292.204484) (xy 269.673681 -292.204484) (xy 269.724084 -292.212307)
			(xy 269.77269 -292.227766) (xy 269.818351 -292.250497) (xy 269.83944 -292.264846) (xy 269.845967 -292.269146)
			(xy 269.86084 -292.273925) (xy 269.86865 -292.274244) (xy 270.384778 -292.274244) (xy 270.390211 -292.274595)
			(xy 270.397899 -292.282273) (xy 270.39824 -292.287706) (xy 270.39824 -292.782244) (xy 276.442424 -292.782244)
			(xy 276.442424 -292.287706) (xy 276.442925 -292.282406) (xy 276.450343 -292.274836) (xy 276.455632 -292.274244)
			(xy 276.97176 -292.274244) (xy 276.97957 -292.273923) (xy 276.994441 -292.269143) (xy 277.00097 -292.264846)
			(xy 277.022059 -292.250497) (xy 277.06772 -292.227766) (xy 277.116326 -292.212307) (xy 277.166729 -292.204484)
			(xy 277.217735 -292.204484) (xy 277.268138 -292.212307) (xy 277.316744 -292.227766) (xy 277.362405 -292.250497)
			(xy 277.383494 -292.264846) (xy 277.390031 -292.269128) (xy 277.404897 -292.273918) (xy 277.412704 -292.274244)
			(xy 277.928832 -292.274244) (xy 277.934087 -292.274769) (xy 277.941525 -292.282198) (xy 277.94204 -292.287452)
			(xy 277.94204 -292.28796) (xy 277.94204 -292.782244) (xy 283.986224 -292.782244) (xy 283.986224 -292.287706)
			(xy 283.986725 -292.282406) (xy 283.994143 -292.274836) (xy 283.999432 -292.274244) (xy 284.51556 -292.274244)
			(xy 284.52337 -292.273923) (xy 284.538241 -292.269143) (xy 284.54477 -292.264846) (xy 284.565859 -292.250497)
			(xy 284.61152 -292.227766) (xy 284.660126 -292.212307) (xy 284.710529 -292.204484) (xy 284.761535 -292.204484)
			(xy 284.811938 -292.212307) (xy 284.860544 -292.227766) (xy 284.906205 -292.250497) (xy 284.927294 -292.264846)
			(xy 284.933831 -292.269128) (xy 284.948697 -292.273918) (xy 284.956504 -292.274244) (xy 285.472632 -292.274244)
			(xy 285.477887 -292.274769) (xy 285.485325 -292.282198) (xy 285.48584 -292.287452) (xy 285.48584 -292.28796)
			(xy 285.48584 -292.782244) (xy 291.530024 -292.782244) (xy 291.530024 -292.287706) (xy 291.530553 -292.282346)
			(xy 291.538127 -292.274761) (xy 291.543486 -292.274244) (xy 292.059614 -292.274244) (xy 292.067426 -292.273946)
			(xy 292.082297 -292.26915) (xy 292.088824 -292.264846) (xy 292.109913 -292.250497) (xy 292.155574 -292.227766)
			(xy 292.20418 -292.212307) (xy 292.254583 -292.204484) (xy 292.305589 -292.204484) (xy 292.355992 -292.212307)
			(xy 292.404598 -292.227766) (xy 292.450259 -292.250497) (xy 292.471348 -292.264846) (xy 292.477873 -292.269149)
			(xy 292.492748 -292.273926) (xy 292.500558 -292.274244) (xy 293.016686 -292.274244) (xy 293.02212 -292.274589)
			(xy 293.029807 -292.282272) (xy 293.030148 -292.287706) (xy 293.030148 -292.782244) (xy 299.074332 -292.782244)
			(xy 299.074332 -292.287706) (xy 299.074826 -292.282404) (xy 299.082249 -292.274833) (xy 299.08754 -292.274244)
			(xy 299.603668 -292.274244) (xy 299.611478 -292.273926) (xy 299.62635 -292.269144) (xy 299.632878 -292.264846)
			(xy 299.653967 -292.250497) (xy 299.699628 -292.227766) (xy 299.748234 -292.212307) (xy 299.798637 -292.204484)
			(xy 299.849643 -292.204484) (xy 299.900046 -292.212307) (xy 299.948652 -292.227766) (xy 299.994313 -292.250497)
			(xy 300.015402 -292.264846) (xy 300.021937 -292.269131) (xy 300.036804 -292.273919) (xy 300.044612 -292.274244)
			(xy 300.56074 -292.274244) (xy 300.565996 -292.274763) (xy 300.573434 -292.282196) (xy 300.573948 -292.287452)
			(xy 300.573948 -292.28796) (xy 300.573948 -292.782244) (xy 306.618132 -292.782244) (xy 306.618132 -292.287706)
			(xy 306.618654 -292.282344) (xy 306.626233 -292.274758) (xy 306.631594 -292.274244) (xy 308.104794 -292.274244)
			(xy 308.110229 -292.274584) (xy 308.117916 -292.282271) (xy 308.118256 -292.287706) (xy 308.118256 -292.7159)
			(xy 345.615064 -292.7159) (xy 345.619238 -292.665531) (xy 345.631645 -292.616535) (xy 345.651946 -292.57025)
			(xy 345.679589 -292.527937) (xy 345.713818 -292.490751) (xy 345.753702 -292.459706) (xy 345.798151 -292.435648)
			(xy 345.845953 -292.419234) (xy 345.895805 -292.410912) (xy 345.921076 -292.410388) (xy 346.86113 -292.410388)
			(xy 346.886409 -292.410812) (xy 346.936276 -292.419138) (xy 346.984094 -292.435558) (xy 347.028556 -292.459624)
			(xy 347.068452 -292.49068) (xy 347.102692 -292.527878) (xy 347.130343 -292.570204) (xy 347.15065 -292.616504)
			(xy 347.163061 -292.665515) (xy 347.167236 -292.7159) (xy 348.435135 -292.7159) (xy 348.43931 -292.665519)
			(xy 348.451722 -292.616513) (xy 348.47203 -292.570219) (xy 348.499682 -292.527899) (xy 348.533923 -292.490707)
			(xy 348.573819 -292.45966) (xy 348.618281 -292.435603) (xy 348.666097 -292.419193) (xy 348.715961 -292.410878)
			(xy 348.741238 -292.410388) (xy 349.681292 -292.410388) (xy 349.706575 -292.410781) (xy 349.756452 -292.419102)
			(xy 349.804279 -292.43552) (xy 349.848752 -292.459587) (xy 349.888656 -292.490645) (xy 349.922905 -292.527847)
			(xy 349.950562 -292.57018) (xy 349.970875 -292.616487) (xy 349.983289 -292.665506) (xy 349.987465 -292.7159)
			(xy 351.255035 -292.7159) (xy 351.259211 -292.665519) (xy 351.271622 -292.616512) (xy 351.291931 -292.570217)
			(xy 351.319584 -292.527896) (xy 351.353826 -292.490705) (xy 351.393723 -292.459657) (xy 351.438186 -292.435601)
			(xy 351.486003 -292.419191) (xy 351.535869 -292.410877) (xy 351.561146 -292.410388) (xy 352.5012 -292.410388)
			(xy 352.52648 -292.41081) (xy 352.576352 -292.419132) (xy 352.624173 -292.435549) (xy 352.66864 -292.459614)
			(xy 352.70854 -292.490669) (xy 352.742784 -292.527868) (xy 352.770438 -292.570196) (xy 352.790748 -292.616498)
			(xy 352.80316 -292.665512) (xy 352.807336 -292.7159) (xy 354.075064 -292.7159) (xy 354.079238 -292.665533)
			(xy 354.091643 -292.61654) (xy 354.111943 -292.570256) (xy 354.139583 -292.527944) (xy 354.17381 -292.490759)
			(xy 354.21369 -292.459713) (xy 354.258136 -292.435654) (xy 354.305935 -292.419239) (xy 354.355784 -292.410913)
			(xy 354.381054 -292.410388) (xy 355.321108 -292.410388) (xy 355.346388 -292.410811) (xy 355.396258 -292.419134)
			(xy 355.444079 -292.435552) (xy 355.488544 -292.459616) (xy 355.528443 -292.490672) (xy 355.562686 -292.52787)
			(xy 355.590339 -292.570198) (xy 355.610649 -292.6165) (xy 355.62306 -292.665513) (xy 355.627236 -292.7159)
			(xy 355.62306 -292.766287) (xy 355.619019 -292.782244) (xy 415.718244 -292.782244) (xy 415.718244 -292.287706)
			(xy 415.718728 -292.282402) (xy 415.726158 -292.27483) (xy 415.731452 -292.274244) (xy 417.204652 -292.274244)
			(xy 417.209898 -292.274822) (xy 417.21734 -292.28221) (xy 417.21786 -292.287452) (xy 417.21786 -292.782244)
			(xy 423.262044 -292.782244) (xy 423.262044 -292.287706) (xy 423.262384 -292.282271) (xy 423.270071 -292.274584)
			(xy 423.275506 -292.274244) (xy 423.791634 -292.274244) (xy 423.799443 -292.273912) (xy 423.814314 -292.269139)
			(xy 423.820844 -292.264846) (xy 423.841933 -292.250497) (xy 423.887594 -292.227766) (xy 423.9362 -292.212307)
			(xy 423.986603 -292.204484) (xy 424.037609 -292.204484) (xy 424.088012 -292.212307) (xy 424.136618 -292.227766)
			(xy 424.182279 -292.250497) (xy 424.203368 -292.264846) (xy 424.209911 -292.269118) (xy 424.224772 -292.273914)
			(xy 424.232578 -292.274244) (xy 424.748706 -292.274244) (xy 424.754072 -292.274747) (xy 424.761658 -292.282339)
			(xy 424.762168 -292.287706) (xy 424.762168 -292.782244) (xy 430.806352 -292.782244) (xy 430.806352 -292.287706)
			(xy 430.806828 -292.2824) (xy 430.814263 -292.274828) (xy 430.81956 -292.274244) (xy 431.335688 -292.274244)
			(xy 431.343499 -292.273934) (xy 431.35837 -292.269147) (xy 431.364898 -292.264846) (xy 431.385987 -292.250497)
			(xy 431.431648 -292.227766) (xy 431.480254 -292.212307) (xy 431.530657 -292.204484) (xy 431.581663 -292.204484)
			(xy 431.632066 -292.212307) (xy 431.680672 -292.227766) (xy 431.726333 -292.250497) (xy 431.747422 -292.264846)
			(xy 431.753953 -292.269139) (xy 431.768823 -292.273922) (xy 431.776632 -292.274244) (xy 432.29276 -292.274244)
			(xy 432.298007 -292.274816) (xy 432.305449 -292.282209) (xy 432.305968 -292.287452) (xy 432.305968 -292.28796)
			(xy 432.305968 -292.782244) (xy 438.350152 -292.782244) (xy 438.350152 -292.287706) (xy 438.350485 -292.282269)
			(xy 438.358176 -292.274581) (xy 438.363614 -292.274244) (xy 438.879742 -292.274244) (xy 438.887551 -292.273915)
			(xy 438.902423 -292.269141) (xy 438.908952 -292.264846) (xy 438.930041 -292.250497) (xy 438.975702 -292.227766)
			(xy 439.024308 -292.212307) (xy 439.074711 -292.204484) (xy 439.125717 -292.204484) (xy 439.17612 -292.212307)
			(xy 439.224726 -292.227766) (xy 439.270387 -292.250497) (xy 439.291476 -292.264846) (xy 439.298017 -292.269122)
			(xy 439.31288 -292.273915) (xy 439.320686 -292.274244) (xy 439.836814 -292.274244) (xy 439.842181 -292.274742)
			(xy 439.849766 -292.282338) (xy 439.850276 -292.287706) (xy 439.850276 -292.782244) (xy 445.89446 -292.782244)
			(xy 445.89446 -292.287706) (xy 445.894929 -292.282398) (xy 445.902369 -292.274825) (xy 445.907668 -292.274244)
			(xy 446.423796 -292.274244) (xy 446.431607 -292.273938) (xy 446.446479 -292.269148) (xy 446.453006 -292.264846)
			(xy 446.474095 -292.250497) (xy 446.519756 -292.227766) (xy 446.568362 -292.212307) (xy 446.618765 -292.204484)
			(xy 446.669771 -292.204484) (xy 446.720174 -292.212307) (xy 446.76878 -292.227766) (xy 446.814441 -292.250497)
			(xy 446.83553 -292.264846) (xy 446.842059 -292.269142) (xy 446.856931 -292.273923) (xy 446.86474 -292.274244)
			(xy 447.380868 -292.274244) (xy 447.386116 -292.274811) (xy 447.393557 -292.282208) (xy 447.394076 -292.287452)
			(xy 447.394076 -292.28796) (xy 447.394076 -292.782244) (xy 453.43826 -292.782244) (xy 453.43826 -292.287706)
			(xy 453.438729 -292.282398) (xy 453.446169 -292.274825) (xy 453.451468 -292.274244) (xy 453.967596 -292.274244)
			(xy 453.975407 -292.273938) (xy 453.990279 -292.269148) (xy 453.996806 -292.264846) (xy 454.017895 -292.250497)
			(xy 454.063556 -292.227766) (xy 454.112162 -292.212307) (xy 454.162565 -292.204484) (xy 454.213571 -292.204484)
			(xy 454.263974 -292.212307) (xy 454.31258 -292.227766) (xy 454.358241 -292.250497) (xy 454.37933 -292.264846)
			(xy 454.385859 -292.269142) (xy 454.400731 -292.273923) (xy 454.40854 -292.274244) (xy 454.924668 -292.274244)
			(xy 454.929916 -292.274811) (xy 454.937357 -292.282208) (xy 454.937876 -292.287452) (xy 454.937876 -292.28796)
			(xy 454.937876 -292.782244) (xy 454.937431 -292.78752) (xy 454.929947 -292.794962) (xy 454.924668 -292.795452)
			(xy 454.408794 -292.795452) (xy 454.40092 -292.795744) (xy 454.385916 -292.800525) (xy 454.37933 -292.80485)
			(xy 454.358263 -292.819257) (xy 454.312614 -292.842082) (xy 454.264005 -292.857635) (xy 454.213586 -292.865549)
			(xy 454.188068 -292.866064) (xy 454.162548 -292.865564) (xy 454.112121 -292.857674) (xy 454.06351 -292.842117)
			(xy 454.017871 -292.819264) (xy 453.996806 -292.80485) (xy 453.990212 -292.800539) (xy 453.975214 -292.795749)
			(xy 453.967342 -292.795452) (xy 453.451468 -292.795452) (xy 453.446212 -292.794931) (xy 453.438774 -292.7875)
			(xy 453.43826 -292.782244) (xy 447.394076 -292.782244) (xy 447.393631 -292.78752) (xy 447.386147 -292.794962)
			(xy 447.380868 -292.795452) (xy 446.864994 -292.795452) (xy 446.85712 -292.795744) (xy 446.842116 -292.800525)
			(xy 446.83553 -292.80485) (xy 446.814463 -292.819257) (xy 446.768814 -292.842082) (xy 446.720205 -292.857635)
			(xy 446.669786 -292.865549) (xy 446.644268 -292.866064) (xy 446.618748 -292.865564) (xy 446.568321 -292.857674)
			(xy 446.51971 -292.842117) (xy 446.474071 -292.819264) (xy 446.453006 -292.80485) (xy 446.446412 -292.800539)
			(xy 446.431414 -292.795749) (xy 446.423542 -292.795452) (xy 445.907668 -292.795452) (xy 445.902412 -292.794931)
			(xy 445.894974 -292.7875) (xy 445.89446 -292.782244) (xy 439.850276 -292.782244) (xy 439.849831 -292.78752)
			(xy 439.842347 -292.794962) (xy 439.837068 -292.795452) (xy 439.83656 -292.795452) (xy 439.32094 -292.795452)
			(xy 439.313064 -292.795721) (xy 439.29806 -292.800517) (xy 439.291476 -292.80485) (xy 439.270396 -292.819237)
			(xy 439.224752 -292.842066) (xy 439.176147 -292.857625) (xy 439.12573 -292.865546) (xy 439.100214 -292.866064)
			(xy 439.074693 -292.865591) (xy 439.024265 -292.857692) (xy 438.975653 -292.842128) (xy 438.930016 -292.819268)
			(xy 438.908952 -292.80485) (xy 438.90237 -292.800518) (xy 438.887363 -292.795741) (xy 438.879488 -292.795452)
			(xy 438.363614 -292.795452) (xy 438.35831 -292.794967) (xy 438.350737 -292.787538) (xy 438.350152 -292.782244)
			(xy 432.305968 -292.782244) (xy 432.30553 -292.787522) (xy 432.298041 -292.794964) (xy 432.29276 -292.795452)
			(xy 431.776886 -292.795452) (xy 431.769012 -292.795741) (xy 431.754008 -292.800524) (xy 431.747422 -292.80485)
			(xy 431.726357 -292.81926) (xy 431.680708 -292.842084) (xy 431.632098 -292.857637) (xy 431.581678 -292.86555)
			(xy 431.55616 -292.866064) (xy 431.53064 -292.865568) (xy 431.480213 -292.857676) (xy 431.431601 -292.842118)
			(xy 431.385963 -292.819265) (xy 431.364898 -292.80485) (xy 431.358306 -292.800536) (xy 431.343306 -292.795748)
			(xy 431.335434 -292.795452) (xy 430.81956 -292.795452) (xy 430.814303 -292.794936) (xy 430.806865 -292.787501)
			(xy 430.806352 -292.782244) (xy 424.762168 -292.782244) (xy 424.76173 -292.787522) (xy 424.754241 -292.794964)
			(xy 424.74896 -292.795452) (xy 424.748452 -292.795452) (xy 424.232832 -292.795452) (xy 424.224955 -292.795718)
			(xy 424.209952 -292.800516) (xy 424.203368 -292.80485) (xy 424.18229 -292.819241) (xy 424.136645 -292.842069)
			(xy 424.08804 -292.857627) (xy 424.037623 -292.865547) (xy 424.012106 -292.866064) (xy 423.986585 -292.865595)
			(xy 423.936157 -292.857695) (xy 423.887545 -292.842129) (xy 423.841908 -292.819268) (xy 423.820844 -292.80485)
			(xy 423.814264 -292.800515) (xy 423.799255 -292.79574) (xy 423.79138 -292.795452) (xy 423.275506 -292.795452)
			(xy 423.270201 -292.794972) (xy 423.262629 -292.787539) (xy 423.262044 -292.782244) (xy 417.21786 -292.782244)
			(xy 417.217598 -292.787594) (xy 417.210004 -292.795135) (xy 417.204652 -292.795452) (xy 415.731452 -292.795452)
			(xy 415.726194 -292.794941) (xy 415.718757 -292.787502) (xy 415.718244 -292.782244) (xy 355.619019 -292.782244)
			(xy 355.610649 -292.8153) (xy 355.590339 -292.861602) (xy 355.562686 -292.90393) (xy 355.528443 -292.941128)
			(xy 355.488544 -292.972184) (xy 355.444079 -292.996248) (xy 355.396258 -293.012666) (xy 355.346388 -293.020989)
			(xy 355.321108 -293.021512) (xy 354.381054 -293.021512) (xy 354.355784 -293.020887) (xy 354.305935 -293.012561)
			(xy 354.258136 -292.996146) (xy 354.21369 -292.972087) (xy 354.17381 -292.941041) (xy 354.139583 -292.903856)
			(xy 354.111943 -292.861544) (xy 354.091643 -292.81526) (xy 354.079238 -292.766267) (xy 354.075064 -292.7159)
			(xy 352.807336 -292.7159) (xy 352.80316 -292.766288) (xy 352.790748 -292.815302) (xy 352.770438 -292.861604)
			(xy 352.742784 -292.903932) (xy 352.70854 -292.941131) (xy 352.66864 -292.972186) (xy 352.624173 -292.996251)
			(xy 352.576352 -293.012668) (xy 352.52648 -293.02099) (xy 352.5012 -293.021512) (xy 351.561146 -293.021512)
			(xy 351.535869 -293.020923) (xy 351.486003 -293.012609) (xy 351.438186 -292.996199) (xy 351.393723 -292.972143)
			(xy 351.353826 -292.941095) (xy 351.319584 -292.903904) (xy 351.291931 -292.861583) (xy 351.271622 -292.815288)
			(xy 351.259211 -292.766281) (xy 351.255035 -292.7159) (xy 349.987465 -292.7159) (xy 349.983289 -292.766294)
			(xy 349.970875 -292.815313) (xy 349.950562 -292.86162) (xy 349.922905 -292.903953) (xy 349.888656 -292.941155)
			(xy 349.848752 -292.972213) (xy 349.804279 -292.99628) (xy 349.756452 -293.012698) (xy 349.706575 -293.021019)
			(xy 349.681292 -293.021512) (xy 348.741238 -293.021512) (xy 348.715961 -293.020922) (xy 348.666097 -293.012607)
			(xy 348.618281 -292.996197) (xy 348.573819 -292.97214) (xy 348.533923 -292.941093) (xy 348.499682 -292.903901)
			(xy 348.47203 -292.861581) (xy 348.451722 -292.815287) (xy 348.43931 -292.766281) (xy 348.435135 -292.7159)
			(xy 347.167236 -292.7159) (xy 347.163061 -292.766285) (xy 347.15065 -292.815296) (xy 347.130343 -292.861596)
			(xy 347.102692 -292.903922) (xy 347.068452 -292.94112) (xy 347.028556 -292.972176) (xy 346.984094 -292.996242)
			(xy 346.936276 -293.012662) (xy 346.886409 -293.020988) (xy 346.86113 -293.021512) (xy 345.921076 -293.021512)
			(xy 345.895805 -293.020888) (xy 345.845953 -293.012566) (xy 345.798151 -292.996152) (xy 345.753702 -292.972094)
			(xy 345.713818 -292.941049) (xy 345.679589 -292.903863) (xy 345.651946 -292.86155) (xy 345.631645 -292.815265)
			(xy 345.619238 -292.766269) (xy 345.615064 -292.7159) (xy 308.118256 -292.7159) (xy 308.118256 -292.782244)
			(xy 308.117739 -292.7875) (xy 308.110304 -292.794938) (xy 308.105048 -292.795452) (xy 308.10454 -292.795452)
			(xy 306.631594 -292.795452) (xy 306.626287 -292.79498) (xy 306.618716 -292.787541) (xy 306.618132 -292.782244)
			(xy 300.573948 -292.782244) (xy 300.573439 -292.787502) (xy 300.565999 -292.79494) (xy 300.56074 -292.795452)
			(xy 300.044866 -292.795452) (xy 300.036991 -292.795733) (xy 300.021987 -292.800521) (xy 300.015402 -292.80485)
			(xy 299.994314 -292.819226) (xy 299.948673 -292.842058) (xy 299.90007 -292.85762) (xy 299.849656 -292.865544)
			(xy 299.82414 -292.866064) (xy 299.79862 -292.865578) (xy 299.748192 -292.857683) (xy 299.69958 -292.842123)
			(xy 299.653942 -292.819266) (xy 299.632878 -292.80485) (xy 299.62629 -292.800529) (xy 299.611287 -292.795745)
			(xy 299.603414 -292.795452) (xy 299.08754 -292.795452) (xy 299.082292 -292.794883) (xy 299.07485 -292.787488)
			(xy 299.074332 -292.782244) (xy 293.030148 -292.782244) (xy 293.029639 -292.787502) (xy 293.022199 -292.79494)
			(xy 293.01694 -292.795452) (xy 293.016432 -292.795452) (xy 292.500812 -292.795452) (xy 292.492939 -292.795752)
			(xy 292.477935 -292.800527) (xy 292.471348 -292.80485) (xy 292.450276 -292.819249) (xy 292.404629 -292.842076)
			(xy 292.356021 -292.857631) (xy 292.305603 -292.865548) (xy 292.280086 -292.866064) (xy 292.254567 -292.865555)
			(xy 292.20414 -292.857667) (xy 292.155528 -292.842113) (xy 292.109889 -292.819263) (xy 292.088824 -292.80485)
			(xy 292.082226 -292.800546) (xy 292.067231 -292.795752) (xy 292.05936 -292.795452) (xy 291.543486 -292.795452)
			(xy 291.538178 -292.794985) (xy 291.530608 -292.787542) (xy 291.530024 -292.782244) (xy 285.48584 -292.782244)
			(xy 285.485338 -292.787504) (xy 285.477893 -292.794943) (xy 285.472632 -292.795452) (xy 284.956758 -292.795452)
			(xy 284.948883 -292.795729) (xy 284.933879 -292.80052) (xy 284.927294 -292.80485) (xy 284.906209 -292.819229)
			(xy 284.860567 -292.842061) (xy 284.811963 -292.857622) (xy 284.761548 -292.865545) (xy 284.736032 -292.866064)
			(xy 284.710511 -292.865582) (xy 284.660084 -292.857686) (xy 284.611472 -292.842124) (xy 284.565834 -292.819267)
			(xy 284.54477 -292.80485) (xy 284.538184 -292.800525) (xy 284.52318 -292.795744) (xy 284.515306 -292.795452)
			(xy 283.999432 -292.795452) (xy 283.994183 -292.794889) (xy 283.986742 -292.787489) (xy 283.986224 -292.782244)
			(xy 277.94204 -292.782244) (xy 277.941538 -292.787504) (xy 277.934093 -292.794943) (xy 277.928832 -292.795452)
			(xy 277.412958 -292.795452) (xy 277.405083 -292.795729) (xy 277.390079 -292.80052) (xy 277.383494 -292.80485)
			(xy 277.362409 -292.819229) (xy 277.316767 -292.842061) (xy 277.268163 -292.857622) (xy 277.217748 -292.865545)
			(xy 277.192232 -292.866064) (xy 277.166711 -292.865582) (xy 277.116284 -292.857686) (xy 277.067672 -292.842124)
			(xy 277.022034 -292.819267) (xy 277.00097 -292.80485) (xy 276.994384 -292.800525) (xy 276.97938 -292.795744)
			(xy 276.971506 -292.795452) (xy 276.455632 -292.795452) (xy 276.450383 -292.794889) (xy 276.442942 -292.787489)
			(xy 276.442424 -292.782244) (xy 270.39824 -292.782244) (xy 270.397738 -292.787504) (xy 270.390293 -292.794943)
			(xy 270.385032 -292.795452) (xy 270.384524 -292.795452) (xy 269.868904 -292.795452) (xy 269.86103 -292.795749)
			(xy 269.846026 -292.800526) (xy 269.83944 -292.80485) (xy 269.81837 -292.819253) (xy 269.772722 -292.842078)
			(xy 269.724114 -292.857633) (xy 269.673695 -292.865549) (xy 269.648178 -292.866064) (xy 269.622658 -292.865559)
			(xy 269.572232 -292.85767) (xy 269.52362 -292.842115) (xy 269.477981 -292.819264) (xy 269.456916 -292.80485)
			(xy 269.45032 -292.800543) (xy 269.435323 -292.79575) (xy 269.427452 -292.795452) (xy 268.911578 -292.795452)
			(xy 268.906269 -292.79499) (xy 268.898699 -292.787544) (xy 268.898116 -292.782244) (xy 206.997808 -292.782244)
			(xy 206.997808 -292.782498) (xy 206.997281 -292.787791) (xy 206.989881 -292.795359) (xy 206.9846 -292.79596)
			(xy 206.468726 -292.79596) (xy 206.460916 -292.796275) (xy 206.446044 -292.801059) (xy 206.439516 -292.805358)
			(xy 206.418388 -292.819697) (xy 206.372666 -292.842426) (xy 206.323995 -292.857859) (xy 206.27353 -292.865629)
			(xy 206.248 -292.866064) (xy 206.22247 -292.865628) (xy 206.172006 -292.857852) (xy 206.123333 -292.842422)
			(xy 206.077606 -292.819706) (xy 206.056484 -292.805358) (xy 206.049952 -292.801067) (xy 206.035082 -292.796283)
			(xy 206.027274 -292.79596) (xy 205.5114 -292.79596) (xy 205.506056 -292.795669) (xy 205.498512 -292.788097)
			(xy 205.498192 -292.782752) (xy 199.453983 -292.782752) (xy 199.453481 -292.787791) (xy 199.446081 -292.795359)
			(xy 199.4408 -292.79596) (xy 198.924926 -292.79596) (xy 198.917116 -292.796275) (xy 198.902244 -292.801059)
			(xy 198.895716 -292.805358) (xy 198.874588 -292.819697) (xy 198.828866 -292.842426) (xy 198.780195 -292.857859)
			(xy 198.72973 -292.865629) (xy 198.7042 -292.866064) (xy 198.67867 -292.865628) (xy 198.628206 -292.857852)
			(xy 198.579533 -292.842422) (xy 198.533806 -292.819706) (xy 198.512684 -292.805358) (xy 198.506152 -292.801067)
			(xy 198.491282 -292.796283) (xy 198.483474 -292.79596) (xy 197.9676 -292.79596) (xy 197.962256 -292.795669)
			(xy 197.954712 -292.788097) (xy 197.954392 -292.782752) (xy 191.910182 -292.782752) (xy 191.909653 -292.787851)
			(xy 191.902097 -292.795434) (xy 191.896746 -292.79596) (xy 191.380872 -292.79596) (xy 191.37306 -292.796251)
			(xy 191.358188 -292.801052) (xy 191.351662 -292.805358) (xy 191.330549 -292.819721) (xy 191.284822 -292.842444)
			(xy 191.236146 -292.85787) (xy 191.185678 -292.865633) (xy 191.160146 -292.866064) (xy 191.134617 -292.865604)
			(xy 191.084154 -292.857836) (xy 191.035481 -292.842413) (xy 190.989753 -292.819703) (xy 190.96863 -292.805358)
			(xy 190.962088 -292.801085) (xy 190.947226 -292.79629) (xy 190.93942 -292.79596) (xy 190.423546 -292.79596)
			(xy 190.418117 -292.79559) (xy 190.410428 -292.787926) (xy 190.410084 -292.782498) (xy 184.3659 -292.782498)
			(xy 184.36538 -292.787793) (xy 184.357975 -292.795361) (xy 184.352692 -292.79596) (xy 183.836818 -292.79596)
			(xy 183.829008 -292.796271) (xy 183.814136 -292.801058) (xy 183.807608 -292.805358) (xy 183.786482 -292.819701)
			(xy 183.74076 -292.842429) (xy 183.692088 -292.857861) (xy 183.641623 -292.86563) (xy 183.616092 -292.866064)
			(xy 183.590562 -292.865632) (xy 183.540098 -292.857854) (xy 183.491425 -292.842424) (xy 183.445698 -292.819706)
			(xy 183.424576 -292.805358) (xy 183.418046 -292.801064) (xy 183.403175 -292.796282) (xy 183.395366 -292.79596)
			(xy 182.879492 -292.79596) (xy 182.874147 -292.795674) (xy 182.866603 -292.788099) (xy 182.866284 -292.782752)
			(xy 176.822074 -292.782752) (xy 176.821552 -292.787853) (xy 176.813991 -292.795436) (xy 176.808638 -292.79596)
			(xy 176.292764 -292.79596) (xy 176.284955 -292.796291) (xy 176.270083 -292.801064) (xy 176.263554 -292.805358)
			(xy 176.242443 -292.819724) (xy 176.196715 -292.842447) (xy 176.148039 -292.857872) (xy 176.09757 -292.865634)
			(xy 176.072038 -292.866064) (xy 176.046508 -292.865608) (xy 175.996045 -292.857838) (xy 175.947373 -292.842415)
			(xy 175.901645 -292.819703) (xy 175.880522 -292.805358) (xy 175.873981 -292.801082) (xy 175.859119 -292.796289)
			(xy 175.851312 -292.79596) (xy 175.335438 -292.79596) (xy 175.330008 -292.795595) (xy 175.322319 -292.787927)
			(xy 175.321976 -292.782498) (xy 169.277792 -292.782498) (xy 169.277279 -292.787794) (xy 169.269869 -292.795364)
			(xy 169.264584 -292.79596) (xy 167.791384 -292.79596) (xy 167.786038 -292.795679) (xy 167.778495 -292.7881)
			(xy 167.778176 -292.782752) (xy 107.678558 -292.782752) (xy 107.670267 -292.815496) (xy 107.64998 -292.86175)
			(xy 107.622357 -292.904034) (xy 107.588152 -292.941196) (xy 107.548297 -292.972221) (xy 107.50388 -292.996264)
			(xy 107.456111 -293.012668) (xy 107.406293 -293.020987) (xy 107.38104 -293.021512) (xy 106.440986 -293.021512)
			(xy 106.415732 -293.020981) (xy 106.365912 -293.012666) (xy 106.318141 -292.996264) (xy 106.273721 -292.972223)
			(xy 106.233864 -292.941199) (xy 106.199656 -292.904038) (xy 106.172031 -292.861754) (xy 106.151743 -292.815499)
			(xy 106.139344 -292.766536) (xy 106.135173 -292.7162) (xy 104.866935 -292.7162) (xy 104.862764 -292.766535)
			(xy 104.850366 -292.815498) (xy 104.830079 -292.861752) (xy 104.802455 -292.904037) (xy 104.768249 -292.941199)
			(xy 104.728393 -292.972224) (xy 104.683974 -292.996266) (xy 104.636204 -293.01267) (xy 104.586386 -293.020988)
			(xy 104.561132 -293.021512) (xy 103.621078 -293.021512) (xy 103.595824 -293.020981) (xy 103.546006 -293.012664)
			(xy 103.498236 -292.996262) (xy 103.453817 -292.972221) (xy 103.41396 -292.941196) (xy 103.379754 -292.904036)
			(xy 103.35213 -292.861751) (xy 103.331842 -292.815497) (xy 103.319444 -292.766535) (xy 103.315273 -292.7162)
			(xy 102.047035 -292.7162) (xy 102.042864 -292.766536) (xy 102.030466 -292.8155) (xy 102.010177 -292.861755)
			(xy 101.982553 -292.90404) (xy 101.948346 -292.941202) (xy 101.908489 -292.972227) (xy 101.864069 -292.996268)
			(xy 101.816298 -293.012672) (xy 101.766478 -293.020989) (xy 101.741224 -293.021512) (xy 100.80117 -293.021512)
			(xy 100.775917 -293.02098) (xy 100.726099 -293.012663) (xy 100.67833 -292.996259) (xy 100.633913 -292.972218)
			(xy 100.594057 -292.941194) (xy 100.559852 -292.904033) (xy 100.532229 -292.861749) (xy 100.511941 -292.815496)
			(xy 100.499544 -292.766534) (xy 100.495373 -292.7162) (xy 99.226964 -292.7162) (xy 99.222792 -292.766548)
			(xy 99.210389 -292.815521) (xy 99.190094 -292.861786) (xy 99.16246 -292.904078) (xy 99.128241 -292.941245)
			(xy 99.088372 -292.972272) (xy 99.043938 -292.996313) (xy 98.996154 -293.012713) (xy 98.946322 -293.021022)
			(xy 98.921062 -293.021512) (xy 97.981008 -293.021512) (xy 97.95575 -293.021012) (xy 97.905923 -293.012699)
			(xy 97.858144 -292.996297) (xy 97.813717 -292.972255) (xy 97.773852 -292.941228) (xy 97.739639 -292.904063)
			(xy 97.712009 -292.861774) (xy 97.691717 -292.815513) (xy 97.679316 -292.766543) (xy 97.675144 -292.7162)
			(xy 60.178188 -292.7162) (xy 60.178188 -292.782498) (xy 60.177651 -292.787855) (xy 60.170082 -292.79544)
			(xy 60.164726 -292.79596) (xy 58.691526 -292.79596) (xy 58.686094 -292.795603) (xy 58.678406 -292.787929)
			(xy 58.678064 -292.782498) (xy 52.63388 -292.782498) (xy 52.633378 -292.787797) (xy 52.62596 -292.795367)
			(xy 52.620672 -292.79596) (xy 52.104798 -292.79596) (xy 52.096987 -292.796263) (xy 52.082115 -292.801055)
			(xy 52.075588 -292.805358) (xy 52.054468 -292.819709) (xy 52.008743 -292.842435) (xy 51.96007 -292.857865)
			(xy 51.909603 -292.865631) (xy 51.884072 -292.866064) (xy 51.858541 -292.865642) (xy 51.808077 -292.857861)
			(xy 51.759404 -292.842428) (xy 51.713677 -292.819707) (xy 51.692556 -292.805358) (xy 51.68603 -292.801057)
			(xy 51.671156 -292.796279) (xy 51.663346 -292.79596) (xy 51.147472 -292.79596) (xy 51.142124 -292.795687)
			(xy 51.134582 -292.788102) (xy 51.134264 -292.782752) (xy 45.090055 -292.782752) (xy 45.08955 -292.787857)
			(xy 45.081977 -292.795442) (xy 45.076618 -292.79596) (xy 44.560744 -292.79596) (xy 44.552935 -292.796282)
			(xy 44.538063 -292.801061) (xy 44.531534 -292.805358) (xy 44.510429 -292.819733) (xy 44.464699 -292.842453)
			(xy 44.416021 -292.857876) (xy 44.36555 -292.865635) (xy 44.340018 -292.866064) (xy 44.314488 -292.865619)
			(xy 44.264025 -292.857845) (xy 44.215352 -292.842419) (xy 44.169624 -292.819704) (xy 44.148502 -292.805358)
			(xy 44.141966 -292.801074) (xy 44.1271 -292.796286) (xy 44.119292 -292.79596) (xy 43.603418 -292.79596)
			(xy 43.597985 -292.795609) (xy 43.590298 -292.787931) (xy 43.589956 -292.782498) (xy 37.545772 -292.782498)
			(xy 37.545277 -292.787799) (xy 37.537854 -292.79537) (xy 37.532564 -292.79596) (xy 37.01669 -292.79596)
			(xy 37.008878 -292.79626) (xy 36.994007 -292.801054) (xy 36.98748 -292.805358) (xy 36.966362 -292.819713)
			(xy 36.920637 -292.842438) (xy 36.871962 -292.857867) (xy 36.821495 -292.865632) (xy 36.795964 -292.866064)
			(xy 36.770433 -292.865646) (xy 36.719968 -292.857864) (xy 36.671296 -292.84243) (xy 36.625569 -292.819708)
			(xy 36.604448 -292.805358) (xy 36.597924 -292.801054) (xy 36.583048 -292.796278) (xy 36.575238 -292.79596)
			(xy 36.059364 -292.79596) (xy 36.054015 -292.795693) (xy 36.046473 -292.788103) (xy 36.046156 -292.782752)
			(xy 30.001948 -292.782752) (xy 30.001477 -292.787799) (xy 29.994054 -292.79537) (xy 29.988764 -292.79596)
			(xy 29.47289 -292.79596) (xy 29.465078 -292.79626) (xy 29.450207 -292.801054) (xy 29.44368 -292.805358)
			(xy 29.422562 -292.819713) (xy 29.376837 -292.842438) (xy 29.328162 -292.857867) (xy 29.277695 -292.865632)
			(xy 29.252164 -292.866064) (xy 29.226633 -292.865646) (xy 29.176168 -292.857864) (xy 29.127496 -292.84243)
			(xy 29.081769 -292.819708) (xy 29.060648 -292.805358) (xy 29.054124 -292.801054) (xy 29.039248 -292.796278)
			(xy 29.031438 -292.79596) (xy 28.515564 -292.79596) (xy 28.510215 -292.795693) (xy 28.502673 -292.788103)
			(xy 28.502356 -292.782752) (xy 22.458147 -292.782752) (xy 22.457649 -292.787859) (xy 22.450071 -292.795445)
			(xy 22.44471 -292.79596) (xy 21.928836 -292.79596) (xy 21.921026 -292.796279) (xy 21.906154 -292.80106)
			(xy 21.899626 -292.805358) (xy 21.878495 -292.819693) (xy 21.832775 -292.842423) (xy 21.784104 -292.857857)
			(xy 21.73364 -292.865628) (xy 21.70811 -292.866064) (xy 21.68258 -292.865623) (xy 21.632116 -292.857848)
			(xy 21.583444 -292.84242) (xy 21.537716 -292.819705) (xy 21.516594 -292.805358) (xy 21.51006 -292.801071)
			(xy 21.495192 -292.796284) (xy 21.487384 -292.79596) (xy 20.97151 -292.79596) (xy 20.966076 -292.795614)
			(xy 20.958389 -292.787932) (xy 20.958048 -292.782498) (xy 2.509012 -292.782498) (xy 2.509012 -293.632382)
			(xy 16.85798 -293.632382) (xy 16.85798 -293.137844) (xy 16.858355 -293.13252) (xy 16.865866 -293.124978)
			(xy 16.871188 -293.124636) (xy 16.871696 -293.124636) (xy 17.38757 -293.124636) (xy 17.39538 -293.12432)
			(xy 17.410252 -293.119537) (xy 17.41678 -293.115238) (xy 17.437869 -293.100889) (xy 17.48353 -293.078158)
			(xy 17.532136 -293.062699) (xy 17.582539 -293.054876) (xy 17.633545 -293.054876) (xy 17.683948 -293.062699)
			(xy 17.732554 -293.078158) (xy 17.778215 -293.100889) (xy 17.799304 -293.115238) (xy 17.805839 -293.119524)
			(xy 17.820706 -293.124311) (xy 17.828514 -293.124636) (xy 18.344642 -293.124636) (xy 18.34995 -293.125095)
			(xy 18.357519 -293.132544) (xy 18.358104 -293.137844) (xy 18.358104 -293.632382) (xy 18.358077 -293.632636)
			(xy 24.402288 -293.632636) (xy 24.402288 -293.632128) (xy 24.402288 -293.137844) (xy 24.402656 -293.132519)
			(xy 24.410172 -293.124975) (xy 24.415496 -293.124636) (xy 24.931624 -293.124636) (xy 24.939436 -293.124344)
			(xy 24.954308 -293.119544) (xy 24.960834 -293.115238) (xy 24.981923 -293.100889) (xy 25.027584 -293.078158)
			(xy 25.07619 -293.062699) (xy 25.126593 -293.054876) (xy 25.177599 -293.054876) (xy 25.228002 -293.062699)
			(xy 25.276608 -293.078158) (xy 25.322269 -293.100889) (xy 25.343358 -293.115238) (xy 25.349881 -293.119544)
			(xy 25.364757 -293.124319) (xy 25.372568 -293.124636) (xy 25.888696 -293.124636) (xy 25.894038 -293.124934)
			(xy 25.901582 -293.132501) (xy 25.901904 -293.137844) (xy 25.901904 -293.632382) (xy 25.901878 -293.632636)
			(xy 31.946088 -293.632636) (xy 31.946088 -293.632128) (xy 31.946088 -293.137844) (xy 31.946456 -293.132519)
			(xy 31.953972 -293.124975) (xy 31.959296 -293.124636) (xy 32.475424 -293.124636) (xy 32.483236 -293.124344)
			(xy 32.498108 -293.119544) (xy 32.504634 -293.115238) (xy 32.525723 -293.100889) (xy 32.571384 -293.078158)
			(xy 32.61999 -293.062699) (xy 32.670393 -293.054876) (xy 32.721399 -293.054876) (xy 32.771802 -293.062699)
			(xy 32.820408 -293.078158) (xy 32.866069 -293.100889) (xy 32.887158 -293.115238) (xy 32.893681 -293.119544)
			(xy 32.908557 -293.124319) (xy 32.916368 -293.124636) (xy 33.432496 -293.124636) (xy 33.437838 -293.124934)
			(xy 33.445382 -293.132501) (xy 33.445704 -293.137844) (xy 33.445704 -293.632382) (xy 39.489888 -293.632382)
			(xy 39.489888 -293.137844) (xy 39.490256 -293.132519) (xy 39.497772 -293.124975) (xy 39.503096 -293.124636)
			(xy 39.503604 -293.124636) (xy 40.019478 -293.124636) (xy 40.027288 -293.124324) (xy 40.04216 -293.119538)
			(xy 40.048688 -293.115238) (xy 40.069777 -293.100889) (xy 40.115438 -293.078158) (xy 40.164044 -293.062699)
			(xy 40.214447 -293.054876) (xy 40.265453 -293.054876) (xy 40.315856 -293.062699) (xy 40.364462 -293.078158)
			(xy 40.410123 -293.100889) (xy 40.431212 -293.115238) (xy 40.437745 -293.119527) (xy 40.452614 -293.124312)
			(xy 40.460422 -293.124636) (xy 40.97655 -293.124636) (xy 40.981847 -293.125156) (xy 40.989421 -293.132559)
			(xy 40.990012 -293.137844) (xy 40.990012 -293.632382) (xy 40.989985 -293.632636) (xy 47.034196 -293.632636)
			(xy 47.034196 -293.632128) (xy 47.034196 -293.137844) (xy 47.034557 -293.132517) (xy 47.042078 -293.124973)
			(xy 47.047404 -293.124636) (xy 47.563532 -293.124636) (xy 47.571341 -293.124304) (xy 47.586213 -293.119532)
			(xy 47.592742 -293.115238) (xy 47.613831 -293.100889) (xy 47.659492 -293.078158) (xy 47.708098 -293.062699)
			(xy 47.758501 -293.054876) (xy 47.809507 -293.054876) (xy 47.85991 -293.062699) (xy 47.908516 -293.078158)
			(xy 47.954177 -293.100889) (xy 47.975266 -293.115238) (xy 47.981809 -293.119509) (xy 47.99667 -293.124306)
			(xy 48.004476 -293.124636) (xy 48.520604 -293.124636) (xy 48.525948 -293.124929) (xy 48.533491 -293.132499)
			(xy 48.533812 -293.137844) (xy 48.533812 -293.632382) (xy 54.577996 -293.632382) (xy 54.577996 -293.137844)
			(xy 54.578357 -293.132517) (xy 54.585878 -293.124973) (xy 54.591204 -293.124636) (xy 56.064658 -293.124636)
			(xy 56.069956 -293.125151) (xy 56.077529 -293.132558) (xy 56.07812 -293.137844) (xy 56.07812 -293.632382)
			(xy 56.078105 -293.632636) (xy 163.678108 -293.632636) (xy 163.678108 -293.632128) (xy 163.678108 -293.137844)
			(xy 163.678458 -293.132514) (xy 163.685986 -293.124969) (xy 163.691316 -293.124636) (xy 165.164516 -293.124636)
			(xy 165.169861 -293.12492) (xy 165.177404 -293.132497) (xy 165.177724 -293.137844) (xy 165.177724 -293.632382)
			(xy 171.221908 -293.632382) (xy 171.221908 -293.137844) (xy 171.222258 -293.132514) (xy 171.229786 -293.124969)
			(xy 171.235116 -293.124636) (xy 171.235624 -293.124636) (xy 171.751498 -293.124636) (xy 171.759309 -293.124332)
			(xy 171.774181 -293.11954) (xy 171.780708 -293.115238) (xy 171.801797 -293.100889) (xy 171.847458 -293.078158)
			(xy 171.896064 -293.062699) (xy 171.946467 -293.054876) (xy 171.997473 -293.054876) (xy 172.047876 -293.062699)
			(xy 172.096482 -293.078158) (xy 172.142143 -293.100889) (xy 172.163232 -293.115238) (xy 172.169761 -293.119534)
			(xy 172.184633 -293.124315) (xy 172.192442 -293.124636) (xy 172.70857 -293.124636) (xy 172.71387 -293.125143)
			(xy 172.721442 -293.132556) (xy 172.722032 -293.137844) (xy 172.722032 -293.632382) (xy 172.722017 -293.632636)
			(xy 178.766216 -293.632636) (xy 178.766216 -293.632128) (xy 178.766216 -293.137844) (xy 178.766559 -293.132512)
			(xy 178.774092 -293.124967) (xy 178.779424 -293.124636) (xy 179.295552 -293.124636) (xy 179.303361 -293.124313)
			(xy 179.318233 -293.119534) (xy 179.324762 -293.115238) (xy 179.345851 -293.100889) (xy 179.391512 -293.078158)
			(xy 179.440118 -293.062699) (xy 179.490521 -293.054876) (xy 179.541527 -293.054876) (xy 179.59193 -293.062699)
			(xy 179.640536 -293.078158) (xy 179.686197 -293.100889) (xy 179.707286 -293.115238) (xy 179.713825 -293.119517)
			(xy 179.728689 -293.124309) (xy 179.736496 -293.124636) (xy 180.252624 -293.124636) (xy 180.25797 -293.124915)
			(xy 180.265512 -293.132496) (xy 180.265832 -293.137844) (xy 180.265832 -293.632382) (xy 186.310016 -293.632382)
			(xy 186.310016 -293.137844) (xy 186.310359 -293.132512) (xy 186.317892 -293.124967) (xy 186.323224 -293.124636)
			(xy 186.323732 -293.124636) (xy 186.839606 -293.124636) (xy 186.847417 -293.124335) (xy 186.862289 -293.119541)
			(xy 186.868816 -293.115238) (xy 186.889905 -293.100889) (xy 186.935566 -293.078158) (xy 186.984172 -293.062699)
			(xy 187.034575 -293.054876) (xy 187.085581 -293.054876) (xy 187.135984 -293.062699) (xy 187.18459 -293.078158)
			(xy 187.230251 -293.100889) (xy 187.25134 -293.115238) (xy 187.257867 -293.119537) (xy 187.27274 -293.124316)
			(xy 187.28055 -293.124636) (xy 187.796678 -293.124636) (xy 187.801979 -293.125137) (xy 187.809551 -293.132554)
			(xy 187.81014 -293.137844) (xy 187.81014 -293.632382) (xy 187.810124 -293.632636) (xy 193.854324 -293.632636)
			(xy 193.854324 -293.632128) (xy 193.854324 -293.137844) (xy 193.85466 -293.13251) (xy 193.862198 -293.124964)
			(xy 193.867532 -293.124636) (xy 194.38366 -293.124636) (xy 194.39147 -293.124316) (xy 194.406342 -293.119535)
			(xy 194.41287 -293.115238) (xy 194.433959 -293.100889) (xy 194.47962 -293.078158) (xy 194.528226 -293.062699)
			(xy 194.578629 -293.054876) (xy 194.629635 -293.054876) (xy 194.680038 -293.062699) (xy 194.728644 -293.078158)
			(xy 194.774305 -293.100889) (xy 194.795394 -293.115238) (xy 194.801931 -293.11952) (xy 194.816797 -293.12431)
			(xy 194.824604 -293.124636) (xy 195.340732 -293.124636) (xy 195.346079 -293.12491) (xy 195.353621 -293.132495)
			(xy 195.35394 -293.137844) (xy 195.35394 -293.632382) (xy 195.353917 -293.632636) (xy 201.398124 -293.632636)
			(xy 201.398124 -293.632128) (xy 201.398124 -293.137844) (xy 201.39846 -293.13251) (xy 201.405998 -293.124964)
			(xy 201.411332 -293.124636) (xy 201.92746 -293.124636) (xy 201.93527 -293.124316) (xy 201.950142 -293.119535)
			(xy 201.95667 -293.115238) (xy 201.977759 -293.100889) (xy 202.02342 -293.078158) (xy 202.072026 -293.062699)
			(xy 202.122429 -293.054876) (xy 202.173435 -293.054876) (xy 202.223838 -293.062699) (xy 202.272444 -293.078158)
			(xy 202.318105 -293.100889) (xy 202.339194 -293.115238) (xy 202.345731 -293.11952) (xy 202.360597 -293.12431)
			(xy 202.368404 -293.124636) (xy 202.884532 -293.124636) (xy 202.889879 -293.12491) (xy 202.897421 -293.132495)
			(xy 202.89774 -293.137844) (xy 202.89774 -293.632128) (xy 264.798048 -293.632128) (xy 264.798048 -293.13759)
			(xy 264.798545 -293.132222) (xy 264.806142 -293.124637) (xy 264.81151 -293.124128) (xy 265.327638 -293.124128)
			(xy 265.335447 -293.1238) (xy 265.350319 -293.119025) (xy 265.356848 -293.11473) (xy 265.377937 -293.100381)
			(xy 265.423598 -293.07765) (xy 265.472204 -293.062191) (xy 265.522607 -293.054368) (xy 265.573613 -293.054368)
			(xy 265.624016 -293.062191) (xy 265.672622 -293.07765) (xy 265.718283 -293.100381) (xy 265.739372 -293.11473)
			(xy 265.745915 -293.119003) (xy 265.760776 -293.123798) (xy 265.768582 -293.124128) (xy 266.28471 -293.124128)
			(xy 266.290073 -293.124643) (xy 266.297657 -293.132227) (xy 266.298172 -293.13759) (xy 266.298172 -293.632128)
			(xy 272.342356 -293.632128) (xy 272.342356 -293.13759) (xy 272.342818 -293.132281) (xy 272.350264 -293.124709)
			(xy 272.355564 -293.124128) (xy 272.871692 -293.124128) (xy 272.879503 -293.123823) (xy 272.894375 -293.119032)
			(xy 272.900902 -293.11473) (xy 272.921991 -293.100381) (xy 272.967652 -293.07765) (xy 273.016258 -293.062191)
			(xy 273.066661 -293.054368) (xy 273.117667 -293.054368) (xy 273.16807 -293.062191) (xy 273.216676 -293.07765)
			(xy 273.262337 -293.100381) (xy 273.283426 -293.11473) (xy 273.289957 -293.119023) (xy 273.304827 -293.123806)
			(xy 273.312636 -293.124128) (xy 273.828764 -293.124128) (xy 273.8341 -293.124454) (xy 273.841646 -293.132)
			(xy 273.841972 -293.137336) (xy 273.841972 -293.137844) (xy 273.841972 -293.632128) (xy 279.886156 -293.632128)
			(xy 279.886156 -293.13759) (xy 279.886618 -293.132281) (xy 279.894064 -293.124709) (xy 279.899364 -293.124128)
			(xy 280.415492 -293.124128) (xy 280.423303 -293.123823) (xy 280.438175 -293.119032) (xy 280.444702 -293.11473)
			(xy 280.465791 -293.100381) (xy 280.511452 -293.07765) (xy 280.560058 -293.062191) (xy 280.610461 -293.054368)
			(xy 280.661467 -293.054368) (xy 280.71187 -293.062191) (xy 280.760476 -293.07765) (xy 280.806137 -293.100381)
			(xy 280.827226 -293.11473) (xy 280.833757 -293.119023) (xy 280.848627 -293.123806) (xy 280.856436 -293.124128)
			(xy 281.372564 -293.124128) (xy 281.3779 -293.124454) (xy 281.385446 -293.132) (xy 281.385772 -293.137336)
			(xy 281.385772 -293.137844) (xy 281.385772 -293.632128) (xy 287.429956 -293.632128) (xy 287.429956 -293.13759)
			(xy 287.430274 -293.132149) (xy 287.437977 -293.124463) (xy 287.443418 -293.124128) (xy 287.959546 -293.124128)
			(xy 287.967355 -293.123803) (xy 287.982227 -293.119026) (xy 287.988756 -293.11473) (xy 288.009845 -293.100381)
			(xy 288.055506 -293.07765) (xy 288.104112 -293.062191) (xy 288.154515 -293.054368) (xy 288.205521 -293.054368)
			(xy 288.255924 -293.062191) (xy 288.30453 -293.07765) (xy 288.350191 -293.100381) (xy 288.37128 -293.11473)
			(xy 288.377821 -293.119006) (xy 288.392683 -293.1238) (xy 288.40049 -293.124128) (xy 288.916618 -293.124128)
			(xy 288.921982 -293.124637) (xy 288.929566 -293.132226) (xy 288.93008 -293.13759) (xy 288.93008 -293.632128)
			(xy 294.974264 -293.632128) (xy 294.974264 -293.13759) (xy 294.974719 -293.132279) (xy 294.98217 -293.124707)
			(xy 294.987472 -293.124128) (xy 295.5036 -293.124128) (xy 295.511411 -293.123826) (xy 295.526283 -293.119033)
			(xy 295.53281 -293.11473) (xy 295.553899 -293.100381) (xy 295.59956 -293.07765) (xy 295.648166 -293.062191)
			(xy 295.698569 -293.054368) (xy 295.749575 -293.054368) (xy 295.799978 -293.062191) (xy 295.848584 -293.07765)
			(xy 295.894245 -293.100381) (xy 295.915334 -293.11473) (xy 295.921863 -293.119026) (xy 295.936735 -293.123807)
			(xy 295.944544 -293.124128) (xy 296.460672 -293.124128) (xy 296.466009 -293.124449) (xy 296.473554 -293.131998)
			(xy 296.47388 -293.137336) (xy 296.47388 -293.137844) (xy 296.47388 -293.632128) (xy 302.518064 -293.632128)
			(xy 302.518064 -293.13759) (xy 302.518375 -293.132147) (xy 302.526083 -293.12446) (xy 302.531526 -293.124128)
			(xy 304.004726 -293.124128) (xy 304.010091 -293.124632) (xy 304.017674 -293.132225) (xy 304.018188 -293.13759)
			(xy 304.018188 -293.632128) (xy 411.618176 -293.632128) (xy 411.618176 -293.13759) (xy 411.618621 -293.132276)
			(xy 411.626078 -293.124704) (xy 411.631384 -293.124128) (xy 413.104584 -293.124128) (xy 413.109923 -293.124441)
			(xy 413.117467 -293.131997) (xy 413.117792 -293.137336) (xy 413.117792 -293.137844) (xy 413.117792 -293.632128)
			(xy 419.161976 -293.632128) (xy 419.161976 -293.13759) (xy 419.162276 -293.132145) (xy 419.169991 -293.124457)
			(xy 419.175438 -293.124128) (xy 419.691566 -293.124128) (xy 419.699376 -293.123812) (xy 419.714248 -293.119029)
			(xy 419.720776 -293.11473) (xy 419.741865 -293.100381) (xy 419.787526 -293.07765) (xy 419.836132 -293.062191)
			(xy 419.886535 -293.054368) (xy 419.937541 -293.054368) (xy 419.987944 -293.062191) (xy 420.03655 -293.07765)
			(xy 420.082211 -293.100381) (xy 420.1033 -293.11473) (xy 420.109836 -293.119013) (xy 420.124702 -293.123803)
			(xy 420.13251 -293.124128) (xy 420.648638 -293.124128) (xy 420.654004 -293.124624) (xy 420.661587 -293.132223)
			(xy 420.6621 -293.13759) (xy 420.6621 -293.632128) (xy 426.706284 -293.632128) (xy 426.706284 -293.13759)
			(xy 426.706722 -293.132274) (xy 426.714184 -293.124701) (xy 426.719492 -293.124128) (xy 427.23562 -293.124128)
			(xy 427.243432 -293.123835) (xy 427.258304 -293.119036) (xy 427.26483 -293.11473) (xy 427.285919 -293.100381)
			(xy 427.33158 -293.07765) (xy 427.380186 -293.062191) (xy 427.430589 -293.054368) (xy 427.481595 -293.054368)
			(xy 427.531998 -293.062191) (xy 427.580604 -293.07765) (xy 427.626265 -293.100381) (xy 427.647354 -293.11473)
			(xy 427.653878 -293.119034) (xy 427.668754 -293.12381) (xy 427.676564 -293.124128) (xy 428.192692 -293.124128)
			(xy 428.198032 -293.124436) (xy 428.205576 -293.131995) (xy 428.2059 -293.137336) (xy 428.2059 -293.137844)
			(xy 428.2059 -293.632128) (xy 434.250084 -293.632128) (xy 434.250084 -293.13759) (xy 434.250377 -293.132143)
			(xy 434.258097 -293.124454) (xy 434.263546 -293.124128) (xy 434.779674 -293.124128) (xy 434.787484 -293.123815)
			(xy 434.802356 -293.11903) (xy 434.808884 -293.11473) (xy 434.829973 -293.100381) (xy 434.875634 -293.07765)
			(xy 434.92424 -293.062191) (xy 434.974643 -293.054368) (xy 435.025649 -293.054368) (xy 435.076052 -293.062191)
			(xy 435.124658 -293.07765) (xy 435.170319 -293.100381) (xy 435.191408 -293.11473) (xy 435.197943 -293.119016)
			(xy 435.21281 -293.123804) (xy 435.220618 -293.124128) (xy 435.736746 -293.124128) (xy 435.742113 -293.124619)
			(xy 435.749696 -293.132222) (xy 435.750208 -293.13759) (xy 435.750208 -293.632128) (xy 441.794392 -293.632128)
			(xy 441.794392 -293.13759) (xy 441.794911 -293.132296) (xy 441.802318 -293.124728) (xy 441.8076 -293.124128)
			(xy 442.323728 -293.124128) (xy 442.33154 -293.123838) (xy 442.346412 -293.119037) (xy 442.352938 -293.11473)
			(xy 442.374027 -293.100381) (xy 442.419688 -293.07765) (xy 442.468294 -293.062191) (xy 442.518697 -293.054368)
			(xy 442.569703 -293.054368) (xy 442.620106 -293.062191) (xy 442.668712 -293.07765) (xy 442.714373 -293.100381)
			(xy 442.735462 -293.11473) (xy 442.742007 -293.118999) (xy 442.756866 -293.123797) (xy 442.764672 -293.124128)
			(xy 443.2808 -293.124128) (xy 443.286141 -293.12443) (xy 443.293684 -293.131994) (xy 443.294008 -293.137336)
			(xy 443.294008 -293.137844) (xy 443.294008 -293.632128) (xy 449.338192 -293.632128) (xy 449.338192 -293.13759)
			(xy 449.338711 -293.132296) (xy 449.346118 -293.124728) (xy 449.3514 -293.124128) (xy 449.867528 -293.124128)
			(xy 449.87534 -293.123838) (xy 449.890212 -293.119037) (xy 449.896738 -293.11473) (xy 449.917827 -293.100381)
			(xy 449.963488 -293.07765) (xy 450.012094 -293.062191) (xy 450.062497 -293.054368) (xy 450.113503 -293.054368)
			(xy 450.163906 -293.062191) (xy 450.212512 -293.07765) (xy 450.258173 -293.100381) (xy 450.279262 -293.11473)
			(xy 450.285807 -293.118999) (xy 450.300666 -293.123797) (xy 450.308472 -293.124128) (xy 450.8246 -293.124128)
			(xy 450.829941 -293.12443) (xy 450.837484 -293.131994) (xy 450.837808 -293.137336) (xy 450.837808 -293.137844)
			(xy 450.837808 -293.632128) (xy 450.837324 -293.637394) (xy 450.829867 -293.644835) (xy 450.8246 -293.645336)
			(xy 450.308726 -293.645336) (xy 450.30085 -293.645602) (xy 450.285846 -293.650401) (xy 450.279262 -293.654734)
			(xy 450.258184 -293.669125) (xy 450.21254 -293.691954) (xy 450.163934 -293.707512) (xy 450.113517 -293.715431)
			(xy 450.088 -293.715948) (xy 450.06248 -293.715467) (xy 450.012053 -293.707568) (xy 449.963441 -293.692006)
			(xy 449.917803 -293.669149) (xy 449.896738 -293.654734) (xy 449.890138 -293.650434) (xy 449.875144 -293.645638)
			(xy 449.867274 -293.645336) (xy 449.3514 -293.645336) (xy 449.346144 -293.644808) (xy 449.338703 -293.637383)
			(xy 449.338192 -293.632128) (xy 443.294008 -293.632128) (xy 443.293524 -293.637394) (xy 443.286067 -293.644835)
			(xy 443.2808 -293.645336) (xy 442.764926 -293.645336) (xy 442.75705 -293.645602) (xy 442.742046 -293.650401)
			(xy 442.735462 -293.654734) (xy 442.714384 -293.669125) (xy 442.66874 -293.691954) (xy 442.620134 -293.707512)
			(xy 442.569717 -293.715431) (xy 442.5442 -293.715948) (xy 442.51868 -293.715467) (xy 442.468253 -293.707568)
			(xy 442.419641 -293.692006) (xy 442.374003 -293.669149) (xy 442.352938 -293.654734) (xy 442.346338 -293.650434)
			(xy 442.331344 -293.645638) (xy 442.323474 -293.645336) (xy 441.8076 -293.645336) (xy 441.802344 -293.644808)
			(xy 441.794903 -293.637383) (xy 441.794392 -293.632128) (xy 435.750208 -293.632128) (xy 435.749724 -293.637394)
			(xy 435.742267 -293.644835) (xy 435.737 -293.645336) (xy 435.736492 -293.645336) (xy 435.220872 -293.645336)
			(xy 435.212997 -293.645621) (xy 435.197993 -293.650407) (xy 435.191408 -293.654734) (xy 435.170345 -293.669149)
			(xy 435.124695 -293.691972) (xy 435.076085 -293.707524) (xy 435.025664 -293.715435) (xy 435.000146 -293.715948)
			(xy 434.974627 -293.715444) (xy 434.924201 -293.707552) (xy 434.875589 -293.691996) (xy 434.82995 -293.669146)
			(xy 434.808884 -293.654734) (xy 434.802296 -293.650413) (xy 434.787293 -293.64563) (xy 434.77942 -293.645336)
			(xy 434.263546 -293.645336) (xy 434.258242 -293.644843) (xy 434.250667 -293.637421) (xy 434.250084 -293.632128)
			(xy 428.2059 -293.632128) (xy 428.205423 -293.637396) (xy 428.197961 -293.644838) (xy 428.192692 -293.645336)
			(xy 427.676818 -293.645336) (xy 427.668945 -293.645641) (xy 427.653941 -293.650413) (xy 427.647354 -293.654734)
			(xy 427.626279 -293.669129) (xy 427.580633 -293.691957) (xy 427.532027 -293.707514) (xy 427.481609 -293.715432)
			(xy 427.456092 -293.715948) (xy 427.430573 -293.71542) (xy 427.380148 -293.707536) (xy 427.331537 -293.691987)
			(xy 427.285897 -293.669143) (xy 427.26483 -293.654734) (xy 427.258231 -293.650431) (xy 427.243237 -293.645636)
			(xy 427.235366 -293.645336) (xy 426.719492 -293.645336) (xy 426.714235 -293.644813) (xy 426.706795 -293.637384)
			(xy 426.706284 -293.632128) (xy 420.6621 -293.632128) (xy 420.661623 -293.637396) (xy 420.654161 -293.644838)
			(xy 420.648892 -293.645336) (xy 420.648384 -293.645336) (xy 420.132764 -293.645336) (xy 420.124889 -293.645618)
			(xy 420.109885 -293.650406) (xy 420.1033 -293.654734) (xy 420.082212 -293.669109) (xy 420.036571 -293.691942)
			(xy 419.987968 -293.707504) (xy 419.937554 -293.715428) (xy 419.912038 -293.715948) (xy 419.886518 -293.715448)
			(xy 419.836092 -293.707555) (xy 419.787481 -293.691998) (xy 419.741842 -293.669147) (xy 419.720776 -293.654734)
			(xy 419.71419 -293.65041) (xy 419.699186 -293.645628) (xy 419.691312 -293.645336) (xy 419.175438 -293.645336)
			(xy 419.170133 -293.644849) (xy 419.162558 -293.637423) (xy 419.161976 -293.632128) (xy 413.117792 -293.632128)
			(xy 413.117322 -293.637398) (xy 413.109856 -293.64484) (xy 413.104584 -293.645336) (xy 411.631384 -293.645336)
			(xy 411.626126 -293.644819) (xy 411.618686 -293.637386) (xy 411.618176 -293.632128) (xy 304.018188 -293.632128)
			(xy 304.017722 -293.637399) (xy 304.010253 -293.644841) (xy 304.00498 -293.645336) (xy 302.531526 -293.645336)
			(xy 302.526219 -293.644857) (xy 302.518645 -293.637425) (xy 302.518064 -293.632128) (xy 296.47388 -293.632128)
			(xy 296.473421 -293.637401) (xy 296.465947 -293.644844) (xy 296.460672 -293.645336) (xy 295.944798 -293.645336)
			(xy 295.936924 -293.645633) (xy 295.92192 -293.650411) (xy 295.915334 -293.654734) (xy 295.894264 -293.669137)
			(xy 295.848617 -293.691963) (xy 295.800008 -293.707518) (xy 295.749589 -293.715433) (xy 295.724072 -293.715948)
			(xy 295.698553 -293.715431) (xy 295.648128 -293.707543) (xy 295.599516 -293.691991) (xy 295.553876 -293.669145)
			(xy 295.53281 -293.654734) (xy 295.526216 -293.650423) (xy 295.511218 -293.645633) (xy 295.503346 -293.645336)
			(xy 294.987472 -293.645336) (xy 294.982213 -293.644827) (xy 294.974773 -293.637387) (xy 294.974264 -293.632128)
			(xy 288.93008 -293.632128) (xy 288.929621 -293.637401) (xy 288.922147 -293.644844) (xy 288.916872 -293.645336)
			(xy 288.916364 -293.645336) (xy 288.400744 -293.645336) (xy 288.392868 -293.645609) (xy 288.377864 -293.650403)
			(xy 288.37128 -293.654734) (xy 288.350197 -293.669118) (xy 288.304555 -293.691948) (xy 288.25595 -293.707508)
			(xy 288.205534 -293.71543) (xy 288.180018 -293.715948) (xy 288.154498 -293.715458) (xy 288.104071 -293.707562)
			(xy 288.05546 -293.692002) (xy 288.009821 -293.669148) (xy 287.988756 -293.654734) (xy 287.982174 -293.650403)
			(xy 287.967167 -293.645625) (xy 287.959292 -293.645336) (xy 287.443418 -293.645336) (xy 287.43811 -293.644862)
			(xy 287.430537 -293.637426) (xy 287.429956 -293.632128) (xy 281.385772 -293.632128) (xy 281.385488 -293.637473)
			(xy 281.37791 -293.645014) (xy 281.372564 -293.645336) (xy 280.85669 -293.645336) (xy 280.848816 -293.64563)
			(xy 280.833812 -293.65041) (xy 280.827226 -293.654734) (xy 280.806158 -293.669141) (xy 280.76051 -293.691966)
			(xy 280.711901 -293.70752) (xy 280.661482 -293.715434) (xy 280.635964 -293.715948) (xy 280.610445 -293.715435)
			(xy 280.560019 -293.707546) (xy 280.511408 -293.691993) (xy 280.465768 -293.669145) (xy 280.444702 -293.654734)
			(xy 280.43811 -293.65042) (xy 280.42311 -293.645632) (xy 280.415238 -293.645336) (xy 279.899364 -293.645336)
			(xy 279.894104 -293.644832) (xy 279.886665 -293.637389) (xy 279.886156 -293.632128) (xy 273.841972 -293.632128)
			(xy 273.841688 -293.637473) (xy 273.83411 -293.645014) (xy 273.828764 -293.645336) (xy 273.31289 -293.645336)
			(xy 273.305016 -293.64563) (xy 273.290012 -293.65041) (xy 273.283426 -293.654734) (xy 273.262358 -293.669141)
			(xy 273.21671 -293.691966) (xy 273.168101 -293.70752) (xy 273.117682 -293.715434) (xy 273.092164 -293.715948)
			(xy 273.066645 -293.715435) (xy 273.016219 -293.707546) (xy 272.967608 -293.691993) (xy 272.921968 -293.669145)
			(xy 272.900902 -293.654734) (xy 272.89431 -293.65042) (xy 272.87931 -293.645632) (xy 272.871438 -293.645336)
			(xy 272.355564 -293.645336) (xy 272.350304 -293.644832) (xy 272.342865 -293.637389) (xy 272.342356 -293.632128)
			(xy 266.298172 -293.632128) (xy 266.297888 -293.637473) (xy 266.29031 -293.645014) (xy 266.284964 -293.645336)
			(xy 266.284456 -293.645336) (xy 265.768836 -293.645336) (xy 265.76096 -293.645606) (xy 265.745956 -293.650402)
			(xy 265.739372 -293.654734) (xy 265.718292 -293.669121) (xy 265.672648 -293.691951) (xy 265.624043 -293.70751)
			(xy 265.573626 -293.71543) (xy 265.54811 -293.715948) (xy 265.52259 -293.715462) (xy 265.472163 -293.707565)
			(xy 265.423552 -293.692003) (xy 265.377913 -293.669149) (xy 265.356848 -293.654734) (xy 265.350268 -293.650399)
			(xy 265.335259 -293.645624) (xy 265.327384 -293.645336) (xy 264.81151 -293.645336) (xy 264.806202 -293.644867)
			(xy 264.798629 -293.637427) (xy 264.798048 -293.632128) (xy 202.89774 -293.632128) (xy 202.89774 -293.632382)
			(xy 202.897263 -293.637689) (xy 202.889829 -293.645262) (xy 202.884532 -293.645844) (xy 202.368658 -293.645844)
			(xy 202.360849 -293.646175) (xy 202.345978 -293.650948) (xy 202.339448 -293.655242) (xy 202.318338 -293.669609)
			(xy 202.27261 -293.692332) (xy 202.223933 -293.707757) (xy 202.173464 -293.715518) (xy 202.147932 -293.715948)
			(xy 202.122402 -293.715498) (xy 202.071939 -293.707727) (xy 202.023266 -293.692302) (xy 201.977538 -293.669588)
			(xy 201.956416 -293.655242) (xy 201.949878 -293.650962) (xy 201.935013 -293.646171) (xy 201.927206 -293.645844)
			(xy 201.411332 -293.645844) (xy 201.406082 -293.645288) (xy 201.398639 -293.637884) (xy 201.398124 -293.632636)
			(xy 195.353917 -293.632636) (xy 195.353463 -293.637689) (xy 195.346029 -293.645262) (xy 195.340732 -293.645844)
			(xy 194.824858 -293.645844) (xy 194.817049 -293.646175) (xy 194.802178 -293.650948) (xy 194.795648 -293.655242)
			(xy 194.774538 -293.669609) (xy 194.72881 -293.692332) (xy 194.680133 -293.707757) (xy 194.629664 -293.715518)
			(xy 194.604132 -293.715948) (xy 194.578602 -293.715498) (xy 194.528139 -293.707727) (xy 194.479466 -293.692302)
			(xy 194.433738 -293.669588) (xy 194.412616 -293.655242) (xy 194.406078 -293.650962) (xy 194.391213 -293.646171)
			(xy 194.383406 -293.645844) (xy 193.867532 -293.645844) (xy 193.862282 -293.645288) (xy 193.854839 -293.637884)
			(xy 193.854324 -293.632636) (xy 187.810124 -293.632636) (xy 187.809807 -293.63782) (xy 187.802116 -293.645508)
			(xy 187.796678 -293.645844) (xy 187.280804 -293.645844) (xy 187.272993 -293.646152) (xy 187.258122 -293.650941)
			(xy 187.251594 -293.655242) (xy 187.230471 -293.669589) (xy 187.184748 -293.692316) (xy 187.136075 -293.707747)
			(xy 187.085609 -293.715515) (xy 187.060078 -293.715948) (xy 187.034547 -293.715525) (xy 186.984083 -293.707746)
			(xy 186.93541 -293.692313) (xy 186.889683 -293.669592) (xy 186.868562 -293.655242) (xy 186.862036 -293.650942)
			(xy 186.847162 -293.646164) (xy 186.839352 -293.645844) (xy 186.323478 -293.645844) (xy 186.318107 -293.645362)
			(xy 186.310522 -293.637754) (xy 186.310016 -293.632382) (xy 180.265832 -293.632382) (xy 180.265362 -293.637691)
			(xy 180.257923 -293.645264) (xy 180.252624 -293.645844) (xy 179.73675 -293.645844) (xy 179.728941 -293.646172)
			(xy 179.714069 -293.650947) (xy 179.70754 -293.655242) (xy 179.686432 -293.669612) (xy 179.640703 -293.692334)
			(xy 179.592026 -293.707759) (xy 179.541556 -293.715519) (xy 179.516024 -293.715948) (xy 179.490494 -293.715502)
			(xy 179.44003 -293.70773) (xy 179.391358 -293.692303) (xy 179.34563 -293.669589) (xy 179.324508 -293.655242)
			(xy 179.317971 -293.650959) (xy 179.303105 -293.64617) (xy 179.295298 -293.645844) (xy 178.779424 -293.645844)
			(xy 178.774173 -293.645293) (xy 178.766731 -293.637885) (xy 178.766216 -293.632636) (xy 172.722017 -293.632636)
			(xy 172.721706 -293.637822) (xy 172.71401 -293.645511) (xy 172.70857 -293.645844) (xy 172.192696 -293.645844)
			(xy 172.184885 -293.646148) (xy 172.170013 -293.65094) (xy 172.163486 -293.655242) (xy 172.142365 -293.669592)
			(xy 172.096641 -293.692319) (xy 172.047968 -293.707749) (xy 171.997501 -293.715515) (xy 171.97197 -293.715948)
			(xy 171.946439 -293.715529) (xy 171.895974 -293.707749) (xy 171.847302 -293.692314) (xy 171.801575 -293.669592)
			(xy 171.780454 -293.655242) (xy 171.773929 -293.650939) (xy 171.759054 -293.646162) (xy 171.751244 -293.645844)
			(xy 171.23537 -293.645844) (xy 171.229998 -293.645368) (xy 171.222413 -293.637756) (xy 171.221908 -293.632382)
			(xy 165.177724 -293.632382) (xy 165.177261 -293.637692) (xy 165.169817 -293.645267) (xy 165.164516 -293.645844)
			(xy 163.691316 -293.645844) (xy 163.686064 -293.645298) (xy 163.678622 -293.637886) (xy 163.678108 -293.632636)
			(xy 56.078105 -293.632636) (xy 56.077805 -293.637825) (xy 56.070101 -293.645514) (xy 56.064658 -293.645844)
			(xy 54.591458 -293.645844) (xy 54.586085 -293.645376) (xy 54.5785 -293.637758) (xy 54.577996 -293.632382)
			(xy 48.533812 -293.632382) (xy 48.533359 -293.637695) (xy 48.525909 -293.64527) (xy 48.520604 -293.645844)
			(xy 48.00473 -293.645844) (xy 47.99692 -293.646163) (xy 47.982049 -293.650945) (xy 47.97552 -293.655242)
			(xy 47.95439 -293.669578) (xy 47.908669 -293.692308) (xy 47.859998 -293.707742) (xy 47.809534 -293.715513)
			(xy 47.784004 -293.715948) (xy 47.758474 -293.715512) (xy 47.70801 -293.707737) (xy 47.659337 -293.692307)
			(xy 47.61361 -293.66959) (xy 47.592488 -293.655242) (xy 47.585956 -293.650952) (xy 47.571086 -293.646167)
			(xy 47.563278 -293.645844) (xy 47.047404 -293.645844) (xy 47.04215 -293.645306) (xy 47.03471 -293.637888)
			(xy 47.034196 -293.632636) (xy 40.989985 -293.632636) (xy 40.989443 -293.637732) (xy 40.981897 -293.645316)
			(xy 40.97655 -293.645844) (xy 40.460676 -293.645844) (xy 40.452864 -293.64614) (xy 40.437993 -293.650937)
			(xy 40.431466 -293.655242) (xy 40.410351 -293.669601) (xy 40.364625 -293.692326) (xy 40.315949 -293.707753)
			(xy 40.265482 -293.715517) (xy 40.23995 -293.715948) (xy 40.214421 -293.715489) (xy 40.163957 -293.707721)
			(xy 40.115285 -293.692298) (xy 40.069557 -293.669587) (xy 40.048434 -293.655242) (xy 40.041892 -293.650969)
			(xy 40.02703 -293.646174) (xy 40.019224 -293.645844) (xy 39.50335 -293.645844) (xy 39.497976 -293.645381)
			(xy 39.490392 -293.637759) (xy 39.489888 -293.632382) (xy 33.445704 -293.632382) (xy 33.44517 -293.637674)
			(xy 33.437775 -293.645243) (xy 33.432496 -293.645844) (xy 32.916622 -293.645844) (xy 32.908812 -293.64616)
			(xy 32.89394 -293.650944) (xy 32.887412 -293.655242) (xy 32.866284 -293.669581) (xy 32.820562 -293.69231)
			(xy 32.771891 -293.707743) (xy 32.721426 -293.715513) (xy 32.695896 -293.715948) (xy 32.670366 -293.715516)
			(xy 32.619901 -293.70774) (xy 32.571229 -293.692309) (xy 32.525502 -293.669591) (xy 32.50438 -293.655242)
			(xy 32.49785 -293.650949) (xy 32.482979 -293.646166) (xy 32.47517 -293.645844) (xy 31.959296 -293.645844)
			(xy 31.954041 -293.645312) (xy 31.946601 -293.637889) (xy 31.946088 -293.632636) (xy 25.901878 -293.632636)
			(xy 25.90137 -293.637674) (xy 25.893975 -293.645243) (xy 25.888696 -293.645844) (xy 25.372822 -293.645844)
			(xy 25.365012 -293.64616) (xy 25.35014 -293.650944) (xy 25.343612 -293.655242) (xy 25.322484 -293.669581)
			(xy 25.276762 -293.69231) (xy 25.228091 -293.707743) (xy 25.177626 -293.715513) (xy 25.152096 -293.715948)
			(xy 25.126566 -293.715516) (xy 25.076101 -293.70774) (xy 25.027429 -293.692309) (xy 24.981702 -293.669591)
			(xy 24.96058 -293.655242) (xy 24.95405 -293.650949) (xy 24.939179 -293.646166) (xy 24.93137 -293.645844)
			(xy 24.415496 -293.645844) (xy 24.410241 -293.645312) (xy 24.402801 -293.637889) (xy 24.402288 -293.632636)
			(xy 18.358077 -293.632636) (xy 18.357542 -293.637734) (xy 18.349991 -293.645318) (xy 18.344642 -293.645844)
			(xy 17.828768 -293.645844) (xy 17.82096 -293.646179) (xy 17.806088 -293.65095) (xy 17.799558 -293.655242)
			(xy 17.778445 -293.669604) (xy 17.732718 -293.692328) (xy 17.684042 -293.707755) (xy 17.633574 -293.715517)
			(xy 17.608042 -293.715948) (xy 17.582512 -293.715493) (xy 17.532049 -293.707723) (xy 17.483377 -293.6923)
			(xy 17.437648 -293.669588) (xy 17.416526 -293.655242) (xy 17.409985 -293.650966) (xy 17.395122 -293.646173)
			(xy 17.387316 -293.645844) (xy 16.871442 -293.645844) (xy 16.866008 -293.645491) (xy 16.858319 -293.637815)
			(xy 16.85798 -293.632382) (xy 2.509012 -293.632382) (xy 2.509012 -294.48252) (xy 20.958048 -294.48252)
			(xy 20.958048 -293.987982) (xy 20.958539 -293.982613) (xy 20.96614 -293.975028) (xy 20.97151 -293.97452)
			(xy 21.487638 -293.97452) (xy 21.495447 -293.974193) (xy 21.510319 -293.969418) (xy 21.516848 -293.965122)
			(xy 21.537937 -293.950773) (xy 21.583598 -293.928042) (xy 21.632204 -293.912583) (xy 21.682607 -293.90476)
			(xy 21.733613 -293.90476) (xy 21.784016 -293.912583) (xy 21.832622 -293.928042) (xy 21.878283 -293.950773)
			(xy 21.899372 -293.965122) (xy 21.905915 -293.969394) (xy 21.920776 -293.97419) (xy 21.928582 -293.97452)
			(xy 22.44471 -293.97452) (xy 22.450071 -293.975042) (xy 22.457655 -293.982622) (xy 22.458172 -293.987982)
			(xy 22.458172 -294.48252) (xy 28.502356 -294.48252) (xy 28.502356 -293.987982) (xy 28.502813 -293.982672)
			(xy 28.510263 -293.975101) (xy 28.515564 -293.97452) (xy 29.031692 -293.97452) (xy 29.039503 -293.974216)
			(xy 29.054375 -293.969425) (xy 29.060902 -293.965122) (xy 29.081991 -293.950773) (xy 29.127652 -293.928042)
			(xy 29.176258 -293.912583) (xy 29.226661 -293.90476) (xy 29.277667 -293.90476) (xy 29.32807 -293.912583)
			(xy 29.376676 -293.928042) (xy 29.422337 -293.950773) (xy 29.443426 -293.965122) (xy 29.449957 -293.969415)
			(xy 29.464827 -293.974198) (xy 29.472636 -293.97452) (xy 29.988764 -293.97452) (xy 29.994098 -293.974854)
			(xy 30.001643 -293.982394) (xy 30.001972 -293.987728) (xy 30.001972 -293.988236) (xy 30.001972 -294.48252)
			(xy 36.046156 -294.48252) (xy 36.046156 -293.987982) (xy 36.046613 -293.982672) (xy 36.054063 -293.975101)
			(xy 36.059364 -293.97452) (xy 36.575492 -293.97452) (xy 36.583303 -293.974216) (xy 36.598175 -293.969425)
			(xy 36.604702 -293.965122) (xy 36.625791 -293.950773) (xy 36.671452 -293.928042) (xy 36.720058 -293.912583)
			(xy 36.770461 -293.90476) (xy 36.821467 -293.90476) (xy 36.87187 -293.912583) (xy 36.920476 -293.928042)
			(xy 36.966137 -293.950773) (xy 36.987226 -293.965122) (xy 36.993757 -293.969415) (xy 37.008627 -293.974198)
			(xy 37.016436 -293.97452) (xy 37.532564 -293.97452) (xy 37.537898 -293.974854) (xy 37.545443 -293.982394)
			(xy 37.545772 -293.987728) (xy 37.545772 -293.988236) (xy 37.545772 -294.48252) (xy 43.589956 -294.48252)
			(xy 43.589956 -293.987982) (xy 43.59044 -293.982611) (xy 43.598046 -293.975026) (xy 43.603418 -293.97452)
			(xy 44.119546 -293.97452) (xy 44.127355 -293.974197) (xy 44.142228 -293.969419) (xy 44.148756 -293.965122)
			(xy 44.169845 -293.950773) (xy 44.215506 -293.928042) (xy 44.264112 -293.912583) (xy 44.314515 -293.90476)
			(xy 44.365521 -293.90476) (xy 44.415924 -293.912583) (xy 44.46453 -293.928042) (xy 44.510191 -293.950773)
			(xy 44.53128 -293.965122) (xy 44.537821 -293.969397) (xy 44.552684 -293.974192) (xy 44.56049 -293.97452)
			(xy 45.076618 -293.97452) (xy 45.08198 -293.975036) (xy 45.089564 -293.98262) (xy 45.09008 -293.987982)
			(xy 45.09008 -294.48252) (xy 51.134264 -294.48252) (xy 51.134264 -293.987982) (xy 51.134714 -293.98267)
			(xy 51.142168 -293.975098) (xy 51.147472 -293.97452) (xy 51.6636 -293.97452) (xy 51.671412 -293.97422)
			(xy 51.686283 -293.969426) (xy 51.69281 -293.965122) (xy 51.713899 -293.950773) (xy 51.75956 -293.928042)
			(xy 51.808166 -293.912583) (xy 51.858569 -293.90476) (xy 51.909575 -293.90476) (xy 51.959978 -293.912583)
			(xy 52.008584 -293.928042) (xy 52.054245 -293.950773) (xy 52.075334 -293.965122) (xy 52.081863 -293.969418)
			(xy 52.096735 -293.974199) (xy 52.104544 -293.97452) (xy 52.620672 -293.97452) (xy 52.626007 -293.974848)
			(xy 52.633552 -293.982393) (xy 52.63388 -293.987728) (xy 52.63388 -293.988236) (xy 52.63388 -294.48252)
			(xy 58.678064 -294.48252) (xy 58.678064 -293.987982) (xy 58.67837 -293.982538) (xy 58.686081 -293.974852)
			(xy 58.691526 -293.97452) (xy 60.164726 -293.97452) (xy 60.170089 -293.975031) (xy 60.177672 -293.982619)
			(xy 60.178188 -293.987982) (xy 60.178188 -294.3362) (xy 96.735185 -294.3362) (xy 96.739355 -294.285869)
			(xy 96.751752 -294.236911) (xy 96.772037 -294.190661) (xy 96.799657 -294.14838) (xy 96.833859 -294.111221)
			(xy 96.873711 -294.080198) (xy 96.918124 -294.056156) (xy 96.965889 -294.039752) (xy 97.015702 -294.031433)
			(xy 97.040954 -294.030908) (xy 97.981008 -294.030908) (xy 98.006264 -294.031398) (xy 98.056088 -294.039713)
			(xy 98.103863 -294.056116) (xy 98.148287 -294.080158) (xy 98.188148 -294.111184) (xy 98.222358 -294.148348)
			(xy 98.249986 -294.190635) (xy 98.270276 -294.236893) (xy 98.282676 -294.28586) (xy 98.286847 -294.3362)
			(xy 99.555256 -294.3362) (xy 99.559428 -294.285858) (xy 99.571829 -294.236889) (xy 99.592121 -294.19063)
			(xy 99.61975 -294.148341) (xy 99.653964 -294.111178) (xy 99.693828 -294.080152) (xy 99.738255 -294.056111)
			(xy 99.786033 -294.039711) (xy 99.835859 -294.031399) (xy 99.861116 -294.030908) (xy 100.80117 -294.030908)
			(xy 100.826431 -294.031366) (xy 100.876264 -294.039678) (xy 100.924049 -294.056078) (xy 100.968482 -294.08012)
			(xy 101.008353 -294.111149) (xy 101.042571 -294.148317) (xy 101.070205 -294.190611) (xy 101.090501 -294.236876)
			(xy 101.102904 -294.285851) (xy 101.107076 -294.3362) (xy 102.375156 -294.3362) (xy 102.379328 -294.285857)
			(xy 102.391729 -294.236888) (xy 102.412022 -294.190628) (xy 102.439652 -294.148339) (xy 102.473867 -294.111175)
			(xy 102.513732 -294.080149) (xy 102.55816 -294.056109) (xy 102.605939 -294.03971) (xy 102.655766 -294.031399)
			(xy 102.681024 -294.030908) (xy 103.621078 -294.030908) (xy 103.646338 -294.031367) (xy 103.69617 -294.039679)
			(xy 103.743954 -294.05608) (xy 103.788387 -294.080123) (xy 103.828256 -294.111152) (xy 103.862473 -294.14832)
			(xy 103.890107 -294.190613) (xy 103.910401 -294.236878) (xy 103.922804 -294.285852) (xy 103.926976 -294.3362)
			(xy 105.195056 -294.3362) (xy 105.199228 -294.285856) (xy 105.21163 -294.236886) (xy 105.231923 -294.190625)
			(xy 105.259554 -294.148336) (xy 105.29377 -294.111172) (xy 105.333636 -294.080147) (xy 105.378065 -294.056107)
			(xy 105.425846 -294.039708) (xy 105.475674 -294.031398) (xy 105.500932 -294.030908) (xy 106.440986 -294.030908)
			(xy 106.466246 -294.031368) (xy 106.516077 -294.039681) (xy 106.56386 -294.056083) (xy 106.608291 -294.080126)
			(xy 106.648159 -294.111155) (xy 106.682376 -294.148322) (xy 106.710008 -294.190615) (xy 106.730302 -294.236879)
			(xy 106.742704 -294.285853) (xy 106.746876 -294.3362) (xy 106.742704 -294.386547) (xy 106.730302 -294.435521)
			(xy 106.710008 -294.481785) (xy 106.709528 -294.48252) (xy 167.778176 -294.48252) (xy 167.778176 -293.987982)
			(xy 167.778615 -293.982667) (xy 167.786077 -293.975095) (xy 167.791384 -293.97452) (xy 169.264584 -293.97452)
			(xy 169.269921 -293.97484) (xy 169.277465 -293.982391) (xy 169.277792 -293.987728) (xy 169.277792 -294.48252)
			(xy 175.321976 -294.48252) (xy 175.321976 -293.987982) (xy 175.322271 -293.982535) (xy 175.32999 -293.974848)
			(xy 175.335438 -293.97452) (xy 175.851566 -293.97452) (xy 175.859376 -293.974205) (xy 175.874248 -293.969421)
			(xy 175.880776 -293.965122) (xy 175.901865 -293.950773) (xy 175.947526 -293.928042) (xy 175.996132 -293.912583)
			(xy 176.046535 -293.90476) (xy 176.097541 -293.90476) (xy 176.147944 -293.912583) (xy 176.19655 -293.928042)
			(xy 176.242211 -293.950773) (xy 176.2633 -293.965122) (xy 176.269837 -293.969405) (xy 176.284703 -293.974194)
			(xy 176.29251 -293.97452) (xy 176.808638 -293.97452) (xy 176.814002 -293.975024) (xy 176.821584 -293.982617)
			(xy 176.8221 -293.987982) (xy 176.8221 -294.48252) (xy 182.866284 -294.48252) (xy 182.866284 -293.987982)
			(xy 182.866716 -293.982665) (xy 182.874183 -293.975093) (xy 182.879492 -293.97452) (xy 183.39562 -293.97452)
			(xy 183.403432 -293.974228) (xy 183.418304 -293.969428) (xy 183.42483 -293.965122) (xy 183.445919 -293.950773)
			(xy 183.49158 -293.928042) (xy 183.540186 -293.912583) (xy 183.590589 -293.90476) (xy 183.641595 -293.90476)
			(xy 183.691998 -293.912583) (xy 183.740604 -293.928042) (xy 183.786265 -293.950773) (xy 183.807354 -293.965122)
			(xy 183.813879 -293.969425) (xy 183.828754 -293.974202) (xy 183.836564 -293.97452) (xy 184.352692 -293.97452)
			(xy 184.35803 -293.974835) (xy 184.365573 -293.982389) (xy 184.3659 -293.987728) (xy 184.3659 -293.988236)
			(xy 184.3659 -294.48252) (xy 190.410084 -294.48252) (xy 190.410084 -293.987982) (xy 190.410372 -293.982533)
			(xy 190.418096 -293.974846) (xy 190.423546 -293.97452) (xy 190.939674 -293.97452) (xy 190.947485 -293.974209)
			(xy 190.962356 -293.969422) (xy 190.968884 -293.965122) (xy 190.989973 -293.950773) (xy 191.035634 -293.928042)
			(xy 191.08424 -293.912583) (xy 191.134643 -293.90476) (xy 191.185649 -293.90476) (xy 191.236052 -293.912583)
			(xy 191.284658 -293.928042) (xy 191.330319 -293.950773) (xy 191.351408 -293.965122) (xy 191.357943 -293.969408)
			(xy 191.37281 -293.974196) (xy 191.380618 -293.97452) (xy 191.896746 -293.97452) (xy 191.902111 -293.975018)
			(xy 191.909693 -293.982616) (xy 191.910208 -293.987982) (xy 191.910208 -294.48252) (xy 197.954392 -294.48252)
			(xy 197.954392 -293.987982) (xy 197.954905 -293.982687) (xy 197.962316 -293.975119) (xy 197.9676 -293.97452)
			(xy 198.483728 -293.97452) (xy 198.491541 -293.974231) (xy 198.506412 -293.96943) (xy 198.512938 -293.965122)
			(xy 198.534027 -293.950773) (xy 198.579688 -293.928042) (xy 198.628294 -293.912583) (xy 198.678697 -293.90476)
			(xy 198.729703 -293.90476) (xy 198.780106 -293.912583) (xy 198.828712 -293.928042) (xy 198.874373 -293.950773)
			(xy 198.895462 -293.965122) (xy 198.902007 -293.96939) (xy 198.916867 -293.974189) (xy 198.924672 -293.97452)
			(xy 199.4408 -293.97452) (xy 199.446139 -293.974829) (xy 199.453682 -293.982388) (xy 199.454008 -293.987728)
			(xy 199.454008 -293.988236) (xy 199.454008 -294.48252) (xy 205.498192 -294.48252) (xy 205.498192 -293.987982)
			(xy 205.498705 -293.982687) (xy 205.506116 -293.975119) (xy 205.5114 -293.97452) (xy 206.027528 -293.97452)
			(xy 206.035341 -293.974231) (xy 206.050212 -293.96943) (xy 206.056738 -293.965122) (xy 206.077827 -293.950773)
			(xy 206.123488 -293.928042) (xy 206.172094 -293.912583) (xy 206.222497 -293.90476) (xy 206.273503 -293.90476)
			(xy 206.323906 -293.912583) (xy 206.372512 -293.928042) (xy 206.418173 -293.950773) (xy 206.439262 -293.965122)
			(xy 206.445807 -293.96939) (xy 206.460667 -293.974189) (xy 206.468472 -293.97452) (xy 206.9846 -293.97452)
			(xy 206.989939 -293.974829) (xy 206.997482 -293.982388) (xy 206.997808 -293.987728) (xy 206.997808 -293.988236)
			(xy 206.997808 -294.482266) (xy 268.898116 -294.482266) (xy 268.898116 -293.987728) (xy 268.898448 -293.982394)
			(xy 268.90599 -293.974849) (xy 268.911324 -293.97452) (xy 268.911832 -293.97452) (xy 269.427706 -293.97452)
			(xy 269.435518 -293.974222) (xy 269.45039 -293.969427) (xy 269.456916 -293.965122) (xy 269.478005 -293.950773)
			(xy 269.523666 -293.928042) (xy 269.572272 -293.912583) (xy 269.622675 -293.90476) (xy 269.673681 -293.90476)
			(xy 269.724084 -293.912583) (xy 269.77269 -293.928042) (xy 269.818351 -293.950773) (xy 269.83944 -293.965122)
			(xy 269.845968 -293.96942) (xy 269.86084 -293.9742) (xy 269.86865 -293.97452) (xy 270.384778 -293.97452)
			(xy 270.390075 -293.975035) (xy 270.397646 -293.982443) (xy 270.39824 -293.987728) (xy 270.39824 -294.482266)
			(xy 270.398224 -294.48252) (xy 276.442424 -294.48252) (xy 276.442424 -294.482012) (xy 276.442424 -293.987728)
			(xy 276.442749 -293.982392) (xy 276.450296 -293.974847) (xy 276.455632 -293.97452) (xy 276.97176 -293.97452)
			(xy 276.97957 -293.974203) (xy 276.994442 -293.969421) (xy 277.00097 -293.965122) (xy 277.022059 -293.950773)
			(xy 277.06772 -293.928042) (xy 277.116326 -293.912583) (xy 277.166729 -293.90476) (xy 277.217735 -293.90476)
			(xy 277.268138 -293.912583) (xy 277.316744 -293.928042) (xy 277.362405 -293.950773) (xy 277.383494 -293.965122)
			(xy 277.390032 -293.969402) (xy 277.404897 -293.974194) (xy 277.412704 -293.97452) (xy 277.928832 -293.97452)
			(xy 277.934105 -293.974976) (xy 277.941548 -293.982452) (xy 277.94204 -293.987728) (xy 277.94204 -294.482266)
			(xy 277.942017 -294.48252) (xy 283.986224 -294.48252) (xy 283.986224 -294.482012) (xy 283.986224 -293.987728)
			(xy 283.986549 -293.982392) (xy 283.994096 -293.974847) (xy 283.999432 -293.97452) (xy 284.51556 -293.97452)
			(xy 284.52337 -293.974203) (xy 284.538242 -293.969421) (xy 284.54477 -293.965122) (xy 284.565859 -293.950773)
			(xy 284.61152 -293.928042) (xy 284.660126 -293.912583) (xy 284.710529 -293.90476) (xy 284.761535 -293.90476)
			(xy 284.811938 -293.912583) (xy 284.860544 -293.928042) (xy 284.906205 -293.950773) (xy 284.927294 -293.965122)
			(xy 284.933832 -293.969402) (xy 284.948697 -293.974194) (xy 284.956504 -293.97452) (xy 285.472632 -293.97452)
			(xy 285.477905 -293.974976) (xy 285.485348 -293.982452) (xy 285.48584 -293.987728) (xy 285.48584 -294.482266)
			(xy 291.530024 -294.482266) (xy 291.530024 -293.987728) (xy 291.530349 -293.982392) (xy 291.537896 -293.974847)
			(xy 291.543232 -293.97452) (xy 291.54374 -293.97452) (xy 292.059614 -293.97452) (xy 292.067426 -293.974226)
			(xy 292.082298 -293.969428) (xy 292.088824 -293.965122) (xy 292.109913 -293.950773) (xy 292.155574 -293.928042)
			(xy 292.20418 -293.912583) (xy 292.254583 -293.90476) (xy 292.305589 -293.90476) (xy 292.355992 -293.912583)
			(xy 292.404598 -293.928042) (xy 292.450259 -293.950773) (xy 292.471348 -293.965122) (xy 292.477874 -293.969423)
			(xy 292.492748 -293.974201) (xy 292.500558 -293.97452) (xy 293.016686 -293.97452) (xy 293.021984 -293.97503)
			(xy 293.029554 -293.982442) (xy 293.030148 -293.987728) (xy 293.030148 -294.482266) (xy 293.030132 -294.48252)
			(xy 299.074332 -294.48252) (xy 299.074332 -294.482012) (xy 299.074332 -293.987728) (xy 299.074649 -293.98239)
			(xy 299.082201 -293.974845) (xy 299.08754 -293.97452) (xy 299.603668 -293.97452) (xy 299.611478 -293.974206)
			(xy 299.62635 -293.969422) (xy 299.632878 -293.965122) (xy 299.653967 -293.950773) (xy 299.699628 -293.928042)
			(xy 299.748234 -293.912583) (xy 299.798637 -293.90476) (xy 299.849643 -293.90476) (xy 299.900046 -293.912583)
			(xy 299.948652 -293.928042) (xy 299.994313 -293.950773) (xy 300.015402 -293.965122) (xy 300.021938 -293.969405)
			(xy 300.036804 -293.974195) (xy 300.044612 -293.97452) (xy 300.56074 -293.97452) (xy 300.566014 -293.974971)
			(xy 300.573456 -293.982451) (xy 300.573948 -293.987728) (xy 300.573948 -294.482266) (xy 306.618132 -294.482266)
			(xy 306.618132 -293.987728) (xy 306.618449 -293.98239) (xy 306.626001 -293.974845) (xy 306.63134 -293.97452)
			(xy 306.631848 -293.97452) (xy 308.104794 -293.97452) (xy 308.110093 -293.975025) (xy 308.117663 -293.98244)
			(xy 308.118256 -293.987728) (xy 308.118256 -294.336) (xy 344.674847 -294.336) (xy 344.679023 -294.285607)
			(xy 344.691437 -294.236588) (xy 344.71175 -294.190281) (xy 344.739408 -294.14795) (xy 344.773657 -294.110748)
			(xy 344.813562 -294.079692) (xy 344.858035 -294.055627) (xy 344.905862 -294.039211) (xy 344.955739 -294.030891)
			(xy 344.981022 -294.0304) (xy 345.921076 -294.0304) (xy 345.946353 -294.030967) (xy 345.996218 -294.039284)
			(xy 346.044033 -294.055696) (xy 346.088495 -294.079755) (xy 346.128391 -294.110804) (xy 346.162631 -294.147996)
			(xy 346.190283 -294.190317) (xy 346.210591 -294.236612) (xy 346.223002 -294.285619) (xy 346.227177 -294.336)
			(xy 347.495076 -294.336) (xy 347.499251 -294.285615) (xy 347.511662 -294.236605) (xy 347.53197 -294.190306)
			(xy 347.559621 -294.14798) (xy 347.593862 -294.110783) (xy 347.633758 -294.079729) (xy 347.678221 -294.055665)
			(xy 347.726038 -294.039247) (xy 347.775905 -294.030923) (xy 347.801184 -294.0304) (xy 348.741238 -294.0304)
			(xy 348.766509 -294.031001) (xy 348.816361 -294.039325) (xy 348.864164 -294.055741) (xy 348.908612 -294.0798)
			(xy 348.948495 -294.110847) (xy 348.982724 -294.148034) (xy 349.010366 -294.190348) (xy 349.030668 -294.236634)
			(xy 349.043074 -294.28563) (xy 349.047248 -294.336) (xy 350.314976 -294.336) (xy 350.319151 -294.285615)
			(xy 350.331563 -294.236603) (xy 350.351871 -294.190304) (xy 350.379523 -294.147978) (xy 350.413765 -294.11078)
			(xy 350.453662 -294.079726) (xy 350.498126 -294.055663) (xy 350.545945 -294.039245) (xy 350.595813 -294.030923)
			(xy 350.621092 -294.0304) (xy 351.561146 -294.0304) (xy 351.586417 -294.031001) (xy 351.636268 -294.039327)
			(xy 351.684069 -294.055743) (xy 351.728516 -294.079803) (xy 351.768398 -294.11085) (xy 351.802626 -294.148037)
			(xy 351.830268 -294.19035) (xy 351.850568 -294.236636) (xy 351.862974 -294.285631) (xy 351.867148 -294.336)
			(xy 353.134877 -294.336) (xy 353.139052 -294.285614) (xy 353.151463 -294.236602) (xy 353.171772 -294.190301)
			(xy 353.199426 -294.147975) (xy 353.233668 -294.110778) (xy 353.273566 -294.079724) (xy 353.318032 -294.05566)
			(xy 353.365851 -294.039244) (xy 353.415721 -294.030922) (xy 353.441 -294.0304) (xy 354.381054 -294.0304)
			(xy 354.406332 -294.030965) (xy 354.4562 -294.03928) (xy 354.504018 -294.05569) (xy 354.548484 -294.079747)
			(xy 354.588382 -294.110796) (xy 354.622625 -294.147989) (xy 354.650279 -294.190311) (xy 354.670589 -294.236608)
			(xy 354.683001 -294.285617) (xy 354.687177 -294.336) (xy 354.683001 -294.386383) (xy 354.670589 -294.435392)
			(xy 354.650279 -294.481689) (xy 354.649736 -294.48252) (xy 415.718244 -294.48252) (xy 415.718244 -293.987728)
			(xy 415.718808 -293.98248) (xy 415.726207 -293.975039) (xy 415.731452 -293.97452) (xy 417.204652 -293.97452)
			(xy 417.209985 -293.974862) (xy 417.21753 -293.982396) (xy 417.21786 -293.987728) (xy 417.21786 -294.482266)
			(xy 423.262044 -294.482266) (xy 423.262044 -293.987728) (xy 423.262608 -293.98248) (xy 423.270007 -293.975039)
			(xy 423.275252 -293.97452) (xy 423.27576 -293.97452) (xy 423.791634 -293.97452) (xy 423.799443 -293.974192)
			(xy 423.814315 -293.969417) (xy 423.820844 -293.965122) (xy 423.841933 -293.950773) (xy 423.887594 -293.928042)
			(xy 423.9362 -293.912583) (xy 423.986603 -293.90476) (xy 424.037609 -293.90476) (xy 424.088012 -293.912583)
			(xy 424.136618 -293.928042) (xy 424.182279 -293.950773) (xy 424.203368 -293.965122) (xy 424.209912 -293.969392)
			(xy 424.224772 -293.97419) (xy 424.232578 -293.97452) (xy 424.748706 -293.97452) (xy 424.754006 -293.975017)
			(xy 424.761576 -293.982438) (xy 424.762168 -293.987728) (xy 424.762168 -294.482266) (xy 424.762151 -294.48252)
			(xy 430.806352 -294.48252) (xy 430.806352 -294.482012) (xy 430.806352 -293.987728) (xy 430.806909 -293.982478)
			(xy 430.814313 -293.975036) (xy 430.81956 -293.97452) (xy 431.335688 -293.97452) (xy 431.343499 -293.974215)
			(xy 431.358371 -293.969424) (xy 431.364898 -293.965122) (xy 431.385987 -293.950773) (xy 431.431648 -293.928042)
			(xy 431.480254 -293.912583) (xy 431.530657 -293.90476) (xy 431.581663 -293.90476) (xy 431.632066 -293.912583)
			(xy 431.680672 -293.928042) (xy 431.726333 -293.950773) (xy 431.747422 -293.965122) (xy 431.753954 -293.969413)
			(xy 431.768823 -293.974198) (xy 431.776632 -293.97452) (xy 432.29276 -293.97452) (xy 432.298094 -293.974857)
			(xy 432.305639 -293.982395) (xy 432.305968 -293.987728) (xy 432.305968 -294.482266) (xy 438.350152 -294.482266)
			(xy 438.350152 -293.987728) (xy 438.350709 -293.982478) (xy 438.358113 -293.975036) (xy 438.36336 -293.97452)
			(xy 438.363868 -293.97452) (xy 438.879742 -293.97452) (xy 438.887551 -293.974195) (xy 438.902423 -293.969418)
			(xy 438.908952 -293.965122) (xy 438.930041 -293.950773) (xy 438.975702 -293.928042) (xy 439.024308 -293.912583)
			(xy 439.074711 -293.90476) (xy 439.125717 -293.90476) (xy 439.17612 -293.912583) (xy 439.224726 -293.928042)
			(xy 439.270387 -293.950773) (xy 439.291476 -293.965122) (xy 439.298018 -293.969395) (xy 439.31288 -293.974191)
			(xy 439.320686 -293.97452) (xy 439.836814 -293.97452) (xy 439.842115 -293.975012) (xy 439.849684 -293.982437)
			(xy 439.850276 -293.987728) (xy 439.850276 -294.482266) (xy 439.850258 -294.48252) (xy 445.89446 -294.48252)
			(xy 445.89446 -294.482012) (xy 445.89446 -293.987728) (xy 445.89501 -293.982476) (xy 445.902419 -293.975034)
			(xy 445.907668 -293.97452) (xy 446.423796 -293.97452) (xy 446.431607 -293.974218) (xy 446.446479 -293.969425)
			(xy 446.453006 -293.965122) (xy 446.474095 -293.950773) (xy 446.519756 -293.928042) (xy 446.568362 -293.912583)
			(xy 446.618765 -293.90476) (xy 446.669771 -293.90476) (xy 446.720174 -293.912583) (xy 446.76878 -293.928042)
			(xy 446.814441 -293.950773) (xy 446.83553 -293.965122) (xy 446.84206 -293.969416) (xy 446.856931 -293.974199)
			(xy 446.86474 -293.97452) (xy 447.380868 -293.97452) (xy 447.386203 -293.974851) (xy 447.393747 -293.982393)
			(xy 447.394076 -293.987728) (xy 447.394076 -294.482266) (xy 447.394051 -294.48252) (xy 453.43826 -294.48252)
			(xy 453.43826 -294.482012) (xy 453.43826 -293.987728) (xy 453.43881 -293.982476) (xy 453.446219 -293.975034)
			(xy 453.451468 -293.97452) (xy 453.967596 -293.97452) (xy 453.975407 -293.974218) (xy 453.990279 -293.969425)
			(xy 453.996806 -293.965122) (xy 454.017895 -293.950773) (xy 454.063556 -293.928042) (xy 454.112162 -293.912583)
			(xy 454.162565 -293.90476) (xy 454.213571 -293.90476) (xy 454.263974 -293.912583) (xy 454.31258 -293.928042)
			(xy 454.358241 -293.950773) (xy 454.37933 -293.965122) (xy 454.38586 -293.969416) (xy 454.400731 -293.974199)
			(xy 454.40854 -293.97452) (xy 454.924668 -293.97452) (xy 454.930003 -293.974851) (xy 454.937547 -293.982393)
			(xy 454.937876 -293.987728) (xy 454.937876 -294.482266) (xy 454.937356 -294.487562) (xy 454.929952 -294.495135)
			(xy 454.924668 -294.495728) (xy 454.408794 -294.495728) (xy 454.400983 -294.496034) (xy 454.386112 -294.500825)
			(xy 454.379584 -294.505126) (xy 454.358462 -294.519475) (xy 454.312739 -294.542203) (xy 454.264065 -294.557633)
			(xy 454.213599 -294.565399) (xy 454.188068 -294.565832) (xy 454.162537 -294.565417) (xy 454.112072 -294.557636)
			(xy 454.063399 -294.5422) (xy 454.017673 -294.519477) (xy 453.996552 -294.505126) (xy 453.990029 -294.50082)
			(xy 453.975152 -294.496046) (xy 453.967342 -294.495728) (xy 453.451468 -294.495728) (xy 453.446206 -294.495229)
			(xy 453.438767 -294.487782) (xy 453.43826 -294.48252) (xy 447.394051 -294.48252) (xy 447.393556 -294.487562)
			(xy 447.386152 -294.495135) (xy 447.380868 -294.495728) (xy 446.864994 -294.495728) (xy 446.857183 -294.496034)
			(xy 446.842312 -294.500825) (xy 446.835784 -294.505126) (xy 446.814662 -294.519475) (xy 446.768939 -294.542203)
			(xy 446.720265 -294.557633) (xy 446.669799 -294.565399) (xy 446.644268 -294.565832) (xy 446.618737 -294.565417)
			(xy 446.568272 -294.557636) (xy 446.519599 -294.5422) (xy 446.473873 -294.519477) (xy 446.452752 -294.505126)
			(xy 446.446229 -294.50082) (xy 446.431352 -294.496046) (xy 446.423542 -294.495728) (xy 445.907668 -294.495728)
			(xy 445.902406 -294.495229) (xy 445.894967 -294.487782) (xy 445.89446 -294.48252) (xy 439.850258 -294.48252)
			(xy 439.849899 -294.487693) (xy 439.84224 -294.49538) (xy 439.836814 -294.495728) (xy 439.32094 -294.495728)
			(xy 439.313131 -294.496054) (xy 439.298259 -294.500831) (xy 439.29173 -294.505126) (xy 439.270623 -294.519499)
			(xy 439.224894 -294.542221) (xy 439.176216 -294.557645) (xy 439.125746 -294.565403) (xy 439.100214 -294.565832)
			(xy 439.074684 -294.565394) (xy 439.02422 -294.55762) (xy 438.975547 -294.542191) (xy 438.92982 -294.519474)
			(xy 438.908698 -294.505126) (xy 438.902165 -294.500838) (xy 438.887296 -294.496053) (xy 438.879488 -294.495728)
			(xy 438.363614 -294.495728) (xy 438.358173 -294.495408) (xy 438.350484 -294.487708) (xy 438.350152 -294.482266)
			(xy 432.305968 -294.482266) (xy 432.305455 -294.487564) (xy 432.298047 -294.495137) (xy 432.29276 -294.495728)
			(xy 431.776886 -294.495728) (xy 431.769075 -294.496031) (xy 431.754203 -294.500824) (xy 431.747676 -294.505126)
			(xy 431.726557 -294.519479) (xy 431.680832 -294.542205) (xy 431.632158 -294.557635) (xy 431.581691 -294.5654)
			(xy 431.55616 -294.565832) (xy 431.530629 -294.565421) (xy 431.480164 -294.557639) (xy 431.431491 -294.542202)
			(xy 431.385765 -294.519477) (xy 431.364644 -294.505126) (xy 431.358123 -294.500817) (xy 431.343245 -294.496045)
			(xy 431.335434 -294.495728) (xy 430.81956 -294.495728) (xy 430.814297 -294.495234) (xy 430.806858 -294.487784)
			(xy 430.806352 -294.48252) (xy 424.762151 -294.48252) (xy 424.761799 -294.487695) (xy 424.754134 -294.495382)
			(xy 424.748706 -294.495728) (xy 424.232832 -294.495728) (xy 424.225023 -294.496051) (xy 424.210151 -294.50083)
			(xy 424.203622 -294.505126) (xy 424.18249 -294.519459) (xy 424.13677 -294.54219) (xy 424.0881 -294.557625)
			(xy 424.037636 -294.565396) (xy 424.012106 -294.565832) (xy 423.986576 -294.565398) (xy 423.936111 -294.557623)
			(xy 423.887439 -294.542193) (xy 423.841712 -294.519475) (xy 423.82059 -294.505126) (xy 423.814058 -294.500835)
			(xy 423.799188 -294.496052) (xy 423.79138 -294.495728) (xy 423.275506 -294.495728) (xy 423.270064 -294.495413)
			(xy 423.262375 -294.487709) (xy 423.262044 -294.482266) (xy 417.21786 -294.482266) (xy 417.217354 -294.487566)
			(xy 417.209941 -294.495139) (xy 417.204652 -294.495728) (xy 415.731452 -294.495728) (xy 415.726188 -294.495239)
			(xy 415.71875 -294.487785) (xy 415.718244 -294.48252) (xy 354.649736 -294.48252) (xy 354.622625 -294.524011)
			(xy 354.588382 -294.561204) (xy 354.548484 -294.592253) (xy 354.504018 -294.61631) (xy 354.4562 -294.63272)
			(xy 354.406332 -294.641035) (xy 354.381054 -294.641524) (xy 353.441 -294.641524) (xy 353.415721 -294.641078)
			(xy 353.365851 -294.632756) (xy 353.318032 -294.61634) (xy 353.273566 -294.592276) (xy 353.233668 -294.561222)
			(xy 353.199426 -294.524025) (xy 353.171772 -294.481699) (xy 353.151463 -294.435398) (xy 353.139052 -294.386386)
			(xy 353.134877 -294.336) (xy 351.867148 -294.336) (xy 351.862974 -294.386369) (xy 351.850568 -294.435364)
			(xy 351.830268 -294.48165) (xy 351.802626 -294.523963) (xy 351.768398 -294.56115) (xy 351.728516 -294.592197)
			(xy 351.684069 -294.616256) (xy 351.636268 -294.632673) (xy 351.586417 -294.640999) (xy 351.561146 -294.641524)
			(xy 350.621092 -294.641524) (xy 350.595813 -294.641077) (xy 350.545945 -294.632755) (xy 350.498126 -294.616337)
			(xy 350.453662 -294.592274) (xy 350.413765 -294.56122) (xy 350.379523 -294.524022) (xy 350.351871 -294.481696)
			(xy 350.331563 -294.435397) (xy 350.319151 -294.386385) (xy 350.314976 -294.336) (xy 349.047248 -294.336)
			(xy 349.043074 -294.38637) (xy 349.030668 -294.435366) (xy 349.010366 -294.481652) (xy 348.982724 -294.523966)
			(xy 348.948495 -294.561153) (xy 348.908612 -294.5922) (xy 348.864164 -294.616259) (xy 348.816361 -294.632675)
			(xy 348.766509 -294.640999) (xy 348.741238 -294.641524) (xy 347.801184 -294.641524) (xy 347.775905 -294.641077)
			(xy 347.726038 -294.632753) (xy 347.678221 -294.616335) (xy 347.633758 -294.592271) (xy 347.593862 -294.561217)
			(xy 347.559621 -294.52402) (xy 347.53197 -294.481694) (xy 347.511662 -294.435395) (xy 347.499251 -294.386385)
			(xy 347.495076 -294.336) (xy 346.227177 -294.336) (xy 346.223002 -294.386381) (xy 346.210591 -294.435388)
			(xy 346.190283 -294.481683) (xy 346.162631 -294.524004) (xy 346.128391 -294.561196) (xy 346.088495 -294.592245)
			(xy 346.044033 -294.616304) (xy 345.996218 -294.632716) (xy 345.946353 -294.641033) (xy 345.921076 -294.641524)
			(xy 344.981022 -294.641524) (xy 344.955739 -294.641109) (xy 344.905862 -294.632789) (xy 344.858035 -294.616373)
			(xy 344.813562 -294.592308) (xy 344.773657 -294.561252) (xy 344.739408 -294.52405) (xy 344.71175 -294.481719)
			(xy 344.691437 -294.435412) (xy 344.679023 -294.386393) (xy 344.674847 -294.336) (xy 308.118256 -294.336)
			(xy 308.118256 -294.482266) (xy 308.117897 -294.487698) (xy 308.110225 -294.495386) (xy 308.104794 -294.495728)
			(xy 306.631594 -294.495728) (xy 306.62615 -294.495421) (xy 306.618463 -294.487711) (xy 306.618132 -294.482266)
			(xy 300.573948 -294.482266) (xy 300.573453 -294.487569) (xy 300.566032 -294.495143) (xy 300.56074 -294.495728)
			(xy 300.044866 -294.495728) (xy 300.037058 -294.496065) (xy 300.022186 -294.500835) (xy 300.015656 -294.505126)
			(xy 299.994542 -294.519487) (xy 299.948816 -294.542212) (xy 299.90014 -294.557639) (xy 299.849672 -294.565401)
			(xy 299.82414 -294.565832) (xy 299.79861 -294.565381) (xy 299.748147 -294.557611) (xy 299.699474 -294.542186)
			(xy 299.653746 -294.519472) (xy 299.632624 -294.505126) (xy 299.626085 -294.500848) (xy 299.611221 -294.496056)
			(xy 299.603414 -294.495728) (xy 299.08754 -294.495728) (xy 299.082218 -294.495348) (xy 299.074676 -294.48784)
			(xy 299.074332 -294.48252) (xy 293.030132 -294.48252) (xy 293.029797 -294.4877) (xy 293.022119 -294.495388)
			(xy 293.016686 -294.495728) (xy 292.500812 -294.495728) (xy 292.493002 -294.496042) (xy 292.47813 -294.500827)
			(xy 292.471602 -294.505126) (xy 292.450475 -294.519468) (xy 292.404754 -294.542197) (xy 292.356082 -294.557629)
			(xy 292.305617 -294.565398) (xy 292.280086 -294.565832) (xy 292.254555 -294.565408) (xy 292.204091 -294.55763)
			(xy 292.155418 -294.542197) (xy 292.109691 -294.519476) (xy 292.08857 -294.505126) (xy 292.082043 -294.500827)
			(xy 292.06717 -294.496049) (xy 292.05936 -294.495728) (xy 291.543486 -294.495728) (xy 291.538041 -294.495427)
			(xy 291.530354 -294.487712) (xy 291.530024 -294.482266) (xy 285.48584 -294.482266) (xy 285.485352 -294.487571)
			(xy 285.477926 -294.495145) (xy 285.472632 -294.495728) (xy 284.956758 -294.495728) (xy 284.94895 -294.496062)
			(xy 284.934078 -294.500834) (xy 284.927548 -294.505126) (xy 284.906436 -294.519491) (xy 284.860709 -294.542215)
			(xy 284.812033 -294.557641) (xy 284.761564 -294.565402) (xy 284.736032 -294.565832) (xy 284.710502 -294.565385)
			(xy 284.660038 -294.557613) (xy 284.611366 -294.542187) (xy 284.565638 -294.519473) (xy 284.544516 -294.505126)
			(xy 284.537979 -294.500845) (xy 284.523113 -294.496055) (xy 284.515306 -294.495728) (xy 283.999432 -294.495728)
			(xy 283.994109 -294.495354) (xy 283.986567 -294.487842) (xy 283.986224 -294.48252) (xy 277.942017 -294.48252)
			(xy 277.941552 -294.487571) (xy 277.934126 -294.495145) (xy 277.928832 -294.495728) (xy 277.412958 -294.495728)
			(xy 277.40515 -294.496062) (xy 277.390278 -294.500834) (xy 277.383748 -294.505126) (xy 277.362636 -294.519491)
			(xy 277.316909 -294.542215) (xy 277.268233 -294.557641) (xy 277.217764 -294.565402) (xy 277.192232 -294.565832)
			(xy 277.166702 -294.565385) (xy 277.116238 -294.557613) (xy 277.067566 -294.542187) (xy 277.021838 -294.519473)
			(xy 277.000716 -294.505126) (xy 276.994179 -294.500845) (xy 276.979313 -294.496055) (xy 276.971506 -294.495728)
			(xy 276.455632 -294.495728) (xy 276.450309 -294.495354) (xy 276.442767 -294.487842) (xy 276.442424 -294.48252)
			(xy 270.398224 -294.48252) (xy 270.397896 -294.487702) (xy 270.390213 -294.495391) (xy 270.384778 -294.495728)
			(xy 269.868904 -294.495728) (xy 269.861094 -294.496039) (xy 269.846222 -294.500826) (xy 269.839694 -294.505126)
			(xy 269.81857 -294.519471) (xy 269.772847 -294.542199) (xy 269.724175 -294.557631) (xy 269.673709 -294.565398)
			(xy 269.648178 -294.565832) (xy 269.622647 -294.565412) (xy 269.572182 -294.557632) (xy 269.52351 -294.542198)
			(xy 269.477783 -294.519476) (xy 269.456662 -294.505126) (xy 269.450137 -294.500824) (xy 269.435262 -294.496047)
			(xy 269.427452 -294.495728) (xy 268.911578 -294.495728) (xy 268.906132 -294.495432) (xy 268.898445 -294.487713)
			(xy 268.898116 -294.482266) (xy 206.997808 -294.482266) (xy 206.997808 -294.48252) (xy 206.997319 -294.487785)
			(xy 206.989866 -294.495227) (xy 206.9846 -294.495728) (xy 206.468726 -294.495728) (xy 206.46085 -294.495995)
			(xy 206.445846 -294.500793) (xy 206.439262 -294.505126) (xy 206.418184 -294.519516) (xy 206.372539 -294.542346)
			(xy 206.323934 -294.557904) (xy 206.273517 -294.565823) (xy 206.248 -294.56634) (xy 206.222479 -294.56586)
			(xy 206.172052 -294.557961) (xy 206.123441 -294.542398) (xy 206.077803 -294.519542) (xy 206.056738 -294.505126)
			(xy 206.050138 -294.500826) (xy 206.035145 -294.496029) (xy 206.027274 -294.495728) (xy 205.5114 -294.495728)
			(xy 205.506142 -294.495207) (xy 205.498701 -294.487777) (xy 205.498192 -294.48252) (xy 199.454008 -294.48252)
			(xy 199.453519 -294.487785) (xy 199.446066 -294.495227) (xy 199.4408 -294.495728) (xy 198.924926 -294.495728)
			(xy 198.91705 -294.495995) (xy 198.902046 -294.500793) (xy 198.895462 -294.505126) (xy 198.874384 -294.519516)
			(xy 198.828739 -294.542346) (xy 198.780134 -294.557904) (xy 198.729717 -294.565823) (xy 198.7042 -294.56634)
			(xy 198.678679 -294.56586) (xy 198.628252 -294.557961) (xy 198.579641 -294.542398) (xy 198.534003 -294.519542)
			(xy 198.512938 -294.505126) (xy 198.506338 -294.500826) (xy 198.491345 -294.496029) (xy 198.483474 -294.495728)
			(xy 197.9676 -294.495728) (xy 197.962342 -294.495207) (xy 197.954901 -294.487777) (xy 197.954392 -294.48252)
			(xy 191.910208 -294.48252) (xy 191.909719 -294.487785) (xy 191.902266 -294.495227) (xy 191.897 -294.495728)
			(xy 191.896492 -294.495728) (xy 191.380872 -294.495728) (xy 191.372997 -294.496015) (xy 191.357994 -294.500799)
			(xy 191.351408 -294.505126) (xy 191.330345 -294.51954) (xy 191.284695 -294.542364) (xy 191.236085 -294.557915)
			(xy 191.185664 -294.565827) (xy 191.160146 -294.56634) (xy 191.134626 -294.565837) (xy 191.0842 -294.557945)
			(xy 191.035589 -294.542389) (xy 190.98995 -294.519539) (xy 190.968884 -294.505126) (xy 190.962296 -294.500805)
			(xy 190.947293 -294.496022) (xy 190.93942 -294.495728) (xy 190.423546 -294.495728) (xy 190.41824 -294.495242)
			(xy 190.410665 -294.487816) (xy 190.410084 -294.48252) (xy 184.3659 -294.48252) (xy 184.365418 -294.487787)
			(xy 184.35796 -294.495229) (xy 184.352692 -294.495728) (xy 183.836818 -294.495728) (xy 183.828945 -294.496035)
			(xy 183.813941 -294.500806) (xy 183.807354 -294.505126) (xy 183.786278 -294.51952) (xy 183.740633 -294.542348)
			(xy 183.692026 -294.557906) (xy 183.641609 -294.565824) (xy 183.616092 -294.56634) (xy 183.590573 -294.565814)
			(xy 183.540148 -294.557929) (xy 183.491537 -294.54238) (xy 183.445897 -294.519536) (xy 183.42483 -294.505126)
			(xy 183.418232 -294.500822) (xy 183.403237 -294.496028) (xy 183.395366 -294.495728) (xy 182.879492 -294.495728)
			(xy 182.874233 -294.495213) (xy 182.866792 -294.487778) (xy 182.866284 -294.48252) (xy 176.8221 -294.48252)
			(xy 176.821618 -294.487787) (xy 176.81416 -294.495229) (xy 176.808892 -294.495728) (xy 176.808384 -294.495728)
			(xy 176.292764 -294.495728) (xy 176.284889 -294.496011) (xy 176.269885 -294.500798) (xy 176.2633 -294.505126)
			(xy 176.242211 -294.5195) (xy 176.196571 -294.542333) (xy 176.147968 -294.557896) (xy 176.097554 -294.56582)
			(xy 176.072038 -294.56634) (xy 176.046518 -294.565841) (xy 175.996092 -294.557948) (xy 175.947481 -294.542391)
			(xy 175.901842 -294.519539) (xy 175.880776 -294.505126) (xy 175.87419 -294.500802) (xy 175.859186 -294.49602)
			(xy 175.851312 -294.495728) (xy 175.335438 -294.495728) (xy 175.330131 -294.495248) (xy 175.322556 -294.487817)
			(xy 175.321976 -294.48252) (xy 169.277792 -294.48252) (xy 169.277317 -294.487789) (xy 169.269854 -294.495231)
			(xy 169.264584 -294.495728) (xy 167.791384 -294.495728) (xy 167.786124 -294.495218) (xy 167.778683 -294.48778)
			(xy 167.778176 -294.48252) (xy 106.709528 -294.48252) (xy 106.682376 -294.524078) (xy 106.648159 -294.561245)
			(xy 106.608291 -294.592274) (xy 106.56386 -294.616317) (xy 106.516077 -294.632719) (xy 106.466246 -294.641032)
			(xy 106.440986 -294.641524) (xy 105.500932 -294.641524) (xy 105.475674 -294.641002) (xy 105.425846 -294.632692)
			(xy 105.378065 -294.616293) (xy 105.333636 -294.592253) (xy 105.29377 -294.561228) (xy 105.259554 -294.524064)
			(xy 105.231923 -294.481775) (xy 105.21163 -294.435514) (xy 105.199228 -294.386544) (xy 105.195056 -294.3362)
			(xy 103.926976 -294.3362) (xy 103.922804 -294.386548) (xy 103.910401 -294.435522) (xy 103.890107 -294.481787)
			(xy 103.862473 -294.52408) (xy 103.828256 -294.561248) (xy 103.788387 -294.592277) (xy 103.743954 -294.61632)
			(xy 103.69617 -294.632721) (xy 103.646338 -294.641033) (xy 103.621078 -294.641524) (xy 102.681024 -294.641524)
			(xy 102.655766 -294.641001) (xy 102.605939 -294.63269) (xy 102.55816 -294.616291) (xy 102.513732 -294.592251)
			(xy 102.473867 -294.561225) (xy 102.439652 -294.524061) (xy 102.412022 -294.481772) (xy 102.391729 -294.435512)
			(xy 102.379328 -294.386543) (xy 102.375156 -294.3362) (xy 101.107076 -294.3362) (xy 101.102904 -294.386549)
			(xy 101.090501 -294.435524) (xy 101.070205 -294.481789) (xy 101.042571 -294.524083) (xy 101.008353 -294.561251)
			(xy 100.968482 -294.59228) (xy 100.924049 -294.616322) (xy 100.876264 -294.632722) (xy 100.826431 -294.641034)
			(xy 100.80117 -294.641524) (xy 99.861116 -294.641524) (xy 99.835859 -294.641001) (xy 99.786033 -294.632689)
			(xy 99.738255 -294.616289) (xy 99.693828 -294.592248) (xy 99.653964 -294.561222) (xy 99.61975 -294.524059)
			(xy 99.592121 -294.48177) (xy 99.571829 -294.435511) (xy 99.559428 -294.386542) (xy 99.555256 -294.3362)
			(xy 98.286847 -294.3362) (xy 98.282676 -294.38654) (xy 98.270276 -294.435507) (xy 98.249986 -294.481765)
			(xy 98.222358 -294.524052) (xy 98.188148 -294.561216) (xy 98.148287 -294.592242) (xy 98.103863 -294.616284)
			(xy 98.056088 -294.632687) (xy 98.006264 -294.641002) (xy 97.981008 -294.641524) (xy 97.040954 -294.641524)
			(xy 97.015702 -294.640967) (xy 96.965889 -294.632648) (xy 96.918124 -294.616244) (xy 96.873711 -294.592202)
			(xy 96.833859 -294.561179) (xy 96.799657 -294.52402) (xy 96.772037 -294.481739) (xy 96.751752 -294.435489)
			(xy 96.739355 -294.386531) (xy 96.735185 -294.3362) (xy 60.178188 -294.3362) (xy 60.178188 -294.48252)
			(xy 60.177717 -294.48779) (xy 60.170251 -294.495233) (xy 60.16498 -294.495728) (xy 60.164472 -294.495728)
			(xy 58.691526 -294.495728) (xy 58.686218 -294.495256) (xy 58.678643 -294.487819) (xy 58.678064 -294.48252)
			(xy 52.63388 -294.48252) (xy 52.633584 -294.487862) (xy 52.626015 -294.495403) (xy 52.620672 -294.495728)
			(xy 52.104798 -294.495728) (xy 52.096924 -294.496026) (xy 52.081921 -294.500803) (xy 52.075334 -294.505126)
			(xy 52.054264 -294.519528) (xy 52.008616 -294.542355) (xy 51.960008 -294.55791) (xy 51.909589 -294.565825)
			(xy 51.884072 -294.56634) (xy 51.858553 -294.565824) (xy 51.808127 -294.557936) (xy 51.759516 -294.542384)
			(xy 51.713876 -294.519537) (xy 51.69281 -294.505126) (xy 51.686216 -294.500815) (xy 51.671218 -294.496025)
			(xy 51.663346 -294.495728) (xy 51.147472 -294.495728) (xy 51.142211 -294.495226) (xy 51.134771 -294.487782)
			(xy 51.134264 -294.48252) (xy 45.09008 -294.48252) (xy 45.089784 -294.487862) (xy 45.082215 -294.495403)
			(xy 45.076872 -294.495728) (xy 45.076364 -294.495728) (xy 44.560744 -294.495728) (xy 44.552868 -294.496003)
			(xy 44.537865 -294.500796) (xy 44.53128 -294.505126) (xy 44.510197 -294.519509) (xy 44.464554 -294.54234)
			(xy 44.41595 -294.5579) (xy 44.365534 -294.565822) (xy 44.340018 -294.56634) (xy 44.314498 -294.565851)
			(xy 44.264071 -294.557955) (xy 44.21546 -294.542395) (xy 44.169821 -294.519541) (xy 44.148756 -294.505126)
			(xy 44.142174 -294.500794) (xy 44.127167 -294.496017) (xy 44.119292 -294.495728) (xy 43.603418 -294.495728)
			(xy 43.598108 -294.495261) (xy 43.590534 -294.48782) (xy 43.589956 -294.48252) (xy 37.545772 -294.48252)
			(xy 37.545483 -294.487864) (xy 37.537909 -294.495406) (xy 37.532564 -294.495728) (xy 37.01669 -294.495728)
			(xy 37.008816 -294.496023) (xy 36.993812 -294.500802) (xy 36.987226 -294.505126) (xy 36.966158 -294.519532)
			(xy 36.92051 -294.542358) (xy 36.871901 -294.557912) (xy 36.821482 -294.565826) (xy 36.795964 -294.56634)
			(xy 36.770445 -294.565828) (xy 36.720019 -294.557939) (xy 36.671408 -294.542385) (xy 36.625768 -294.519538)
			(xy 36.604702 -294.505126) (xy 36.59811 -294.500812) (xy 36.58311 -294.496024) (xy 36.575238 -294.495728)
			(xy 36.059364 -294.495728) (xy 36.054102 -294.495231) (xy 36.046663 -294.487783) (xy 36.046156 -294.48252)
			(xy 30.001972 -294.48252) (xy 30.001683 -294.487864) (xy 29.994109 -294.495406) (xy 29.988764 -294.495728)
			(xy 29.47289 -294.495728) (xy 29.465016 -294.496023) (xy 29.450012 -294.500802) (xy 29.443426 -294.505126)
			(xy 29.422358 -294.519532) (xy 29.37671 -294.542358) (xy 29.328101 -294.557912) (xy 29.277682 -294.565826)
			(xy 29.252164 -294.56634) (xy 29.226645 -294.565828) (xy 29.176219 -294.557939) (xy 29.127608 -294.542385)
			(xy 29.081968 -294.519538) (xy 29.060902 -294.505126) (xy 29.05431 -294.500812) (xy 29.03931 -294.496024)
			(xy 29.031438 -294.495728) (xy 28.515564 -294.495728) (xy 28.510302 -294.495231) (xy 28.502863 -294.487783)
			(xy 28.502356 -294.48252) (xy 22.458172 -294.48252) (xy 22.457883 -294.487864) (xy 22.450309 -294.495406)
			(xy 22.444964 -294.495728) (xy 22.444456 -294.495728) (xy 21.928836 -294.495728) (xy 21.92096 -294.495999)
			(xy 21.905956 -294.500795) (xy 21.899372 -294.505126) (xy 21.878291 -294.519512) (xy 21.832648 -294.542342)
			(xy 21.784043 -294.557902) (xy 21.733626 -294.565822) (xy 21.70811 -294.56634) (xy 21.68259 -294.565855)
			(xy 21.632163 -294.557958) (xy 21.583552 -294.542396) (xy 21.537913 -294.519541) (xy 21.516848 -294.505126)
			(xy 21.510268 -294.500791) (xy 21.495259 -294.496016) (xy 21.487384 -294.495728) (xy 20.97151 -294.495728)
			(xy 20.9662 -294.495266) (xy 20.958626 -294.487821) (xy 20.958048 -294.48252) (xy 2.509012 -294.48252)
			(xy 2.509012 -295.332404) (xy 16.85798 -295.332404) (xy 16.85798 -294.837866) (xy 16.858261 -294.832416)
			(xy 16.865991 -294.82473) (xy 16.871442 -294.824404) (xy 17.38757 -294.824404) (xy 17.395379 -294.824077)
			(xy 17.41025 -294.8193) (xy 17.41678 -294.815006) (xy 17.437869 -294.800657) (xy 17.48353 -294.777926)
			(xy 17.532136 -294.762467) (xy 17.582539 -294.754644) (xy 17.633545 -294.754644) (xy 17.683948 -294.762467)
			(xy 17.732554 -294.777926) (xy 17.778215 -294.800657) (xy 17.799304 -294.815006) (xy 17.805835 -294.819298)
			(xy 17.820705 -294.82408) (xy 17.828514 -294.824404) (xy 18.344642 -294.824404) (xy 18.350003 -294.824919)
			(xy 18.357584 -294.832505) (xy 18.358104 -294.837866) (xy 18.358104 -295.332404) (xy 20.958048 -295.332404)
			(xy 20.958048 -294.837866) (xy 20.958529 -294.832496) (xy 20.966138 -294.824911) (xy 20.97151 -294.824404)
			(xy 21.487638 -294.824404) (xy 21.495446 -294.824063) (xy 21.510317 -294.819296) (xy 21.516848 -294.815006)
			(xy 21.537937 -294.800657) (xy 21.583598 -294.777926) (xy 21.632204 -294.762467) (xy 21.682607 -294.754644)
			(xy 21.733613 -294.754644) (xy 21.784016 -294.762467) (xy 21.832622 -294.777926) (xy 21.878283 -294.800657)
			(xy 21.899372 -294.815006) (xy 21.90591 -294.819286) (xy 21.920775 -294.824076) (xy 21.928582 -294.824404)
			(xy 22.44471 -294.824404) (xy 22.450067 -294.82494) (xy 22.45765 -294.83251) (xy 22.458172 -294.837866)
			(xy 22.458172 -295.332404) (xy 24.402288 -295.332404) (xy 24.402288 -294.837866) (xy 24.402706 -294.832546)
			(xy 24.410183 -294.824975) (xy 24.415496 -294.824404) (xy 24.931624 -294.824404) (xy 24.939435 -294.8241)
			(xy 24.954306 -294.819307) (xy 24.960834 -294.815006) (xy 24.981923 -294.800657) (xy 25.027584 -294.777926)
			(xy 25.07619 -294.762467) (xy 25.126593 -294.754644) (xy 25.177599 -294.754644) (xy 25.228002 -294.762467)
			(xy 25.276608 -294.777926) (xy 25.322269 -294.800657) (xy 25.343358 -294.815006) (xy 25.349877 -294.819319)
			(xy 25.364757 -294.824088) (xy 25.372568 -294.824404) (xy 25.888696 -294.824404) (xy 25.894031 -294.824731)
			(xy 25.901572 -294.832277) (xy 25.901904 -294.837612) (xy 25.901904 -294.83812) (xy 25.901904 -295.332404)
			(xy 28.502356 -295.332404) (xy 28.502356 -294.837866) (xy 28.502802 -294.832554) (xy 28.51026 -294.824984)
			(xy 28.515564 -294.824404) (xy 29.031692 -294.824404) (xy 29.039502 -294.824086) (xy 29.054373 -294.819303)
			(xy 29.060902 -294.815006) (xy 29.081991 -294.800657) (xy 29.127652 -294.777926) (xy 29.176258 -294.762467)
			(xy 29.226661 -294.754644) (xy 29.277667 -294.754644) (xy 29.32807 -294.762467) (xy 29.376676 -294.777926)
			(xy 29.422337 -294.800657) (xy 29.443426 -294.815006) (xy 29.449952 -294.819307) (xy 29.464826 -294.824084)
			(xy 29.472636 -294.824404) (xy 29.988764 -294.824404) (xy 29.994094 -294.824752) (xy 30.001638 -294.832282)
			(xy 30.001972 -294.837612) (xy 30.001972 -294.83812) (xy 30.001972 -295.332404) (xy 31.946088 -295.332404)
			(xy 31.946088 -294.837866) (xy 31.946506 -294.832546) (xy 31.953983 -294.824975) (xy 31.959296 -294.824404)
			(xy 32.475424 -294.824404) (xy 32.483235 -294.8241) (xy 32.498106 -294.819307) (xy 32.504634 -294.815006)
			(xy 32.525723 -294.800657) (xy 32.571384 -294.777926) (xy 32.61999 -294.762467) (xy 32.670393 -294.754644)
			(xy 32.721399 -294.754644) (xy 32.771802 -294.762467) (xy 32.820408 -294.777926) (xy 32.866069 -294.800657)
			(xy 32.887158 -294.815006) (xy 32.893677 -294.819319) (xy 32.908557 -294.824088) (xy 32.916368 -294.824404)
			(xy 33.432496 -294.824404) (xy 33.437831 -294.824731) (xy 33.445372 -294.832277) (xy 33.445704 -294.837612)
			(xy 33.445704 -294.83812) (xy 33.445704 -295.332404) (xy 36.046156 -295.332404) (xy 36.046156 -294.837866)
			(xy 36.046602 -294.832554) (xy 36.05406 -294.824984) (xy 36.059364 -294.824404) (xy 36.575492 -294.824404)
			(xy 36.583302 -294.824086) (xy 36.598173 -294.819303) (xy 36.604702 -294.815006) (xy 36.625791 -294.800657)
			(xy 36.671452 -294.777926) (xy 36.720058 -294.762467) (xy 36.770461 -294.754644) (xy 36.821467 -294.754644)
			(xy 36.87187 -294.762467) (xy 36.920476 -294.777926) (xy 36.966137 -294.800657) (xy 36.987226 -294.815006)
			(xy 36.993752 -294.819307) (xy 37.008626 -294.824084) (xy 37.016436 -294.824404) (xy 37.532564 -294.824404)
			(xy 37.537894 -294.824752) (xy 37.545438 -294.832282) (xy 37.545772 -294.837612) (xy 37.545772 -294.83812)
			(xy 37.545772 -295.332404) (xy 39.489888 -295.332404) (xy 39.489888 -294.837866) (xy 39.490423 -294.83251)
			(xy 39.497995 -294.824929) (xy 39.50335 -294.824404) (xy 40.019478 -294.824404) (xy 40.027287 -294.82408)
			(xy 40.042159 -294.819301) (xy 40.048688 -294.815006) (xy 40.069777 -294.800657) (xy 40.115438 -294.777926)
			(xy 40.164044 -294.762467) (xy 40.214447 -294.754644) (xy 40.265453 -294.754644) (xy 40.315856 -294.762467)
			(xy 40.364462 -294.777926) (xy 40.410123 -294.800657) (xy 40.431212 -294.815006) (xy 40.437741 -294.819301)
			(xy 40.452613 -294.824082) (xy 40.460422 -294.824404) (xy 40.97655 -294.824404) (xy 40.981912 -294.824914)
			(xy 40.989492 -294.832504) (xy 40.990012 -294.837866) (xy 40.990012 -295.332404) (xy 43.589956 -295.332404)
			(xy 43.589956 -294.837866) (xy 43.59043 -294.832494) (xy 43.598044 -294.824909) (xy 43.603418 -294.824404)
			(xy 44.119546 -294.824404) (xy 44.127354 -294.824067) (xy 44.142225 -294.819297) (xy 44.148756 -294.815006)
			(xy 44.169845 -294.800657) (xy 44.215506 -294.777926) (xy 44.264112 -294.762467) (xy 44.314515 -294.754644)
			(xy 44.365521 -294.754644) (xy 44.415924 -294.762467) (xy 44.46453 -294.777926) (xy 44.510191 -294.800657)
			(xy 44.53128 -294.815006) (xy 44.537816 -294.819289) (xy 44.552683 -294.824077) (xy 44.56049 -294.824404)
			(xy 45.076618 -294.824404) (xy 45.081976 -294.824935) (xy 45.089559 -294.832509) (xy 45.09008 -294.837866)
			(xy 45.09008 -295.332404) (xy 47.034196 -295.332404) (xy 47.034196 -294.837866) (xy 47.034695 -294.832568)
			(xy 47.042117 -294.825001) (xy 47.047404 -294.824404) (xy 47.563532 -294.824404) (xy 47.571339 -294.824061)
			(xy 47.586211 -294.819295) (xy 47.592742 -294.815006) (xy 47.613831 -294.800657) (xy 47.659492 -294.777926)
			(xy 47.708098 -294.762467) (xy 47.758501 -294.754644) (xy 47.809507 -294.754644) (xy 47.85991 -294.762467)
			(xy 47.908516 -294.777926) (xy 47.954177 -294.800657) (xy 47.975266 -294.815006) (xy 47.981805 -294.819284)
			(xy 47.996669 -294.824075) (xy 48.004476 -294.824404) (xy 48.520604 -294.824404) (xy 48.52594 -294.824725)
			(xy 48.533481 -294.832276) (xy 48.533812 -294.837612) (xy 48.533812 -294.83812) (xy 48.533812 -295.332404)
			(xy 51.134264 -295.332404) (xy 51.134264 -294.837866) (xy 51.134703 -294.832552) (xy 51.142166 -294.824982)
			(xy 51.147472 -294.824404) (xy 51.6636 -294.824404) (xy 51.67141 -294.82409) (xy 51.686281 -294.819304)
			(xy 51.69281 -294.815006) (xy 51.713899 -294.800657) (xy 51.75956 -294.777926) (xy 51.808166 -294.762467)
			(xy 51.858569 -294.754644) (xy 51.909575 -294.754644) (xy 51.959978 -294.762467) (xy 52.008584 -294.777926)
			(xy 52.054245 -294.800657) (xy 52.075334 -294.815006) (xy 52.081858 -294.81931) (xy 52.096734 -294.824085)
			(xy 52.104544 -294.824404) (xy 52.620672 -294.824404) (xy 52.626003 -294.824747) (xy 52.633547 -294.832281)
			(xy 52.63388 -294.837612) (xy 52.63388 -294.83812) (xy 52.63388 -295.332404) (xy 54.577996 -295.332404)
			(xy 54.577996 -294.837866) (xy 54.578524 -294.832508) (xy 54.5861 -294.824927) (xy 54.591458 -294.824404)
			(xy 56.064658 -294.824404) (xy 56.070079 -294.824804) (xy 56.077765 -294.832447) (xy 56.07812 -294.837866)
			(xy 56.07812 -295.332404) (xy 58.678064 -295.332404) (xy 58.678064 -294.837866) (xy 58.67853 -294.832492)
			(xy 58.68615 -294.824906) (xy 58.691526 -294.824404) (xy 60.164726 -294.824404) (xy 60.170085 -294.82493)
			(xy 60.177667 -294.832507) (xy 60.178188 -294.837866) (xy 60.178188 -295.332404) (xy 163.678108 -295.332404)
			(xy 163.678108 -294.837866) (xy 163.678597 -294.832565) (xy 163.686025 -294.824998) (xy 163.691316 -294.824404)
			(xy 165.164516 -294.824404) (xy 165.169784 -294.824885) (xy 165.177226 -294.832343) (xy 165.177724 -294.837612)
			(xy 165.177724 -294.83812) (xy 165.177724 -295.332404) (xy 167.778176 -295.332404) (xy 167.778176 -294.837866)
			(xy 167.778605 -294.832549) (xy 167.786075 -294.824978) (xy 167.791384 -294.824404) (xy 169.264584 -294.824404)
			(xy 169.269917 -294.824739) (xy 169.27746 -294.832279) (xy 169.277792 -294.837612) (xy 169.277792 -295.332404)
			(xy 171.221908 -295.332404) (xy 171.221908 -294.837866) (xy 171.222425 -294.832505) (xy 171.230009 -294.824923)
			(xy 171.23537 -294.824404) (xy 171.751498 -294.824404) (xy 171.759308 -294.824089) (xy 171.774179 -294.819304)
			(xy 171.780708 -294.815006) (xy 171.801797 -294.800657) (xy 171.847458 -294.777926) (xy 171.896064 -294.762467)
			(xy 171.946467 -294.754644) (xy 171.997473 -294.754644) (xy 172.047876 -294.762467) (xy 172.096482 -294.777926)
			(xy 172.142143 -294.800657) (xy 172.163232 -294.815006) (xy 172.169757 -294.819309) (xy 172.184632 -294.824085)
			(xy 172.192442 -294.824404) (xy 172.70857 -294.824404) (xy 172.713922 -294.824967) (xy 172.721508 -294.832516)
			(xy 172.722032 -294.837866) (xy 172.722032 -295.332404) (xy 175.321976 -295.332404) (xy 175.321976 -294.837866)
			(xy 175.32226 -294.832417) (xy 175.329988 -294.824731) (xy 175.335438 -294.824404) (xy 175.851566 -294.824404)
			(xy 175.859375 -294.824075) (xy 175.874246 -294.8193) (xy 175.880776 -294.815006) (xy 175.901865 -294.800657)
			(xy 175.947526 -294.777926) (xy 175.996132 -294.762467) (xy 176.046535 -294.754644) (xy 176.097541 -294.754644)
			(xy 176.147944 -294.762467) (xy 176.19655 -294.777926) (xy 176.242211 -294.800657) (xy 176.2633 -294.815006)
			(xy 176.269832 -294.819297) (xy 176.284702 -294.82408) (xy 176.29251 -294.824404) (xy 176.808638 -294.824404)
			(xy 176.813998 -294.824922) (xy 176.82158 -294.832506) (xy 176.8221 -294.837866) (xy 176.8221 -295.332404)
			(xy 178.766216 -295.332404) (xy 178.766216 -294.837866) (xy 178.766698 -294.832563) (xy 178.774131 -294.824996)
			(xy 178.779424 -294.824404) (xy 179.295552 -294.824404) (xy 179.30336 -294.824069) (xy 179.318232 -294.819298)
			(xy 179.324762 -294.815006) (xy 179.345851 -294.800657) (xy 179.391512 -294.777926) (xy 179.440118 -294.762467)
			(xy 179.490521 -294.754644) (xy 179.541527 -294.754644) (xy 179.59193 -294.762467) (xy 179.640536 -294.777926)
			(xy 179.686197 -294.800657) (xy 179.707286 -294.815006) (xy 179.713821 -294.819291) (xy 179.728688 -294.824078)
			(xy 179.736496 -294.824404) (xy 180.252624 -294.824404) (xy 180.257892 -294.82488) (xy 180.265334 -294.832342)
			(xy 180.265832 -294.837612) (xy 180.265832 -294.83812) (xy 180.265832 -295.332404) (xy 182.866284 -295.332404)
			(xy 182.866284 -294.837866) (xy 182.866706 -294.832547) (xy 182.87418 -294.824976) (xy 182.879492 -294.824404)
			(xy 183.39562 -294.824404) (xy 183.403431 -294.824098) (xy 183.418302 -294.819307) (xy 183.42483 -294.815006)
			(xy 183.445919 -294.800657) (xy 183.49158 -294.777926) (xy 183.540186 -294.762467) (xy 183.590589 -294.754644)
			(xy 183.641595 -294.754644) (xy 183.691998 -294.762467) (xy 183.740604 -294.777926) (xy 183.786265 -294.800657)
			(xy 183.807354 -294.815006) (xy 183.813874 -294.819317) (xy 183.828753 -294.824088) (xy 183.836564 -294.824404)
			(xy 184.352692 -294.824404) (xy 184.358026 -294.824733) (xy 184.365568 -294.832278) (xy 184.3659 -294.837612)
			(xy 184.3659 -294.83812) (xy 184.3659 -295.332404) (xy 186.310016 -295.332404) (xy 186.310016 -294.837866)
			(xy 186.310526 -294.832503) (xy 186.318115 -294.824921) (xy 186.323478 -294.824404) (xy 186.839606 -294.824404)
			(xy 186.847416 -294.824092) (xy 186.862288 -294.819305) (xy 186.868816 -294.815006) (xy 186.889905 -294.800657)
			(xy 186.935566 -294.777926) (xy 186.984172 -294.762467) (xy 187.034575 -294.754644) (xy 187.085581 -294.754644)
			(xy 187.135984 -294.762467) (xy 187.18459 -294.777926) (xy 187.230251 -294.800657) (xy 187.25134 -294.815006)
			(xy 187.257863 -294.819312) (xy 187.27274 -294.824086) (xy 187.28055 -294.824404) (xy 187.796678 -294.824404)
			(xy 187.802031 -294.824962) (xy 187.809616 -294.832515) (xy 187.81014 -294.837866) (xy 187.81014 -295.332404)
			(xy 190.410084 -295.332404) (xy 190.410084 -294.837866) (xy 190.410361 -294.832415) (xy 190.418094 -294.824729)
			(xy 190.423546 -294.824404) (xy 190.939674 -294.824404) (xy 190.947483 -294.824079) (xy 190.962354 -294.819301)
			(xy 190.968884 -294.815006) (xy 190.989973 -294.800657) (xy 191.035634 -294.777926) (xy 191.08424 -294.762467)
			(xy 191.134643 -294.754644) (xy 191.185649 -294.754644) (xy 191.236052 -294.762467) (xy 191.284658 -294.777926)
			(xy 191.330319 -294.800657) (xy 191.351408 -294.815006) (xy 191.357938 -294.8193) (xy 191.372809 -294.824081)
			(xy 191.380618 -294.824404) (xy 191.896746 -294.824404) (xy 191.902107 -294.824916) (xy 191.909688 -294.832504)
			(xy 191.910208 -294.837866) (xy 191.910208 -295.332404) (xy 193.854324 -295.332404) (xy 193.854324 -294.837866)
			(xy 193.854799 -294.832561) (xy 193.862237 -294.824993) (xy 193.867532 -294.824404) (xy 194.38366 -294.824404)
			(xy 194.391468 -294.824073) (xy 194.40634 -294.819299) (xy 194.41287 -294.815006) (xy 194.433959 -294.800657)
			(xy 194.47962 -294.777926) (xy 194.528226 -294.762467) (xy 194.578629 -294.754644) (xy 194.629635 -294.754644)
			(xy 194.680038 -294.762467) (xy 194.728644 -294.777926) (xy 194.774305 -294.800657) (xy 194.795394 -294.815006)
			(xy 194.801927 -294.819294) (xy 194.816796 -294.824079) (xy 194.824604 -294.824404) (xy 195.340732 -294.824404)
			(xy 195.346002 -294.824875) (xy 195.353443 -294.832341) (xy 195.35394 -294.837612) (xy 195.35394 -294.83812)
			(xy 195.35394 -295.332404) (xy 197.954392 -295.332404) (xy 197.954392 -294.837866) (xy 197.954895 -294.832569)
			(xy 197.962314 -294.825003) (xy 197.9676 -294.824404) (xy 198.483728 -294.824404) (xy 198.491539 -294.824101)
			(xy 198.50641 -294.819308) (xy 198.512938 -294.815006) (xy 198.534027 -294.800657) (xy 198.579688 -294.777926)
			(xy 198.628294 -294.762467) (xy 198.678697 -294.754644) (xy 198.729703 -294.754644) (xy 198.780106 -294.762467)
			(xy 198.828712 -294.777926) (xy 198.874373 -294.800657) (xy 198.895462 -294.815006) (xy 198.902002 -294.819282)
			(xy 198.916866 -294.824074) (xy 198.924672 -294.824404) (xy 199.4408 -294.824404) (xy 199.446135 -294.824728)
			(xy 199.453677 -294.832276) (xy 199.454008 -294.837612) (xy 199.454008 -294.83812) (xy 199.454008 -295.332404)
			(xy 201.398124 -295.332404) (xy 201.398124 -294.837866) (xy 201.398599 -294.832561) (xy 201.406037 -294.824993)
			(xy 201.411332 -294.824404) (xy 201.92746 -294.824404) (xy 201.935268 -294.824073) (xy 201.95014 -294.819299)
			(xy 201.95667 -294.815006) (xy 201.977759 -294.800657) (xy 202.02342 -294.777926) (xy 202.072026 -294.762467)
			(xy 202.122429 -294.754644) (xy 202.173435 -294.754644) (xy 202.223838 -294.762467) (xy 202.272444 -294.777926)
			(xy 202.318105 -294.800657) (xy 202.339194 -294.815006) (xy 202.345727 -294.819294) (xy 202.360596 -294.824079)
			(xy 202.368404 -294.824404) (xy 202.884532 -294.824404) (xy 202.889802 -294.824875) (xy 202.897243 -294.832341)
			(xy 202.89774 -294.837612) (xy 202.89774 -294.83812) (xy 202.89774 -295.332404) (xy 205.498192 -295.332404)
			(xy 205.498192 -294.837866) (xy 205.498695 -294.832569) (xy 205.506114 -294.825003) (xy 205.5114 -294.824404)
			(xy 206.027528 -294.824404) (xy 206.035339 -294.824101) (xy 206.05021 -294.819308) (xy 206.056738 -294.815006)
			(xy 206.077827 -294.800657) (xy 206.123488 -294.777926) (xy 206.172094 -294.762467) (xy 206.222497 -294.754644)
			(xy 206.273503 -294.754644) (xy 206.323906 -294.762467) (xy 206.372512 -294.777926) (xy 206.418173 -294.800657)
			(xy 206.439262 -294.815006) (xy 206.445802 -294.819282) (xy 206.460666 -294.824074) (xy 206.468472 -294.824404)
			(xy 206.9846 -294.824404) (xy 206.989935 -294.824728) (xy 206.997477 -294.832276) (xy 206.997808 -294.837612)
			(xy 206.997808 -294.83812) (xy 206.997808 -295.33215) (xy 264.798048 -295.33215) (xy 264.798048 -294.837612)
			(xy 264.798598 -294.832361) (xy 264.806007 -294.824921) (xy 264.811256 -294.824404) (xy 264.811764 -294.824404)
			(xy 265.327638 -294.824404) (xy 265.335446 -294.824063) (xy 265.350317 -294.819296) (xy 265.356848 -294.815006)
			(xy 265.377937 -294.800657) (xy 265.423598 -294.777926) (xy 265.472204 -294.762467) (xy 265.522607 -294.754644)
			(xy 265.573613 -294.754644) (xy 265.624016 -294.762467) (xy 265.672622 -294.777926) (xy 265.718283 -294.800657)
			(xy 265.739372 -294.815006) (xy 265.74591 -294.819286) (xy 265.760775 -294.824076) (xy 265.768582 -294.824404)
			(xy 266.28471 -294.824404) (xy 266.290007 -294.824912) (xy 266.297575 -294.832326) (xy 266.298172 -294.837612)
			(xy 266.298172 -295.33215) (xy 268.898116 -295.33215) (xy 268.898116 -294.837612) (xy 268.898437 -294.832276)
			(xy 268.905987 -294.824733) (xy 268.911324 -294.824404) (xy 268.911832 -294.824404) (xy 269.427706 -294.824404)
			(xy 269.435516 -294.824092) (xy 269.450388 -294.819305) (xy 269.456916 -294.815006) (xy 269.478005 -294.800657)
			(xy 269.523666 -294.777926) (xy 269.572272 -294.762467) (xy 269.622675 -294.754644) (xy 269.673681 -294.754644)
			(xy 269.724084 -294.762467) (xy 269.77269 -294.777926) (xy 269.818351 -294.800657) (xy 269.83944 -294.815006)
			(xy 269.845963 -294.819312) (xy 269.86084 -294.824086) (xy 269.86865 -294.824404) (xy 270.384778 -294.824404)
			(xy 270.390071 -294.824933) (xy 270.397642 -294.832331) (xy 270.39824 -294.837612) (xy 270.39824 -295.33215)
			(xy 270.398218 -295.332404) (xy 272.342356 -295.332404) (xy 272.342356 -295.331896) (xy 272.342356 -294.837612)
			(xy 272.342899 -294.832359) (xy 272.350313 -294.824918) (xy 272.355564 -294.824404) (xy 272.871692 -294.824404)
			(xy 272.879502 -294.824086) (xy 272.894373 -294.819303) (xy 272.900902 -294.815006) (xy 272.921991 -294.800657)
			(xy 272.967652 -294.777926) (xy 273.016258 -294.762467) (xy 273.066661 -294.754644) (xy 273.117667 -294.754644)
			(xy 273.16807 -294.762467) (xy 273.216676 -294.777926) (xy 273.262337 -294.800657) (xy 273.283426 -294.815006)
			(xy 273.289952 -294.819307) (xy 273.304826 -294.824084) (xy 273.312636 -294.824404) (xy 273.828764 -294.824404)
			(xy 273.834094 -294.824752) (xy 273.841638 -294.832282) (xy 273.841972 -294.837612) (xy 273.841972 -295.33215)
			(xy 273.841947 -295.332404) (xy 276.442424 -295.332404) (xy 276.442424 -295.331896) (xy 276.442424 -294.837612)
			(xy 276.442738 -294.832274) (xy 276.450293 -294.82473) (xy 276.455632 -294.824404) (xy 276.97176 -294.824404)
			(xy 276.979568 -294.824073) (xy 276.99444 -294.819299) (xy 277.00097 -294.815006) (xy 277.022059 -294.800657)
			(xy 277.06772 -294.777926) (xy 277.116326 -294.762467) (xy 277.166729 -294.754644) (xy 277.217735 -294.754644)
			(xy 277.268138 -294.762467) (xy 277.316744 -294.777926) (xy 277.362405 -294.800657) (xy 277.383494 -294.815006)
			(xy 277.390027 -294.819294) (xy 277.404896 -294.824079) (xy 277.412704 -294.824404) (xy 277.928832 -294.824404)
			(xy 277.934102 -294.824875) (xy 277.941543 -294.832341) (xy 277.94204 -294.837612) (xy 277.94204 -295.33215)
			(xy 277.942016 -295.332404) (xy 279.886156 -295.332404) (xy 279.886156 -295.331896) (xy 279.886156 -294.837612)
			(xy 279.886699 -294.832359) (xy 279.894113 -294.824918) (xy 279.899364 -294.824404) (xy 280.415492 -294.824404)
			(xy 280.423302 -294.824086) (xy 280.438173 -294.819303) (xy 280.444702 -294.815006) (xy 280.465791 -294.800657)
			(xy 280.511452 -294.777926) (xy 280.560058 -294.762467) (xy 280.610461 -294.754644) (xy 280.661467 -294.754644)
			(xy 280.71187 -294.762467) (xy 280.760476 -294.777926) (xy 280.806137 -294.800657) (xy 280.827226 -294.815006)
			(xy 280.833752 -294.819307) (xy 280.848626 -294.824084) (xy 280.856436 -294.824404) (xy 281.372564 -294.824404)
			(xy 281.377894 -294.824752) (xy 281.385438 -294.832282) (xy 281.385772 -294.837612) (xy 281.385772 -295.33215)
			(xy 281.385747 -295.332404) (xy 283.986224 -295.332404) (xy 283.986224 -295.331896) (xy 283.986224 -294.837612)
			(xy 283.986538 -294.832274) (xy 283.994093 -294.82473) (xy 283.999432 -294.824404) (xy 284.51556 -294.824404)
			(xy 284.523368 -294.824073) (xy 284.53824 -294.819299) (xy 284.54477 -294.815006) (xy 284.565859 -294.800657)
			(xy 284.61152 -294.777926) (xy 284.660126 -294.762467) (xy 284.710529 -294.754644) (xy 284.761535 -294.754644)
			(xy 284.811938 -294.762467) (xy 284.860544 -294.777926) (xy 284.906205 -294.800657) (xy 284.927294 -294.815006)
			(xy 284.933827 -294.819294) (xy 284.948696 -294.824079) (xy 284.956504 -294.824404) (xy 285.472632 -294.824404)
			(xy 285.477902 -294.824875) (xy 285.485343 -294.832341) (xy 285.48584 -294.837612) (xy 285.48584 -295.33215)
			(xy 287.429956 -295.33215) (xy 287.429956 -294.837612) (xy 287.430499 -294.832359) (xy 287.437913 -294.824918)
			(xy 287.443164 -294.824404) (xy 287.443672 -294.824404) (xy 287.959546 -294.824404) (xy 287.967354 -294.824067)
			(xy 287.982225 -294.819297) (xy 287.988756 -294.815006) (xy 288.009845 -294.800657) (xy 288.055506 -294.777926)
			(xy 288.104112 -294.762467) (xy 288.154515 -294.754644) (xy 288.205521 -294.754644) (xy 288.255924 -294.762467)
			(xy 288.30453 -294.777926) (xy 288.350191 -294.800657) (xy 288.37128 -294.815006) (xy 288.377816 -294.819289)
			(xy 288.392683 -294.824077) (xy 288.40049 -294.824404) (xy 288.916618 -294.824404) (xy 288.921916 -294.824907)
			(xy 288.929484 -294.832325) (xy 288.93008 -294.837612) (xy 288.93008 -295.33215) (xy 291.530024 -295.33215)
			(xy 291.530024 -294.837612) (xy 291.530338 -294.832274) (xy 291.537893 -294.82473) (xy 291.543232 -294.824404)
			(xy 291.54374 -294.824404) (xy 292.059614 -294.824404) (xy 292.067425 -294.824096) (xy 292.082296 -294.819306)
			(xy 292.088824 -294.815006) (xy 292.109913 -294.800657) (xy 292.155574 -294.777926) (xy 292.20418 -294.762467)
			(xy 292.254583 -294.754644) (xy 292.305589 -294.754644) (xy 292.355992 -294.762467) (xy 292.404598 -294.777926)
			(xy 292.450259 -294.800657) (xy 292.471348 -294.815006) (xy 292.477869 -294.819315) (xy 292.492747 -294.824087)
			(xy 292.500558 -294.824404) (xy 293.016686 -294.824404) (xy 293.02198 -294.824928) (xy 293.02955 -294.83233)
			(xy 293.030148 -294.837612) (xy 293.030148 -295.33215) (xy 293.030126 -295.332404) (xy 294.974264 -295.332404)
			(xy 294.974264 -295.331896) (xy 294.974264 -294.837612) (xy 294.9748 -294.832357) (xy 294.982219 -294.824916)
			(xy 294.987472 -294.824404) (xy 295.5036 -294.824404) (xy 295.51141 -294.82409) (xy 295.526281 -294.819304)
			(xy 295.53281 -294.815006) (xy 295.553899 -294.800657) (xy 295.59956 -294.777926) (xy 295.648166 -294.762467)
			(xy 295.698569 -294.754644) (xy 295.749575 -294.754644) (xy 295.799978 -294.762467) (xy 295.848584 -294.777926)
			(xy 295.894245 -294.800657) (xy 295.915334 -294.815006) (xy 295.921858 -294.81931) (xy 295.936734 -294.824085)
			(xy 295.944544 -294.824404) (xy 296.460672 -294.824404) (xy 296.466003 -294.824747) (xy 296.473547 -294.832281)
			(xy 296.47388 -294.837612) (xy 296.47388 -295.33215) (xy 296.473854 -295.332404) (xy 299.074332 -295.332404)
			(xy 299.074332 -295.331896) (xy 299.074332 -294.837612) (xy 299.074639 -294.832272) (xy 299.082199 -294.824728)
			(xy 299.08754 -294.824404) (xy 299.603668 -294.824404) (xy 299.611477 -294.824076) (xy 299.626348 -294.8193)
			(xy 299.632878 -294.815006) (xy 299.653967 -294.800657) (xy 299.699628 -294.777926) (xy 299.748234 -294.762467)
			(xy 299.798637 -294.754644) (xy 299.849643 -294.754644) (xy 299.900046 -294.762467) (xy 299.948652 -294.777926)
			(xy 299.994313 -294.800657) (xy 300.015402 -294.815006) (xy 300.021933 -294.819297) (xy 300.036804 -294.82408)
			(xy 300.044612 -294.824404) (xy 300.56074 -294.824404) (xy 300.566011 -294.824869) (xy 300.573452 -294.83234)
			(xy 300.573948 -294.837612) (xy 300.573948 -295.33215) (xy 302.518064 -295.33215) (xy 302.518064 -294.837612)
			(xy 302.5186 -294.832357) (xy 302.526019 -294.824916) (xy 302.531272 -294.824404) (xy 304.004726 -294.824404)
			(xy 304.010025 -294.824901) (xy 304.017593 -294.832324) (xy 304.018188 -294.837612) (xy 304.018188 -295.33215)
			(xy 306.618132 -295.33215) (xy 306.618132 -294.837612) (xy 306.618439 -294.832272) (xy 306.625999 -294.824728)
			(xy 306.63134 -294.824404) (xy 306.631848 -294.824404) (xy 308.104794 -294.824404) (xy 308.110089 -294.824923)
			(xy 308.117659 -294.832329) (xy 308.118256 -294.837612) (xy 308.118256 -295.33215) (xy 308.118234 -295.332404)
			(xy 411.618176 -295.332404) (xy 411.618176 -295.331896) (xy 411.618176 -294.837612) (xy 411.618701 -294.832355)
			(xy 411.626128 -294.824912) (xy 411.631384 -294.824404) (xy 413.104584 -294.824404) (xy 413.109917 -294.824739)
			(xy 413.11746 -294.832279) (xy 413.117792 -294.837612) (xy 413.117792 -295.33215) (xy 413.117766 -295.332404)
			(xy 415.718244 -295.332404) (xy 415.718244 -294.837612) (xy 415.718798 -294.832362) (xy 415.726205 -294.824922)
			(xy 415.731452 -294.824404) (xy 417.204652 -294.824404) (xy 417.209981 -294.824761) (xy 417.217525 -294.832284)
			(xy 417.21786 -294.837612) (xy 417.21786 -295.33215) (xy 419.161976 -295.33215) (xy 419.161976 -294.837612)
			(xy 419.162501 -294.832355) (xy 419.169928 -294.824912) (xy 419.175184 -294.824404) (xy 419.175692 -294.824404)
			(xy 419.691566 -294.824404) (xy 419.699375 -294.824075) (xy 419.714246 -294.8193) (xy 419.720776 -294.815006)
			(xy 419.741865 -294.800657) (xy 419.787526 -294.777926) (xy 419.836132 -294.762467) (xy 419.886535 -294.754644)
			(xy 419.937541 -294.754644) (xy 419.987944 -294.762467) (xy 420.03655 -294.777926) (xy 420.082211 -294.800657)
			(xy 420.1033 -294.815006) (xy 420.109832 -294.819297) (xy 420.124702 -294.82408) (xy 420.13251 -294.824404)
			(xy 420.648638 -294.824404) (xy 420.653939 -294.824893) (xy 420.661506 -294.832322) (xy 420.6621 -294.837612)
			(xy 420.6621 -295.33215) (xy 423.262044 -295.33215) (xy 423.262044 -294.837612) (xy 423.262598 -294.832362)
			(xy 423.270005 -294.824922) (xy 423.275252 -294.824404) (xy 423.27576 -294.824404) (xy 423.791634 -294.824404)
			(xy 423.799441 -294.824062) (xy 423.814313 -294.819295) (xy 423.820844 -294.815006) (xy 423.841933 -294.800657)
			(xy 423.887594 -294.777926) (xy 423.9362 -294.762467) (xy 423.986603 -294.754644) (xy 424.037609 -294.754644)
			(xy 424.088012 -294.762467) (xy 424.136618 -294.777926) (xy 424.182279 -294.800657) (xy 424.203368 -294.815006)
			(xy 424.209907 -294.819284) (xy 424.224771 -294.824075) (xy 424.232578 -294.824404) (xy 424.748706 -294.824404)
			(xy 424.754003 -294.824915) (xy 424.761571 -294.832327) (xy 424.762168 -294.837612) (xy 424.762168 -295.33215)
			(xy 424.762145 -295.332404) (xy 426.706284 -295.332404) (xy 426.706284 -295.331896) (xy 426.706284 -294.837612)
			(xy 426.706634 -294.832283) (xy 426.714164 -294.824742) (xy 426.719492 -294.824404) (xy 427.23562 -294.824404)
			(xy 427.243431 -294.824098) (xy 427.258302 -294.819307) (xy 427.26483 -294.815006) (xy 427.285919 -294.800657)
			(xy 427.33158 -294.777926) (xy 427.380186 -294.762467) (xy 427.430589 -294.754644) (xy 427.481595 -294.754644)
			(xy 427.531998 -294.762467) (xy 427.580604 -294.777926) (xy 427.626265 -294.800657) (xy 427.647354 -294.815006)
			(xy 427.653874 -294.819317) (xy 427.668753 -294.824088) (xy 427.676564 -294.824404) (xy 428.192692 -294.824404)
			(xy 428.198026 -294.824733) (xy 428.205568 -294.832278) (xy 428.2059 -294.837612) (xy 428.2059 -295.33215)
			(xy 428.205873 -295.332404) (xy 430.806352 -295.332404) (xy 430.806352 -295.331896) (xy 430.806352 -294.837612)
			(xy 430.806899 -294.83236) (xy 430.81431 -294.824919) (xy 430.81956 -294.824404) (xy 431.335688 -294.824404)
			(xy 431.343498 -294.824085) (xy 431.358369 -294.819302) (xy 431.364898 -294.815006) (xy 431.385987 -294.800657)
			(xy 431.431648 -294.777926) (xy 431.480254 -294.762467) (xy 431.530657 -294.754644) (xy 431.581663 -294.754644)
			(xy 431.632066 -294.762467) (xy 431.680672 -294.777926) (xy 431.726333 -294.800657) (xy 431.747422 -294.815006)
			(xy 431.753949 -294.819305) (xy 431.768823 -294.824083) (xy 431.776632 -294.824404) (xy 432.29276 -294.824404)
			(xy 432.29809 -294.824755) (xy 432.305634 -294.832283) (xy 432.305968 -294.837612) (xy 432.305968 -295.33215)
			(xy 434.250084 -295.33215) (xy 434.250084 -294.837612) (xy 434.250434 -294.832283) (xy 434.257964 -294.824742)
			(xy 434.263292 -294.824404) (xy 434.2638 -294.824404) (xy 434.779674 -294.824404) (xy 434.787483 -294.824079)
			(xy 434.802354 -294.819301) (xy 434.808884 -294.815006) (xy 434.829973 -294.800657) (xy 434.875634 -294.777926)
			(xy 434.92424 -294.762467) (xy 434.974643 -294.754644) (xy 435.025649 -294.754644) (xy 435.076052 -294.762467)
			(xy 435.124658 -294.777926) (xy 435.170319 -294.800657) (xy 435.191408 -294.815006) (xy 435.197938 -294.8193)
			(xy 435.212809 -294.824081) (xy 435.220618 -294.824404) (xy 435.736746 -294.824404) (xy 435.742035 -294.824955)
			(xy 435.749607 -294.832336) (xy 435.750208 -294.837612) (xy 435.750208 -295.33215) (xy 438.350152 -295.33215)
			(xy 438.350152 -294.837612) (xy 438.350699 -294.83236) (xy 438.35811 -294.824919) (xy 438.36336 -294.824404)
			(xy 438.363868 -294.824404) (xy 438.879742 -294.824404) (xy 438.88755 -294.824065) (xy 438.902421 -294.819296)
			(xy 438.908952 -294.815006) (xy 438.930041 -294.800657) (xy 438.975702 -294.777926) (xy 439.024308 -294.762467)
			(xy 439.074711 -294.754644) (xy 439.125717 -294.754644) (xy 439.17612 -294.762467) (xy 439.224726 -294.777926)
			(xy 439.270387 -294.800657) (xy 439.291476 -294.815006) (xy 439.298013 -294.819287) (xy 439.312879 -294.824076)
			(xy 439.320686 -294.824404) (xy 439.836814 -294.824404) (xy 439.842112 -294.824909) (xy 439.84968 -294.832325)
			(xy 439.850276 -294.837612) (xy 439.850276 -295.33215) (xy 439.850253 -295.332404) (xy 441.794392 -295.332404)
			(xy 441.794392 -295.331896) (xy 441.794392 -294.837612) (xy 441.794735 -294.832281) (xy 441.80227 -294.82474)
			(xy 441.8076 -294.824404) (xy 442.323728 -294.824404) (xy 442.331539 -294.824101) (xy 442.34641 -294.819308)
			(xy 442.352938 -294.815006) (xy 442.374027 -294.800657) (xy 442.419688 -294.777926) (xy 442.468294 -294.762467)
			(xy 442.518697 -294.754644) (xy 442.569703 -294.754644) (xy 442.620106 -294.762467) (xy 442.668712 -294.777926)
			(xy 442.714373 -294.800657) (xy 442.735462 -294.815006) (xy 442.742002 -294.819282) (xy 442.756866 -294.824074)
			(xy 442.764672 -294.824404) (xy 443.2808 -294.824404) (xy 443.286135 -294.824728) (xy 443.293677 -294.832276)
			(xy 443.294008 -294.837612) (xy 443.294008 -295.33215) (xy 443.293981 -295.332404) (xy 445.89446 -295.332404)
			(xy 445.89446 -295.331896) (xy 445.89446 -294.837612) (xy 445.895 -294.832358) (xy 445.902416 -294.824917)
			(xy 445.907668 -294.824404) (xy 446.423796 -294.824404) (xy 446.431606 -294.824088) (xy 446.446477 -294.819303)
			(xy 446.453006 -294.815006) (xy 446.474095 -294.800657) (xy 446.519756 -294.777926) (xy 446.568362 -294.762467)
			(xy 446.618765 -294.754644) (xy 446.669771 -294.754644) (xy 446.720174 -294.762467) (xy 446.76878 -294.777926)
			(xy 446.814441 -294.800657) (xy 446.83553 -294.815006) (xy 446.842055 -294.819308) (xy 446.85693 -294.824084)
			(xy 446.86474 -294.824404) (xy 447.380868 -294.824404) (xy 447.386199 -294.82475) (xy 447.393742 -294.832282)
			(xy 447.394076 -294.837612) (xy 447.394076 -295.33215) (xy 447.394051 -295.332404) (xy 449.338192 -295.332404)
			(xy 449.338192 -295.331896) (xy 449.338192 -294.837612) (xy 449.338535 -294.832281) (xy 449.34607 -294.82474)
			(xy 449.3514 -294.824404) (xy 449.867528 -294.824404) (xy 449.875339 -294.824101) (xy 449.89021 -294.819308)
			(xy 449.896738 -294.815006) (xy 449.917827 -294.800657) (xy 449.963488 -294.777926) (xy 450.012094 -294.762467)
			(xy 450.062497 -294.754644) (xy 450.113503 -294.754644) (xy 450.163906 -294.762467) (xy 450.212512 -294.777926)
			(xy 450.258173 -294.800657) (xy 450.279262 -294.815006) (xy 450.285802 -294.819282) (xy 450.300666 -294.824074)
			(xy 450.308472 -294.824404) (xy 450.8246 -294.824404) (xy 450.829935 -294.824728) (xy 450.837477 -294.832276)
			(xy 450.837808 -294.837612) (xy 450.837808 -295.33215) (xy 450.837781 -295.332404) (xy 453.43826 -295.332404)
			(xy 453.43826 -295.331896) (xy 453.43826 -294.837612) (xy 453.4388 -294.832358) (xy 453.446216 -294.824917)
			(xy 453.451468 -294.824404) (xy 453.967596 -294.824404) (xy 453.975406 -294.824088) (xy 453.990277 -294.819303)
			(xy 453.996806 -294.815006) (xy 454.017895 -294.800657) (xy 454.063556 -294.777926) (xy 454.112162 -294.762467)
			(xy 454.162565 -294.754644) (xy 454.213571 -294.754644) (xy 454.263974 -294.762467) (xy 454.31258 -294.777926)
			(xy 454.358241 -294.800657) (xy 454.37933 -294.815006) (xy 454.385855 -294.819308) (xy 454.40073 -294.824084)
			(xy 454.40854 -294.824404) (xy 454.924668 -294.824404) (xy 454.929999 -294.82475) (xy 454.937542 -294.832282)
			(xy 454.937876 -294.837612) (xy 454.937876 -295.33215) (xy 454.937345 -295.337444) (xy 454.92995 -295.345017)
			(xy 454.924668 -295.345612) (xy 454.408794 -295.345612) (xy 454.400983 -295.345921) (xy 454.386112 -295.35071)
			(xy 454.379584 -295.35501) (xy 454.358461 -295.369357) (xy 454.312738 -295.392086) (xy 454.264065 -295.407517)
			(xy 454.213599 -295.415283) (xy 454.188068 -295.415716) (xy 454.162538 -295.415286) (xy 454.112074 -295.407507)
			(xy 454.063402 -295.392075) (xy 454.017674 -295.369358) (xy 453.996552 -295.35501) (xy 453.99003 -295.350702)
			(xy 453.975153 -295.345929) (xy 453.967342 -295.345612) (xy 453.451468 -295.345612) (xy 453.446202 -295.345127)
			(xy 453.438762 -295.337671) (xy 453.43826 -295.332404) (xy 450.837781 -295.332404) (xy 450.837249 -295.337437)
			(xy 450.829873 -295.345008) (xy 450.8246 -295.345612) (xy 450.308726 -295.345612) (xy 450.300917 -295.345935)
			(xy 450.286045 -295.350714) (xy 450.279516 -295.35501) (xy 450.258384 -295.369344) (xy 450.212664 -295.392075)
			(xy 450.163994 -295.40751) (xy 450.11353 -295.415281) (xy 450.088 -295.415716) (xy 450.06247 -295.41527)
			(xy 450.012007 -295.407496) (xy 449.963335 -295.392069) (xy 449.917607 -295.369356) (xy 449.896484 -295.35501)
			(xy 449.889955 -295.350715) (xy 449.875083 -295.345934) (xy 449.867274 -295.345612) (xy 449.3514 -295.345612)
			(xy 449.346138 -295.345106) (xy 449.338696 -295.337666) (xy 449.338192 -295.332404) (xy 447.394051 -295.332404)
			(xy 447.393545 -295.337444) (xy 447.38615 -295.345017) (xy 447.380868 -295.345612) (xy 446.864994 -295.345612)
			(xy 446.857183 -295.345921) (xy 446.842312 -295.35071) (xy 446.835784 -295.35501) (xy 446.814661 -295.369357)
			(xy 446.768938 -295.392086) (xy 446.720265 -295.407517) (xy 446.669799 -295.415283) (xy 446.644268 -295.415716)
			(xy 446.618738 -295.415286) (xy 446.568274 -295.407507) (xy 446.519602 -295.392075) (xy 446.473874 -295.369358)
			(xy 446.452752 -295.35501) (xy 446.44623 -295.350702) (xy 446.431353 -295.345929) (xy 446.423542 -295.345612)
			(xy 445.907668 -295.345612) (xy 445.902402 -295.345127) (xy 445.894962 -295.337671) (xy 445.89446 -295.332404)
			(xy 443.293981 -295.332404) (xy 443.293449 -295.337437) (xy 443.286073 -295.345008) (xy 443.2808 -295.345612)
			(xy 442.764926 -295.345612) (xy 442.757117 -295.345935) (xy 442.742245 -295.350714) (xy 442.735716 -295.35501)
			(xy 442.714584 -295.369344) (xy 442.668864 -295.392075) (xy 442.620194 -295.40751) (xy 442.56973 -295.415281)
			(xy 442.5442 -295.415716) (xy 442.51867 -295.41527) (xy 442.468207 -295.407496) (xy 442.419535 -295.392069)
			(xy 442.373807 -295.369356) (xy 442.352684 -295.35501) (xy 442.346155 -295.350715) (xy 442.331283 -295.345934)
			(xy 442.323474 -295.345612) (xy 441.8076 -295.345612) (xy 441.802338 -295.345106) (xy 441.794896 -295.337666)
			(xy 441.794392 -295.332404) (xy 439.850253 -295.332404) (xy 439.849784 -295.337517) (xy 439.842182 -295.345098)
			(xy 439.836814 -295.345612) (xy 439.32094 -295.345612) (xy 439.313131 -295.34594) (xy 439.29826 -295.350716)
			(xy 439.29173 -295.35501) (xy 439.270622 -295.369381) (xy 439.224894 -295.392104) (xy 439.176216 -295.407528)
			(xy 439.125746 -295.415287) (xy 439.100214 -295.415716) (xy 439.074684 -295.415263) (xy 439.024222 -295.407491)
			(xy 438.975549 -295.392066) (xy 438.929821 -295.369355) (xy 438.908698 -295.35501) (xy 438.902166 -295.35072)
			(xy 438.887296 -295.345936) (xy 438.879488 -295.345612) (xy 438.363614 -295.345612) (xy 438.358264 -295.345045)
			(xy 438.35068 -295.337498) (xy 438.350152 -295.33215) (xy 435.750208 -295.33215) (xy 435.749687 -295.337509)
			(xy 435.742105 -295.345089) (xy 435.736746 -295.345612) (xy 435.220872 -295.345612) (xy 435.213061 -295.345912)
			(xy 435.198189 -295.350707) (xy 435.191662 -295.35501) (xy 435.170545 -295.369367) (xy 435.12482 -295.392093)
			(xy 435.076145 -295.407521) (xy 435.025677 -295.415285) (xy 435.000146 -295.415716) (xy 434.974617 -295.415247)
			(xy 434.924155 -295.407479) (xy 434.875483 -295.39206) (xy 434.829754 -295.369353) (xy 434.80863 -295.35501)
			(xy 434.802091 -295.350732) (xy 434.787227 -295.345941) (xy 434.77942 -295.345612) (xy 434.263546 -295.345612)
			(xy 434.258199 -295.345024) (xy 434.250614 -295.337493) (xy 434.250084 -295.33215) (xy 432.305968 -295.33215)
			(xy 432.305444 -295.337446) (xy 432.298044 -295.34502) (xy 432.29276 -295.345612) (xy 431.776886 -295.345612)
			(xy 431.769075 -295.345918) (xy 431.754204 -295.350709) (xy 431.747676 -295.35501) (xy 431.726555 -295.369361)
			(xy 431.680832 -295.392088) (xy 431.632158 -295.407518) (xy 431.581691 -295.415284) (xy 431.55616 -295.415716)
			(xy 431.530629 -295.41529) (xy 431.480166 -295.40751) (xy 431.431493 -295.392077) (xy 431.385766 -295.369358)
			(xy 431.364644 -295.35501) (xy 431.358124 -295.350699) (xy 431.343245 -295.345928) (xy 431.335434 -295.345612)
			(xy 430.81956 -295.345612) (xy 430.814293 -295.345132) (xy 430.806853 -295.337672) (xy 430.806352 -295.332404)
			(xy 428.205873 -295.332404) (xy 428.205348 -295.337439) (xy 428.197967 -295.34501) (xy 428.192692 -295.345612)
			(xy 427.676818 -295.345612) (xy 427.669008 -295.345931) (xy 427.654137 -295.350713) (xy 427.647608 -295.35501)
			(xy 427.626478 -295.369347) (xy 427.580758 -295.392078) (xy 427.532087 -295.407511) (xy 427.481622 -295.415281)
			(xy 427.456092 -295.415716) (xy 427.430562 -295.415274) (xy 427.380099 -295.407498) (xy 427.331427 -295.39207)
			(xy 427.285699 -295.369356) (xy 427.264576 -295.35501) (xy 427.258049 -295.350712) (xy 427.243175 -295.345933)
			(xy 427.235366 -295.345612) (xy 426.719492 -295.345612) (xy 426.714229 -295.345111) (xy 426.706787 -295.337667)
			(xy 426.706284 -295.332404) (xy 424.762145 -295.332404) (xy 424.761683 -295.337519) (xy 424.754076 -295.345101)
			(xy 424.748706 -295.345612) (xy 424.232832 -295.345612) (xy 424.225023 -295.345937) (xy 424.210151 -295.350715)
			(xy 424.203622 -295.35501) (xy 424.182488 -295.369341) (xy 424.136769 -295.392073) (xy 424.0881 -295.407508)
			(xy 424.037636 -295.41528) (xy 424.012106 -295.415716) (xy 423.986576 -295.415267) (xy 423.936113 -295.407493)
			(xy 423.887441 -295.392068) (xy 423.841713 -295.369355) (xy 423.82059 -295.35501) (xy 423.814059 -295.350717)
			(xy 423.799189 -295.345935) (xy 423.79138 -295.345612) (xy 423.275506 -295.345612) (xy 423.270155 -295.345051)
			(xy 423.262571 -295.337499) (xy 423.262044 -295.33215) (xy 420.6621 -295.33215) (xy 420.661586 -295.337511)
			(xy 420.653999 -295.345091) (xy 420.648638 -295.345612) (xy 420.132764 -295.345612) (xy 420.124956 -295.345951)
			(xy 420.110085 -295.35072) (xy 420.103554 -295.35501) (xy 420.082439 -295.36937) (xy 420.036714 -295.392096)
			(xy 419.988038 -295.407523) (xy 419.93757 -295.415285) (xy 419.912038 -295.415716) (xy 419.886509 -295.415251)
			(xy 419.836047 -295.407482) (xy 419.787374 -295.392061) (xy 419.741645 -295.369353) (xy 419.720522 -295.35501)
			(xy 419.713984 -295.350729) (xy 419.699119 -295.34594) (xy 419.691312 -295.345612) (xy 419.175438 -295.345612)
			(xy 419.17009 -295.345029) (xy 419.162506 -295.337494) (xy 419.161976 -295.33215) (xy 417.21786 -295.33215)
			(xy 417.217343 -295.337448) (xy 417.209938 -295.345022) (xy 417.204652 -295.345612) (xy 415.731452 -295.345612)
			(xy 415.726184 -295.345137) (xy 415.718745 -295.337673) (xy 415.718244 -295.332404) (xy 413.117766 -295.332404)
			(xy 413.117247 -295.337441) (xy 413.109861 -295.345013) (xy 413.104584 -295.345612) (xy 411.631384 -295.345612)
			(xy 411.62612 -295.345117) (xy 411.618679 -295.337668) (xy 411.618176 -295.332404) (xy 308.118234 -295.332404)
			(xy 308.117782 -295.337521) (xy 308.110167 -295.345104) (xy 308.104794 -295.345612) (xy 306.631594 -295.345612)
			(xy 306.626241 -295.345059) (xy 306.618659 -295.337501) (xy 306.618132 -295.33215) (xy 304.018188 -295.33215)
			(xy 304.017685 -295.337514) (xy 304.010091 -295.345095) (xy 304.004726 -295.345612) (xy 302.531526 -295.345612)
			(xy 302.526177 -295.345037) (xy 302.518593 -295.337496) (xy 302.518064 -295.33215) (xy 300.573948 -295.33215)
			(xy 300.573442 -295.337451) (xy 300.566029 -295.345025) (xy 300.56074 -295.345612) (xy 300.044866 -295.345612)
			(xy 300.037058 -295.345952) (xy 300.022187 -295.35072) (xy 300.015656 -295.35501) (xy 299.994541 -295.36937)
			(xy 299.948815 -295.392095) (xy 299.90014 -295.407523) (xy 299.849672 -295.415285) (xy 299.82414 -295.415716)
			(xy 299.798611 -295.41525) (xy 299.748149 -295.407482) (xy 299.699476 -295.392061) (xy 299.653747 -295.369353)
			(xy 299.632624 -295.35501) (xy 299.626086 -295.35073) (xy 299.611221 -295.34594) (xy 299.603414 -295.345612)
			(xy 299.08754 -295.345612) (xy 299.082214 -295.345247) (xy 299.074671 -295.337729) (xy 299.074332 -295.332404)
			(xy 296.473854 -295.332404) (xy 296.473346 -295.337444) (xy 296.465953 -295.345016) (xy 296.460672 -295.345612)
			(xy 295.944798 -295.345612) (xy 295.936988 -295.345923) (xy 295.922116 -295.350711) (xy 295.915588 -295.35501)
			(xy 295.894464 -295.369356) (xy 295.848741 -295.392084) (xy 295.800069 -295.407516) (xy 295.749603 -295.415283)
			(xy 295.724072 -295.415716) (xy 295.698542 -295.415284) (xy 295.648078 -295.407505) (xy 295.599406 -295.392075)
			(xy 295.553678 -295.369357) (xy 295.532556 -295.35501) (xy 295.526033 -295.350704) (xy 295.511156 -295.34593)
			(xy 295.503346 -295.345612) (xy 294.987472 -295.345612) (xy 294.982207 -295.345124) (xy 294.974766 -295.33767)
			(xy 294.974264 -295.332404) (xy 293.030126 -295.332404) (xy 293.029681 -295.337523) (xy 293.022062 -295.345107)
			(xy 293.016686 -295.345612) (xy 292.500812 -295.345612) (xy 292.493002 -295.345929) (xy 292.478131 -295.350712)
			(xy 292.471602 -295.35501) (xy 292.450474 -295.36935) (xy 292.404753 -295.39208) (xy 292.356082 -295.407513)
			(xy 292.305616 -295.415282) (xy 292.280086 -295.415716) (xy 292.254556 -295.415277) (xy 292.204093 -295.4075)
			(xy 292.15542 -295.392072) (xy 292.109692 -295.369356) (xy 292.08857 -295.35501) (xy 292.082044 -295.350709)
			(xy 292.06717 -295.345932) (xy 292.05936 -295.345612) (xy 291.543486 -295.345612) (xy 291.538132 -295.345064)
			(xy 291.530551 -295.337502) (xy 291.530024 -295.33215) (xy 288.93008 -295.33215) (xy 288.929584 -295.337516)
			(xy 288.921985 -295.345097) (xy 288.916618 -295.345612) (xy 288.400744 -295.345612) (xy 288.392935 -295.345942)
			(xy 288.378064 -295.350717) (xy 288.371534 -295.35501) (xy 288.350425 -295.369379) (xy 288.304697 -295.392102)
			(xy 288.25602 -295.407527) (xy 288.20555 -295.415287) (xy 288.180018 -295.415716) (xy 288.154489 -295.415261)
			(xy 288.104026 -295.407489) (xy 288.055354 -295.392065) (xy 288.009625 -295.369354) (xy 287.988502 -295.35501)
			(xy 287.981969 -295.350722) (xy 287.9671 -295.345937) (xy 287.959292 -295.345612) (xy 287.443418 -295.345612)
			(xy 287.438068 -295.345043) (xy 287.430484 -295.337497) (xy 287.429956 -295.33215) (xy 285.48584 -295.33215)
			(xy 285.485341 -295.337453) (xy 285.477924 -295.345028) (xy 285.472632 -295.345612) (xy 284.956758 -295.345612)
			(xy 284.94895 -295.345949) (xy 284.934078 -295.350719) (xy 284.927548 -295.35501) (xy 284.906435 -295.369373)
			(xy 284.860709 -295.392098) (xy 284.812033 -295.407524) (xy 284.761564 -295.415286) (xy 284.736032 -295.415716)
			(xy 284.710503 -295.415254) (xy 284.66004 -295.407484) (xy 284.611368 -295.392062) (xy 284.565639 -295.369353)
			(xy 284.544516 -295.35501) (xy 284.53798 -295.350727) (xy 284.523113 -295.345939) (xy 284.515306 -295.345612)
			(xy 283.999432 -295.345612) (xy 283.994105 -295.345252) (xy 283.986563 -295.33773) (xy 283.986224 -295.332404)
			(xy 281.385747 -295.332404) (xy 281.385245 -295.337445) (xy 281.377847 -295.345018) (xy 281.372564 -295.345612)
			(xy 280.85669 -295.345612) (xy 280.848879 -295.345919) (xy 280.834008 -295.35071) (xy 280.82748 -295.35501)
			(xy 280.806358 -295.369359) (xy 280.760635 -295.392087) (xy 280.711962 -295.407517) (xy 280.661495 -295.415284)
			(xy 280.635964 -295.415716) (xy 280.610434 -295.415288) (xy 280.55997 -295.407508) (xy 280.511298 -295.392076)
			(xy 280.46557 -295.369358) (xy 280.444448 -295.35501) (xy 280.437927 -295.350701) (xy 280.423049 -295.345929)
			(xy 280.415238 -295.345612) (xy 279.899364 -295.345612) (xy 279.894098 -295.345129) (xy 279.886658 -295.337671)
			(xy 279.886156 -295.332404) (xy 277.942016 -295.332404) (xy 277.941541 -295.337453) (xy 277.934124 -295.345028)
			(xy 277.928832 -295.345612) (xy 277.412958 -295.345612) (xy 277.40515 -295.345949) (xy 277.390278 -295.350719)
			(xy 277.383748 -295.35501) (xy 277.362635 -295.369373) (xy 277.316909 -295.392098) (xy 277.268233 -295.407524)
			(xy 277.217764 -295.415286) (xy 277.192232 -295.415716) (xy 277.166703 -295.415254) (xy 277.11624 -295.407484)
			(xy 277.067568 -295.392062) (xy 277.021839 -295.369353) (xy 277.000716 -295.35501) (xy 276.99418 -295.350727)
			(xy 276.979313 -295.345939) (xy 276.971506 -295.345612) (xy 276.455632 -295.345612) (xy 276.450305 -295.345252)
			(xy 276.442763 -295.33773) (xy 276.442424 -295.332404) (xy 273.841947 -295.332404) (xy 273.841445 -295.337445)
			(xy 273.834047 -295.345018) (xy 273.828764 -295.345612) (xy 273.31289 -295.345612) (xy 273.305079 -295.345919)
			(xy 273.290208 -295.35071) (xy 273.28368 -295.35501) (xy 273.262558 -295.369359) (xy 273.216835 -295.392087)
			(xy 273.168162 -295.407517) (xy 273.117695 -295.415284) (xy 273.092164 -295.415716) (xy 273.066634 -295.415288)
			(xy 273.01617 -295.407508) (xy 272.967498 -295.392076) (xy 272.92177 -295.369358) (xy 272.900648 -295.35501)
			(xy 272.894127 -295.350701) (xy 272.879249 -295.345929) (xy 272.871438 -295.345612) (xy 272.355564 -295.345612)
			(xy 272.350298 -295.345129) (xy 272.342858 -295.337671) (xy 272.342356 -295.332404) (xy 270.398218 -295.332404)
			(xy 270.39778 -295.337525) (xy 270.390156 -295.345109) (xy 270.384778 -295.345612) (xy 269.868904 -295.345612)
			(xy 269.861094 -295.345925) (xy 269.846222 -295.350711) (xy 269.839694 -295.35501) (xy 269.818568 -295.369353)
			(xy 269.772846 -295.392082) (xy 269.724174 -295.407514) (xy 269.673709 -295.415282) (xy 269.648178 -295.415716)
			(xy 269.622648 -295.415281) (xy 269.572184 -295.407503) (xy 269.523512 -295.392073) (xy 269.477784 -295.369357)
			(xy 269.456662 -295.35501) (xy 269.450138 -295.350706) (xy 269.435262 -295.345931) (xy 269.427452 -295.345612)
			(xy 268.911578 -295.345612) (xy 268.906223 -295.345069) (xy 268.898642 -295.337503) (xy 268.898116 -295.33215)
			(xy 266.298172 -295.33215) (xy 266.297684 -295.337518) (xy 266.290079 -295.3451) (xy 266.28471 -295.345612)
			(xy 265.768836 -295.345612) (xy 265.761027 -295.345939) (xy 265.746155 -295.350715) (xy 265.739626 -295.35501)
			(xy 265.718491 -295.369339) (xy 265.672773 -295.392072) (xy 265.624103 -295.407508) (xy 265.57364 -295.41528)
			(xy 265.54811 -295.415716) (xy 265.52258 -295.415265) (xy 265.472118 -295.407492) (xy 265.423445 -295.392067)
			(xy 265.377717 -295.369355) (xy 265.356594 -295.35501) (xy 265.350063 -295.350719) (xy 265.335193 -295.345935)
			(xy 265.327384 -295.345612) (xy 264.81151 -295.345612) (xy 264.806159 -295.345048) (xy 264.798576 -295.337498)
			(xy 264.798048 -295.33215) (xy 206.997808 -295.33215) (xy 206.997808 -295.332404) (xy 206.997308 -295.337667)
			(xy 206.989863 -295.34511) (xy 206.9846 -295.345612) (xy 206.468726 -295.345612) (xy 206.46085 -295.345882)
			(xy 206.445846 -295.350678) (xy 206.439262 -295.35501) (xy 206.418182 -295.369398) (xy 206.372539 -295.392229)
			(xy 206.323933 -295.407788) (xy 206.273517 -295.415707) (xy 206.248 -295.416224) (xy 206.222479 -295.415747)
			(xy 206.172052 -295.407848) (xy 206.123441 -295.392284) (xy 206.077803 -295.369426) (xy 206.056738 -295.35501)
			(xy 206.050139 -295.350708) (xy 206.035145 -295.345913) (xy 206.027274 -295.345612) (xy 205.5114 -295.345612)
			(xy 205.506138 -295.345106) (xy 205.498696 -295.337666) (xy 205.498192 -295.332404) (xy 202.89774 -295.332404)
			(xy 202.897211 -295.33766) (xy 202.889787 -295.3451) (xy 202.884532 -295.345612) (xy 202.368658 -295.345612)
			(xy 202.360783 -295.345896) (xy 202.34578 -295.350683) (xy 202.339194 -295.35501) (xy 202.318106 -295.369385)
			(xy 202.272465 -295.392218) (xy 202.223862 -295.407781) (xy 202.173448 -295.415705) (xy 202.147932 -295.416224)
			(xy 202.122412 -295.415731) (xy 202.071985 -295.407837) (xy 202.023374 -295.392278) (xy 201.977735 -295.369424)
			(xy 201.95667 -295.35501) (xy 201.950086 -295.350681) (xy 201.93508 -295.345903) (xy 201.927206 -295.345612)
			(xy 201.411332 -295.345612) (xy 201.406005 -295.345252) (xy 201.398463 -295.33773) (xy 201.398124 -295.332404)
			(xy 199.454008 -295.332404) (xy 199.453508 -295.337667) (xy 199.446063 -295.34511) (xy 199.4408 -295.345612)
			(xy 198.924926 -295.345612) (xy 198.91705 -295.345882) (xy 198.902046 -295.350678) (xy 198.895462 -295.35501)
			(xy 198.874382 -295.369398) (xy 198.828739 -295.392229) (xy 198.780133 -295.407788) (xy 198.729717 -295.415707)
			(xy 198.7042 -295.416224) (xy 198.678679 -295.415747) (xy 198.628252 -295.407848) (xy 198.579641 -295.392284)
			(xy 198.534003 -295.369426) (xy 198.512938 -295.35501) (xy 198.506339 -295.350708) (xy 198.491345 -295.345913)
			(xy 198.483474 -295.345612) (xy 197.9676 -295.345612) (xy 197.962338 -295.345106) (xy 197.954896 -295.337666)
			(xy 197.954392 -295.332404) (xy 195.35394 -295.332404) (xy 195.353411 -295.33766) (xy 195.345987 -295.3451)
			(xy 195.340732 -295.345612) (xy 194.824858 -295.345612) (xy 194.816983 -295.345896) (xy 194.80198 -295.350683)
			(xy 194.795394 -295.35501) (xy 194.774306 -295.369385) (xy 194.728665 -295.392218) (xy 194.680062 -295.407781)
			(xy 194.629648 -295.415705) (xy 194.604132 -295.416224) (xy 194.578612 -295.415731) (xy 194.528185 -295.407837)
			(xy 194.479574 -295.392278) (xy 194.433935 -295.369424) (xy 194.41287 -295.35501) (xy 194.406286 -295.350681)
			(xy 194.39128 -295.345903) (xy 194.383406 -295.345612) (xy 193.867532 -295.345612) (xy 193.862205 -295.345252)
			(xy 193.854663 -295.33773) (xy 193.854324 -295.332404) (xy 191.910208 -295.332404) (xy 191.909708 -295.337667)
			(xy 191.902263 -295.34511) (xy 191.897 -295.345612) (xy 191.896492 -295.345612) (xy 191.380872 -295.345612)
			(xy 191.372998 -295.345901) (xy 191.357994 -295.350685) (xy 191.351408 -295.35501) (xy 191.330344 -295.369422)
			(xy 191.284694 -295.392247) (xy 191.236084 -295.407799) (xy 191.185664 -295.415711) (xy 191.160146 -295.416224)
			(xy 191.134626 -295.415724) (xy 191.0842 -295.407832) (xy 191.035588 -295.392275) (xy 190.98995 -295.369423)
			(xy 190.968884 -295.35501) (xy 190.962297 -295.350687) (xy 190.947294 -295.345905) (xy 190.93942 -295.345612)
			(xy 190.423546 -295.345612) (xy 190.418236 -295.34514) (xy 190.41066 -295.337704) (xy 190.410084 -295.332404)
			(xy 187.81014 -295.332404) (xy 187.809611 -295.33766) (xy 187.802187 -295.3451) (xy 187.796932 -295.345612)
			(xy 187.796424 -295.345612) (xy 187.280804 -295.345612) (xy 187.272931 -295.345915) (xy 187.257927 -295.350689)
			(xy 187.25134 -295.35501) (xy 187.230267 -295.369408) (xy 187.184621 -295.392236) (xy 187.136013 -295.407792)
			(xy 187.085595 -295.415709) (xy 187.060078 -295.416224) (xy 187.034559 -295.415708) (xy 186.984133 -295.407821)
			(xy 186.935522 -295.392268) (xy 186.889882 -295.369421) (xy 186.868816 -295.35501) (xy 186.862222 -295.350699)
			(xy 186.847224 -295.34591) (xy 186.839352 -295.345612) (xy 186.323478 -295.345612) (xy 186.31816 -295.345186)
			(xy 186.310587 -295.337715) (xy 186.310016 -295.332404) (xy 184.3659 -295.332404) (xy 184.365575 -295.337739)
			(xy 184.358027 -295.34528) (xy 184.352692 -295.345612) (xy 183.836818 -295.345612) (xy 183.828945 -295.345922)
			(xy 183.813942 -295.350691) (xy 183.807354 -295.35501) (xy 183.786277 -295.369402) (xy 183.740632 -295.392231)
			(xy 183.692026 -295.407789) (xy 183.641609 -295.415708) (xy 183.616092 -295.416224) (xy 183.590573 -295.415701)
			(xy 183.540148 -295.407816) (xy 183.491536 -295.392265) (xy 183.445896 -295.36942) (xy 183.42483 -295.35501)
			(xy 183.418233 -295.350705) (xy 183.403237 -295.345912) (xy 183.395366 -295.345612) (xy 182.879492 -295.345612)
			(xy 182.874229 -295.345111) (xy 182.866787 -295.337667) (xy 182.866284 -295.332404) (xy 180.265832 -295.332404)
			(xy 180.265311 -295.337662) (xy 180.257881 -295.345103) (xy 180.252624 -295.345612) (xy 179.73675 -295.345612)
			(xy 179.728875 -295.345892) (xy 179.713871 -295.350682) (xy 179.707286 -295.35501) (xy 179.6862 -295.369388)
			(xy 179.640558 -295.392221) (xy 179.591955 -295.407782) (xy 179.54154 -295.415705) (xy 179.516024 -295.416224)
			(xy 179.490504 -295.415735) (xy 179.440077 -295.40784) (xy 179.391466 -295.392279) (xy 179.345827 -295.369425)
			(xy 179.324762 -295.35501) (xy 179.31818 -295.350678) (xy 179.303173 -295.345902) (xy 179.295298 -295.345612)
			(xy 178.779424 -295.345612) (xy 178.774096 -295.345257) (xy 178.766554 -295.337731) (xy 178.766216 -295.332404)
			(xy 176.8221 -295.332404) (xy 176.821775 -295.337739) (xy 176.814227 -295.34528) (xy 176.808892 -295.345612)
			(xy 176.808384 -295.345612) (xy 176.292764 -295.345612) (xy 176.284889 -295.345898) (xy 176.269886 -295.350683)
			(xy 176.2633 -295.35501) (xy 176.24221 -295.369382) (xy 176.19657 -295.392216) (xy 176.147968 -295.407779)
			(xy 176.097554 -295.415704) (xy 176.072038 -295.416224) (xy 176.046518 -295.415728) (xy 175.996092 -295.407835)
			(xy 175.94748 -295.392276) (xy 175.901841 -295.369424) (xy 175.880776 -295.35501) (xy 175.874191 -295.350684)
			(xy 175.859186 -295.345904) (xy 175.851312 -295.345612) (xy 175.335438 -295.345612) (xy 175.330127 -295.345146)
			(xy 175.322551 -295.337705) (xy 175.321976 -295.332404) (xy 172.722032 -295.332404) (xy 172.721511 -295.337662)
			(xy 172.714081 -295.345103) (xy 172.708824 -295.345612) (xy 172.708316 -295.345612) (xy 172.192696 -295.345612)
			(xy 172.184823 -295.345912) (xy 172.169819 -295.350688) (xy 172.163232 -295.35501) (xy 172.142161 -295.369411)
			(xy 172.096514 -295.392239) (xy 172.047906 -295.407794) (xy 171.997487 -295.415709) (xy 171.97197 -295.416224)
			(xy 171.946451 -295.415712) (xy 171.896025 -295.407823) (xy 171.847413 -295.39227) (xy 171.801774 -295.369422)
			(xy 171.780708 -295.35501) (xy 171.774116 -295.350696) (xy 171.759116 -295.345908) (xy 171.751244 -295.345612)
			(xy 171.23537 -295.345612) (xy 171.230051 -295.345191) (xy 171.222479 -295.337716) (xy 171.221908 -295.332404)
			(xy 169.277792 -295.332404) (xy 169.277474 -295.337741) (xy 169.269921 -295.345282) (xy 169.264584 -295.345612)
			(xy 167.791384 -295.345612) (xy 167.78612 -295.345117) (xy 167.778679 -295.337668) (xy 167.778176 -295.332404)
			(xy 165.177724 -295.332404) (xy 165.17721 -295.337663) (xy 165.169775 -295.345105) (xy 165.164516 -295.345612)
			(xy 163.691316 -295.345612) (xy 163.685987 -295.345263) (xy 163.678445 -295.337733) (xy 163.678108 -295.332404)
			(xy 60.178188 -295.332404) (xy 60.177874 -295.337742) (xy 60.170318 -295.345283) (xy 60.16498 -295.345612)
			(xy 60.164472 -295.345612) (xy 58.691526 -295.345612) (xy 58.686214 -295.345154) (xy 58.678638 -295.337707)
			(xy 58.678064 -295.332404) (xy 56.07812 -295.332404) (xy 56.077609 -295.337664) (xy 56.070172 -295.345106)
			(xy 56.064912 -295.345612) (xy 54.591458 -295.345612) (xy 54.586137 -295.345199) (xy 54.578566 -295.337718)
			(xy 54.577996 -295.332404) (xy 52.63388 -295.332404) (xy 52.633573 -295.337744) (xy 52.626012 -295.345286)
			(xy 52.620672 -295.345612) (xy 52.104798 -295.345612) (xy 52.096925 -295.345913) (xy 52.081921 -295.350688)
			(xy 52.075334 -295.35501) (xy 52.054262 -295.369411) (xy 52.008616 -295.392238) (xy 51.960008 -295.407793)
			(xy 51.909589 -295.415709) (xy 51.884072 -295.416224) (xy 51.858553 -295.415711) (xy 51.808127 -295.407823)
			(xy 51.759515 -295.39227) (xy 51.713876 -295.369422) (xy 51.69281 -295.35501) (xy 51.686217 -295.350697)
			(xy 51.671218 -295.345909) (xy 51.663346 -295.345612) (xy 51.147472 -295.345612) (xy 51.142207 -295.345124)
			(xy 51.134766 -295.33767) (xy 51.134264 -295.332404) (xy 48.533812 -295.332404) (xy 48.533309 -295.337666)
			(xy 48.525866 -295.345109) (xy 48.520604 -295.345612) (xy 48.00473 -295.345612) (xy 47.996854 -295.345884)
			(xy 47.981851 -295.350679) (xy 47.975266 -295.35501) (xy 47.954185 -295.369397) (xy 47.908542 -295.392227)
			(xy 47.859937 -295.407787) (xy 47.80952 -295.415707) (xy 47.784004 -295.416224) (xy 47.758483 -295.415745)
			(xy 47.708056 -295.407847) (xy 47.659445 -295.392283) (xy 47.613807 -295.369426) (xy 47.592742 -295.35501)
			(xy 47.586165 -295.350671) (xy 47.571154 -295.345899) (xy 47.563278 -295.345612) (xy 47.047404 -295.345612)
			(xy 47.042143 -295.345103) (xy 47.0347 -295.337665) (xy 47.034196 -295.332404) (xy 45.09008 -295.332404)
			(xy 45.089773 -295.337744) (xy 45.082212 -295.345286) (xy 45.076872 -295.345612) (xy 45.076364 -295.345612)
			(xy 44.560744 -295.345612) (xy 44.552869 -295.34589) (xy 44.537865 -295.350681) (xy 44.53128 -295.35501)
			(xy 44.510195 -295.369391) (xy 44.464554 -295.392223) (xy 44.41595 -295.407784) (xy 44.365534 -295.415706)
			(xy 44.340018 -295.416224) (xy 44.314498 -295.415738) (xy 44.264071 -295.407842) (xy 44.215459 -295.39228)
			(xy 44.169821 -295.369425) (xy 44.148756 -295.35501) (xy 44.142176 -295.350676) (xy 44.127167 -295.345901)
			(xy 44.119292 -295.345612) (xy 43.603418 -295.345612) (xy 43.598105 -295.345159) (xy 43.59053 -295.337709)
			(xy 43.589956 -295.332404) (xy 40.990012 -295.332404) (xy 40.989509 -295.337666) (xy 40.982066 -295.345109)
			(xy 40.976804 -295.345612) (xy 40.976296 -295.345612) (xy 40.460676 -295.345612) (xy 40.452802 -295.345903)
			(xy 40.437798 -295.350685) (xy 40.431212 -295.35501) (xy 40.410146 -295.36942) (xy 40.364498 -295.392245)
			(xy 40.315888 -295.407798) (xy 40.265468 -295.415711) (xy 40.23995 -295.416224) (xy 40.21443 -295.415722)
			(xy 40.164004 -295.40783) (xy 40.115393 -295.392274) (xy 40.069754 -295.369423) (xy 40.048688 -295.35501)
			(xy 40.0421 -295.350688) (xy 40.027097 -295.345905) (xy 40.019224 -295.345612) (xy 39.50335 -295.345612)
			(xy 39.498041 -295.345138) (xy 39.490464 -295.337703) (xy 39.489888 -295.332404) (xy 37.545772 -295.332404)
			(xy 37.545472 -295.337746) (xy 37.537907 -295.345288) (xy 37.532564 -295.345612) (xy 37.01669 -295.345612)
			(xy 37.008816 -295.345909) (xy 36.993813 -295.350687) (xy 36.987226 -295.35501) (xy 36.966157 -295.369414)
			(xy 36.920509 -295.392241) (xy 36.871901 -295.407795) (xy 36.821481 -295.41571) (xy 36.795964 -295.416224)
			(xy 36.770445 -295.415715) (xy 36.720019 -295.407826) (xy 36.671407 -295.392271) (xy 36.625768 -295.369422)
			(xy 36.604702 -295.35501) (xy 36.598111 -295.350694) (xy 36.583111 -295.345908) (xy 36.575238 -295.345612)
			(xy 36.059364 -295.345612) (xy 36.054098 -295.345129) (xy 36.046658 -295.337671) (xy 36.046156 -295.332404)
			(xy 33.445704 -295.332404) (xy 33.445208 -295.337668) (xy 33.437761 -295.345111) (xy 33.432496 -295.345612)
			(xy 32.916622 -295.345612) (xy 32.90875 -295.345923) (xy 32.893746 -295.350692) (xy 32.887158 -295.35501)
			(xy 32.86608 -295.3694) (xy 32.820435 -295.39223) (xy 32.77183 -295.407788) (xy 32.721413 -295.415707)
			(xy 32.695896 -295.416224) (xy 32.670375 -295.415749) (xy 32.619948 -295.407849) (xy 32.571337 -295.392285)
			(xy 32.525699 -295.369427) (xy 32.504634 -295.35501) (xy 32.498036 -295.350706) (xy 32.483041 -295.345912)
			(xy 32.47517 -295.345612) (xy 31.959296 -295.345612) (xy 31.954034 -295.345109) (xy 31.946591 -295.337666)
			(xy 31.946088 -295.332404) (xy 30.001972 -295.332404) (xy 30.001672 -295.337746) (xy 29.994107 -295.345288)
			(xy 29.988764 -295.345612) (xy 29.47289 -295.345612) (xy 29.465016 -295.345909) (xy 29.450013 -295.350687)
			(xy 29.443426 -295.35501) (xy 29.422357 -295.369414) (xy 29.376709 -295.392241) (xy 29.328101 -295.407795)
			(xy 29.277681 -295.41571) (xy 29.252164 -295.416224) (xy 29.226645 -295.415715) (xy 29.176219 -295.407826)
			(xy 29.127607 -295.392271) (xy 29.081968 -295.369422) (xy 29.060902 -295.35501) (xy 29.054311 -295.350694)
			(xy 29.039311 -295.345908) (xy 29.031438 -295.345612) (xy 28.515564 -295.345612) (xy 28.510298 -295.345129)
			(xy 28.502858 -295.337671) (xy 28.502356 -295.332404) (xy 25.901904 -295.332404) (xy 25.901408 -295.337668)
			(xy 25.893961 -295.345111) (xy 25.888696 -295.345612) (xy 25.372822 -295.345612) (xy 25.36495 -295.345923)
			(xy 25.349946 -295.350692) (xy 25.343358 -295.35501) (xy 25.32228 -295.3694) (xy 25.276635 -295.39223)
			(xy 25.22803 -295.407788) (xy 25.177613 -295.415707) (xy 25.152096 -295.416224) (xy 25.126575 -295.415749)
			(xy 25.076148 -295.407849) (xy 25.027537 -295.392285) (xy 24.981899 -295.369427) (xy 24.960834 -295.35501)
			(xy 24.954236 -295.350706) (xy 24.939241 -295.345912) (xy 24.93137 -295.345612) (xy 24.415496 -295.345612)
			(xy 24.410234 -295.345109) (xy 24.402791 -295.337666) (xy 24.402288 -295.332404) (xy 22.458172 -295.332404)
			(xy 22.457872 -295.337746) (xy 22.450307 -295.345288) (xy 22.444964 -295.345612) (xy 22.444456 -295.345612)
			(xy 21.928836 -295.345612) (xy 21.92096 -295.345886) (xy 21.905957 -295.35068) (xy 21.899372 -295.35501)
			(xy 21.87829 -295.369394) (xy 21.832647 -295.392225) (xy 21.784042 -295.407785) (xy 21.733626 -295.415706)
			(xy 21.70811 -295.416224) (xy 21.68259 -295.415742) (xy 21.632163 -295.407844) (xy 21.583551 -295.392282)
			(xy 21.537913 -295.369426) (xy 21.516848 -295.35501) (xy 21.510269 -295.350673) (xy 21.495259 -295.3459)
			(xy 21.487384 -295.345612) (xy 20.97151 -295.345612) (xy 20.966196 -295.345164) (xy 20.958622 -295.33771)
			(xy 20.958048 -295.332404) (xy 18.358104 -295.332404) (xy 18.357608 -295.337668) (xy 18.350161 -295.345111)
			(xy 18.344896 -295.345612) (xy 18.344388 -295.345612) (xy 17.828768 -295.345612) (xy 17.820894 -295.3459)
			(xy 17.80589 -295.350684) (xy 17.799304 -295.35501) (xy 17.778213 -295.36938) (xy 17.732573 -295.392215)
			(xy 17.683971 -295.407779) (xy 17.633558 -295.415704) (xy 17.608042 -295.416224) (xy 17.582522 -295.415726)
			(xy 17.532096 -295.407833) (xy 17.483484 -295.392276) (xy 17.437845 -295.369424) (xy 17.41678 -295.35501)
			(xy 17.410194 -295.350685) (xy 17.39519 -295.345904) (xy 17.387316 -295.345612) (xy 16.871442 -295.345612)
			(xy 16.866132 -295.345143) (xy 16.858555 -295.337705) (xy 16.85798 -295.332404) (xy 2.509012 -295.332404)
			(xy 2.509012 -296.182542) (xy 16.85798 -296.182542) (xy 16.85798 -295.688004) (xy 16.858496 -295.682745)
			(xy 16.865929 -295.675302) (xy 16.871188 -295.674796) (xy 16.871696 -295.674796) (xy 17.38757 -295.674796)
			(xy 17.395379 -295.67447) (xy 17.410251 -295.669693) (xy 17.41678 -295.665398) (xy 17.437869 -295.651049)
			(xy 17.48353 -295.628318) (xy 17.532136 -295.612859) (xy 17.582539 -295.605036) (xy 17.633545 -295.605036)
			(xy 17.683948 -295.612859) (xy 17.732554 -295.628318) (xy 17.778215 -295.651049) (xy 17.799304 -295.665398)
			(xy 17.805835 -295.669689) (xy 17.820706 -295.674472) (xy 17.828514 -295.674796) (xy 18.344642 -295.674796)
			(xy 18.349941 -295.67529) (xy 18.357507 -295.682715) (xy 18.358104 -295.688004) (xy 18.358104 -296.182542)
			(xy 18.358079 -296.182796) (xy 24.402288 -296.182796) (xy 24.402288 -296.182288) (xy 24.402288 -295.688004)
			(xy 24.402797 -295.682743) (xy 24.410235 -295.6753) (xy 24.415496 -295.674796) (xy 24.931624 -295.674796)
			(xy 24.939435 -295.674493) (xy 24.954306 -295.6697) (xy 24.960834 -295.665398) (xy 24.981923 -295.651049)
			(xy 25.027584 -295.628318) (xy 25.07619 -295.612859) (xy 25.126593 -295.605036) (xy 25.177599 -295.605036)
			(xy 25.228002 -295.612859) (xy 25.276608 -295.628318) (xy 25.322269 -295.651049) (xy 25.343358 -295.665398)
			(xy 25.349877 -295.66971) (xy 25.364757 -295.67448) (xy 25.372568 -295.674796) (xy 25.888696 -295.674796)
			(xy 25.894029 -295.67513) (xy 25.90157 -295.682671) (xy 25.901904 -295.688004) (xy 25.901904 -296.182542)
			(xy 25.90188 -296.182796) (xy 31.946088 -296.182796) (xy 31.946088 -296.182288) (xy 31.946088 -295.688004)
			(xy 31.946597 -295.682743) (xy 31.954035 -295.6753) (xy 31.959296 -295.674796) (xy 32.475424 -295.674796)
			(xy 32.483235 -295.674493) (xy 32.498106 -295.6697) (xy 32.504634 -295.665398) (xy 32.525723 -295.651049)
			(xy 32.571384 -295.628318) (xy 32.61999 -295.612859) (xy 32.670393 -295.605036) (xy 32.721399 -295.605036)
			(xy 32.771802 -295.612859) (xy 32.820408 -295.628318) (xy 32.866069 -295.651049) (xy 32.887158 -295.665398)
			(xy 32.893677 -295.66971) (xy 32.908557 -295.67448) (xy 32.916368 -295.674796) (xy 33.432496 -295.674796)
			(xy 33.437829 -295.67513) (xy 33.44537 -295.682671) (xy 33.445704 -295.688004) (xy 33.445704 -296.182542)
			(xy 39.489888 -296.182542) (xy 39.489888 -295.688004) (xy 39.490397 -295.682743) (xy 39.497835 -295.6753)
			(xy 39.503096 -295.674796) (xy 39.503604 -295.674796) (xy 40.019478 -295.674796) (xy 40.027287 -295.674474)
			(xy 40.042159 -295.669694) (xy 40.048688 -295.665398) (xy 40.069777 -295.651049) (xy 40.115438 -295.628318)
			(xy 40.164044 -295.612859) (xy 40.214447 -295.605036) (xy 40.265453 -295.605036) (xy 40.315856 -295.612859)
			(xy 40.364462 -295.628318) (xy 40.410123 -295.651049) (xy 40.431212 -295.665398) (xy 40.437742 -295.669692)
			(xy 40.452613 -295.674474) (xy 40.460422 -295.674796) (xy 40.97655 -295.674796) (xy 40.981838 -295.675352)
			(xy 40.989409 -295.68273) (xy 40.990012 -295.688004) (xy 40.990012 -296.182542) (xy 40.989987 -296.182796)
			(xy 47.034196 -296.182796) (xy 47.034196 -296.182288) (xy 47.034196 -295.688004) (xy 47.03453 -295.682671)
			(xy 47.042071 -295.67513) (xy 47.047404 -295.674796) (xy 47.563532 -295.674796) (xy 47.571339 -295.674454)
			(xy 47.586211 -295.669687) (xy 47.592742 -295.665398) (xy 47.613831 -295.651049) (xy 47.659492 -295.628318)
			(xy 47.708098 -295.612859) (xy 47.758501 -295.605036) (xy 47.809507 -295.605036) (xy 47.85991 -295.612859)
			(xy 47.908516 -295.628318) (xy 47.954177 -295.651049) (xy 47.975266 -295.665398) (xy 47.981806 -295.669675)
			(xy 47.996669 -295.674467) (xy 48.004476 -295.674796) (xy 48.520604 -295.674796) (xy 48.525868 -295.675292)
			(xy 48.533311 -295.682739) (xy 48.533812 -295.688004) (xy 48.533812 -296.182542) (xy 54.577996 -296.182542)
			(xy 54.577996 -295.688004) (xy 54.57833 -295.682671) (xy 54.585871 -295.67513) (xy 54.591204 -295.674796)
			(xy 56.064658 -295.674796) (xy 56.069947 -295.675346) (xy 56.077518 -295.682729) (xy 56.07812 -295.688004)
			(xy 56.07812 -296.182542) (xy 56.078099 -296.182796) (xy 163.678108 -296.182796) (xy 163.678108 -296.182288)
			(xy 163.678108 -295.688004) (xy 163.678431 -295.682668) (xy 163.68598 -295.675126) (xy 163.691316 -295.674796)
			(xy 165.164516 -295.674796) (xy 165.169782 -295.675284) (xy 165.177224 -295.682738) (xy 165.177724 -295.688004)
			(xy 165.177724 -296.182542) (xy 171.221908 -296.182542) (xy 171.221908 -295.688004) (xy 171.222231 -295.682668)
			(xy 171.22978 -295.675126) (xy 171.235116 -295.674796) (xy 171.235624 -295.674796) (xy 171.751498 -295.674796)
			(xy 171.759308 -295.674482) (xy 171.774179 -295.669696) (xy 171.780708 -295.665398) (xy 171.801797 -295.651049)
			(xy 171.847458 -295.628318) (xy 171.896064 -295.612859) (xy 171.946467 -295.605036) (xy 171.997473 -295.605036)
			(xy 172.047876 -295.612859) (xy 172.096482 -295.628318) (xy 172.142143 -295.651049) (xy 172.163232 -295.665398)
			(xy 172.169757 -295.6697) (xy 172.184632 -295.674476) (xy 172.192442 -295.674796) (xy 172.70857 -295.674796)
			(xy 172.71386 -295.675338) (xy 172.721431 -295.682727) (xy 172.722032 -295.688004) (xy 172.722032 -296.182542)
			(xy 172.72201 -296.182796) (xy 178.766216 -296.182796) (xy 178.766216 -296.182288) (xy 178.766216 -295.688004)
			(xy 178.766532 -295.682666) (xy 178.774086 -295.675124) (xy 178.779424 -295.674796) (xy 179.295552 -295.674796)
			(xy 179.30336 -295.674463) (xy 179.318232 -295.66969) (xy 179.324762 -295.665398) (xy 179.345851 -295.651049)
			(xy 179.391512 -295.628318) (xy 179.440118 -295.612859) (xy 179.490521 -295.605036) (xy 179.541527 -295.605036)
			(xy 179.59193 -295.612859) (xy 179.640536 -295.628318) (xy 179.686197 -295.651049) (xy 179.707286 -295.665398)
			(xy 179.713821 -295.669683) (xy 179.728688 -295.67447) (xy 179.736496 -295.674796) (xy 180.252624 -295.674796)
			(xy 180.257891 -295.675279) (xy 180.265332 -295.682736) (xy 180.265832 -295.688004) (xy 180.265832 -296.182542)
			(xy 186.310016 -296.182542) (xy 186.310016 -295.688004) (xy 186.310332 -295.682666) (xy 186.317886 -295.675124)
			(xy 186.323224 -295.674796) (xy 186.323732 -295.674796) (xy 186.839606 -295.674796) (xy 186.847416 -295.674486)
			(xy 186.862288 -295.669697) (xy 186.868816 -295.665398) (xy 186.889905 -295.651049) (xy 186.935566 -295.628318)
			(xy 186.984172 -295.612859) (xy 187.034575 -295.605036) (xy 187.085581 -295.605036) (xy 187.135984 -295.612859)
			(xy 187.18459 -295.628318) (xy 187.230251 -295.651049) (xy 187.25134 -295.665398) (xy 187.257863 -295.669703)
			(xy 187.27274 -295.674478) (xy 187.28055 -295.674796) (xy 187.796678 -295.674796) (xy 187.801969 -295.675332)
			(xy 187.809539 -295.682725) (xy 187.81014 -295.688004) (xy 187.81014 -296.182542) (xy 187.810118 -296.182796)
			(xy 193.854324 -296.182796) (xy 193.854324 -296.182288) (xy 193.854324 -295.688004) (xy 193.854633 -295.682665)
			(xy 193.862192 -295.675122) (xy 193.867532 -295.674796) (xy 194.38366 -295.674796) (xy 194.391469 -295.674466)
			(xy 194.40634 -295.669691) (xy 194.41287 -295.665398) (xy 194.433959 -295.651049) (xy 194.47962 -295.628318)
			(xy 194.528226 -295.612859) (xy 194.578629 -295.605036) (xy 194.629635 -295.605036) (xy 194.680038 -295.612859)
			(xy 194.728644 -295.628318) (xy 194.774305 -295.651049) (xy 194.795394 -295.665398) (xy 194.801928 -295.669686)
			(xy 194.816796 -295.674471) (xy 194.824604 -295.674796) (xy 195.340732 -295.674796) (xy 195.346 -295.675274)
			(xy 195.353441 -295.682735) (xy 195.35394 -295.688004) (xy 195.35394 -296.182542) (xy 195.353919 -296.182796)
			(xy 201.398124 -296.182796) (xy 201.398124 -296.182288) (xy 201.398124 -295.688004) (xy 201.398433 -295.682665)
			(xy 201.405992 -295.675122) (xy 201.411332 -295.674796) (xy 201.92746 -295.674796) (xy 201.935269 -295.674466)
			(xy 201.95014 -295.669691) (xy 201.95667 -295.665398) (xy 201.977759 -295.651049) (xy 202.02342 -295.628318)
			(xy 202.072026 -295.612859) (xy 202.122429 -295.605036) (xy 202.173435 -295.605036) (xy 202.223838 -295.612859)
			(xy 202.272444 -295.628318) (xy 202.318105 -295.651049) (xy 202.339194 -295.665398) (xy 202.345728 -295.669686)
			(xy 202.360596 -295.674471) (xy 202.368404 -295.674796) (xy 202.884532 -295.674796) (xy 202.8898 -295.675274)
			(xy 202.897241 -295.682735) (xy 202.89774 -295.688004) (xy 202.89774 -296.182288) (xy 264.798048 -296.182288)
			(xy 264.798048 -295.68775) (xy 264.798518 -295.682378) (xy 264.806136 -295.674794) (xy 264.81151 -295.674288)
			(xy 265.327638 -295.674288) (xy 265.335446 -295.67395) (xy 265.350317 -295.669181) (xy 265.356848 -295.66489)
			(xy 265.377937 -295.650541) (xy 265.423598 -295.62781) (xy 265.472204 -295.612351) (xy 265.522607 -295.604528)
			(xy 265.573613 -295.604528) (xy 265.624016 -295.612351) (xy 265.672622 -295.62781) (xy 265.718283 -295.650541)
			(xy 265.739372 -295.66489) (xy 265.745911 -295.669168) (xy 265.760775 -295.67396) (xy 265.768582 -295.674288)
			(xy 266.28471 -295.674288) (xy 266.290063 -295.674839) (xy 266.297645 -295.682398) (xy 266.298172 -295.68775)
			(xy 266.298172 -296.182288) (xy 272.342356 -296.182288) (xy 272.342356 -295.68775) (xy 272.342858 -295.682448)
			(xy 272.350273 -295.674873) (xy 272.355564 -295.674288) (xy 272.871692 -295.674288) (xy 272.879502 -295.673973)
			(xy 272.894373 -295.669188) (xy 272.900902 -295.66489) (xy 272.921991 -295.650541) (xy 272.967652 -295.62781)
			(xy 273.016258 -295.612351) (xy 273.066661 -295.604528) (xy 273.117667 -295.604528) (xy 273.16807 -295.612351)
			(xy 273.216676 -295.62781) (xy 273.262337 -295.650541) (xy 273.283426 -295.66489) (xy 273.289953 -295.669189)
			(xy 273.304826 -295.673967) (xy 273.312636 -295.674288) (xy 273.828764 -295.674288) (xy 273.834091 -295.674651)
			(xy 273.841633 -295.682171) (xy 273.841972 -295.687496) (xy 273.841972 -295.688004) (xy 273.841972 -296.182288)
			(xy 279.886156 -296.182288) (xy 279.886156 -295.68775) (xy 279.886658 -295.682448) (xy 279.894073 -295.674873)
			(xy 279.899364 -295.674288) (xy 280.415492 -295.674288) (xy 280.423302 -295.673973) (xy 280.438173 -295.669188)
			(xy 280.444702 -295.66489) (xy 280.465791 -295.650541) (xy 280.511452 -295.62781) (xy 280.560058 -295.612351)
			(xy 280.610461 -295.604528) (xy 280.661467 -295.604528) (xy 280.71187 -295.612351) (xy 280.760476 -295.62781)
			(xy 280.806137 -295.650541) (xy 280.827226 -295.66489) (xy 280.833753 -295.669189) (xy 280.848626 -295.673967)
			(xy 280.856436 -295.674288) (xy 281.372564 -295.674288) (xy 281.377891 -295.674651) (xy 281.385433 -295.682171)
			(xy 281.385772 -295.687496) (xy 281.385772 -295.688004) (xy 281.385772 -296.182288) (xy 287.429956 -296.182288)
			(xy 287.429956 -295.68775) (xy 287.430419 -295.682376) (xy 287.438041 -295.674792) (xy 287.443418 -295.674288)
			(xy 287.959546 -295.674288) (xy 287.967354 -295.673954) (xy 287.982226 -295.669182) (xy 287.988756 -295.66489)
			(xy 288.009845 -295.650541) (xy 288.055506 -295.62781) (xy 288.104112 -295.612351) (xy 288.154515 -295.604528)
			(xy 288.205521 -295.604528) (xy 288.255924 -295.612351) (xy 288.30453 -295.62781) (xy 288.350191 -295.650541)
			(xy 288.37128 -295.66489) (xy 288.377817 -295.669171) (xy 288.392683 -295.673961) (xy 288.40049 -295.674288)
			(xy 288.916618 -295.674288) (xy 288.921972 -295.674833) (xy 288.929554 -295.682397) (xy 288.93008 -295.68775)
			(xy 288.93008 -296.182288) (xy 294.974264 -296.182288) (xy 294.974264 -295.68775) (xy 294.974759 -295.682446)
			(xy 294.982179 -295.674871) (xy 294.987472 -295.674288) (xy 295.5036 -295.674288) (xy 295.51141 -295.673976)
			(xy 295.526282 -295.669189) (xy 295.53281 -295.66489) (xy 295.553899 -295.650541) (xy 295.59956 -295.62781)
			(xy 295.648166 -295.612351) (xy 295.698569 -295.604528) (xy 295.749575 -295.604528) (xy 295.799978 -295.612351)
			(xy 295.848584 -295.62781) (xy 295.894245 -295.650541) (xy 295.915334 -295.66489) (xy 295.921859 -295.669192)
			(xy 295.936734 -295.673969) (xy 295.944544 -295.674288) (xy 296.460672 -295.674288) (xy 296.466 -295.674645)
			(xy 296.473542 -295.682169) (xy 296.47388 -295.687496) (xy 296.47388 -295.688004) (xy 296.47388 -296.182288)
			(xy 302.518064 -296.182288) (xy 302.518064 -295.68775) (xy 302.51852 -295.682374) (xy 302.526147 -295.67479)
			(xy 302.531526 -295.674288) (xy 304.004726 -295.674288) (xy 304.010081 -295.674828) (xy 304.017662 -295.682396)
			(xy 304.018188 -295.68775) (xy 304.018188 -296.182288) (xy 411.618176 -296.182288) (xy 411.618176 -295.68775)
			(xy 411.618661 -295.682443) (xy 411.626088 -295.674867) (xy 411.631384 -295.674288) (xy 413.104584 -295.674288)
			(xy 413.109913 -295.674637) (xy 413.117455 -295.682167) (xy 413.117792 -295.687496) (xy 413.117792 -295.688004)
			(xy 413.117792 -296.182288) (xy 419.161976 -296.182288) (xy 419.161976 -295.68775) (xy 419.162421 -295.682371)
			(xy 419.170056 -295.674786) (xy 419.175438 -295.674288) (xy 419.691566 -295.674288) (xy 419.699375 -295.673962)
			(xy 419.714247 -295.669185) (xy 419.720776 -295.66489) (xy 419.741865 -295.650541) (xy 419.787526 -295.62781)
			(xy 419.836132 -295.612351) (xy 419.886535 -295.604528) (xy 419.937541 -295.604528) (xy 419.987944 -295.612351)
			(xy 420.03655 -295.62781) (xy 420.082211 -295.650541) (xy 420.1033 -295.66489) (xy 420.109833 -295.669179)
			(xy 420.124702 -295.673964) (xy 420.13251 -295.674288) (xy 420.648638 -295.674288) (xy 420.653994 -295.67482)
			(xy 420.661575 -295.682394) (xy 420.6621 -295.68775) (xy 420.6621 -296.182288) (xy 426.706284 -296.182288)
			(xy 426.706284 -295.68775) (xy 426.706762 -295.682442) (xy 426.714194 -295.674865) (xy 426.719492 -295.674288)
			(xy 427.23562 -295.674288) (xy 427.243431 -295.673985) (xy 427.258302 -295.669192) (xy 427.26483 -295.66489)
			(xy 427.285919 -295.650541) (xy 427.33158 -295.62781) (xy 427.380186 -295.612351) (xy 427.430589 -295.604528)
			(xy 427.481595 -295.604528) (xy 427.531998 -295.612351) (xy 427.580604 -295.62781) (xy 427.626265 -295.650541)
			(xy 427.647354 -295.66489) (xy 427.653875 -295.6692) (xy 427.668753 -295.673972) (xy 427.676564 -295.674288)
			(xy 428.192692 -295.674288) (xy 428.198022 -295.674632) (xy 428.205563 -295.682166) (xy 428.2059 -295.687496)
			(xy 428.2059 -295.688004) (xy 428.2059 -296.182288) (xy 434.250084 -296.182288) (xy 434.250084 -295.68775)
			(xy 434.250522 -295.682369) (xy 434.258162 -295.674784) (xy 434.263546 -295.674288) (xy 434.779674 -295.674288)
			(xy 434.787483 -295.673965) (xy 434.802355 -295.669186) (xy 434.808884 -295.66489) (xy 434.829973 -295.650541)
			(xy 434.875634 -295.62781) (xy 434.92424 -295.612351) (xy 434.974643 -295.604528) (xy 435.025649 -295.604528)
			(xy 435.076052 -295.612351) (xy 435.124658 -295.62781) (xy 435.170319 -295.650541) (xy 435.191408 -295.66489)
			(xy 435.197939 -295.669182) (xy 435.212809 -295.673965) (xy 435.220618 -295.674288) (xy 435.736746 -295.674288)
			(xy 435.742103 -295.674815) (xy 435.749684 -295.682393) (xy 435.750208 -295.68775) (xy 435.750208 -296.182288)
			(xy 441.794392 -296.182288) (xy 441.794392 -295.68775) (xy 441.794951 -295.682463) (xy 441.802327 -295.674892)
			(xy 441.8076 -295.674288) (xy 442.323728 -295.674288) (xy 442.331539 -295.673988) (xy 442.346411 -295.669193)
			(xy 442.352938 -295.66489) (xy 442.374027 -295.650541) (xy 442.419688 -295.62781) (xy 442.468294 -295.612351)
			(xy 442.518697 -295.604528) (xy 442.569703 -295.604528) (xy 442.620106 -295.612351) (xy 442.668712 -295.62781)
			(xy 442.714373 -295.650541) (xy 442.735462 -295.66489) (xy 442.742003 -295.669165) (xy 442.756866 -295.673958)
			(xy 442.764672 -295.674288) (xy 443.2808 -295.674288) (xy 443.286062 -295.674794) (xy 443.293504 -295.682234)
			(xy 443.294008 -295.687496) (xy 443.294008 -295.688004) (xy 443.294008 -296.182288) (xy 449.338192 -296.182288)
			(xy 449.338192 -295.68775) (xy 449.338751 -295.682463) (xy 449.346127 -295.674892) (xy 449.3514 -295.674288)
			(xy 449.867528 -295.674288) (xy 449.875339 -295.673988) (xy 449.890211 -295.669193) (xy 449.896738 -295.66489)
			(xy 449.917827 -295.650541) (xy 449.963488 -295.62781) (xy 450.012094 -295.612351) (xy 450.062497 -295.604528)
			(xy 450.113503 -295.604528) (xy 450.163906 -295.612351) (xy 450.212512 -295.62781) (xy 450.258173 -295.650541)
			(xy 450.279262 -295.66489) (xy 450.285803 -295.669165) (xy 450.300666 -295.673958) (xy 450.308472 -295.674288)
			(xy 450.8246 -295.674288) (xy 450.829862 -295.674794) (xy 450.837304 -295.682234) (xy 450.837808 -295.687496)
			(xy 450.837808 -295.688004) (xy 450.837808 -296.182288) (xy 450.837465 -296.187619) (xy 450.82993 -296.19516)
			(xy 450.8246 -296.195496) (xy 450.308726 -296.195496) (xy 450.300849 -296.195752) (xy 450.285844 -296.200557)
			(xy 450.279262 -296.204894) (xy 450.258189 -296.219292) (xy 450.212542 -296.242118) (xy 450.163935 -296.257673)
			(xy 450.113517 -296.265591) (xy 450.088 -296.266108) (xy 450.062479 -296.265634) (xy 450.012052 -296.257734)
			(xy 449.96344 -296.24217) (xy 449.917802 -296.219311) (xy 449.896738 -296.204894) (xy 449.89014 -296.20059)
			(xy 449.875145 -296.195797) (xy 449.867274 -296.195496) (xy 449.3514 -296.195496) (xy 449.346065 -296.195172)
			(xy 449.338523 -296.187624) (xy 449.338192 -296.182288) (xy 443.294008 -296.182288) (xy 443.293665 -296.187619)
			(xy 443.28613 -296.19516) (xy 443.2808 -296.195496) (xy 442.764926 -296.195496) (xy 442.757049 -296.195752)
			(xy 442.742044 -296.200557) (xy 442.735462 -296.204894) (xy 442.714389 -296.219292) (xy 442.668742 -296.242118)
			(xy 442.620135 -296.257673) (xy 442.569717 -296.265591) (xy 442.5442 -296.266108) (xy 442.518679 -296.265634)
			(xy 442.468252 -296.257734) (xy 442.41964 -296.24217) (xy 442.374002 -296.219311) (xy 442.352938 -296.204894)
			(xy 442.34634 -296.20059) (xy 442.331345 -296.195797) (xy 442.323474 -296.195496) (xy 441.8076 -296.195496)
			(xy 441.802265 -296.195172) (xy 441.794723 -296.187624) (xy 441.794392 -296.182288) (xy 435.750208 -296.182288)
			(xy 435.749865 -296.187619) (xy 435.74233 -296.19516) (xy 435.737 -296.195496) (xy 435.736492 -296.195496)
			(xy 435.220872 -296.195496) (xy 435.212996 -296.195771) (xy 435.197992 -296.200563) (xy 435.191408 -296.204894)
			(xy 435.17035 -296.219316) (xy 435.124698 -296.242136) (xy 435.076086 -296.257685) (xy 435.025664 -296.265595)
			(xy 435.000146 -296.266108) (xy 434.974626 -296.265611) (xy 434.9242 -296.257718) (xy 434.875588 -296.242161)
			(xy 434.829949 -296.219308) (xy 434.808884 -296.204894) (xy 434.802298 -296.200569) (xy 434.787294 -296.195789)
			(xy 434.77942 -296.195496) (xy 434.263546 -296.195496) (xy 434.258256 -296.19495) (xy 434.250684 -296.187565)
			(xy 434.250084 -296.182288) (xy 428.2059 -296.182288) (xy 428.205564 -296.187621) (xy 428.198024 -296.195163)
			(xy 428.192692 -296.195496) (xy 427.676818 -296.195496) (xy 427.668944 -296.195791) (xy 427.65394 -296.200569)
			(xy 427.647354 -296.204894) (xy 427.626283 -296.219296) (xy 427.580636 -296.242121) (xy 427.532028 -296.257675)
			(xy 427.481609 -296.265592) (xy 427.456092 -296.266108) (xy 427.430573 -296.265588) (xy 427.380147 -296.257702)
			(xy 427.331536 -296.242151) (xy 427.285896 -296.219305) (xy 427.26483 -296.204894) (xy 427.258234 -296.200587)
			(xy 427.243237 -296.195795) (xy 427.235366 -296.195496) (xy 426.719492 -296.195496) (xy 426.714156 -296.195178)
			(xy 426.706614 -296.187625) (xy 426.706284 -296.182288) (xy 420.6621 -296.182288) (xy 420.661764 -296.187621)
			(xy 420.654224 -296.195163) (xy 420.648892 -296.195496) (xy 420.648384 -296.195496) (xy 420.132764 -296.195496)
			(xy 420.124888 -296.195768) (xy 420.109884 -296.200562) (xy 420.1033 -296.204894) (xy 420.082217 -296.219276)
			(xy 420.036573 -296.242105) (xy 419.987969 -296.257665) (xy 419.937554 -296.265588) (xy 419.912038 -296.266108)
			(xy 419.886518 -296.265615) (xy 419.836091 -296.257721) (xy 419.78748 -296.242162) (xy 419.741841 -296.219309)
			(xy 419.720776 -296.204894) (xy 419.714192 -296.200566) (xy 419.699186 -296.195788) (xy 419.691312 -296.195496)
			(xy 419.175438 -296.195496) (xy 419.170147 -296.194956) (xy 419.162576 -296.187566) (xy 419.161976 -296.182288)
			(xy 413.117792 -296.182288) (xy 413.117463 -296.187622) (xy 413.109919 -296.195165) (xy 413.104584 -296.195496)
			(xy 411.631384 -296.195496) (xy 411.626116 -296.195015) (xy 411.618674 -296.187557) (xy 411.618176 -296.182288)
			(xy 304.018188 -296.182288) (xy 304.017863 -296.187623) (xy 304.010316 -296.195166) (xy 304.00498 -296.195496)
			(xy 302.531526 -296.195496) (xy 302.526233 -296.194964) (xy 302.518663 -296.187568) (xy 302.518064 -296.182288)
			(xy 296.47388 -296.182288) (xy 296.473562 -296.187625) (xy 296.46601 -296.195169) (xy 296.460672 -296.195496)
			(xy 295.944798 -296.195496) (xy 295.936923 -296.195783) (xy 295.921919 -296.200566) (xy 295.915334 -296.204894)
			(xy 295.894269 -296.219304) (xy 295.848619 -296.242127) (xy 295.800009 -296.257679) (xy 295.74959 -296.265593)
			(xy 295.724072 -296.266108) (xy 295.698553 -296.265598) (xy 295.648127 -296.257709) (xy 295.599515 -296.242155)
			(xy 295.553876 -296.219306) (xy 295.53281 -296.204894) (xy 295.526218 -296.200579) (xy 295.511218 -296.195793)
			(xy 295.503346 -296.195496) (xy 294.987472 -296.195496) (xy 294.982203 -296.195023) (xy 294.974761 -296.187559)
			(xy 294.974264 -296.182288) (xy 288.93008 -296.182288) (xy 288.929762 -296.187625) (xy 288.92221 -296.195169)
			(xy 288.916872 -296.195496) (xy 288.916364 -296.195496) (xy 288.400744 -296.195496) (xy 288.392867 -296.19576)
			(xy 288.377863 -296.200559) (xy 288.37128 -296.204894) (xy 288.350202 -296.219285) (xy 288.304557 -296.242112)
			(xy 288.255951 -296.25767) (xy 288.205535 -296.26559) (xy 288.180018 -296.266108) (xy 288.154498 -296.265625)
			(xy 288.10407 -296.257728) (xy 288.055459 -296.242166) (xy 288.009821 -296.21931) (xy 287.988756 -296.204894)
			(xy 287.982176 -296.200559) (xy 287.967167 -296.195785) (xy 287.959292 -296.195496) (xy 287.443418 -296.195496)
			(xy 287.438124 -296.194969) (xy 287.430554 -296.187569) (xy 287.429956 -296.182288) (xy 281.385772 -296.182288)
			(xy 281.385461 -296.187627) (xy 281.377904 -296.195171) (xy 281.372564 -296.195496) (xy 280.85669 -296.195496)
			(xy 280.848815 -296.195779) (xy 280.833811 -296.200565) (xy 280.827226 -296.204894) (xy 280.806163 -296.219308)
			(xy 280.760513 -296.24213) (xy 280.711902 -296.257681) (xy 280.661482 -296.265594) (xy 280.635964 -296.266108)
			(xy 280.610445 -296.265602) (xy 280.560018 -296.257712) (xy 280.511407 -296.242157) (xy 280.465768 -296.219307)
			(xy 280.444702 -296.204894) (xy 280.438112 -296.200576) (xy 280.423111 -296.195791) (xy 280.415238 -296.195496)
			(xy 279.899364 -296.195496) (xy 279.894094 -296.195028) (xy 279.886653 -296.18756) (xy 279.886156 -296.182288)
			(xy 273.841972 -296.182288) (xy 273.841661 -296.187627) (xy 273.834104 -296.195171) (xy 273.828764 -296.195496)
			(xy 273.31289 -296.195496) (xy 273.305015 -296.195779) (xy 273.290011 -296.200565) (xy 273.283426 -296.204894)
			(xy 273.262363 -296.219308) (xy 273.216713 -296.24213) (xy 273.168102 -296.257681) (xy 273.117682 -296.265594)
			(xy 273.092164 -296.266108) (xy 273.066645 -296.265602) (xy 273.016218 -296.257712) (xy 272.967607 -296.242157)
			(xy 272.921968 -296.219307) (xy 272.900902 -296.204894) (xy 272.894312 -296.200576) (xy 272.879311 -296.195791)
			(xy 272.871438 -296.195496) (xy 272.355564 -296.195496) (xy 272.350294 -296.195028) (xy 272.342853 -296.18756)
			(xy 272.342356 -296.182288) (xy 266.298172 -296.182288) (xy 266.297861 -296.187627) (xy 266.290304 -296.195171)
			(xy 266.284964 -296.195496) (xy 266.284456 -296.195496) (xy 265.768836 -296.195496) (xy 265.760959 -296.195756)
			(xy 265.745955 -296.200558) (xy 265.739372 -296.204894) (xy 265.718296 -296.219288) (xy 265.67265 -296.242115)
			(xy 265.624044 -296.257671) (xy 265.573627 -296.26559) (xy 265.54811 -296.266108) (xy 265.522589 -296.265629)
			(xy 265.472162 -296.257731) (xy 265.423551 -296.242168) (xy 265.377913 -296.21931) (xy 265.356848 -296.204894)
			(xy 265.35027 -296.200555) (xy 265.33526 -296.195783) (xy 265.327384 -296.195496) (xy 264.81151 -296.195496)
			(xy 264.806215 -296.194975) (xy 264.798646 -296.187571) (xy 264.798048 -296.182288) (xy 202.89774 -296.182288)
			(xy 202.89774 -296.182542) (xy 202.897303 -296.187856) (xy 202.889838 -296.195426) (xy 202.884532 -296.196004)
			(xy 202.368658 -296.196004) (xy 202.36085 -296.196341) (xy 202.345978 -296.201111) (xy 202.339448 -296.205402)
			(xy 202.318335 -296.219764) (xy 202.272608 -296.242489) (xy 202.223932 -296.257916) (xy 202.173464 -296.265678)
			(xy 202.147932 -296.266108) (xy 202.122403 -296.265648) (xy 202.07194 -296.257878) (xy 202.023268 -296.242455)
			(xy 201.977539 -296.219746) (xy 201.956416 -296.205402) (xy 201.94988 -296.201118) (xy 201.935013 -296.196331)
			(xy 201.927206 -296.196004) (xy 201.411332 -296.196004) (xy 201.406003 -296.195651) (xy 201.39846 -296.188124)
			(xy 201.398124 -296.182796) (xy 195.353919 -296.182796) (xy 195.353503 -296.187856) (xy 195.346038 -296.195426)
			(xy 195.340732 -296.196004) (xy 194.824858 -296.196004) (xy 194.81705 -296.196341) (xy 194.802178 -296.201111)
			(xy 194.795648 -296.205402) (xy 194.774535 -296.219764) (xy 194.728808 -296.242489) (xy 194.680132 -296.257916)
			(xy 194.629664 -296.265678) (xy 194.604132 -296.266108) (xy 194.578603 -296.265648) (xy 194.52814 -296.257878)
			(xy 194.479468 -296.242455) (xy 194.433739 -296.219746) (xy 194.412616 -296.205402) (xy 194.40608 -296.201118)
			(xy 194.391213 -296.196331) (xy 194.383406 -296.196004) (xy 193.867532 -296.196004) (xy 193.862203 -296.195651)
			(xy 193.85466 -296.188124) (xy 193.854324 -296.182796) (xy 187.810118 -296.182796) (xy 187.809675 -296.187916)
			(xy 187.802055 -296.195501) (xy 187.796678 -296.196004) (xy 187.280804 -296.196004) (xy 187.272994 -296.196319)
			(xy 187.258123 -296.201104) (xy 187.251594 -296.205402) (xy 187.230468 -296.219744) (xy 187.184746 -296.242474)
			(xy 187.136074 -296.257906) (xy 187.085609 -296.265674) (xy 187.060078 -296.266108) (xy 187.034548 -296.265675)
			(xy 186.984084 -296.257896) (xy 186.935412 -296.242466) (xy 186.889684 -296.219749) (xy 186.868562 -296.205402)
			(xy 186.862038 -296.201098) (xy 186.847162 -296.196323) (xy 186.839352 -296.196004) (xy 186.323478 -296.196004)
			(xy 186.318122 -296.195468) (xy 186.31054 -296.187898) (xy 186.310016 -296.182542) (xy 180.265832 -296.182542)
			(xy 180.265402 -296.187858) (xy 180.257933 -296.195428) (xy 180.252624 -296.196004) (xy 179.73675 -296.196004)
			(xy 179.728942 -296.196338) (xy 179.71407 -296.20111) (xy 179.70754 -296.205402) (xy 179.686429 -296.219768)
			(xy 179.640702 -296.242492) (xy 179.592025 -296.257918) (xy 179.541556 -296.265679) (xy 179.516024 -296.266108)
			(xy 179.490495 -296.265652) (xy 179.440032 -296.25788) (xy 179.39136 -296.242457) (xy 179.345631 -296.219746)
			(xy 179.324508 -296.205402) (xy 179.317974 -296.201115) (xy 179.303106 -296.196329) (xy 179.295298 -296.196004)
			(xy 178.779424 -296.196004) (xy 178.774094 -296.195657) (xy 178.766551 -296.188125) (xy 178.766216 -296.182796)
			(xy 172.72201 -296.182796) (xy 172.721575 -296.187918) (xy 172.713949 -296.195503) (xy 172.70857 -296.196004)
			(xy 172.192696 -296.196004) (xy 172.184886 -296.196315) (xy 172.170014 -296.201103) (xy 172.163486 -296.205402)
			(xy 172.142362 -296.219748) (xy 172.096639 -296.242477) (xy 172.047967 -296.257908) (xy 171.997501 -296.265675)
			(xy 171.97197 -296.266108) (xy 171.94644 -296.265679) (xy 171.895976 -296.257899) (xy 171.847304 -296.242468)
			(xy 171.801576 -296.21975) (xy 171.780454 -296.205402) (xy 171.773932 -296.201094) (xy 171.759055 -296.196322)
			(xy 171.751244 -296.196004) (xy 171.23537 -296.196004) (xy 171.230013 -296.195474) (xy 171.222431 -296.187899)
			(xy 171.221908 -296.182542) (xy 165.177724 -296.182542) (xy 165.177301 -296.18786) (xy 165.169827 -296.195431)
			(xy 165.164516 -296.196004) (xy 163.691316 -296.196004) (xy 163.685985 -296.195662) (xy 163.678443 -296.188127)
			(xy 163.678108 -296.182796) (xy 56.078099 -296.182796) (xy 56.077673 -296.187921) (xy 56.07004 -296.195507)
			(xy 56.064658 -296.196004) (xy 54.591458 -296.196004) (xy 54.586099 -296.195482) (xy 54.578518 -296.187901)
			(xy 54.577996 -296.182542) (xy 48.533812 -296.182542) (xy 48.533399 -296.187863) (xy 48.525918 -296.195434)
			(xy 48.520604 -296.196004) (xy 48.00473 -296.196004) (xy 47.996921 -296.19633) (xy 47.982049 -296.201107)
			(xy 47.97552 -296.205402) (xy 47.954386 -296.219733) (xy 47.908667 -296.242465) (xy 47.859998 -296.257901)
			(xy 47.809534 -296.265672) (xy 47.784004 -296.266108) (xy 47.758474 -296.265662) (xy 47.708011 -296.257887)
			(xy 47.659339 -296.242461) (xy 47.613611 -296.219748) (xy 47.592488 -296.205402) (xy 47.585958 -296.201108)
			(xy 47.571087 -296.196326) (xy 47.563278 -296.196004) (xy 47.047404 -296.196004) (xy 47.042071 -296.19567)
			(xy 47.03453 -296.188129) (xy 47.034196 -296.182796) (xy 40.989987 -296.182796) (xy 40.989483 -296.187899)
			(xy 40.981907 -296.19548) (xy 40.97655 -296.196004) (xy 40.460676 -296.196004) (xy 40.452865 -296.196307)
			(xy 40.437994 -296.2011) (xy 40.431466 -296.205402) (xy 40.410347 -296.219756) (xy 40.364623 -296.242483)
			(xy 40.315949 -296.257912) (xy 40.265481 -296.265677) (xy 40.23995 -296.266108) (xy 40.214421 -296.265639)
			(xy 40.163959 -296.257871) (xy 40.115287 -296.242452) (xy 40.069557 -296.219745) (xy 40.048434 -296.205402)
			(xy 40.041894 -296.201125) (xy 40.027031 -296.196333) (xy 40.019224 -296.196004) (xy 39.50335 -296.196004)
			(xy 39.49799 -296.195487) (xy 39.49041 -296.187902) (xy 39.489888 -296.182542) (xy 33.445704 -296.182542)
			(xy 33.44521 -296.187841) (xy 33.437785 -296.195407) (xy 33.432496 -296.196004) (xy 32.916622 -296.196004)
			(xy 32.908813 -296.196326) (xy 32.893941 -296.201106) (xy 32.887412 -296.205402) (xy 32.866281 -296.219736)
			(xy 32.820561 -296.242468) (xy 32.77189 -296.257902) (xy 32.721426 -296.265673) (xy 32.695896 -296.266108)
			(xy 32.670366 -296.265666) (xy 32.619903 -296.25789) (xy 32.571231 -296.242463) (xy 32.525503 -296.219748)
			(xy 32.50438 -296.205402) (xy 32.497852 -296.201104) (xy 32.482979 -296.196325) (xy 32.47517 -296.196004)
			(xy 31.959296 -296.196004) (xy 31.954032 -296.195508) (xy 31.946589 -296.188061) (xy 31.946088 -296.182796)
			(xy 25.90188 -296.182796) (xy 25.90141 -296.187841) (xy 25.893985 -296.195407) (xy 25.888696 -296.196004)
			(xy 25.372822 -296.196004) (xy 25.365013 -296.196326) (xy 25.350141 -296.201106) (xy 25.343612 -296.205402)
			(xy 25.322481 -296.219736) (xy 25.276761 -296.242468) (xy 25.22809 -296.257902) (xy 25.177626 -296.265673)
			(xy 25.152096 -296.266108) (xy 25.126566 -296.265666) (xy 25.076103 -296.25789) (xy 25.027431 -296.242463)
			(xy 24.981703 -296.219748) (xy 24.96058 -296.205402) (xy 24.954052 -296.201104) (xy 24.939179 -296.196325)
			(xy 24.93137 -296.196004) (xy 24.415496 -296.196004) (xy 24.410232 -296.195508) (xy 24.402789 -296.188061)
			(xy 24.402288 -296.182796) (xy 18.358079 -296.182796) (xy 18.357582 -296.187901) (xy 18.350001 -296.195482)
			(xy 18.344642 -296.196004) (xy 17.828768 -296.196004) (xy 17.820961 -296.196346) (xy 17.806089 -296.201113)
			(xy 17.799558 -296.205402) (xy 17.778442 -296.21976) (xy 17.732716 -296.242486) (xy 17.684041 -296.257914)
			(xy 17.633574 -296.265677) (xy 17.608042 -296.266108) (xy 17.582513 -296.265643) (xy 17.532051 -296.257874)
			(xy 17.483378 -296.242453) (xy 17.437649 -296.219745) (xy 17.416526 -296.205402) (xy 17.409988 -296.201122)
			(xy 17.395123 -296.196332) (xy 17.387316 -296.196004) (xy 16.871442 -296.196004) (xy 16.866093 -296.195426)
			(xy 16.858507 -296.187888) (xy 16.85798 -296.182542) (xy 2.509012 -296.182542) (xy 2.509012 -297.032426)
			(xy 20.958048 -297.032426) (xy 20.958048 -296.537888) (xy 20.958582 -296.532634) (xy 20.966004 -296.525195)
			(xy 20.971256 -296.52468) (xy 20.971764 -296.52468) (xy 21.487638 -296.52468) (xy 21.495446 -296.524343)
			(xy 21.510318 -296.519573) (xy 21.516848 -296.515282) (xy 21.537937 -296.500933) (xy 21.583598 -296.478202)
			(xy 21.632204 -296.462743) (xy 21.682607 -296.45492) (xy 21.733613 -296.45492) (xy 21.784016 -296.462743)
			(xy 21.832622 -296.478202) (xy 21.878283 -296.500933) (xy 21.899372 -296.515282) (xy 21.905912 -296.519559)
			(xy 21.920775 -296.524351) (xy 21.928582 -296.52468) (xy 22.44471 -296.52468) (xy 22.450025 -296.525121)
			(xy 22.457598 -296.532581) (xy 22.458172 -296.537888) (xy 22.458172 -297.032426) (xy 22.458148 -297.03268)
			(xy 28.502356 -297.03268) (xy 28.502356 -297.032172) (xy 28.502356 -296.537888) (xy 28.502883 -296.532633)
			(xy 28.510309 -296.525193) (xy 28.515564 -296.52468) (xy 29.031692 -296.52468) (xy 29.039502 -296.524366)
			(xy 29.054374 -296.519581) (xy 29.060902 -296.515282) (xy 29.081991 -296.500933) (xy 29.127652 -296.478202)
			(xy 29.176258 -296.462743) (xy 29.226661 -296.45492) (xy 29.277667 -296.45492) (xy 29.32807 -296.462743)
			(xy 29.376676 -296.478202) (xy 29.422337 -296.500933) (xy 29.443426 -296.515282) (xy 29.449954 -296.51958)
			(xy 29.464827 -296.524359) (xy 29.472636 -296.52468) (xy 29.988764 -296.52468) (xy 29.994089 -296.52505)
			(xy 30.001631 -296.532565) (xy 30.001972 -296.537888) (xy 30.001972 -297.032426) (xy 30.001949 -297.03268)
			(xy 36.046156 -297.03268) (xy 36.046156 -297.032172) (xy 36.046156 -296.537888) (xy 36.046683 -296.532633)
			(xy 36.054109 -296.525193) (xy 36.059364 -296.52468) (xy 36.575492 -296.52468) (xy 36.583302 -296.524366)
			(xy 36.598174 -296.519581) (xy 36.604702 -296.515282) (xy 36.625791 -296.500933) (xy 36.671452 -296.478202)
			(xy 36.720058 -296.462743) (xy 36.770461 -296.45492) (xy 36.821467 -296.45492) (xy 36.87187 -296.462743)
			(xy 36.920476 -296.478202) (xy 36.966137 -296.500933) (xy 36.987226 -296.515282) (xy 36.993754 -296.51958)
			(xy 37.008627 -296.524359) (xy 37.016436 -296.52468) (xy 37.532564 -296.52468) (xy 37.537889 -296.52505)
			(xy 37.545431 -296.532565) (xy 37.545772 -296.537888) (xy 37.545772 -297.032426) (xy 43.589956 -297.032426)
			(xy 43.589956 -296.537888) (xy 43.590483 -296.532633) (xy 43.597909 -296.525193) (xy 43.603164 -296.52468)
			(xy 43.603672 -296.52468) (xy 44.119546 -296.52468) (xy 44.127354 -296.524347) (xy 44.142226 -296.519574)
			(xy 44.148756 -296.515282) (xy 44.169845 -296.500933) (xy 44.215506 -296.478202) (xy 44.264112 -296.462743)
			(xy 44.314515 -296.45492) (xy 44.365521 -296.45492) (xy 44.415924 -296.462743) (xy 44.46453 -296.478202)
			(xy 44.510191 -296.500933) (xy 44.53128 -296.515282) (xy 44.537818 -296.519562) (xy 44.552683 -296.524352)
			(xy 44.56049 -296.52468) (xy 45.076618 -296.52468) (xy 45.081934 -296.525116) (xy 45.089506 -296.53258)
			(xy 45.09008 -296.537888) (xy 45.09008 -297.032426) (xy 45.090056 -297.03268) (xy 51.134264 -297.03268)
			(xy 51.134264 -297.032172) (xy 51.134264 -296.537888) (xy 51.134784 -296.532631) (xy 51.142215 -296.52519)
			(xy 51.147472 -296.52468) (xy 51.6636 -296.52468) (xy 51.67141 -296.52437) (xy 51.686282 -296.519582)
			(xy 51.69281 -296.515282) (xy 51.713899 -296.500933) (xy 51.75956 -296.478202) (xy 51.808166 -296.462743)
			(xy 51.858569 -296.45492) (xy 51.909575 -296.45492) (xy 51.959978 -296.462743) (xy 52.008584 -296.478202)
			(xy 52.054245 -296.500933) (xy 52.075334 -296.515282) (xy 52.08186 -296.519583) (xy 52.096734 -296.52436)
			(xy 52.104544 -296.52468) (xy 52.620672 -296.52468) (xy 52.625998 -296.525044) (xy 52.63354 -296.532563)
			(xy 52.63388 -296.537888) (xy 52.63388 -297.032426) (xy 58.678064 -297.032426) (xy 58.678064 -296.537888)
			(xy 58.678584 -296.532631) (xy 58.686015 -296.52519) (xy 58.691272 -296.52468) (xy 58.69178 -296.52468)
			(xy 60.164726 -296.52468) (xy 60.170043 -296.525111) (xy 60.177614 -296.532579) (xy 60.178188 -296.537888)
			(xy 60.178188 -297.032426) (xy 60.178163 -297.03268) (xy 167.778176 -297.03268) (xy 167.778176 -296.537888)
			(xy 167.778685 -296.532628) (xy 167.786124 -296.525187) (xy 167.791384 -296.52468) (xy 169.264584 -296.52468)
			(xy 169.269911 -296.525036) (xy 169.277452 -296.532562) (xy 169.277792 -296.537888) (xy 169.277792 -297.032426)
			(xy 175.321976 -297.032426) (xy 175.321976 -296.537888) (xy 175.322485 -296.532628) (xy 175.329924 -296.525187)
			(xy 175.335184 -296.52468) (xy 175.335692 -296.52468) (xy 175.851566 -296.52468) (xy 175.859375 -296.524355)
			(xy 175.874247 -296.519577) (xy 175.880776 -296.515282) (xy 175.901865 -296.500933) (xy 175.947526 -296.478202)
			(xy 175.996132 -296.462743) (xy 176.046535 -296.45492) (xy 176.097541 -296.45492) (xy 176.147944 -296.462743)
			(xy 176.19655 -296.478202) (xy 176.242211 -296.500933) (xy 176.2633 -296.515282) (xy 176.269833 -296.51957)
			(xy 176.284702 -296.524355) (xy 176.29251 -296.52468) (xy 176.808638 -296.52468) (xy 176.813956 -296.525103)
			(xy 176.821527 -296.532577) (xy 176.8221 -296.537888) (xy 176.8221 -297.032426) (xy 176.822075 -297.03268)
			(xy 182.866284 -297.03268) (xy 182.866284 -297.032172) (xy 182.866284 -296.537888) (xy 182.866786 -296.532626)
			(xy 182.87423 -296.525184) (xy 182.879492 -296.52468) (xy 183.39562 -296.52468) (xy 183.403431 -296.524378)
			(xy 183.418303 -296.519584) (xy 183.42483 -296.515282) (xy 183.445919 -296.500933) (xy 183.49158 -296.478202)
			(xy 183.540186 -296.462743) (xy 183.590589 -296.45492) (xy 183.641595 -296.45492) (xy 183.691998 -296.462743)
			(xy 183.740604 -296.478202) (xy 183.786265 -296.500933) (xy 183.807354 -296.515282) (xy 183.813875 -296.519591)
			(xy 183.828753 -296.524363) (xy 183.836564 -296.52468) (xy 184.352692 -296.52468) (xy 184.357951 -296.525199)
			(xy 184.365393 -296.53263) (xy 184.3659 -296.537888) (xy 184.3659 -297.032426) (xy 190.410084 -297.032426)
			(xy 190.410084 -296.537888) (xy 190.410586 -296.532626) (xy 190.41803 -296.525184) (xy 190.423292 -296.52468)
			(xy 190.4238 -296.52468) (xy 190.939674 -296.52468) (xy 190.947483 -296.524359) (xy 190.962355 -296.519578)
			(xy 190.968884 -296.515282) (xy 190.989973 -296.500933) (xy 191.035634 -296.478202) (xy 191.08424 -296.462743)
			(xy 191.134643 -296.45492) (xy 191.185649 -296.45492) (xy 191.236052 -296.462743) (xy 191.284658 -296.478202)
			(xy 191.330319 -296.500933) (xy 191.351408 -296.515282) (xy 191.35794 -296.519573) (xy 191.37281 -296.524356)
			(xy 191.380618 -296.52468) (xy 191.896746 -296.52468) (xy 191.902053 -296.525164) (xy 191.90963 -296.532591)
			(xy 191.910208 -296.537888) (xy 191.910208 -297.032426) (xy 191.910183 -297.03268) (xy 197.954392 -297.03268)
			(xy 197.954392 -297.032172) (xy 197.954392 -296.537888) (xy 197.954887 -296.532624) (xy 197.962335 -296.525182)
			(xy 197.9676 -296.52468) (xy 198.483728 -296.52468) (xy 198.49154 -296.524382) (xy 198.506411 -296.519585)
			(xy 198.512938 -296.515282) (xy 198.534027 -296.500933) (xy 198.579688 -296.478202) (xy 198.628294 -296.462743)
			(xy 198.678697 -296.45492) (xy 198.729703 -296.45492) (xy 198.780106 -296.462743) (xy 198.828712 -296.478202)
			(xy 198.874373 -296.500933) (xy 198.895462 -296.515282) (xy 198.902004 -296.519555) (xy 198.916866 -296.52435)
			(xy 198.924672 -296.52468) (xy 199.4408 -296.52468) (xy 199.44606 -296.525194) (xy 199.453502 -296.532629)
			(xy 199.454008 -296.537888) (xy 199.454008 -297.032426) (xy 199.453984 -297.03268) (xy 205.498192 -297.03268)
			(xy 205.498192 -297.032172) (xy 205.498192 -296.537888) (xy 205.498687 -296.532624) (xy 205.506135 -296.525182)
			(xy 205.5114 -296.52468) (xy 206.027528 -296.52468) (xy 206.03534 -296.524382) (xy 206.050211 -296.519585)
			(xy 206.056738 -296.515282) (xy 206.077827 -296.500933) (xy 206.123488 -296.478202) (xy 206.172094 -296.462743)
			(xy 206.222497 -296.45492) (xy 206.273503 -296.45492) (xy 206.323906 -296.462743) (xy 206.372512 -296.478202)
			(xy 206.418173 -296.500933) (xy 206.439262 -296.515282) (xy 206.445804 -296.519555) (xy 206.460666 -296.52435)
			(xy 206.468472 -296.52468) (xy 206.9846 -296.52468) (xy 206.98986 -296.525194) (xy 206.997302 -296.532629)
			(xy 206.997808 -296.537888) (xy 206.997808 -297.032172) (xy 268.898116 -297.032172) (xy 268.898116 -296.537634)
			(xy 268.8985 -296.532209) (xy 268.906155 -296.524522) (xy 268.911578 -296.524172) (xy 269.427706 -296.524172)
			(xy 269.435517 -296.523866) (xy 269.450388 -296.519075) (xy 269.456916 -296.514774) (xy 269.478005 -296.500425)
			(xy 269.523666 -296.477694) (xy 269.572272 -296.462235) (xy 269.622675 -296.454412) (xy 269.673681 -296.454412)
			(xy 269.724084 -296.462235) (xy 269.77269 -296.477694) (xy 269.818351 -296.500425) (xy 269.83944 -296.514774)
			(xy 269.845965 -296.519077) (xy 269.86084 -296.523853) (xy 269.86865 -296.524172) (xy 270.384778 -296.524172)
			(xy 270.390218 -296.524498) (xy 270.397907 -296.532194) (xy 270.39824 -296.537634) (xy 270.39824 -297.032172)
			(xy 276.442424 -297.032172) (xy 276.442424 -296.537634) (xy 276.442944 -296.532338) (xy 276.450348 -296.524765)
			(xy 276.455632 -296.524172) (xy 276.97176 -296.524172) (xy 276.979569 -296.523846) (xy 276.994441 -296.519069)
			(xy 277.00097 -296.514774) (xy 277.022059 -296.500425) (xy 277.06772 -296.477694) (xy 277.116326 -296.462235)
			(xy 277.166729 -296.454412) (xy 277.217735 -296.454412) (xy 277.268138 -296.462235) (xy 277.316744 -296.477694)
			(xy 277.362405 -296.500425) (xy 277.383494 -296.514774) (xy 277.390029 -296.519059) (xy 277.404896 -296.523846)
			(xy 277.412704 -296.524172) (xy 277.928832 -296.524172) (xy 277.934094 -296.524671) (xy 277.941533 -296.532118)
			(xy 277.94204 -296.53738) (xy 277.94204 -296.537888) (xy 277.94204 -297.032172) (xy 283.986224 -297.032172)
			(xy 283.986224 -296.537634) (xy 283.986744 -296.532338) (xy 283.994148 -296.524765) (xy 283.999432 -296.524172)
			(xy 284.51556 -296.524172) (xy 284.523369 -296.523846) (xy 284.538241 -296.519069) (xy 284.54477 -296.514774)
			(xy 284.565859 -296.500425) (xy 284.61152 -296.477694) (xy 284.660126 -296.462235) (xy 284.710529 -296.454412)
			(xy 284.761535 -296.454412) (xy 284.811938 -296.462235) (xy 284.860544 -296.477694) (xy 284.906205 -296.500425)
			(xy 284.927294 -296.514774) (xy 284.933829 -296.519059) (xy 284.948696 -296.523846) (xy 284.956504 -296.524172)
			(xy 285.472632 -296.524172) (xy 285.477894 -296.524671) (xy 285.485333 -296.532118) (xy 285.48584 -296.53738)
			(xy 285.48584 -296.537888) (xy 285.48584 -297.032172) (xy 291.530024 -297.032172) (xy 291.530024 -296.537634)
			(xy 291.530401 -296.532207) (xy 291.53806 -296.52452) (xy 291.543486 -296.524172) (xy 292.059614 -296.524172)
			(xy 292.067425 -296.523869) (xy 292.082297 -296.519076) (xy 292.088824 -296.514774) (xy 292.109913 -296.500425)
			(xy 292.155574 -296.477694) (xy 292.20418 -296.462235) (xy 292.254583 -296.454412) (xy 292.305589 -296.454412)
			(xy 292.355992 -296.462235) (xy 292.404598 -296.477694) (xy 292.450259 -296.500425) (xy 292.471348 -296.514774)
			(xy 292.477871 -296.51908) (xy 292.492748 -296.523854) (xy 292.500558 -296.524172) (xy 293.016686 -296.524172)
			(xy 293.022127 -296.524492) (xy 293.029816 -296.532192) (xy 293.030148 -296.537634) (xy 293.030148 -297.032172)
			(xy 299.074332 -297.032172) (xy 299.074332 -296.537634) (xy 299.074845 -296.532336) (xy 299.082253 -296.524763)
			(xy 299.08754 -296.524172) (xy 299.603668 -296.524172) (xy 299.611477 -296.523849) (xy 299.626349 -296.51907)
			(xy 299.632878 -296.514774) (xy 299.653967 -296.500425) (xy 299.699628 -296.477694) (xy 299.748234 -296.462235)
			(xy 299.798637 -296.454412) (xy 299.849643 -296.454412) (xy 299.900046 -296.462235) (xy 299.948652 -296.477694)
			(xy 299.994313 -296.500425) (xy 300.015402 -296.514774) (xy 300.021935 -296.519062) (xy 300.036804 -296.523847)
			(xy 300.044612 -296.524172) (xy 300.56074 -296.524172) (xy 300.566003 -296.524666) (xy 300.573442 -296.532116)
			(xy 300.573948 -296.53738) (xy 300.573948 -296.537888) (xy 300.573948 -297.032172) (xy 306.618132 -297.032172)
			(xy 306.618132 -296.537634) (xy 306.618501 -296.532205) (xy 306.626166 -296.524518) (xy 306.631594 -296.524172)
			(xy 308.104794 -296.524172) (xy 308.110236 -296.524487) (xy 308.117925 -296.532191) (xy 308.118256 -296.537634)
			(xy 308.118256 -297.032172) (xy 415.718244 -297.032172) (xy 415.718244 -296.537634) (xy 415.718746 -296.532333)
			(xy 415.726162 -296.52476) (xy 415.731452 -296.524172) (xy 417.204652 -296.524172) (xy 417.209973 -296.524557)
			(xy 417.217515 -296.532061) (xy 417.21786 -296.53738) (xy 417.21786 -297.032172) (xy 423.262044 -297.032172)
			(xy 423.262044 -296.537634) (xy 423.262403 -296.532202) (xy 423.270075 -296.524514) (xy 423.275506 -296.524172)
			(xy 423.791634 -296.524172) (xy 423.799442 -296.523835) (xy 423.814314 -296.519065) (xy 423.820844 -296.514774)
			(xy 423.841933 -296.500425) (xy 423.887594 -296.477694) (xy 423.9362 -296.462235) (xy 423.986603 -296.454412)
			(xy 424.037609 -296.454412) (xy 424.088012 -296.462235) (xy 424.136618 -296.477694) (xy 424.182279 -296.500425)
			(xy 424.203368 -296.514774) (xy 424.209909 -296.519049) (xy 424.224772 -296.523842) (xy 424.232578 -296.524172)
			(xy 424.748706 -296.524172) (xy 424.75415 -296.524479) (xy 424.761837 -296.532189) (xy 424.762168 -296.537634)
			(xy 424.762168 -297.032172) (xy 430.806352 -297.032172) (xy 430.806352 -296.537634) (xy 430.806847 -296.532331)
			(xy 430.814268 -296.524757) (xy 430.81956 -296.524172) (xy 431.335688 -296.524172) (xy 431.343498 -296.523858)
			(xy 431.35837 -296.519073) (xy 431.364898 -296.514774) (xy 431.385987 -296.500425) (xy 431.431648 -296.477694)
			(xy 431.480254 -296.462235) (xy 431.530657 -296.454412) (xy 431.581663 -296.454412) (xy 431.632066 -296.462235)
			(xy 431.680672 -296.477694) (xy 431.726333 -296.500425) (xy 431.747422 -296.514774) (xy 431.753951 -296.51907)
			(xy 431.768823 -296.52385) (xy 431.776632 -296.524172) (xy 432.29276 -296.524172) (xy 432.298082 -296.524552)
			(xy 432.305624 -296.53206) (xy 432.305968 -296.53738) (xy 432.305968 -296.537888) (xy 432.305968 -297.032172)
			(xy 438.350152 -297.032172) (xy 438.350152 -296.537634) (xy 438.350503 -296.5322) (xy 438.358181 -296.524512)
			(xy 438.363614 -296.524172) (xy 438.879742 -296.524172) (xy 438.88755 -296.523838) (xy 438.902422 -296.519066)
			(xy 438.908952 -296.514774) (xy 438.930041 -296.500425) (xy 438.975702 -296.477694) (xy 439.024308 -296.462235)
			(xy 439.074711 -296.454412) (xy 439.125717 -296.454412) (xy 439.17612 -296.462235) (xy 439.224726 -296.477694)
			(xy 439.270387 -296.500425) (xy 439.291476 -296.514774) (xy 439.298015 -296.519052) (xy 439.312879 -296.523844)
			(xy 439.320686 -296.524172) (xy 439.836814 -296.524172) (xy 439.842259 -296.524473) (xy 439.849946 -296.532188)
			(xy 439.850276 -296.537634) (xy 439.850276 -297.032172) (xy 445.89446 -297.032172) (xy 445.89446 -296.537634)
			(xy 445.894948 -296.532329) (xy 445.902374 -296.524755) (xy 445.907668 -296.524172) (xy 446.423796 -296.524172)
			(xy 446.431606 -296.523861) (xy 446.446478 -296.519074) (xy 446.453006 -296.514774) (xy 446.474095 -296.500425)
			(xy 446.519756 -296.477694) (xy 446.568362 -296.462235) (xy 446.618765 -296.454412) (xy 446.669771 -296.454412)
			(xy 446.720174 -296.462235) (xy 446.76878 -296.477694) (xy 446.814441 -296.500425) (xy 446.83553 -296.514774)
			(xy 446.842057 -296.519073) (xy 446.85693 -296.523851) (xy 446.86474 -296.524172) (xy 447.380868 -296.524172)
			(xy 447.386191 -296.524546) (xy 447.393733 -296.532058) (xy 447.394076 -296.53738) (xy 447.394076 -296.537888)
			(xy 447.394076 -297.032172) (xy 453.43826 -297.032172) (xy 453.43826 -296.537634) (xy 453.438748 -296.532329)
			(xy 453.446174 -296.524755) (xy 453.451468 -296.524172) (xy 453.967596 -296.524172) (xy 453.975406 -296.523861)
			(xy 453.990278 -296.519074) (xy 453.996806 -296.514774) (xy 454.017895 -296.500425) (xy 454.063556 -296.477694)
			(xy 454.112162 -296.462235) (xy 454.162565 -296.454412) (xy 454.213571 -296.454412) (xy 454.263974 -296.462235)
			(xy 454.31258 -296.477694) (xy 454.358241 -296.500425) (xy 454.37933 -296.514774) (xy 454.385857 -296.519073)
			(xy 454.40073 -296.523851) (xy 454.40854 -296.524172) (xy 454.924668 -296.524172) (xy 454.929991 -296.524546)
			(xy 454.937533 -296.532058) (xy 454.937876 -296.53738) (xy 454.937876 -296.537888) (xy 454.937876 -297.032172)
			(xy 454.937551 -297.037508) (xy 454.930004 -297.045053) (xy 454.924668 -297.04538) (xy 454.408794 -297.04538)
			(xy 454.400919 -297.045668) (xy 454.385915 -297.050451) (xy 454.37933 -297.054778) (xy 454.358265 -297.069188)
			(xy 454.312615 -297.092012) (xy 454.264006 -297.107564) (xy 454.213586 -297.115477) (xy 454.188068 -297.115992)
			(xy 454.162548 -297.115487) (xy 454.112122 -297.107597) (xy 454.06351 -297.092042) (xy 454.017871 -297.069191)
			(xy 453.996806 -297.054778) (xy 453.99021 -297.05047) (xy 453.975214 -297.045677) (xy 453.967342 -297.04538)
			(xy 453.451468 -297.04538) (xy 453.446195 -297.044924) (xy 453.438752 -297.037448) (xy 453.43826 -297.032172)
			(xy 447.394076 -297.032172) (xy 447.393751 -297.037508) (xy 447.386204 -297.045053) (xy 447.380868 -297.04538)
			(xy 446.864994 -297.04538) (xy 446.857119 -297.045668) (xy 446.842115 -297.050451) (xy 446.83553 -297.054778)
			(xy 446.814465 -297.069188) (xy 446.768815 -297.092012) (xy 446.720206 -297.107564) (xy 446.669786 -297.115477)
			(xy 446.644268 -297.115992) (xy 446.618748 -297.115487) (xy 446.568322 -297.107597) (xy 446.51971 -297.092042)
			(xy 446.474071 -297.069191) (xy 446.453006 -297.054778) (xy 446.44641 -297.05047) (xy 446.431414 -297.045677)
			(xy 446.423542 -297.04538) (xy 445.907668 -297.04538) (xy 445.902395 -297.044924) (xy 445.894952 -297.037448)
			(xy 445.89446 -297.032172) (xy 439.850276 -297.032172) (xy 439.849951 -297.037508) (xy 439.842404 -297.045053)
			(xy 439.837068 -297.04538) (xy 439.83656 -297.04538) (xy 439.32094 -297.04538) (xy 439.313063 -297.045645)
			(xy 439.298059 -297.050444) (xy 439.291476 -297.054778) (xy 439.270398 -297.069168) (xy 439.224753 -297.091996)
			(xy 439.176147 -297.107554) (xy 439.125731 -297.115474) (xy 439.100214 -297.115992) (xy 439.074693 -297.115514)
			(xy 439.024266 -297.107616) (xy 438.975654 -297.092053) (xy 438.930016 -297.069195) (xy 438.908952 -297.054778)
			(xy 438.902368 -297.050449) (xy 438.887362 -297.045669) (xy 438.879488 -297.04538) (xy 438.363614 -297.04538)
			(xy 438.358316 -297.04487) (xy 438.350746 -297.037458) (xy 438.350152 -297.032172) (xy 432.305968 -297.032172)
			(xy 432.305651 -297.03751) (xy 432.298099 -297.045055) (xy 432.29276 -297.04538) (xy 431.776886 -297.04538)
			(xy 431.769011 -297.045664) (xy 431.754007 -297.05045) (xy 431.747422 -297.054778) (xy 431.726359 -297.069192)
			(xy 431.680709 -297.092014) (xy 431.632098 -297.107566) (xy 431.581678 -297.115478) (xy 431.55616 -297.115992)
			(xy 431.53064 -297.115491) (xy 431.480214 -297.1076) (xy 431.431602 -297.092043) (xy 431.385963 -297.069192)
			(xy 431.364898 -297.054778) (xy 431.358304 -297.050467) (xy 431.343306 -297.045676) (xy 431.335434 -297.04538)
			(xy 430.81956 -297.04538) (xy 430.814286 -297.044929) (xy 430.806844 -297.037449) (xy 430.806352 -297.032172)
			(xy 424.762168 -297.032172) (xy 424.761851 -297.03751) (xy 424.754299 -297.045055) (xy 424.74896 -297.04538)
			(xy 424.748452 -297.04538) (xy 424.232832 -297.04538) (xy 424.224955 -297.045641) (xy 424.209951 -297.050443)
			(xy 424.203368 -297.054778) (xy 424.182292 -297.069172) (xy 424.136646 -297.091999) (xy 424.08804 -297.107556)
			(xy 424.037623 -297.115475) (xy 424.012106 -297.115992) (xy 423.986585 -297.115518) (xy 423.936158 -297.107619)
			(xy 423.887546 -297.092054) (xy 423.841908 -297.069195) (xy 423.820844 -297.054778) (xy 423.814262 -297.050446)
			(xy 423.799255 -297.045668) (xy 423.79138 -297.04538) (xy 423.275506 -297.04538) (xy 423.270207 -297.044875)
			(xy 423.262637 -297.03746) (xy 423.262044 -297.032172) (xy 417.21786 -297.032172) (xy 417.21755 -297.037512)
			(xy 417.209993 -297.045058) (xy 417.204652 -297.04538) (xy 415.731452 -297.04538) (xy 415.726177 -297.044934)
			(xy 415.718735 -297.03745) (xy 415.718244 -297.032172) (xy 308.118256 -297.032172) (xy 308.117692 -297.03742)
			(xy 308.110293 -297.044861) (xy 308.105048 -297.04538) (xy 308.10454 -297.04538) (xy 306.631594 -297.04538)
			(xy 306.626294 -297.044883) (xy 306.618724 -297.037462) (xy 306.618132 -297.032172) (xy 300.573948 -297.032172)
			(xy 300.573391 -297.037422) (xy 300.565987 -297.044864) (xy 300.56074 -297.04538) (xy 300.044866 -297.04538)
			(xy 300.03699 -297.045656) (xy 300.021986 -297.050447) (xy 300.015402 -297.054778) (xy 299.994317 -297.069157)
			(xy 299.948674 -297.091988) (xy 299.900071 -297.107549) (xy 299.849656 -297.115472) (xy 299.82414 -297.115992)
			(xy 299.79862 -297.115501) (xy 299.748193 -297.107607) (xy 299.699581 -297.092047) (xy 299.653943 -297.069193)
			(xy 299.632878 -297.054778) (xy 299.626289 -297.050459) (xy 299.611287 -297.045673) (xy 299.603414 -297.04538)
			(xy 299.08754 -297.04538) (xy 299.082206 -297.045043) (xy 299.074661 -297.037505) (xy 299.074332 -297.032172)
			(xy 293.030148 -297.032172) (xy 293.029591 -297.037422) (xy 293.022187 -297.044864) (xy 293.01694 -297.04538)
			(xy 293.016432 -297.04538) (xy 292.500812 -297.04538) (xy 292.492938 -297.045675) (xy 292.477934 -297.050453)
			(xy 292.471348 -297.054778) (xy 292.450278 -297.069181) (xy 292.40463 -297.092006) (xy 292.356022 -297.10756)
			(xy 292.305603 -297.115476) (xy 292.280086 -297.115992) (xy 292.254567 -297.115478) (xy 292.204141 -297.107591)
			(xy 292.155529 -297.092038) (xy 292.10989 -297.06919) (xy 292.088824 -297.054778) (xy 292.082224 -297.050477)
			(xy 292.067231 -297.04568) (xy 292.05936 -297.04538) (xy 291.543486 -297.04538) (xy 291.538185 -297.044888)
			(xy 291.530616 -297.037463) (xy 291.530024 -297.032172) (xy 285.48584 -297.032172) (xy 285.48529 -297.037424)
			(xy 285.477881 -297.044866) (xy 285.472632 -297.04538) (xy 284.956758 -297.04538) (xy 284.948882 -297.045652)
			(xy 284.933878 -297.050446) (xy 284.927294 -297.054778) (xy 284.906211 -297.069161) (xy 284.860568 -297.09199)
			(xy 284.811964 -297.10755) (xy 284.761548 -297.115473) (xy 284.736032 -297.115992) (xy 284.710512 -297.115505)
			(xy 284.660085 -297.10761) (xy 284.611473 -297.092049) (xy 284.565835 -297.069194) (xy 284.54477 -297.054778)
			(xy 284.538182 -297.050456) (xy 284.52318 -297.045672) (xy 284.515306 -297.04538) (xy 283.999432 -297.04538)
			(xy 283.994097 -297.045049) (xy 283.986553 -297.037507) (xy 283.986224 -297.032172) (xy 277.94204 -297.032172)
			(xy 277.94149 -297.037424) (xy 277.934081 -297.044866) (xy 277.928832 -297.04538) (xy 277.412958 -297.04538)
			(xy 277.405082 -297.045652) (xy 277.390078 -297.050446) (xy 277.383494 -297.054778) (xy 277.362411 -297.069161)
			(xy 277.316768 -297.09199) (xy 277.268164 -297.10755) (xy 277.217748 -297.115473) (xy 277.192232 -297.115992)
			(xy 277.166712 -297.115505) (xy 277.116285 -297.10761) (xy 277.067673 -297.092049) (xy 277.022035 -297.069194)
			(xy 277.00097 -297.054778) (xy 276.994382 -297.050456) (xy 276.97938 -297.045672) (xy 276.971506 -297.04538)
			(xy 276.455632 -297.04538) (xy 276.450297 -297.045049) (xy 276.442753 -297.037507) (xy 276.442424 -297.032172)
			(xy 270.39824 -297.032172) (xy 270.39769 -297.037424) (xy 270.390281 -297.044866) (xy 270.385032 -297.04538)
			(xy 270.384524 -297.04538) (xy 269.868904 -297.04538) (xy 269.86103 -297.045672) (xy 269.846025 -297.050452)
			(xy 269.83944 -297.054778) (xy 269.818372 -297.069184) (xy 269.772723 -297.092008) (xy 269.724115 -297.107562)
			(xy 269.673695 -297.115477) (xy 269.648178 -297.115992) (xy 269.622659 -297.115482) (xy 269.572232 -297.107594)
			(xy 269.523621 -297.09204) (xy 269.477982 -297.069191) (xy 269.456916 -297.054778) (xy 269.450318 -297.050474)
			(xy 269.435323 -297.045679) (xy 269.427452 -297.04538) (xy 268.911578 -297.04538) (xy 268.906276 -297.044894)
			(xy 268.898707 -297.037464) (xy 268.898116 -297.032172) (xy 206.997808 -297.032172) (xy 206.997808 -297.032426)
			(xy 206.9973 -297.037722) (xy 206.989885 -297.045289) (xy 206.9846 -297.045888) (xy 206.468726 -297.045888)
			(xy 206.460915 -297.046198) (xy 206.446043 -297.050985) (xy 206.439516 -297.055286) (xy 206.41839 -297.069629)
			(xy 206.372667 -297.092356) (xy 206.323996 -297.107787) (xy 206.273531 -297.115557) (xy 206.248 -297.115992)
			(xy 206.22247 -297.11555) (xy 206.172007 -297.107775) (xy 206.123334 -297.092347) (xy 206.077606 -297.069633)
			(xy 206.056484 -297.055286) (xy 206.04995 -297.050998) (xy 206.035082 -297.046211) (xy 206.027274 -297.045888)
			(xy 205.5114 -297.045888) (xy 205.506063 -297.045571) (xy 205.498521 -297.038018) (xy 205.498192 -297.03268)
			(xy 199.453984 -297.03268) (xy 199.4535 -297.037722) (xy 199.446085 -297.045289) (xy 199.4408 -297.045888)
			(xy 198.924926 -297.045888) (xy 198.917115 -297.046198) (xy 198.902243 -297.050985) (xy 198.895716 -297.055286)
			(xy 198.87459 -297.069629) (xy 198.828867 -297.092356) (xy 198.780196 -297.107787) (xy 198.729731 -297.115557)
			(xy 198.7042 -297.115992) (xy 198.67867 -297.11555) (xy 198.628207 -297.107775) (xy 198.579534 -297.092347)
			(xy 198.533806 -297.069633) (xy 198.512684 -297.055286) (xy 198.50615 -297.050998) (xy 198.491282 -297.046211)
			(xy 198.483474 -297.045888) (xy 197.9676 -297.045888) (xy 197.962263 -297.045571) (xy 197.954721 -297.038018)
			(xy 197.954392 -297.03268) (xy 191.910183 -297.03268) (xy 191.909671 -297.037782) (xy 191.902101 -297.045363)
			(xy 191.896746 -297.045888) (xy 191.380872 -297.045888) (xy 191.373059 -297.046175) (xy 191.358187 -297.050978)
			(xy 191.351662 -297.055286) (xy 191.330551 -297.069652) (xy 191.284823 -297.092374) (xy 191.236147 -297.107799)
			(xy 191.185678 -297.115561) (xy 191.160146 -297.115992) (xy 191.134617 -297.115527) (xy 191.084154 -297.107759)
			(xy 191.035482 -297.092338) (xy 190.989753 -297.06963) (xy 190.96863 -297.055286) (xy 190.962086 -297.051016)
			(xy 190.947226 -297.046218) (xy 190.93942 -297.045888) (xy 190.423546 -297.045888) (xy 190.418123 -297.045493)
			(xy 190.410436 -297.037846) (xy 190.410084 -297.032426) (xy 184.3659 -297.032426) (xy 184.365399 -297.037724)
			(xy 184.357979 -297.045292) (xy 184.352692 -297.045888) (xy 183.836818 -297.045888) (xy 183.829007 -297.046195)
			(xy 183.814135 -297.050984) (xy 183.807608 -297.055286) (xy 183.786484 -297.069632) (xy 183.740761 -297.092358)
			(xy 183.692088 -297.107789) (xy 183.641623 -297.115558) (xy 183.616092 -297.115992) (xy 183.590562 -297.115555)
			(xy 183.540098 -297.107778) (xy 183.491426 -297.092349) (xy 183.445698 -297.069633) (xy 183.424576 -297.055286)
			(xy 183.418044 -297.050995) (xy 183.403175 -297.04621) (xy 183.395366 -297.045888) (xy 182.879492 -297.045888)
			(xy 182.874154 -297.045577) (xy 182.866612 -297.038019) (xy 182.866284 -297.03268) (xy 176.822075 -297.03268)
			(xy 176.821571 -297.037784) (xy 176.813995 -297.045366) (xy 176.808638 -297.045888) (xy 176.292764 -297.045888)
			(xy 176.284955 -297.046214) (xy 176.270083 -297.05099) (xy 176.263554 -297.055286) (xy 176.242445 -297.069655)
			(xy 176.196717 -297.092377) (xy 176.148039 -297.107801) (xy 176.09757 -297.115562) (xy 176.072038 -297.115992)
			(xy 176.046509 -297.115531) (xy 175.996046 -297.107762) (xy 175.947374 -297.09234) (xy 175.901645 -297.06963)
			(xy 175.880522 -297.055286) (xy 175.87398 -297.051013) (xy 175.859118 -297.046217) (xy 175.851312 -297.045888)
			(xy 175.335438 -297.045888) (xy 175.330014 -297.045498) (xy 175.322328 -297.037848) (xy 175.321976 -297.032426)
			(xy 169.277792 -297.032426) (xy 169.277298 -297.037726) (xy 169.269873 -297.045293) (xy 169.264584 -297.045888)
			(xy 167.791384 -297.045888) (xy 167.786045 -297.045582) (xy 167.778503 -297.03802) (xy 167.778176 -297.03268)
			(xy 60.178163 -297.03268) (xy 60.177669 -297.037787) (xy 60.170087 -297.045369) (xy 60.164726 -297.045888)
			(xy 58.691526 -297.045888) (xy 58.686171 -297.045335) (xy 58.678586 -297.037779) (xy 58.678064 -297.032426)
			(xy 52.63388 -297.032426) (xy 52.633396 -297.037729) (xy 52.625965 -297.045297) (xy 52.620672 -297.045888)
			(xy 52.104798 -297.045888) (xy 52.096986 -297.046186) (xy 52.082114 -297.050981) (xy 52.075588 -297.055286)
			(xy 52.05447 -297.069641) (xy 52.008744 -297.092365) (xy 51.96007 -297.107793) (xy 51.909603 -297.115559)
			(xy 51.884072 -297.115992) (xy 51.858541 -297.115565) (xy 51.808077 -297.107785) (xy 51.759405 -297.092353)
			(xy 51.713678 -297.069634) (xy 51.692556 -297.055286) (xy 51.686029 -297.050987) (xy 51.671156 -297.046207)
			(xy 51.663346 -297.045888) (xy 51.147472 -297.045888) (xy 51.142201 -297.045422) (xy 51.134759 -297.037953)
			(xy 51.134264 -297.03268) (xy 45.090056 -297.03268) (xy 45.089569 -297.037789) (xy 45.081981 -297.045372)
			(xy 45.076618 -297.045888) (xy 44.560744 -297.045888) (xy 44.552934 -297.046206) (xy 44.538062 -297.050987)
			(xy 44.531534 -297.055286) (xy 44.510431 -297.069664) (xy 44.4647 -297.092383) (xy 44.416021 -297.107805)
			(xy 44.365551 -297.115563) (xy 44.340018 -297.115992) (xy 44.314488 -297.115541) (xy 44.264025 -297.107769)
			(xy 44.215353 -297.092344) (xy 44.169625 -297.069631) (xy 44.148502 -297.055286) (xy 44.141964 -297.051005)
			(xy 44.127099 -297.046214) (xy 44.119292 -297.045888) (xy 43.603418 -297.045888) (xy 43.598062 -297.04534)
			(xy 43.590477 -297.03778) (xy 43.589956 -297.032426) (xy 37.545772 -297.032426) (xy 37.545295 -297.03773)
			(xy 37.537859 -297.045299) (xy 37.532564 -297.045888) (xy 37.01669 -297.045888) (xy 37.008878 -297.046183)
			(xy 36.994006 -297.05098) (xy 36.98748 -297.055286) (xy 36.966364 -297.069644) (xy 36.920638 -297.092368)
			(xy 36.871963 -297.107795) (xy 36.821495 -297.11556) (xy 36.795964 -297.115992) (xy 36.770433 -297.115569)
			(xy 36.719969 -297.107788) (xy 36.671297 -297.092355) (xy 36.62557 -297.069635) (xy 36.604448 -297.055286)
			(xy 36.597922 -297.050984) (xy 36.583048 -297.046206) (xy 36.575238 -297.045888) (xy 36.059364 -297.045888)
			(xy 36.054092 -297.045427) (xy 36.046651 -297.037954) (xy 36.046156 -297.03268) (xy 30.001949 -297.03268)
			(xy 30.001495 -297.03773) (xy 29.994059 -297.045299) (xy 29.988764 -297.045888) (xy 29.47289 -297.045888)
			(xy 29.465078 -297.046183) (xy 29.450206 -297.05098) (xy 29.44368 -297.055286) (xy 29.422564 -297.069644)
			(xy 29.376838 -297.092368) (xy 29.328163 -297.107795) (xy 29.277695 -297.11556) (xy 29.252164 -297.115992)
			(xy 29.226633 -297.115569) (xy 29.176169 -297.107788) (xy 29.127497 -297.092355) (xy 29.08177 -297.069635)
			(xy 29.060648 -297.055286) (xy 29.054122 -297.050984) (xy 29.039248 -297.046206) (xy 29.031438 -297.045888)
			(xy 28.515564 -297.045888) (xy 28.510292 -297.045427) (xy 28.502851 -297.037954) (xy 28.502356 -297.03268)
			(xy 22.458148 -297.03268) (xy 22.457668 -297.037791) (xy 22.450075 -297.045374) (xy 22.44471 -297.045888)
			(xy 21.928836 -297.045888) (xy 21.921026 -297.046202) (xy 21.906154 -297.050986) (xy 21.899626 -297.055286)
			(xy 21.878497 -297.069624) (xy 21.832776 -297.092352) (xy 21.784105 -297.107785) (xy 21.73364 -297.115556)
			(xy 21.70811 -297.115992) (xy 21.68258 -297.115545) (xy 21.632117 -297.107772) (xy 21.583445 -297.092345)
			(xy 21.537717 -297.069632) (xy 21.516594 -297.055286) (xy 21.510058 -297.051002) (xy 21.495192 -297.046213)
			(xy 21.487384 -297.045888) (xy 20.97151 -297.045888) (xy 20.966154 -297.045345) (xy 20.958569 -297.037781)
			(xy 20.958048 -297.032426) (xy 2.509012 -297.032426) (xy 2.509012 -297.882564) (xy 16.85798 -297.882564)
			(xy 16.85798 -297.388026) (xy 16.858301 -297.382584) (xy 16.866 -297.374894) (xy 16.871442 -297.374564)
			(xy 17.38757 -297.374564) (xy 17.39538 -297.374243) (xy 17.410251 -297.369463) (xy 17.41678 -297.365166)
			(xy 17.437869 -297.350817) (xy 17.48353 -297.328086) (xy 17.532136 -297.312627) (xy 17.582539 -297.304804)
			(xy 17.633545 -297.304804) (xy 17.683948 -297.312627) (xy 17.732554 -297.328086) (xy 17.778215 -297.350817)
			(xy 17.799304 -297.365166) (xy 17.805837 -297.369454) (xy 17.820706 -297.37424) (xy 17.828514 -297.374564)
			(xy 18.344642 -297.374564) (xy 18.350017 -297.375025) (xy 18.357602 -297.382648) (xy 18.358104 -297.388026)
			(xy 18.358104 -297.882564) (xy 24.402288 -297.882564) (xy 24.402288 -297.388026) (xy 24.402746 -297.382714)
			(xy 24.410193 -297.375138) (xy 24.415496 -297.374564) (xy 24.931624 -297.374564) (xy 24.939436 -297.374267)
			(xy 24.954307 -297.36947) (xy 24.960834 -297.365166) (xy 24.981923 -297.350817) (xy 25.027584 -297.328086)
			(xy 25.07619 -297.312627) (xy 25.126593 -297.304804) (xy 25.177599 -297.304804) (xy 25.228002 -297.312627)
			(xy 25.276608 -297.328086) (xy 25.322269 -297.350817) (xy 25.343358 -297.365166) (xy 25.349879 -297.369475)
			(xy 25.364757 -297.374247) (xy 25.372568 -297.374564) (xy 25.888696 -297.374564) (xy 25.893952 -297.375094)
			(xy 25.901393 -297.382518) (xy 25.901904 -297.387772) (xy 25.901904 -297.38828) (xy 25.901904 -297.882564)
			(xy 31.946088 -297.882564) (xy 31.946088 -297.388026) (xy 31.946546 -297.382714) (xy 31.953993 -297.375138)
			(xy 31.959296 -297.374564) (xy 32.475424 -297.374564) (xy 32.483236 -297.374267) (xy 32.498107 -297.36947)
			(xy 32.504634 -297.365166) (xy 32.525723 -297.350817) (xy 32.571384 -297.328086) (xy 32.61999 -297.312627)
			(xy 32.670393 -297.304804) (xy 32.721399 -297.304804) (xy 32.771802 -297.312627) (xy 32.820408 -297.328086)
			(xy 32.866069 -297.350817) (xy 32.887158 -297.365166) (xy 32.893679 -297.369475) (xy 32.908557 -297.374247)
			(xy 32.916368 -297.374564) (xy 33.432496 -297.374564) (xy 33.437752 -297.375094) (xy 33.445193 -297.382518)
			(xy 33.445704 -297.387772) (xy 33.445704 -297.38828) (xy 33.445704 -297.882564) (xy 39.489888 -297.882564)
			(xy 39.489888 -297.388026) (xy 39.490463 -297.382677) (xy 39.498004 -297.375093) (xy 39.50335 -297.374564)
			(xy 40.019478 -297.374564) (xy 40.027288 -297.374247) (xy 40.042159 -297.369464) (xy 40.048688 -297.365166)
			(xy 40.069777 -297.350817) (xy 40.115438 -297.328086) (xy 40.164044 -297.312627) (xy 40.214447 -297.304804)
			(xy 40.265453 -297.304804) (xy 40.315856 -297.312627) (xy 40.364462 -297.328086) (xy 40.410123 -297.350817)
			(xy 40.431212 -297.365166) (xy 40.437744 -297.369457) (xy 40.452613 -297.374241) (xy 40.460422 -297.374564)
			(xy 40.97655 -297.374564) (xy 40.981926 -297.37502) (xy 40.98951 -297.382647) (xy 40.990012 -297.388026)
			(xy 40.990012 -297.882564) (xy 47.034196 -297.882564) (xy 47.034196 -297.388026) (xy 47.034735 -297.382735)
			(xy 47.042126 -297.375165) (xy 47.047404 -297.374564) (xy 47.563532 -297.374564) (xy 47.57134 -297.374227)
			(xy 47.586212 -297.369458) (xy 47.592742 -297.365166) (xy 47.613831 -297.350817) (xy 47.659492 -297.328086)
			(xy 47.708098 -297.312627) (xy 47.758501 -297.304804) (xy 47.809507 -297.304804) (xy 47.85991 -297.312627)
			(xy 47.908516 -297.328086) (xy 47.954177 -297.350817) (xy 47.975266 -297.365166) (xy 47.981808 -297.36944)
			(xy 47.99667 -297.374234) (xy 48.004476 -297.374564) (xy 48.520604 -297.374564) (xy 48.525861 -297.375089)
			(xy 48.533301 -297.382516) (xy 48.533812 -297.387772) (xy 48.533812 -297.38828) (xy 48.533812 -297.882564)
			(xy 54.577996 -297.882564) (xy 54.577996 -297.388026) (xy 54.578563 -297.382675) (xy 54.58611 -297.375091)
			(xy 54.591458 -297.374564) (xy 56.064658 -297.374564) (xy 56.070094 -297.37491) (xy 56.077783 -297.382591)
			(xy 56.07812 -297.388026) (xy 56.07812 -297.882564) (xy 163.678108 -297.882564) (xy 163.678108 -297.388026)
			(xy 163.678637 -297.382732) (xy 163.686035 -297.375162) (xy 163.691316 -297.374564) (xy 165.164516 -297.374564)
			(xy 165.169774 -297.375081) (xy 165.177214 -297.382514) (xy 165.177724 -297.387772) (xy 165.177724 -297.38828)
			(xy 165.177724 -297.882564) (xy 171.221908 -297.882564) (xy 171.221908 -297.388026) (xy 171.222465 -297.382672)
			(xy 171.230019 -297.375087) (xy 171.23537 -297.374564) (xy 171.751498 -297.374564) (xy 171.759309 -297.374256)
			(xy 171.77418 -297.369467) (xy 171.780708 -297.365166) (xy 171.801797 -297.350817) (xy 171.847458 -297.328086)
			(xy 171.896064 -297.312627) (xy 171.946467 -297.304804) (xy 171.997473 -297.304804) (xy 172.047876 -297.312627)
			(xy 172.096482 -297.328086) (xy 172.142143 -297.350817) (xy 172.163232 -297.365166) (xy 172.169759 -297.369465)
			(xy 172.184632 -297.374244) (xy 172.192442 -297.374564) (xy 172.70857 -297.374564) (xy 172.714007 -297.374902)
			(xy 172.721696 -297.382589) (xy 172.722032 -297.388026) (xy 172.722032 -297.882564) (xy 178.766216 -297.882564)
			(xy 178.766216 -297.388026) (xy 178.766738 -297.382731) (xy 178.774141 -297.375159) (xy 178.779424 -297.374564)
			(xy 179.295552 -297.374564) (xy 179.303361 -297.374236) (xy 179.318233 -297.36946) (xy 179.324762 -297.365166)
			(xy 179.345851 -297.350817) (xy 179.391512 -297.328086) (xy 179.440118 -297.312627) (xy 179.490521 -297.304804)
			(xy 179.541527 -297.304804) (xy 179.59193 -297.312627) (xy 179.640536 -297.328086) (xy 179.686197 -297.350817)
			(xy 179.707286 -297.365166) (xy 179.713823 -297.369447) (xy 179.728689 -297.374237) (xy 179.736496 -297.374564)
			(xy 180.252624 -297.374564) (xy 180.257883 -297.375076) (xy 180.265322 -297.382513) (xy 180.265832 -297.387772)
			(xy 180.265832 -297.38828) (xy 180.265832 -297.882564) (xy 186.310016 -297.882564) (xy 186.310016 -297.388026)
			(xy 186.310394 -297.3826) (xy 186.318053 -297.374914) (xy 186.323478 -297.374564) (xy 186.839606 -297.374564)
			(xy 186.847417 -297.374259) (xy 186.862289 -297.369468) (xy 186.868816 -297.365166) (xy 186.889905 -297.350817)
			(xy 186.935566 -297.328086) (xy 186.984172 -297.312627) (xy 187.034575 -297.304804) (xy 187.085581 -297.304804)
			(xy 187.135984 -297.312627) (xy 187.18459 -297.328086) (xy 187.230251 -297.350817) (xy 187.25134 -297.365166)
			(xy 187.257865 -297.369468) (xy 187.27274 -297.374245) (xy 187.28055 -297.374564) (xy 187.796678 -297.374564)
			(xy 187.802116 -297.374897) (xy 187.809805 -297.382588) (xy 187.81014 -297.388026) (xy 187.81014 -297.882564)
			(xy 193.854324 -297.882564) (xy 193.854324 -297.388026) (xy 193.854839 -297.382729) (xy 193.862246 -297.375157)
			(xy 193.867532 -297.374564) (xy 194.38366 -297.374564) (xy 194.391469 -297.374239) (xy 194.406341 -297.369461)
			(xy 194.41287 -297.365166) (xy 194.433959 -297.350817) (xy 194.47962 -297.328086) (xy 194.528226 -297.312627)
			(xy 194.578629 -297.304804) (xy 194.629635 -297.304804) (xy 194.680038 -297.312627) (xy 194.728644 -297.328086)
			(xy 194.774305 -297.350817) (xy 194.795394 -297.365166) (xy 194.80193 -297.36945) (xy 194.816796 -297.374238)
			(xy 194.824604 -297.374564) (xy 195.340732 -297.374564) (xy 195.345992 -297.375071) (xy 195.353431 -297.382512)
			(xy 195.35394 -297.387772) (xy 195.35394 -297.38828) (xy 195.35394 -297.882564) (xy 201.398124 -297.882564)
			(xy 201.398124 -297.388026) (xy 201.398639 -297.382729) (xy 201.406046 -297.375157) (xy 201.411332 -297.374564)
			(xy 201.92746 -297.374564) (xy 201.935269 -297.374239) (xy 201.950141 -297.369461) (xy 201.95667 -297.365166)
			(xy 201.977759 -297.350817) (xy 202.02342 -297.328086) (xy 202.072026 -297.312627) (xy 202.122429 -297.304804)
			(xy 202.173435 -297.304804) (xy 202.223838 -297.312627) (xy 202.272444 -297.328086) (xy 202.318105 -297.350817)
			(xy 202.339194 -297.365166) (xy 202.34573 -297.36945) (xy 202.360596 -297.374238) (xy 202.368404 -297.374564)
			(xy 202.884532 -297.374564) (xy 202.889792 -297.375071) (xy 202.897231 -297.382512) (xy 202.89774 -297.387772)
			(xy 202.89774 -297.38828) (xy 202.89774 -297.88231) (xy 264.798048 -297.88231) (xy 264.798048 -297.387772)
			(xy 264.798571 -297.382516) (xy 264.806001 -297.375078) (xy 264.811256 -297.374564) (xy 264.811764 -297.374564)
			(xy 265.327638 -297.374564) (xy 265.335446 -297.37423) (xy 265.350318 -297.369458) (xy 265.356848 -297.365166)
			(xy 265.377937 -297.350817) (xy 265.423598 -297.328086) (xy 265.472204 -297.312627) (xy 265.522607 -297.304804)
			(xy 265.573613 -297.304804) (xy 265.624016 -297.312627) (xy 265.672622 -297.328086) (xy 265.718283 -297.350817)
			(xy 265.739372 -297.365166) (xy 265.745913 -297.369442) (xy 265.760776 -297.374235) (xy 265.768582 -297.374564)
			(xy 266.28471 -297.374564) (xy 266.290021 -297.375019) (xy 266.297593 -297.38247) (xy 266.298172 -297.387772)
			(xy 266.298172 -297.88231) (xy 266.298148 -297.882564) (xy 272.342356 -297.882564) (xy 272.342356 -297.882056)
			(xy 272.342356 -297.387772) (xy 272.342872 -297.382515) (xy 272.350307 -297.375075) (xy 272.355564 -297.374564)
			(xy 272.871692 -297.374564) (xy 272.879502 -297.374253) (xy 272.894374 -297.369466) (xy 272.900902 -297.365166)
			(xy 272.921991 -297.350817) (xy 272.967652 -297.328086) (xy 273.016258 -297.312627) (xy 273.066661 -297.304804)
			(xy 273.117667 -297.304804) (xy 273.16807 -297.312627) (xy 273.216676 -297.328086) (xy 273.262337 -297.350817)
			(xy 273.283426 -297.365166) (xy 273.289955 -297.369463) (xy 273.304827 -297.374243) (xy 273.312636 -297.374564)
			(xy 273.828764 -297.374564) (xy 273.834085 -297.374948) (xy 273.841626 -297.382453) (xy 273.841972 -297.387772)
			(xy 273.841972 -297.88231) (xy 273.841949 -297.882564) (xy 279.886156 -297.882564) (xy 279.886156 -297.882056)
			(xy 279.886156 -297.387772) (xy 279.886672 -297.382515) (xy 279.894107 -297.375075) (xy 279.899364 -297.374564)
			(xy 280.415492 -297.374564) (xy 280.423302 -297.374253) (xy 280.438174 -297.369466) (xy 280.444702 -297.365166)
			(xy 280.465791 -297.350817) (xy 280.511452 -297.328086) (xy 280.560058 -297.312627) (xy 280.610461 -297.304804)
			(xy 280.661467 -297.304804) (xy 280.71187 -297.312627) (xy 280.760476 -297.328086) (xy 280.806137 -297.350817)
			(xy 280.827226 -297.365166) (xy 280.833755 -297.369463) (xy 280.848627 -297.374243) (xy 280.856436 -297.374564)
			(xy 281.372564 -297.374564) (xy 281.377885 -297.374948) (xy 281.385426 -297.382453) (xy 281.385772 -297.387772)
			(xy 281.385772 -297.88231) (xy 287.429956 -297.88231) (xy 287.429956 -297.387772) (xy 287.430472 -297.382515)
			(xy 287.437907 -297.375075) (xy 287.443164 -297.374564) (xy 287.443672 -297.374564) (xy 287.959546 -297.374564)
			(xy 287.967355 -297.374233) (xy 287.982226 -297.36946) (xy 287.988756 -297.365166) (xy 288.009845 -297.350817)
			(xy 288.055506 -297.328086) (xy 288.104112 -297.312627) (xy 288.154515 -297.304804) (xy 288.205521 -297.304804)
			(xy 288.255924 -297.312627) (xy 288.30453 -297.328086) (xy 288.350191 -297.350817) (xy 288.37128 -297.365166)
			(xy 288.377819 -297.369445) (xy 288.392683 -297.374236) (xy 288.40049 -297.374564) (xy 288.916618 -297.374564)
			(xy 288.92193 -297.375014) (xy 288.929502 -297.382468) (xy 288.93008 -297.387772) (xy 288.93008 -297.88231)
			(xy 288.930055 -297.882564) (xy 294.974264 -297.882564) (xy 294.974264 -297.882056) (xy 294.974264 -297.387772)
			(xy 294.974773 -297.382513) (xy 294.982213 -297.375073) (xy 294.987472 -297.374564) (xy 295.5036 -297.374564)
			(xy 295.511411 -297.374257) (xy 295.526282 -297.369467) (xy 295.53281 -297.365166) (xy 295.553899 -297.350817)
			(xy 295.59956 -297.328086) (xy 295.648166 -297.312627) (xy 295.698569 -297.304804) (xy 295.749575 -297.304804)
			(xy 295.799978 -297.312627) (xy 295.848584 -297.328086) (xy 295.894245 -297.350817) (xy 295.915334 -297.365166)
			(xy 295.921861 -297.369466) (xy 295.936734 -297.374244) (xy 295.944544 -297.374564) (xy 296.460672 -297.374564)
			(xy 296.465925 -297.37511) (xy 296.473367 -297.382522) (xy 296.47388 -297.387772) (xy 296.47388 -297.88231)
			(xy 302.518064 -297.88231) (xy 302.518064 -297.387772) (xy 302.518573 -297.382513) (xy 302.526013 -297.375073)
			(xy 302.531272 -297.374564) (xy 304.004726 -297.374564) (xy 304.010039 -297.375009) (xy 304.01761 -297.382467)
			(xy 304.018188 -297.387772) (xy 304.018188 -297.88231) (xy 304.018163 -297.882564) (xy 411.618176 -297.882564)
			(xy 411.618176 -297.882056) (xy 411.618176 -297.387772) (xy 411.618674 -297.38251) (xy 411.626121 -297.37507)
			(xy 411.631384 -297.374564) (xy 413.104584 -297.374564) (xy 413.109838 -297.375102) (xy 413.11728 -297.38252)
			(xy 413.117792 -297.387772) (xy 413.117792 -297.88231) (xy 419.161976 -297.88231) (xy 419.161976 -297.387772)
			(xy 419.162474 -297.38251) (xy 419.169921 -297.37507) (xy 419.175184 -297.374564) (xy 419.175692 -297.374564)
			(xy 419.691566 -297.374564) (xy 419.699375 -297.374242) (xy 419.714247 -297.369462) (xy 419.720776 -297.365166)
			(xy 419.741865 -297.350817) (xy 419.787526 -297.328086) (xy 419.836132 -297.312627) (xy 419.886535 -297.304804)
			(xy 419.937541 -297.304804) (xy 419.987944 -297.312627) (xy 420.03655 -297.328086) (xy 420.082211 -297.350817)
			(xy 420.1033 -297.365166) (xy 420.109834 -297.369453) (xy 420.124702 -297.374239) (xy 420.13251 -297.374564)
			(xy 420.648638 -297.374564) (xy 420.653952 -297.375001) (xy 420.661523 -297.382465) (xy 420.6621 -297.387772)
			(xy 420.6621 -297.88231) (xy 420.662074 -297.882564) (xy 426.706284 -297.882564) (xy 426.706284 -297.882056)
			(xy 426.706284 -297.387772) (xy 426.706775 -297.382508) (xy 426.714227 -297.375067) (xy 426.719492 -297.374564)
			(xy 427.23562 -297.374564) (xy 427.243432 -297.374265) (xy 427.258303 -297.36947) (xy 427.26483 -297.365166)
			(xy 427.285919 -297.350817) (xy 427.33158 -297.328086) (xy 427.380186 -297.312627) (xy 427.430589 -297.304804)
			(xy 427.481595 -297.304804) (xy 427.531998 -297.312627) (xy 427.580604 -297.328086) (xy 427.626265 -297.350817)
			(xy 427.647354 -297.365166) (xy 427.653876 -297.369473) (xy 427.668753 -297.374247) (xy 427.676564 -297.374564)
			(xy 428.192692 -297.374564) (xy 428.197947 -297.375097) (xy 428.205389 -297.382518) (xy 428.2059 -297.387772)
			(xy 428.2059 -297.88231) (xy 434.250084 -297.88231) (xy 434.250084 -297.387772) (xy 434.250575 -297.382508)
			(xy 434.258027 -297.375067) (xy 434.263292 -297.374564) (xy 434.2638 -297.374564) (xy 434.779674 -297.374564)
			(xy 434.787484 -297.374245) (xy 434.802355 -297.369463) (xy 434.808884 -297.365166) (xy 434.829973 -297.350817)
			(xy 434.875634 -297.328086) (xy 434.92424 -297.312627) (xy 434.974643 -297.304804) (xy 435.025649 -297.304804)
			(xy 435.076052 -297.312627) (xy 435.124658 -297.328086) (xy 435.170319 -297.350817) (xy 435.191408 -297.365166)
			(xy 435.197941 -297.369456) (xy 435.21281 -297.37424) (xy 435.220618 -297.374564) (xy 435.736746 -297.374564)
			(xy 435.742049 -297.375062) (xy 435.749625 -297.38248) (xy 435.750208 -297.387772) (xy 435.750208 -297.88231)
			(xy 435.750182 -297.882564) (xy 441.794392 -297.882564) (xy 441.794392 -297.882056) (xy 441.794392 -297.387772)
			(xy 441.794876 -297.382506) (xy 441.802333 -297.375065) (xy 441.8076 -297.374564) (xy 442.323728 -297.374564)
			(xy 442.33154 -297.374268) (xy 442.346411 -297.369471) (xy 442.352938 -297.365166) (xy 442.374027 -297.350817)
			(xy 442.419688 -297.328086) (xy 442.468294 -297.312627) (xy 442.518697 -297.304804) (xy 442.569703 -297.304804)
			(xy 442.620106 -297.312627) (xy 442.668712 -297.328086) (xy 442.714373 -297.350817) (xy 442.735462 -297.365166)
			(xy 442.742005 -297.369438) (xy 442.756866 -297.374233) (xy 442.764672 -297.374564) (xy 443.2808 -297.374564)
			(xy 443.286056 -297.375092) (xy 443.293497 -297.382517) (xy 443.294008 -297.387772) (xy 443.294008 -297.88231)
			(xy 443.293983 -297.882564) (xy 449.338192 -297.882564) (xy 449.338192 -297.882056) (xy 449.338192 -297.387772)
			(xy 449.338676 -297.382506) (xy 449.346133 -297.375065) (xy 449.3514 -297.374564) (xy 449.867528 -297.374564)
			(xy 449.87534 -297.374268) (xy 449.890211 -297.369471) (xy 449.896738 -297.365166) (xy 449.917827 -297.350817)
			(xy 449.963488 -297.328086) (xy 450.012094 -297.312627) (xy 450.062497 -297.304804) (xy 450.113503 -297.304804)
			(xy 450.163906 -297.312627) (xy 450.212512 -297.328086) (xy 450.258173 -297.350817) (xy 450.279262 -297.365166)
			(xy 450.285805 -297.369438) (xy 450.300666 -297.374233) (xy 450.308472 -297.374564) (xy 450.8246 -297.374564)
			(xy 450.829856 -297.375092) (xy 450.837297 -297.382517) (xy 450.837808 -297.387772) (xy 450.837808 -297.88231)
			(xy 450.837289 -297.887604) (xy 450.829882 -297.895172) (xy 450.8246 -297.895772) (xy 450.308726 -297.895772)
			(xy 450.300916 -297.896085) (xy 450.286044 -297.90087) (xy 450.279516 -297.90517) (xy 450.258389 -297.919511)
			(xy 450.212667 -297.942239) (xy 450.163995 -297.957671) (xy 450.11353 -297.965441) (xy 450.088 -297.965876)
			(xy 450.06247 -297.965437) (xy 450.012006 -297.957662) (xy 449.963334 -297.942233) (xy 449.917606 -297.919517)
			(xy 449.896484 -297.90517) (xy 449.889951 -297.900881) (xy 449.875082 -297.896095) (xy 449.867274 -297.895772)
			(xy 449.3514 -297.895772) (xy 449.346059 -297.89547) (xy 449.338516 -297.887906) (xy 449.338192 -297.882564)
			(xy 443.293983 -297.882564) (xy 443.293489 -297.887604) (xy 443.286082 -297.895172) (xy 443.2808 -297.895772)
			(xy 442.764926 -297.895772) (xy 442.757116 -297.896085) (xy 442.742244 -297.90087) (xy 442.735716 -297.90517)
			(xy 442.714589 -297.919511) (xy 442.668867 -297.942239) (xy 442.620195 -297.957671) (xy 442.56973 -297.965441)
			(xy 442.5442 -297.965876) (xy 442.51867 -297.965437) (xy 442.468206 -297.957662) (xy 442.419534 -297.942233)
			(xy 442.373806 -297.919517) (xy 442.352684 -297.90517) (xy 442.346151 -297.900881) (xy 442.331282 -297.896095)
			(xy 442.323474 -297.895772) (xy 441.8076 -297.895772) (xy 441.802259 -297.89547) (xy 441.794716 -297.887906)
			(xy 441.794392 -297.882564) (xy 435.750182 -297.882564) (xy 435.749661 -297.887664) (xy 435.742099 -297.895247)
			(xy 435.736746 -297.895772) (xy 435.220872 -297.895772) (xy 435.21306 -297.896062) (xy 435.198188 -297.900863)
			(xy 435.191662 -297.90517) (xy 435.17055 -297.919534) (xy 435.124822 -297.942257) (xy 435.076146 -297.957683)
			(xy 435.025678 -297.965445) (xy 435.000146 -297.965876) (xy 434.974617 -297.965414) (xy 434.924154 -297.957646)
			(xy 434.875482 -297.942224) (xy 434.829753 -297.919514) (xy 434.80863 -297.90517) (xy 434.802087 -297.900898)
			(xy 434.787226 -297.896102) (xy 434.77942 -297.895772) (xy 434.263546 -297.895772) (xy 434.25812 -297.895391)
			(xy 434.250432 -297.887735) (xy 434.250084 -297.88231) (xy 428.2059 -297.88231) (xy 428.205388 -297.887606)
			(xy 428.197977 -297.895174) (xy 428.192692 -297.895772) (xy 427.676818 -297.895772) (xy 427.669007 -297.896081)
			(xy 427.654135 -297.900869) (xy 427.647608 -297.90517) (xy 427.626483 -297.919514) (xy 427.58076 -297.942241)
			(xy 427.532088 -297.957673) (xy 427.481623 -297.965442) (xy 427.456092 -297.965876) (xy 427.430562 -297.965441)
			(xy 427.380098 -297.957665) (xy 427.331426 -297.942235) (xy 427.285698 -297.919518) (xy 427.264576 -297.90517)
			(xy 427.258045 -297.900878) (xy 427.243175 -297.896094) (xy 427.235366 -297.895772) (xy 426.719492 -297.895772)
			(xy 426.71415 -297.895475) (xy 426.706607 -297.887907) (xy 426.706284 -297.882564) (xy 420.662074 -297.882564)
			(xy 420.66156 -297.887666) (xy 420.653993 -297.895249) (xy 420.648638 -297.895772) (xy 420.132764 -297.895772)
			(xy 420.124955 -297.896101) (xy 420.110083 -297.900875) (xy 420.103554 -297.90517) (xy 420.082444 -297.919537)
			(xy 420.036716 -297.94226) (xy 419.988039 -297.957684) (xy 419.93757 -297.965446) (xy 419.912038 -297.965876)
			(xy 419.886509 -297.965418) (xy 419.836046 -297.957649) (xy 419.787373 -297.942225) (xy 419.741645 -297.919515)
			(xy 419.720522 -297.90517) (xy 419.713981 -297.900895) (xy 419.699118 -297.896101) (xy 419.691312 -297.895772)
			(xy 419.175438 -297.895772) (xy 419.170011 -297.895396) (xy 419.162323 -297.887736) (xy 419.161976 -297.88231)
			(xy 413.117792 -297.88231) (xy 413.117287 -297.887608) (xy 413.109871 -297.895177) (xy 413.104584 -297.895772)
			(xy 411.631384 -297.895772) (xy 411.626041 -297.895481) (xy 411.618498 -297.887909) (xy 411.618176 -297.882564)
			(xy 304.018163 -297.882564) (xy 304.017659 -297.887669) (xy 304.010084 -297.895252) (xy 304.004726 -297.895772)
			(xy 302.531526 -297.895772) (xy 302.526097 -297.895404) (xy 302.51841 -297.887738) (xy 302.518064 -297.88231)
			(xy 296.47388 -297.88231) (xy 296.473386 -297.887611) (xy 296.465962 -297.89518) (xy 296.460672 -297.895772)
			(xy 295.944798 -297.895772) (xy 295.936987 -297.896073) (xy 295.922115 -297.900866) (xy 295.915588 -297.90517)
			(xy 295.894469 -297.919523) (xy 295.848744 -297.942248) (xy 295.80007 -297.957677) (xy 295.749603 -297.965443)
			(xy 295.724072 -297.965876) (xy 295.698541 -297.965451) (xy 295.648077 -297.957672) (xy 295.599405 -297.942239)
			(xy 295.553678 -297.919519) (xy 295.532556 -297.90517) (xy 295.526029 -297.90087) (xy 295.511156 -297.896091)
			(xy 295.503346 -297.895772) (xy 294.987472 -297.895772) (xy 294.982127 -297.895488) (xy 294.974586 -297.88791)
			(xy 294.974264 -297.882564) (xy 288.930055 -297.882564) (xy 288.929558 -297.887671) (xy 288.921978 -297.895255)
			(xy 288.916618 -297.895772) (xy 288.400744 -297.895772) (xy 288.392934 -297.896092) (xy 288.378062 -297.900872)
			(xy 288.371534 -297.90517) (xy 288.35043 -297.919546) (xy 288.304699 -297.942266) (xy 288.256021 -297.957689)
			(xy 288.20555 -297.965447) (xy 288.180018 -297.965876) (xy 288.154488 -297.965428) (xy 288.104025 -297.957655)
			(xy 288.055352 -297.94223) (xy 288.009624 -297.919516) (xy 287.988502 -297.90517) (xy 287.981965 -297.900887)
			(xy 287.967099 -297.896098) (xy 287.959292 -297.895772) (xy 287.443418 -297.895772) (xy 287.437988 -297.89541)
			(xy 287.430301 -297.887739) (xy 287.429956 -297.88231) (xy 281.385772 -297.88231) (xy 281.385285 -297.887613)
			(xy 281.377856 -297.895182) (xy 281.372564 -297.895772) (xy 280.85669 -297.895772) (xy 280.848878 -297.896069)
			(xy 280.834007 -297.900865) (xy 280.82748 -297.90517) (xy 280.806363 -297.919526) (xy 280.760637 -297.942251)
			(xy 280.711963 -297.957679) (xy 280.661495 -297.965444) (xy 280.635964 -297.965876) (xy 280.610433 -297.965455)
			(xy 280.559969 -297.957674) (xy 280.511296 -297.94224) (xy 280.465569 -297.919519) (xy 280.444448 -297.90517)
			(xy 280.437923 -297.900867) (xy 280.423048 -297.89609) (xy 280.415238 -297.895772) (xy 279.899364 -297.895772)
			(xy 279.894088 -297.895325) (xy 279.886646 -297.887842) (xy 279.886156 -297.882564) (xy 273.841949 -297.882564)
			(xy 273.841485 -297.887613) (xy 273.834056 -297.895182) (xy 273.828764 -297.895772) (xy 273.31289 -297.895772)
			(xy 273.305078 -297.896069) (xy 273.290207 -297.900865) (xy 273.28368 -297.90517) (xy 273.262563 -297.919526)
			(xy 273.216837 -297.942251) (xy 273.168163 -297.957679) (xy 273.117695 -297.965444) (xy 273.092164 -297.965876)
			(xy 273.066633 -297.965455) (xy 273.016169 -297.957674) (xy 272.967496 -297.94224) (xy 272.921769 -297.919519)
			(xy 272.900648 -297.90517) (xy 272.894123 -297.900867) (xy 272.879248 -297.89609) (xy 272.871438 -297.895772)
			(xy 272.355564 -297.895772) (xy 272.350288 -297.895325) (xy 272.342846 -297.887842) (xy 272.342356 -297.882564)
			(xy 266.298148 -297.882564) (xy 266.297657 -297.887673) (xy 266.290073 -297.895257) (xy 266.28471 -297.895772)
			(xy 265.768836 -297.895772) (xy 265.761026 -297.896089) (xy 265.746154 -297.900871) (xy 265.739626 -297.90517)
			(xy 265.718496 -297.919506) (xy 265.672775 -297.942235) (xy 265.624104 -297.957669) (xy 265.57364 -297.96544)
			(xy 265.54811 -297.965876) (xy 265.52258 -297.965432) (xy 265.472117 -297.957658) (xy 265.423444 -297.942231)
			(xy 265.377716 -297.919516) (xy 265.356594 -297.90517) (xy 265.350059 -297.900884) (xy 265.335192 -297.896097)
			(xy 265.327384 -297.895772) (xy 264.81151 -297.895772) (xy 264.80615 -297.895244) (xy 264.798564 -297.887669)
			(xy 264.798048 -297.88231) (xy 202.89774 -297.88231) (xy 202.89774 -297.882564) (xy 202.897352 -297.887884)
			(xy 202.88985 -297.895425) (xy 202.884532 -297.895772) (xy 202.368658 -297.895772) (xy 202.360782 -297.896046)
			(xy 202.345778 -297.900839) (xy 202.339194 -297.90517) (xy 202.31811 -297.919552) (xy 202.272467 -297.942382)
			(xy 202.223863 -297.957942) (xy 202.173448 -297.965865) (xy 202.147932 -297.966384) (xy 202.122412 -297.965898)
			(xy 202.071984 -297.958003) (xy 202.023373 -297.942442) (xy 201.977735 -297.919586) (xy 201.95667 -297.90517)
			(xy 201.950083 -297.900847) (xy 201.93508 -297.896064) (xy 201.927206 -297.895772) (xy 201.411332 -297.895772)
			(xy 201.405995 -297.895448) (xy 201.39845 -297.887901) (xy 201.398124 -297.882564) (xy 195.35394 -297.882564)
			(xy 195.353552 -297.887884) (xy 195.34605 -297.895425) (xy 195.340732 -297.895772) (xy 194.824858 -297.895772)
			(xy 194.816982 -297.896046) (xy 194.801978 -297.900839) (xy 194.795394 -297.90517) (xy 194.77431 -297.919552)
			(xy 194.728667 -297.942382) (xy 194.680063 -297.957942) (xy 194.629648 -297.965865) (xy 194.604132 -297.966384)
			(xy 194.578612 -297.965898) (xy 194.528184 -297.958003) (xy 194.479573 -297.942442) (xy 194.433935 -297.919586)
			(xy 194.41287 -297.90517) (xy 194.406283 -297.900847) (xy 194.39128 -297.896064) (xy 194.383406 -297.895772)
			(xy 193.867532 -297.895772) (xy 193.862195 -297.895448) (xy 193.85465 -297.887901) (xy 193.854324 -297.882564)
			(xy 187.81014 -297.882564) (xy 187.809752 -297.887884) (xy 187.80225 -297.895425) (xy 187.796932 -297.895772)
			(xy 187.796424 -297.895772) (xy 187.280804 -297.895772) (xy 187.27293 -297.896065) (xy 187.257926 -297.900845)
			(xy 187.25134 -297.90517) (xy 187.230271 -297.919575) (xy 187.184623 -297.9424) (xy 187.136014 -297.957954)
			(xy 187.085595 -297.965869) (xy 187.060078 -297.966384) (xy 187.034559 -297.965875) (xy 186.984132 -297.957987)
			(xy 186.935521 -297.942433) (xy 186.889881 -297.919583) (xy 186.868816 -297.90517) (xy 186.862219 -297.900865)
			(xy 186.847223 -297.896071) (xy 186.839352 -297.895772) (xy 186.323478 -297.895772) (xy 186.318174 -297.895293)
			(xy 186.310605 -297.887858) (xy 186.310016 -297.882564) (xy 180.265832 -297.882564) (xy 180.265451 -297.887886)
			(xy 180.257944 -297.895427) (xy 180.252624 -297.895772) (xy 179.73675 -297.895772) (xy 179.728874 -297.896042)
			(xy 179.71387 -297.900838) (xy 179.707286 -297.90517) (xy 179.686205 -297.919555) (xy 179.640561 -297.942384)
			(xy 179.591956 -297.957944) (xy 179.54154 -297.965865) (xy 179.516024 -297.966384) (xy 179.490503 -297.965902)
			(xy 179.440076 -297.958006) (xy 179.391464 -297.942444) (xy 179.345826 -297.919586) (xy 179.324762 -297.90517)
			(xy 179.318177 -297.900844) (xy 179.303172 -297.896063) (xy 179.295298 -297.895772) (xy 178.779424 -297.895772)
			(xy 178.774086 -297.895453) (xy 178.766542 -297.887902) (xy 178.766216 -297.882564) (xy 172.722032 -297.882564)
			(xy 172.721651 -297.887886) (xy 172.714144 -297.895427) (xy 172.708824 -297.895772) (xy 172.708316 -297.895772)
			(xy 172.192696 -297.895772) (xy 172.184822 -297.896062) (xy 172.169817 -297.900844) (xy 172.163232 -297.90517)
			(xy 172.142166 -297.919578) (xy 172.096517 -297.942402) (xy 172.047907 -297.957955) (xy 171.997488 -297.965869)
			(xy 171.97197 -297.966384) (xy 171.94645 -297.965879) (xy 171.896024 -297.95799) (xy 171.847412 -297.942434)
			(xy 171.801773 -297.919583) (xy 171.780708 -297.90517) (xy 171.774112 -297.900862) (xy 171.759116 -297.89607)
			(xy 171.751244 -297.895772) (xy 171.23537 -297.895772) (xy 171.230065 -297.895298) (xy 171.222496 -297.88786)
			(xy 171.221908 -297.882564) (xy 165.177724 -297.882564) (xy 165.177351 -297.887888) (xy 165.169838 -297.89543)
			(xy 165.164516 -297.895772) (xy 163.691316 -297.895772) (xy 163.685977 -297.895459) (xy 163.678433 -297.887903)
			(xy 163.678108 -297.882564) (xy 56.07812 -297.882564) (xy 56.07775 -297.887889) (xy 56.070235 -297.895431)
			(xy 56.064912 -297.895772) (xy 54.591458 -297.895772) (xy 54.586151 -297.895306) (xy 54.578583 -297.887862)
			(xy 54.577996 -297.882564) (xy 48.533812 -297.882564) (xy 48.533449 -297.887891) (xy 48.525929 -297.895433)
			(xy 48.520604 -297.895772) (xy 48.00473 -297.895772) (xy 47.996853 -297.896034) (xy 47.981849 -297.900835)
			(xy 47.975266 -297.90517) (xy 47.95419 -297.919564) (xy 47.908544 -297.942391) (xy 47.859938 -297.957948)
			(xy 47.809521 -297.965867) (xy 47.784004 -297.966384) (xy 47.758483 -297.965912) (xy 47.708055 -297.958013)
			(xy 47.659444 -297.942448) (xy 47.613806 -297.919588) (xy 47.592742 -297.90517) (xy 47.586161 -297.900836)
			(xy 47.571153 -297.89606) (xy 47.563278 -297.895772) (xy 47.047404 -297.895772) (xy 47.042064 -297.895467)
			(xy 47.03452 -297.887905) (xy 47.034196 -297.882564) (xy 40.990012 -297.882564) (xy 40.989649 -297.887891)
			(xy 40.982129 -297.895433) (xy 40.976804 -297.895772) (xy 40.976296 -297.895772) (xy 40.460676 -297.895772)
			(xy 40.452801 -297.896053) (xy 40.437797 -297.900841) (xy 40.431212 -297.90517) (xy 40.410151 -297.919587)
			(xy 40.3645 -297.942409) (xy 40.315889 -297.95796) (xy 40.265468 -297.965871) (xy 40.23995 -297.966384)
			(xy 40.21443 -297.965889) (xy 40.164003 -297.957997) (xy 40.115391 -297.942438) (xy 40.069753 -297.919585)
			(xy 40.048688 -297.90517) (xy 40.042097 -297.900854) (xy 40.027097 -297.896067) (xy 40.019224 -297.895772)
			(xy 39.50335 -297.895772) (xy 39.498055 -297.895245) (xy 39.490482 -297.887847) (xy 39.489888 -297.882564)
			(xy 33.445704 -297.882564) (xy 33.445349 -297.887892) (xy 33.437824 -297.895436) (xy 33.432496 -297.895772)
			(xy 32.916622 -297.895772) (xy 32.908749 -297.896073) (xy 32.893744 -297.900847) (xy 32.887158 -297.90517)
			(xy 32.866084 -297.919567) (xy 32.820438 -297.942394) (xy 32.771831 -297.95795) (xy 32.721413 -297.965867)
			(xy 32.695896 -297.966384) (xy 32.670375 -297.965916) (xy 32.619947 -297.958016) (xy 32.571335 -297.942449)
			(xy 32.525698 -297.919588) (xy 32.504634 -297.90517) (xy 32.498033 -297.900872) (xy 32.48304 -297.896073)
			(xy 32.47517 -297.895772) (xy 31.959296 -297.895772) (xy 31.953954 -297.895472) (xy 31.946412 -297.887907)
			(xy 31.946088 -297.882564) (xy 25.901904 -297.882564) (xy 25.901549 -297.887892) (xy 25.894024 -297.895436)
			(xy 25.888696 -297.895772) (xy 25.372822 -297.895772) (xy 25.364949 -297.896073) (xy 25.349944 -297.900847)
			(xy 25.343358 -297.90517) (xy 25.322284 -297.919567) (xy 25.276638 -297.942394) (xy 25.228031 -297.95795)
			(xy 25.177613 -297.965867) (xy 25.152096 -297.966384) (xy 25.126575 -297.965916) (xy 25.076147 -297.958016)
			(xy 25.027535 -297.942449) (xy 24.981898 -297.919588) (xy 24.960834 -297.90517) (xy 24.954233 -297.900872)
			(xy 24.93924 -297.896073) (xy 24.93137 -297.895772) (xy 24.415496 -297.895772) (xy 24.410154 -297.895472)
			(xy 24.402612 -297.887907) (xy 24.402288 -297.882564) (xy 18.358104 -297.882564) (xy 18.357749 -297.887892)
			(xy 18.350224 -297.895436) (xy 18.344896 -297.895772) (xy 18.344388 -297.895772) (xy 17.828768 -297.895772)
			(xy 17.820893 -297.89605) (xy 17.805888 -297.90084) (xy 17.799304 -297.90517) (xy 17.778218 -297.919547)
			(xy 17.732576 -297.942378) (xy 17.683973 -297.95794) (xy 17.633558 -297.965864) (xy 17.608042 -297.966384)
			(xy 17.582522 -297.965893) (xy 17.532095 -297.958) (xy 17.483483 -297.94244) (xy 17.437845 -297.919585)
			(xy 17.41678 -297.90517) (xy 17.410191 -297.900851) (xy 17.395189 -297.896065) (xy 17.387316 -297.895772)
			(xy 16.871442 -297.895772) (xy 16.866146 -297.89525) (xy 16.858573 -297.887848) (xy 16.85798 -297.882564)
			(xy 2.509012 -297.882564) (xy 2.509012 -298.732448) (xy 20.958048 -298.732448) (xy 20.958048 -298.23791)
			(xy 20.958387 -298.232474) (xy 20.966074 -298.224787) (xy 20.97151 -298.224448) (xy 21.487638 -298.224448)
			(xy 21.495447 -298.224117) (xy 21.510318 -298.219344) (xy 21.516848 -298.21505) (xy 21.537937 -298.200701)
			(xy 21.583598 -298.17797) (xy 21.632204 -298.162511) (xy 21.682607 -298.154688) (xy 21.733613 -298.154688)
			(xy 21.784016 -298.162511) (xy 21.832622 -298.17797) (xy 21.878283 -298.200701) (xy 21.899372 -298.21505)
			(xy 21.905913 -298.219324) (xy 21.920776 -298.224119) (xy 21.928582 -298.224448) (xy 22.44471 -298.224448)
			(xy 22.450078 -298.224945) (xy 22.457663 -298.232542) (xy 22.458172 -298.23791) (xy 22.458172 -298.732448)
			(xy 28.502356 -298.732448) (xy 28.502356 -298.23791) (xy 28.502831 -298.232603) (xy 28.510267 -298.22503)
			(xy 28.515564 -298.224448) (xy 29.031692 -298.224448) (xy 29.039503 -298.224139) (xy 29.054374 -298.219351)
			(xy 29.060902 -298.21505) (xy 29.081991 -298.200701) (xy 29.127652 -298.17797) (xy 29.176258 -298.162511)
			(xy 29.226661 -298.154688) (xy 29.277667 -298.154688) (xy 29.32807 -298.162511) (xy 29.376676 -298.17797)
			(xy 29.422337 -298.200701) (xy 29.443426 -298.21505) (xy 29.449955 -298.219345) (xy 29.464827 -298.224127)
			(xy 29.472636 -298.224448) (xy 29.988764 -298.224448) (xy 29.994012 -298.225014) (xy 30.001454 -298.232411)
			(xy 30.001972 -298.237656) (xy 30.001972 -298.238164) (xy 30.001972 -298.732448) (xy 36.046156 -298.732448)
			(xy 36.046156 -298.23791) (xy 36.046631 -298.232603) (xy 36.054067 -298.22503) (xy 36.059364 -298.224448)
			(xy 36.575492 -298.224448) (xy 36.583303 -298.224139) (xy 36.598174 -298.219351) (xy 36.604702 -298.21505)
			(xy 36.625791 -298.200701) (xy 36.671452 -298.17797) (xy 36.720058 -298.162511) (xy 36.770461 -298.154688)
			(xy 36.821467 -298.154688) (xy 36.87187 -298.162511) (xy 36.920476 -298.17797) (xy 36.966137 -298.200701)
			(xy 36.987226 -298.21505) (xy 36.993755 -298.219345) (xy 37.008627 -298.224127) (xy 37.016436 -298.224448)
			(xy 37.532564 -298.224448) (xy 37.537812 -298.225014) (xy 37.545254 -298.232411) (xy 37.545772 -298.237656)
			(xy 37.545772 -298.238164) (xy 37.545772 -298.732448) (xy 43.589956 -298.732448) (xy 43.589956 -298.23791)
			(xy 43.590288 -298.232472) (xy 43.59798 -298.224784) (xy 43.603418 -298.224448) (xy 44.119546 -298.224448)
			(xy 44.127355 -298.22412) (xy 44.142227 -298.219345) (xy 44.148756 -298.21505) (xy 44.169845 -298.200701)
			(xy 44.215506 -298.17797) (xy 44.264112 -298.162511) (xy 44.314515 -298.154688) (xy 44.365521 -298.154688)
			(xy 44.415924 -298.162511) (xy 44.46453 -298.17797) (xy 44.510191 -298.200701) (xy 44.53128 -298.21505)
			(xy 44.53782 -298.219327) (xy 44.552683 -298.22412) (xy 44.56049 -298.224448) (xy 45.076618 -298.224448)
			(xy 45.081987 -298.224939) (xy 45.089572 -298.23254) (xy 45.09008 -298.23791) (xy 45.09008 -298.732448)
			(xy 51.134264 -298.732448) (xy 51.134264 -298.23791) (xy 51.134733 -298.232602) (xy 51.142173 -298.225029)
			(xy 51.147472 -298.224448) (xy 51.6636 -298.224448) (xy 51.671411 -298.224143) (xy 51.686283 -298.219352)
			(xy 51.69281 -298.21505) (xy 51.713899 -298.200701) (xy 51.75956 -298.17797) (xy 51.808166 -298.162511)
			(xy 51.858569 -298.154688) (xy 51.909575 -298.154688) (xy 51.959978 -298.162511) (xy 52.008584 -298.17797)
			(xy 52.054245 -298.200701) (xy 52.075334 -298.21505) (xy 52.081862 -298.219348) (xy 52.096735 -298.224128)
			(xy 52.104544 -298.224448) (xy 52.620672 -298.224448) (xy 52.625921 -298.225009) (xy 52.633362 -298.23241)
			(xy 52.63388 -298.237656) (xy 52.63388 -298.238164) (xy 52.63388 -298.732448) (xy 58.678064 -298.732448)
			(xy 58.678064 -298.23791) (xy 58.678388 -298.23247) (xy 58.686086 -298.224782) (xy 58.691526 -298.224448)
			(xy 60.164726 -298.224448) (xy 60.170095 -298.224934) (xy 60.17768 -298.232539) (xy 60.178188 -298.23791)
			(xy 60.178188 -298.732448) (xy 167.778176 -298.732448) (xy 167.778176 -298.23791) (xy 167.778634 -298.232599)
			(xy 167.786082 -298.225025) (xy 167.791384 -298.224448) (xy 169.264584 -298.224448) (xy 169.269834 -298.225001)
			(xy 169.277275 -298.232408) (xy 169.277792 -298.237656) (xy 169.277792 -298.732448) (xy 175.321976 -298.732448)
			(xy 175.321976 -298.23791) (xy 175.32229 -298.232467) (xy 175.329994 -298.224778) (xy 175.335438 -298.224448)
			(xy 175.851566 -298.224448) (xy 175.859376 -298.224128) (xy 175.874247 -298.219347) (xy 175.880776 -298.21505)
			(xy 175.901865 -298.200701) (xy 175.947526 -298.17797) (xy 175.996132 -298.162511) (xy 176.046535 -298.154688)
			(xy 176.097541 -298.154688) (xy 176.147944 -298.162511) (xy 176.19655 -298.17797) (xy 176.242211 -298.200701)
			(xy 176.2633 -298.21505) (xy 176.269835 -298.219335) (xy 176.284702 -298.224123) (xy 176.29251 -298.224448)
			(xy 176.808638 -298.224448) (xy 176.814009 -298.224926) (xy 176.821593 -298.232537) (xy 176.8221 -298.23791)
			(xy 176.8221 -298.732448) (xy 182.866284 -298.732448) (xy 182.866284 -298.23791) (xy 182.866735 -298.232597)
			(xy 182.874187 -298.225023) (xy 182.879492 -298.224448) (xy 183.39562 -298.224448) (xy 183.403432 -298.224152)
			(xy 183.418304 -298.219355) (xy 183.42483 -298.21505) (xy 183.445919 -298.200701) (xy 183.49158 -298.17797)
			(xy 183.540186 -298.162511) (xy 183.590589 -298.154688) (xy 183.641595 -298.154688) (xy 183.691998 -298.162511)
			(xy 183.740604 -298.17797) (xy 183.786265 -298.200701) (xy 183.807354 -298.21505) (xy 183.813877 -298.219356)
			(xy 183.828753 -298.224131) (xy 183.836564 -298.224448) (xy 184.352692 -298.224448) (xy 184.357943 -298.224995)
			(xy 184.365384 -298.232407) (xy 184.3659 -298.237656) (xy 184.3659 -298.238164) (xy 184.3659 -298.732448)
			(xy 190.410084 -298.732448) (xy 190.410084 -298.23791) (xy 190.41039 -298.232465) (xy 190.4181 -298.224776)
			(xy 190.423546 -298.224448) (xy 190.939674 -298.224448) (xy 190.947484 -298.224132) (xy 190.962356 -298.219348)
			(xy 190.968884 -298.21505) (xy 190.989973 -298.200701) (xy 191.035634 -298.17797) (xy 191.08424 -298.162511)
			(xy 191.134643 -298.154688) (xy 191.185649 -298.154688) (xy 191.236052 -298.162511) (xy 191.284658 -298.17797)
			(xy 191.330319 -298.200701) (xy 191.351408 -298.21505) (xy 191.357941 -298.219338) (xy 191.37281 -298.224124)
			(xy 191.380618 -298.224448) (xy 191.896746 -298.224448) (xy 191.902118 -298.224921) (xy 191.909701 -298.232536)
			(xy 191.910208 -298.23791) (xy 191.910208 -298.732448) (xy 197.954392 -298.732448) (xy 197.954392 -298.23791)
			(xy 197.954924 -298.232618) (xy 197.962321 -298.225049) (xy 197.9676 -298.224448) (xy 198.483728 -298.224448)
			(xy 198.49154 -298.224155) (xy 198.506412 -298.219356) (xy 198.512938 -298.21505) (xy 198.534027 -298.200701)
			(xy 198.579688 -298.17797) (xy 198.628294 -298.162511) (xy 198.678697 -298.154688) (xy 198.729703 -298.154688)
			(xy 198.780106 -298.162511) (xy 198.828712 -298.17797) (xy 198.874373 -298.200701) (xy 198.895462 -298.21505)
			(xy 198.902006 -298.219321) (xy 198.916866 -298.224117) (xy 198.924672 -298.224448) (xy 199.4408 -298.224448)
			(xy 199.446052 -298.22499) (xy 199.453492 -298.232406) (xy 199.454008 -298.237656) (xy 199.454008 -298.238164)
			(xy 199.454008 -298.732448) (xy 205.498192 -298.732448) (xy 205.498192 -298.23791) (xy 205.498724 -298.232618)
			(xy 205.506121 -298.225049) (xy 205.5114 -298.224448) (xy 206.027528 -298.224448) (xy 206.03534 -298.224155)
			(xy 206.050212 -298.219356) (xy 206.056738 -298.21505) (xy 206.077827 -298.200701) (xy 206.123488 -298.17797)
			(xy 206.172094 -298.162511) (xy 206.222497 -298.154688) (xy 206.273503 -298.154688) (xy 206.323906 -298.162511)
			(xy 206.372512 -298.17797) (xy 206.418173 -298.200701) (xy 206.439262 -298.21505) (xy 206.445806 -298.219321)
			(xy 206.460666 -298.224117) (xy 206.468472 -298.224448) (xy 206.9846 -298.224448) (xy 206.989852 -298.22499)
			(xy 206.997292 -298.232406) (xy 206.997808 -298.237656) (xy 206.997808 -298.238164) (xy 206.997808 -298.732194)
			(xy 268.898116 -298.732194) (xy 268.898116 -298.237656) (xy 268.898568 -298.232382) (xy 268.906048 -298.224941)
			(xy 268.911324 -298.224448) (xy 268.911832 -298.224448) (xy 269.427706 -298.224448) (xy 269.435517 -298.224146)
			(xy 269.450389 -298.219353) (xy 269.456916 -298.21505) (xy 269.478005 -298.200701) (xy 269.523666 -298.17797)
			(xy 269.572272 -298.162511) (xy 269.622675 -298.154688) (xy 269.673681 -298.154688) (xy 269.724084 -298.162511)
			(xy 269.77269 -298.17797) (xy 269.818351 -298.200701) (xy 269.83944 -298.21505) (xy 269.845966 -298.21935)
			(xy 269.86084 -298.224129) (xy 269.86865 -298.224448) (xy 270.384778 -298.224448) (xy 270.390081 -298.224939)
			(xy 270.397654 -298.232363) (xy 270.39824 -298.237656) (xy 270.39824 -298.732194) (xy 270.398225 -298.732448)
			(xy 276.442424 -298.732448) (xy 276.442424 -298.73194) (xy 276.442424 -298.237656) (xy 276.442869 -298.23238)
			(xy 276.450353 -298.224938) (xy 276.455632 -298.224448) (xy 276.97176 -298.224448) (xy 276.979569 -298.224126)
			(xy 276.994441 -298.219347) (xy 277.00097 -298.21505) (xy 277.022059 -298.200701) (xy 277.06772 -298.17797)
			(xy 277.116326 -298.162511) (xy 277.166729 -298.154688) (xy 277.217735 -298.154688) (xy 277.268138 -298.162511)
			(xy 277.316744 -298.17797) (xy 277.362405 -298.200701) (xy 277.383494 -298.21505) (xy 277.390031 -298.219333)
			(xy 277.404897 -298.224122) (xy 277.412704 -298.224448) (xy 277.928832 -298.224448) (xy 277.934088 -298.224969)
			(xy 277.941526 -298.2324) (xy 277.94204 -298.237656) (xy 277.94204 -298.732194) (xy 277.942018 -298.732448)
			(xy 283.986224 -298.732448) (xy 283.986224 -298.73194) (xy 283.986224 -298.237656) (xy 283.986669 -298.23238)
			(xy 283.994153 -298.224938) (xy 283.999432 -298.224448) (xy 284.51556 -298.224448) (xy 284.523369 -298.224126)
			(xy 284.538241 -298.219347) (xy 284.54477 -298.21505) (xy 284.565859 -298.200701) (xy 284.61152 -298.17797)
			(xy 284.660126 -298.162511) (xy 284.710529 -298.154688) (xy 284.761535 -298.154688) (xy 284.811938 -298.162511)
			(xy 284.860544 -298.17797) (xy 284.906205 -298.200701) (xy 284.927294 -298.21505) (xy 284.933831 -298.219333)
			(xy 284.948697 -298.224122) (xy 284.956504 -298.224448) (xy 285.472632 -298.224448) (xy 285.477888 -298.224969)
			(xy 285.485326 -298.2324) (xy 285.48584 -298.237656) (xy 285.48584 -298.732194) (xy 291.530024 -298.732194)
			(xy 291.530024 -298.237656) (xy 291.530469 -298.23238) (xy 291.537953 -298.224938) (xy 291.543232 -298.224448)
			(xy 291.54374 -298.224448) (xy 292.059614 -298.224448) (xy 292.067426 -298.224149) (xy 292.082297 -298.219354)
			(xy 292.088824 -298.21505) (xy 292.109913 -298.200701) (xy 292.155574 -298.17797) (xy 292.20418 -298.162511)
			(xy 292.254583 -298.154688) (xy 292.305589 -298.154688) (xy 292.355992 -298.162511) (xy 292.404598 -298.17797)
			(xy 292.450259 -298.200701) (xy 292.471348 -298.21505) (xy 292.477873 -298.219353) (xy 292.492748 -298.22413)
			(xy 292.500558 -298.224448) (xy 293.016686 -298.224448) (xy 293.02199 -298.224933) (xy 293.029563 -298.232362)
			(xy 293.030148 -298.237656) (xy 293.030148 -298.732194) (xy 293.030132 -298.732448) (xy 299.074332 -298.732448)
			(xy 299.074332 -298.73194) (xy 299.074332 -298.237656) (xy 299.07477 -298.232378) (xy 299.082259 -298.224936)
			(xy 299.08754 -298.224448) (xy 299.603668 -298.224448) (xy 299.611478 -298.224129) (xy 299.62635 -298.219348)
			(xy 299.632878 -298.21505) (xy 299.653967 -298.200701) (xy 299.699628 -298.17797) (xy 299.748234 -298.162511)
			(xy 299.798637 -298.154688) (xy 299.849643 -298.154688) (xy 299.900046 -298.162511) (xy 299.948652 -298.17797)
			(xy 299.994313 -298.200701) (xy 300.015402 -298.21505) (xy 300.021937 -298.219336) (xy 300.036804 -298.224123)
			(xy 300.044612 -298.224448) (xy 300.56074 -298.224448) (xy 300.565997 -298.224964) (xy 300.573435 -298.232399)
			(xy 300.573948 -298.237656) (xy 300.573948 -298.732194) (xy 306.618132 -298.732194) (xy 306.618132 -298.237656)
			(xy 306.61857 -298.232378) (xy 306.626059 -298.224936) (xy 306.63134 -298.224448) (xy 306.631848 -298.224448)
			(xy 308.104794 -298.224448) (xy 308.110099 -298.224928) (xy 308.117671 -298.232361) (xy 308.118256 -298.237656)
			(xy 308.118256 -298.732194) (xy 308.11824 -298.732448) (xy 415.718244 -298.732448) (xy 415.718244 -298.237656)
			(xy 415.718761 -298.2324) (xy 415.726196 -298.224962) (xy 415.731452 -298.224448) (xy 417.204652 -298.224448)
			(xy 417.209967 -298.224855) (xy 417.217508 -298.232343) (xy 417.21786 -298.237656) (xy 417.21786 -298.732194)
			(xy 423.262044 -298.732194) (xy 423.262044 -298.237656) (xy 423.262561 -298.2324) (xy 423.269996 -298.224962)
			(xy 423.275252 -298.224448) (xy 423.27576 -298.224448) (xy 423.791634 -298.224448) (xy 423.799442 -298.224115)
			(xy 423.814314 -298.219343) (xy 423.820844 -298.21505) (xy 423.841933 -298.200701) (xy 423.887594 -298.17797)
			(xy 423.9362 -298.162511) (xy 423.986603 -298.154688) (xy 424.037609 -298.154688) (xy 424.088012 -298.162511)
			(xy 424.136618 -298.17797) (xy 424.182279 -298.200701) (xy 424.203368 -298.21505) (xy 424.20991 -298.219323)
			(xy 424.224772 -298.224118) (xy 424.232578 -298.224448) (xy 424.748706 -298.224448) (xy 424.754013 -298.22492)
			(xy 424.761584 -298.232359) (xy 424.762168 -298.237656) (xy 424.762168 -298.732194) (xy 424.762143 -298.732448)
			(xy 430.806352 -298.732448) (xy 430.806352 -298.73194) (xy 430.806352 -298.237656) (xy 430.806861 -298.232398)
			(xy 430.814301 -298.22496) (xy 430.81956 -298.224448) (xy 431.335688 -298.224448) (xy 431.343499 -298.224138)
			(xy 431.35837 -298.21935) (xy 431.364898 -298.21505) (xy 431.385987 -298.200701) (xy 431.431648 -298.17797)
			(xy 431.480254 -298.162511) (xy 431.530657 -298.154688) (xy 431.581663 -298.154688) (xy 431.632066 -298.162511)
			(xy 431.680672 -298.17797) (xy 431.726333 -298.200701) (xy 431.747422 -298.21505) (xy 431.753952 -298.219344)
			(xy 431.768823 -298.224126) (xy 431.776632 -298.224448) (xy 432.29276 -298.224448) (xy 432.298008 -298.225017)
			(xy 432.30545 -298.232412) (xy 432.305968 -298.237656) (xy 432.305968 -298.732194) (xy 438.350152 -298.732194)
			(xy 438.350152 -298.237656) (xy 438.350661 -298.232398) (xy 438.358101 -298.22496) (xy 438.36336 -298.224448)
			(xy 438.363868 -298.224448) (xy 438.879742 -298.224448) (xy 438.887551 -298.224118) (xy 438.902423 -298.219344)
			(xy 438.908952 -298.21505) (xy 438.930041 -298.200701) (xy 438.975702 -298.17797) (xy 439.024308 -298.162511)
			(xy 439.074711 -298.154688) (xy 439.125717 -298.154688) (xy 439.17612 -298.162511) (xy 439.224726 -298.17797)
			(xy 439.270387 -298.200701) (xy 439.291476 -298.21505) (xy 439.298017 -298.219326) (xy 439.31288 -298.224119)
			(xy 439.320686 -298.224448) (xy 439.836814 -298.224448) (xy 439.842122 -298.224915) (xy 439.849692 -298.232358)
			(xy 439.850276 -298.237656) (xy 439.850276 -298.732194) (xy 439.850251 -298.732448) (xy 445.89446 -298.732448)
			(xy 445.89446 -298.73194) (xy 445.89446 -298.237656) (xy 445.894962 -298.232396) (xy 445.902407 -298.224957)
			(xy 445.907668 -298.224448) (xy 446.423796 -298.224448) (xy 446.431607 -298.224141) (xy 446.446478 -298.219351)
			(xy 446.453006 -298.21505) (xy 446.474095 -298.200701) (xy 446.519756 -298.17797) (xy 446.568362 -298.162511)
			(xy 446.618765 -298.154688) (xy 446.669771 -298.154688) (xy 446.720174 -298.162511) (xy 446.76878 -298.17797)
			(xy 446.814441 -298.200701) (xy 446.83553 -298.21505) (xy 446.842059 -298.219347) (xy 446.856931 -298.224127)
			(xy 446.86474 -298.224448) (xy 447.380868 -298.224448) (xy 447.386117 -298.225011) (xy 447.393558 -298.232411)
			(xy 447.394076 -298.237656) (xy 447.394076 -298.732194) (xy 447.394052 -298.732448) (xy 453.43826 -298.732448)
			(xy 453.43826 -298.73194) (xy 453.43826 -298.237656) (xy 453.438762 -298.232396) (xy 453.446207 -298.224957)
			(xy 453.451468 -298.224448) (xy 453.967596 -298.224448) (xy 453.975407 -298.224141) (xy 453.990278 -298.219351)
			(xy 453.996806 -298.21505) (xy 454.017895 -298.200701) (xy 454.063556 -298.17797) (xy 454.112162 -298.162511)
			(xy 454.162565 -298.154688) (xy 454.213571 -298.154688) (xy 454.263974 -298.162511) (xy 454.31258 -298.17797)
			(xy 454.358241 -298.200701) (xy 454.37933 -298.21505) (xy 454.385859 -298.219347) (xy 454.400731 -298.224127)
			(xy 454.40854 -298.224448) (xy 454.924668 -298.224448) (xy 454.929917 -298.225011) (xy 454.937358 -298.232411)
			(xy 454.937876 -298.237656) (xy 454.937876 -298.732194) (xy 454.937375 -298.737494) (xy 454.929957 -298.745064)
			(xy 454.924668 -298.745656) (xy 454.408794 -298.745656) (xy 454.400983 -298.745958) (xy 454.386111 -298.750751)
			(xy 454.379584 -298.755054) (xy 454.358465 -298.769407) (xy 454.31274 -298.792132) (xy 454.264066 -298.807562)
			(xy 454.213599 -298.815327) (xy 454.188068 -298.81576) (xy 454.162537 -298.81534) (xy 454.112073 -298.807559)
			(xy 454.0634 -298.792125) (xy 454.017673 -298.769404) (xy 453.996552 -298.755054) (xy 453.990027 -298.750751)
			(xy 453.975152 -298.745974) (xy 453.967342 -298.745656) (xy 453.451468 -298.745656) (xy 453.446213 -298.745131)
			(xy 453.438775 -298.737702) (xy 453.43826 -298.732448) (xy 447.394052 -298.732448) (xy 447.393575 -298.737494)
			(xy 447.386157 -298.745064) (xy 447.380868 -298.745656) (xy 446.864994 -298.745656) (xy 446.857183 -298.745958)
			(xy 446.842311 -298.750751) (xy 446.835784 -298.755054) (xy 446.814665 -298.769407) (xy 446.76894 -298.792132)
			(xy 446.720266 -298.807562) (xy 446.669799 -298.815327) (xy 446.644268 -298.81576) (xy 446.618737 -298.81534)
			(xy 446.568273 -298.807559) (xy 446.5196 -298.792125) (xy 446.473873 -298.769404) (xy 446.452752 -298.755054)
			(xy 446.446227 -298.750751) (xy 446.431352 -298.745974) (xy 446.423542 -298.745656) (xy 445.907668 -298.745656)
			(xy 445.902413 -298.745131) (xy 445.894975 -298.737702) (xy 445.89446 -298.732448) (xy 439.850251 -298.732448)
			(xy 439.849747 -298.737554) (xy 439.842173 -298.745139) (xy 439.836814 -298.745656) (xy 439.32094 -298.745656)
			(xy 439.31313 -298.745977) (xy 439.298259 -298.750757) (xy 439.29173 -298.755054) (xy 439.270626 -298.76943)
			(xy 439.224896 -298.792151) (xy 439.176217 -298.807573) (xy 439.125746 -298.815331) (xy 439.100214 -298.81576)
			(xy 439.074684 -298.815317) (xy 439.02422 -298.807543) (xy 438.975548 -298.792116) (xy 438.92982 -298.769401)
			(xy 438.908698 -298.755054) (xy 438.902163 -298.750769) (xy 438.887296 -298.745981) (xy 438.879488 -298.745656)
			(xy 438.363614 -298.745656) (xy 438.35818 -298.745311) (xy 438.350493 -298.737628) (xy 438.350152 -298.732194)
			(xy 432.305968 -298.732194) (xy 432.305474 -298.737496) (xy 432.298051 -298.745067) (xy 432.29276 -298.745656)
			(xy 431.776886 -298.745656) (xy 431.769074 -298.745954) (xy 431.754203 -298.75075) (xy 431.747676 -298.755054)
			(xy 431.726559 -298.76941) (xy 431.680833 -298.792135) (xy 431.632159 -298.807563) (xy 431.581691 -298.815328)
			(xy 431.55616 -298.81576) (xy 431.530629 -298.815344) (xy 431.480164 -298.807562) (xy 431.431492 -298.792127)
			(xy 431.385765 -298.769404) (xy 431.364644 -298.755054) (xy 431.358121 -298.750748) (xy 431.343245 -298.745973)
			(xy 431.335434 -298.745656) (xy 430.81956 -298.745656) (xy 430.814304 -298.745137) (xy 430.806866 -298.737704)
			(xy 430.806352 -298.732448) (xy 424.762143 -298.732448) (xy 424.761646 -298.737556) (xy 424.754067 -298.745142)
			(xy 424.748706 -298.745656) (xy 424.232832 -298.745656) (xy 424.225022 -298.745974) (xy 424.21015 -298.750756)
			(xy 424.203622 -298.755054) (xy 424.182492 -298.76939) (xy 424.136771 -298.79212) (xy 424.0881 -298.807553)
			(xy 424.037636 -298.815324) (xy 424.012106 -298.81576) (xy 423.986576 -298.815321) (xy 423.936112 -298.807546)
			(xy 423.88744 -298.792118) (xy 423.841712 -298.769401) (xy 423.82059 -298.755054) (xy 423.814057 -298.750765)
			(xy 423.799188 -298.74598) (xy 423.79138 -298.745656) (xy 423.275506 -298.745656) (xy 423.270071 -298.745316)
			(xy 423.262384 -298.737629) (xy 423.262044 -298.732194) (xy 417.21786 -298.732194) (xy 417.217373 -298.737497)
			(xy 417.209945 -298.745069) (xy 417.204652 -298.745656) (xy 415.731452 -298.745656) (xy 415.726195 -298.745142)
			(xy 415.718758 -298.737705) (xy 415.718244 -298.732448) (xy 308.11824 -298.732448) (xy 308.117916 -298.737629)
			(xy 308.110229 -298.745316) (xy 308.104794 -298.745656) (xy 306.631594 -298.745656) (xy 306.626228 -298.745153)
			(xy 306.618642 -298.737561) (xy 306.618132 -298.732194) (xy 300.573948 -298.732194) (xy 300.573472 -298.7375)
			(xy 300.566037 -298.745072) (xy 300.56074 -298.745656) (xy 300.044866 -298.745656) (xy 300.037057 -298.745988)
			(xy 300.022186 -298.750761) (xy 300.015656 -298.755054) (xy 299.994544 -298.769419) (xy 299.948817 -298.792142)
			(xy 299.900141 -298.807568) (xy 299.849672 -298.815329) (xy 299.82414 -298.81576) (xy 299.79861 -298.815304)
			(xy 299.748147 -298.807534) (xy 299.699475 -298.792111) (xy 299.653747 -298.769399) (xy 299.632624 -298.755054)
			(xy 299.626083 -298.750778) (xy 299.61122 -298.745985) (xy 299.603414 -298.745656) (xy 299.08754 -298.745656)
			(xy 299.082293 -298.745084) (xy 299.074851 -298.737691) (xy 299.074332 -298.732448) (xy 293.030132 -298.732448)
			(xy 293.029815 -298.737631) (xy 293.022124 -298.745319) (xy 293.016686 -298.745656) (xy 292.500812 -298.745656)
			(xy 292.493001 -298.745966) (xy 292.47813 -298.750753) (xy 292.471602 -298.755054) (xy 292.450478 -298.769399)
			(xy 292.404755 -298.792126) (xy 292.356082 -298.807558) (xy 292.305617 -298.815326) (xy 292.280086 -298.81576)
			(xy 292.254555 -298.815331) (xy 292.204091 -298.807553) (xy 292.155419 -298.792122) (xy 292.109692 -298.769403)
			(xy 292.08857 -298.755054) (xy 292.082041 -298.750758) (xy 292.067169 -298.745977) (xy 292.05936 -298.745656)
			(xy 291.543486 -298.745656) (xy 291.538119 -298.745158) (xy 291.530534 -298.737562) (xy 291.530024 -298.732194)
			(xy 285.48584 -298.732194) (xy 285.485371 -298.737502) (xy 285.477931 -298.745075) (xy 285.472632 -298.745656)
			(xy 284.956758 -298.745656) (xy 284.948949 -298.745985) (xy 284.934077 -298.750759) (xy 284.927548 -298.755054)
			(xy 284.906439 -298.769422) (xy 284.86071 -298.792145) (xy 284.812033 -298.807569) (xy 284.761564 -298.81533)
			(xy 284.736032 -298.81576) (xy 284.710502 -298.815308) (xy 284.660039 -298.807537) (xy 284.611367 -298.792112)
			(xy 284.565638 -298.7694) (xy 284.544516 -298.755054) (xy 284.537977 -298.750775) (xy 284.523113 -298.745984)
			(xy 284.515306 -298.745656) (xy 283.999432 -298.745656) (xy 283.994184 -298.745089) (xy 283.986743 -298.737692)
			(xy 283.986224 -298.732448) (xy 277.942018 -298.732448) (xy 277.941571 -298.737502) (xy 277.934131 -298.745075)
			(xy 277.928832 -298.745656) (xy 277.412958 -298.745656) (xy 277.405149 -298.745985) (xy 277.390277 -298.750759)
			(xy 277.383748 -298.755054) (xy 277.362639 -298.769422) (xy 277.31691 -298.792145) (xy 277.268233 -298.807569)
			(xy 277.217764 -298.81533) (xy 277.192232 -298.81576) (xy 277.166702 -298.815308) (xy 277.116239 -298.807537)
			(xy 277.067567 -298.792112) (xy 277.021838 -298.7694) (xy 277.000716 -298.755054) (xy 276.994177 -298.750775)
			(xy 276.979313 -298.745984) (xy 276.971506 -298.745656) (xy 276.455632 -298.745656) (xy 276.450384 -298.745089)
			(xy 276.442943 -298.737692) (xy 276.442424 -298.732448) (xy 270.398225 -298.732448) (xy 270.397915 -298.737633)
			(xy 270.390218 -298.745321) (xy 270.384778 -298.745656) (xy 269.868904 -298.745656) (xy 269.861093 -298.745962)
			(xy 269.846221 -298.750752) (xy 269.839694 -298.755054) (xy 269.818572 -298.769402) (xy 269.772848 -298.792129)
			(xy 269.724175 -298.807559) (xy 269.673709 -298.815327) (xy 269.648178 -298.81576) (xy 269.622647 -298.815335)
			(xy 269.572183 -298.807556) (xy 269.523511 -298.792123) (xy 269.477783 -298.769403) (xy 269.456662 -298.755054)
			(xy 269.450135 -298.750755) (xy 269.435262 -298.745976) (xy 269.427452 -298.745656) (xy 268.911578 -298.745656)
			(xy 268.90621 -298.745164) (xy 268.898625 -298.737563) (xy 268.898116 -298.732194) (xy 206.997808 -298.732194)
			(xy 206.997808 -298.732448) (xy 206.997337 -298.737717) (xy 206.98987 -298.745156) (xy 206.9846 -298.745656)
			(xy 206.468726 -298.745656) (xy 206.460849 -298.745918) (xy 206.445845 -298.750719) (xy 206.439262 -298.755054)
			(xy 206.418186 -298.769448) (xy 206.372541 -298.792275) (xy 206.323934 -298.807833) (xy 206.273517 -298.815751)
			(xy 206.248 -298.816268) (xy 206.222479 -298.815801) (xy 206.172051 -298.807901) (xy 206.123439 -298.792334)
			(xy 206.077802 -298.769473) (xy 206.056738 -298.755054) (xy 206.050137 -298.750756) (xy 206.035144 -298.745958)
			(xy 206.027274 -298.745656) (xy 205.5114 -298.745656) (xy 205.506149 -298.74511) (xy 205.498709 -298.737697)
			(xy 205.498192 -298.732448) (xy 199.454008 -298.732448) (xy 199.453537 -298.737717) (xy 199.44607 -298.745156)
			(xy 199.4408 -298.745656) (xy 198.924926 -298.745656) (xy 198.917049 -298.745918) (xy 198.902045 -298.750719)
			(xy 198.895462 -298.755054) (xy 198.874386 -298.769448) (xy 198.828741 -298.792275) (xy 198.780134 -298.807833)
			(xy 198.729717 -298.815751) (xy 198.7042 -298.816268) (xy 198.678679 -298.815801) (xy 198.628251 -298.807901)
			(xy 198.579639 -298.792334) (xy 198.534002 -298.769473) (xy 198.512938 -298.755054) (xy 198.506337 -298.750756)
			(xy 198.491344 -298.745958) (xy 198.483474 -298.745656) (xy 197.9676 -298.745656) (xy 197.962349 -298.74511)
			(xy 197.954909 -298.737697) (xy 197.954392 -298.732448) (xy 191.910208 -298.732448) (xy 191.909737 -298.737717)
			(xy 191.90227 -298.745156) (xy 191.897 -298.745656) (xy 191.896492 -298.745656) (xy 191.380872 -298.745656)
			(xy 191.372997 -298.745938) (xy 191.357993 -298.750726) (xy 191.351408 -298.755054) (xy 191.330347 -298.769471)
			(xy 191.284696 -298.792293) (xy 191.236085 -298.807844) (xy 191.185664 -298.815755) (xy 191.160146 -298.816268)
			(xy 191.134626 -298.815778) (xy 191.084199 -298.807885) (xy 191.035587 -298.792325) (xy 190.989949 -298.76947)
			(xy 190.968884 -298.755054) (xy 190.962295 -298.750735) (xy 190.947293 -298.74595) (xy 190.93942 -298.745656)
			(xy 190.423546 -298.745656) (xy 190.418246 -298.745146) (xy 190.410672 -298.737736) (xy 190.410084 -298.732448)
			(xy 184.3659 -298.732448) (xy 184.365436 -298.737718) (xy 184.357964 -298.745159) (xy 184.352692 -298.745656)
			(xy 183.836818 -298.745656) (xy 183.828945 -298.745958) (xy 183.813941 -298.750732) (xy 183.807354 -298.755054)
			(xy 183.78628 -298.769451) (xy 183.740634 -298.792278) (xy 183.692027 -298.807834) (xy 183.641609 -298.815752)
			(xy 183.616092 -298.816268) (xy 183.590573 -298.815755) (xy 183.540146 -298.807869) (xy 183.491535 -298.792316)
			(xy 183.445895 -298.769467) (xy 183.42483 -298.755054) (xy 183.41823 -298.750753) (xy 183.403237 -298.745957)
			(xy 183.395366 -298.745656) (xy 182.879492 -298.745656) (xy 182.87424 -298.745116) (xy 182.8668 -298.737699)
			(xy 182.866284 -298.732448) (xy 176.8221 -298.732448) (xy 176.821636 -298.737718) (xy 176.814164 -298.745159)
			(xy 176.808892 -298.745656) (xy 176.808384 -298.745656) (xy 176.292764 -298.745656) (xy 176.284889 -298.745935)
			(xy 176.269885 -298.750725) (xy 176.2633 -298.755054) (xy 176.242213 -298.769431) (xy 176.196572 -298.792263)
			(xy 176.147969 -298.807824) (xy 176.097554 -298.815748) (xy 176.072038 -298.816268) (xy 176.046518 -298.815782)
			(xy 175.99609 -298.807887) (xy 175.947479 -298.792326) (xy 175.90184 -298.76947) (xy 175.880776 -298.755054)
			(xy 175.874188 -298.750732) (xy 175.859185 -298.745949) (xy 175.851312 -298.745656) (xy 175.335438 -298.745656)
			(xy 175.330137 -298.745151) (xy 175.322564 -298.737737) (xy 175.321976 -298.732448) (xy 169.277792 -298.732448)
			(xy 169.277335 -298.73772) (xy 169.269859 -298.745161) (xy 169.264584 -298.745656) (xy 167.791384 -298.745656)
			(xy 167.786131 -298.745121) (xy 167.778692 -298.7377) (xy 167.778176 -298.732448) (xy 60.178188 -298.732448)
			(xy 60.177735 -298.737721) (xy 60.170256 -298.745162) (xy 60.16498 -298.745656) (xy 60.164472 -298.745656)
			(xy 58.691526 -298.745656) (xy 58.686224 -298.745159) (xy 58.678651 -298.737739) (xy 58.678064 -298.732448)
			(xy 52.63388 -298.732448) (xy 52.633434 -298.737723) (xy 52.62595 -298.745165) (xy 52.620672 -298.745656)
			(xy 52.104798 -298.745656) (xy 52.096924 -298.745949) (xy 52.08192 -298.750729) (xy 52.075334 -298.755054)
			(xy 52.054266 -298.76946) (xy 52.008618 -298.792285) (xy 51.960009 -298.807839) (xy 51.909589 -298.815753)
			(xy 51.884072 -298.816268) (xy 51.858552 -298.815765) (xy 51.808126 -298.807876) (xy 51.759514 -298.79232)
			(xy 51.713875 -298.769468) (xy 51.69281 -298.755054) (xy 51.686215 -298.750745) (xy 51.671218 -298.745954)
			(xy 51.663346 -298.745656) (xy 51.147472 -298.745656) (xy 51.142217 -298.745129) (xy 51.134779 -298.737702)
			(xy 51.134264 -298.732448) (xy 45.09008 -298.732448) (xy 45.089634 -298.737723) (xy 45.08215 -298.745165)
			(xy 45.076872 -298.745656) (xy 45.076364 -298.745656) (xy 44.560744 -298.745656) (xy 44.552868 -298.745926)
			(xy 44.537864 -298.750722) (xy 44.53128 -298.755054) (xy 44.510199 -298.76944) (xy 44.464555 -298.792269)
			(xy 44.41595 -298.807829) (xy 44.365534 -298.81575) (xy 44.340018 -298.816268) (xy 44.314497 -298.815792)
			(xy 44.264069 -298.807894) (xy 44.215458 -298.792331) (xy 44.16982 -298.769471) (xy 44.148756 -298.755054)
			(xy 44.142173 -298.750724) (xy 44.127166 -298.745946) (xy 44.119292 -298.745656) (xy 43.603418 -298.745656)
			(xy 43.598115 -298.745164) (xy 43.590543 -298.73774) (xy 43.589956 -298.732448) (xy 37.545772 -298.732448)
			(xy 37.545333 -298.737725) (xy 37.537844 -298.745167) (xy 37.532564 -298.745656) (xy 37.01669 -298.745656)
			(xy 37.008816 -298.745946) (xy 36.993812 -298.750728) (xy 36.987226 -298.755054) (xy 36.96616 -298.769463)
			(xy 36.920511 -298.792287) (xy 36.871901 -298.80784) (xy 36.821482 -298.815754) (xy 36.795964 -298.816268)
			(xy 36.770444 -298.815769) (xy 36.720017 -298.807878) (xy 36.671406 -298.792321) (xy 36.625767 -298.769468)
			(xy 36.604702 -298.755054) (xy 36.598109 -298.750742) (xy 36.58311 -298.745952) (xy 36.575238 -298.745656)
			(xy 36.059364 -298.745656) (xy 36.054109 -298.745134) (xy 36.046671 -298.737703) (xy 36.046156 -298.732448)
			(xy 30.001972 -298.732448) (xy 30.001533 -298.737725) (xy 29.994044 -298.745167) (xy 29.988764 -298.745656)
			(xy 29.47289 -298.745656) (xy 29.465016 -298.745946) (xy 29.450012 -298.750728) (xy 29.443426 -298.755054)
			(xy 29.42236 -298.769463) (xy 29.376711 -298.792287) (xy 29.328101 -298.80784) (xy 29.277682 -298.815754)
			(xy 29.252164 -298.816268) (xy 29.226644 -298.815769) (xy 29.176217 -298.807878) (xy 29.127606 -298.792321)
			(xy 29.081967 -298.769468) (xy 29.060902 -298.755054) (xy 29.054309 -298.750742) (xy 29.03931 -298.745952)
			(xy 29.031438 -298.745656) (xy 28.515564 -298.745656) (xy 28.510309 -298.745134) (xy 28.502871 -298.737703)
			(xy 28.502356 -298.732448) (xy 22.458172 -298.732448) (xy 22.457733 -298.737725) (xy 22.450244 -298.745167)
			(xy 22.444964 -298.745656) (xy 22.444456 -298.745656) (xy 21.928836 -298.745656) (xy 21.92096 -298.745923)
			(xy 21.905956 -298.75072) (xy 21.899372 -298.755054) (xy 21.878293 -298.769443) (xy 21.832649 -298.792272)
			(xy 21.784043 -298.80783) (xy 21.733627 -298.81575) (xy 21.70811 -298.816268) (xy 21.682589 -298.815796)
			(xy 21.632161 -298.807897) (xy 21.583549 -298.792332) (xy 21.537912 -298.769472) (xy 21.516848 -298.755054)
			(xy 21.510267 -298.750721) (xy 21.495259 -298.745945) (xy 21.487384 -298.745656) (xy 20.97151 -298.745656)
			(xy 20.966206 -298.74517) (xy 20.958634 -298.737742) (xy 20.958048 -298.732448) (xy 2.509012 -298.732448)
			(xy 2.509012 -299.582586) (xy 16.85798 -299.582586) (xy 16.85798 -299.088048) (xy 16.858358 -299.082725)
			(xy 16.865867 -299.075182) (xy 16.871188 -299.07484) (xy 16.871696 -299.07484) (xy 17.38757 -299.07484)
			(xy 17.39538 -299.074524) (xy 17.410252 -299.06974) (xy 17.41678 -299.065442) (xy 17.437869 -299.051093)
			(xy 17.48353 -299.028362) (xy 17.532136 -299.012903) (xy 17.582539 -299.00508) (xy 17.633545 -299.00508)
			(xy 17.683948 -299.012903) (xy 17.732554 -299.028362) (xy 17.778215 -299.051093) (xy 17.799304 -299.065442)
			(xy 17.805839 -299.069728) (xy 17.820706 -299.074515) (xy 17.828514 -299.07484) (xy 18.344642 -299.07484)
			(xy 18.349951 -299.075295) (xy 18.35752 -299.082747) (xy 18.358104 -299.088048) (xy 18.358104 -299.582586)
			(xy 18.358077 -299.58284) (xy 24.402288 -299.58284) (xy 24.402288 -299.582332) (xy 24.402288 -299.088048)
			(xy 24.402659 -299.082723) (xy 24.410173 -299.07518) (xy 24.415496 -299.07484) (xy 24.931624 -299.07484)
			(xy 24.939436 -299.074547) (xy 24.954308 -299.069748) (xy 24.960834 -299.065442) (xy 24.981923 -299.051093)
			(xy 25.027584 -299.028362) (xy 25.07619 -299.012903) (xy 25.126593 -299.00508) (xy 25.177599 -299.00508)
			(xy 25.228002 -299.012903) (xy 25.276608 -299.028362) (xy 25.322269 -299.051093) (xy 25.343358 -299.065442)
			(xy 25.349881 -299.069749) (xy 25.364757 -299.074523) (xy 25.372568 -299.07484) (xy 25.888696 -299.07484)
			(xy 25.894039 -299.075134) (xy 25.901583 -299.082704) (xy 25.901904 -299.088048) (xy 25.901904 -299.582586)
			(xy 25.901879 -299.58284) (xy 31.946088 -299.58284) (xy 31.946088 -299.582332) (xy 31.946088 -299.088048)
			(xy 31.946459 -299.082723) (xy 31.953973 -299.07518) (xy 31.959296 -299.07484) (xy 32.475424 -299.07484)
			(xy 32.483236 -299.074547) (xy 32.498108 -299.069748) (xy 32.504634 -299.065442) (xy 32.525723 -299.051093)
			(xy 32.571384 -299.028362) (xy 32.61999 -299.012903) (xy 32.670393 -299.00508) (xy 32.721399 -299.00508)
			(xy 32.771802 -299.012903) (xy 32.820408 -299.028362) (xy 32.866069 -299.051093) (xy 32.887158 -299.065442)
			(xy 32.893681 -299.069749) (xy 32.908557 -299.074523) (xy 32.916368 -299.07484) (xy 33.432496 -299.07484)
			(xy 33.437839 -299.075134) (xy 33.445383 -299.082704) (xy 33.445704 -299.088048) (xy 33.445704 -299.582586)
			(xy 39.489888 -299.582586) (xy 39.489888 -299.088048) (xy 39.490259 -299.082723) (xy 39.497773 -299.07518)
			(xy 39.503096 -299.07484) (xy 39.503604 -299.07484) (xy 40.019478 -299.07484) (xy 40.027288 -299.074527)
			(xy 40.04216 -299.069742) (xy 40.048688 -299.065442) (xy 40.069777 -299.051093) (xy 40.115438 -299.028362)
			(xy 40.164044 -299.012903) (xy 40.214447 -299.00508) (xy 40.265453 -299.00508) (xy 40.315856 -299.012903)
			(xy 40.364462 -299.028362) (xy 40.410123 -299.051093) (xy 40.431212 -299.065442) (xy 40.437745 -299.069731)
			(xy 40.452614 -299.074516) (xy 40.460422 -299.07484) (xy 40.97655 -299.07484) (xy 40.981848 -299.075357)
			(xy 40.989422 -299.082762) (xy 40.990012 -299.088048) (xy 40.990012 -299.582586) (xy 40.989985 -299.58284)
			(xy 47.034196 -299.58284) (xy 47.034196 -299.582332) (xy 47.034196 -299.088048) (xy 47.03456 -299.082721)
			(xy 47.042078 -299.075177) (xy 47.047404 -299.07484) (xy 47.563532 -299.07484) (xy 47.571341 -299.074507)
			(xy 47.586212 -299.069736) (xy 47.592742 -299.065442) (xy 47.613831 -299.051093) (xy 47.659492 -299.028362)
			(xy 47.708098 -299.012903) (xy 47.758501 -299.00508) (xy 47.809507 -299.00508) (xy 47.85991 -299.012903)
			(xy 47.908516 -299.028362) (xy 47.954177 -299.051093) (xy 47.975266 -299.065442) (xy 47.981809 -299.069713)
			(xy 47.99667 -299.07451) (xy 48.004476 -299.07484) (xy 48.520604 -299.07484) (xy 48.525949 -299.075129)
			(xy 48.533492 -299.082702) (xy 48.533812 -299.088048) (xy 48.533812 -299.582586) (xy 54.577996 -299.582586)
			(xy 54.577996 -299.088048) (xy 54.57836 -299.082721) (xy 54.585878 -299.075177) (xy 54.591204 -299.07484)
			(xy 56.064658 -299.07484) (xy 56.069957 -299.075351) (xy 56.077531 -299.082761) (xy 56.07812 -299.088048)
			(xy 56.07812 -299.582586) (xy 56.078105 -299.58284) (xy 163.678108 -299.58284) (xy 163.678108 -299.582332)
			(xy 163.678108 -299.088048) (xy 163.678461 -299.082718) (xy 163.685987 -299.075174) (xy 163.691316 -299.07484)
			(xy 165.164516 -299.07484) (xy 165.169862 -299.075121) (xy 165.177405 -299.0827) (xy 165.177724 -299.088048)
			(xy 165.177724 -299.582586) (xy 171.221908 -299.582586) (xy 171.221908 -299.088048) (xy 171.222261 -299.082718)
			(xy 171.229787 -299.075174) (xy 171.235116 -299.07484) (xy 171.235624 -299.07484) (xy 171.751498 -299.07484)
			(xy 171.759309 -299.074535) (xy 171.774181 -299.069744) (xy 171.780708 -299.065442) (xy 171.801797 -299.051093)
			(xy 171.847458 -299.028362) (xy 171.896064 -299.012903) (xy 171.946467 -299.00508) (xy 171.997473 -299.00508)
			(xy 172.047876 -299.012903) (xy 172.096482 -299.028362) (xy 172.142143 -299.051093) (xy 172.163232 -299.065442)
			(xy 172.169761 -299.069739) (xy 172.184633 -299.074519) (xy 172.192442 -299.07484) (xy 172.70857 -299.07484)
			(xy 172.713871 -299.075343) (xy 172.721443 -299.082759) (xy 172.722032 -299.088048) (xy 172.722032 -299.582586)
			(xy 172.722017 -299.58284) (xy 178.766216 -299.58284) (xy 178.766216 -299.582332) (xy 178.766216 -299.088048)
			(xy 178.766562 -299.082716) (xy 178.774093 -299.075171) (xy 178.779424 -299.07484) (xy 179.295552 -299.07484)
			(xy 179.303361 -299.074516) (xy 179.318233 -299.069738) (xy 179.324762 -299.065442) (xy 179.345851 -299.051093)
			(xy 179.391512 -299.028362) (xy 179.440118 -299.012903) (xy 179.490521 -299.00508) (xy 179.541527 -299.00508)
			(xy 179.59193 -299.012903) (xy 179.640536 -299.028362) (xy 179.686197 -299.051093) (xy 179.707286 -299.065442)
			(xy 179.713825 -299.069721) (xy 179.728689 -299.074513) (xy 179.736496 -299.07484) (xy 180.252624 -299.07484)
			(xy 180.257971 -299.075116) (xy 180.265513 -299.082699) (xy 180.265832 -299.088048) (xy 180.265832 -299.582586)
			(xy 186.310016 -299.582586) (xy 186.310016 -299.088048) (xy 186.310362 -299.082716) (xy 186.317893 -299.075171)
			(xy 186.323224 -299.07484) (xy 186.323732 -299.07484) (xy 186.839606 -299.07484) (xy 186.847417 -299.074539)
			(xy 186.862289 -299.069745) (xy 186.868816 -299.065442) (xy 186.889905 -299.051093) (xy 186.935566 -299.028362)
			(xy 186.984172 -299.012903) (xy 187.034575 -299.00508) (xy 187.085581 -299.00508) (xy 187.135984 -299.012903)
			(xy 187.18459 -299.028362) (xy 187.230251 -299.051093) (xy 187.25134 -299.065442) (xy 187.257867 -299.069742)
			(xy 187.27274 -299.074521) (xy 187.28055 -299.07484) (xy 187.796678 -299.07484) (xy 187.80198 -299.075338)
			(xy 187.809552 -299.082757) (xy 187.81014 -299.088048) (xy 187.81014 -299.582586) (xy 187.810125 -299.58284)
			(xy 193.854324 -299.58284) (xy 193.854324 -299.582332) (xy 193.854324 -299.088048) (xy 193.854662 -299.082714)
			(xy 193.862199 -299.075169) (xy 193.867532 -299.07484) (xy 194.38366 -299.07484) (xy 194.39147 -299.074519)
			(xy 194.406341 -299.069739) (xy 194.41287 -299.065442) (xy 194.433959 -299.051093) (xy 194.47962 -299.028362)
			(xy 194.528226 -299.012903) (xy 194.578629 -299.00508) (xy 194.629635 -299.00508) (xy 194.680038 -299.012903)
			(xy 194.728644 -299.028362) (xy 194.774305 -299.051093) (xy 194.795394 -299.065442) (xy 194.801931 -299.069724)
			(xy 194.816797 -299.074514) (xy 194.824604 -299.07484) (xy 195.340732 -299.07484) (xy 195.34608 -299.07511)
			(xy 195.353622 -299.082698) (xy 195.35394 -299.088048) (xy 195.35394 -299.582586) (xy 195.353917 -299.58284)
			(xy 201.398124 -299.58284) (xy 201.398124 -299.582332) (xy 201.398124 -299.088048) (xy 201.398462 -299.082714)
			(xy 201.405999 -299.075169) (xy 201.411332 -299.07484) (xy 201.92746 -299.07484) (xy 201.93527 -299.074519)
			(xy 201.950141 -299.069739) (xy 201.95667 -299.065442) (xy 201.977759 -299.051093) (xy 202.02342 -299.028362)
			(xy 202.072026 -299.012903) (xy 202.122429 -299.00508) (xy 202.173435 -299.00508) (xy 202.223838 -299.012903)
			(xy 202.272444 -299.028362) (xy 202.318105 -299.051093) (xy 202.339194 -299.065442) (xy 202.345731 -299.069724)
			(xy 202.360597 -299.074514) (xy 202.368404 -299.07484) (xy 202.884532 -299.07484) (xy 202.88988 -299.07511)
			(xy 202.897422 -299.082698) (xy 202.89774 -299.088048) (xy 202.89774 -299.582332) (xy 264.798048 -299.582332)
			(xy 264.798048 -299.087794) (xy 264.798376 -299.082356) (xy 264.806072 -299.07467) (xy 264.81151 -299.074332)
			(xy 265.327638 -299.074332) (xy 265.335447 -299.074003) (xy 265.350319 -299.069229) (xy 265.356848 -299.064934)
			(xy 265.377937 -299.050585) (xy 265.423598 -299.027854) (xy 265.472204 -299.012395) (xy 265.522607 -299.004572)
			(xy 265.573613 -299.004572) (xy 265.624016 -299.012395) (xy 265.672622 -299.027854) (xy 265.718283 -299.050585)
			(xy 265.739372 -299.064934) (xy 265.745914 -299.069207) (xy 265.760776 -299.074002) (xy 265.768582 -299.074332)
			(xy 266.28471 -299.074332) (xy 266.290074 -299.074843) (xy 266.297658 -299.08243) (xy 266.298172 -299.087794)
			(xy 266.298172 -299.582332) (xy 272.342356 -299.582332) (xy 272.342356 -299.087794) (xy 272.342821 -299.082485)
			(xy 272.350264 -299.074914) (xy 272.355564 -299.074332) (xy 272.871692 -299.074332) (xy 272.879503 -299.074026)
			(xy 272.894375 -299.069236) (xy 272.900902 -299.064934) (xy 272.921991 -299.050585) (xy 272.967652 -299.027854)
			(xy 273.016258 -299.012395) (xy 273.066661 -299.004572) (xy 273.117667 -299.004572) (xy 273.16807 -299.012395)
			(xy 273.216676 -299.027854) (xy 273.262337 -299.050585) (xy 273.283426 -299.064934) (xy 273.289956 -299.069228)
			(xy 273.304827 -299.07401) (xy 273.312636 -299.074332) (xy 273.828764 -299.074332) (xy 273.834101 -299.074655)
			(xy 273.841647 -299.082203) (xy 273.841972 -299.08754) (xy 273.841972 -299.088048) (xy 273.841972 -299.582332)
			(xy 279.886156 -299.582332) (xy 279.886156 -299.087794) (xy 279.886621 -299.082485) (xy 279.894064 -299.074914)
			(xy 279.899364 -299.074332) (xy 280.415492 -299.074332) (xy 280.423303 -299.074026) (xy 280.438175 -299.069236)
			(xy 280.444702 -299.064934) (xy 280.465791 -299.050585) (xy 280.511452 -299.027854) (xy 280.560058 -299.012395)
			(xy 280.610461 -299.004572) (xy 280.661467 -299.004572) (xy 280.71187 -299.012395) (xy 280.760476 -299.027854)
			(xy 280.806137 -299.050585) (xy 280.827226 -299.064934) (xy 280.833756 -299.069228) (xy 280.848627 -299.07401)
			(xy 280.856436 -299.074332) (xy 281.372564 -299.074332) (xy 281.377901 -299.074655) (xy 281.385447 -299.082203)
			(xy 281.385772 -299.08754) (xy 281.385772 -299.088048) (xy 281.385772 -299.582332) (xy 287.429956 -299.582332)
			(xy 287.429956 -299.087794) (xy 287.430277 -299.082354) (xy 287.437977 -299.074667) (xy 287.443418 -299.074332)
			(xy 287.959546 -299.074332) (xy 287.967355 -299.074007) (xy 287.982227 -299.06923) (xy 287.988756 -299.064934)
			(xy 288.009845 -299.050585) (xy 288.055506 -299.027854) (xy 288.104112 -299.012395) (xy 288.154515 -299.004572)
			(xy 288.205521 -299.004572) (xy 288.255924 -299.012395) (xy 288.30453 -299.027854) (xy 288.350191 -299.050585)
			(xy 288.37128 -299.064934) (xy 288.377821 -299.06921) (xy 288.392683 -299.074004) (xy 288.40049 -299.074332)
			(xy 288.916618 -299.074332) (xy 288.921983 -299.074838) (xy 288.929567 -299.082429) (xy 288.93008 -299.087794)
			(xy 288.93008 -299.582332) (xy 294.974264 -299.582332) (xy 294.974264 -299.087794) (xy 294.974722 -299.082483)
			(xy 294.98217 -299.074911) (xy 294.987472 -299.074332) (xy 295.5036 -299.074332) (xy 295.511411 -299.07403)
			(xy 295.526283 -299.069237) (xy 295.53281 -299.064934) (xy 295.553899 -299.050585) (xy 295.59956 -299.027854)
			(xy 295.648166 -299.012395) (xy 295.698569 -299.004572) (xy 295.749575 -299.004572) (xy 295.799978 -299.012395)
			(xy 295.848584 -299.027854) (xy 295.894245 -299.050585) (xy 295.915334 -299.064934) (xy 295.921863 -299.069231)
			(xy 295.936735 -299.074012) (xy 295.944544 -299.074332) (xy 296.460672 -299.074332) (xy 296.46601 -299.074649)
			(xy 296.473555 -299.082201) (xy 296.47388 -299.08754) (xy 296.47388 -299.088048) (xy 296.47388 -299.582332)
			(xy 302.518064 -299.582332) (xy 302.518064 -299.087794) (xy 302.518378 -299.082352) (xy 302.526083 -299.074665)
			(xy 302.531526 -299.074332) (xy 304.004726 -299.074332) (xy 304.010092 -299.074833) (xy 304.017675 -299.082428)
			(xy 304.018188 -299.087794) (xy 304.018188 -299.582332) (xy 304.017725 -299.587603) (xy 304.010253 -299.595045)
			(xy 304.00498 -299.59554) (xy 302.531526 -299.59554) (xy 302.52622 -299.595057) (xy 302.518647 -299.587627)
			(xy 302.518064 -299.582332) (xy 296.47388 -299.582332) (xy 296.473424 -299.587605) (xy 296.465948 -299.595048)
			(xy 296.460672 -299.59554) (xy 295.944798 -299.59554) (xy 295.936924 -299.595836) (xy 295.92192 -299.600614)
			(xy 295.915334 -299.604938) (xy 295.894265 -299.619342) (xy 295.848617 -299.642168) (xy 295.800008 -299.657722)
			(xy 295.749589 -299.665637) (xy 295.724072 -299.666152) (xy 295.698553 -299.665634) (xy 295.648128 -299.657746)
			(xy 295.599516 -299.642194) (xy 295.553876 -299.619349) (xy 295.53281 -299.604938) (xy 295.526216 -299.600628)
			(xy 295.511218 -299.595837) (xy 295.503346 -299.59554) (xy 294.987472 -299.59554) (xy 294.982214 -299.595027)
			(xy 294.974774 -299.58759) (xy 294.974264 -299.582332) (xy 288.93008 -299.582332) (xy 288.929624 -299.587605)
			(xy 288.922148 -299.595048) (xy 288.916872 -299.59554) (xy 288.916364 -299.59554) (xy 288.400744 -299.59554)
			(xy 288.392868 -299.595813) (xy 288.377864 -299.600607) (xy 288.37128 -299.604938) (xy 288.350198 -299.619322)
			(xy 288.304555 -299.642152) (xy 288.25595 -299.657712) (xy 288.205534 -299.665634) (xy 288.180018 -299.666152)
			(xy 288.154498 -299.665661) (xy 288.104072 -299.657765) (xy 288.05546 -299.642205) (xy 288.009821 -299.619352)
			(xy 287.988756 -299.604938) (xy 287.982174 -299.600607) (xy 287.967167 -299.59583) (xy 287.959292 -299.59554)
			(xy 287.443418 -299.59554) (xy 287.438111 -299.595063) (xy 287.430538 -299.587629) (xy 287.429956 -299.582332)
			(xy 281.385772 -299.582332) (xy 281.385491 -299.587677) (xy 281.377911 -299.595218) (xy 281.372564 -299.59554)
			(xy 280.85669 -299.59554) (xy 280.848816 -299.595833) (xy 280.833812 -299.600613) (xy 280.827226 -299.604938)
			(xy 280.806159 -299.619345) (xy 280.76051 -299.64217) (xy 280.711901 -299.657724) (xy 280.661482 -299.665638)
			(xy 280.635964 -299.666152) (xy 280.610445 -299.665638) (xy 280.560019 -299.657749) (xy 280.511408 -299.642196)
			(xy 280.465768 -299.619349) (xy 280.444702 -299.604938) (xy 280.438109 -299.600625) (xy 280.42311 -299.595836)
			(xy 280.415238 -299.59554) (xy 279.899364 -299.59554) (xy 279.894105 -299.595032) (xy 279.886666 -299.587591)
			(xy 279.886156 -299.582332) (xy 273.841972 -299.582332) (xy 273.841691 -299.587677) (xy 273.834111 -299.595218)
			(xy 273.828764 -299.59554) (xy 273.31289 -299.59554) (xy 273.305016 -299.595833) (xy 273.290012 -299.600613)
			(xy 273.283426 -299.604938) (xy 273.262359 -299.619345) (xy 273.21671 -299.64217) (xy 273.168101 -299.657724)
			(xy 273.117682 -299.665638) (xy 273.092164 -299.666152) (xy 273.066645 -299.665638) (xy 273.016219 -299.657749)
			(xy 272.967608 -299.642196) (xy 272.921968 -299.619349) (xy 272.900902 -299.604938) (xy 272.894309 -299.600625)
			(xy 272.87931 -299.595836) (xy 272.871438 -299.59554) (xy 272.355564 -299.59554) (xy 272.350305 -299.595032)
			(xy 272.342866 -299.587591) (xy 272.342356 -299.582332) (xy 266.298172 -299.582332) (xy 266.297891 -299.587677)
			(xy 266.290311 -299.595218) (xy 266.284964 -299.59554) (xy 266.284456 -299.59554) (xy 265.768836 -299.59554)
			(xy 265.76096 -299.595809) (xy 265.745956 -299.600606) (xy 265.739372 -299.604938) (xy 265.718292 -299.619325)
			(xy 265.672648 -299.642155) (xy 265.624043 -299.657714) (xy 265.573626 -299.665634) (xy 265.54811 -299.666152)
			(xy 265.52259 -299.665665) (xy 265.472163 -299.657768) (xy 265.423552 -299.642207) (xy 265.377913 -299.619353)
			(xy 265.356848 -299.604938) (xy 265.350268 -299.600604) (xy 265.335259 -299.595828) (xy 265.327384 -299.59554)
			(xy 264.81151 -299.59554) (xy 264.806202 -299.595068) (xy 264.798629 -299.58763) (xy 264.798048 -299.582332)
			(xy 202.89774 -299.582332) (xy 202.89774 -299.582586) (xy 202.897265 -299.587893) (xy 202.889829 -299.595466)
			(xy 202.884532 -299.596048) (xy 202.368658 -299.596048) (xy 202.360849 -299.596378) (xy 202.345977 -299.601152)
			(xy 202.339448 -299.605446) (xy 202.318338 -299.619813) (xy 202.27261 -299.642536) (xy 202.223933 -299.657961)
			(xy 202.173464 -299.665722) (xy 202.147932 -299.666152) (xy 202.122402 -299.665702) (xy 202.071939 -299.65793)
			(xy 202.023266 -299.642505) (xy 201.977538 -299.619792) (xy 201.956416 -299.605446) (xy 201.949877 -299.601167)
			(xy 201.935013 -299.596376) (xy 201.927206 -299.596048) (xy 201.411332 -299.596048) (xy 201.406083 -299.595488)
			(xy 201.39864 -299.588087) (xy 201.398124 -299.58284) (xy 195.353917 -299.58284) (xy 195.353465 -299.587893)
			(xy 195.346029 -299.595466) (xy 195.340732 -299.596048) (xy 194.824858 -299.596048) (xy 194.817049 -299.596378)
			(xy 194.802177 -299.601152) (xy 194.795648 -299.605446) (xy 194.774538 -299.619813) (xy 194.72881 -299.642536)
			(xy 194.680133 -299.657961) (xy 194.629664 -299.665722) (xy 194.604132 -299.666152) (xy 194.578602 -299.665702)
			(xy 194.528139 -299.65793) (xy 194.479466 -299.642505) (xy 194.433738 -299.619792) (xy 194.412616 -299.605446)
			(xy 194.406077 -299.601167) (xy 194.391213 -299.596376) (xy 194.383406 -299.596048) (xy 193.867532 -299.596048)
			(xy 193.862283 -299.595488) (xy 193.85484 -299.588087) (xy 193.854324 -299.58284) (xy 187.810125 -299.58284)
			(xy 187.809809 -299.588024) (xy 187.802116 -299.595712) (xy 187.796678 -299.596048) (xy 187.280804 -299.596048)
			(xy 187.272993 -299.596356) (xy 187.258122 -299.601145) (xy 187.251594 -299.605446) (xy 187.230471 -299.619793)
			(xy 187.184748 -299.642521) (xy 187.136075 -299.657951) (xy 187.085609 -299.665719) (xy 187.060078 -299.666152)
			(xy 187.034547 -299.665729) (xy 186.984083 -299.657949) (xy 186.93541 -299.642516) (xy 186.889683 -299.619796)
			(xy 186.868562 -299.605446) (xy 186.862035 -299.601146) (xy 186.847162 -299.596368) (xy 186.839352 -299.596048)
			(xy 186.323478 -299.596048) (xy 186.318108 -299.595563) (xy 186.310523 -299.587957) (xy 186.310016 -299.582586)
			(xy 180.265832 -299.582586) (xy 180.265364 -299.587895) (xy 180.257924 -299.595468) (xy 180.252624 -299.596048)
			(xy 179.73675 -299.596048) (xy 179.728941 -299.596375) (xy 179.714069 -299.601151) (xy 179.70754 -299.605446)
			(xy 179.686432 -299.619817) (xy 179.640703 -299.642539) (xy 179.592026 -299.657963) (xy 179.541556 -299.665723)
			(xy 179.516024 -299.666152) (xy 179.490494 -299.665706) (xy 179.440031 -299.657933) (xy 179.391358 -299.642507)
			(xy 179.34563 -299.619793) (xy 179.324508 -299.605446) (xy 179.317971 -299.601164) (xy 179.303105 -299.596374)
			(xy 179.295298 -299.596048) (xy 178.779424 -299.596048) (xy 178.774174 -299.595493) (xy 178.766732 -299.588088)
			(xy 178.766216 -299.58284) (xy 172.722017 -299.58284) (xy 172.721708 -299.588026) (xy 172.714011 -299.595715)
			(xy 172.70857 -299.596048) (xy 172.192696 -299.596048) (xy 172.184885 -299.596352) (xy 172.170013 -299.601144)
			(xy 172.163486 -299.605446) (xy 172.142365 -299.619797) (xy 172.096641 -299.642523) (xy 172.047968 -299.657953)
			(xy 171.997501 -299.665719) (xy 171.97197 -299.666152) (xy 171.946439 -299.665733) (xy 171.895974 -299.657952)
			(xy 171.847302 -299.642518) (xy 171.801575 -299.619796) (xy 171.780454 -299.605446) (xy 171.773929 -299.601143)
			(xy 171.759054 -299.596366) (xy 171.751244 -299.596048) (xy 171.23537 -299.596048) (xy 171.229999 -299.595568)
			(xy 171.222414 -299.587959) (xy 171.221908 -299.582586) (xy 165.177724 -299.582586) (xy 165.177263 -299.587897)
			(xy 165.169818 -299.595471) (xy 165.164516 -299.596048) (xy 163.691316 -299.596048) (xy 163.686065 -299.595499)
			(xy 163.678624 -299.588089) (xy 163.678108 -299.58284) (xy 56.078105 -299.58284) (xy 56.077807 -299.588029)
			(xy 56.070102 -299.595718) (xy 56.064658 -299.596048) (xy 54.591458 -299.596048) (xy 54.586086 -299.595576)
			(xy 54.578501 -299.58796) (xy 54.577996 -299.582586) (xy 48.533812 -299.582586) (xy 48.533362 -299.5879)
			(xy 48.525909 -299.595474) (xy 48.520604 -299.596048) (xy 48.00473 -299.596048) (xy 47.99692 -299.596367)
			(xy 47.982049 -299.601148) (xy 47.97552 -299.605446) (xy 47.95439 -299.619782) (xy 47.908669 -299.642512)
			(xy 47.859999 -299.657946) (xy 47.809534 -299.665717) (xy 47.784004 -299.666152) (xy 47.758474 -299.665716)
			(xy 47.70801 -299.65794) (xy 47.659337 -299.642511) (xy 47.61361 -299.619794) (xy 47.592488 -299.605446)
			(xy 47.585956 -299.601156) (xy 47.571086 -299.596371) (xy 47.563278 -299.596048) (xy 47.047404 -299.596048)
			(xy 47.042151 -299.595507) (xy 47.034711 -299.588091) (xy 47.034196 -299.58284) (xy 40.989985 -299.58284)
			(xy 40.989445 -299.587936) (xy 40.981898 -299.59552) (xy 40.97655 -299.596048) (xy 40.460676 -299.596048)
			(xy 40.452864 -299.596343) (xy 40.437992 -299.601141) (xy 40.431466 -299.605446) (xy 40.410351 -299.619805)
			(xy 40.364625 -299.64253) (xy 40.31595 -299.657957) (xy 40.265482 -299.665721) (xy 40.23995 -299.666152)
			(xy 40.214421 -299.665693) (xy 40.163958 -299.657924) (xy 40.115285 -299.642502) (xy 40.069557 -299.619791)
			(xy 40.048434 -299.605446) (xy 40.041891 -299.601174) (xy 40.02703 -299.596378) (xy 40.019224 -299.596048)
			(xy 39.50335 -299.596048) (xy 39.497977 -299.595581) (xy 39.490393 -299.587962) (xy 39.489888 -299.582586)
			(xy 33.445704 -299.582586) (xy 33.445173 -299.587878) (xy 33.437776 -299.595448) (xy 33.432496 -299.596048)
			(xy 32.916622 -299.596048) (xy 32.908812 -299.596363) (xy 32.89394 -299.601147) (xy 32.887412 -299.605446)
			(xy 32.866284 -299.619786) (xy 32.820563 -299.642515) (xy 32.771891 -299.657947) (xy 32.721426 -299.665717)
			(xy 32.695896 -299.666152) (xy 32.670366 -299.66572) (xy 32.619901 -299.657943) (xy 32.571229 -299.642513)
			(xy 32.525502 -299.619794) (xy 32.50438 -299.605446) (xy 32.497849 -299.601153) (xy 32.482979 -299.59637)
			(xy 32.47517 -299.596048) (xy 31.959296 -299.596048) (xy 31.954042 -299.595512) (xy 31.946602 -299.588092)
			(xy 31.946088 -299.58284) (xy 25.901879 -299.58284) (xy 25.901373 -299.587878) (xy 25.893976 -299.595448)
			(xy 25.888696 -299.596048) (xy 25.372822 -299.596048) (xy 25.365012 -299.596363) (xy 25.35014 -299.601147)
			(xy 25.343612 -299.605446) (xy 25.322484 -299.619786) (xy 25.276763 -299.642515) (xy 25.228091 -299.657947)
			(xy 25.177626 -299.665717) (xy 25.152096 -299.666152) (xy 25.126566 -299.66572) (xy 25.076101 -299.657943)
			(xy 25.027429 -299.642513) (xy 24.981702 -299.619794) (xy 24.96058 -299.605446) (xy 24.954049 -299.601153)
			(xy 24.939179 -299.59637) (xy 24.93137 -299.596048) (xy 24.415496 -299.596048) (xy 24.410242 -299.595512)
			(xy 24.402802 -299.588092) (xy 24.402288 -299.58284) (xy 18.358077 -299.58284) (xy 18.357545 -299.587938)
			(xy 18.349992 -299.595522) (xy 18.344642 -299.596048) (xy 17.828768 -299.596048) (xy 17.82096 -299.596383)
			(xy 17.806088 -299.601153) (xy 17.799558 -299.605446) (xy 17.778445 -299.619809) (xy 17.732718 -299.642533)
			(xy 17.684042 -299.657959) (xy 17.633574 -299.665721) (xy 17.608042 -299.666152) (xy 17.582512 -299.665697)
			(xy 17.532049 -299.657927) (xy 17.483377 -299.642503) (xy 17.437648 -299.619791) (xy 17.416526 -299.605446)
			(xy 17.409985 -299.601171) (xy 17.395122 -299.596377) (xy 17.387316 -299.596048) (xy 16.871442 -299.596048)
			(xy 16.866009 -299.595691) (xy 16.85832 -299.588018) (xy 16.85798 -299.582586) (xy 2.509012 -299.582586)
			(xy 2.509012 -300.43247) (xy 20.958048 -300.43247) (xy 20.958048 -299.937932) (xy 20.958611 -299.932683)
			(xy 20.966011 -299.925242) (xy 20.971256 -299.924724) (xy 20.971764 -299.924724) (xy 21.487638 -299.924724)
			(xy 21.495447 -299.924397) (xy 21.510319 -299.919622) (xy 21.516848 -299.915326) (xy 21.537937 -299.900977)
			(xy 21.583598 -299.878246) (xy 21.632204 -299.862787) (xy 21.682607 -299.854964) (xy 21.733613 -299.854964)
			(xy 21.784016 -299.862787) (xy 21.832622 -299.878246) (xy 21.878283 -299.900977) (xy 21.899372 -299.915326)
			(xy 21.905915 -299.919598) (xy 21.920776 -299.924394) (xy 21.928582 -299.924724) (xy 22.44471 -299.924724)
			(xy 22.450012 -299.925215) (xy 22.457581 -299.932641) (xy 22.458172 -299.937932) (xy 22.458172 -300.43247)
			(xy 22.458155 -300.432724) (xy 28.502356 -300.432724) (xy 28.502356 -300.432216) (xy 28.502356 -299.937932)
			(xy 28.502912 -299.932682) (xy 28.510316 -299.925239) (xy 28.515564 -299.924724) (xy 29.031692 -299.924724)
			(xy 29.039503 -299.92442) (xy 29.054375 -299.919629) (xy 29.060902 -299.915326) (xy 29.081991 -299.900977)
			(xy 29.127652 -299.878246) (xy 29.176258 -299.862787) (xy 29.226661 -299.854964) (xy 29.277667 -299.854964)
			(xy 29.32807 -299.862787) (xy 29.376676 -299.878246) (xy 29.422337 -299.900977) (xy 29.443426 -299.915326)
			(xy 29.449957 -299.919619) (xy 29.464827 -299.924402) (xy 29.472636 -299.924724) (xy 29.988764 -299.924724)
			(xy 29.994099 -299.925054) (xy 30.001644 -299.932597) (xy 30.001972 -299.937932) (xy 30.001972 -300.43247)
			(xy 30.001947 -300.432724) (xy 36.046156 -300.432724) (xy 36.046156 -300.432216) (xy 36.046156 -299.937932)
			(xy 36.046712 -299.932682) (xy 36.054116 -299.925239) (xy 36.059364 -299.924724) (xy 36.575492 -299.924724)
			(xy 36.583303 -299.92442) (xy 36.598175 -299.919629) (xy 36.604702 -299.915326) (xy 36.625791 -299.900977)
			(xy 36.671452 -299.878246) (xy 36.720058 -299.862787) (xy 36.770461 -299.854964) (xy 36.821467 -299.854964)
			(xy 36.87187 -299.862787) (xy 36.920476 -299.878246) (xy 36.966137 -299.900977) (xy 36.987226 -299.915326)
			(xy 36.993757 -299.919619) (xy 37.008627 -299.924402) (xy 37.016436 -299.924724) (xy 37.532564 -299.924724)
			(xy 37.537899 -299.925054) (xy 37.545444 -299.932597) (xy 37.545772 -299.937932) (xy 37.545772 -300.43247)
			(xy 43.589956 -300.43247) (xy 43.589956 -299.937932) (xy 43.590512 -299.932682) (xy 43.597916 -299.925239)
			(xy 43.603164 -299.924724) (xy 43.603672 -299.924724) (xy 44.119546 -299.924724) (xy 44.127355 -299.9244)
			(xy 44.142227 -299.919623) (xy 44.148756 -299.915326) (xy 44.169845 -299.900977) (xy 44.215506 -299.878246)
			(xy 44.264112 -299.862787) (xy 44.314515 -299.854964) (xy 44.365521 -299.854964) (xy 44.415924 -299.862787)
			(xy 44.46453 -299.878246) (xy 44.510191 -299.900977) (xy 44.53128 -299.915326) (xy 44.537821 -299.919601)
			(xy 44.552684 -299.924396) (xy 44.56049 -299.924724) (xy 45.076618 -299.924724) (xy 45.081921 -299.925209)
			(xy 45.08949 -299.932639) (xy 45.09008 -299.937932) (xy 45.09008 -300.43247) (xy 45.090062 -300.432724)
			(xy 51.134264 -300.432724) (xy 51.134264 -300.432216) (xy 51.134264 -299.937932) (xy 51.134646 -299.932611)
			(xy 51.142152 -299.92507) (xy 51.147472 -299.924724) (xy 51.6636 -299.924724) (xy 51.671411 -299.924423)
			(xy 51.686283 -299.91963) (xy 51.69281 -299.915326) (xy 51.713899 -299.900977) (xy 51.75956 -299.878246)
			(xy 51.808166 -299.862787) (xy 51.858569 -299.854964) (xy 51.909575 -299.854964) (xy 51.959978 -299.862787)
			(xy 52.008584 -299.878246) (xy 52.054245 -299.900977) (xy 52.075334 -299.915326) (xy 52.081863 -299.919622)
			(xy 52.096735 -299.924403) (xy 52.104544 -299.924724) (xy 52.620672 -299.924724) (xy 52.626008 -299.925049)
			(xy 52.633553 -299.932596) (xy 52.63388 -299.937932) (xy 52.63388 -300.43247) (xy 58.678064 -300.43247)
			(xy 58.678064 -299.937932) (xy 58.678446 -299.932611) (xy 58.685952 -299.92507) (xy 58.691272 -299.924724)
			(xy 58.69178 -299.924724) (xy 60.164726 -299.924724) (xy 60.17003 -299.925204) (xy 60.177598 -299.932638)
			(xy 60.178188 -299.937932) (xy 60.178188 -300.43247) (xy 60.17817 -300.432724) (xy 167.778176 -300.432724)
			(xy 167.778176 -299.937932) (xy 167.778547 -299.932608) (xy 167.786061 -299.925066) (xy 167.791384 -299.924724)
			(xy 169.264584 -299.924724) (xy 169.269922 -299.925041) (xy 169.277466 -299.932594) (xy 169.277792 -299.937932)
			(xy 169.277792 -300.43247) (xy 175.321976 -300.43247) (xy 175.321976 -299.937932) (xy 175.322347 -299.932608)
			(xy 175.329861 -299.925066) (xy 175.335184 -299.924724) (xy 175.335692 -299.924724) (xy 175.851566 -299.924724)
			(xy 175.859376 -299.924409) (xy 175.874248 -299.919625) (xy 175.880776 -299.915326) (xy 175.901865 -299.900977)
			(xy 175.947526 -299.878246) (xy 175.996132 -299.862787) (xy 176.046535 -299.854964) (xy 176.097541 -299.854964)
			(xy 176.147944 -299.862787) (xy 176.19655 -299.878246) (xy 176.242211 -299.900977) (xy 176.2633 -299.915326)
			(xy 176.269837 -299.919609) (xy 176.284703 -299.924398) (xy 176.29251 -299.924724) (xy 176.808638 -299.924724)
			(xy 176.813943 -299.925196) (xy 176.821511 -299.932636) (xy 176.8221 -299.937932) (xy 176.8221 -300.43247)
			(xy 176.822073 -300.432724) (xy 182.866284 -300.432724) (xy 182.866284 -300.432216) (xy 182.866284 -299.937932)
			(xy 182.866648 -299.932606) (xy 182.874167 -299.925064) (xy 182.879492 -299.924724) (xy 183.39562 -299.924724)
			(xy 183.403432 -299.924431) (xy 183.418304 -299.919632) (xy 183.42483 -299.915326) (xy 183.445919 -299.900977)
			(xy 183.49158 -299.878246) (xy 183.540186 -299.862787) (xy 183.590589 -299.854964) (xy 183.641595 -299.854964)
			(xy 183.691998 -299.862787) (xy 183.740604 -299.878246) (xy 183.786265 -299.900977) (xy 183.807354 -299.915326)
			(xy 183.813879 -299.91963) (xy 183.828754 -299.924406) (xy 183.836564 -299.924724) (xy 184.352692 -299.924724)
			(xy 184.358031 -299.925035) (xy 184.365574 -299.932592) (xy 184.3659 -299.937932) (xy 184.3659 -300.43247)
			(xy 190.410084 -300.43247) (xy 190.410084 -299.937932) (xy 190.410448 -299.932606) (xy 190.417967 -299.925064)
			(xy 190.423292 -299.924724) (xy 190.4238 -299.924724) (xy 190.939674 -299.924724) (xy 190.947484 -299.924412)
			(xy 190.962356 -299.919626) (xy 190.968884 -299.915326) (xy 190.989973 -299.900977) (xy 191.035634 -299.878246)
			(xy 191.08424 -299.862787) (xy 191.134643 -299.854964) (xy 191.185649 -299.854964) (xy 191.236052 -299.862787)
			(xy 191.284658 -299.878246) (xy 191.330319 -299.900977) (xy 191.351408 -299.915326) (xy 191.357943 -299.919612)
			(xy 191.37281 -299.9244) (xy 191.380618 -299.924724) (xy 191.896746 -299.924724) (xy 191.90204 -299.925257)
			(xy 191.909613 -299.932651) (xy 191.910208 -299.937932) (xy 191.910208 -300.43247) (xy 191.910181 -300.432724)
			(xy 197.954392 -300.432724) (xy 197.954392 -300.432216) (xy 197.954392 -299.937932) (xy 197.954748 -299.932604)
			(xy 197.962273 -299.925061) (xy 197.9676 -299.924724) (xy 198.483728 -299.924724) (xy 198.491541 -299.924435)
			(xy 198.506412 -299.919633) (xy 198.512938 -299.915326) (xy 198.534027 -299.900977) (xy 198.579688 -299.878246)
			(xy 198.628294 -299.862787) (xy 198.678697 -299.854964) (xy 198.729703 -299.854964) (xy 198.780106 -299.862787)
			(xy 198.828712 -299.878246) (xy 198.874373 -299.900977) (xy 198.895462 -299.915326) (xy 198.902007 -299.919594)
			(xy 198.916866 -299.924393) (xy 198.924672 -299.924724) (xy 199.4408 -299.924724) (xy 199.44614 -299.92503)
			(xy 199.453683 -299.932591) (xy 199.454008 -299.937932) (xy 199.454008 -300.43247) (xy 199.453982 -300.432724)
			(xy 205.498192 -300.432724) (xy 205.498192 -300.432216) (xy 205.498192 -299.937932) (xy 205.498548 -299.932604)
			(xy 205.506073 -299.925061) (xy 205.5114 -299.924724) (xy 206.027528 -299.924724) (xy 206.035341 -299.924435)
			(xy 206.050212 -299.919633) (xy 206.056738 -299.915326) (xy 206.077827 -299.900977) (xy 206.123488 -299.878246)
			(xy 206.172094 -299.862787) (xy 206.222497 -299.854964) (xy 206.273503 -299.854964) (xy 206.323906 -299.862787)
			(xy 206.372512 -299.878246) (xy 206.418173 -299.900977) (xy 206.439262 -299.915326) (xy 206.445807 -299.919594)
			(xy 206.460666 -299.924393) (xy 206.468472 -299.924724) (xy 206.9846 -299.924724) (xy 206.98994 -299.92503)
			(xy 206.997483 -299.932591) (xy 206.997808 -299.937932) (xy 206.997808 -300.432216) (xy 268.898116 -300.432216)
			(xy 268.898116 -299.937678) (xy 268.898634 -299.932317) (xy 268.906217 -299.924734) (xy 268.911578 -299.924216)
			(xy 269.427706 -299.924216) (xy 269.435518 -299.923919) (xy 269.45039 -299.919123) (xy 269.456916 -299.914818)
			(xy 269.478005 -299.900469) (xy 269.523666 -299.877738) (xy 269.572272 -299.862279) (xy 269.622675 -299.854456)
			(xy 269.673681 -299.854456) (xy 269.724084 -299.862279) (xy 269.77269 -299.877738) (xy 269.818351 -299.900469)
			(xy 269.83944 -299.914818) (xy 269.845968 -299.919116) (xy 269.860841 -299.923896) (xy 269.86865 -299.924216)
			(xy 270.384778 -299.924216) (xy 270.390134 -299.924763) (xy 270.39772 -299.932324) (xy 270.39824 -299.937678)
			(xy 270.39824 -300.432216) (xy 276.442424 -300.432216) (xy 276.442424 -299.937678) (xy 276.442907 -299.932375)
			(xy 276.450339 -299.924806) (xy 276.455632 -299.924216) (xy 276.97176 -299.924216) (xy 276.97957 -299.923899)
			(xy 276.994442 -299.919117) (xy 277.00097 -299.914818) (xy 277.022059 -299.900469) (xy 277.06772 -299.877738)
			(xy 277.116326 -299.862279) (xy 277.166729 -299.854456) (xy 277.217735 -299.854456) (xy 277.268138 -299.862279)
			(xy 277.316744 -299.877738) (xy 277.362405 -299.900469) (xy 277.383494 -299.914818) (xy 277.390032 -299.919098)
			(xy 277.404897 -299.92389) (xy 277.412704 -299.924216) (xy 277.928832 -299.924216) (xy 277.934104 -299.924676)
			(xy 277.941547 -299.93215) (xy 277.94204 -299.937424) (xy 277.94204 -299.937932) (xy 277.94204 -300.432216)
			(xy 283.986224 -300.432216) (xy 283.986224 -299.937678) (xy 283.986707 -299.932375) (xy 283.994139 -299.924806)
			(xy 283.999432 -299.924216) (xy 284.51556 -299.924216) (xy 284.52337 -299.923899) (xy 284.538242 -299.919117)
			(xy 284.54477 -299.914818) (xy 284.565859 -299.900469) (xy 284.61152 -299.877738) (xy 284.660126 -299.862279)
			(xy 284.710529 -299.854456) (xy 284.761535 -299.854456) (xy 284.811938 -299.862279) (xy 284.860544 -299.877738)
			(xy 284.906205 -299.900469) (xy 284.927294 -299.914818) (xy 284.933832 -299.919098) (xy 284.948697 -299.92389)
			(xy 284.956504 -299.924216) (xy 285.472632 -299.924216) (xy 285.477904 -299.924676) (xy 285.485347 -299.93215)
			(xy 285.48584 -299.937424) (xy 285.48584 -299.937932) (xy 285.48584 -300.432216) (xy 291.530024 -300.432216)
			(xy 291.530024 -299.937678) (xy 291.530534 -299.932315) (xy 291.538123 -299.924731) (xy 291.543486 -299.924216)
			(xy 292.059614 -299.924216) (xy 292.067426 -299.923922) (xy 292.082298 -299.919124) (xy 292.088824 -299.914818)
			(xy 292.109913 -299.900469) (xy 292.155574 -299.877738) (xy 292.20418 -299.862279) (xy 292.254583 -299.854456)
			(xy 292.305589 -299.854456) (xy 292.355992 -299.862279) (xy 292.404598 -299.877738) (xy 292.450259 -299.900469)
			(xy 292.471348 -299.914818) (xy 292.477874 -299.919119) (xy 292.492748 -299.923897) (xy 292.500558 -299.924216)
			(xy 293.016686 -299.924216) (xy 293.022043 -299.924757) (xy 293.029628 -299.932322) (xy 293.030148 -299.937678)
			(xy 293.030148 -300.432216) (xy 299.074332 -300.432216) (xy 299.074332 -299.937678) (xy 299.074808 -299.932373)
			(xy 299.082245 -299.924804) (xy 299.08754 -299.924216) (xy 299.603668 -299.924216) (xy 299.611478 -299.923903)
			(xy 299.62635 -299.919118) (xy 299.632878 -299.914818) (xy 299.653967 -299.900469) (xy 299.699628 -299.877738)
			(xy 299.748234 -299.862279) (xy 299.798637 -299.854456) (xy 299.849643 -299.854456) (xy 299.900046 -299.862279)
			(xy 299.948652 -299.877738) (xy 299.994313 -299.900469) (xy 300.015402 -299.914818) (xy 300.021939 -299.919101)
			(xy 300.036804 -299.923891) (xy 300.044612 -299.924216) (xy 300.56074 -299.924216) (xy 300.566013 -299.92467)
			(xy 300.573455 -299.932148) (xy 300.573948 -299.937424) (xy 300.573948 -299.937932) (xy 300.573948 -300.432216)
			(xy 306.618132 -300.432216) (xy 306.618132 -299.937678) (xy 306.618635 -299.932313) (xy 306.626228 -299.924729)
			(xy 306.631594 -299.924216) (xy 308.104794 -299.924216) (xy 308.110152 -299.924752) (xy 308.117737 -299.932321)
			(xy 308.118256 -299.937678) (xy 308.118256 -300.146974) (xy 340.219284 -300.146974) (xy 340.219284 -299.130974)
			(xy 340.21977 -299.103723) (xy 340.227526 -299.049775) (xy 340.242881 -298.99748) (xy 340.265523 -298.947903)
			(xy 340.294989 -298.902053) (xy 340.33068 -298.860862) (xy 340.371871 -298.825171) (xy 340.417721 -298.795705)
			(xy 340.467298 -298.773063) (xy 340.519593 -298.757708) (xy 340.573541 -298.749952) (xy 340.628043 -298.749952)
			(xy 340.681991 -298.757708) (xy 340.734286 -298.773063) (xy 340.783863 -298.795705) (xy 340.829713 -298.825171)
			(xy 340.870904 -298.860862) (xy 340.906595 -298.902053) (xy 340.936061 -298.947903) (xy 340.958703 -298.99748)
			(xy 340.974058 -299.049775) (xy 340.981814 -299.103723) (xy 340.9823 -299.130974) (xy 340.9823 -299.582332)
			(xy 411.618176 -299.582332) (xy 411.618176 -299.087794) (xy 411.618623 -299.082481) (xy 411.626079 -299.074908)
			(xy 411.631384 -299.074332) (xy 413.104584 -299.074332) (xy 413.109924 -299.074641) (xy 413.117468 -299.0822)
			(xy 413.117792 -299.08754) (xy 413.117792 -299.088048) (xy 413.117792 -299.582332) (xy 419.161976 -299.582332)
			(xy 419.161976 -299.087794) (xy 419.162279 -299.082349) (xy 419.169992 -299.074661) (xy 419.175438 -299.074332)
			(xy 419.691566 -299.074332) (xy 419.699376 -299.074015) (xy 419.714248 -299.069233) (xy 419.720776 -299.064934)
			(xy 419.741865 -299.050585) (xy 419.787526 -299.027854) (xy 419.836132 -299.012395) (xy 419.886535 -299.004572)
			(xy 419.937541 -299.004572) (xy 419.987944 -299.012395) (xy 420.03655 -299.027854) (xy 420.082211 -299.050585)
			(xy 420.1033 -299.064934) (xy 420.109836 -299.069218) (xy 420.124702 -299.074007) (xy 420.13251 -299.074332)
			(xy 420.648638 -299.074332) (xy 420.654005 -299.074825) (xy 420.661588 -299.082426) (xy 420.6621 -299.087794)
			(xy 420.6621 -299.582332) (xy 426.706284 -299.582332) (xy 426.706284 -299.087794) (xy 426.706724 -299.082479)
			(xy 426.714185 -299.074905) (xy 426.719492 -299.074332) (xy 427.23562 -299.074332) (xy 427.243432 -299.074038)
			(xy 427.258304 -299.06924) (xy 427.26483 -299.064934) (xy 427.285919 -299.050585) (xy 427.33158 -299.027854)
			(xy 427.380186 -299.012395) (xy 427.430589 -299.004572) (xy 427.481595 -299.004572) (xy 427.531998 -299.012395)
			(xy 427.580604 -299.027854) (xy 427.626265 -299.050585) (xy 427.647354 -299.064934) (xy 427.653878 -299.069238)
			(xy 427.668754 -299.074014) (xy 427.676564 -299.074332) (xy 428.192692 -299.074332) (xy 428.198033 -299.074636)
			(xy 428.205577 -299.082198) (xy 428.2059 -299.08754) (xy 428.2059 -299.088048) (xy 428.2059 -299.582332)
			(xy 434.250084 -299.582332) (xy 434.250084 -299.087794) (xy 434.25038 -299.082347) (xy 434.258098 -299.074659)
			(xy 434.263546 -299.074332) (xy 434.779674 -299.074332) (xy 434.787484 -299.074019) (xy 434.802356 -299.069234)
			(xy 434.808884 -299.064934) (xy 434.829973 -299.050585) (xy 434.875634 -299.027854) (xy 434.92424 -299.012395)
			(xy 434.974643 -299.004572) (xy 435.025649 -299.004572) (xy 435.076052 -299.012395) (xy 435.124658 -299.027854)
			(xy 435.170319 -299.050585) (xy 435.191408 -299.064934) (xy 435.197942 -299.069221) (xy 435.21281 -299.074008)
			(xy 435.220618 -299.074332) (xy 435.736746 -299.074332) (xy 435.742114 -299.074819) (xy 435.749697 -299.082425)
			(xy 435.750208 -299.087794) (xy 435.750208 -299.582332) (xy 441.794392 -299.582332) (xy 441.794392 -299.087794)
			(xy 441.794913 -299.0825) (xy 441.802318 -299.074932) (xy 441.8076 -299.074332) (xy 442.323728 -299.074332)
			(xy 442.33154 -299.074042) (xy 442.346412 -299.069241) (xy 442.352938 -299.064934) (xy 442.374027 -299.050585)
			(xy 442.419688 -299.027854) (xy 442.468294 -299.012395) (xy 442.518697 -299.004572) (xy 442.569703 -299.004572)
			(xy 442.620106 -299.012395) (xy 442.668712 -299.027854) (xy 442.714373 -299.050585) (xy 442.735462 -299.064934)
			(xy 442.742007 -299.069203) (xy 442.756866 -299.074001) (xy 442.764672 -299.074332) (xy 443.2808 -299.074332)
			(xy 443.286142 -299.074631) (xy 443.293685 -299.082197) (xy 443.294008 -299.08754) (xy 443.294008 -299.088048)
			(xy 443.294008 -299.582332) (xy 449.338192 -299.582332) (xy 449.338192 -299.087794) (xy 449.338713 -299.0825)
			(xy 449.346118 -299.074932) (xy 449.3514 -299.074332) (xy 449.867528 -299.074332) (xy 449.87534 -299.074042)
			(xy 449.890212 -299.069241) (xy 449.896738 -299.064934) (xy 449.917827 -299.050585) (xy 449.963488 -299.027854)
			(xy 450.012094 -299.012395) (xy 450.062497 -299.004572) (xy 450.113503 -299.004572) (xy 450.163906 -299.012395)
			(xy 450.212512 -299.027854) (xy 450.258173 -299.050585) (xy 450.279262 -299.064934) (xy 450.285807 -299.069203)
			(xy 450.300666 -299.074001) (xy 450.308472 -299.074332) (xy 450.8246 -299.074332) (xy 450.829942 -299.074631)
			(xy 450.837485 -299.082197) (xy 450.837808 -299.08754) (xy 450.837808 -299.088048) (xy 450.837808 -299.582332)
			(xy 450.837327 -299.587599) (xy 450.829868 -299.595039) (xy 450.8246 -299.59554) (xy 450.308726 -299.59554)
			(xy 450.300849 -299.595805) (xy 450.285846 -299.600604) (xy 450.279262 -299.604938) (xy 450.258185 -299.61933)
			(xy 450.21254 -299.642158) (xy 450.163934 -299.657716) (xy 450.113517 -299.665635) (xy 450.088 -299.666152)
			(xy 450.06248 -299.66567) (xy 450.012053 -299.657772) (xy 449.963441 -299.642209) (xy 449.917803 -299.619353)
			(xy 449.896738 -299.604938) (xy 449.890137 -299.600639) (xy 449.875144 -299.595842) (xy 449.867274 -299.59554)
			(xy 449.3514 -299.59554) (xy 449.346145 -299.595008) (xy 449.338704 -299.587586) (xy 449.338192 -299.582332)
			(xy 443.294008 -299.582332) (xy 443.293527 -299.587599) (xy 443.286068 -299.595039) (xy 443.2808 -299.59554)
			(xy 442.764926 -299.59554) (xy 442.757049 -299.595805) (xy 442.742046 -299.600604) (xy 442.735462 -299.604938)
			(xy 442.714385 -299.61933) (xy 442.66874 -299.642158) (xy 442.620134 -299.657716) (xy 442.569717 -299.665635)
			(xy 442.5442 -299.666152) (xy 442.51868 -299.66567) (xy 442.468253 -299.657772) (xy 442.419641 -299.642209)
			(xy 442.374003 -299.619353) (xy 442.352938 -299.604938) (xy 442.346337 -299.600639) (xy 442.331344 -299.595842)
			(xy 442.323474 -299.59554) (xy 441.8076 -299.59554) (xy 441.802345 -299.595008) (xy 441.794904 -299.587586)
			(xy 441.794392 -299.582332) (xy 435.750208 -299.582332) (xy 435.749727 -299.587599) (xy 435.742268 -299.595039)
			(xy 435.737 -299.59554) (xy 435.736492 -299.59554) (xy 435.220872 -299.59554) (xy 435.212997 -299.595825)
			(xy 435.197993 -299.600611) (xy 435.191408 -299.604938) (xy 435.170346 -299.619353) (xy 435.124696 -299.642176)
			(xy 435.076085 -299.657728) (xy 435.025664 -299.665639) (xy 435.000146 -299.666152) (xy 434.974627 -299.665647)
			(xy 434.924201 -299.657755) (xy 434.875589 -299.6422) (xy 434.82995 -299.61935) (xy 434.808884 -299.604938)
			(xy 434.802296 -299.600618) (xy 434.787293 -299.595834) (xy 434.77942 -299.59554) (xy 434.263546 -299.59554)
			(xy 434.258243 -299.595044) (xy 434.250668 -299.587624) (xy 434.250084 -299.582332) (xy 428.2059 -299.582332)
			(xy 428.205426 -299.587601) (xy 428.197962 -299.595042) (xy 428.192692 -299.59554) (xy 427.676818 -299.59554)
			(xy 427.668945 -299.595845) (xy 427.653941 -299.600617) (xy 427.647354 -299.604938) (xy 427.626279 -299.619333)
			(xy 427.580633 -299.642161) (xy 427.532027 -299.657718) (xy 427.481609 -299.665636) (xy 427.456092 -299.666152)
			(xy 427.430573 -299.665624) (xy 427.380149 -299.657739) (xy 427.331537 -299.64219) (xy 427.285897 -299.619347)
			(xy 427.26483 -299.604938) (xy 427.258231 -299.600636) (xy 427.243237 -299.59584) (xy 427.235366 -299.59554)
			(xy 426.719492 -299.59554) (xy 426.714236 -299.595014) (xy 426.706796 -299.587587) (xy 426.706284 -299.582332)
			(xy 420.6621 -299.582332) (xy 420.661626 -299.587601) (xy 420.654162 -299.595042) (xy 420.648892 -299.59554)
			(xy 420.648384 -299.59554) (xy 420.132764 -299.59554) (xy 420.124889 -299.595821) (xy 420.109885 -299.600609)
			(xy 420.1033 -299.604938) (xy 420.082212 -299.619313) (xy 420.036571 -299.642146) (xy 419.987968 -299.657708)
			(xy 419.937554 -299.665632) (xy 419.912038 -299.666152) (xy 419.886518 -299.665651) (xy 419.836092 -299.657758)
			(xy 419.787481 -299.642201) (xy 419.741842 -299.619351) (xy 419.720776 -299.604938) (xy 419.714189 -299.600615)
			(xy 419.699186 -299.595832) (xy 419.691312 -299.59554) (xy 419.175438 -299.59554) (xy 419.170134 -299.595049)
			(xy 419.162559 -299.587626) (xy 419.161976 -299.582332) (xy 413.117792 -299.582332) (xy 413.117325 -299.587602)
			(xy 413.109856 -299.595044) (xy 413.104584 -299.59554) (xy 411.631384 -299.59554) (xy 411.626127 -299.595019)
			(xy 411.618687 -299.587588) (xy 411.618176 -299.582332) (xy 340.9823 -299.582332) (xy 340.9823 -300.146974)
			(xy 340.981814 -300.174225) (xy 340.974058 -300.228173) (xy 340.958703 -300.280468) (xy 340.936061 -300.330045)
			(xy 340.906595 -300.375895) (xy 340.870904 -300.417086) (xy 340.853442 -300.432216) (xy 415.718244 -300.432216)
			(xy 415.718244 -299.937678) (xy 415.718709 -299.93237) (xy 415.726153 -299.9248) (xy 415.731452 -299.924216)
			(xy 417.204652 -299.924216) (xy 417.209984 -299.924562) (xy 417.217529 -299.932093) (xy 417.21786 -299.937424)
			(xy 417.21786 -300.432216) (xy 423.262044 -300.432216) (xy 423.262044 -299.937678) (xy 423.262536 -299.93231)
			(xy 423.270137 -299.924725) (xy 423.275506 -299.924216) (xy 423.791634 -299.924216) (xy 423.799443 -299.923888)
			(xy 423.814315 -299.919114) (xy 423.820844 -299.914818) (xy 423.841933 -299.900469) (xy 423.887594 -299.877738)
			(xy 423.9362 -299.862279) (xy 423.986603 -299.854456) (xy 424.037609 -299.854456) (xy 424.088012 -299.862279)
			(xy 424.136618 -299.877738) (xy 424.182279 -299.900469) (xy 424.203368 -299.914818) (xy 424.209912 -299.919088)
			(xy 424.224772 -299.923886) (xy 424.232578 -299.924216) (xy 424.748706 -299.924216) (xy 424.754065 -299.924744)
			(xy 424.76165 -299.932319) (xy 424.762168 -299.937678) (xy 424.762168 -300.432216) (xy 430.806352 -300.432216)
			(xy 430.806352 -299.937678) (xy 430.80681 -299.932368) (xy 430.814259 -299.924798) (xy 430.81956 -299.924216)
			(xy 431.335688 -299.924216) (xy 431.343499 -299.923911) (xy 431.358371 -299.919121) (xy 431.364898 -299.914818)
			(xy 431.385987 -299.900469) (xy 431.431648 -299.877738) (xy 431.480254 -299.862279) (xy 431.530657 -299.854456)
			(xy 431.581663 -299.854456) (xy 431.632066 -299.862279) (xy 431.680672 -299.877738) (xy 431.726333 -299.900469)
			(xy 431.747422 -299.914818) (xy 431.753954 -299.919109) (xy 431.768823 -299.923894) (xy 431.776632 -299.924216)
			(xy 432.29276 -299.924216) (xy 432.298093 -299.924556) (xy 432.305637 -299.932092) (xy 432.305968 -299.937424)
			(xy 432.305968 -299.937932) (xy 432.305968 -300.432216) (xy 438.350152 -300.432216) (xy 438.350152 -299.937678)
			(xy 438.350637 -299.932308) (xy 438.358243 -299.924723) (xy 438.363614 -299.924216) (xy 438.879742 -299.924216)
			(xy 438.887551 -299.923892) (xy 438.902423 -299.919115) (xy 438.908952 -299.914818) (xy 438.930041 -299.900469)
			(xy 438.975702 -299.877738) (xy 439.024308 -299.862279) (xy 439.074711 -299.854456) (xy 439.125717 -299.854456)
			(xy 439.17612 -299.862279) (xy 439.224726 -299.877738) (xy 439.270387 -299.900469) (xy 439.291476 -299.914818)
			(xy 439.298018 -299.919091) (xy 439.31288 -299.923887) (xy 439.320686 -299.924216) (xy 439.836814 -299.924216)
			(xy 439.842174 -299.924739) (xy 439.849758 -299.932318) (xy 439.850276 -299.937678) (xy 439.850276 -300.432216)
			(xy 445.89446 -300.432216) (xy 445.89446 -299.937678) (xy 445.894911 -299.932366) (xy 445.902365 -299.924795)
			(xy 445.907668 -299.924216) (xy 446.423796 -299.924216) (xy 446.431607 -299.923915) (xy 446.446479 -299.919122)
			(xy 446.453006 -299.914818) (xy 446.474095 -299.900469) (xy 446.519756 -299.877738) (xy 446.568362 -299.862279)
			(xy 446.618765 -299.854456) (xy 446.669771 -299.854456) (xy 446.720174 -299.862279) (xy 446.76878 -299.877738)
			(xy 446.814441 -299.900469) (xy 446.83553 -299.914818) (xy 446.84206 -299.919112) (xy 446.856931 -299.923895)
			(xy 446.86474 -299.924216) (xy 447.380868 -299.924216) (xy 447.386202 -299.924551) (xy 447.393746 -299.93209)
			(xy 447.394076 -299.937424) (xy 447.394076 -299.937932) (xy 447.394076 -300.432216) (xy 453.43826 -300.432216)
			(xy 453.43826 -299.937678) (xy 453.438711 -299.932366) (xy 453.446165 -299.924795) (xy 453.451468 -299.924216)
			(xy 453.967596 -299.924216) (xy 453.975407 -299.923915) (xy 453.990279 -299.919122) (xy 453.996806 -299.914818)
			(xy 454.017895 -299.900469) (xy 454.063556 -299.877738) (xy 454.112162 -299.862279) (xy 454.162565 -299.854456)
			(xy 454.213571 -299.854456) (xy 454.263974 -299.862279) (xy 454.31258 -299.877738) (xy 454.358241 -299.900469)
			(xy 454.37933 -299.914818) (xy 454.38586 -299.919112) (xy 454.400731 -299.923895) (xy 454.40854 -299.924216)
			(xy 454.924668 -299.924216) (xy 454.930002 -299.924551) (xy 454.937546 -299.93209) (xy 454.937876 -299.937424)
			(xy 454.937876 -299.937932) (xy 454.937876 -300.432216) (xy 454.937581 -300.437558) (xy 454.930012 -300.4451)
			(xy 454.924668 -300.445424) (xy 454.408794 -300.445424) (xy 454.40092 -300.445721) (xy 454.385917 -300.450499)
			(xy 454.37933 -300.454822) (xy 454.35826 -300.469226) (xy 454.312613 -300.492052) (xy 454.264005 -300.507607)
			(xy 454.213585 -300.515521) (xy 454.188068 -300.516036) (xy 454.162549 -300.515523) (xy 454.112123 -300.507634)
			(xy 454.063512 -300.492081) (xy 454.017872 -300.469233) (xy 453.996806 -300.454822) (xy 453.990213 -300.450509)
			(xy 453.975214 -300.445721) (xy 453.967342 -300.445424) (xy 453.451468 -300.445424) (xy 453.446205 -300.444928)
			(xy 453.438765 -300.437479) (xy 453.43826 -300.432216) (xy 447.394076 -300.432216) (xy 447.393781 -300.437558)
			(xy 447.386212 -300.4451) (xy 447.380868 -300.445424) (xy 446.864994 -300.445424) (xy 446.85712 -300.445721)
			(xy 446.842117 -300.450499) (xy 446.83553 -300.454822) (xy 446.81446 -300.469226) (xy 446.768813 -300.492052)
			(xy 446.720205 -300.507607) (xy 446.669785 -300.515521) (xy 446.644268 -300.516036) (xy 446.618749 -300.515523)
			(xy 446.568323 -300.507634) (xy 446.519712 -300.492081) (xy 446.474072 -300.469233) (xy 446.453006 -300.454822)
			(xy 446.446413 -300.450509) (xy 446.431414 -300.445721) (xy 446.423542 -300.445424) (xy 445.907668 -300.445424)
			(xy 445.902405 -300.444928) (xy 445.894965 -300.437479) (xy 445.89446 -300.432216) (xy 439.850276 -300.432216)
			(xy 439.849981 -300.437558) (xy 439.842412 -300.4451) (xy 439.837068 -300.445424) (xy 439.83656 -300.445424)
			(xy 439.32094 -300.445424) (xy 439.313064 -300.445698) (xy 439.298061 -300.450491) (xy 439.291476 -300.454822)
			(xy 439.270394 -300.469206) (xy 439.224751 -300.492037) (xy 439.176146 -300.507597) (xy 439.12573 -300.515518)
			(xy 439.100214 -300.516036) (xy 439.074694 -300.51555) (xy 439.024267 -300.507653) (xy 438.975656 -300.492092)
			(xy 438.930017 -300.469237) (xy 438.908952 -300.454822) (xy 438.902372 -300.450488) (xy 438.887363 -300.445713)
			(xy 438.879488 -300.445424) (xy 438.363614 -300.445424) (xy 438.358303 -300.444963) (xy 438.350729 -300.437518)
			(xy 438.350152 -300.432216) (xy 432.305968 -300.432216) (xy 432.30568 -300.43756) (xy 432.298106 -300.445103)
			(xy 432.29276 -300.445424) (xy 431.776886 -300.445424) (xy 431.769012 -300.445717) (xy 431.754008 -300.450497)
			(xy 431.747422 -300.454822) (xy 431.726355 -300.469229) (xy 431.680706 -300.492055) (xy 431.632097 -300.507608)
			(xy 431.581678 -300.515522) (xy 431.55616 -300.516036) (xy 431.530641 -300.515527) (xy 431.480215 -300.507637)
			(xy 431.431603 -300.492083) (xy 431.385964 -300.469234) (xy 431.364898 -300.454822) (xy 431.358307 -300.450506)
			(xy 431.343307 -300.44572) (xy 431.335434 -300.445424) (xy 430.81956 -300.445424) (xy 430.814296 -300.444934)
			(xy 430.806857 -300.437481) (xy 430.806352 -300.432216) (xy 424.762168 -300.432216) (xy 424.76188 -300.43756)
			(xy 424.754306 -300.445103) (xy 424.74896 -300.445424) (xy 424.748452 -300.445424) (xy 424.232832 -300.445424)
			(xy 424.224956 -300.445694) (xy 424.209952 -300.45049) (xy 424.203368 -300.454822) (xy 424.182288 -300.469209)
			(xy 424.136644 -300.492039) (xy 424.088039 -300.507599) (xy 424.037622 -300.515518) (xy 424.012106 -300.516036)
			(xy 423.986586 -300.515554) (xy 423.936159 -300.507656) (xy 423.887547 -300.492094) (xy 423.841909 -300.469237)
			(xy 423.820844 -300.454822) (xy 423.814265 -300.450485) (xy 423.799255 -300.445712) (xy 423.79138 -300.445424)
			(xy 423.275506 -300.445424) (xy 423.270194 -300.444969) (xy 423.26262 -300.437519) (xy 423.262044 -300.432216)
			(xy 417.21786 -300.432216) (xy 417.217579 -300.437562) (xy 417.21 -300.445105) (xy 417.204652 -300.445424)
			(xy 415.731452 -300.445424) (xy 415.726187 -300.444939) (xy 415.718749 -300.437482) (xy 415.718244 -300.432216)
			(xy 340.853442 -300.432216) (xy 340.829713 -300.452777) (xy 340.783863 -300.482243) (xy 340.734286 -300.504885)
			(xy 340.681991 -300.52024) (xy 340.628043 -300.527996) (xy 340.573541 -300.527996) (xy 340.519593 -300.52024)
			(xy 340.467298 -300.504885) (xy 340.417721 -300.482243) (xy 340.371871 -300.452777) (xy 340.33068 -300.417086)
			(xy 340.294989 -300.375895) (xy 340.265523 -300.330045) (xy 340.242881 -300.280468) (xy 340.227526 -300.228173)
			(xy 340.21977 -300.174225) (xy 340.219284 -300.146974) (xy 308.118256 -300.146974) (xy 308.118256 -300.432216)
			(xy 308.117721 -300.437469) (xy 308.1103 -300.444908) (xy 308.105048 -300.445424) (xy 308.10454 -300.445424)
			(xy 306.631594 -300.445424) (xy 306.626281 -300.444977) (xy 306.618708 -300.437521) (xy 306.618132 -300.432216)
			(xy 300.573948 -300.432216) (xy 300.57342 -300.437471) (xy 300.565994 -300.444911) (xy 300.56074 -300.445424)
			(xy 300.044866 -300.445424) (xy 300.036991 -300.445709) (xy 300.021987 -300.450495) (xy 300.015402 -300.454822)
			(xy 299.994312 -300.469195) (xy 299.948672 -300.492028) (xy 299.90007 -300.507591) (xy 299.849656 -300.515516)
			(xy 299.82414 -300.516036) (xy 299.79862 -300.515537) (xy 299.748194 -300.507644) (xy 299.699583 -300.492087)
			(xy 299.653944 -300.469235) (xy 299.632878 -300.454822) (xy 299.626292 -300.450498) (xy 299.611288 -300.445717)
			(xy 299.603414 -300.445424) (xy 299.08754 -300.445424) (xy 299.082217 -300.445048) (xy 299.074675 -300.437537)
			(xy 299.074332 -300.432216) (xy 293.030148 -300.432216) (xy 293.02962 -300.437471) (xy 293.022194 -300.444911)
			(xy 293.01694 -300.445424) (xy 293.016432 -300.445424) (xy 292.500812 -300.445424) (xy 292.492939 -300.445729)
			(xy 292.477935 -300.450501) (xy 292.471348 -300.454822) (xy 292.450273 -300.469218) (xy 292.404628 -300.492046)
			(xy 292.356021 -300.507603) (xy 292.305603 -300.51552) (xy 292.280086 -300.516036) (xy 292.254567 -300.515514)
			(xy 292.204142 -300.507628) (xy 292.15553 -300.492077) (xy 292.10989 -300.469232) (xy 292.088824 -300.454822)
			(xy 292.082227 -300.450516) (xy 292.067231 -300.445723) (xy 292.05936 -300.445424) (xy 291.543486 -300.445424)
			(xy 291.538172 -300.444982) (xy 291.530599 -300.437522) (xy 291.530024 -300.432216) (xy 285.48584 -300.432216)
			(xy 285.485319 -300.437473) (xy 285.477888 -300.444913) (xy 285.472632 -300.445424) (xy 284.956758 -300.445424)
			(xy 284.948883 -300.445705) (xy 284.933879 -300.450494) (xy 284.927294 -300.454822) (xy 284.906207 -300.469198)
			(xy 284.860566 -300.492031) (xy 284.811963 -300.507593) (xy 284.761548 -300.515517) (xy 284.736032 -300.516036)
			(xy 284.710512 -300.515541) (xy 284.660086 -300.507647) (xy 284.611474 -300.492088) (xy 284.565835 -300.469236)
			(xy 284.54477 -300.454822) (xy 284.538186 -300.450495) (xy 284.52318 -300.445715) (xy 284.515306 -300.445424)
			(xy 283.999432 -300.445424) (xy 283.994108 -300.445053) (xy 283.986566 -300.437539) (xy 283.986224 -300.432216)
			(xy 277.94204 -300.432216) (xy 277.941519 -300.437473) (xy 277.934088 -300.444913) (xy 277.928832 -300.445424)
			(xy 277.412958 -300.445424) (xy 277.405083 -300.445705) (xy 277.390079 -300.450494) (xy 277.383494 -300.454822)
			(xy 277.362407 -300.469198) (xy 277.316766 -300.492031) (xy 277.268163 -300.507593) (xy 277.217748 -300.515517)
			(xy 277.192232 -300.516036) (xy 277.166712 -300.515541) (xy 277.116286 -300.507647) (xy 277.067674 -300.492088)
			(xy 277.022035 -300.469236) (xy 277.00097 -300.454822) (xy 276.994386 -300.450495) (xy 276.97938 -300.445715)
			(xy 276.971506 -300.445424) (xy 276.455632 -300.445424) (xy 276.450308 -300.445053) (xy 276.442766 -300.437539)
			(xy 276.442424 -300.432216) (xy 270.39824 -300.432216) (xy 270.397719 -300.437473) (xy 270.390288 -300.444913)
			(xy 270.385032 -300.445424) (xy 270.384524 -300.445424) (xy 269.868904 -300.445424) (xy 269.861031 -300.445726)
			(xy 269.846027 -300.4505) (xy 269.83944 -300.454822) (xy 269.818368 -300.469221) (xy 269.772721 -300.492049)
			(xy 269.724114 -300.507604) (xy 269.673695 -300.515521) (xy 269.648178 -300.516036) (xy 269.622659 -300.515518)
			(xy 269.572234 -300.507631) (xy 269.523622 -300.492079) (xy 269.477982 -300.469233) (xy 269.456916 -300.454822)
			(xy 269.450321 -300.450513) (xy 269.435324 -300.445722) (xy 269.427452 -300.445424) (xy 268.911578 -300.445424)
			(xy 268.906263 -300.444987) (xy 268.898691 -300.437524) (xy 268.898116 -300.432216) (xy 206.997808 -300.432216)
			(xy 206.997808 -300.43247) (xy 206.997262 -300.437759) (xy 206.989876 -300.445329) (xy 206.9846 -300.445932)
			(xy 206.468726 -300.445932) (xy 206.460916 -300.446252) (xy 206.446045 -300.451033) (xy 206.439516 -300.45533)
			(xy 206.418386 -300.469666) (xy 206.372665 -300.492396) (xy 206.323995 -300.50783) (xy 206.27353 -300.515601)
			(xy 206.248 -300.516036) (xy 206.222469 -300.515605) (xy 206.172005 -300.507828) (xy 206.123333 -300.492397)
			(xy 206.077605 -300.469679) (xy 206.056484 -300.45533) (xy 206.049953 -300.451037) (xy 206.035083 -300.446255)
			(xy 206.027274 -300.445932) (xy 205.5114 -300.445932) (xy 205.506143 -300.445408) (xy 205.498702 -300.43798)
			(xy 205.498192 -300.432724) (xy 199.453982 -300.432724) (xy 199.453462 -300.437759) (xy 199.446076 -300.445329)
			(xy 199.4408 -300.445932) (xy 198.924926 -300.445932) (xy 198.917116 -300.446252) (xy 198.902245 -300.451033)
			(xy 198.895716 -300.45533) (xy 198.874586 -300.469666) (xy 198.828865 -300.492396) (xy 198.780195 -300.50783)
			(xy 198.72973 -300.515601) (xy 198.7042 -300.516036) (xy 198.678669 -300.515605) (xy 198.628205 -300.507828)
			(xy 198.579533 -300.492397) (xy 198.533805 -300.469679) (xy 198.512684 -300.45533) (xy 198.506153 -300.451037)
			(xy 198.491283 -300.446255) (xy 198.483474 -300.445932) (xy 197.9676 -300.445932) (xy 197.962343 -300.445408)
			(xy 197.954902 -300.43798) (xy 197.954392 -300.432724) (xy 191.910181 -300.432724) (xy 191.909634 -300.437819)
			(xy 191.902092 -300.445404) (xy 191.896746 -300.445932) (xy 191.380872 -300.445932) (xy 191.37306 -300.446228)
			(xy 191.358189 -300.451026) (xy 191.351662 -300.45533) (xy 191.330547 -300.469689) (xy 191.284821 -300.492414)
			(xy 191.236146 -300.507842) (xy 191.185678 -300.515605) (xy 191.160146 -300.516036) (xy 191.134616 -300.515582)
			(xy 191.084153 -300.507812) (xy 191.03548 -300.492388) (xy 190.989752 -300.469676) (xy 190.96863 -300.45533)
			(xy 190.962089 -300.451055) (xy 190.947226 -300.446261) (xy 190.93942 -300.445932) (xy 190.423546 -300.445932)
			(xy 190.41811 -300.445587) (xy 190.410419 -300.437906) (xy 190.410084 -300.43247) (xy 184.3659 -300.43247)
			(xy 184.365362 -300.437761) (xy 184.35797 -300.445332) (xy 184.352692 -300.445932) (xy 183.836818 -300.445932)
			(xy 183.829008 -300.446248) (xy 183.814136 -300.451032) (xy 183.807608 -300.45533) (xy 183.78648 -300.469669)
			(xy 183.740759 -300.492399) (xy 183.692087 -300.507832) (xy 183.641622 -300.515601) (xy 183.616092 -300.516036)
			(xy 183.590561 -300.515609) (xy 183.540097 -300.507831) (xy 183.491424 -300.492399) (xy 183.445697 -300.469679)
			(xy 183.424576 -300.45533) (xy 183.418047 -300.451034) (xy 183.403175 -300.446254) (xy 183.395366 -300.445932)
			(xy 182.879492 -300.445932) (xy 182.874234 -300.445413) (xy 182.866793 -300.437981) (xy 182.866284 -300.432724)
			(xy 176.822073 -300.432724) (xy 176.821534 -300.437821) (xy 176.813987 -300.445407) (xy 176.808638 -300.445932)
			(xy 176.292764 -300.445932) (xy 176.284956 -300.446268) (xy 176.270084 -300.451038) (xy 176.263554 -300.45533)
			(xy 176.242441 -300.469693) (xy 176.196714 -300.492417) (xy 176.148038 -300.507843) (xy 176.09757 -300.515606)
			(xy 176.072038 -300.516036) (xy 176.046508 -300.515586) (xy 175.996045 -300.507815) (xy 175.947372 -300.49239)
			(xy 175.901644 -300.469676) (xy 175.880522 -300.45533) (xy 175.873983 -300.451052) (xy 175.859119 -300.44626)
			(xy 175.851312 -300.445932) (xy 175.335438 -300.445932) (xy 175.330001 -300.445592) (xy 175.322311 -300.437907)
			(xy 175.321976 -300.43247) (xy 169.277792 -300.43247) (xy 169.277261 -300.437763) (xy 169.269865 -300.445334)
			(xy 169.264584 -300.445932) (xy 167.791384 -300.445932) (xy 167.786125 -300.445419) (xy 167.778685 -300.437983)
			(xy 167.778176 -300.432724) (xy 60.17817 -300.432724) (xy 60.177803 -300.437894) (xy 60.170149 -300.44558)
			(xy 60.164726 -300.445932) (xy 58.691526 -300.445932) (xy 58.686087 -300.4456) (xy 58.678398 -300.437909)
			(xy 58.678064 -300.43247) (xy 52.63388 -300.43247) (xy 52.633359 -300.437766) (xy 52.625956 -300.445338)
			(xy 52.620672 -300.445932) (xy 52.104798 -300.445932) (xy 52.096987 -300.446239) (xy 52.082116 -300.451029)
			(xy 52.075588 -300.45533) (xy 52.054466 -300.469678) (xy 52.008742 -300.492406) (xy 51.960069 -300.507836)
			(xy 51.909603 -300.515603) (xy 51.884072 -300.516036) (xy 51.858541 -300.515619) (xy 51.808076 -300.507838)
			(xy 51.759404 -300.492403) (xy 51.713677 -300.469681) (xy 51.692556 -300.45533) (xy 51.686032 -300.451026)
			(xy 51.671156 -300.446251) (xy 51.663346 -300.445932) (xy 51.147472 -300.445932) (xy 51.142212 -300.445426)
			(xy 51.134772 -300.437985) (xy 51.134264 -300.432724) (xy 45.090062 -300.432724) (xy 45.089702 -300.437896)
			(xy 45.082043 -300.445583) (xy 45.076618 -300.445932) (xy 44.560744 -300.445932) (xy 44.552935 -300.446259)
			(xy 44.538063 -300.451035) (xy 44.531534 -300.45533) (xy 44.510427 -300.469701) (xy 44.464698 -300.492424)
			(xy 44.41602 -300.507848) (xy 44.36555 -300.515607) (xy 44.340018 -300.516036) (xy 44.314488 -300.515596)
			(xy 44.264024 -300.507822) (xy 44.215351 -300.492394) (xy 44.169624 -300.469678) (xy 44.148502 -300.45533)
			(xy 44.141967 -300.451044) (xy 44.1271 -300.446257) (xy 44.119292 -300.445932) (xy 43.603418 -300.445932)
			(xy 43.597978 -300.445606) (xy 43.590289 -300.43791) (xy 43.589956 -300.43247) (xy 37.545772 -300.43247)
			(xy 37.545258 -300.437768) (xy 37.53785 -300.44534) (xy 37.532564 -300.445932) (xy 37.01669 -300.445932)
			(xy 37.008879 -300.446236) (xy 36.994007 -300.451028) (xy 36.98748 -300.45533) (xy 36.96636 -300.469682)
			(xy 36.920636 -300.492408) (xy 36.871962 -300.507838) (xy 36.821495 -300.515604) (xy 36.795964 -300.516036)
			(xy 36.770433 -300.515623) (xy 36.719968 -300.507841) (xy 36.671295 -300.492405) (xy 36.625569 -300.469681)
			(xy 36.604448 -300.45533) (xy 36.597925 -300.451023) (xy 36.583049 -300.446249) (xy 36.575238 -300.445932)
			(xy 36.059364 -300.445932) (xy 36.054103 -300.445431) (xy 36.046664 -300.437986) (xy 36.046156 -300.432724)
			(xy 30.001947 -300.432724) (xy 30.001458 -300.437768) (xy 29.99405 -300.44534) (xy 29.988764 -300.445932)
			(xy 29.47289 -300.445932) (xy 29.465079 -300.446236) (xy 29.450207 -300.451028) (xy 29.44368 -300.45533)
			(xy 29.42256 -300.469682) (xy 29.376836 -300.492408) (xy 29.328162 -300.507838) (xy 29.277695 -300.515604)
			(xy 29.252164 -300.516036) (xy 29.226633 -300.515623) (xy 29.176168 -300.507841) (xy 29.127495 -300.492405)
			(xy 29.081769 -300.469681) (xy 29.060648 -300.45533) (xy 29.054125 -300.451023) (xy 29.039249 -300.446249)
			(xy 29.031438 -300.445932) (xy 28.515564 -300.445932) (xy 28.510303 -300.445431) (xy 28.502864 -300.437986)
			(xy 28.502356 -300.432724) (xy 22.458155 -300.432724) (xy 22.457801 -300.437898) (xy 22.450137 -300.445585)
			(xy 22.44471 -300.445932) (xy 21.928836 -300.445932) (xy 21.921027 -300.446256) (xy 21.906155 -300.451034)
			(xy 21.899626 -300.45533) (xy 21.878493 -300.469662) (xy 21.832773 -300.492393) (xy 21.784104 -300.507828)
			(xy 21.73364 -300.5156) (xy 21.70811 -300.516036) (xy 21.68258 -300.5156) (xy 21.632116 -300.507825)
			(xy 21.583443 -300.492395) (xy 21.537716 -300.469678) (xy 21.516594 -300.45533) (xy 21.510061 -300.451041)
			(xy 21.495192 -300.446256) (xy 21.487384 -300.445932) (xy 20.97151 -300.445932) (xy 20.966069 -300.445611)
			(xy 20.958381 -300.437911) (xy 20.958048 -300.43247) (xy 2.509012 -300.43247) (xy 2.509012 -301.282354)
			(xy 16.85798 -301.282354) (xy 16.85798 -300.787816) (xy 16.858336 -300.782489) (xy 16.865862 -300.774948)
			(xy 16.871188 -300.774608) (xy 16.871696 -300.774608) (xy 17.38757 -300.774608) (xy 17.395379 -300.77428)
			(xy 17.41025 -300.769504) (xy 17.41678 -300.76521) (xy 17.437869 -300.750861) (xy 17.48353 -300.72813)
			(xy 17.532136 -300.712671) (xy 17.582539 -300.704848) (xy 17.633545 -300.704848) (xy 17.683948 -300.712671)
			(xy 17.732554 -300.72813) (xy 17.778215 -300.750861) (xy 17.799304 -300.76521) (xy 17.805835 -300.769502)
			(xy 17.820705 -300.774284) (xy 17.828514 -300.774608) (xy 18.344642 -300.774608) (xy 18.349944 -300.775091)
			(xy 18.357511 -300.782524) (xy 18.358104 -300.787816) (xy 18.358104 -301.282354) (xy 18.358085 -301.282608)
			(xy 24.402288 -301.282608) (xy 24.402288 -301.2821) (xy 24.402288 -300.787816) (xy 24.402637 -300.782487)
			(xy 24.410167 -300.774945) (xy 24.415496 -300.774608) (xy 24.931624 -300.774608) (xy 24.939435 -300.774303)
			(xy 24.954306 -300.769511) (xy 24.960834 -300.76521) (xy 24.981923 -300.750861) (xy 25.027584 -300.72813)
			(xy 25.07619 -300.712671) (xy 25.126593 -300.704848) (xy 25.177599 -300.704848) (xy 25.228002 -300.712671)
			(xy 25.276608 -300.72813) (xy 25.322269 -300.750861) (xy 25.343358 -300.76521) (xy 25.349877 -300.769523)
			(xy 25.364757 -300.774292) (xy 25.372568 -300.774608) (xy 25.888696 -300.774608) (xy 25.894032 -300.774931)
			(xy 25.901574 -300.78248) (xy 25.901904 -300.787816) (xy 25.901904 -301.282354) (xy 25.901877 -301.282608)
			(xy 31.946088 -301.282608) (xy 31.946088 -301.2821) (xy 31.946088 -300.787816) (xy 31.946437 -300.782487)
			(xy 31.953967 -300.774945) (xy 31.959296 -300.774608) (xy 32.475424 -300.774608) (xy 32.483235 -300.774303)
			(xy 32.498106 -300.769511) (xy 32.504634 -300.76521) (xy 32.525723 -300.750861) (xy 32.571384 -300.72813)
			(xy 32.61999 -300.712671) (xy 32.670393 -300.704848) (xy 32.721399 -300.704848) (xy 32.771802 -300.712671)
			(xy 32.820408 -300.72813) (xy 32.866069 -300.750861) (xy 32.887158 -300.76521) (xy 32.893677 -300.769523)
			(xy 32.908557 -300.774292) (xy 32.916368 -300.774608) (xy 33.432496 -300.774608) (xy 33.437832 -300.774931)
			(xy 33.445374 -300.78248) (xy 33.445704 -300.787816) (xy 33.445704 -301.282354) (xy 39.489888 -301.282354)
			(xy 39.489888 -300.787816) (xy 39.490237 -300.782487) (xy 39.497767 -300.774945) (xy 39.503096 -300.774608)
			(xy 39.503604 -300.774608) (xy 40.019478 -300.774608) (xy 40.027287 -300.774284) (xy 40.042158 -300.769505)
			(xy 40.048688 -300.76521) (xy 40.069777 -300.750861) (xy 40.115438 -300.72813) (xy 40.164044 -300.712671)
			(xy 40.214447 -300.704848) (xy 40.265453 -300.704848) (xy 40.315856 -300.712671) (xy 40.364462 -300.72813)
			(xy 40.410123 -300.750861) (xy 40.431212 -300.76521) (xy 40.437741 -300.769506) (xy 40.452613 -300.774286)
			(xy 40.460422 -300.774608) (xy 40.97655 -300.774608) (xy 40.981841 -300.775153) (xy 40.989413 -300.782539)
			(xy 40.990012 -300.787816) (xy 40.990012 -301.282354) (xy 40.989984 -301.282608) (xy 47.034196 -301.282608)
			(xy 47.034196 -301.2821) (xy 47.034196 -300.787816) (xy 47.034538 -300.782485) (xy 47.042073 -300.774943)
			(xy 47.047404 -300.774608) (xy 47.563532 -300.774608) (xy 47.571339 -300.774264) (xy 47.586211 -300.769499)
			(xy 47.592742 -300.76521) (xy 47.613831 -300.750861) (xy 47.659492 -300.72813) (xy 47.708098 -300.712671)
			(xy 47.758501 -300.704848) (xy 47.809507 -300.704848) (xy 47.85991 -300.712671) (xy 47.908516 -300.72813)
			(xy 47.954177 -300.750861) (xy 47.975266 -300.76521) (xy 47.981805 -300.769488) (xy 47.996669 -300.774279)
			(xy 48.004476 -300.774608) (xy 48.520604 -300.774608) (xy 48.525941 -300.774926) (xy 48.533482 -300.782479)
			(xy 48.533812 -300.787816) (xy 48.533812 -301.282354) (xy 54.577996 -301.282354) (xy 54.577996 -300.787816)
			(xy 54.578338 -300.782485) (xy 54.585873 -300.774943) (xy 54.591204 -300.774608) (xy 56.064658 -300.774608)
			(xy 56.06995 -300.775147) (xy 56.077521 -300.782537) (xy 56.07812 -300.787816) (xy 56.07812 -301.282354)
			(xy 56.078104 -301.282608) (xy 163.678108 -301.282608) (xy 163.678108 -301.2821) (xy 163.678108 -300.787816)
			(xy 163.678439 -300.782482) (xy 163.685982 -300.774939) (xy 163.691316 -300.774608) (xy 165.164516 -300.774608)
			(xy 165.169785 -300.775085) (xy 165.177227 -300.782546) (xy 165.177724 -300.787816) (xy 165.177724 -301.282354)
			(xy 171.221908 -301.282354) (xy 171.221908 -300.787816) (xy 171.222239 -300.782482) (xy 171.229782 -300.774939)
			(xy 171.235116 -300.774608) (xy 171.235624 -300.774608) (xy 171.751498 -300.774608) (xy 171.759308 -300.774292)
			(xy 171.774179 -300.769507) (xy 171.780708 -300.76521) (xy 171.801797 -300.750861) (xy 171.847458 -300.72813)
			(xy 171.896064 -300.712671) (xy 171.946467 -300.704848) (xy 171.997473 -300.704848) (xy 172.047876 -300.712671)
			(xy 172.096482 -300.72813) (xy 172.142143 -300.750861) (xy 172.163232 -300.76521) (xy 172.169757 -300.769513)
			(xy 172.184632 -300.774289) (xy 172.192442 -300.774608) (xy 172.70857 -300.774608) (xy 172.713863 -300.775139)
			(xy 172.721434 -300.782535) (xy 172.722032 -300.787816) (xy 172.722032 -301.282354) (xy 172.722016 -301.282608)
			(xy 178.766216 -301.282608) (xy 178.766216 -301.2821) (xy 178.766216 -300.787816) (xy 178.76654 -300.78248)
			(xy 178.774088 -300.774937) (xy 178.779424 -300.774608) (xy 179.295552 -300.774608) (xy 179.30336 -300.774273)
			(xy 179.318232 -300.769501) (xy 179.324762 -300.76521) (xy 179.345851 -300.750861) (xy 179.391512 -300.72813)
			(xy 179.440118 -300.712671) (xy 179.490521 -300.704848) (xy 179.541527 -300.704848) (xy 179.59193 -300.712671)
			(xy 179.640536 -300.72813) (xy 179.686197 -300.750861) (xy 179.707286 -300.76521) (xy 179.713821 -300.769496)
			(xy 179.728688 -300.774282) (xy 179.736496 -300.774608) (xy 180.252624 -300.774608) (xy 180.257893 -300.775081)
			(xy 180.265335 -300.782545) (xy 180.265832 -300.787816) (xy 180.265832 -301.282354) (xy 186.310016 -301.282354)
			(xy 186.310016 -300.787816) (xy 186.31034 -300.78248) (xy 186.317888 -300.774937) (xy 186.323224 -300.774608)
			(xy 186.323732 -300.774608) (xy 186.839606 -300.774608) (xy 186.847416 -300.774296) (xy 186.862287 -300.769508)
			(xy 186.868816 -300.76521) (xy 186.889905 -300.750861) (xy 186.935566 -300.72813) (xy 186.984172 -300.712671)
			(xy 187.034575 -300.704848) (xy 187.085581 -300.704848) (xy 187.135984 -300.712671) (xy 187.18459 -300.72813)
			(xy 187.230251 -300.750861) (xy 187.25134 -300.76521) (xy 187.257863 -300.769516) (xy 187.27274 -300.77429)
			(xy 187.28055 -300.774608) (xy 187.796678 -300.774608) (xy 187.801972 -300.775134) (xy 187.809543 -300.782534)
			(xy 187.81014 -300.787816) (xy 187.81014 -301.282354) (xy 187.810124 -301.282608) (xy 193.854324 -301.282608)
			(xy 193.854324 -301.2821) (xy 193.854324 -300.787816) (xy 193.854641 -300.782478) (xy 193.862194 -300.774934)
			(xy 193.867532 -300.774608) (xy 194.38366 -300.774608) (xy 194.391468 -300.774276) (xy 194.40634 -300.769502)
			(xy 194.41287 -300.76521) (xy 194.433959 -300.750861) (xy 194.47962 -300.72813) (xy 194.528226 -300.712671)
			(xy 194.578629 -300.704848) (xy 194.629635 -300.704848) (xy 194.680038 -300.712671) (xy 194.728644 -300.72813)
			(xy 194.774305 -300.750861) (xy 194.795394 -300.76521) (xy 194.801927 -300.769499) (xy 194.816796 -300.774283)
			(xy 194.824604 -300.774608) (xy 195.340732 -300.774608) (xy 195.346002 -300.775075) (xy 195.353444 -300.782544)
			(xy 195.35394 -300.787816) (xy 195.35394 -301.282354) (xy 195.353916 -301.282608) (xy 201.398124 -301.282608)
			(xy 201.398124 -301.2821) (xy 201.398124 -300.787816) (xy 201.398441 -300.782478) (xy 201.405994 -300.774934)
			(xy 201.411332 -300.774608) (xy 201.92746 -300.774608) (xy 201.935268 -300.774276) (xy 201.95014 -300.769502)
			(xy 201.95667 -300.76521) (xy 201.977759 -300.750861) (xy 202.02342 -300.72813) (xy 202.072026 -300.712671)
			(xy 202.122429 -300.704848) (xy 202.173435 -300.704848) (xy 202.223838 -300.712671) (xy 202.272444 -300.72813)
			(xy 202.318105 -300.750861) (xy 202.339194 -300.76521) (xy 202.345727 -300.769499) (xy 202.360596 -300.774283)
			(xy 202.368404 -300.774608) (xy 202.884532 -300.774608) (xy 202.889802 -300.775075) (xy 202.897244 -300.782544)
			(xy 202.89774 -300.787816) (xy 202.89774 -301.2821) (xy 264.798048 -301.2821) (xy 264.798048 -300.787562)
			(xy 264.798526 -300.782191) (xy 264.806137 -300.774607) (xy 264.81151 -300.7741) (xy 265.327638 -300.7741)
			(xy 265.335446 -300.77376) (xy 265.350317 -300.768992) (xy 265.356848 -300.764702) (xy 265.377937 -300.750353)
			(xy 265.423598 -300.727622) (xy 265.472204 -300.712163) (xy 265.522607 -300.70434) (xy 265.573613 -300.70434)
			(xy 265.624016 -300.712163) (xy 265.672622 -300.727622) (xy 265.718283 -300.750353) (xy 265.739372 -300.764702)
			(xy 265.74591 -300.768982) (xy 265.760775 -300.773772) (xy 265.768582 -300.7741) (xy 266.28471 -300.7741)
			(xy 266.290066 -300.77464) (xy 266.297649 -300.782207) (xy 266.298172 -300.787562) (xy 266.298172 -301.2821)
			(xy 272.342356 -301.2821) (xy 272.342356 -300.787562) (xy 272.3428 -300.782249) (xy 272.35026 -300.77468)
			(xy 272.355564 -300.7741) (xy 272.871692 -300.7741) (xy 272.879502 -300.773783) (xy 272.894373 -300.768999)
			(xy 272.900902 -300.764702) (xy 272.921991 -300.750353) (xy 272.967652 -300.727622) (xy 273.016258 -300.712163)
			(xy 273.066661 -300.70434) (xy 273.117667 -300.70434) (xy 273.16807 -300.712163) (xy 273.216676 -300.727622)
			(xy 273.262337 -300.750353) (xy 273.283426 -300.764702) (xy 273.289952 -300.769002) (xy 273.304826 -300.77378)
			(xy 273.312636 -300.7741) (xy 273.828764 -300.7741) (xy 273.834093 -300.774452) (xy 273.841637 -300.781979)
			(xy 273.841972 -300.787308) (xy 273.841972 -300.787816) (xy 273.841972 -301.2821) (xy 279.886156 -301.2821)
			(xy 279.886156 -300.787562) (xy 279.8866 -300.782249) (xy 279.89406 -300.77468) (xy 279.899364 -300.7741)
			(xy 280.415492 -300.7741) (xy 280.423302 -300.773783) (xy 280.438173 -300.768999) (xy 280.444702 -300.764702)
			(xy 280.465791 -300.750353) (xy 280.511452 -300.727622) (xy 280.560058 -300.712163) (xy 280.610461 -300.70434)
			(xy 280.661467 -300.70434) (xy 280.71187 -300.712163) (xy 280.760476 -300.727622) (xy 280.806137 -300.750353)
			(xy 280.827226 -300.764702) (xy 280.833752 -300.769002) (xy 280.848626 -300.77378) (xy 280.856436 -300.7741)
			(xy 281.372564 -300.7741) (xy 281.377893 -300.774452) (xy 281.385437 -300.781979) (xy 281.385772 -300.787308)
			(xy 281.385772 -300.787816) (xy 281.385772 -301.2821) (xy 287.429956 -301.2821) (xy 287.429956 -300.787562)
			(xy 287.430427 -300.782189) (xy 287.438043 -300.774605) (xy 287.443418 -300.7741) (xy 287.959546 -300.7741)
			(xy 287.967354 -300.773764) (xy 287.982226 -300.768993) (xy 287.988756 -300.764702) (xy 288.009845 -300.750353)
			(xy 288.055506 -300.727622) (xy 288.104112 -300.712163) (xy 288.154515 -300.70434) (xy 288.205521 -300.70434)
			(xy 288.255924 -300.712163) (xy 288.30453 -300.727622) (xy 288.350191 -300.750353) (xy 288.37128 -300.764702)
			(xy 288.377817 -300.768985) (xy 288.392683 -300.773773) (xy 288.40049 -300.7741) (xy 288.916618 -300.7741)
			(xy 288.921975 -300.774634) (xy 288.929558 -300.782206) (xy 288.93008 -300.787562) (xy 288.93008 -301.2821)
			(xy 294.974264 -301.2821) (xy 294.974264 -300.787562) (xy 294.974701 -300.782248) (xy 294.982165 -300.774677)
			(xy 294.987472 -300.7741) (xy 295.5036 -300.7741) (xy 295.51141 -300.773786) (xy 295.526281 -300.769)
			(xy 295.53281 -300.764702) (xy 295.553899 -300.750353) (xy 295.59956 -300.727622) (xy 295.648166 -300.712163)
			(xy 295.698569 -300.70434) (xy 295.749575 -300.70434) (xy 295.799978 -300.712163) (xy 295.848584 -300.727622)
			(xy 295.894245 -300.750353) (xy 295.915334 -300.764702) (xy 295.921859 -300.769005) (xy 295.936734 -300.773781)
			(xy 295.944544 -300.7741) (xy 296.460672 -300.7741) (xy 296.466003 -300.774446) (xy 296.473546 -300.781978)
			(xy 296.47388 -300.787308) (xy 296.47388 -300.787816) (xy 296.47388 -301.2821) (xy 302.518064 -301.2821)
			(xy 302.518064 -300.787562) (xy 302.518528 -300.782187) (xy 302.526149 -300.774602) (xy 302.531526 -300.7741)
			(xy 304.004726 -300.7741) (xy 304.010084 -300.774629) (xy 304.017666 -300.782205) (xy 304.018188 -300.787562)
			(xy 304.018188 -301.2821) (xy 411.618176 -301.2821) (xy 411.618176 -300.787562) (xy 411.618602 -300.782245)
			(xy 411.626074 -300.774674) (xy 411.631384 -300.7741) (xy 413.104584 -300.7741) (xy 413.109916 -300.774438)
			(xy 413.117458 -300.781976) (xy 413.117792 -300.787308) (xy 413.117792 -300.787816) (xy 413.117792 -301.2821)
			(xy 419.161976 -301.2821) (xy 419.161976 -300.787562) (xy 419.162429 -300.782184) (xy 419.170058 -300.774599)
			(xy 419.175438 -300.7741) (xy 419.691566 -300.7741) (xy 419.699375 -300.773772) (xy 419.714246 -300.768996)
			(xy 419.720776 -300.764702) (xy 419.741865 -300.750353) (xy 419.787526 -300.727622) (xy 419.836132 -300.712163)
			(xy 419.886535 -300.70434) (xy 419.937541 -300.70434) (xy 419.987944 -300.712163) (xy 420.03655 -300.727622)
			(xy 420.082211 -300.750353) (xy 420.1033 -300.764702) (xy 420.109832 -300.768992) (xy 420.124702 -300.773776)
			(xy 420.13251 -300.7741) (xy 420.648638 -300.7741) (xy 420.653997 -300.774621) (xy 420.661579 -300.782203)
			(xy 420.6621 -300.787562) (xy 420.6621 -301.2821) (xy 426.706284 -301.2821) (xy 426.706284 -300.787562)
			(xy 426.706703 -300.782243) (xy 426.71418 -300.774672) (xy 426.719492 -300.7741) (xy 427.23562 -300.7741)
			(xy 427.243431 -300.773795) (xy 427.258302 -300.769003) (xy 427.26483 -300.764702) (xy 427.285919 -300.750353)
			(xy 427.33158 -300.727622) (xy 427.380186 -300.712163) (xy 427.430589 -300.70434) (xy 427.481595 -300.70434)
			(xy 427.531998 -300.712163) (xy 427.580604 -300.727622) (xy 427.626265 -300.750353) (xy 427.647354 -300.764702)
			(xy 427.653874 -300.769013) (xy 427.668753 -300.773784) (xy 427.676564 -300.7741) (xy 428.192692 -300.7741)
			(xy 428.198025 -300.774433) (xy 428.205567 -300.781975) (xy 428.2059 -300.787308) (xy 428.2059 -300.787816)
			(xy 428.2059 -301.2821) (xy 434.250084 -301.2821) (xy 434.250084 -300.787562) (xy 434.250358 -300.782111)
			(xy 434.258093 -300.774424) (xy 434.263546 -300.7741) (xy 434.779674 -300.7741) (xy 434.787483 -300.773775)
			(xy 434.802355 -300.768997) (xy 434.808884 -300.764702) (xy 434.829973 -300.750353) (xy 434.875634 -300.727622)
			(xy 434.92424 -300.712163) (xy 434.974643 -300.70434) (xy 435.025649 -300.70434) (xy 435.076052 -300.712163)
			(xy 435.124658 -300.727622) (xy 435.170319 -300.750353) (xy 435.191408 -300.764702) (xy 435.197938 -300.768995)
			(xy 435.212809 -300.773777) (xy 435.220618 -300.7741) (xy 435.736746 -300.7741) (xy 435.742106 -300.774616)
			(xy 435.749687 -300.782201) (xy 435.750208 -300.787562) (xy 435.750208 -301.2821) (xy 441.794392 -301.2821)
			(xy 441.794392 -300.787562) (xy 441.794892 -300.782264) (xy 441.802313 -300.774698) (xy 441.8076 -300.7741)
			(xy 442.323728 -300.7741) (xy 442.331539 -300.773798) (xy 442.34641 -300.769004) (xy 442.352938 -300.764702)
			(xy 442.374027 -300.750353) (xy 442.419688 -300.727622) (xy 442.468294 -300.712163) (xy 442.518697 -300.70434)
			(xy 442.569703 -300.70434) (xy 442.620106 -300.712163) (xy 442.668712 -300.727622) (xy 442.714373 -300.750353)
			(xy 442.735462 -300.764702) (xy 442.742003 -300.768978) (xy 442.756866 -300.77377) (xy 442.764672 -300.7741)
			(xy 443.2808 -300.7741) (xy 443.286134 -300.774427) (xy 443.293676 -300.781974) (xy 443.294008 -300.787308)
			(xy 443.294008 -300.787816) (xy 443.294008 -301.2821) (xy 449.338192 -301.2821) (xy 449.338192 -300.787562)
			(xy 449.338692 -300.782264) (xy 449.346113 -300.774698) (xy 449.3514 -300.7741) (xy 449.867528 -300.7741)
			(xy 449.875339 -300.773798) (xy 449.89021 -300.769004) (xy 449.896738 -300.764702) (xy 449.917827 -300.750353)
			(xy 449.963488 -300.727622) (xy 450.012094 -300.712163) (xy 450.062497 -300.70434) (xy 450.113503 -300.70434)
			(xy 450.163906 -300.712163) (xy 450.212512 -300.727622) (xy 450.258173 -300.750353) (xy 450.279262 -300.764702)
			(xy 450.285803 -300.768978) (xy 450.300666 -300.77377) (xy 450.308472 -300.7741) (xy 450.8246 -300.7741)
			(xy 450.829934 -300.774427) (xy 450.837476 -300.781974) (xy 450.837808 -300.787308) (xy 450.837808 -300.787816)
			(xy 450.837808 -301.2821) (xy 450.837305 -301.287363) (xy 450.829863 -301.294805) (xy 450.8246 -301.295308)
			(xy 450.308726 -301.295308) (xy 450.30085 -301.295579) (xy 450.285847 -301.300375) (xy 450.279262 -301.304706)
			(xy 450.258182 -301.319094) (xy 450.212539 -301.341924) (xy 450.163933 -301.357483) (xy 450.113517 -301.365403)
			(xy 450.088 -301.36592) (xy 450.062479 -301.365444) (xy 450.012052 -301.357545) (xy 449.963441 -301.341981)
			(xy 449.917803 -301.319122) (xy 449.896738 -301.304706) (xy 449.890139 -301.300403) (xy 449.875145 -301.295609)
			(xy 449.867274 -301.295308) (xy 449.3514 -301.295308) (xy 449.346137 -301.294805) (xy 449.338695 -301.287363)
			(xy 449.338192 -301.2821) (xy 443.294008 -301.2821) (xy 443.293505 -301.287363) (xy 443.286063 -301.294805)
			(xy 443.2808 -301.295308) (xy 442.764926 -301.295308) (xy 442.75705 -301.295579) (xy 442.742047 -301.300375)
			(xy 442.735462 -301.304706) (xy 442.714382 -301.319094) (xy 442.668739 -301.341924) (xy 442.620133 -301.357483)
			(xy 442.569717 -301.365403) (xy 442.5442 -301.36592) (xy 442.518679 -301.365444) (xy 442.468252 -301.357545)
			(xy 442.419641 -301.341981) (xy 442.374003 -301.319122) (xy 442.352938 -301.304706) (xy 442.346339 -301.300403)
			(xy 442.331345 -301.295609) (xy 442.323474 -301.295308) (xy 441.8076 -301.295308) (xy 441.802337 -301.294805)
			(xy 441.794895 -301.287363) (xy 441.794392 -301.2821) (xy 435.750208 -301.2821) (xy 435.749705 -301.287363)
			(xy 435.742263 -301.294805) (xy 435.737 -301.295308) (xy 435.736492 -301.295308) (xy 435.220872 -301.295308)
			(xy 435.212998 -301.295598) (xy 435.197994 -301.300381) (xy 435.191408 -301.304706) (xy 435.170343 -301.319117)
			(xy 435.124694 -301.341942) (xy 435.076084 -301.357495) (xy 435.025664 -301.365407) (xy 435.000146 -301.36592)
			(xy 434.974626 -301.365421) (xy 434.9242 -301.357528) (xy 434.875588 -301.341971) (xy 434.829949 -301.31912)
			(xy 434.808884 -301.304706) (xy 434.802298 -301.300382) (xy 434.787294 -301.295601) (xy 434.77942 -301.295308)
			(xy 434.263546 -301.295308) (xy 434.258258 -301.294752) (xy 434.250687 -301.287374) (xy 434.250084 -301.2821)
			(xy 428.2059 -301.2821) (xy 428.205573 -301.287434) (xy 428.198026 -301.294976) (xy 428.192692 -301.295308)
			(xy 427.676818 -301.295308) (xy 427.668946 -301.295618) (xy 427.653942 -301.300387) (xy 427.647354 -301.304706)
			(xy 427.626276 -301.319097) (xy 427.580632 -301.341927) (xy 427.532026 -301.357485) (xy 427.481609 -301.365403)
			(xy 427.456092 -301.36592) (xy 427.430573 -301.365398) (xy 427.380148 -301.357512) (xy 427.331536 -301.341962)
			(xy 427.285896 -301.319117) (xy 427.26483 -301.304706) (xy 427.258233 -301.3004) (xy 427.243237 -301.295608)
			(xy 427.235366 -301.295308) (xy 426.719492 -301.295308) (xy 426.714228 -301.294811) (xy 426.706786 -301.287364)
			(xy 426.706284 -301.2821) (xy 420.6621 -301.2821) (xy 420.661773 -301.287434) (xy 420.654226 -301.294976)
			(xy 420.648892 -301.295308) (xy 420.648384 -301.295308) (xy 420.132764 -301.295308) (xy 420.12489 -301.295595)
			(xy 420.109886 -301.30038) (xy 420.1033 -301.304706) (xy 420.08221 -301.319078) (xy 420.03657 -301.341912)
			(xy 419.987968 -301.357475) (xy 419.937554 -301.3654) (xy 419.912038 -301.36592) (xy 419.886518 -301.365425)
			(xy 419.836092 -301.357531) (xy 419.78748 -301.341973) (xy 419.741841 -301.31912) (xy 419.720776 -301.304706)
			(xy 419.714191 -301.300379) (xy 419.699186 -301.2956) (xy 419.691312 -301.295308) (xy 419.175438 -301.295308)
			(xy 419.17015 -301.294757) (xy 419.162579 -301.287375) (xy 419.161976 -301.2821) (xy 413.117792 -301.2821)
			(xy 413.117472 -301.287436) (xy 413.109921 -301.294978) (xy 413.104584 -301.295308) (xy 411.631384 -301.295308)
			(xy 411.626119 -301.294816) (xy 411.618678 -301.287365) (xy 411.618176 -301.2821) (xy 304.018188 -301.2821)
			(xy 304.017871 -301.287437) (xy 304.010318 -301.294979) (xy 304.00498 -301.295308) (xy 302.531526 -301.295308)
			(xy 302.526236 -301.294765) (xy 302.518666 -301.287377) (xy 302.518064 -301.2821) (xy 296.47388 -301.2821)
			(xy 296.473571 -301.287439) (xy 296.466012 -301.294982) (xy 296.460672 -301.295308) (xy 295.944798 -301.295308)
			(xy 295.936925 -301.295609) (xy 295.921921 -301.300384) (xy 295.915334 -301.304706) (xy 295.894262 -301.319106)
			(xy 295.848616 -301.341934) (xy 295.800008 -301.357489) (xy 295.749589 -301.365405) (xy 295.724072 -301.36592)
			(xy 295.698553 -301.365408) (xy 295.648127 -301.357519) (xy 295.599515 -301.341966) (xy 295.553876 -301.319118)
			(xy 295.53281 -301.304706) (xy 295.526218 -301.300393) (xy 295.511218 -301.295605) (xy 295.503346 -301.295308)
			(xy 294.987472 -301.295308) (xy 294.982206 -301.294824) (xy 294.974765 -301.287367) (xy 294.974264 -301.2821)
			(xy 288.93008 -301.2821) (xy 288.929771 -301.287439) (xy 288.922212 -301.294982) (xy 288.916872 -301.295308)
			(xy 288.916364 -301.295308) (xy 288.400744 -301.295308) (xy 288.392869 -301.295586) (xy 288.377865 -301.300377)
			(xy 288.37128 -301.304706) (xy 288.350195 -301.319086) (xy 288.304553 -301.341918) (xy 288.25595 -301.35748)
			(xy 288.205534 -301.365402) (xy 288.180018 -301.36592) (xy 288.154498 -301.365435) (xy 288.104071 -301.357538)
			(xy 288.055459 -301.341977) (xy 288.009821 -301.319121) (xy 287.988756 -301.304706) (xy 287.982176 -301.300372)
			(xy 287.967167 -301.295597) (xy 287.959292 -301.295308) (xy 287.443418 -301.295308) (xy 287.438127 -301.294771)
			(xy 287.430558 -301.287378) (xy 287.429956 -301.2821) (xy 281.385772 -301.2821) (xy 281.38547 -301.287441)
			(xy 281.377906 -301.294984) (xy 281.372564 -301.295308) (xy 280.85669 -301.295308) (xy 280.848816 -301.295606)
			(xy 280.833813 -301.300383) (xy 280.827226 -301.304706) (xy 280.806156 -301.319109) (xy 280.760509 -301.341936)
			(xy 280.711901 -301.357491) (xy 280.661481 -301.365406) (xy 280.635964 -301.36592) (xy 280.610445 -301.365412)
			(xy 280.560019 -301.357522) (xy 280.511407 -301.341968) (xy 280.465768 -301.319118) (xy 280.444702 -301.304706)
			(xy 280.438111 -301.300389) (xy 280.423111 -301.295603) (xy 280.415238 -301.295308) (xy 279.899364 -301.295308)
			(xy 279.894097 -301.294829) (xy 279.886657 -301.287368) (xy 279.886156 -301.2821) (xy 273.841972 -301.2821)
			(xy 273.84167 -301.287441) (xy 273.834106 -301.294984) (xy 273.828764 -301.295308) (xy 273.31289 -301.295308)
			(xy 273.305016 -301.295606) (xy 273.290013 -301.300383) (xy 273.283426 -301.304706) (xy 273.262356 -301.319109)
			(xy 273.216709 -301.341936) (xy 273.168101 -301.357491) (xy 273.117681 -301.365406) (xy 273.092164 -301.36592)
			(xy 273.066645 -301.365412) (xy 273.016219 -301.357522) (xy 272.967607 -301.341968) (xy 272.921968 -301.319118)
			(xy 272.900902 -301.304706) (xy 272.894311 -301.300389) (xy 272.879311 -301.295603) (xy 272.871438 -301.295308)
			(xy 272.355564 -301.295308) (xy 272.350297 -301.294829) (xy 272.342857 -301.287368) (xy 272.342356 -301.2821)
			(xy 266.298172 -301.2821) (xy 266.29787 -301.287441) (xy 266.290306 -301.294984) (xy 266.284964 -301.295308)
			(xy 266.284456 -301.295308) (xy 265.768836 -301.295308) (xy 265.76096 -301.295583) (xy 265.745957 -301.300376)
			(xy 265.739372 -301.304706) (xy 265.718289 -301.31909) (xy 265.672647 -301.341921) (xy 265.624042 -301.357481)
			(xy 265.573626 -301.365402) (xy 265.54811 -301.36592) (xy 265.52259 -301.365439) (xy 265.472162 -301.357541)
			(xy 265.423551 -301.341979) (xy 265.377913 -301.319122) (xy 265.356848 -301.304706) (xy 265.35027 -301.300369)
			(xy 265.335259 -301.295596) (xy 265.327384 -301.295308) (xy 264.81151 -301.295308) (xy 264.806218 -301.294776)
			(xy 264.798649 -301.287379) (xy 264.798048 -301.2821) (xy 202.89774 -301.2821) (xy 202.89774 -301.282354)
			(xy 202.897244 -301.287657) (xy 202.889824 -301.295232) (xy 202.884532 -301.295816) (xy 202.368658 -301.295816)
			(xy 202.36085 -301.296152) (xy 202.345978 -301.300922) (xy 202.339448 -301.305214) (xy 202.318335 -301.319577)
			(xy 202.272609 -301.342302) (xy 202.223933 -301.357728) (xy 202.173464 -301.36549) (xy 202.147932 -301.36592)
			(xy 202.122402 -301.365475) (xy 202.071938 -301.357703) (xy 202.023265 -301.342277) (xy 201.977538 -301.319561)
			(xy 201.956416 -301.305214) (xy 201.949879 -301.300931) (xy 201.935013 -301.296143) (xy 201.927206 -301.295816)
			(xy 201.411332 -301.295816) (xy 201.406006 -301.295452) (xy 201.398464 -301.287933) (xy 201.398124 -301.282608)
			(xy 195.353916 -301.282608) (xy 195.353444 -301.287657) (xy 195.346024 -301.295232) (xy 195.340732 -301.295816)
			(xy 194.824858 -301.295816) (xy 194.81705 -301.296152) (xy 194.802178 -301.300922) (xy 194.795648 -301.305214)
			(xy 194.774535 -301.319577) (xy 194.728809 -301.342302) (xy 194.680133 -301.357728) (xy 194.629664 -301.36549)
			(xy 194.604132 -301.36592) (xy 194.578602 -301.365475) (xy 194.528138 -301.357703) (xy 194.479465 -301.342277)
			(xy 194.433738 -301.319561) (xy 194.412616 -301.305214) (xy 194.406079 -301.300931) (xy 194.391213 -301.296143)
			(xy 194.383406 -301.295816) (xy 193.867532 -301.295816) (xy 193.862206 -301.295452) (xy 193.854664 -301.287933)
			(xy 193.854324 -301.282608) (xy 187.810124 -301.282608) (xy 187.809788 -301.287788) (xy 187.802111 -301.295478)
			(xy 187.796678 -301.295816) (xy 187.280804 -301.295816) (xy 187.272994 -301.296129) (xy 187.258122 -301.300915)
			(xy 187.251594 -301.305214) (xy 187.230469 -301.319558) (xy 187.184747 -301.342287) (xy 187.136074 -301.357719)
			(xy 187.085609 -301.365486) (xy 187.060078 -301.36592) (xy 187.034547 -301.365503) (xy 186.984082 -301.357722)
			(xy 186.935409 -301.342288) (xy 186.889683 -301.319565) (xy 186.868562 -301.305214) (xy 186.862037 -301.300911)
			(xy 186.847162 -301.296135) (xy 186.839352 -301.295816) (xy 186.323478 -301.295816) (xy 186.318029 -301.295531)
			(xy 186.310342 -301.287805) (xy 186.310016 -301.282354) (xy 180.265832 -301.282354) (xy 180.265343 -301.287659)
			(xy 180.257918 -301.295234) (xy 180.252624 -301.295816) (xy 179.73675 -301.295816) (xy 179.728942 -301.296148)
			(xy 179.71407 -301.300921) (xy 179.70754 -301.305214) (xy 179.68643 -301.319581) (xy 179.640702 -301.342305)
			(xy 179.592025 -301.35773) (xy 179.541556 -301.365491) (xy 179.516024 -301.36592) (xy 179.490494 -301.365479)
			(xy 179.44003 -301.357706) (xy 179.391357 -301.342278) (xy 179.34563 -301.319562) (xy 179.324508 -301.305214)
			(xy 179.317973 -301.300928) (xy 179.303106 -301.296142) (xy 179.295298 -301.295816) (xy 178.779424 -301.295816)
			(xy 178.774097 -301.295458) (xy 178.766555 -301.287934) (xy 178.766216 -301.282608) (xy 172.722016 -301.282608)
			(xy 172.721687 -301.28779) (xy 172.714006 -301.295481) (xy 172.70857 -301.295816) (xy 172.192696 -301.295816)
			(xy 172.184885 -301.296125) (xy 172.170014 -301.300914) (xy 172.163486 -301.305214) (xy 172.142363 -301.319561)
			(xy 172.09664 -301.342289) (xy 172.047967 -301.35772) (xy 171.997501 -301.365487) (xy 171.97197 -301.36592)
			(xy 171.946439 -301.365507) (xy 171.895974 -301.357725) (xy 171.847301 -301.342289) (xy 171.801575 -301.319565)
			(xy 171.780454 -301.305214) (xy 171.773931 -301.300908) (xy 171.759055 -301.296134) (xy 171.751244 -301.295816)
			(xy 171.23537 -301.295816) (xy 171.22992 -301.295536) (xy 171.222233 -301.287806) (xy 171.221908 -301.282354)
			(xy 165.177724 -301.282354) (xy 165.177242 -301.287661) (xy 165.169813 -301.295237) (xy 165.164516 -301.295816)
			(xy 163.691316 -301.295816) (xy 163.685988 -301.295463) (xy 163.678446 -301.287936) (xy 163.678108 -301.282608)
			(xy 56.078104 -301.282608) (xy 56.077786 -301.287793) (xy 56.070097 -301.295484) (xy 56.064658 -301.295816)
			(xy 54.591458 -301.295816) (xy 54.586006 -301.295544) (xy 54.57832 -301.287808) (xy 54.577996 -301.282354)
			(xy 48.533812 -301.282354) (xy 48.53334 -301.287664) (xy 48.525904 -301.29524) (xy 48.520604 -301.295816)
			(xy 48.00473 -301.295816) (xy 47.996921 -301.29614) (xy 47.982049 -301.300918) (xy 47.97552 -301.305214)
			(xy 47.954387 -301.319546) (xy 47.908668 -301.342278) (xy 47.859998 -301.357713) (xy 47.809534 -301.365484)
			(xy 47.784004 -301.36592) (xy 47.758473 -301.365489) (xy 47.708009 -301.357713) (xy 47.659336 -301.342282)
			(xy 47.613609 -301.319563) (xy 47.592488 -301.305214) (xy 47.585958 -301.300921) (xy 47.571087 -301.296139)
			(xy 47.563278 -301.295816) (xy 47.047404 -301.295816) (xy 47.042144 -301.295303) (xy 47.034701 -301.287868)
			(xy 47.034196 -301.282608) (xy 40.989984 -301.282608) (xy 40.989424 -301.287701) (xy 40.981893 -301.295286)
			(xy 40.97655 -301.295816) (xy 40.460676 -301.295816) (xy 40.452865 -301.296117) (xy 40.437993 -301.300911)
			(xy 40.431466 -301.305214) (xy 40.410348 -301.31957) (xy 40.364624 -301.342296) (xy 40.315949 -301.357725)
			(xy 40.265481 -301.365489) (xy 40.23995 -301.36592) (xy 40.21442 -301.365466) (xy 40.163957 -301.357697)
			(xy 40.115284 -301.342273) (xy 40.069556 -301.31956) (xy 40.048434 -301.305214) (xy 40.041893 -301.300938)
			(xy 40.02703 -301.296145) (xy 40.019224 -301.295816) (xy 39.50335 -301.295816) (xy 39.497969 -301.295378)
			(xy 39.490384 -301.287738) (xy 39.489888 -301.282354) (xy 33.445704 -301.282354) (xy 33.445151 -301.287643)
			(xy 33.437771 -301.295214) (xy 33.432496 -301.295816) (xy 32.916622 -301.295816) (xy 32.908812 -301.296136)
			(xy 32.893941 -301.300917) (xy 32.887412 -301.305214) (xy 32.866282 -301.31955) (xy 32.820561 -301.342281)
			(xy 32.771891 -301.357715) (xy 32.721426 -301.365485) (xy 32.695896 -301.36592) (xy 32.670365 -301.365493)
			(xy 32.619901 -301.357716) (xy 32.571228 -301.342284) (xy 32.525501 -301.319564) (xy 32.50438 -301.305214)
			(xy 32.497851 -301.300918) (xy 32.482979 -301.296137) (xy 32.47517 -301.295816) (xy 31.959296 -301.295816)
			(xy 31.954035 -301.295309) (xy 31.946593 -301.287869) (xy 31.946088 -301.282608) (xy 25.901877 -301.282608)
			(xy 25.901351 -301.287643) (xy 25.893971 -301.295214) (xy 25.888696 -301.295816) (xy 25.372822 -301.295816)
			(xy 25.365012 -301.296136) (xy 25.350141 -301.300917) (xy 25.343612 -301.305214) (xy 25.322482 -301.31955)
			(xy 25.276761 -301.342281) (xy 25.228091 -301.357715) (xy 25.177626 -301.365485) (xy 25.152096 -301.36592)
			(xy 25.126565 -301.365493) (xy 25.076101 -301.357716) (xy 25.027428 -301.342284) (xy 24.981701 -301.319564)
			(xy 24.96058 -301.305214) (xy 24.954051 -301.300918) (xy 24.939179 -301.296137) (xy 24.93137 -301.295816)
			(xy 24.415496 -301.295816) (xy 24.410235 -301.295309) (xy 24.402793 -301.287869) (xy 24.402288 -301.282608)
			(xy 18.358085 -301.282608) (xy 18.357694 -301.287773) (xy 18.350058 -301.295459) (xy 18.344642 -301.295816)
			(xy 17.828768 -301.295816) (xy 17.82096 -301.296156) (xy 17.806089 -301.300924) (xy 17.799558 -301.305214)
			(xy 17.778443 -301.319573) (xy 17.732717 -301.342299) (xy 17.684042 -301.357726) (xy 17.633574 -301.365489)
			(xy 17.608042 -301.36592) (xy 17.582512 -301.36547) (xy 17.532048 -301.3577) (xy 17.483376 -301.342275)
			(xy 17.437648 -301.319561) (xy 17.416526 -301.305214) (xy 17.409987 -301.300935) (xy 17.395123 -301.296144)
			(xy 17.387316 -301.295816) (xy 16.871442 -301.295816) (xy 16.866002 -301.295488) (xy 16.85831 -301.287794)
			(xy 16.85798 -301.282354) (xy 2.509012 -301.282354) (xy 2.509012 -302.132492) (xy 20.958048 -302.132492)
			(xy 20.958048 -301.637954) (xy 20.958521 -301.632582) (xy 20.966136 -301.624999) (xy 20.97151 -301.624492)
			(xy 21.487638 -301.624492) (xy 21.495446 -301.624153) (xy 21.510317 -301.619384) (xy 21.516848 -301.615094)
			(xy 21.537937 -301.600745) (xy 21.583598 -301.578014) (xy 21.632204 -301.562555) (xy 21.682607 -301.554732)
			(xy 21.733613 -301.554732) (xy 21.784016 -301.562555) (xy 21.832622 -301.578014) (xy 21.878283 -301.600745)
			(xy 21.899372 -301.615094) (xy 21.905911 -301.619373) (xy 21.920775 -301.624164) (xy 21.928582 -301.624492)
			(xy 22.44471 -301.624492) (xy 22.450064 -301.625039) (xy 22.457647 -301.632601) (xy 22.458172 -301.637954)
			(xy 22.458172 -302.132492) (xy 28.502356 -302.132492) (xy 28.502356 -301.637954) (xy 28.502861 -301.632653)
			(xy 28.510274 -301.625077) (xy 28.515564 -301.624492) (xy 29.031692 -301.624492) (xy 29.039502 -301.624176)
			(xy 29.054373 -301.619392) (xy 29.060902 -301.615094) (xy 29.081991 -301.600745) (xy 29.127652 -301.578014)
			(xy 29.176258 -301.562555) (xy 29.226661 -301.554732) (xy 29.277667 -301.554732) (xy 29.32807 -301.562555)
			(xy 29.376676 -301.578014) (xy 29.422337 -301.600745) (xy 29.443426 -301.615094) (xy 29.449953 -301.619393)
			(xy 29.464826 -301.624172) (xy 29.472636 -301.624492) (xy 29.988764 -301.624492) (xy 29.994092 -301.624851)
			(xy 30.001635 -301.632373) (xy 30.001972 -301.6377) (xy 30.001972 -301.638208) (xy 30.001972 -302.132492)
			(xy 36.046156 -302.132492) (xy 36.046156 -301.637954) (xy 36.046661 -301.632653) (xy 36.054074 -301.625077)
			(xy 36.059364 -301.624492) (xy 36.575492 -301.624492) (xy 36.583302 -301.624176) (xy 36.598173 -301.619392)
			(xy 36.604702 -301.615094) (xy 36.625791 -301.600745) (xy 36.671452 -301.578014) (xy 36.720058 -301.562555)
			(xy 36.770461 -301.554732) (xy 36.821467 -301.554732) (xy 36.87187 -301.562555) (xy 36.920476 -301.578014)
			(xy 36.966137 -301.600745) (xy 36.987226 -301.615094) (xy 36.993753 -301.619393) (xy 37.008626 -301.624172)
			(xy 37.016436 -301.624492) (xy 37.532564 -301.624492) (xy 37.537892 -301.624851) (xy 37.545435 -301.632373)
			(xy 37.545772 -301.6377) (xy 37.545772 -301.638208) (xy 37.545772 -302.132492) (xy 43.589956 -302.132492)
			(xy 43.589956 -301.637954) (xy 43.590422 -301.63258) (xy 43.598042 -301.624996) (xy 43.603418 -301.624492)
			(xy 44.119546 -301.624492) (xy 44.127354 -301.624157) (xy 44.142226 -301.619386) (xy 44.148756 -301.615094)
			(xy 44.169845 -301.600745) (xy 44.215506 -301.578014) (xy 44.264112 -301.562555) (xy 44.314515 -301.554732)
			(xy 44.365521 -301.554732) (xy 44.415924 -301.562555) (xy 44.46453 -301.578014) (xy 44.510191 -301.600745)
			(xy 44.53128 -301.615094) (xy 44.537817 -301.619376) (xy 44.552683 -301.624165) (xy 44.56049 -301.624492)
			(xy 45.076618 -301.624492) (xy 45.081973 -301.625034) (xy 45.089555 -301.6326) (xy 45.09008 -301.637954)
			(xy 45.09008 -302.132492) (xy 51.134264 -302.132492) (xy 51.134264 -301.637954) (xy 51.134762 -301.632651)
			(xy 51.14218 -301.625075) (xy 51.147472 -301.624492) (xy 51.6636 -301.624492) (xy 51.67141 -301.62418)
			(xy 51.686282 -301.619393) (xy 51.69281 -301.615094) (xy 51.713899 -301.600745) (xy 51.75956 -301.578014)
			(xy 51.808166 -301.562555) (xy 51.858569 -301.554732) (xy 51.909575 -301.554732) (xy 51.959978 -301.562555)
			(xy 52.008584 -301.578014) (xy 52.054245 -301.600745) (xy 52.075334 -301.615094) (xy 52.081859 -301.619397)
			(xy 52.096734 -301.624173) (xy 52.104544 -301.624492) (xy 52.620672 -301.624492) (xy 52.626001 -301.624845)
			(xy 52.633543 -301.632372) (xy 52.63388 -301.6377) (xy 52.63388 -301.638208) (xy 52.63388 -302.132492)
			(xy 58.678064 -302.132492) (xy 58.678064 -301.637954) (xy 58.678523 -301.632578) (xy 58.686148 -301.624994)
			(xy 58.691526 -301.624492) (xy 60.164726 -301.624492) (xy 60.170082 -301.625029) (xy 60.177663 -301.632599)
			(xy 60.178188 -301.637954) (xy 60.178188 -302.132492) (xy 167.778176 -302.132492) (xy 167.778176 -301.637954)
			(xy 167.778663 -301.632648) (xy 167.786089 -301.625072) (xy 167.791384 -301.624492) (xy 169.264584 -301.624492)
			(xy 169.269914 -301.624838) (xy 169.277456 -301.63237) (xy 169.277792 -301.6377) (xy 169.277792 -302.132492)
			(xy 175.321976 -302.132492) (xy 175.321976 -301.637954) (xy 175.322424 -301.632575) (xy 175.330056 -301.62499)
			(xy 175.335438 -301.624492) (xy 175.851566 -301.624492) (xy 175.859375 -301.624165) (xy 175.874246 -301.619388)
			(xy 175.880776 -301.615094) (xy 175.901865 -301.600745) (xy 175.947526 -301.578014) (xy 175.996132 -301.562555)
			(xy 176.046535 -301.554732) (xy 176.097541 -301.554732) (xy 176.147944 -301.562555) (xy 176.19655 -301.578014)
			(xy 176.242211 -301.600745) (xy 176.2633 -301.615094) (xy 176.269833 -301.619384) (xy 176.284702 -301.624168)
			(xy 176.29251 -301.624492) (xy 176.808638 -301.624492) (xy 176.813995 -301.625021) (xy 176.821576 -301.632597)
			(xy 176.8221 -301.637954) (xy 176.8221 -302.132492) (xy 182.866284 -302.132492) (xy 182.866284 -301.637954)
			(xy 182.866764 -301.632646) (xy 182.874194 -301.625069) (xy 182.879492 -301.624492) (xy 183.39562 -301.624492)
			(xy 183.403431 -301.624188) (xy 183.418302 -301.619395) (xy 183.42483 -301.615094) (xy 183.445919 -301.600745)
			(xy 183.49158 -301.578014) (xy 183.540186 -301.562555) (xy 183.590589 -301.554732) (xy 183.641595 -301.554732)
			(xy 183.691998 -301.562555) (xy 183.740604 -301.578014) (xy 183.786265 -301.600745) (xy 183.807354 -301.615094)
			(xy 183.813875 -301.619404) (xy 183.828753 -301.624176) (xy 183.836564 -301.624492) (xy 184.352692 -301.624492)
			(xy 184.358023 -301.624832) (xy 184.365565 -301.632369) (xy 184.3659 -301.6377) (xy 184.3659 -301.638208)
			(xy 184.3659 -302.132492) (xy 190.410084 -302.132492) (xy 190.410084 -301.637954) (xy 190.410525 -301.632573)
			(xy 190.418162 -301.624988) (xy 190.423546 -301.624492) (xy 190.939674 -301.624492) (xy 190.947483 -301.624169)
			(xy 190.962355 -301.61939) (xy 190.968884 -301.615094) (xy 190.989973 -301.600745) (xy 191.035634 -301.578014)
			(xy 191.08424 -301.562555) (xy 191.134643 -301.554732) (xy 191.185649 -301.554732) (xy 191.236052 -301.562555)
			(xy 191.284658 -301.578014) (xy 191.330319 -301.600745) (xy 191.351408 -301.615094) (xy 191.357939 -301.619387)
			(xy 191.372809 -301.624169) (xy 191.380618 -301.624492) (xy 191.896746 -301.624492) (xy 191.902104 -301.625015)
			(xy 191.909685 -301.632596) (xy 191.910208 -301.637954) (xy 191.910208 -302.132492) (xy 197.954392 -302.132492)
			(xy 197.954392 -301.637954) (xy 197.954954 -301.632667) (xy 197.962328 -301.625096) (xy 197.9676 -301.624492)
			(xy 198.483728 -301.624492) (xy 198.491539 -301.624192) (xy 198.506411 -301.619397) (xy 198.512938 -301.615094)
			(xy 198.534027 -301.600745) (xy 198.579688 -301.578014) (xy 198.628294 -301.562555) (xy 198.678697 -301.554732)
			(xy 198.729703 -301.554732) (xy 198.780106 -301.562555) (xy 198.828712 -301.578014) (xy 198.874373 -301.600745)
			(xy 198.895462 -301.615094) (xy 198.902003 -301.619369) (xy 198.916866 -301.624162) (xy 198.924672 -301.624492)
			(xy 199.4408 -301.624492) (xy 199.446063 -301.624995) (xy 199.453505 -301.632437) (xy 199.454008 -301.6377)
			(xy 199.454008 -301.638208) (xy 199.454008 -302.132492) (xy 205.498192 -302.132492) (xy 205.498192 -301.637954)
			(xy 205.498754 -301.632667) (xy 205.506128 -301.625096) (xy 205.5114 -301.624492) (xy 206.027528 -301.624492)
			(xy 206.035339 -301.624192) (xy 206.050211 -301.619397) (xy 206.056738 -301.615094) (xy 206.077827 -301.600745)
			(xy 206.123488 -301.578014) (xy 206.172094 -301.562555) (xy 206.222497 -301.554732) (xy 206.273503 -301.554732)
			(xy 206.323906 -301.562555) (xy 206.372512 -301.578014) (xy 206.418173 -301.600745) (xy 206.439262 -301.615094)
			(xy 206.445803 -301.619369) (xy 206.460666 -301.624162) (xy 206.468472 -301.624492) (xy 206.9846 -301.624492)
			(xy 206.989863 -301.624995) (xy 206.997305 -301.632437) (xy 206.997808 -301.6377) (xy 206.997808 -301.638208)
			(xy 206.997808 -302.132238) (xy 268.898116 -302.132238) (xy 268.898116 -301.6377) (xy 268.898429 -301.632362)
			(xy 268.905985 -301.624819) (xy 268.911324 -301.624492) (xy 268.911832 -301.624492) (xy 269.427706 -301.624492)
			(xy 269.435516 -301.624182) (xy 269.450388 -301.619394) (xy 269.456916 -301.615094) (xy 269.478005 -301.600745)
			(xy 269.523666 -301.578014) (xy 269.572272 -301.562555) (xy 269.622675 -301.554732) (xy 269.673681 -301.554732)
			(xy 269.724084 -301.562555) (xy 269.77269 -301.578014) (xy 269.818351 -301.600745) (xy 269.83944 -301.615094)
			(xy 269.845964 -301.619399) (xy 269.86084 -301.624174) (xy 269.86865 -301.624492) (xy 270.384778 -301.624492)
			(xy 270.390068 -301.625032) (xy 270.397638 -301.632423) (xy 270.39824 -301.6377) (xy 270.39824 -302.132238)
			(xy 270.398218 -302.132492) (xy 276.442424 -302.132492) (xy 276.442424 -302.131984) (xy 276.442424 -301.6377)
			(xy 276.44273 -301.63236) (xy 276.450291 -301.624817) (xy 276.455632 -301.624492) (xy 276.97176 -301.624492)
			(xy 276.979569 -301.624163) (xy 276.99444 -301.619388) (xy 277.00097 -301.615094) (xy 277.022059 -301.600745)
			(xy 277.06772 -301.578014) (xy 277.116326 -301.562555) (xy 277.166729 -301.554732) (xy 277.217735 -301.554732)
			(xy 277.268138 -301.562555) (xy 277.316744 -301.578014) (xy 277.362405 -301.600745) (xy 277.383494 -301.615094)
			(xy 277.390028 -301.619381) (xy 277.404896 -301.624167) (xy 277.412704 -301.624492) (xy 277.928832 -301.624492)
			(xy 277.934099 -301.624973) (xy 277.941539 -301.632432) (xy 277.94204 -301.6377) (xy 277.94204 -302.132238)
			(xy 277.942019 -302.132492) (xy 283.986224 -302.132492) (xy 283.986224 -302.131984) (xy 283.986224 -301.6377)
			(xy 283.98653 -301.63236) (xy 283.994091 -301.624817) (xy 283.999432 -301.624492) (xy 284.51556 -301.624492)
			(xy 284.523369 -301.624163) (xy 284.53824 -301.619388) (xy 284.54477 -301.615094) (xy 284.565859 -301.600745)
			(xy 284.61152 -301.578014) (xy 284.660126 -301.562555) (xy 284.710529 -301.554732) (xy 284.761535 -301.554732)
			(xy 284.811938 -301.562555) (xy 284.860544 -301.578014) (xy 284.906205 -301.600745) (xy 284.927294 -301.615094)
			(xy 284.933828 -301.619381) (xy 284.948696 -301.624167) (xy 284.956504 -301.624492) (xy 285.472632 -301.624492)
			(xy 285.477899 -301.624973) (xy 285.485339 -301.632432) (xy 285.48584 -301.6377) (xy 285.48584 -302.132238)
			(xy 291.530024 -302.132238) (xy 291.530024 -301.6377) (xy 291.53033 -301.63236) (xy 291.537891 -301.624817)
			(xy 291.543232 -301.624492) (xy 291.54374 -301.624492) (xy 292.059614 -301.624492) (xy 292.067425 -301.624186)
			(xy 292.082296 -301.619395) (xy 292.088824 -301.615094) (xy 292.109913 -301.600745) (xy 292.155574 -301.578014)
			(xy 292.20418 -301.562555) (xy 292.254583 -301.554732) (xy 292.305589 -301.554732) (xy 292.355992 -301.562555)
			(xy 292.404598 -301.578014) (xy 292.450259 -301.600745) (xy 292.471348 -301.615094) (xy 292.47787 -301.619402)
			(xy 292.492747 -301.624175) (xy 292.500558 -301.624492) (xy 293.016686 -301.624492) (xy 293.021977 -301.625027)
			(xy 293.029546 -301.632421) (xy 293.030148 -301.6377) (xy 293.030148 -302.132238) (xy 293.030126 -302.132492)
			(xy 299.074332 -302.132492) (xy 299.074332 -302.131984) (xy 299.074332 -301.6377) (xy 299.074631 -301.632358)
			(xy 299.082197 -301.624815) (xy 299.08754 -301.624492) (xy 299.603668 -301.624492) (xy 299.611477 -301.624166)
			(xy 299.626349 -301.619389) (xy 299.632878 -301.615094) (xy 299.653967 -301.600745) (xy 299.699628 -301.578014)
			(xy 299.748234 -301.562555) (xy 299.798637 -301.554732) (xy 299.849643 -301.554732) (xy 299.900046 -301.562555)
			(xy 299.948652 -301.578014) (xy 299.994313 -301.600745) (xy 300.015402 -301.615094) (xy 300.021934 -301.619384)
			(xy 300.036804 -301.624168) (xy 300.044612 -301.624492) (xy 300.56074 -301.624492) (xy 300.566008 -301.624968)
			(xy 300.573448 -301.632431) (xy 300.573948 -301.6377) (xy 300.573948 -302.132238) (xy 306.618132 -302.132238)
			(xy 306.618132 -301.6377) (xy 306.618431 -301.632358) (xy 306.625997 -301.624815) (xy 306.63134 -301.624492)
			(xy 306.631848 -301.624492) (xy 308.104794 -301.624492) (xy 308.110086 -301.625021) (xy 308.117655 -301.63242)
			(xy 308.118256 -301.6377) (xy 308.118256 -302.132238) (xy 308.118233 -302.132492) (xy 415.718244 -302.132492)
			(xy 415.718244 -301.6377) (xy 415.71879 -301.632449) (xy 415.726203 -301.625009) (xy 415.731452 -301.624492)
			(xy 417.204652 -301.624492) (xy 417.209978 -301.624859) (xy 417.217521 -301.632376) (xy 417.21786 -301.6377)
			(xy 417.21786 -302.132238) (xy 423.262044 -302.132238) (xy 423.262044 -301.6377) (xy 423.26259 -301.632449)
			(xy 423.270003 -301.625009) (xy 423.275252 -301.624492) (xy 423.27576 -301.624492) (xy 423.791634 -301.624492)
			(xy 423.799442 -301.624151) (xy 423.814313 -301.619384) (xy 423.820844 -301.615094) (xy 423.841933 -301.600745)
			(xy 423.887594 -301.578014) (xy 423.9362 -301.562555) (xy 423.986603 -301.554732) (xy 424.037609 -301.554732)
			(xy 424.088012 -301.562555) (xy 424.136618 -301.578014) (xy 424.182279 -301.600745) (xy 424.203368 -301.615094)
			(xy 424.209908 -301.619371) (xy 424.224771 -301.624163) (xy 424.232578 -301.624492) (xy 424.748706 -301.624492)
			(xy 424.754 -301.625013) (xy 424.761568 -301.632418) (xy 424.762168 -301.6377) (xy 424.762168 -302.132238)
			(xy 424.762145 -302.132492) (xy 430.806352 -302.132492) (xy 430.806352 -302.131984) (xy 430.806352 -301.6377)
			(xy 430.806891 -301.632447) (xy 430.814308 -301.625007) (xy 430.81956 -301.624492) (xy 431.335688 -301.624492)
			(xy 431.343498 -301.624175) (xy 431.358369 -301.619391) (xy 431.364898 -301.615094) (xy 431.385987 -301.600745)
			(xy 431.431648 -301.578014) (xy 431.480254 -301.562555) (xy 431.530657 -301.554732) (xy 431.581663 -301.554732)
			(xy 431.632066 -301.562555) (xy 431.680672 -301.578014) (xy 431.726333 -301.600745) (xy 431.747422 -301.615094)
			(xy 431.75395 -301.619392) (xy 431.768823 -301.624171) (xy 431.776632 -301.624492) (xy 432.29276 -301.624492)
			(xy 432.298087 -301.624854) (xy 432.30563 -301.632374) (xy 432.305968 -301.6377) (xy 432.305968 -302.132238)
			(xy 438.350152 -302.132238) (xy 438.350152 -301.6377) (xy 438.350691 -301.632447) (xy 438.358108 -301.625007)
			(xy 438.36336 -301.624492) (xy 438.363868 -301.624492) (xy 438.879742 -301.624492) (xy 438.88755 -301.624155)
			(xy 438.902422 -301.619385) (xy 438.908952 -301.615094) (xy 438.930041 -301.600745) (xy 438.975702 -301.578014)
			(xy 439.024308 -301.562555) (xy 439.074711 -301.554732) (xy 439.125717 -301.554732) (xy 439.17612 -301.562555)
			(xy 439.224726 -301.578014) (xy 439.270387 -301.600745) (xy 439.291476 -301.615094) (xy 439.298014 -301.619374)
			(xy 439.312879 -301.624164) (xy 439.320686 -301.624492) (xy 439.836814 -301.624492) (xy 439.842109 -301.625008)
			(xy 439.849676 -301.632417) (xy 439.850276 -301.6377) (xy 439.850276 -302.132238) (xy 439.850252 -302.132492)
			(xy 445.89446 -302.132492) (xy 445.89446 -302.131984) (xy 445.89446 -301.6377) (xy 445.894992 -301.632445)
			(xy 445.902414 -301.625004) (xy 445.907668 -301.624492) (xy 446.423796 -301.624492) (xy 446.431606 -301.624178)
			(xy 446.446478 -301.619392) (xy 446.453006 -301.615094) (xy 446.474095 -301.600745) (xy 446.519756 -301.578014)
			(xy 446.568362 -301.562555) (xy 446.618765 -301.554732) (xy 446.669771 -301.554732) (xy 446.720174 -301.562555)
			(xy 446.76878 -301.578014) (xy 446.814441 -301.600745) (xy 446.83553 -301.615094) (xy 446.842056 -301.619395)
			(xy 446.85693 -301.624172) (xy 446.86474 -301.624492) (xy 447.380868 -301.624492) (xy 447.386196 -301.624848)
			(xy 447.393739 -301.632373) (xy 447.394076 -301.6377) (xy 447.394076 -302.132238) (xy 447.394053 -302.132492)
			(xy 453.43826 -302.132492) (xy 453.43826 -302.131984) (xy 453.43826 -301.6377) (xy 453.438792 -301.632445)
			(xy 453.446214 -301.625004) (xy 453.451468 -301.624492) (xy 453.967596 -301.624492) (xy 453.975406 -301.624178)
			(xy 453.990278 -301.619392) (xy 453.996806 -301.615094) (xy 454.017895 -301.600745) (xy 454.063556 -301.578014)
			(xy 454.112162 -301.562555) (xy 454.162565 -301.554732) (xy 454.213571 -301.554732) (xy 454.263974 -301.562555)
			(xy 454.31258 -301.578014) (xy 454.358241 -301.600745) (xy 454.37933 -301.615094) (xy 454.385856 -301.619395)
			(xy 454.40073 -301.624172) (xy 454.40854 -301.624492) (xy 454.924668 -301.624492) (xy 454.929996 -301.624848)
			(xy 454.937539 -301.632373) (xy 454.937876 -301.6377) (xy 454.937876 -302.132238) (xy 454.937404 -302.137543)
			(xy 454.929964 -302.145111) (xy 454.924668 -302.1457) (xy 454.408794 -302.1457) (xy 454.400984 -302.146011)
			(xy 454.386112 -302.150799) (xy 454.379584 -302.155098) (xy 454.35846 -302.169444) (xy 454.312738 -302.192173)
			(xy 454.264065 -302.207604) (xy 454.213599 -302.215371) (xy 454.188068 -302.215804) (xy 454.162537 -302.215376)
			(xy 454.112074 -302.207597) (xy 454.063401 -302.192165) (xy 454.017674 -302.169446) (xy 453.996552 -302.155098)
			(xy 453.990031 -302.150789) (xy 453.975153 -302.146017) (xy 453.967342 -302.1457) (xy 453.451468 -302.1457)
			(xy 453.446199 -302.145226) (xy 453.438758 -302.137762) (xy 453.43826 -302.132492) (xy 447.394053 -302.132492)
			(xy 447.393604 -302.137543) (xy 447.386164 -302.145111) (xy 447.380868 -302.1457) (xy 446.864994 -302.1457)
			(xy 446.857184 -302.146011) (xy 446.842312 -302.150799) (xy 446.835784 -302.155098) (xy 446.81466 -302.169444)
			(xy 446.768938 -302.192173) (xy 446.720265 -302.207604) (xy 446.669799 -302.215371) (xy 446.644268 -302.215804)
			(xy 446.618737 -302.215376) (xy 446.568274 -302.207597) (xy 446.519601 -302.192165) (xy 446.473874 -302.169446)
			(xy 446.452752 -302.155098) (xy 446.446231 -302.150789) (xy 446.431353 -302.146017) (xy 446.423542 -302.1457)
			(xy 445.907668 -302.1457) (xy 445.902399 -302.145226) (xy 445.894958 -302.137762) (xy 445.89446 -302.132492)
			(xy 439.850252 -302.132492) (xy 439.849776 -302.137603) (xy 439.84218 -302.145186) (xy 439.836814 -302.1457)
			(xy 439.32094 -302.1457) (xy 439.313131 -302.146031) (xy 439.29826 -302.150805) (xy 439.29173 -302.155098)
			(xy 439.270621 -302.169467) (xy 439.224893 -302.192191) (xy 439.176216 -302.207616) (xy 439.125746 -302.215375)
			(xy 439.100214 -302.215804) (xy 439.074684 -302.215353) (xy 439.024221 -302.207581) (xy 438.975549 -302.192155)
			(xy 438.929821 -302.169443) (xy 438.908698 -302.155098) (xy 438.902166 -302.150807) (xy 438.887296 -302.146024)
			(xy 438.879488 -302.1457) (xy 438.363614 -302.1457) (xy 438.358261 -302.145144) (xy 438.350677 -302.137589)
			(xy 438.350152 -302.132238) (xy 432.305968 -302.132238) (xy 432.305503 -302.137545) (xy 432.298058 -302.145113)
			(xy 432.29276 -302.1457) (xy 431.776886 -302.1457) (xy 431.769075 -302.146008) (xy 431.754204 -302.150798)
			(xy 431.747676 -302.155098) (xy 431.726554 -302.169447) (xy 431.680831 -302.192176) (xy 431.632158 -302.207606)
			(xy 431.581691 -302.215372) (xy 431.55616 -302.215804) (xy 431.530629 -302.21538) (xy 431.480165 -302.207599)
			(xy 431.431493 -302.192166) (xy 431.385766 -302.169447) (xy 431.364644 -302.155098) (xy 431.358124 -302.150786)
			(xy 431.343245 -302.146016) (xy 431.335434 -302.1457) (xy 430.81956 -302.1457) (xy 430.81429 -302.145231)
			(xy 430.80685 -302.137763) (xy 430.806352 -302.132492) (xy 424.762145 -302.132492) (xy 424.761675 -302.137605)
			(xy 424.754074 -302.145188) (xy 424.748706 -302.1457) (xy 424.232832 -302.1457) (xy 424.225023 -302.146027)
			(xy 424.210152 -302.150804) (xy 424.203622 -302.155098) (xy 424.182488 -302.169428) (xy 424.136769 -302.19216)
			(xy 424.088099 -302.207596) (xy 424.037636 -302.215368) (xy 424.012106 -302.215804) (xy 423.986576 -302.215357)
			(xy 423.936113 -302.207583) (xy 423.887441 -302.192157) (xy 423.841713 -302.169444) (xy 423.82059 -302.155098)
			(xy 423.81406 -302.150804) (xy 423.799189 -302.146023) (xy 423.79138 -302.1457) (xy 423.275506 -302.1457)
			(xy 423.270152 -302.14515) (xy 423.262568 -302.13759) (xy 423.262044 -302.132238) (xy 417.21786 -302.132238)
			(xy 417.217402 -302.137547) (xy 417.209952 -302.145116) (xy 417.204652 -302.1457) (xy 415.731452 -302.1457)
			(xy 415.726182 -302.145236) (xy 415.718741 -302.137764) (xy 415.718244 -302.132492) (xy 308.118233 -302.132492)
			(xy 308.117774 -302.137608) (xy 308.110165 -302.145192) (xy 308.104794 -302.1457) (xy 306.631594 -302.1457)
			(xy 306.626238 -302.145158) (xy 306.618655 -302.137592) (xy 306.618132 -302.132238) (xy 300.573948 -302.132238)
			(xy 300.5735 -302.13755) (xy 300.566043 -302.145119) (xy 300.56074 -302.1457) (xy 300.044866 -302.1457)
			(xy 300.037058 -302.146042) (xy 300.022187 -302.150808) (xy 300.015656 -302.155098) (xy 299.99454 -302.169456)
			(xy 299.948815 -302.192182) (xy 299.90014 -302.20761) (xy 299.849672 -302.215373) (xy 299.82414 -302.215804)
			(xy 299.798611 -302.21534) (xy 299.748148 -302.207571) (xy 299.699476 -302.19215) (xy 299.653747 -302.169441)
			(xy 299.632624 -302.155098) (xy 299.626087 -302.150817) (xy 299.611221 -302.146028) (xy 299.603414 -302.1457)
			(xy 299.08754 -302.1457) (xy 299.082211 -302.145345) (xy 299.074668 -302.13782) (xy 299.074332 -302.132492)
			(xy 293.030126 -302.132492) (xy 293.029673 -302.13761) (xy 293.02206 -302.145194) (xy 293.016686 -302.1457)
			(xy 292.500812 -302.1457) (xy 292.493002 -302.146019) (xy 292.478131 -302.150801) (xy 292.471602 -302.155098)
			(xy 292.450473 -302.169436) (xy 292.404752 -302.192167) (xy 292.356081 -302.2076) (xy 292.305616 -302.21537)
			(xy 292.280086 -302.215804) (xy 292.254556 -302.215367) (xy 292.204092 -302.20759) (xy 292.15542 -302.192161)
			(xy 292.109692 -302.169445) (xy 292.08857 -302.155098) (xy 292.082045 -302.150796) (xy 292.06717 -302.14602)
			(xy 292.05936 -302.1457) (xy 291.543486 -302.1457) (xy 291.53813 -302.145163) (xy 291.530547 -302.137593)
			(xy 291.530024 -302.132238) (xy 285.48584 -302.132238) (xy 285.4854 -302.137551) (xy 285.477938 -302.145121)
			(xy 285.472632 -302.1457) (xy 284.956758 -302.1457) (xy 284.94895 -302.146038) (xy 284.934079 -302.150807)
			(xy 284.927548 -302.155098) (xy 284.906434 -302.16946) (xy 284.860708 -302.192185) (xy 284.812032 -302.207612)
			(xy 284.761564 -302.215374) (xy 284.736032 -302.215804) (xy 284.710503 -302.215344) (xy 284.66004 -302.207574)
			(xy 284.611368 -302.192152) (xy 284.565639 -302.169442) (xy 284.544516 -302.155098) (xy 284.53798 -302.150814)
			(xy 284.523114 -302.146027) (xy 284.515306 -302.1457) (xy 283.999432 -302.1457) (xy 283.994102 -302.145351)
			(xy 283.986559 -302.137821) (xy 283.986224 -302.132492) (xy 277.942019 -302.132492) (xy 277.9416 -302.137551)
			(xy 277.934138 -302.145121) (xy 277.928832 -302.1457) (xy 277.412958 -302.1457) (xy 277.40515 -302.146038)
			(xy 277.390279 -302.150807) (xy 277.383748 -302.155098) (xy 277.362634 -302.16946) (xy 277.316908 -302.192185)
			(xy 277.268232 -302.207612) (xy 277.217764 -302.215374) (xy 277.192232 -302.215804) (xy 277.166703 -302.215344)
			(xy 277.11624 -302.207574) (xy 277.067568 -302.192152) (xy 277.021839 -302.169442) (xy 277.000716 -302.155098)
			(xy 276.99418 -302.150814) (xy 276.979314 -302.146027) (xy 276.971506 -302.1457) (xy 276.455632 -302.1457)
			(xy 276.450302 -302.145351) (xy 276.442759 -302.137821) (xy 276.442424 -302.132492) (xy 270.398218 -302.132492)
			(xy 270.397772 -302.137612) (xy 270.390154 -302.145196) (xy 270.384778 -302.1457) (xy 269.868904 -302.1457)
			(xy 269.861094 -302.146015) (xy 269.846223 -302.1508) (xy 269.839694 -302.155098) (xy 269.818567 -302.16944)
			(xy 269.772846 -302.19217) (xy 269.724174 -302.207602) (xy 269.673709 -302.21537) (xy 269.648178 -302.215804)
			(xy 269.622648 -302.215371) (xy 269.572184 -302.207593) (xy 269.523512 -302.192163) (xy 269.477784 -302.169445)
			(xy 269.456662 -302.155098) (xy 269.450138 -302.150793) (xy 269.435262 -302.146019) (xy 269.427452 -302.1457)
			(xy 268.911578 -302.1457) (xy 268.906221 -302.145168) (xy 268.898638 -302.137595) (xy 268.898116 -302.132238)
			(xy 206.997808 -302.132238) (xy 206.997808 -302.132492) (xy 206.997468 -302.137823) (xy 206.989931 -302.145365)
			(xy 206.9846 -302.1457) (xy 206.468726 -302.1457) (xy 206.46085 -302.145972) (xy 206.445847 -302.150767)
			(xy 206.439262 -302.155098) (xy 206.418182 -302.169485) (xy 206.372538 -302.192316) (xy 206.323933 -302.207875)
			(xy 206.273517 -302.215795) (xy 206.248 -302.216312) (xy 206.222479 -302.215837) (xy 206.172052 -302.207938)
			(xy 206.12344 -302.192373) (xy 206.077802 -302.169515) (xy 206.056738 -302.155098) (xy 206.05014 -302.150795)
			(xy 206.035145 -302.146001) (xy 206.027274 -302.1457) (xy 205.5114 -302.1457) (xy 205.506066 -302.145373)
			(xy 205.498524 -302.137826) (xy 205.498192 -302.132492) (xy 199.454008 -302.132492) (xy 199.453668 -302.137823)
			(xy 199.446131 -302.145365) (xy 199.4408 -302.1457) (xy 198.924926 -302.1457) (xy 198.91705 -302.145972)
			(xy 198.902047 -302.150767) (xy 198.895462 -302.155098) (xy 198.874382 -302.169485) (xy 198.828738 -302.192316)
			(xy 198.780133 -302.207875) (xy 198.729717 -302.215795) (xy 198.7042 -302.216312) (xy 198.678679 -302.215837)
			(xy 198.628252 -302.207938) (xy 198.57964 -302.192373) (xy 198.534002 -302.169515) (xy 198.512938 -302.155098)
			(xy 198.50634 -302.150795) (xy 198.491345 -302.146001) (xy 198.483474 -302.1457) (xy 197.9676 -302.1457)
			(xy 197.962266 -302.145373) (xy 197.954724 -302.137826) (xy 197.954392 -302.132492) (xy 191.910208 -302.132492)
			(xy 191.909868 -302.137823) (xy 191.902331 -302.145365) (xy 191.897 -302.1457) (xy 191.896492 -302.1457)
			(xy 191.380872 -302.1457) (xy 191.372998 -302.145992) (xy 191.357994 -302.150773) (xy 191.351408 -302.155098)
			(xy 191.330343 -302.169508) (xy 191.284694 -302.192334) (xy 191.236084 -302.207887) (xy 191.185664 -302.215799)
			(xy 191.160146 -302.216312) (xy 191.134626 -302.215814) (xy 191.0842 -302.207922) (xy 191.035588 -302.192364)
			(xy 190.989949 -302.169512) (xy 190.968884 -302.155098) (xy 190.962298 -302.150774) (xy 190.947294 -302.145993)
			(xy 190.93942 -302.1457) (xy 190.423546 -302.1457) (xy 190.418256 -302.145151) (xy 190.410685 -302.137768)
			(xy 190.410084 -302.132492) (xy 184.3659 -302.132492) (xy 184.365567 -302.137825) (xy 184.358025 -302.145367)
			(xy 184.352692 -302.1457) (xy 183.836818 -302.1457) (xy 183.828946 -302.146011) (xy 183.813942 -302.150779)
			(xy 183.807354 -302.155098) (xy 183.786276 -302.169488) (xy 183.740632 -302.192319) (xy 183.692026 -302.207877)
			(xy 183.641609 -302.215795) (xy 183.616092 -302.216312) (xy 183.590573 -302.215791) (xy 183.540148 -302.207906)
			(xy 183.491536 -302.192355) (xy 183.445896 -302.169509) (xy 183.42483 -302.155098) (xy 183.418234 -302.150792)
			(xy 183.403237 -302.146) (xy 183.395366 -302.1457) (xy 182.879492 -302.1457) (xy 182.874226 -302.14521)
			(xy 182.866784 -302.137758) (xy 182.866284 -302.132492) (xy 176.8221 -302.132492) (xy 176.821767 -302.137825)
			(xy 176.814225 -302.145367) (xy 176.808892 -302.1457) (xy 176.808384 -302.1457) (xy 176.292764 -302.1457)
			(xy 176.28489 -302.145988) (xy 176.269886 -302.150772) (xy 176.2633 -302.155098) (xy 176.242209 -302.169469)
			(xy 176.196569 -302.192303) (xy 176.147968 -302.207867) (xy 176.097554 -302.215792) (xy 176.072038 -302.216312)
			(xy 176.046518 -302.215818) (xy 175.996091 -302.207925) (xy 175.94748 -302.192366) (xy 175.901841 -302.169512)
			(xy 175.880776 -302.155098) (xy 175.874192 -302.150771) (xy 175.859186 -302.145992) (xy 175.851312 -302.1457)
			(xy 175.335438 -302.1457) (xy 175.330148 -302.145156) (xy 175.322577 -302.137769) (xy 175.321976 -302.132492)
			(xy 169.277792 -302.132492) (xy 169.277466 -302.137827) (xy 169.269919 -302.14537) (xy 169.264584 -302.1457)
			(xy 167.791384 -302.1457) (xy 167.786117 -302.145215) (xy 167.778675 -302.13776) (xy 167.778176 -302.132492)
			(xy 60.178188 -302.132492) (xy 60.177866 -302.137828) (xy 60.170316 -302.145371) (xy 60.16498 -302.1457)
			(xy 60.164472 -302.1457) (xy 58.691526 -302.1457) (xy 58.686234 -302.145164) (xy 58.678664 -302.137771)
			(xy 58.678064 -302.132492) (xy 52.63388 -302.132492) (xy 52.633565 -302.13783) (xy 52.626011 -302.145373)
			(xy 52.620672 -302.1457) (xy 52.104798 -302.1457) (xy 52.096925 -302.146003) (xy 52.081921 -302.150777)
			(xy 52.075334 -302.155098) (xy 52.054261 -302.169497) (xy 52.008615 -302.192325) (xy 51.960008 -302.207881)
			(xy 51.909589 -302.215797) (xy 51.884072 -302.216312) (xy 51.858553 -302.215801) (xy 51.808127 -302.207913)
			(xy 51.759515 -302.192359) (xy 51.713876 -302.16951) (xy 51.69281 -302.155098) (xy 51.686218 -302.150784)
			(xy 51.671218 -302.145997) (xy 51.663346 -302.1457) (xy 51.147472 -302.1457) (xy 51.142204 -302.145223)
			(xy 51.134762 -302.137761) (xy 51.134264 -302.132492) (xy 45.09008 -302.132492) (xy 45.089765 -302.13783)
			(xy 45.082211 -302.145373) (xy 45.076872 -302.1457) (xy 45.076364 -302.1457) (xy 44.560744 -302.1457)
			(xy 44.552869 -302.14598) (xy 44.537865 -302.15077) (xy 44.53128 -302.155098) (xy 44.510195 -302.169477)
			(xy 44.464553 -302.19231) (xy 44.415949 -302.207871) (xy 44.365534 -302.215794) (xy 44.340018 -302.216312)
			(xy 44.314498 -302.215828) (xy 44.264071 -302.207932) (xy 44.215459 -302.19237) (xy 44.169821 -302.169514)
			(xy 44.148756 -302.155098) (xy 44.142176 -302.150763) (xy 44.127167 -302.145989) (xy 44.119292 -302.1457)
			(xy 43.603418 -302.1457) (xy 43.598125 -302.14517) (xy 43.590555 -302.137772) (xy 43.589956 -302.132492)
			(xy 37.545772 -302.132492) (xy 37.545464 -302.137832) (xy 37.537905 -302.145376) (xy 37.532564 -302.1457)
			(xy 37.01669 -302.1457) (xy 37.008817 -302.145999) (xy 36.993813 -302.150776) (xy 36.987226 -302.155098)
			(xy 36.966156 -302.169501) (xy 36.920509 -302.192328) (xy 36.8719 -302.207883) (xy 36.821481 -302.215798)
			(xy 36.795964 -302.216312) (xy 36.770445 -302.215805) (xy 36.720018 -302.207915) (xy 36.671407 -302.19236)
			(xy 36.625768 -302.169511) (xy 36.604702 -302.155098) (xy 36.598112 -302.150781) (xy 36.583111 -302.145995)
			(xy 36.575238 -302.1457) (xy 36.059364 -302.1457) (xy 36.054095 -302.145228) (xy 36.046654 -302.137763)
			(xy 36.046156 -302.132492) (xy 30.001972 -302.132492) (xy 30.001664 -302.137832) (xy 29.994105 -302.145376)
			(xy 29.988764 -302.1457) (xy 29.47289 -302.1457) (xy 29.465017 -302.145999) (xy 29.450013 -302.150776)
			(xy 29.443426 -302.155098) (xy 29.422356 -302.169501) (xy 29.376709 -302.192328) (xy 29.3281 -302.207883)
			(xy 29.277681 -302.215798) (xy 29.252164 -302.216312) (xy 29.226645 -302.215805) (xy 29.176218 -302.207915)
			(xy 29.127607 -302.19236) (xy 29.081968 -302.169511) (xy 29.060902 -302.155098) (xy 29.054312 -302.150781)
			(xy 29.039311 -302.145995) (xy 29.031438 -302.1457) (xy 28.515564 -302.1457) (xy 28.510295 -302.145228)
			(xy 28.502854 -302.137763) (xy 28.502356 -302.132492) (xy 22.458172 -302.132492) (xy 22.457864 -302.137832)
			(xy 22.450305 -302.145376) (xy 22.444964 -302.1457) (xy 22.444456 -302.1457) (xy 21.928836 -302.1457)
			(xy 21.920961 -302.145976) (xy 21.905957 -302.150769) (xy 21.899372 -302.155098) (xy 21.878289 -302.169481)
			(xy 21.832646 -302.192313) (xy 21.784042 -302.207873) (xy 21.733626 -302.215794) (xy 21.70811 -302.216312)
			(xy 21.682589 -302.215832) (xy 21.632162 -302.207934) (xy 21.583551 -302.192371) (xy 21.537913 -302.169514)
			(xy 21.516848 -302.155098) (xy 21.51027 -302.15076) (xy 21.49526 -302.145987) (xy 21.487384 -302.1457)
			(xy 20.97151 -302.1457) (xy 20.966216 -302.145175) (xy 20.958647 -302.137774) (xy 20.958048 -302.132492)
			(xy 2.509012 -302.132492) (xy 2.509012 -302.982376) (xy 16.85798 -302.982376) (xy 16.85798 -302.487838)
			(xy 16.858309 -302.482398) (xy 16.866002 -302.474707) (xy 16.871442 -302.474376) (xy 17.38757 -302.474376)
			(xy 17.395379 -302.474054) (xy 17.410251 -302.469274) (xy 17.41678 -302.464978) (xy 17.437869 -302.450629)
			(xy 17.48353 -302.427898) (xy 17.532136 -302.412439) (xy 17.582539 -302.404616) (xy 17.633545 -302.404616)
			(xy 17.683948 -302.412439) (xy 17.732554 -302.427898) (xy 17.778215 -302.450629) (xy 17.799304 -302.464978)
			(xy 17.805837 -302.469267) (xy 17.820706 -302.474052) (xy 17.828514 -302.474376) (xy 18.344642 -302.474376)
			(xy 18.35002 -302.474826) (xy 18.357606 -302.482457) (xy 18.358104 -302.487838) (xy 18.358104 -302.982376)
			(xy 24.402288 -302.982376) (xy 24.402288 -302.487838) (xy 24.402754 -302.482527) (xy 24.410195 -302.474951)
			(xy 24.415496 -302.474376) (xy 24.931624 -302.474376) (xy 24.939435 -302.474077) (xy 24.954307 -302.469281)
			(xy 24.960834 -302.464978) (xy 24.981923 -302.450629) (xy 25.027584 -302.427898) (xy 25.07619 -302.412439)
			(xy 25.126593 -302.404616) (xy 25.177599 -302.404616) (xy 25.228002 -302.412439) (xy 25.276608 -302.427898)
			(xy 25.322269 -302.450629) (xy 25.343358 -302.464978) (xy 25.349879 -302.469288) (xy 25.364757 -302.47406)
			(xy 25.372568 -302.474376) (xy 25.888696 -302.474376) (xy 25.893954 -302.474896) (xy 25.901396 -302.482326)
			(xy 25.901904 -302.487584) (xy 25.901904 -302.488092) (xy 25.901904 -302.982376) (xy 31.946088 -302.982376)
			(xy 31.946088 -302.487838) (xy 31.946554 -302.482527) (xy 31.953995 -302.474951) (xy 31.959296 -302.474376)
			(xy 32.475424 -302.474376) (xy 32.483235 -302.474077) (xy 32.498107 -302.469281) (xy 32.504634 -302.464978)
			(xy 32.525723 -302.450629) (xy 32.571384 -302.427898) (xy 32.61999 -302.412439) (xy 32.670393 -302.404616)
			(xy 32.721399 -302.404616) (xy 32.771802 -302.412439) (xy 32.820408 -302.427898) (xy 32.866069 -302.450629)
			(xy 32.887158 -302.464978) (xy 32.893679 -302.469288) (xy 32.908557 -302.47406) (xy 32.916368 -302.474376)
			(xy 33.432496 -302.474376) (xy 33.437754 -302.474896) (xy 33.445196 -302.482326) (xy 33.445704 -302.487584)
			(xy 33.445704 -302.488092) (xy 33.445704 -302.982376) (xy 39.489888 -302.982376) (xy 39.489888 -302.487838)
			(xy 39.490471 -302.48249) (xy 39.498006 -302.474906) (xy 39.50335 -302.474376) (xy 40.019478 -302.474376)
			(xy 40.027288 -302.474057) (xy 40.042159 -302.469275) (xy 40.048688 -302.464978) (xy 40.069777 -302.450629)
			(xy 40.115438 -302.427898) (xy 40.164044 -302.412439) (xy 40.214447 -302.404616) (xy 40.265453 -302.404616)
			(xy 40.315856 -302.412439) (xy 40.364462 -302.427898) (xy 40.410123 -302.450629) (xy 40.431212 -302.464978)
			(xy 40.437743 -302.46927) (xy 40.452613 -302.474053) (xy 40.460422 -302.474376) (xy 40.97655 -302.474376)
			(xy 40.981929 -302.474821) (xy 40.989514 -302.482456) (xy 40.990012 -302.487838) (xy 40.990012 -302.982376)
			(xy 47.034196 -302.982376) (xy 47.034196 -302.487838) (xy 47.034744 -302.482549) (xy 47.042128 -302.474978)
			(xy 47.047404 -302.474376) (xy 47.563532 -302.474376) (xy 47.57134 -302.474037) (xy 47.586212 -302.469269)
			(xy 47.592742 -302.464978) (xy 47.613831 -302.450629) (xy 47.659492 -302.427898) (xy 47.708098 -302.412439)
			(xy 47.758501 -302.404616) (xy 47.809507 -302.404616) (xy 47.85991 -302.412439) (xy 47.908516 -302.427898)
			(xy 47.954177 -302.450629) (xy 47.975266 -302.464978) (xy 47.981807 -302.469253) (xy 47.99667 -302.474046)
			(xy 48.004476 -302.474376) (xy 48.520604 -302.474376) (xy 48.525863 -302.47489) (xy 48.533305 -302.482325)
			(xy 48.533812 -302.487584) (xy 48.533812 -302.488092) (xy 48.533812 -302.982376) (xy 54.577996 -302.982376)
			(xy 54.577996 -302.487838) (xy 54.578571 -302.482489) (xy 54.586112 -302.474903) (xy 54.591458 -302.474376)
			(xy 56.064658 -302.474376) (xy 56.070096 -302.474711) (xy 56.077787 -302.4824) (xy 56.07812 -302.487838)
			(xy 56.07812 -302.982376) (xy 56.077758 -302.987702) (xy 56.070237 -302.995244) (xy 56.064912 -302.995584)
			(xy 54.591458 -302.995584) (xy 54.586154 -302.995108) (xy 54.578587 -302.98767) (xy 54.577996 -302.982376)
			(xy 48.533812 -302.982376) (xy 48.533457 -302.987704) (xy 48.525931 -302.995246) (xy 48.520604 -302.995584)
			(xy 48.00473 -302.995584) (xy 47.996853 -302.995844) (xy 47.981849 -303.000646) (xy 47.975266 -303.004982)
			(xy 47.954191 -303.019377) (xy 47.908545 -303.042204) (xy 47.859938 -303.05776) (xy 47.809521 -303.065679)
			(xy 47.784004 -303.066196) (xy 47.758483 -303.065722) (xy 47.708056 -303.057823) (xy 47.659444 -303.042258)
			(xy 47.613806 -303.019399) (xy 47.592742 -303.004982) (xy 47.586166 -303.00064) (xy 47.571154 -302.99587)
			(xy 47.563278 -302.995584) (xy 47.047404 -302.995584) (xy 47.042066 -302.995268) (xy 47.034524 -302.987714)
			(xy 47.034196 -302.982376) (xy 40.990012 -302.982376) (xy 40.989657 -302.987704) (xy 40.982131 -302.995246)
			(xy 40.976804 -302.995584) (xy 40.976296 -302.995584) (xy 40.460676 -302.995584) (xy 40.452801 -302.995863)
			(xy 40.437796 -303.000652) (xy 40.431212 -303.004982) (xy 40.410152 -303.019401) (xy 40.364501 -303.042222)
			(xy 40.315889 -303.057772) (xy 40.265468 -303.065683) (xy 40.23995 -303.066196) (xy 40.21443 -303.065699)
			(xy 40.164003 -303.057807) (xy 40.115392 -303.042249) (xy 40.069753 -303.019396) (xy 40.048688 -303.004982)
			(xy 40.042102 -303.000658) (xy 40.027098 -302.995877) (xy 40.019224 -302.995584) (xy 39.50335 -302.995584)
			(xy 39.498057 -302.995046) (xy 39.490485 -302.987655) (xy 39.489888 -302.982376) (xy 33.445704 -302.982376)
			(xy 33.445357 -302.987706) (xy 33.437825 -302.995249) (xy 33.432496 -302.995584) (xy 32.916622 -302.995584)
			(xy 32.908748 -302.995883) (xy 32.893744 -303.000658) (xy 32.887158 -303.004982) (xy 32.866085 -303.019381)
			(xy 32.820438 -303.042206) (xy 32.771831 -303.057762) (xy 32.721413 -303.065679) (xy 32.695896 -303.066196)
			(xy 32.670375 -303.065726) (xy 32.619947 -303.057826) (xy 32.571336 -303.04226) (xy 32.525698 -303.0194)
			(xy 32.504634 -303.004982) (xy 32.498038 -303.000676) (xy 32.483041 -302.995884) (xy 32.47517 -302.995584)
			(xy 31.959296 -302.995584) (xy 31.953957 -302.995273) (xy 31.946415 -302.987715) (xy 31.946088 -302.982376)
			(xy 25.901904 -302.982376) (xy 25.901557 -302.987706) (xy 25.894025 -302.995249) (xy 25.888696 -302.995584)
			(xy 25.372822 -302.995584) (xy 25.364948 -302.995883) (xy 25.349944 -303.000658) (xy 25.343358 -303.004982)
			(xy 25.322285 -303.019381) (xy 25.276638 -303.042206) (xy 25.228031 -303.057762) (xy 25.177613 -303.065679)
			(xy 25.152096 -303.066196) (xy 25.126575 -303.065726) (xy 25.076147 -303.057826) (xy 25.027536 -303.04226)
			(xy 24.981898 -303.0194) (xy 24.960834 -303.004982) (xy 24.954238 -303.000676) (xy 24.939241 -302.995884)
			(xy 24.93137 -302.995584) (xy 24.415496 -302.995584) (xy 24.410157 -302.995273) (xy 24.402615 -302.987715)
			(xy 24.402288 -302.982376) (xy 18.358104 -302.982376) (xy 18.357757 -302.987706) (xy 18.350225 -302.995249)
			(xy 18.344896 -302.995584) (xy 18.344388 -302.995584) (xy 17.828768 -302.995584) (xy 17.820892 -302.99586)
			(xy 17.805888 -303.000651) (xy 17.799304 -303.004982) (xy 17.778218 -303.019361) (xy 17.732576 -303.042191)
			(xy 17.683973 -303.057752) (xy 17.633558 -303.065676) (xy 17.608042 -303.066196) (xy 17.582522 -303.065703)
			(xy 17.532095 -303.05781) (xy 17.483483 -303.042251) (xy 17.437845 -303.019397) (xy 17.41678 -303.004982)
			(xy 17.410196 -303.000655) (xy 17.39519 -302.995876) (xy 17.387316 -302.995584) (xy 16.871442 -302.995584)
			(xy 16.866148 -302.995052) (xy 16.858576 -302.987657) (xy 16.85798 -302.982376) (xy 2.509012 -302.982376)
			(xy 2.509012 -303.832514) (xy 20.958048 -303.832514) (xy 20.958048 -303.337976) (xy 20.958574 -303.332721)
			(xy 20.966002 -303.325282) (xy 20.971256 -303.324768) (xy 20.971764 -303.324768) (xy 21.487638 -303.324768)
			(xy 21.495446 -303.324433) (xy 21.510318 -303.319662) (xy 21.516848 -303.31537) (xy 21.537937 -303.301021)
			(xy 21.583598 -303.27829) (xy 21.632204 -303.262831) (xy 21.682607 -303.255008) (xy 21.733613 -303.255008)
			(xy 21.784016 -303.262831) (xy 21.832622 -303.27829) (xy 21.878283 -303.301021) (xy 21.899372 -303.31537)
			(xy 21.905912 -303.319646) (xy 21.920776 -303.324439) (xy 21.928582 -303.324768) (xy 22.44471 -303.324768)
			(xy 22.450022 -303.32522) (xy 22.457594 -303.332673) (xy 22.458172 -303.337976) (xy 22.458172 -303.832514)
			(xy 22.458148 -303.832768) (xy 28.502356 -303.832768) (xy 28.502356 -303.83226) (xy 28.502356 -303.337976)
			(xy 28.502875 -303.332719) (xy 28.510308 -303.32528) (xy 28.515564 -303.324768) (xy 29.031692 -303.324768)
			(xy 29.039502 -303.324456) (xy 29.054374 -303.31967) (xy 29.060902 -303.31537) (xy 29.081991 -303.301021)
			(xy 29.127652 -303.27829) (xy 29.176258 -303.262831) (xy 29.226661 -303.255008) (xy 29.277667 -303.255008)
			(xy 29.32807 -303.262831) (xy 29.376676 -303.27829) (xy 29.422337 -303.301021) (xy 29.443426 -303.31537)
			(xy 29.449954 -303.319667) (xy 29.464827 -303.324447) (xy 29.472636 -303.324768) (xy 29.988764 -303.324768)
			(xy 29.994086 -303.325149) (xy 30.001627 -303.332656) (xy 30.001972 -303.337976) (xy 30.001972 -303.832514)
			(xy 30.001949 -303.832768) (xy 36.046156 -303.832768) (xy 36.046156 -303.83226) (xy 36.046156 -303.337976)
			(xy 36.046675 -303.332719) (xy 36.054108 -303.32528) (xy 36.059364 -303.324768) (xy 36.575492 -303.324768)
			(xy 36.583302 -303.324456) (xy 36.598174 -303.31967) (xy 36.604702 -303.31537) (xy 36.625791 -303.301021)
			(xy 36.671452 -303.27829) (xy 36.720058 -303.262831) (xy 36.770461 -303.255008) (xy 36.821467 -303.255008)
			(xy 36.87187 -303.262831) (xy 36.920476 -303.27829) (xy 36.966137 -303.301021) (xy 36.987226 -303.31537)
			(xy 36.993754 -303.319667) (xy 37.008627 -303.324447) (xy 37.016436 -303.324768) (xy 37.532564 -303.324768)
			(xy 37.537886 -303.325149) (xy 37.545427 -303.332656) (xy 37.545772 -303.337976) (xy 37.545772 -303.832514)
			(xy 43.589956 -303.832514) (xy 43.589956 -303.337976) (xy 43.590475 -303.332719) (xy 43.597908 -303.32528)
			(xy 43.603164 -303.324768) (xy 43.603672 -303.324768) (xy 44.119546 -303.324768) (xy 44.127355 -303.324437)
			(xy 44.142226 -303.319663) (xy 44.148756 -303.31537) (xy 44.169845 -303.301021) (xy 44.215506 -303.27829)
			(xy 44.264112 -303.262831) (xy 44.314515 -303.255008) (xy 44.365521 -303.255008) (xy 44.415924 -303.262831)
			(xy 44.46453 -303.27829) (xy 44.510191 -303.301021) (xy 44.53128 -303.31537) (xy 44.537819 -303.319649)
			(xy 44.552683 -303.32444) (xy 44.56049 -303.324768) (xy 45.076618 -303.324768) (xy 45.081931 -303.325214)
			(xy 45.089503 -303.332671) (xy 45.09008 -303.337976) (xy 45.09008 -303.832514) (xy 45.090055 -303.832768)
			(xy 51.134264 -303.832768) (xy 51.134264 -303.83226) (xy 51.134264 -303.337976) (xy 51.134776 -303.332717)
			(xy 51.142213 -303.325278) (xy 51.147472 -303.324768) (xy 51.6636 -303.324768) (xy 51.671411 -303.32446)
			(xy 51.686282 -303.319671) (xy 51.69281 -303.31537) (xy 51.713899 -303.301021) (xy 51.75956 -303.27829)
			(xy 51.808166 -303.262831) (xy 51.858569 -303.255008) (xy 51.909575 -303.255008) (xy 51.959978 -303.262831)
			(xy 52.008584 -303.27829) (xy 52.054245 -303.301021) (xy 52.075334 -303.31537) (xy 52.081861 -303.31967)
			(xy 52.096734 -303.324448) (xy 52.104544 -303.324768) (xy 52.620672 -303.324768) (xy 52.625995 -303.325143)
			(xy 52.633536 -303.332655) (xy 52.63388 -303.337976) (xy 52.63388 -303.832514) (xy 58.678064 -303.832514)
			(xy 58.678064 -303.337976) (xy 58.678576 -303.332717) (xy 58.686013 -303.325278) (xy 58.691272 -303.324768)
			(xy 58.69178 -303.324768) (xy 60.164726 -303.324768) (xy 60.17004 -303.325209) (xy 60.177611 -303.33267)
			(xy 60.178188 -303.337976) (xy 60.178188 -303.832514) (xy 60.177661 -303.837873) (xy 60.170085 -303.845457)
			(xy 60.164726 -303.845976) (xy 58.691526 -303.845976) (xy 58.686098 -303.845605) (xy 58.678411 -303.837941)
			(xy 58.678064 -303.832514) (xy 52.63388 -303.832514) (xy 52.633388 -303.837815) (xy 52.625963 -303.845384)
			(xy 52.620672 -303.845976) (xy 52.104798 -303.845976) (xy 52.096986 -303.846276) (xy 52.082115 -303.85107)
			(xy 52.075588 -303.855374) (xy 52.054469 -303.869727) (xy 52.008744 -303.892452) (xy 51.96007 -303.907881)
			(xy 51.909603 -303.915647) (xy 51.884072 -303.91608) (xy 51.858541 -303.915655) (xy 51.808077 -303.907875)
			(xy 51.759405 -303.892442) (xy 51.713678 -303.869723) (xy 51.692556 -303.855374) (xy 51.686029 -303.851074)
			(xy 51.671156 -303.846295) (xy 51.663346 -303.845976) (xy 51.147472 -303.845976) (xy 51.142128 -303.845689)
			(xy 51.134587 -303.838113) (xy 51.134264 -303.832768) (xy 45.090055 -303.832768) (xy 45.089561 -303.837875)
			(xy 45.081979 -303.845459) (xy 45.076618 -303.845976) (xy 44.560744 -303.845976) (xy 44.552934 -303.846296)
			(xy 44.538062 -303.851076) (xy 44.531534 -303.855374) (xy 44.51043 -303.869751) (xy 44.4647 -303.89247)
			(xy 44.416021 -303.907893) (xy 44.36555 -303.915651) (xy 44.340018 -303.91608) (xy 44.314488 -303.915632)
			(xy 44.264025 -303.907859) (xy 44.215353 -303.892433) (xy 44.169624 -303.86972) (xy 44.148502 -303.855374)
			(xy 44.141965 -303.851092) (xy 44.127099 -303.846302) (xy 44.119292 -303.845976) (xy 43.603418 -303.845976)
			(xy 43.597989 -303.84561) (xy 43.590303 -303.837942) (xy 43.589956 -303.832514) (xy 37.545772 -303.832514)
			(xy 37.545287 -303.837817) (xy 37.537857 -303.845386) (xy 37.532564 -303.845976) (xy 37.01669 -303.845976)
			(xy 37.008878 -303.846273) (xy 36.994006 -303.851069) (xy 36.98748 -303.855374) (xy 36.966363 -303.869731)
			(xy 36.920637 -303.892455) (xy 36.871963 -303.907883) (xy 36.821495 -303.915648) (xy 36.795964 -303.91608)
			(xy 36.770433 -303.915659) (xy 36.719969 -303.907878) (xy 36.671297 -303.892444) (xy 36.62557 -303.869723)
			(xy 36.604448 -303.855374) (xy 36.597923 -303.851071) (xy 36.583048 -303.846294) (xy 36.575238 -303.845976)
			(xy 36.059364 -303.845976) (xy 36.054089 -303.845526) (xy 36.046647 -303.838045) (xy 36.046156 -303.832768)
			(xy 30.001949 -303.832768) (xy 30.001487 -303.837817) (xy 29.994057 -303.845386) (xy 29.988764 -303.845976)
			(xy 29.47289 -303.845976) (xy 29.465078 -303.846273) (xy 29.450206 -303.851069) (xy 29.44368 -303.855374)
			(xy 29.422563 -303.869731) (xy 29.376837 -303.892455) (xy 29.328163 -303.907883) (xy 29.277695 -303.915648)
			(xy 29.252164 -303.91608) (xy 29.226633 -303.915659) (xy 29.176169 -303.907878) (xy 29.127497 -303.892444)
			(xy 29.08177 -303.869723) (xy 29.060648 -303.855374) (xy 29.054123 -303.851071) (xy 29.039248 -303.846294)
			(xy 29.031438 -303.845976) (xy 28.515564 -303.845976) (xy 28.510289 -303.845526) (xy 28.502847 -303.838045)
			(xy 28.502356 -303.832768) (xy 22.458148 -303.832768) (xy 22.45766 -303.837877) (xy 22.450073 -303.845461)
			(xy 22.44471 -303.845976) (xy 21.928836 -303.845976) (xy 21.921026 -303.846292) (xy 21.906154 -303.851075)
			(xy 21.899626 -303.855374) (xy 21.878496 -303.869711) (xy 21.832775 -303.89244) (xy 21.784104 -303.907873)
			(xy 21.73364 -303.915644) (xy 21.70811 -303.91608) (xy 21.68258 -303.915636) (xy 21.632117 -303.907862)
			(xy 21.583444 -303.892435) (xy 21.537716 -303.86972) (xy 21.516594 -303.855374) (xy 21.510059 -303.851089)
			(xy 21.495192 -303.846301) (xy 21.487384 -303.845976) (xy 20.97151 -303.845976) (xy 20.966151 -303.845444)
			(xy 20.958565 -303.837872) (xy 20.958048 -303.832514) (xy 2.509012 -303.832514) (xy 2.509012 -304.682398)
			(xy 16.85798 -304.682398) (xy 16.85798 -304.18786) (xy 16.858467 -304.182595) (xy 16.865922 -304.175156)
			(xy 16.871188 -304.174652) (xy 16.871696 -304.174652) (xy 17.38757 -304.174652) (xy 17.39538 -304.174333)
			(xy 17.410251 -304.169552) (xy 17.41678 -304.165254) (xy 17.437869 -304.150905) (xy 17.48353 -304.128174)
			(xy 17.532136 -304.112715) (xy 17.582539 -304.104892) (xy 17.633545 -304.104892) (xy 17.683948 -304.112715)
			(xy 17.732554 -304.128174) (xy 17.778215 -304.150905) (xy 17.799304 -304.165254) (xy 17.805838 -304.169541)
			(xy 17.820706 -304.174327) (xy 17.828514 -304.174652) (xy 18.344642 -304.174652) (xy 18.349954 -304.175097)
			(xy 18.357524 -304.182556) (xy 18.358104 -304.18786) (xy 18.358104 -304.682398) (xy 20.958048 -304.682398)
			(xy 20.958048 -304.18786) (xy 20.958564 -304.182603) (xy 20.965999 -304.175165) (xy 20.971256 -304.174652)
			(xy 20.971764 -304.174652) (xy 21.487638 -304.174652) (xy 21.495447 -304.17432) (xy 21.510318 -304.169547)
			(xy 21.516848 -304.165254) (xy 21.537937 -304.150905) (xy 21.583598 -304.128174) (xy 21.632204 -304.112715)
			(xy 21.682607 -304.104892) (xy 21.733613 -304.104892) (xy 21.784016 -304.112715) (xy 21.832622 -304.128174)
			(xy 21.878283 -304.150905) (xy 21.899372 -304.165254) (xy 21.905913 -304.169529) (xy 21.920776 -304.174323)
			(xy 21.928582 -304.174652) (xy 22.44471 -304.174652) (xy 22.450018 -304.175118) (xy 22.457589 -304.182561)
			(xy 22.458172 -304.18786) (xy 22.458172 -304.682398) (xy 22.458147 -304.682652) (xy 24.402288 -304.682652)
			(xy 24.402288 -304.682144) (xy 24.402288 -304.18786) (xy 24.402768 -304.182593) (xy 24.410228 -304.175153)
			(xy 24.415496 -304.174652) (xy 24.931624 -304.174652) (xy 24.939436 -304.174357) (xy 24.954308 -304.169559)
			(xy 24.960834 -304.165254) (xy 24.981923 -304.150905) (xy 25.027584 -304.128174) (xy 25.07619 -304.112715)
			(xy 25.126593 -304.104892) (xy 25.177599 -304.104892) (xy 25.228002 -304.112715) (xy 25.276608 -304.128174)
			(xy 25.322269 -304.150905) (xy 25.343358 -304.165254) (xy 25.34988 -304.169562) (xy 25.364757 -304.174335)
			(xy 25.372568 -304.174652) (xy 25.888696 -304.174652) (xy 25.893949 -304.175193) (xy 25.901389 -304.182609)
			(xy 25.901904 -304.18786) (xy 25.901904 -304.682398) (xy 25.901879 -304.682652) (xy 28.502356 -304.682652)
			(xy 28.502356 -304.682144) (xy 28.502356 -304.18786) (xy 28.502864 -304.182601) (xy 28.510305 -304.175163)
			(xy 28.515564 -304.174652) (xy 29.031692 -304.174652) (xy 29.039503 -304.174343) (xy 29.054374 -304.169554)
			(xy 29.060902 -304.165254) (xy 29.081991 -304.150905) (xy 29.127652 -304.128174) (xy 29.176258 -304.112715)
			(xy 29.226661 -304.104892) (xy 29.277667 -304.104892) (xy 29.32807 -304.112715) (xy 29.376676 -304.128174)
			(xy 29.422337 -304.150905) (xy 29.443426 -304.165254) (xy 29.449955 -304.169549) (xy 29.464827 -304.174331)
			(xy 29.472636 -304.174652) (xy 29.988764 -304.174652) (xy 29.994013 -304.175215) (xy 30.001455 -304.182614)
			(xy 30.001972 -304.18786) (xy 30.001972 -304.682398) (xy 30.001948 -304.682652) (xy 31.946088 -304.682652)
			(xy 31.946088 -304.682144) (xy 31.946088 -304.18786) (xy 31.946568 -304.182593) (xy 31.954028 -304.175153)
			(xy 31.959296 -304.174652) (xy 32.475424 -304.174652) (xy 32.483236 -304.174357) (xy 32.498108 -304.169559)
			(xy 32.504634 -304.165254) (xy 32.525723 -304.150905) (xy 32.571384 -304.128174) (xy 32.61999 -304.112715)
			(xy 32.670393 -304.104892) (xy 32.721399 -304.104892) (xy 32.771802 -304.112715) (xy 32.820408 -304.128174)
			(xy 32.866069 -304.150905) (xy 32.887158 -304.165254) (xy 32.89368 -304.169562) (xy 32.908557 -304.174335)
			(xy 32.916368 -304.174652) (xy 33.432496 -304.174652) (xy 33.437749 -304.175193) (xy 33.445189 -304.182609)
			(xy 33.445704 -304.18786) (xy 33.445704 -304.682398) (xy 33.445679 -304.682652) (xy 36.046156 -304.682652)
			(xy 36.046156 -304.682144) (xy 36.046156 -304.18786) (xy 36.046664 -304.182601) (xy 36.054105 -304.175163)
			(xy 36.059364 -304.174652) (xy 36.575492 -304.174652) (xy 36.583303 -304.174343) (xy 36.598174 -304.169554)
			(xy 36.604702 -304.165254) (xy 36.625791 -304.150905) (xy 36.671452 -304.128174) (xy 36.720058 -304.112715)
			(xy 36.770461 -304.104892) (xy 36.821467 -304.104892) (xy 36.87187 -304.112715) (xy 36.920476 -304.128174)
			(xy 36.966137 -304.150905) (xy 36.987226 -304.165254) (xy 36.993755 -304.169549) (xy 37.008627 -304.174331)
			(xy 37.016436 -304.174652) (xy 37.532564 -304.174652) (xy 37.537813 -304.175215) (xy 37.545255 -304.182614)
			(xy 37.545772 -304.18786) (xy 37.545772 -304.682398) (xy 39.489888 -304.682398) (xy 39.489888 -304.18786)
			(xy 39.490368 -304.182593) (xy 39.497828 -304.175153) (xy 39.503096 -304.174652) (xy 39.503604 -304.174652)
			(xy 40.019478 -304.174652) (xy 40.027288 -304.174337) (xy 40.04216 -304.169553) (xy 40.048688 -304.165254)
			(xy 40.069777 -304.150905) (xy 40.115438 -304.128174) (xy 40.164044 -304.112715) (xy 40.214447 -304.104892)
			(xy 40.265453 -304.104892) (xy 40.315856 -304.112715) (xy 40.364462 -304.128174) (xy 40.410123 -304.150905)
			(xy 40.431212 -304.165254) (xy 40.437744 -304.169544) (xy 40.452614 -304.174329) (xy 40.460422 -304.174652)
			(xy 40.97655 -304.174652) (xy 40.981851 -304.175158) (xy 40.989425 -304.182571) (xy 40.990012 -304.18786)
			(xy 40.990012 -304.682398) (xy 43.589956 -304.682398) (xy 43.589956 -304.18786) (xy 43.590464 -304.182601)
			(xy 43.597905 -304.175163) (xy 43.603164 -304.174652) (xy 43.603672 -304.174652) (xy 44.119546 -304.174652)
			(xy 44.127355 -304.174323) (xy 44.142227 -304.169548) (xy 44.148756 -304.165254) (xy 44.169845 -304.150905)
			(xy 44.215506 -304.128174) (xy 44.264112 -304.112715) (xy 44.314515 -304.104892) (xy 44.365521 -304.104892)
			(xy 44.415924 -304.112715) (xy 44.46453 -304.128174) (xy 44.510191 -304.150905) (xy 44.53128 -304.165254)
			(xy 44.537819 -304.169532) (xy 44.552683 -304.174324) (xy 44.56049 -304.174652) (xy 45.076618 -304.174652)
			(xy 45.081927 -304.175112) (xy 45.089498 -304.18256) (xy 45.09008 -304.18786) (xy 45.09008 -304.682398)
			(xy 45.090055 -304.682652) (xy 47.034196 -304.682652) (xy 47.034196 -304.682144) (xy 47.034196 -304.18786)
			(xy 47.034668 -304.182591) (xy 47.042134 -304.175151) (xy 47.047404 -304.174652) (xy 47.563532 -304.174652)
			(xy 47.57134 -304.174317) (xy 47.586212 -304.169547) (xy 47.592742 -304.165254) (xy 47.613831 -304.150905)
			(xy 47.659492 -304.128174) (xy 47.708098 -304.112715) (xy 47.758501 -304.104892) (xy 47.809507 -304.104892)
			(xy 47.85991 -304.112715) (xy 47.908516 -304.128174) (xy 47.954177 -304.150905) (xy 47.975266 -304.165254)
			(xy 47.981809 -304.169526) (xy 47.99667 -304.174322) (xy 48.004476 -304.174652) (xy 48.520604 -304.174652)
			(xy 48.525858 -304.175188) (xy 48.533298 -304.182608) (xy 48.533812 -304.18786) (xy 48.533812 -304.682398)
			(xy 48.533791 -304.682652) (xy 51.134264 -304.682652) (xy 51.134264 -304.682144) (xy 51.134264 -304.18786)
			(xy 51.134765 -304.182599) (xy 51.142211 -304.17516) (xy 51.147472 -304.174652) (xy 51.6636 -304.174652)
			(xy 51.671411 -304.174347) (xy 51.686283 -304.169556) (xy 51.69281 -304.165254) (xy 51.713899 -304.150905)
			(xy 51.75956 -304.128174) (xy 51.808166 -304.112715) (xy 51.858569 -304.104892) (xy 51.909575 -304.104892)
			(xy 51.959978 -304.112715) (xy 52.008584 -304.128174) (xy 52.054245 -304.150905) (xy 52.075334 -304.165254)
			(xy 52.081861 -304.169552) (xy 52.096734 -304.174332) (xy 52.104544 -304.174652) (xy 52.620672 -304.174652)
			(xy 52.625922 -304.175209) (xy 52.633364 -304.182613) (xy 52.63388 -304.18786) (xy 52.63388 -304.682398)
			(xy 54.577996 -304.682398) (xy 54.577996 -304.18786) (xy 54.578468 -304.182591) (xy 54.585934 -304.175151)
			(xy 54.591204 -304.174652) (xy 56.064658 -304.174652) (xy 56.06996 -304.175153) (xy 56.077534 -304.182569)
			(xy 56.07812 -304.18786) (xy 56.07812 -304.682398) (xy 58.678064 -304.682398) (xy 58.678064 -304.18786)
			(xy 58.678565 -304.182599) (xy 58.686011 -304.17516) (xy 58.691272 -304.174652) (xy 58.69178 -304.174652)
			(xy 60.164726 -304.174652) (xy 60.170036 -304.175107) (xy 60.177606 -304.182559) (xy 60.178188 -304.18786)
			(xy 60.178188 -304.682398) (xy 60.177651 -304.687755) (xy 60.170082 -304.69534) (xy 60.164726 -304.69586)
			(xy 58.691526 -304.69586) (xy 58.686094 -304.695503) (xy 58.678406 -304.687829) (xy 58.678064 -304.682398)
			(xy 56.07812 -304.682398) (xy 56.077815 -304.687843) (xy 56.070104 -304.695531) (xy 56.064658 -304.69586)
			(xy 54.591458 -304.69586) (xy 54.586088 -304.695377) (xy 54.578505 -304.687769) (xy 54.577996 -304.682398)
			(xy 52.63388 -304.682398) (xy 52.633378 -304.687697) (xy 52.62596 -304.695267) (xy 52.620672 -304.69586)
			(xy 52.104798 -304.69586) (xy 52.096987 -304.696163) (xy 52.082115 -304.700955) (xy 52.075588 -304.705258)
			(xy 52.054468 -304.719609) (xy 52.008743 -304.742335) (xy 51.96007 -304.757765) (xy 51.909603 -304.765531)
			(xy 51.884072 -304.765964) (xy 51.858541 -304.765542) (xy 51.808077 -304.757761) (xy 51.759404 -304.742328)
			(xy 51.713677 -304.719607) (xy 51.692556 -304.705258) (xy 51.68603 -304.700957) (xy 51.671156 -304.696179)
			(xy 51.663346 -304.69586) (xy 51.147472 -304.69586) (xy 51.142124 -304.695587) (xy 51.134582 -304.688002)
			(xy 51.134264 -304.682652) (xy 48.533791 -304.682652) (xy 48.53337 -304.687713) (xy 48.525911 -304.695287)
			(xy 48.520604 -304.69586) (xy 48.00473 -304.69586) (xy 47.99692 -304.696176) (xy 47.982048 -304.70096)
			(xy 47.97552 -304.705258) (xy 47.954391 -304.719596) (xy 47.90867 -304.742325) (xy 47.859999 -304.757758)
			(xy 47.809534 -304.765529) (xy 47.784004 -304.765964) (xy 47.758474 -304.765526) (xy 47.70801 -304.75775)
			(xy 47.659338 -304.742322) (xy 47.61361 -304.719605) (xy 47.592488 -304.705258) (xy 47.585955 -304.700969)
			(xy 47.571086 -304.696184) (xy 47.563278 -304.69586) (xy 47.047404 -304.69586) (xy 47.042061 -304.695566)
			(xy 47.034517 -304.687996) (xy 47.034196 -304.682652) (xy 45.090055 -304.682652) (xy 45.08955 -304.687757)
			(xy 45.081977 -304.695342) (xy 45.076618 -304.69586) (xy 44.560744 -304.69586) (xy 44.552935 -304.696182)
			(xy 44.538063 -304.700961) (xy 44.531534 -304.705258) (xy 44.510429 -304.719633) (xy 44.464699 -304.742353)
			(xy 44.416021 -304.757776) (xy 44.36555 -304.765535) (xy 44.340018 -304.765964) (xy 44.314488 -304.765519)
			(xy 44.264025 -304.757745) (xy 44.215352 -304.742319) (xy 44.169624 -304.719604) (xy 44.148502 -304.705258)
			(xy 44.141966 -304.700974) (xy 44.1271 -304.696186) (xy 44.119292 -304.69586) (xy 43.603418 -304.69586)
			(xy 43.597985 -304.695509) (xy 43.590298 -304.687831) (xy 43.589956 -304.682398) (xy 40.990012 -304.682398)
			(xy 40.989453 -304.68775) (xy 40.9819 -304.695333) (xy 40.97655 -304.69586) (xy 40.460676 -304.69586)
			(xy 40.452864 -304.696153) (xy 40.437992 -304.700952) (xy 40.431466 -304.705258) (xy 40.410352 -304.719619)
			(xy 40.364625 -304.742343) (xy 40.31595 -304.75777) (xy 40.265482 -304.765533) (xy 40.23995 -304.765964)
			(xy 40.214421 -304.765502) (xy 40.163958 -304.757734) (xy 40.115285 -304.742312) (xy 40.069557 -304.719602)
			(xy 40.048434 -304.705258) (xy 40.041891 -304.700987) (xy 40.02703 -304.69619) (xy 40.019224 -304.69586)
			(xy 39.50335 -304.69586) (xy 39.49798 -304.695382) (xy 39.490397 -304.68777) (xy 39.489888 -304.682398)
			(xy 37.545772 -304.682398) (xy 37.545277 -304.687699) (xy 37.537854 -304.69527) (xy 37.532564 -304.69586)
			(xy 37.01669 -304.69586) (xy 37.008878 -304.69616) (xy 36.994007 -304.700954) (xy 36.98748 -304.705258)
			(xy 36.966362 -304.719613) (xy 36.920637 -304.742338) (xy 36.871962 -304.757767) (xy 36.821495 -304.765532)
			(xy 36.795964 -304.765964) (xy 36.770433 -304.765546) (xy 36.719968 -304.757764) (xy 36.671296 -304.74233)
			(xy 36.625569 -304.719608) (xy 36.604448 -304.705258) (xy 36.597924 -304.700954) (xy 36.583048 -304.696178)
			(xy 36.575238 -304.69586) (xy 36.059364 -304.69586) (xy 36.054015 -304.695593) (xy 36.046473 -304.688003)
			(xy 36.046156 -304.682652) (xy 33.445679 -304.682652) (xy 33.445181 -304.687692) (xy 33.437778 -304.69526)
			(xy 33.432496 -304.69586) (xy 32.916622 -304.69586) (xy 32.908812 -304.696173) (xy 32.89394 -304.700958)
			(xy 32.887412 -304.705258) (xy 32.866285 -304.719599) (xy 32.820563 -304.742327) (xy 32.771891 -304.75776)
			(xy 32.721426 -304.765529) (xy 32.695896 -304.765964) (xy 32.670366 -304.76553) (xy 32.619902 -304.757753)
			(xy 32.571229 -304.742323) (xy 32.525502 -304.719606) (xy 32.50438 -304.705258) (xy 32.497849 -304.700966)
			(xy 32.482979 -304.696182) (xy 32.47517 -304.69586) (xy 31.959296 -304.69586) (xy 31.953951 -304.695571)
			(xy 31.946408 -304.687998) (xy 31.946088 -304.682652) (xy 30.001948 -304.682652) (xy 30.001477 -304.687699)
			(xy 29.994054 -304.69527) (xy 29.988764 -304.69586) (xy 29.47289 -304.69586) (xy 29.465078 -304.69616)
			(xy 29.450207 -304.700954) (xy 29.44368 -304.705258) (xy 29.422562 -304.719613) (xy 29.376837 -304.742338)
			(xy 29.328162 -304.757767) (xy 29.277695 -304.765532) (xy 29.252164 -304.765964) (xy 29.226633 -304.765546)
			(xy 29.176168 -304.757764) (xy 29.127496 -304.74233) (xy 29.081769 -304.719608) (xy 29.060648 -304.705258)
			(xy 29.054124 -304.700954) (xy 29.039248 -304.696178) (xy 29.031438 -304.69586) (xy 28.515564 -304.69586)
			(xy 28.510215 -304.695593) (xy 28.502673 -304.688003) (xy 28.502356 -304.682652) (xy 25.901879 -304.682652)
			(xy 25.901381 -304.687692) (xy 25.893978 -304.69526) (xy 25.888696 -304.69586) (xy 25.372822 -304.69586)
			(xy 25.365012 -304.696173) (xy 25.35014 -304.700958) (xy 25.343612 -304.705258) (xy 25.322485 -304.719599)
			(xy 25.276763 -304.742327) (xy 25.228091 -304.75776) (xy 25.177626 -304.765529) (xy 25.152096 -304.765964)
			(xy 25.126566 -304.76553) (xy 25.076102 -304.757753) (xy 25.027429 -304.742323) (xy 24.981702 -304.719606)
			(xy 24.96058 -304.705258) (xy 24.954049 -304.700966) (xy 24.939179 -304.696182) (xy 24.93137 -304.69586)
			(xy 24.415496 -304.69586) (xy 24.410151 -304.695571) (xy 24.402608 -304.687998) (xy 24.402288 -304.682652)
			(xy 22.458147 -304.682652) (xy 22.457649 -304.687759) (xy 22.450071 -304.695345) (xy 22.44471 -304.69586)
			(xy 21.928836 -304.69586) (xy 21.921026 -304.696179) (xy 21.906154 -304.70096) (xy 21.899626 -304.705258)
			(xy 21.878495 -304.719593) (xy 21.832775 -304.742323) (xy 21.784104 -304.757757) (xy 21.73364 -304.765528)
			(xy 21.70811 -304.765964) (xy 21.68258 -304.765523) (xy 21.632116 -304.757748) (xy 21.583444 -304.74232)
			(xy 21.537716 -304.719605) (xy 21.516594 -304.705258) (xy 21.51006 -304.700971) (xy 21.495192 -304.696184)
			(xy 21.487384 -304.69586) (xy 20.97151 -304.69586) (xy 20.966076 -304.695514) (xy 20.958389 -304.687832)
			(xy 20.958048 -304.682398) (xy 18.358104 -304.682398) (xy 18.357553 -304.687752) (xy 18.349994 -304.695335)
			(xy 18.344642 -304.69586) (xy 17.828768 -304.69586) (xy 17.820959 -304.696193) (xy 17.806088 -304.700964)
			(xy 17.799558 -304.705258) (xy 17.778446 -304.719622) (xy 17.732719 -304.742345) (xy 17.684042 -304.757771)
			(xy 17.633574 -304.765533) (xy 17.608042 -304.765964) (xy 17.582513 -304.765506) (xy 17.53205 -304.757737)
			(xy 17.483377 -304.742314) (xy 17.437649 -304.719603) (xy 17.416526 -304.705258) (xy 17.409985 -304.700984)
			(xy 17.395122 -304.696189) (xy 17.387316 -304.69586) (xy 16.871442 -304.69586) (xy 16.866012 -304.695492)
			(xy 16.858324 -304.687827) (xy 16.85798 -304.682398) (xy 2.509012 -304.682398) (xy 2.509012 -304.780442)
			(xy 78.811632 -304.780442) (xy 78.815662 -304.638078) (xy 78.82774 -304.49617) (xy 78.847828 -304.355173)
			(xy 78.87586 -304.215538) (xy 78.911747 -304.077712) (xy 78.955374 -303.942138) (xy 79.006601 -303.809249)
			(xy 79.065264 -303.67947) (xy 79.131176 -303.553219) (xy 79.204125 -303.430899) (xy 79.283877 -303.312902)
			(xy 79.370177 -303.199606) (xy 79.462749 -303.091373) (xy 79.561295 -302.988551) (xy 79.665501 -302.89147)
			(xy 79.775033 -302.800439) (xy 79.889539 -302.715751) (xy 80.008653 -302.637676) (xy 80.131993 -302.566466)
			(xy 80.259164 -302.502347) (xy 80.38976 -302.445526) (xy 80.52336 -302.396185) (xy 80.659539 -302.35448)
			(xy 80.797858 -302.320547) (xy 80.937876 -302.294494) (xy 81.079143 -302.276404) (xy 81.221208 -302.266335)
			(xy 81.363615 -302.26432) (xy 81.505908 -302.270364) (xy 81.64763 -302.28445) (xy 81.788329 -302.30653)
			(xy 81.927554 -302.336535) (xy 82.064858 -302.374369) (xy 82.199801 -302.41991) (xy 82.331952 -302.473013)
			(xy 82.460887 -302.533507) (xy 82.586193 -302.601198) (xy 82.707469 -302.675871) (xy 82.824325 -302.757285)
			(xy 82.936389 -302.845179) (xy 83.043301 -302.939273) (xy 83.144718 -303.039265) (xy 83.240315 -303.144834)
			(xy 83.329787 -303.255643) (xy 83.412846 -303.371336) (xy 83.489227 -303.491543) (xy 83.558685 -303.615878)
			(xy 83.620998 -303.743944) (xy 83.675965 -303.875331) (xy 83.723411 -304.009616) (xy 83.763184 -304.146371)
			(xy 83.795156 -304.285157) (xy 83.819226 -304.425529) (xy 83.835315 -304.567039) (xy 83.843372 -304.709231)
			(xy 83.843876 -304.780442) (xy 140.011408 -304.780442) (xy 140.015438 -304.638078) (xy 140.027516 -304.49617)
			(xy 140.047604 -304.355173) (xy 140.075636 -304.215538) (xy 140.111523 -304.077712) (xy 140.15515 -303.942138)
			(xy 140.206377 -303.809249) (xy 140.26504 -303.67947) (xy 140.330952 -303.553219) (xy 140.403901 -303.430899)
			(xy 140.483653 -303.312902) (xy 140.569953 -303.199606) (xy 140.662525 -303.091373) (xy 140.761071 -302.988551)
			(xy 140.865277 -302.89147) (xy 140.974809 -302.800439) (xy 141.089315 -302.715751) (xy 141.208429 -302.637676)
			(xy 141.331769 -302.566466) (xy 141.45894 -302.502347) (xy 141.589536 -302.445526) (xy 141.723136 -302.396185)
			(xy 141.859315 -302.35448) (xy 141.997634 -302.320547) (xy 142.137652 -302.294494) (xy 142.278919 -302.276404)
			(xy 142.420984 -302.266335) (xy 142.563391 -302.26432) (xy 142.705684 -302.270364) (xy 142.847406 -302.28445)
			(xy 142.988105 -302.30653) (xy 143.12733 -302.336535) (xy 143.264634 -302.374369) (xy 143.399577 -302.41991)
			(xy 143.531728 -302.473013) (xy 143.660663 -302.533507) (xy 143.785969 -302.601198) (xy 143.907245 -302.675871)
			(xy 144.024101 -302.757285) (xy 144.136165 -302.845179) (xy 144.243077 -302.939273) (xy 144.286794 -302.982376)
			(xy 163.678108 -302.982376) (xy 163.678108 -302.487838) (xy 163.678645 -302.482546) (xy 163.686037 -302.474975)
			(xy 163.691316 -302.474376) (xy 165.164516 -302.474376) (xy 165.169777 -302.474882) (xy 165.177218 -302.482323)
			(xy 165.177724 -302.487584) (xy 165.177724 -302.488092) (xy 165.177724 -302.982376) (xy 171.221908 -302.982376)
			(xy 171.221908 -302.487838) (xy 171.222302 -302.482415) (xy 171.229949 -302.474729) (xy 171.23537 -302.474376)
			(xy 171.751498 -302.474376) (xy 171.759308 -302.474066) (xy 171.77418 -302.469278) (xy 171.780708 -302.464978)
			(xy 171.801797 -302.450629) (xy 171.847458 -302.427898) (xy 171.896064 -302.412439) (xy 171.946467 -302.404616)
			(xy 171.997473 -302.404616) (xy 172.047876 -302.412439) (xy 172.096482 -302.427898) (xy 172.142143 -302.450629)
			(xy 172.163232 -302.464978) (xy 172.169759 -302.469278) (xy 172.184632 -302.474056) (xy 172.192442 -302.474376)
			(xy 172.70857 -302.474376) (xy 172.71401 -302.474703) (xy 172.7217 -302.482398) (xy 172.722032 -302.487838)
			(xy 172.722032 -302.982376) (xy 178.766216 -302.982376) (xy 178.766216 -302.487838) (xy 178.766746 -302.482544)
			(xy 178.774143 -302.474972) (xy 178.779424 -302.474376) (xy 179.295552 -302.474376) (xy 179.303361 -302.474046)
			(xy 179.318232 -302.469271) (xy 179.324762 -302.464978) (xy 179.345851 -302.450629) (xy 179.391512 -302.427898)
			(xy 179.440118 -302.412439) (xy 179.490521 -302.404616) (xy 179.541527 -302.404616) (xy 179.59193 -302.412439)
			(xy 179.640536 -302.427898) (xy 179.686197 -302.450629) (xy 179.707286 -302.464978) (xy 179.713823 -302.46926)
			(xy 179.728689 -302.474049) (xy 179.736496 -302.474376) (xy 180.252624 -302.474376) (xy 180.257886 -302.474877)
			(xy 180.265326 -302.482322) (xy 180.265832 -302.487584) (xy 180.265832 -302.488092) (xy 180.265832 -302.982376)
			(xy 186.310016 -302.982376) (xy 186.310016 -302.487838) (xy 186.310402 -302.482413) (xy 186.318055 -302.474727)
			(xy 186.323478 -302.474376) (xy 186.839606 -302.474376) (xy 186.847417 -302.474069) (xy 186.862288 -302.469279)
			(xy 186.868816 -302.464978) (xy 186.889905 -302.450629) (xy 186.935566 -302.427898) (xy 186.984172 -302.412439)
			(xy 187.034575 -302.404616) (xy 187.085581 -302.404616) (xy 187.135984 -302.412439) (xy 187.18459 -302.427898)
			(xy 187.230251 -302.450629) (xy 187.25134 -302.464978) (xy 187.257865 -302.469281) (xy 187.27274 -302.474057)
			(xy 187.28055 -302.474376) (xy 187.796678 -302.474376) (xy 187.802119 -302.474698) (xy 187.809809 -302.482397)
			(xy 187.81014 -302.487838) (xy 187.81014 -302.982376) (xy 193.854324 -302.982376) (xy 193.854324 -302.487838)
			(xy 193.854847 -302.482542) (xy 193.862248 -302.47497) (xy 193.867532 -302.474376) (xy 194.38366 -302.474376)
			(xy 194.391469 -302.474049) (xy 194.40634 -302.469272) (xy 194.41287 -302.464978) (xy 194.433959 -302.450629)
			(xy 194.47962 -302.427898) (xy 194.528226 -302.412439) (xy 194.578629 -302.404616) (xy 194.629635 -302.404616)
			(xy 194.680038 -302.412439) (xy 194.728644 -302.427898) (xy 194.774305 -302.450629) (xy 194.795394 -302.464978)
			(xy 194.801929 -302.469263) (xy 194.816796 -302.47405) (xy 194.824604 -302.474376) (xy 195.340732 -302.474376)
			(xy 195.345995 -302.474872) (xy 195.353435 -302.482321) (xy 195.35394 -302.487584) (xy 195.35394 -302.488092)
			(xy 195.35394 -302.982376) (xy 201.398124 -302.982376) (xy 201.398124 -302.487838) (xy 201.398647 -302.482542)
			(xy 201.406048 -302.47497) (xy 201.411332 -302.474376) (xy 201.92746 -302.474376) (xy 201.935269 -302.474049)
			(xy 201.95014 -302.469272) (xy 201.95667 -302.464978) (xy 201.977759 -302.450629) (xy 202.02342 -302.427898)
			(xy 202.072026 -302.412439) (xy 202.122429 -302.404616) (xy 202.173435 -302.404616) (xy 202.223838 -302.412439)
			(xy 202.272444 -302.427898) (xy 202.318105 -302.450629) (xy 202.339194 -302.464978) (xy 202.345729 -302.469263)
			(xy 202.360596 -302.47405) (xy 202.368404 -302.474376) (xy 202.884532 -302.474376) (xy 202.889795 -302.474872)
			(xy 202.897235 -302.482321) (xy 202.89774 -302.487584) (xy 202.89774 -302.488092) (xy 202.89774 -302.982122)
			(xy 264.798048 -302.982122) (xy 264.798048 -302.487584) (xy 264.798579 -302.48233) (xy 264.806003 -302.474891)
			(xy 264.811256 -302.474376) (xy 264.811764 -302.474376) (xy 265.327638 -302.474376) (xy 265.335446 -302.47404)
			(xy 265.350318 -302.46927) (xy 265.356848 -302.464978) (xy 265.377937 -302.450629) (xy 265.423598 -302.427898)
			(xy 265.472204 -302.412439) (xy 265.522607 -302.404616) (xy 265.573613 -302.404616) (xy 265.624016 -302.412439)
			(xy 265.672622 -302.427898) (xy 265.718283 -302.450629) (xy 265.739372 -302.464978) (xy 265.745912 -302.469255)
			(xy 265.760775 -302.474047) (xy 265.768582 -302.474376) (xy 266.28471 -302.474376) (xy 266.290024 -302.474821)
			(xy 266.297596 -302.482278) (xy 266.298172 -302.487584) (xy 266.298172 -302.982122) (xy 266.298148 -302.982376)
			(xy 272.342356 -302.982376) (xy 272.342356 -302.981868) (xy 272.342356 -302.487584) (xy 272.34288 -302.482328)
			(xy 272.350309 -302.474888) (xy 272.355564 -302.474376) (xy 272.871692 -302.474376) (xy 272.879502 -302.474063)
			(xy 272.894374 -302.469277) (xy 272.900902 -302.464978) (xy 272.921991 -302.450629) (xy 272.967652 -302.427898)
			(xy 273.016258 -302.412439) (xy 273.066661 -302.404616) (xy 273.117667 -302.404616) (xy 273.16807 -302.412439)
			(xy 273.216676 -302.427898) (xy 273.262337 -302.450629) (xy 273.283426 -302.464978) (xy 273.289954 -302.469276)
			(xy 273.304827 -302.474055) (xy 273.312636 -302.474376) (xy 273.828764 -302.474376) (xy 273.834088 -302.474749)
			(xy 273.84163 -302.482262) (xy 273.841972 -302.487584) (xy 273.841972 -302.982122) (xy 273.841949 -302.982376)
			(xy 279.886156 -302.982376) (xy 279.886156 -302.981868) (xy 279.886156 -302.487584) (xy 279.88668 -302.482328)
			(xy 279.894109 -302.474888) (xy 279.899364 -302.474376) (xy 280.415492 -302.474376) (xy 280.423302 -302.474063)
			(xy 280.438174 -302.469277) (xy 280.444702 -302.464978) (xy 280.465791 -302.450629) (xy 280.511452 -302.427898)
			(xy 280.560058 -302.412439) (xy 280.610461 -302.404616) (xy 280.661467 -302.404616) (xy 280.71187 -302.412439)
			(xy 280.760476 -302.427898) (xy 280.806137 -302.450629) (xy 280.827226 -302.464978) (xy 280.833754 -302.469276)
			(xy 280.848627 -302.474055) (xy 280.856436 -302.474376) (xy 281.372564 -302.474376) (xy 281.377888 -302.474749)
			(xy 281.38543 -302.482262) (xy 281.385772 -302.487584) (xy 281.385772 -302.982122) (xy 287.429956 -302.982122)
			(xy 287.429956 -302.487584) (xy 287.43048 -302.482328) (xy 287.437909 -302.474888) (xy 287.443164 -302.474376)
			(xy 287.443672 -302.474376) (xy 287.959546 -302.474376) (xy 287.967354 -302.474043) (xy 287.982226 -302.469271)
			(xy 287.988756 -302.464978) (xy 288.009845 -302.450629) (xy 288.055506 -302.427898) (xy 288.104112 -302.412439)
			(xy 288.154515 -302.404616) (xy 288.205521 -302.404616) (xy 288.255924 -302.412439) (xy 288.30453 -302.427898)
			(xy 288.350191 -302.450629) (xy 288.37128 -302.464978) (xy 288.377818 -302.469258) (xy 288.392683 -302.474048)
			(xy 288.40049 -302.474376) (xy 288.916618 -302.474376) (xy 288.921933 -302.474815) (xy 288.929505 -302.482277)
			(xy 288.93008 -302.487584) (xy 288.93008 -302.982122) (xy 288.930056 -302.982376) (xy 294.974264 -302.982376)
			(xy 294.974264 -302.981868) (xy 294.974264 -302.487584) (xy 294.974781 -302.482326) (xy 294.982214 -302.474886)
			(xy 294.987472 -302.474376) (xy 295.5036 -302.474376) (xy 295.511411 -302.474066) (xy 295.526282 -302.469278)
			(xy 295.53281 -302.464978) (xy 295.553899 -302.450629) (xy 295.59956 -302.427898) (xy 295.648166 -302.412439)
			(xy 295.698569 -302.404616) (xy 295.749575 -302.404616) (xy 295.799978 -302.412439) (xy 295.848584 -302.427898)
			(xy 295.894245 -302.450629) (xy 295.915334 -302.464978) (xy 295.92186 -302.469279) (xy 295.936734 -302.474056)
			(xy 295.944544 -302.474376) (xy 296.460672 -302.474376) (xy 296.465997 -302.474744) (xy 296.473538 -302.48226)
			(xy 296.47388 -302.487584) (xy 296.47388 -302.982122) (xy 302.518064 -302.982122) (xy 302.518064 -302.487584)
			(xy 302.518581 -302.482326) (xy 302.526014 -302.474886) (xy 302.531272 -302.474376) (xy 304.004726 -302.474376)
			(xy 304.010042 -302.47481) (xy 304.017613 -302.482276) (xy 304.018188 -302.487584) (xy 304.018188 -302.982122)
			(xy 304.017667 -302.987482) (xy 304.010086 -302.995065) (xy 304.004726 -302.995584) (xy 302.531526 -302.995584)
			(xy 302.5261 -302.995206) (xy 302.518414 -302.987547) (xy 302.518064 -302.982122) (xy 296.47388 -302.982122)
			(xy 296.473394 -302.987424) (xy 296.465964 -302.994993) (xy 296.460672 -302.995584) (xy 295.944798 -302.995584)
			(xy 295.936986 -302.995883) (xy 295.922114 -303.000678) (xy 295.915588 -303.004982) (xy 295.89447 -303.019336)
			(xy 295.848744 -303.042061) (xy 295.80007 -303.057489) (xy 295.749603 -303.065255) (xy 295.724072 -303.065688)
			(xy 295.698541 -303.065261) (xy 295.648077 -303.057482) (xy 295.599405 -303.04205) (xy 295.553678 -303.01933)
			(xy 295.532556 -303.004982) (xy 295.526029 -303.000683) (xy 295.511156 -302.995903) (xy 295.503346 -302.995584)
			(xy 294.987472 -302.995584) (xy 294.9822 -302.995122) (xy 294.974758 -302.98765) (xy 294.974264 -302.982376)
			(xy 288.930056 -302.982376) (xy 288.929566 -302.987484) (xy 288.92198 -302.995068) (xy 288.916618 -302.995584)
			(xy 288.400744 -302.995584) (xy 288.392934 -302.995902) (xy 288.378062 -303.000684) (xy 288.371534 -303.004982)
			(xy 288.350431 -303.01936) (xy 288.3047 -303.042079) (xy 288.256021 -303.057501) (xy 288.20555 -303.065259)
			(xy 288.180018 -303.065688) (xy 288.154488 -303.065238) (xy 288.104025 -303.057466) (xy 288.055353 -303.04204)
			(xy 288.009625 -303.019328) (xy 287.988502 -303.004982) (xy 287.981965 -303.000701) (xy 287.967099 -302.99591)
			(xy 287.959292 -302.995584) (xy 287.443418 -302.995584) (xy 287.438061 -302.99504) (xy 287.430476 -302.987477)
			(xy 287.429956 -302.982122) (xy 281.385772 -302.982122) (xy 281.385293 -302.987426) (xy 281.377858 -302.994995)
			(xy 281.372564 -302.995584) (xy 280.85669 -302.995584) (xy 280.848878 -302.995879) (xy 280.834006 -303.000677)
			(xy 280.82748 -303.004982) (xy 280.806364 -303.01934) (xy 280.760638 -303.042064) (xy 280.711963 -303.057491)
			(xy 280.661495 -303.065256) (xy 280.635964 -303.065688) (xy 280.610433 -303.065265) (xy 280.559969 -303.057484)
			(xy 280.511297 -303.042051) (xy 280.46557 -303.019331) (xy 280.444448 -303.004982) (xy 280.437923 -303.00068)
			(xy 280.423048 -302.995902) (xy 280.415238 -302.995584) (xy 279.899364 -302.995584) (xy 279.894091 -302.995127)
			(xy 279.886649 -302.987651) (xy 279.886156 -302.982376) (xy 273.841949 -302.982376) (xy 273.841493 -302.987426)
			(xy 273.834058 -302.994995) (xy 273.828764 -302.995584) (xy 273.31289 -302.995584) (xy 273.305078 -302.995879)
			(xy 273.290206 -303.000677) (xy 273.28368 -303.004982) (xy 273.262564 -303.01934) (xy 273.216838 -303.042064)
			(xy 273.168163 -303.057491) (xy 273.117695 -303.065256) (xy 273.092164 -303.065688) (xy 273.066633 -303.065265)
			(xy 273.016169 -303.057484) (xy 272.967497 -303.042051) (xy 272.92177 -303.019331) (xy 272.900648 -303.004982)
			(xy 272.894123 -303.00068) (xy 272.879248 -302.995902) (xy 272.871438 -302.995584) (xy 272.355564 -302.995584)
			(xy 272.350291 -302.995127) (xy 272.342849 -302.987651) (xy 272.342356 -302.982376) (xy 266.298148 -302.982376)
			(xy 266.297665 -302.987486) (xy 266.290075 -302.99507) (xy 266.28471 -302.995584) (xy 265.768836 -302.995584)
			(xy 265.761026 -302.995899) (xy 265.746154 -303.000683) (xy 265.739626 -303.004982) (xy 265.718497 -303.01932)
			(xy 265.672776 -303.042048) (xy 265.624105 -303.057481) (xy 265.57364 -303.065252) (xy 265.54811 -303.065688)
			(xy 265.52258 -303.065242) (xy 265.472117 -303.057468) (xy 265.423445 -303.042042) (xy 265.377716 -303.019328)
			(xy 265.356594 -303.004982) (xy 265.350058 -303.000698) (xy 265.335192 -302.995909) (xy 265.327384 -302.995584)
			(xy 264.81151 -302.995584) (xy 264.806153 -302.995045) (xy 264.798568 -302.987478) (xy 264.798048 -302.982122)
			(xy 202.89774 -302.982122) (xy 202.89774 -302.982376) (xy 202.897192 -302.987628) (xy 202.889782 -302.99507)
			(xy 202.884532 -302.995584) (xy 202.368658 -302.995584) (xy 202.360782 -302.995856) (xy 202.345778 -303.00065)
			(xy 202.339194 -303.004982) (xy 202.318111 -303.019365) (xy 202.272468 -303.042195) (xy 202.223864 -303.057754)
			(xy 202.173448 -303.065677) (xy 202.147932 -303.066196) (xy 202.122412 -303.065708) (xy 202.071985 -303.057813)
			(xy 202.023373 -303.042253) (xy 201.977735 -303.019397) (xy 201.95667 -303.004982) (xy 201.950088 -303.000651)
			(xy 201.935081 -302.995874) (xy 201.927206 -302.995584) (xy 201.411332 -302.995584) (xy 201.405998 -302.995249)
			(xy 201.398454 -302.98771) (xy 201.398124 -302.982376) (xy 195.35394 -302.982376) (xy 195.353392 -302.987628)
			(xy 195.345982 -302.99507) (xy 195.340732 -302.995584) (xy 194.824858 -302.995584) (xy 194.816982 -302.995856)
			(xy 194.801978 -303.00065) (xy 194.795394 -303.004982) (xy 194.774311 -303.019365) (xy 194.728668 -303.042195)
			(xy 194.680064 -303.057754) (xy 194.629648 -303.065677) (xy 194.604132 -303.066196) (xy 194.578612 -303.065708)
			(xy 194.528185 -303.057813) (xy 194.479573 -303.042253) (xy 194.433935 -303.019397) (xy 194.41287 -303.004982)
			(xy 194.406288 -303.000651) (xy 194.391281 -302.995874) (xy 194.383406 -302.995584) (xy 193.867532 -302.995584)
			(xy 193.862198 -302.995249) (xy 193.854654 -302.98771) (xy 193.854324 -302.982376) (xy 187.81014 -302.982376)
			(xy 187.809592 -302.987628) (xy 187.802182 -302.99507) (xy 187.796932 -302.995584) (xy 187.796424 -302.995584)
			(xy 187.280804 -302.995584) (xy 187.27293 -302.995875) (xy 187.257925 -303.000656) (xy 187.25134 -303.004982)
			(xy 187.230272 -303.019388) (xy 187.184624 -303.042212) (xy 187.136015 -303.057766) (xy 187.085595 -303.065681)
			(xy 187.060078 -303.066196) (xy 187.034559 -303.065685) (xy 186.984133 -303.057797) (xy 186.935521 -303.042243)
			(xy 186.889882 -303.019394) (xy 186.868816 -303.004982) (xy 186.862224 -303.000669) (xy 186.847224 -302.995881)
			(xy 186.839352 -302.995584) (xy 186.323478 -302.995584) (xy 186.318177 -302.995094) (xy 186.310608 -302.987667)
			(xy 186.310016 -302.982376) (xy 180.265832 -302.982376) (xy 180.265292 -302.98763) (xy 180.257876 -302.995073)
			(xy 180.252624 -302.995584) (xy 179.73675 -302.995584) (xy 179.728874 -302.995852) (xy 179.71387 -303.000649)
			(xy 179.707286 -303.004982) (xy 179.686206 -303.019369) (xy 179.640561 -303.042197) (xy 179.591956 -303.057756)
			(xy 179.54154 -303.065677) (xy 179.516024 -303.066196) (xy 179.490504 -303.065712) (xy 179.440076 -303.057816)
			(xy 179.391465 -303.042254) (xy 179.345827 -303.019398) (xy 179.324762 -303.004982) (xy 179.318182 -303.000648)
			(xy 179.303173 -302.995873) (xy 179.295298 -302.995584) (xy 178.779424 -302.995584) (xy 178.774089 -302.995255)
			(xy 178.766545 -302.987711) (xy 178.766216 -302.982376) (xy 172.722032 -302.982376) (xy 172.721492 -302.98763)
			(xy 172.714076 -302.995073) (xy 172.708824 -302.995584) (xy 172.708316 -302.995584) (xy 172.192696 -302.995584)
			(xy 172.184821 -302.995872) (xy 172.169817 -303.000655) (xy 172.163232 -303.004982) (xy 172.142167 -303.019392)
			(xy 172.096517 -303.042215) (xy 172.047907 -303.057768) (xy 171.997488 -303.065681) (xy 171.97197 -303.066196)
			(xy 171.946451 -303.065689) (xy 171.896024 -303.0578) (xy 171.847413 -303.042245) (xy 171.801774 -303.019395)
			(xy 171.780708 -303.004982) (xy 171.774117 -303.000666) (xy 171.759117 -302.99588) (xy 171.751244 -302.995584)
			(xy 171.23537 -302.995584) (xy 171.230068 -302.9951) (xy 171.2225 -302.987668) (xy 171.221908 -302.982376)
			(xy 165.177724 -302.982376) (xy 165.177359 -302.987701) (xy 165.16984 -302.995243) (xy 165.164516 -302.995584)
			(xy 163.691316 -302.995584) (xy 163.68598 -302.99526) (xy 163.678437 -302.987712) (xy 163.678108 -302.982376)
			(xy 144.286794 -302.982376) (xy 144.344494 -303.039265) (xy 144.440091 -303.144834) (xy 144.529563 -303.255643)
			(xy 144.612622 -303.371336) (xy 144.689003 -303.491543) (xy 144.758461 -303.615878) (xy 144.820774 -303.743944)
			(xy 144.857934 -303.832768) (xy 167.778176 -303.832768) (xy 167.778176 -303.337976) (xy 167.778677 -303.332714)
			(xy 167.786122 -303.325274) (xy 167.791384 -303.324768) (xy 169.264584 -303.324768) (xy 169.269839 -303.325303)
			(xy 169.277281 -303.332722) (xy 169.277792 -303.337976) (xy 169.277792 -303.832514) (xy 175.321976 -303.832514)
			(xy 175.321976 -303.337976) (xy 175.322477 -303.332714) (xy 175.329922 -303.325274) (xy 175.335184 -303.324768)
			(xy 175.335692 -303.324768) (xy 175.851566 -303.324768) (xy 175.859375 -303.324445) (xy 175.874247 -303.319666)
			(xy 175.880776 -303.31537) (xy 175.901865 -303.301021) (xy 175.947526 -303.27829) (xy 175.996132 -303.262831)
			(xy 176.046535 -303.255008) (xy 176.097541 -303.255008) (xy 176.147944 -303.262831) (xy 176.19655 -303.27829)
			(xy 176.242211 -303.301021) (xy 176.2633 -303.31537) (xy 176.269834 -303.319657) (xy 176.284702 -303.324443)
			(xy 176.29251 -303.324768) (xy 176.808638 -303.324768) (xy 176.813953 -303.325201) (xy 176.821524 -303.332668)
			(xy 176.8221 -303.337976) (xy 176.8221 -303.832514) (xy 176.822075 -303.832768) (xy 182.866284 -303.832768)
			(xy 182.866284 -303.83226) (xy 182.866284 -303.337976) (xy 182.866778 -303.332712) (xy 182.874228 -303.325272)
			(xy 182.879492 -303.324768) (xy 183.39562 -303.324768) (xy 183.403431 -303.324468) (xy 183.418303 -303.319673)
			(xy 183.42483 -303.31537) (xy 183.445919 -303.301021) (xy 183.49158 -303.27829) (xy 183.540186 -303.262831)
			(xy 183.590589 -303.255008) (xy 183.641595 -303.255008) (xy 183.691998 -303.262831) (xy 183.740604 -303.27829)
			(xy 183.786265 -303.301021) (xy 183.807354 -303.31537) (xy 183.813876 -303.319678) (xy 183.828753 -303.324451)
			(xy 183.836564 -303.324768) (xy 184.352692 -303.324768) (xy 184.357948 -303.325297) (xy 184.36539 -303.332721)
			(xy 184.3659 -303.337976) (xy 184.3659 -303.832514) (xy 190.410084 -303.832514) (xy 190.410084 -303.337976)
			(xy 190.410578 -303.332712) (xy 190.418028 -303.325272) (xy 190.423292 -303.324768) (xy 190.4238 -303.324768)
			(xy 190.939674 -303.324768) (xy 190.947484 -303.324448) (xy 190.962355 -303.319667) (xy 190.968884 -303.31537)
			(xy 190.989973 -303.301021) (xy 191.035634 -303.27829) (xy 191.08424 -303.262831) (xy 191.134643 -303.255008)
			(xy 191.185649 -303.255008) (xy 191.236052 -303.262831) (xy 191.284658 -303.27829) (xy 191.330319 -303.301021)
			(xy 191.351408 -303.31537) (xy 191.35794 -303.31966) (xy 191.37281 -303.324444) (xy 191.380618 -303.324768)
			(xy 191.896746 -303.324768) (xy 191.90205 -303.325262) (xy 191.909626 -303.332683) (xy 191.910208 -303.337976)
			(xy 191.910208 -303.832514) (xy 191.910182 -303.832768) (xy 197.954392 -303.832768) (xy 197.954392 -303.83226)
			(xy 197.954392 -303.337976) (xy 197.954879 -303.33271) (xy 197.962334 -303.325269) (xy 197.9676 -303.324768)
			(xy 198.483728 -303.324768) (xy 198.49154 -303.324472) (xy 198.506411 -303.319674) (xy 198.512938 -303.31537)
			(xy 198.534027 -303.301021) (xy 198.579688 -303.27829) (xy 198.628294 -303.262831) (xy 198.678697 -303.255008)
			(xy 198.729703 -303.255008) (xy 198.780106 -303.262831) (xy 198.828712 -303.27829) (xy 198.874373 -303.301021)
			(xy 198.895462 -303.31537) (xy 198.902005 -303.319642) (xy 198.916866 -303.324437) (xy 198.924672 -303.324768)
			(xy 199.4408 -303.324768) (xy 199.446057 -303.325292) (xy 199.453498 -303.33272) (xy 199.454008 -303.337976)
			(xy 199.454008 -303.832514) (xy 199.453983 -303.832768) (xy 205.498192 -303.832768) (xy 205.498192 -303.83226)
			(xy 205.498192 -303.337976) (xy 205.498679 -303.33271) (xy 205.506134 -303.325269) (xy 205.5114 -303.324768)
			(xy 206.027528 -303.324768) (xy 206.03534 -303.324472) (xy 206.050211 -303.319674) (xy 206.056738 -303.31537)
			(xy 206.077827 -303.301021) (xy 206.123488 -303.27829) (xy 206.172094 -303.262831) (xy 206.222497 -303.255008)
			(xy 206.273503 -303.255008) (xy 206.323906 -303.262831) (xy 206.372512 -303.27829) (xy 206.418173 -303.301021)
			(xy 206.439262 -303.31537) (xy 206.445805 -303.319642) (xy 206.460666 -303.324437) (xy 206.468472 -303.324768)
			(xy 206.9846 -303.324768) (xy 206.989857 -303.325292) (xy 206.997298 -303.33272) (xy 206.997808 -303.337976)
			(xy 206.997808 -303.83226) (xy 268.898116 -303.83226) (xy 268.898116 -303.337722) (xy 268.898663 -303.332366)
			(xy 268.906224 -303.32478) (xy 268.911578 -303.32426) (xy 269.427706 -303.32426) (xy 269.435517 -303.323956)
			(xy 269.450389 -303.319164) (xy 269.456916 -303.314862) (xy 269.478005 -303.300513) (xy 269.523666 -303.277782)
			(xy 269.572272 -303.262323) (xy 269.622675 -303.2545) (xy 269.673681 -303.2545) (xy 269.724084 -303.262323)
			(xy 269.77269 -303.277782) (xy 269.818351 -303.300513) (xy 269.83944 -303.314862) (xy 269.845966 -303.319164)
			(xy 269.86084 -303.323941) (xy 269.86865 -303.32426) (xy 270.384778 -303.32426) (xy 270.390215 -303.324596)
			(xy 270.397904 -303.332285) (xy 270.39824 -303.337722) (xy 270.39824 -303.83226) (xy 276.442424 -303.83226)
			(xy 276.442424 -303.337722) (xy 276.442936 -303.332424) (xy 276.450346 -303.324853) (xy 276.455632 -303.32426)
			(xy 276.97176 -303.32426) (xy 276.979569 -303.323936) (xy 276.994441 -303.319158) (xy 277.00097 -303.314862)
			(xy 277.022059 -303.300513) (xy 277.06772 -303.277782) (xy 277.116326 -303.262323) (xy 277.166729 -303.2545)
			(xy 277.217735 -303.2545) (xy 277.268138 -303.262323) (xy 277.316744 -303.277782) (xy 277.362405 -303.300513)
			(xy 277.383494 -303.314862) (xy 277.39003 -303.319146) (xy 277.404896 -303.323934) (xy 277.412704 -303.32426)
			(xy 277.928832 -303.32426) (xy 277.934091 -303.32477) (xy 277.94153 -303.332209) (xy 277.94204 -303.337468)
			(xy 277.94204 -303.337976) (xy 277.94204 -303.83226) (xy 283.986224 -303.83226) (xy 283.986224 -303.337722)
			(xy 283.986736 -303.332424) (xy 283.994146 -303.324853) (xy 283.999432 -303.32426) (xy 284.51556 -303.32426)
			(xy 284.523369 -303.323936) (xy 284.538241 -303.319158) (xy 284.54477 -303.314862) (xy 284.565859 -303.300513)
			(xy 284.61152 -303.277782) (xy 284.660126 -303.262323) (xy 284.710529 -303.2545) (xy 284.761535 -303.2545)
			(xy 284.811938 -303.262323) (xy 284.860544 -303.277782) (xy 284.906205 -303.300513) (xy 284.927294 -303.314862)
			(xy 284.93383 -303.319146) (xy 284.948696 -303.323934) (xy 284.956504 -303.32426) (xy 285.472632 -303.32426)
			(xy 285.477891 -303.32477) (xy 285.48533 -303.332209) (xy 285.48584 -303.337468) (xy 285.48584 -303.337976)
			(xy 285.48584 -303.83226) (xy 291.530024 -303.83226) (xy 291.530024 -303.337722) (xy 291.530393 -303.332294)
			(xy 291.538059 -303.324607) (xy 291.543486 -303.32426) (xy 292.059614 -303.32426) (xy 292.067425 -303.323959)
			(xy 292.082297 -303.319165) (xy 292.088824 -303.314862) (xy 292.109913 -303.300513) (xy 292.155574 -303.277782)
			(xy 292.20418 -303.262323) (xy 292.254583 -303.2545) (xy 292.305589 -303.2545) (xy 292.355992 -303.262323)
			(xy 292.404598 -303.277782) (xy 292.450259 -303.300513) (xy 292.471348 -303.314862) (xy 292.477872 -303.319167)
			(xy 292.492748 -303.323942) (xy 292.500558 -303.32426) (xy 293.016686 -303.32426) (xy 293.022124 -303.324591)
			(xy 293.029812 -303.332284) (xy 293.030148 -303.337722) (xy 293.030148 -303.83226) (xy 299.074332 -303.83226)
			(xy 299.074332 -303.337722) (xy 299.074837 -303.332422) (xy 299.082251 -303.32485) (xy 299.08754 -303.32426)
			(xy 299.603668 -303.32426) (xy 299.611478 -303.323939) (xy 299.626349 -303.319159) (xy 299.632878 -303.314862)
			(xy 299.653967 -303.300513) (xy 299.699628 -303.277782) (xy 299.748234 -303.262323) (xy 299.798637 -303.2545)
			(xy 299.849643 -303.2545) (xy 299.900046 -303.262323) (xy 299.948652 -303.277782) (xy 299.994313 -303.300513)
			(xy 300.015402 -303.314862) (xy 300.021936 -303.319149) (xy 300.036804 -303.323935) (xy 300.044612 -303.32426)
			(xy 300.56074 -303.32426) (xy 300.566 -303.324765) (xy 300.573438 -303.332208) (xy 300.573948 -303.337468)
			(xy 300.573948 -303.337976) (xy 300.573948 -303.83226) (xy 306.618132 -303.83226) (xy 306.618132 -303.337722)
			(xy 306.618494 -303.332292) (xy 306.626164 -303.324605) (xy 306.631594 -303.32426) (xy 308.104794 -303.32426)
			(xy 308.110233 -303.324585) (xy 308.117921 -303.332282) (xy 308.118256 -303.337722) (xy 308.118256 -303.83226)
			(xy 308.117684 -303.837507) (xy 308.110291 -303.844949) (xy 308.105048 -303.845468) (xy 308.10454 -303.845468)
			(xy 306.631594 -303.845468) (xy 306.626291 -303.844982) (xy 306.618721 -303.837553) (xy 306.618132 -303.83226)
			(xy 300.573948 -303.83226) (xy 300.573383 -303.837508) (xy 300.565985 -303.844951) (xy 300.56074 -303.845468)
			(xy 300.044866 -303.845468) (xy 300.036991 -303.845746) (xy 300.021986 -303.850536) (xy 300.015402 -303.854866)
			(xy 299.994316 -303.869244) (xy 299.948674 -303.892075) (xy 299.900071 -303.907636) (xy 299.849656 -303.91556)
			(xy 299.82414 -303.91608) (xy 299.79862 -303.915591) (xy 299.748193 -303.907697) (xy 299.699581 -303.892137)
			(xy 299.653943 -303.869282) (xy 299.632878 -303.854866) (xy 299.626289 -303.850546) (xy 299.611287 -303.845761)
			(xy 299.603414 -303.845468) (xy 299.08754 -303.845468) (xy 299.082203 -303.845142) (xy 299.074658 -303.837597)
			(xy 299.074332 -303.83226) (xy 293.030148 -303.83226) (xy 293.029583 -303.837508) (xy 293.022185 -303.844951)
			(xy 293.01694 -303.845468) (xy 293.016432 -303.845468) (xy 292.500812 -303.845468) (xy 292.492938 -303.845765)
			(xy 292.477934 -303.850542) (xy 292.471348 -303.854866) (xy 292.450277 -303.869267) (xy 292.40463 -303.892093)
			(xy 292.356022 -303.907648) (xy 292.305603 -303.915564) (xy 292.280086 -303.91608) (xy 292.254567 -303.915568)
			(xy 292.20414 -303.907681) (xy 292.155529 -303.892127) (xy 292.10989 -303.869279) (xy 292.088824 -303.854866)
			(xy 292.082225 -303.850564) (xy 292.067231 -303.845768) (xy 292.05936 -303.845468) (xy 291.543486 -303.845468)
			(xy 291.538182 -303.844987) (xy 291.530612 -303.837554) (xy 291.530024 -303.83226) (xy 285.48584 -303.83226)
			(xy 285.485449 -303.837579) (xy 285.477949 -303.84512) (xy 285.472632 -303.845468) (xy 284.956758 -303.845468)
			(xy 284.948882 -303.845742) (xy 284.933878 -303.850535) (xy 284.927294 -303.854866) (xy 284.90621 -303.869247)
			(xy 284.860567 -303.892078) (xy 284.811963 -303.907638) (xy 284.761548 -303.915561) (xy 284.736032 -303.91608)
			(xy 284.710512 -303.915595) (xy 284.660084 -303.9077) (xy 284.611473 -303.892138) (xy 284.565835 -303.869282)
			(xy 284.54477 -303.854866) (xy 284.538183 -303.850543) (xy 284.52318 -303.84576) (xy 284.515306 -303.845468)
			(xy 283.999432 -303.845468) (xy 283.994094 -303.845148) (xy 283.986549 -303.837598) (xy 283.986224 -303.83226)
			(xy 277.94204 -303.83226) (xy 277.941649 -303.837579) (xy 277.934149 -303.84512) (xy 277.928832 -303.845468)
			(xy 277.412958 -303.845468) (xy 277.405082 -303.845742) (xy 277.390078 -303.850535) (xy 277.383494 -303.854866)
			(xy 277.36241 -303.869247) (xy 277.316767 -303.892078) (xy 277.268163 -303.907638) (xy 277.217748 -303.915561)
			(xy 277.192232 -303.91608) (xy 277.166712 -303.915595) (xy 277.116284 -303.9077) (xy 277.067673 -303.892138)
			(xy 277.022035 -303.869282) (xy 277.00097 -303.854866) (xy 276.994383 -303.850543) (xy 276.97938 -303.84576)
			(xy 276.971506 -303.845468) (xy 276.455632 -303.845468) (xy 276.450294 -303.845148) (xy 276.442749 -303.837598)
			(xy 276.442424 -303.83226) (xy 270.39824 -303.83226) (xy 270.397849 -303.837579) (xy 270.390349 -303.84512)
			(xy 270.385032 -303.845468) (xy 270.384524 -303.845468) (xy 269.868904 -303.845468) (xy 269.86103 -303.845762)
			(xy 269.846026 -303.850541) (xy 269.83944 -303.854866) (xy 269.818371 -303.869271) (xy 269.772723 -303.892095)
			(xy 269.724114 -303.90765) (xy 269.673695 -303.915565) (xy 269.648178 -303.91608) (xy 269.622659 -303.915572)
			(xy 269.572232 -303.907684) (xy 269.52362 -303.892129) (xy 269.477981 -303.869279) (xy 269.456916 -303.854866)
			(xy 269.450319 -303.850561) (xy 269.435323 -303.845767) (xy 269.427452 -303.845468) (xy 268.911578 -303.845468)
			(xy 268.906273 -303.844992) (xy 268.898704 -303.837555) (xy 268.898116 -303.83226) (xy 206.997808 -303.83226)
			(xy 206.997808 -303.832514) (xy 206.997292 -303.837809) (xy 206.989883 -303.845376) (xy 206.9846 -303.845976)
			(xy 206.468726 -303.845976) (xy 206.460916 -303.846288) (xy 206.446044 -303.851074) (xy 206.439516 -303.855374)
			(xy 206.418389 -303.869715) (xy 206.372667 -303.892443) (xy 206.323995 -303.907875) (xy 206.27353 -303.915645)
			(xy 206.248 -303.91608) (xy 206.22247 -303.915641) (xy 206.172006 -303.907865) (xy 206.123334 -303.892437)
			(xy 206.077606 -303.869721) (xy 206.056484 -303.855374) (xy 206.049951 -303.851085) (xy 206.035082 -303.846299)
			(xy 206.027274 -303.845976) (xy 205.5114 -303.845976) (xy 205.50606 -303.84567) (xy 205.498517 -303.838109)
			(xy 205.498192 -303.832768) (xy 199.453983 -303.832768) (xy 199.453492 -303.837809) (xy 199.446083 -303.845376)
			(xy 199.4408 -303.845976) (xy 198.924926 -303.845976) (xy 198.917116 -303.846288) (xy 198.902244 -303.851074)
			(xy 198.895716 -303.855374) (xy 198.874589 -303.869715) (xy 198.828867 -303.892443) (xy 198.780195 -303.907875)
			(xy 198.72973 -303.915645) (xy 198.7042 -303.91608) (xy 198.67867 -303.915641) (xy 198.628206 -303.907865)
			(xy 198.579534 -303.892437) (xy 198.533806 -303.869721) (xy 198.512684 -303.855374) (xy 198.506151 -303.851085)
			(xy 198.491282 -303.846299) (xy 198.483474 -303.845976) (xy 197.9676 -303.845976) (xy 197.96226 -303.84567)
			(xy 197.954717 -303.838109) (xy 197.954392 -303.832768) (xy 191.910182 -303.832768) (xy 191.909663 -303.837868)
			(xy 191.902099 -303.845451) (xy 191.896746 -303.845976) (xy 191.380872 -303.845976) (xy 191.373059 -303.846265)
			(xy 191.358188 -303.851067) (xy 191.351662 -303.855374) (xy 191.33055 -303.869738) (xy 191.284823 -303.892461)
			(xy 191.236146 -303.907887) (xy 191.185678 -303.915649) (xy 191.160146 -303.91608) (xy 191.134617 -303.915618)
			(xy 191.084154 -303.907849) (xy 191.035482 -303.892427) (xy 190.989753 -303.869718) (xy 190.96863 -303.855374)
			(xy 190.962087 -303.851103) (xy 190.947226 -303.846306) (xy 190.93942 -303.845976) (xy 190.423546 -303.845976)
			(xy 190.418121 -303.845591) (xy 190.410433 -303.837938) (xy 190.410084 -303.832514) (xy 184.3659 -303.832514)
			(xy 184.365391 -303.837811) (xy 184.357977 -303.845379) (xy 184.352692 -303.845976) (xy 183.836818 -303.845976)
			(xy 183.829007 -303.846285) (xy 183.814135 -303.851073) (xy 183.807608 -303.855374) (xy 183.786483 -303.869719)
			(xy 183.74076 -303.892446) (xy 183.692088 -303.907877) (xy 183.641623 -303.915646) (xy 183.616092 -303.91608)
			(xy 183.590562 -303.915645) (xy 183.540098 -303.907868) (xy 183.491426 -303.892438) (xy 183.445698 -303.869722)
			(xy 183.424576 -303.855374) (xy 183.418045 -303.851082) (xy 183.403175 -303.846298) (xy 183.395366 -303.845976)
			(xy 182.879492 -303.845976) (xy 182.874151 -303.845676) (xy 182.866608 -303.83811) (xy 182.866284 -303.832768)
			(xy 176.822075 -303.832768) (xy 176.821563 -303.83787) (xy 176.813993 -303.845453) (xy 176.808638 -303.845976)
			(xy 176.292764 -303.845976) (xy 176.284955 -303.846304) (xy 176.270083 -303.851079) (xy 176.263554 -303.855374)
			(xy 176.242444 -303.869742) (xy 176.196716 -303.892464) (xy 176.148039 -303.907888) (xy 176.09757 -303.91565)
			(xy 176.072038 -303.91608) (xy 176.046509 -303.915622) (xy 175.996046 -303.907852) (xy 175.947373 -303.892429)
			(xy 175.901645 -303.869719) (xy 175.880522 -303.855374) (xy 175.873981 -303.8511) (xy 175.859118 -303.846305)
			(xy 175.851312 -303.845976) (xy 175.335438 -303.845976) (xy 175.330012 -303.845597) (xy 175.322324 -303.837939)
			(xy 175.321976 -303.832514) (xy 169.277792 -303.832514) (xy 169.27729 -303.837812) (xy 169.269871 -303.845381)
			(xy 169.264584 -303.845976) (xy 167.791384 -303.845976) (xy 167.786042 -303.845681) (xy 167.7785 -303.838112)
			(xy 167.778176 -303.832768) (xy 144.857934 -303.832768) (xy 144.875741 -303.875331) (xy 144.923187 -304.009616)
			(xy 144.96296 -304.146371) (xy 144.994932 -304.285157) (xy 145.019002 -304.425529) (xy 145.035091 -304.567039)
			(xy 145.041642 -304.682652) (xy 163.678108 -304.682652) (xy 163.678108 -304.682144) (xy 163.678108 -304.18786)
			(xy 163.67857 -304.182588) (xy 163.686042 -304.175147) (xy 163.691316 -304.174652) (xy 165.164516 -304.174652)
			(xy 165.169771 -304.17518) (xy 165.177211 -304.182606) (xy 165.177724 -304.18786) (xy 165.177724 -304.682398)
			(xy 165.177702 -304.682652) (xy 167.778176 -304.682652) (xy 167.778176 -304.18786) (xy 167.778666 -304.182596)
			(xy 167.786119 -304.175157) (xy 167.791384 -304.174652) (xy 169.264584 -304.174652) (xy 169.269835 -304.175201)
			(xy 169.277276 -304.182611) (xy 169.277792 -304.18786) (xy 169.277792 -304.682398) (xy 171.221908 -304.682398)
			(xy 171.221908 -304.18786) (xy 171.22237 -304.182588) (xy 171.229842 -304.175147) (xy 171.235116 -304.174652)
			(xy 171.235624 -304.174652) (xy 171.751498 -304.174652) (xy 171.759309 -304.174346) (xy 171.774181 -304.169556)
			(xy 171.780708 -304.165254) (xy 171.801797 -304.150905) (xy 171.847458 -304.128174) (xy 171.896064 -304.112715)
			(xy 171.946467 -304.104892) (xy 171.997473 -304.104892) (xy 172.047876 -304.112715) (xy 172.096482 -304.128174)
			(xy 172.142143 -304.150905) (xy 172.163232 -304.165254) (xy 172.16976 -304.169552) (xy 172.184633 -304.174331)
			(xy 172.192442 -304.174652) (xy 172.70857 -304.174652) (xy 172.713873 -304.175144) (xy 172.721447 -304.182567)
			(xy 172.722032 -304.18786) (xy 172.722032 -304.682398) (xy 175.321976 -304.682398) (xy 175.321976 -304.18786)
			(xy 175.322466 -304.182596) (xy 175.329919 -304.175157) (xy 175.335184 -304.174652) (xy 175.335692 -304.174652)
			(xy 175.851566 -304.174652) (xy 175.859376 -304.174332) (xy 175.874247 -304.169551) (xy 175.880776 -304.165254)
			(xy 175.901865 -304.150905) (xy 175.947526 -304.128174) (xy 175.996132 -304.112715) (xy 176.046535 -304.104892)
			(xy 176.097541 -304.104892) (xy 176.147944 -304.112715) (xy 176.19655 -304.128174) (xy 176.242211 -304.150905)
			(xy 176.2633 -304.165254) (xy 176.269835 -304.169539) (xy 176.284702 -304.174327) (xy 176.29251 -304.174652)
			(xy 176.808638 -304.174652) (xy 176.81395 -304.1751) (xy 176.821519 -304.182557) (xy 176.8221 -304.18786)
			(xy 176.8221 -304.682398) (xy 176.822074 -304.682652) (xy 178.766216 -304.682652) (xy 178.766216 -304.682144)
			(xy 178.766216 -304.18786) (xy 178.76667 -304.182587) (xy 178.774148 -304.175145) (xy 178.779424 -304.174652)
			(xy 179.295552 -304.174652) (xy 179.303361 -304.174326) (xy 179.318233 -304.169549) (xy 179.324762 -304.165254)
			(xy 179.345851 -304.150905) (xy 179.391512 -304.128174) (xy 179.440118 -304.112715) (xy 179.490521 -304.104892)
			(xy 179.541527 -304.104892) (xy 179.59193 -304.112715) (xy 179.640536 -304.128174) (xy 179.686197 -304.150905)
			(xy 179.707286 -304.165254) (xy 179.713824 -304.169534) (xy 179.728689 -304.174325) (xy 179.736496 -304.174652)
			(xy 180.252624 -304.174652) (xy 180.25788 -304.175175) (xy 180.265319 -304.182605) (xy 180.265832 -304.18786)
			(xy 180.265832 -304.682398) (xy 180.26581 -304.682652) (xy 182.866284 -304.682652) (xy 182.866284 -304.682144)
			(xy 182.866284 -304.18786) (xy 182.866767 -304.182594) (xy 182.874225 -304.175154) (xy 182.879492 -304.174652)
			(xy 183.39562 -304.174652) (xy 183.403432 -304.174355) (xy 183.418303 -304.169559) (xy 183.42483 -304.165254)
			(xy 183.445919 -304.150905) (xy 183.49158 -304.128174) (xy 183.540186 -304.112715) (xy 183.590589 -304.104892)
			(xy 183.641595 -304.104892) (xy 183.691998 -304.112715) (xy 183.740604 -304.128174) (xy 183.786265 -304.150905)
			(xy 183.807354 -304.165254) (xy 183.813877 -304.16956) (xy 183.828753 -304.174335) (xy 183.836564 -304.174652)
			(xy 184.352692 -304.174652) (xy 184.357944 -304.175196) (xy 184.365385 -304.18261) (xy 184.3659 -304.18786)
			(xy 184.3659 -304.682398) (xy 186.310016 -304.682398) (xy 186.310016 -304.18786) (xy 186.31047 -304.182587)
			(xy 186.317948 -304.175145) (xy 186.323224 -304.174652) (xy 186.323732 -304.174652) (xy 186.839606 -304.174652)
			(xy 186.847417 -304.174349) (xy 186.862289 -304.169557) (xy 186.868816 -304.165254) (xy 186.889905 -304.150905)
			(xy 186.935566 -304.128174) (xy 186.984172 -304.112715) (xy 187.034575 -304.104892) (xy 187.085581 -304.104892)
			(xy 187.135984 -304.112715) (xy 187.18459 -304.128174) (xy 187.230251 -304.150905) (xy 187.25134 -304.165254)
			(xy 187.257866 -304.169555) (xy 187.27274 -304.174333) (xy 187.28055 -304.174652) (xy 187.796678 -304.174652)
			(xy 187.801982 -304.175139) (xy 187.809556 -304.182566) (xy 187.81014 -304.18786) (xy 187.81014 -304.682398)
			(xy 190.410084 -304.682398) (xy 190.410084 -304.18786) (xy 190.410567 -304.182594) (xy 190.418025 -304.175154)
			(xy 190.423292 -304.174652) (xy 190.4238 -304.174652) (xy 190.939674 -304.174652) (xy 190.947484 -304.174335)
			(xy 190.962356 -304.169552) (xy 190.968884 -304.165254) (xy 190.989973 -304.150905) (xy 191.035634 -304.128174)
			(xy 191.08424 -304.112715) (xy 191.134643 -304.104892) (xy 191.185649 -304.104892) (xy 191.236052 -304.112715)
			(xy 191.284658 -304.128174) (xy 191.330319 -304.150905) (xy 191.351408 -304.165254) (xy 191.357941 -304.169543)
			(xy 191.37281 -304.174328) (xy 191.380618 -304.174652) (xy 191.896746 -304.174652) (xy 191.902047 -304.175161)
			(xy 191.909621 -304.182571) (xy 191.910208 -304.18786) (xy 191.910208 -304.682398) (xy 191.910182 -304.682652)
			(xy 193.854324 -304.682652) (xy 193.854324 -304.682144) (xy 193.854324 -304.18786) (xy 193.854771 -304.182585)
			(xy 193.862254 -304.175142) (xy 193.867532 -304.174652) (xy 194.38366 -304.174652) (xy 194.391469 -304.174329)
			(xy 194.406341 -304.16955) (xy 194.41287 -304.165254) (xy 194.433959 -304.150905) (xy 194.47962 -304.128174)
			(xy 194.528226 -304.112715) (xy 194.578629 -304.104892) (xy 194.629635 -304.104892) (xy 194.680038 -304.112715)
			(xy 194.728644 -304.128174) (xy 194.774305 -304.150905) (xy 194.795394 -304.165254) (xy 194.80193 -304.169537)
			(xy 194.816797 -304.174326) (xy 194.824604 -304.174652) (xy 195.340732 -304.174652) (xy 195.345989 -304.175169)
			(xy 195.353427 -304.182603) (xy 195.35394 -304.18786) (xy 195.35394 -304.682398) (xy 195.353918 -304.682652)
			(xy 197.954392 -304.682652) (xy 197.954392 -304.682144) (xy 197.954392 -304.18786) (xy 197.954868 -304.182592)
			(xy 197.962331 -304.175152) (xy 197.9676 -304.174652) (xy 198.483728 -304.174652) (xy 198.49154 -304.174358)
			(xy 198.506412 -304.16956) (xy 198.512938 -304.165254) (xy 198.534027 -304.150905) (xy 198.579688 -304.128174)
			(xy 198.628294 -304.112715) (xy 198.678697 -304.104892) (xy 198.729703 -304.104892) (xy 198.780106 -304.112715)
			(xy 198.828712 -304.128174) (xy 198.874373 -304.150905) (xy 198.895462 -304.165254) (xy 198.902005 -304.169525)
			(xy 198.916866 -304.174321) (xy 198.924672 -304.174652) (xy 199.4408 -304.174652) (xy 199.446053 -304.175191)
			(xy 199.453493 -304.182608) (xy 199.454008 -304.18786) (xy 199.454008 -304.682398) (xy 199.453983 -304.682652)
			(xy 201.398124 -304.682652) (xy 201.398124 -304.682144) (xy 201.398124 -304.18786) (xy 201.398571 -304.182585)
			(xy 201.406054 -304.175142) (xy 201.411332 -304.174652) (xy 201.92746 -304.174652) (xy 201.935269 -304.174329)
			(xy 201.950141 -304.16955) (xy 201.95667 -304.165254) (xy 201.977759 -304.150905) (xy 202.02342 -304.128174)
			(xy 202.072026 -304.112715) (xy 202.122429 -304.104892) (xy 202.173435 -304.104892) (xy 202.223838 -304.112715)
			(xy 202.272444 -304.128174) (xy 202.318105 -304.150905) (xy 202.339194 -304.165254) (xy 202.34573 -304.169537)
			(xy 202.360597 -304.174326) (xy 202.368404 -304.174652) (xy 202.884532 -304.174652) (xy 202.889789 -304.175169)
			(xy 202.897227 -304.182603) (xy 202.89774 -304.18786) (xy 202.89774 -304.682398) (xy 202.897718 -304.682652)
			(xy 205.498192 -304.682652) (xy 205.498192 -304.682144) (xy 205.498192 -304.18786) (xy 205.498668 -304.182592)
			(xy 205.506131 -304.175152) (xy 205.5114 -304.174652) (xy 206.027528 -304.174652) (xy 206.03534 -304.174358)
			(xy 206.050212 -304.16956) (xy 206.056738 -304.165254) (xy 206.077827 -304.150905) (xy 206.123488 -304.128174)
			(xy 206.172094 -304.112715) (xy 206.222497 -304.104892) (xy 206.273503 -304.104892) (xy 206.323906 -304.112715)
			(xy 206.372512 -304.128174) (xy 206.418173 -304.150905) (xy 206.439262 -304.165254) (xy 206.445805 -304.169525)
			(xy 206.460666 -304.174321) (xy 206.468472 -304.174652) (xy 206.9846 -304.174652) (xy 206.989853 -304.175191)
			(xy 206.997293 -304.182608) (xy 206.997808 -304.18786) (xy 206.997808 -304.682144) (xy 264.798048 -304.682144)
			(xy 264.798048 -304.187606) (xy 264.798384 -304.18217) (xy 264.806073 -304.174483) (xy 264.81151 -304.174144)
			(xy 265.327638 -304.174144) (xy 265.335447 -304.173813) (xy 265.350319 -304.16904) (xy 265.356848 -304.164746)
			(xy 265.377937 -304.150397) (xy 265.423598 -304.127666) (xy 265.472204 -304.112207) (xy 265.522607 -304.104384)
			(xy 265.573613 -304.104384) (xy 265.624016 -304.112207) (xy 265.672622 -304.127666) (xy 265.718283 -304.150397)
			(xy 265.739372 -304.164746) (xy 265.745914 -304.16902) (xy 265.760776 -304.173815) (xy 265.768582 -304.174144)
			(xy 266.28471 -304.174144) (xy 266.290077 -304.174644) (xy 266.297662 -304.182239) (xy 266.298172 -304.187606)
			(xy 266.298172 -304.682144) (xy 268.898116 -304.682144) (xy 268.898116 -304.187606) (xy 268.898652 -304.182248)
			(xy 268.906221 -304.174663) (xy 268.911578 -304.174144) (xy 269.427706 -304.174144) (xy 269.435517 -304.173842)
			(xy 269.450389 -304.169049) (xy 269.456916 -304.164746) (xy 269.478005 -304.150397) (xy 269.523666 -304.127666)
			(xy 269.572272 -304.112207) (xy 269.622675 -304.104384) (xy 269.673681 -304.104384) (xy 269.724084 -304.112207)
			(xy 269.77269 -304.127666) (xy 269.818351 -304.150397) (xy 269.83944 -304.164746) (xy 269.845967 -304.169046)
			(xy 269.86084 -304.173825) (xy 269.86865 -304.174144) (xy 270.384778 -304.174144) (xy 270.390211 -304.174495)
			(xy 270.397899 -304.182173) (xy 270.39824 -304.187606) (xy 270.39824 -304.682144) (xy 272.342356 -304.682144)
			(xy 272.342356 -304.187606) (xy 272.342829 -304.182299) (xy 272.350266 -304.174726) (xy 272.355564 -304.174144)
			(xy 272.871692 -304.174144) (xy 272.879503 -304.173836) (xy 272.894374 -304.169047) (xy 272.900902 -304.164746)
			(xy 272.921991 -304.150397) (xy 272.967652 -304.127666) (xy 273.016258 -304.112207) (xy 273.066661 -304.104384)
			(xy 273.117667 -304.104384) (xy 273.16807 -304.112207) (xy 273.216676 -304.127666) (xy 273.262337 -304.150397)
			(xy 273.283426 -304.164746) (xy 273.289956 -304.169041) (xy 273.304827 -304.173823) (xy 273.312636 -304.174144)
			(xy 273.828764 -304.174144) (xy 273.834011 -304.174714) (xy 273.841453 -304.182108) (xy 273.841972 -304.187352)
			(xy 273.841972 -304.18786) (xy 273.841972 -304.682144) (xy 276.442424 -304.682144) (xy 276.442424 -304.187606)
			(xy 276.442925 -304.182306) (xy 276.450343 -304.174736) (xy 276.455632 -304.174144) (xy 276.97176 -304.174144)
			(xy 276.97957 -304.173823) (xy 276.994441 -304.169043) (xy 277.00097 -304.164746) (xy 277.022059 -304.150397)
			(xy 277.06772 -304.127666) (xy 277.116326 -304.112207) (xy 277.166729 -304.104384) (xy 277.217735 -304.104384)
			(xy 277.268138 -304.112207) (xy 277.316744 -304.127666) (xy 277.362405 -304.150397) (xy 277.383494 -304.164746)
			(xy 277.390031 -304.169028) (xy 277.404897 -304.173818) (xy 277.412704 -304.174144) (xy 277.928832 -304.174144)
			(xy 277.934087 -304.174669) (xy 277.941525 -304.182098) (xy 277.94204 -304.187352) (xy 277.94204 -304.18786)
			(xy 277.94204 -304.682144) (xy 279.886156 -304.682144) (xy 279.886156 -304.187606) (xy 279.886629 -304.182299)
			(xy 279.894066 -304.174726) (xy 279.899364 -304.174144) (xy 280.415492 -304.174144) (xy 280.423303 -304.173836)
			(xy 280.438174 -304.169047) (xy 280.444702 -304.164746) (xy 280.465791 -304.150397) (xy 280.511452 -304.127666)
			(xy 280.560058 -304.112207) (xy 280.610461 -304.104384) (xy 280.661467 -304.104384) (xy 280.71187 -304.112207)
			(xy 280.760476 -304.127666) (xy 280.806137 -304.150397) (xy 280.827226 -304.164746) (xy 280.833756 -304.169041)
			(xy 280.848627 -304.173823) (xy 280.856436 -304.174144) (xy 281.372564 -304.174144) (xy 281.377811 -304.174714)
			(xy 281.385253 -304.182108) (xy 281.385772 -304.187352) (xy 281.385772 -304.18786) (xy 281.385772 -304.682144)
			(xy 283.986224 -304.682144) (xy 283.986224 -304.187606) (xy 283.986725 -304.182306) (xy 283.994143 -304.174736)
			(xy 283.999432 -304.174144) (xy 284.51556 -304.174144) (xy 284.52337 -304.173823) (xy 284.538241 -304.169043)
			(xy 284.54477 -304.164746) (xy 284.565859 -304.150397) (xy 284.61152 -304.127666) (xy 284.660126 -304.112207)
			(xy 284.710529 -304.104384) (xy 284.761535 -304.104384) (xy 284.811938 -304.112207) (xy 284.860544 -304.127666)
			(xy 284.906205 -304.150397) (xy 284.927294 -304.164746) (xy 284.933831 -304.169028) (xy 284.948697 -304.173818)
			(xy 284.956504 -304.174144) (xy 285.472632 -304.174144) (xy 285.477887 -304.174669) (xy 285.485325 -304.182098)
			(xy 285.48584 -304.187352) (xy 285.48584 -304.18786) (xy 285.48584 -304.682144) (xy 287.429956 -304.682144)
			(xy 287.429956 -304.187606) (xy 287.430285 -304.182168) (xy 287.437979 -304.17448) (xy 287.443418 -304.174144)
			(xy 287.959546 -304.174144) (xy 287.967355 -304.173817) (xy 287.982227 -304.169041) (xy 287.988756 -304.164746)
			(xy 288.009845 -304.150397) (xy 288.055506 -304.127666) (xy 288.104112 -304.112207) (xy 288.154515 -304.104384)
			(xy 288.205521 -304.104384) (xy 288.255924 -304.112207) (xy 288.30453 -304.127666) (xy 288.350191 -304.150397)
			(xy 288.37128 -304.164746) (xy 288.37782 -304.169023) (xy 288.392683 -304.173816) (xy 288.40049 -304.174144)
			(xy 288.916618 -304.174144) (xy 288.921986 -304.174639) (xy 288.929571 -304.182238) (xy 288.93008 -304.187606)
			(xy 288.93008 -304.682144) (xy 291.530024 -304.682144) (xy 291.530024 -304.187606) (xy 291.530553 -304.182246)
			(xy 291.538127 -304.174661) (xy 291.543486 -304.174144) (xy 292.059614 -304.174144) (xy 292.067426 -304.173846)
			(xy 292.082297 -304.16905) (xy 292.088824 -304.164746) (xy 292.109913 -304.150397) (xy 292.155574 -304.127666)
			(xy 292.20418 -304.112207) (xy 292.254583 -304.104384) (xy 292.305589 -304.104384) (xy 292.355992 -304.112207)
			(xy 292.404598 -304.127666) (xy 292.450259 -304.150397) (xy 292.471348 -304.164746) (xy 292.477873 -304.169049)
			(xy 292.492748 -304.173826) (xy 292.500558 -304.174144) (xy 293.016686 -304.174144) (xy 293.02212 -304.174489)
			(xy 293.029807 -304.182172) (xy 293.030148 -304.187606) (xy 293.030148 -304.682144) (xy 294.974264 -304.682144)
			(xy 294.974264 -304.187606) (xy 294.97473 -304.182297) (xy 294.982172 -304.174724) (xy 294.987472 -304.174144)
			(xy 295.5036 -304.174144) (xy 295.511411 -304.17384) (xy 295.526283 -304.169048) (xy 295.53281 -304.164746)
			(xy 295.553899 -304.150397) (xy 295.59956 -304.127666) (xy 295.648166 -304.112207) (xy 295.698569 -304.104384)
			(xy 295.749575 -304.104384) (xy 295.799978 -304.112207) (xy 295.848584 -304.127666) (xy 295.894245 -304.150397)
			(xy 295.915334 -304.164746) (xy 295.921862 -304.169044) (xy 295.936735 -304.173824) (xy 295.944544 -304.174144)
			(xy 296.460672 -304.174144) (xy 296.46592 -304.174708) (xy 296.473361 -304.182107) (xy 296.47388 -304.187352)
			(xy 296.47388 -304.18786) (xy 296.47388 -304.682144) (xy 299.074332 -304.682144) (xy 299.074332 -304.187606)
			(xy 299.074826 -304.182304) (xy 299.082249 -304.174733) (xy 299.08754 -304.174144) (xy 299.603668 -304.174144)
			(xy 299.611478 -304.173826) (xy 299.62635 -304.169044) (xy 299.632878 -304.164746) (xy 299.653967 -304.150397)
			(xy 299.699628 -304.127666) (xy 299.748234 -304.112207) (xy 299.798637 -304.104384) (xy 299.849643 -304.104384)
			(xy 299.900046 -304.112207) (xy 299.948652 -304.127666) (xy 299.994313 -304.150397) (xy 300.015402 -304.164746)
			(xy 300.021937 -304.169031) (xy 300.036804 -304.173819) (xy 300.044612 -304.174144) (xy 300.56074 -304.174144)
			(xy 300.565996 -304.174663) (xy 300.573434 -304.182096) (xy 300.573948 -304.187352) (xy 300.573948 -304.18786)
			(xy 300.573948 -304.682144) (xy 302.518064 -304.682144) (xy 302.518064 -304.187606) (xy 302.518386 -304.182166)
			(xy 302.526085 -304.174478) (xy 302.531526 -304.174144) (xy 304.004726 -304.174144) (xy 304.010094 -304.174634)
			(xy 304.017679 -304.182236) (xy 304.018188 -304.187606) (xy 304.018188 -304.682144) (xy 306.618132 -304.682144)
			(xy 306.618132 -304.187606) (xy 306.618654 -304.182244) (xy 306.626233 -304.174658) (xy 306.631594 -304.174144)
			(xy 308.104794 -304.174144) (xy 308.110229 -304.174484) (xy 308.117916 -304.182171) (xy 308.118256 -304.187606)
			(xy 308.118256 -304.682144) (xy 308.117739 -304.6874) (xy 308.110304 -304.694838) (xy 308.105048 -304.695352)
			(xy 308.10454 -304.695352) (xy 306.631594 -304.695352) (xy 306.626287 -304.69488) (xy 306.618716 -304.687441)
			(xy 306.618132 -304.682144) (xy 304.018188 -304.682144) (xy 304.017732 -304.687417) (xy 304.010255 -304.694858)
			(xy 304.00498 -304.695352) (xy 302.531526 -304.695352) (xy 302.526223 -304.694858) (xy 302.51865 -304.687436)
			(xy 302.518064 -304.682144) (xy 300.573948 -304.682144) (xy 300.573439 -304.687402) (xy 300.565999 -304.69484)
			(xy 300.56074 -304.695352) (xy 300.044866 -304.695352) (xy 300.036991 -304.695633) (xy 300.021987 -304.700421)
			(xy 300.015402 -304.70475) (xy 299.994314 -304.719126) (xy 299.948673 -304.741958) (xy 299.90007 -304.75752)
			(xy 299.849656 -304.765444) (xy 299.82414 -304.765964) (xy 299.79862 -304.765478) (xy 299.748192 -304.757583)
			(xy 299.69958 -304.742023) (xy 299.653942 -304.719166) (xy 299.632878 -304.70475) (xy 299.62629 -304.700429)
			(xy 299.611287 -304.695645) (xy 299.603414 -304.695352) (xy 299.08754 -304.695352) (xy 299.082292 -304.694783)
			(xy 299.07485 -304.687388) (xy 299.074332 -304.682144) (xy 296.47388 -304.682144) (xy 296.473432 -304.687419)
			(xy 296.465949 -304.69486) (xy 296.460672 -304.695352) (xy 295.944798 -304.695352) (xy 295.936924 -304.695646)
			(xy 295.92192 -304.700425) (xy 295.915334 -304.70475) (xy 295.894265 -304.719155) (xy 295.848617 -304.74198)
			(xy 295.800009 -304.757534) (xy 295.749589 -304.765449) (xy 295.724072 -304.765964) (xy 295.698552 -304.765462)
			(xy 295.648126 -304.757572) (xy 295.599514 -304.742016) (xy 295.553875 -304.719164) (xy 295.53281 -304.70475)
			(xy 295.526215 -304.700441) (xy 295.511218 -304.69565) (xy 295.503346 -304.695352) (xy 294.987472 -304.695352)
			(xy 294.982216 -304.694829) (xy 294.974778 -304.687399) (xy 294.974264 -304.682144) (xy 293.030148 -304.682144)
			(xy 293.029639 -304.687402) (xy 293.022199 -304.69484) (xy 293.01694 -304.695352) (xy 293.016432 -304.695352)
			(xy 292.500812 -304.695352) (xy 292.492939 -304.695652) (xy 292.477935 -304.700427) (xy 292.471348 -304.70475)
			(xy 292.450276 -304.719149) (xy 292.404629 -304.741976) (xy 292.356021 -304.757531) (xy 292.305603 -304.765448)
			(xy 292.280086 -304.765964) (xy 292.254567 -304.765455) (xy 292.20414 -304.757567) (xy 292.155528 -304.742013)
			(xy 292.109889 -304.719163) (xy 292.088824 -304.70475) (xy 292.082226 -304.700446) (xy 292.067231 -304.695652)
			(xy 292.05936 -304.695352) (xy 291.543486 -304.695352) (xy 291.538178 -304.694885) (xy 291.530608 -304.687442)
			(xy 291.530024 -304.682144) (xy 288.93008 -304.682144) (xy 288.929632 -304.687419) (xy 288.922149 -304.69486)
			(xy 288.916872 -304.695352) (xy 288.916364 -304.695352) (xy 288.400744 -304.695352) (xy 288.392868 -304.695623)
			(xy 288.377864 -304.700418) (xy 288.37128 -304.70475) (xy 288.350199 -304.719135) (xy 288.304555 -304.741965)
			(xy 288.25595 -304.757525) (xy 288.205534 -304.765446) (xy 288.180018 -304.765964) (xy 288.154497 -304.765489)
			(xy 288.104069 -304.757591) (xy 288.055458 -304.742027) (xy 288.00982 -304.719168) (xy 287.988756 -304.70475)
			(xy 287.982173 -304.70042) (xy 287.967167 -304.695642) (xy 287.959292 -304.695352) (xy 287.443418 -304.695352)
			(xy 287.438114 -304.694864) (xy 287.430541 -304.687437) (xy 287.429956 -304.682144) (xy 285.48584 -304.682144)
			(xy 285.485338 -304.687404) (xy 285.477893 -304.694843) (xy 285.472632 -304.695352) (xy 284.956758 -304.695352)
			(xy 284.948883 -304.695629) (xy 284.933879 -304.70042) (xy 284.927294 -304.70475) (xy 284.906209 -304.719129)
			(xy 284.860567 -304.741961) (xy 284.811963 -304.757522) (xy 284.761548 -304.765445) (xy 284.736032 -304.765964)
			(xy 284.710511 -304.765482) (xy 284.660084 -304.757586) (xy 284.611472 -304.742024) (xy 284.565834 -304.719167)
			(xy 284.54477 -304.70475) (xy 284.538184 -304.700425) (xy 284.52318 -304.695644) (xy 284.515306 -304.695352)
			(xy 283.999432 -304.695352) (xy 283.994183 -304.694789) (xy 283.986742 -304.687389) (xy 283.986224 -304.682144)
			(xy 281.385772 -304.682144) (xy 281.385331 -304.687421) (xy 281.377844 -304.694863) (xy 281.372564 -304.695352)
			(xy 280.85669 -304.695352) (xy 280.848816 -304.695643) (xy 280.833812 -304.700424) (xy 280.827226 -304.70475)
			(xy 280.80616 -304.719159) (xy 280.760511 -304.741983) (xy 280.711901 -304.757536) (xy 280.661482 -304.76545)
			(xy 280.635964 -304.765964) (xy 280.610444 -304.765466) (xy 280.560017 -304.757575) (xy 280.511405 -304.742018)
			(xy 280.465767 -304.719165) (xy 280.444702 -304.70475) (xy 280.438109 -304.700438) (xy 280.42311 -304.695648)
			(xy 280.415238 -304.695352) (xy 279.899364 -304.695352) (xy 279.894108 -304.694834) (xy 279.88667 -304.6874)
			(xy 279.886156 -304.682144) (xy 277.94204 -304.682144) (xy 277.941538 -304.687404) (xy 277.934093 -304.694843)
			(xy 277.928832 -304.695352) (xy 277.412958 -304.695352) (xy 277.405083 -304.695629) (xy 277.390079 -304.70042)
			(xy 277.383494 -304.70475) (xy 277.362409 -304.719129) (xy 277.316767 -304.741961) (xy 277.268163 -304.757522)
			(xy 277.217748 -304.765445) (xy 277.192232 -304.765964) (xy 277.166711 -304.765482) (xy 277.116284 -304.757586)
			(xy 277.067672 -304.742024) (xy 277.022034 -304.719167) (xy 277.00097 -304.70475) (xy 276.994384 -304.700425)
			(xy 276.97938 -304.695644) (xy 276.971506 -304.695352) (xy 276.455632 -304.695352) (xy 276.450383 -304.694789)
			(xy 276.442942 -304.687389) (xy 276.442424 -304.682144) (xy 273.841972 -304.682144) (xy 273.841531 -304.687421)
			(xy 273.834044 -304.694863) (xy 273.828764 -304.695352) (xy 273.31289 -304.695352) (xy 273.305016 -304.695643)
			(xy 273.290012 -304.700424) (xy 273.283426 -304.70475) (xy 273.26236 -304.719159) (xy 273.216711 -304.741983)
			(xy 273.168101 -304.757536) (xy 273.117682 -304.76545) (xy 273.092164 -304.765964) (xy 273.066644 -304.765466)
			(xy 273.016217 -304.757575) (xy 272.967605 -304.742018) (xy 272.921967 -304.719165) (xy 272.900902 -304.70475)
			(xy 272.894309 -304.700438) (xy 272.87931 -304.695648) (xy 272.871438 -304.695352) (xy 272.355564 -304.695352)
			(xy 272.350308 -304.694834) (xy 272.34287 -304.6874) (xy 272.342356 -304.682144) (xy 270.39824 -304.682144)
			(xy 270.397738 -304.687404) (xy 270.390293 -304.694843) (xy 270.385032 -304.695352) (xy 270.384524 -304.695352)
			(xy 269.868904 -304.695352) (xy 269.86103 -304.695649) (xy 269.846026 -304.700426) (xy 269.83944 -304.70475)
			(xy 269.81837 -304.719153) (xy 269.772722 -304.741978) (xy 269.724114 -304.757533) (xy 269.673695 -304.765449)
			(xy 269.648178 -304.765964) (xy 269.622658 -304.765459) (xy 269.572232 -304.75757) (xy 269.52362 -304.742015)
			(xy 269.477981 -304.719164) (xy 269.456916 -304.70475) (xy 269.45032 -304.700443) (xy 269.435323 -304.69565)
			(xy 269.427452 -304.695352) (xy 268.911578 -304.695352) (xy 268.906269 -304.69489) (xy 268.898699 -304.687444)
			(xy 268.898116 -304.682144) (xy 266.298172 -304.682144) (xy 266.297731 -304.687421) (xy 266.290244 -304.694863)
			(xy 266.284964 -304.695352) (xy 266.284456 -304.695352) (xy 265.768836 -304.695352) (xy 265.76096 -304.695619)
			(xy 265.745956 -304.700417) (xy 265.739372 -304.70475) (xy 265.718293 -304.719139) (xy 265.672649 -304.741968)
			(xy 265.624043 -304.757526) (xy 265.573627 -304.765446) (xy 265.54811 -304.765964) (xy 265.522589 -304.765493)
			(xy 265.472161 -304.757594) (xy 265.423549 -304.742029) (xy 265.377912 -304.719168) (xy 265.356848 -304.70475)
			(xy 265.350267 -304.700417) (xy 265.335259 -304.69564) (xy 265.327384 -304.695352) (xy 264.81151 -304.695352)
			(xy 264.806205 -304.694869) (xy 264.798633 -304.687439) (xy 264.798048 -304.682144) (xy 206.997808 -304.682144)
			(xy 206.997808 -304.682398) (xy 206.997281 -304.687691) (xy 206.989881 -304.695259) (xy 206.9846 -304.69586)
			(xy 206.468726 -304.69586) (xy 206.460916 -304.696175) (xy 206.446044 -304.700959) (xy 206.439516 -304.705258)
			(xy 206.418388 -304.719597) (xy 206.372666 -304.742326) (xy 206.323995 -304.757759) (xy 206.27353 -304.765529)
			(xy 206.248 -304.765964) (xy 206.22247 -304.765528) (xy 206.172006 -304.757752) (xy 206.123333 -304.742322)
			(xy 206.077606 -304.719606) (xy 206.056484 -304.705258) (xy 206.049952 -304.700967) (xy 206.035082 -304.696183)
			(xy 206.027274 -304.69586) (xy 205.5114 -304.69586) (xy 205.506056 -304.695569) (xy 205.498512 -304.687997)
			(xy 205.498192 -304.682652) (xy 202.897718 -304.682652) (xy 202.897273 -304.687707) (xy 202.889831 -304.695279)
			(xy 202.884532 -304.69586) (xy 202.368658 -304.69586) (xy 202.360849 -304.696188) (xy 202.345977 -304.700963)
			(xy 202.339448 -304.705258) (xy 202.318339 -304.719627) (xy 202.272611 -304.742349) (xy 202.223933 -304.757773)
			(xy 202.173464 -304.765534) (xy 202.147932 -304.765964) (xy 202.122402 -304.765511) (xy 202.071939 -304.75774)
			(xy 202.023267 -304.742316) (xy 201.977538 -304.719604) (xy 201.956416 -304.705258) (xy 201.949877 -304.70098)
			(xy 201.935013 -304.696188) (xy 201.927206 -304.69586) (xy 201.411332 -304.69586) (xy 201.405992 -304.695547)
			(xy 201.398447 -304.687992) (xy 201.398124 -304.682652) (xy 199.453983 -304.682652) (xy 199.453481 -304.687691)
			(xy 199.446081 -304.695259) (xy 199.4408 -304.69586) (xy 198.924926 -304.69586) (xy 198.917116 -304.696175)
			(xy 198.902244 -304.700959) (xy 198.895716 -304.705258) (xy 198.874588 -304.719597) (xy 198.828866 -304.742326)
			(xy 198.780195 -304.757759) (xy 198.72973 -304.765529) (xy 198.7042 -304.765964) (xy 198.67867 -304.765528)
			(xy 198.628206 -304.757752) (xy 198.579533 -304.742322) (xy 198.533806 -304.719606) (xy 198.512684 -304.705258)
			(xy 198.506152 -304.700967) (xy 198.491282 -304.696183) (xy 198.483474 -304.69586) (xy 197.9676 -304.69586)
			(xy 197.962256 -304.695569) (xy 197.954712 -304.687997) (xy 197.954392 -304.682652) (xy 195.353918 -304.682652)
			(xy 195.353473 -304.687707) (xy 195.346031 -304.695279) (xy 195.340732 -304.69586) (xy 194.824858 -304.69586)
			(xy 194.817049 -304.696188) (xy 194.802177 -304.700963) (xy 194.795648 -304.705258) (xy 194.774539 -304.719627)
			(xy 194.728811 -304.742349) (xy 194.680133 -304.757773) (xy 194.629664 -304.765534) (xy 194.604132 -304.765964)
			(xy 194.578602 -304.765511) (xy 194.528139 -304.75774) (xy 194.479467 -304.742316) (xy 194.433738 -304.719604)
			(xy 194.412616 -304.705258) (xy 194.406077 -304.70098) (xy 194.391213 -304.696188) (xy 194.383406 -304.69586)
			(xy 193.867532 -304.69586) (xy 193.862192 -304.695547) (xy 193.854647 -304.687992) (xy 193.854324 -304.682652)
			(xy 191.910182 -304.682652) (xy 191.909653 -304.687751) (xy 191.902097 -304.695334) (xy 191.896746 -304.69586)
			(xy 191.380872 -304.69586) (xy 191.37306 -304.696151) (xy 191.358188 -304.700952) (xy 191.351662 -304.705258)
			(xy 191.330549 -304.719621) (xy 191.284822 -304.742344) (xy 191.236146 -304.75777) (xy 191.185678 -304.765533)
			(xy 191.160146 -304.765964) (xy 191.134617 -304.765504) (xy 191.084154 -304.757736) (xy 191.035481 -304.742313)
			(xy 190.989753 -304.719603) (xy 190.96863 -304.705258) (xy 190.962088 -304.700985) (xy 190.947226 -304.69619)
			(xy 190.93942 -304.69586) (xy 190.423546 -304.69586) (xy 190.418117 -304.69549) (xy 190.410428 -304.687826)
			(xy 190.410084 -304.682398) (xy 187.81014 -304.682398) (xy 187.809817 -304.687838) (xy 187.802118 -304.695525)
			(xy 187.796678 -304.69586) (xy 187.280804 -304.69586) (xy 187.272993 -304.696165) (xy 187.258121 -304.700956)
			(xy 187.251594 -304.705258) (xy 187.230472 -304.719607) (xy 187.184748 -304.742333) (xy 187.136075 -304.757764)
			(xy 187.085609 -304.765531) (xy 187.060078 -304.765964) (xy 187.034547 -304.765539) (xy 186.984083 -304.757759)
			(xy 186.935411 -304.742327) (xy 186.889684 -304.719607) (xy 186.868562 -304.705258) (xy 186.862035 -304.700959)
			(xy 186.847162 -304.69618) (xy 186.839352 -304.69586) (xy 186.323478 -304.69586) (xy 186.318111 -304.695364)
			(xy 186.310526 -304.687766) (xy 186.310016 -304.682398) (xy 184.3659 -304.682398) (xy 184.36538 -304.687693)
			(xy 184.357975 -304.695261) (xy 184.352692 -304.69586) (xy 183.836818 -304.69586) (xy 183.829008 -304.696171)
			(xy 183.814136 -304.700958) (xy 183.807608 -304.705258) (xy 183.786482 -304.719601) (xy 183.74076 -304.742329)
			(xy 183.692088 -304.757761) (xy 183.641623 -304.76553) (xy 183.616092 -304.765964) (xy 183.590562 -304.765532)
			(xy 183.540098 -304.757754) (xy 183.491425 -304.742324) (xy 183.445698 -304.719606) (xy 183.424576 -304.705258)
			(xy 183.418046 -304.700964) (xy 183.403175 -304.696182) (xy 183.395366 -304.69586) (xy 182.879492 -304.69586)
			(xy 182.874147 -304.695574) (xy 182.866603 -304.687999) (xy 182.866284 -304.682652) (xy 180.26581 -304.682652)
			(xy 180.265372 -304.687708) (xy 180.257926 -304.695281) (xy 180.252624 -304.69586) (xy 179.73675 -304.69586)
			(xy 179.728941 -304.696185) (xy 179.714069 -304.700962) (xy 179.70754 -304.705258) (xy 179.686433 -304.71963)
			(xy 179.640704 -304.742351) (xy 179.592026 -304.757775) (xy 179.541556 -304.765535) (xy 179.516024 -304.765964)
			(xy 179.490494 -304.765516) (xy 179.440031 -304.757743) (xy 179.391358 -304.742318) (xy 179.34563 -304.719604)
			(xy 179.324508 -304.705258) (xy 179.317971 -304.700977) (xy 179.303105 -304.696187) (xy 179.295298 -304.69586)
			(xy 178.779424 -304.69586) (xy 178.774083 -304.695552) (xy 178.766538 -304.687993) (xy 178.766216 -304.682652)
			(xy 176.822074 -304.682652) (xy 176.821552 -304.687753) (xy 176.813991 -304.695336) (xy 176.808638 -304.69586)
			(xy 176.292764 -304.69586) (xy 176.284955 -304.696191) (xy 176.270083 -304.700964) (xy 176.263554 -304.705258)
			(xy 176.242443 -304.719624) (xy 176.196715 -304.742347) (xy 176.148039 -304.757772) (xy 176.09757 -304.765534)
			(xy 176.072038 -304.765964) (xy 176.046508 -304.765508) (xy 175.996045 -304.757738) (xy 175.947373 -304.742315)
			(xy 175.901645 -304.719603) (xy 175.880522 -304.705258) (xy 175.873981 -304.700982) (xy 175.859119 -304.696189)
			(xy 175.851312 -304.69586) (xy 175.335438 -304.69586) (xy 175.330008 -304.695495) (xy 175.322319 -304.687827)
			(xy 175.321976 -304.682398) (xy 172.722032 -304.682398) (xy 172.721716 -304.68784) (xy 172.714012 -304.695528)
			(xy 172.70857 -304.69586) (xy 172.192696 -304.69586) (xy 172.184885 -304.696162) (xy 172.170013 -304.700955)
			(xy 172.163486 -304.705258) (xy 172.142366 -304.71961) (xy 172.096642 -304.742336) (xy 172.047968 -304.757765)
			(xy 171.997501 -304.765531) (xy 171.97197 -304.765964) (xy 171.946439 -304.765543) (xy 171.895975 -304.757762)
			(xy 171.847302 -304.742329) (xy 171.801575 -304.719608) (xy 171.780454 -304.705258) (xy 171.773929 -304.700956)
			(xy 171.759054 -304.696179) (xy 171.751244 -304.69586) (xy 171.23537 -304.69586) (xy 171.230002 -304.695369)
			(xy 171.222418 -304.687767) (xy 171.221908 -304.682398) (xy 169.277792 -304.682398) (xy 169.277279 -304.687694)
			(xy 169.269869 -304.695264) (xy 169.264584 -304.69586) (xy 167.791384 -304.69586) (xy 167.786038 -304.695579)
			(xy 167.778495 -304.688) (xy 167.778176 -304.682652) (xy 165.177702 -304.682652) (xy 165.177271 -304.68771)
			(xy 165.16982 -304.695284) (xy 165.164516 -304.69586) (xy 163.691316 -304.69586) (xy 163.685974 -304.695558)
			(xy 163.678429 -304.687995) (xy 163.678108 -304.682652) (xy 145.041642 -304.682652) (xy 145.043148 -304.709231)
			(xy 145.04365 -304.780188) (xy 326.7517 -304.780188) (xy 326.75573 -304.637824) (xy 326.767808 -304.495916)
			(xy 326.787896 -304.354919) (xy 326.815928 -304.215284) (xy 326.851815 -304.077458) (xy 326.895442 -303.941884)
			(xy 326.946669 -303.808995) (xy 327.005332 -303.679216) (xy 327.071244 -303.552965) (xy 327.144193 -303.430645)
			(xy 327.223945 -303.312648) (xy 327.310245 -303.199352) (xy 327.402817 -303.091119) (xy 327.501363 -302.988297)
			(xy 327.605569 -302.891216) (xy 327.715101 -302.800185) (xy 327.829607 -302.715497) (xy 327.948721 -302.637422)
			(xy 328.072061 -302.566212) (xy 328.199232 -302.502093) (xy 328.329828 -302.445272) (xy 328.463428 -302.395931)
			(xy 328.599607 -302.354226) (xy 328.737926 -302.320293) (xy 328.877944 -302.29424) (xy 329.019211 -302.27615)
			(xy 329.161276 -302.266081) (xy 329.303683 -302.264066) (xy 329.445976 -302.27011) (xy 329.587698 -302.284196)
			(xy 329.728397 -302.306276) (xy 329.867622 -302.336281) (xy 330.004926 -302.374115) (xy 330.139869 -302.419656)
			(xy 330.27202 -302.472759) (xy 330.400955 -302.533253) (xy 330.526261 -302.600944) (xy 330.647537 -302.675617)
			(xy 330.764393 -302.757031) (xy 330.876457 -302.844925) (xy 330.983369 -302.939019) (xy 331.084786 -303.039011)
			(xy 331.180383 -303.14458) (xy 331.269855 -303.255389) (xy 331.352914 -303.371082) (xy 331.429295 -303.491289)
			(xy 331.498753 -303.615624) (xy 331.561066 -303.74369) (xy 331.616033 -303.875077) (xy 331.663479 -304.009362)
			(xy 331.703252 -304.146117) (xy 331.735224 -304.284903) (xy 331.759294 -304.425275) (xy 331.775383 -304.566785)
			(xy 331.781862 -304.681128) (xy 333.795116 -304.681128) (xy 333.795116 -303.817528) (xy 333.795602 -303.790259)
			(xy 333.803364 -303.736275) (xy 333.818729 -303.683945) (xy 333.841386 -303.634335) (xy 333.870872 -303.588454)
			(xy 333.906587 -303.547237) (xy 333.947804 -303.511522) (xy 333.993685 -303.482036) (xy 334.043295 -303.459379)
			(xy 334.095625 -303.444014) (xy 334.149609 -303.436252) (xy 334.204147 -303.436252) (xy 334.258131 -303.444014)
			(xy 334.310461 -303.459379) (xy 334.360071 -303.482036) (xy 334.405952 -303.511522) (xy 334.447169 -303.547237)
			(xy 334.482884 -303.588454) (xy 334.51237 -303.634335) (xy 334.535027 -303.683945) (xy 334.550392 -303.736275)
			(xy 334.558154 -303.790259) (xy 334.55864 -303.817528) (xy 334.55864 -304.681128) (xy 334.558154 -304.708397)
			(xy 334.550392 -304.762381) (xy 334.545164 -304.780188) (xy 387.951476 -304.780188) (xy 387.955506 -304.637824)
			(xy 387.967584 -304.495916) (xy 387.987672 -304.354919) (xy 388.015704 -304.215284) (xy 388.051591 -304.077458)
			(xy 388.095218 -303.941884) (xy 388.146445 -303.808995) (xy 388.205108 -303.679216) (xy 388.27102 -303.552965)
			(xy 388.343969 -303.430645) (xy 388.423721 -303.312648) (xy 388.510021 -303.199352) (xy 388.602593 -303.091119)
			(xy 388.701139 -302.988297) (xy 388.805345 -302.891216) (xy 388.914877 -302.800185) (xy 389.029383 -302.715497)
			(xy 389.148497 -302.637422) (xy 389.271837 -302.566212) (xy 389.399008 -302.502093) (xy 389.529604 -302.445272)
			(xy 389.663204 -302.395931) (xy 389.799383 -302.354226) (xy 389.937702 -302.320293) (xy 390.07772 -302.29424)
			(xy 390.218987 -302.27615) (xy 390.361052 -302.266081) (xy 390.503459 -302.264066) (xy 390.645752 -302.27011)
			(xy 390.787474 -302.284196) (xy 390.928173 -302.306276) (xy 391.067398 -302.336281) (xy 391.204702 -302.374115)
			(xy 391.339645 -302.419656) (xy 391.471796 -302.472759) (xy 391.600731 -302.533253) (xy 391.726037 -302.600944)
			(xy 391.847313 -302.675617) (xy 391.964169 -302.757031) (xy 392.076233 -302.844925) (xy 392.183145 -302.939019)
			(xy 392.22712 -302.982376) (xy 411.618176 -302.982376) (xy 411.618176 -302.981868) (xy 411.618176 -302.487584)
			(xy 411.618682 -302.482323) (xy 411.626123 -302.474882) (xy 411.631384 -302.474376) (xy 413.104584 -302.474376)
			(xy 413.109841 -302.474904) (xy 413.117284 -302.482328) (xy 413.117792 -302.487584) (xy 413.117792 -302.982122)
			(xy 419.161976 -302.982122) (xy 419.161976 -302.487584) (xy 419.162482 -302.482323) (xy 419.169923 -302.474882)
			(xy 419.175184 -302.474376) (xy 419.175692 -302.474376) (xy 419.691566 -302.474376) (xy 419.699375 -302.474052)
			(xy 419.714247 -302.469274) (xy 419.720776 -302.464978) (xy 419.741865 -302.450629) (xy 419.787526 -302.427898)
			(xy 419.836132 -302.412439) (xy 419.886535 -302.404616) (xy 419.937541 -302.404616) (xy 419.987944 -302.412439)
			(xy 420.03655 -302.427898) (xy 420.082211 -302.450629) (xy 420.1033 -302.464978) (xy 420.109834 -302.469266)
			(xy 420.124702 -302.474051) (xy 420.13251 -302.474376) (xy 420.648638 -302.474376) (xy 420.653955 -302.474802)
			(xy 420.661526 -302.482274) (xy 420.6621 -302.487584) (xy 420.6621 -302.982122) (xy 420.662075 -302.982376)
			(xy 426.706284 -302.982376) (xy 426.706284 -302.981868) (xy 426.706284 -302.487584) (xy 426.706783 -302.482321)
			(xy 426.714229 -302.47488) (xy 426.719492 -302.474376) (xy 427.23562 -302.474376) (xy 427.243431 -302.474075)
			(xy 427.258303 -302.469281) (xy 427.26483 -302.464978) (xy 427.285919 -302.450629) (xy 427.33158 -302.427898)
			(xy 427.380186 -302.412439) (xy 427.430589 -302.404616) (xy 427.481595 -302.404616) (xy 427.531998 -302.412439)
			(xy 427.580604 -302.427898) (xy 427.626265 -302.450629) (xy 427.647354 -302.464978) (xy 427.653876 -302.469286)
			(xy 427.668753 -302.474059) (xy 427.676564 -302.474376) (xy 428.192692 -302.474376) (xy 428.19795 -302.474898)
			(xy 428.205392 -302.482327) (xy 428.2059 -302.487584) (xy 428.2059 -302.982122) (xy 434.250084 -302.982122)
			(xy 434.250084 -302.487584) (xy 434.250583 -302.482321) (xy 434.258029 -302.47488) (xy 434.263292 -302.474376)
			(xy 434.2638 -302.474376) (xy 434.779674 -302.474376) (xy 434.787484 -302.474056) (xy 434.802355 -302.469275)
			(xy 434.808884 -302.464978) (xy 434.829973 -302.450629) (xy 434.875634 -302.427898) (xy 434.92424 -302.412439)
			(xy 434.974643 -302.404616) (xy 435.025649 -302.404616) (xy 435.076052 -302.412439) (xy 435.124658 -302.427898)
			(xy 435.170319 -302.450629) (xy 435.191408 -302.464978) (xy 435.19794 -302.469269) (xy 435.21281 -302.474052)
			(xy 435.220618 -302.474376) (xy 435.736746 -302.474376) (xy 435.742052 -302.474863) (xy 435.749628 -302.482289)
			(xy 435.750208 -302.487584) (xy 435.750208 -302.982122) (xy 435.750182 -302.982376) (xy 441.794392 -302.982376)
			(xy 441.794392 -302.981868) (xy 441.794392 -302.487584) (xy 441.794884 -302.482319) (xy 441.802335 -302.474878)
			(xy 441.8076 -302.474376) (xy 442.323728 -302.474376) (xy 442.33154 -302.474078) (xy 442.346411 -302.469282)
			(xy 442.352938 -302.464978) (xy 442.374027 -302.450629) (xy 442.419688 -302.427898) (xy 442.468294 -302.412439)
			(xy 442.518697 -302.404616) (xy 442.569703 -302.404616) (xy 442.620106 -302.412439) (xy 442.668712 -302.427898)
			(xy 442.714373 -302.450629) (xy 442.735462 -302.464978) (xy 442.742004 -302.469251) (xy 442.756866 -302.474046)
			(xy 442.764672 -302.474376) (xy 443.2808 -302.474376) (xy 443.286059 -302.474893) (xy 443.2935 -302.482326)
			(xy 443.294008 -302.487584) (xy 443.294008 -302.982122) (xy 443.293983 -302.982376) (xy 449.338192 -302.982376)
			(xy 449.338192 -302.981868) (xy 449.338192 -302.487584) (xy 449.338684 -302.482319) (xy 449.346135 -302.474878)
			(xy 449.3514 -302.474376) (xy 449.867528 -302.474376) (xy 449.87534 -302.474078) (xy 449.890211 -302.469282)
			(xy 449.896738 -302.464978) (xy 449.917827 -302.450629) (xy 449.963488 -302.427898) (xy 450.012094 -302.412439)
			(xy 450.062497 -302.404616) (xy 450.113503 -302.404616) (xy 450.163906 -302.412439) (xy 450.212512 -302.427898)
			(xy 450.258173 -302.450629) (xy 450.279262 -302.464978) (xy 450.285804 -302.469251) (xy 450.300666 -302.474046)
			(xy 450.308472 -302.474376) (xy 450.8246 -302.474376) (xy 450.829859 -302.474893) (xy 450.8373 -302.482326)
			(xy 450.837808 -302.487584) (xy 450.837808 -302.982122) (xy 450.837297 -302.987418) (xy 450.829884 -302.994985)
			(xy 450.8246 -302.995584) (xy 450.308726 -302.995584) (xy 450.300915 -302.995895) (xy 450.286043 -303.000681)
			(xy 450.279516 -303.004982) (xy 450.25839 -303.019324) (xy 450.212667 -303.042052) (xy 450.163996 -303.057483)
			(xy 450.11353 -303.065253) (xy 450.088 -303.065688) (xy 450.06247 -303.065247) (xy 450.012006 -303.057472)
			(xy 449.963334 -303.042044) (xy 449.917606 -303.019329) (xy 449.896484 -303.004982) (xy 449.889951 -303.000694)
			(xy 449.875082 -302.995907) (xy 449.867274 -302.995584) (xy 449.3514 -302.995584) (xy 449.346062 -302.995271)
			(xy 449.338519 -302.987715) (xy 449.338192 -302.982376) (xy 443.293983 -302.982376) (xy 443.293497 -302.987418)
			(xy 443.286084 -302.994985) (xy 443.2808 -302.995584) (xy 442.764926 -302.995584) (xy 442.757115 -302.995895)
			(xy 442.742243 -303.000681) (xy 442.735716 -303.004982) (xy 442.71459 -303.019324) (xy 442.668867 -303.042052)
			(xy 442.620196 -303.057483) (xy 442.56973 -303.065253) (xy 442.5442 -303.065688) (xy 442.51867 -303.065247)
			(xy 442.468206 -303.057472) (xy 442.419534 -303.042044) (xy 442.373806 -303.019329) (xy 442.352684 -303.004982)
			(xy 442.346151 -303.000694) (xy 442.331282 -302.995907) (xy 442.323474 -302.995584) (xy 441.8076 -302.995584)
			(xy 441.802262 -302.995271) (xy 441.794719 -302.987715) (xy 441.794392 -302.982376) (xy 435.750182 -302.982376)
			(xy 435.749669 -302.987477) (xy 435.742101 -302.995059) (xy 435.736746 -302.995584) (xy 435.220872 -302.995584)
			(xy 435.213059 -302.995872) (xy 435.198188 -303.000674) (xy 435.191662 -303.004982) (xy 435.170551 -303.019347)
			(xy 435.124823 -303.04207) (xy 435.076147 -303.057495) (xy 435.025678 -303.065257) (xy 435.000146 -303.065688)
			(xy 434.974617 -303.065224) (xy 434.924154 -303.057456) (xy 434.875482 -303.042035) (xy 434.829753 -303.019326)
			(xy 434.80863 -303.004982) (xy 434.802086 -303.000711) (xy 434.787226 -302.995914) (xy 434.77942 -302.995584)
			(xy 434.263546 -302.995584) (xy 434.258123 -302.995192) (xy 434.250435 -302.987544) (xy 434.250084 -302.982122)
			(xy 428.2059 -302.982122) (xy 428.205396 -302.987419) (xy 428.197979 -302.994987) (xy 428.192692 -302.995584)
			(xy 427.676818 -302.995584) (xy 427.669007 -302.995891) (xy 427.654135 -303.00068) (xy 427.647608 -303.004982)
			(xy 427.626484 -303.019328) (xy 427.580761 -303.042054) (xy 427.532088 -303.057485) (xy 427.481623 -303.065254)
			(xy 427.456092 -303.065688) (xy 427.430562 -303.065251) (xy 427.380098 -303.057475) (xy 427.331426 -303.042045)
			(xy 427.285698 -303.019329) (xy 427.264576 -303.004982) (xy 427.258044 -303.000691) (xy 427.243175 -302.995906)
			(xy 427.235366 -302.995584) (xy 426.719492 -302.995584) (xy 426.714153 -302.995276) (xy 426.706611 -302.987716)
			(xy 426.706284 -302.982376) (xy 420.662075 -302.982376) (xy 420.661568 -302.987479) (xy 420.653995 -302.995062)
			(xy 420.648638 -302.995584) (xy 420.132764 -302.995584) (xy 420.124955 -302.995911) (xy 420.110083 -303.000686)
			(xy 420.103554 -303.004982) (xy 420.082445 -303.019351) (xy 420.036716 -303.042072) (xy 419.988039 -303.057497)
			(xy 419.93757 -303.065258) (xy 419.912038 -303.065688) (xy 419.886509 -303.065228) (xy 419.836046 -303.057459)
			(xy 419.787374 -303.042036) (xy 419.741645 -303.019326) (xy 419.720522 -303.004982) (xy 419.71398 -303.000708)
			(xy 419.699118 -302.995913) (xy 419.691312 -302.995584) (xy 419.175438 -302.995584) (xy 419.170013 -302.995198)
			(xy 419.162327 -302.987545) (xy 419.161976 -302.982122) (xy 413.117792 -302.982122) (xy 413.117295 -302.987421)
			(xy 413.109873 -302.994989) (xy 413.104584 -302.995584) (xy 411.631384 -302.995584) (xy 411.626044 -302.995282)
			(xy 411.618502 -302.987717) (xy 411.618176 -302.982376) (xy 392.22712 -302.982376) (xy 392.284562 -303.039011)
			(xy 392.380159 -303.14458) (xy 392.469631 -303.255389) (xy 392.55269 -303.371082) (xy 392.629071 -303.491289)
			(xy 392.698529 -303.615624) (xy 392.760842 -303.74369) (xy 392.797896 -303.83226) (xy 415.718244 -303.83226)
			(xy 415.718244 -303.337722) (xy 415.718738 -303.332419) (xy 415.72616 -303.324847) (xy 415.731452 -303.32426)
			(xy 417.204652 -303.32426) (xy 417.20997 -303.324656) (xy 417.217512 -303.332152) (xy 417.21786 -303.337468)
			(xy 417.21786 -303.83226) (xy 423.262044 -303.83226) (xy 423.262044 -303.337722) (xy 423.262395 -303.332289)
			(xy 423.270073 -303.324601) (xy 423.275506 -303.32426) (xy 423.791634 -303.32426) (xy 423.799442 -303.323925)
			(xy 423.814314 -303.319154) (xy 423.820844 -303.314862) (xy 423.841933 -303.300513) (xy 423.887594 -303.277782)
			(xy 423.9362 -303.262323) (xy 423.986603 -303.2545) (xy 424.037609 -303.2545) (xy 424.088012 -303.262323)
			(xy 424.136618 -303.277782) (xy 424.182279 -303.300513) (xy 424.203368 -303.314862) (xy 424.20991 -303.319136)
			(xy 424.224772 -303.32393) (xy 424.232578 -303.32426) (xy 424.748706 -303.32426) (xy 424.754147 -303.324578)
			(xy 424.761834 -303.33228) (xy 424.762168 -303.337722) (xy 424.762168 -303.83226) (xy 430.806352 -303.83226)
			(xy 430.806352 -303.337722) (xy 430.806839 -303.332418) (xy 430.814266 -303.324844) (xy 430.81956 -303.32426)
			(xy 431.335688 -303.32426) (xy 431.343498 -303.323948) (xy 431.35837 -303.319162) (xy 431.364898 -303.314862)
			(xy 431.385987 -303.300513) (xy 431.431648 -303.277782) (xy 431.480254 -303.262323) (xy 431.530657 -303.2545)
			(xy 431.581663 -303.2545) (xy 431.632066 -303.262323) (xy 431.680672 -303.277782) (xy 431.726333 -303.300513)
			(xy 431.747422 -303.314862) (xy 431.753952 -303.319157) (xy 431.768823 -303.323938) (xy 431.776632 -303.32426)
			(xy 432.29276 -303.32426) (xy 432.298079 -303.324651) (xy 432.30562 -303.332151) (xy 432.305968 -303.337468)
			(xy 432.305968 -303.337976) (xy 432.305968 -303.83226) (xy 438.350152 -303.83226) (xy 438.350152 -303.337722)
			(xy 438.350496 -303.332287) (xy 438.358179 -303.324599) (xy 438.363614 -303.32426) (xy 438.879742 -303.32426)
			(xy 438.887551 -303.323928) (xy 438.902422 -303.319155) (xy 438.908952 -303.314862) (xy 438.930041 -303.300513)
			(xy 438.975702 -303.277782) (xy 439.024308 -303.262323) (xy 439.074711 -303.2545) (xy 439.125717 -303.2545)
			(xy 439.17612 -303.262323) (xy 439.224726 -303.277782) (xy 439.270387 -303.300513) (xy 439.291476 -303.314862)
			(xy 439.298016 -303.319139) (xy 439.312879 -303.323931) (xy 439.320686 -303.32426) (xy 439.836814 -303.32426)
			(xy 439.842256 -303.324572) (xy 439.849942 -303.332279) (xy 439.850276 -303.337722) (xy 439.850276 -303.83226)
			(xy 445.89446 -303.83226) (xy 445.89446 -303.337722) (xy 445.89494 -303.332416) (xy 445.902372 -303.324842)
			(xy 445.907668 -303.32426) (xy 446.423796 -303.32426) (xy 446.431607 -303.323952) (xy 446.446478 -303.319163)
			(xy 446.453006 -303.314862) (xy 446.474095 -303.300513) (xy 446.519756 -303.277782) (xy 446.568362 -303.262323)
			(xy 446.618765 -303.2545) (xy 446.669771 -303.2545) (xy 446.720174 -303.262323) (xy 446.76878 -303.277782)
			(xy 446.814441 -303.300513) (xy 446.83553 -303.314862) (xy 446.842058 -303.31916) (xy 446.856931 -303.323939)
			(xy 446.86474 -303.32426) (xy 447.380868 -303.32426) (xy 447.386119 -303.324813) (xy 447.393562 -303.332219)
			(xy 447.394076 -303.337468) (xy 447.394076 -303.337976) (xy 447.394076 -303.83226) (xy 453.43826 -303.83226)
			(xy 453.43826 -303.337722) (xy 453.43874 -303.332416) (xy 453.446172 -303.324842) (xy 453.451468 -303.32426)
			(xy 453.967596 -303.32426) (xy 453.975407 -303.323952) (xy 453.990278 -303.319163) (xy 453.996806 -303.314862)
			(xy 454.017895 -303.300513) (xy 454.063556 -303.277782) (xy 454.112162 -303.262323) (xy 454.162565 -303.2545)
			(xy 454.213571 -303.2545) (xy 454.263974 -303.262323) (xy 454.31258 -303.277782) (xy 454.358241 -303.300513)
			(xy 454.37933 -303.314862) (xy 454.385858 -303.31916) (xy 454.400731 -303.323939) (xy 454.40854 -303.32426)
			(xy 454.924668 -303.32426) (xy 454.929919 -303.324813) (xy 454.937362 -303.332219) (xy 454.937876 -303.337468)
			(xy 454.937876 -303.337976) (xy 454.937876 -303.83226) (xy 454.937543 -303.837595) (xy 454.930002 -303.84514)
			(xy 454.924668 -303.845468) (xy 454.408794 -303.845468) (xy 454.40092 -303.845758) (xy 454.385915 -303.85054)
			(xy 454.37933 -303.854866) (xy 454.358264 -303.869275) (xy 454.312615 -303.892099) (xy 454.264005 -303.907652)
			(xy 454.213586 -303.915565) (xy 454.188068 -303.91608) (xy 454.162548 -303.915577) (xy 454.112122 -303.907687)
			(xy 454.06351 -303.892131) (xy 454.017871 -303.86928) (xy 453.996806 -303.854866) (xy 453.990211 -303.850557)
			(xy 453.975214 -303.845765) (xy 453.967342 -303.845468) (xy 453.451468 -303.845468) (xy 453.446122 -303.845191)
			(xy 453.43858 -303.837608) (xy 453.43826 -303.83226) (xy 447.394076 -303.83226) (xy 447.393743 -303.837595)
			(xy 447.386202 -303.84514) (xy 447.380868 -303.845468) (xy 446.864994 -303.845468) (xy 446.85712 -303.845758)
			(xy 446.842115 -303.85054) (xy 446.83553 -303.854866) (xy 446.814464 -303.869275) (xy 446.768815 -303.892099)
			(xy 446.720205 -303.907652) (xy 446.669786 -303.915565) (xy 446.644268 -303.91608) (xy 446.618748 -303.915577)
			(xy 446.568322 -303.907687) (xy 446.51971 -303.892131) (xy 446.474071 -303.86928) (xy 446.453006 -303.854866)
			(xy 446.446411 -303.850557) (xy 446.431414 -303.845765) (xy 446.423542 -303.845468) (xy 445.907668 -303.845468)
			(xy 445.902322 -303.845191) (xy 445.89478 -303.837608) (xy 445.89446 -303.83226) (xy 439.850276 -303.83226)
			(xy 439.849943 -303.837595) (xy 439.842402 -303.84514) (xy 439.837068 -303.845468) (xy 439.83656 -303.845468)
			(xy 439.32094 -303.845468) (xy 439.313064 -303.845735) (xy 439.29806 -303.850533) (xy 439.291476 -303.854866)
			(xy 439.270397 -303.869255) (xy 439.224753 -303.892083) (xy 439.176147 -303.907642) (xy 439.125731 -303.915562)
			(xy 439.100214 -303.91608) (xy 439.074693 -303.915604) (xy 439.024266 -303.907706) (xy 438.975654 -303.892142)
			(xy 438.930016 -303.869283) (xy 438.908952 -303.854866) (xy 438.902369 -303.850536) (xy 438.887363 -303.845757)
			(xy 438.879488 -303.845468) (xy 438.363614 -303.845468) (xy 438.358313 -303.844968) (xy 438.350742 -303.83755)
			(xy 438.350152 -303.83226) (xy 432.305968 -303.83226) (xy 432.305642 -303.837597) (xy 432.298097 -303.845142)
			(xy 432.29276 -303.845468) (xy 431.776886 -303.845468) (xy 431.769011 -303.845754) (xy 431.754007 -303.850539)
			(xy 431.747422 -303.854866) (xy 431.726358 -303.869278) (xy 431.680708 -303.892101) (xy 431.632098 -303.907653)
			(xy 431.581678 -303.915566) (xy 431.55616 -303.91608) (xy 431.53064 -303.915581) (xy 431.480213 -303.90769)
			(xy 431.431602 -303.892133) (xy 431.385963 -303.86928) (xy 431.364898 -303.854866) (xy 431.358305 -303.850554)
			(xy 431.343306 -303.845764) (xy 431.335434 -303.845468) (xy 430.81956 -303.845468) (xy 430.814283 -303.845028)
			(xy 430.80684 -303.83754) (xy 430.806352 -303.83226) (xy 424.762168 -303.83226) (xy 424.761842 -303.837597)
			(xy 424.754297 -303.845142) (xy 424.74896 -303.845468) (xy 424.748452 -303.845468) (xy 424.232832 -303.845468)
			(xy 424.224955 -303.845731) (xy 424.209951 -303.850531) (xy 424.203368 -303.854866) (xy 424.182291 -303.869259)
			(xy 424.136646 -303.892086) (xy 424.08804 -303.907644) (xy 424.037623 -303.915563) (xy 424.012106 -303.91608)
			(xy 423.986585 -303.915608) (xy 423.936157 -303.907709) (xy 423.887546 -303.892144) (xy 423.841908 -303.869284)
			(xy 423.820844 -303.854866) (xy 423.814263 -303.850533) (xy 423.799255 -303.845756) (xy 423.79138 -303.845468)
			(xy 423.275506 -303.845468) (xy 423.270204 -303.844974) (xy 423.262633 -303.837551) (xy 423.262044 -303.83226)
			(xy 417.21786 -303.83226) (xy 417.217541 -303.837599) (xy 417.209991 -303.845145) (xy 417.204652 -303.845468)
			(xy 415.731452 -303.845468) (xy 415.726174 -303.845033) (xy 415.718732 -303.837541) (xy 415.718244 -303.83226)
			(xy 392.797896 -303.83226) (xy 392.815809 -303.875077) (xy 392.863255 -304.009362) (xy 392.903028 -304.146117)
			(xy 392.935 -304.284903) (xy 392.95907 -304.425275) (xy 392.975159 -304.566785) (xy 392.981696 -304.682144)
			(xy 411.618176 -304.682144) (xy 411.618176 -304.187606) (xy 411.618631 -304.182294) (xy 411.626081 -304.17472)
			(xy 411.631384 -304.174144) (xy 413.104584 -304.174144) (xy 413.109833 -304.1747) (xy 413.117274 -304.182105)
			(xy 413.117792 -304.187352) (xy 413.117792 -304.18786) (xy 413.117792 -304.682144) (xy 415.718244 -304.682144)
			(xy 415.718244 -304.187606) (xy 415.718728 -304.182302) (xy 415.726158 -304.17473) (xy 415.731452 -304.174144)
			(xy 417.204652 -304.174144) (xy 417.209898 -304.174722) (xy 417.21734 -304.18211) (xy 417.21786 -304.187352)
			(xy 417.21786 -304.682144) (xy 419.161976 -304.682144) (xy 419.161976 -304.187606) (xy 419.162287 -304.182163)
			(xy 419.169994 -304.174474) (xy 419.175438 -304.174144) (xy 419.691566 -304.174144) (xy 419.699376 -304.173825)
			(xy 419.714248 -304.169044) (xy 419.720776 -304.164746) (xy 419.741865 -304.150397) (xy 419.787526 -304.127666)
			(xy 419.836132 -304.112207) (xy 419.886535 -304.104384) (xy 419.937541 -304.104384) (xy 419.987944 -304.112207)
			(xy 420.03655 -304.127666) (xy 420.082211 -304.150397) (xy 420.1033 -304.164746) (xy 420.109835 -304.169031)
			(xy 420.124702 -304.173819) (xy 420.13251 -304.174144) (xy 420.648638 -304.174144) (xy 420.654008 -304.174626)
			(xy 420.661592 -304.182235) (xy 420.6621 -304.187606) (xy 420.6621 -304.682144) (xy 423.262044 -304.682144)
			(xy 423.262044 -304.187606) (xy 423.262384 -304.182171) (xy 423.270071 -304.174484) (xy 423.275506 -304.174144)
			(xy 423.791634 -304.174144) (xy 423.799443 -304.173812) (xy 423.814314 -304.169039) (xy 423.820844 -304.164746)
			(xy 423.841933 -304.150397) (xy 423.887594 -304.127666) (xy 423.9362 -304.112207) (xy 423.986603 -304.104384)
			(xy 424.037609 -304.104384) (xy 424.088012 -304.112207) (xy 424.136618 -304.127666) (xy 424.182279 -304.150397)
			(xy 424.203368 -304.164746) (xy 424.209911 -304.169018) (xy 424.224772 -304.173814) (xy 424.232578 -304.174144)
			(xy 424.748706 -304.174144) (xy 424.754072 -304.174647) (xy 424.761658 -304.182239) (xy 424.762168 -304.187606)
			(xy 424.762168 -304.682144) (xy 426.706284 -304.682144) (xy 426.706284 -304.187606) (xy 426.706732 -304.182292)
			(xy 426.714187 -304.174718) (xy 426.719492 -304.174144) (xy 427.23562 -304.174144) (xy 427.243432 -304.173848)
			(xy 427.258304 -304.169051) (xy 427.26483 -304.164746) (xy 427.285919 -304.150397) (xy 427.33158 -304.127666)
			(xy 427.380186 -304.112207) (xy 427.430589 -304.104384) (xy 427.481595 -304.104384) (xy 427.531998 -304.112207)
			(xy 427.580604 -304.127666) (xy 427.626265 -304.150397) (xy 427.647354 -304.164746) (xy 427.653877 -304.169051)
			(xy 427.668754 -304.173827) (xy 427.676564 -304.174144) (xy 428.192692 -304.174144) (xy 428.197942 -304.174695)
			(xy 428.205383 -304.182104) (xy 428.2059 -304.187352) (xy 428.2059 -304.18786) (xy 428.2059 -304.682144)
			(xy 430.806352 -304.682144) (xy 430.806352 -304.187606) (xy 430.806828 -304.1823) (xy 430.814263 -304.174728)
			(xy 430.81956 -304.174144) (xy 431.335688 -304.174144) (xy 431.343499 -304.173834) (xy 431.35837 -304.169047)
			(xy 431.364898 -304.164746) (xy 431.385987 -304.150397) (xy 431.431648 -304.127666) (xy 431.480254 -304.112207)
			(xy 431.530657 -304.104384) (xy 431.581663 -304.104384) (xy 431.632066 -304.112207) (xy 431.680672 -304.127666)
			(xy 431.726333 -304.150397) (xy 431.747422 -304.164746) (xy 431.753953 -304.169039) (xy 431.768823 -304.173822)
			(xy 431.776632 -304.174144) (xy 432.29276 -304.174144) (xy 432.298007 -304.174716) (xy 432.305449 -304.182109)
			(xy 432.305968 -304.187352) (xy 432.305968 -304.18786) (xy 432.305968 -304.682144) (xy 434.250084 -304.682144)
			(xy 434.250084 -304.187606) (xy 434.250388 -304.182161) (xy 434.2581 -304.174472) (xy 434.263546 -304.174144)
			(xy 434.779674 -304.174144) (xy 434.787484 -304.173829) (xy 434.802356 -304.169045) (xy 434.808884 -304.164746)
			(xy 434.829973 -304.150397) (xy 434.875634 -304.127666) (xy 434.92424 -304.112207) (xy 434.974643 -304.104384)
			(xy 435.025649 -304.104384) (xy 435.076052 -304.112207) (xy 435.124658 -304.127666) (xy 435.170319 -304.150397)
			(xy 435.191408 -304.164746) (xy 435.197942 -304.169034) (xy 435.21281 -304.17382) (xy 435.220618 -304.174144)
			(xy 435.736746 -304.174144) (xy 435.742117 -304.174621) (xy 435.7497 -304.182233) (xy 435.750208 -304.187606)
			(xy 435.750208 -304.682144) (xy 438.350152 -304.682144) (xy 438.350152 -304.187606) (xy 438.350485 -304.182169)
			(xy 438.358176 -304.174481) (xy 438.363614 -304.174144) (xy 438.879742 -304.174144) (xy 438.887551 -304.173815)
			(xy 438.902423 -304.169041) (xy 438.908952 -304.164746) (xy 438.930041 -304.150397) (xy 438.975702 -304.127666)
			(xy 439.024308 -304.112207) (xy 439.074711 -304.104384) (xy 439.125717 -304.104384) (xy 439.17612 -304.112207)
			(xy 439.224726 -304.127666) (xy 439.270387 -304.150397) (xy 439.291476 -304.164746) (xy 439.298017 -304.169022)
			(xy 439.31288 -304.173815) (xy 439.320686 -304.174144) (xy 439.836814 -304.174144) (xy 439.842181 -304.174642)
			(xy 439.849766 -304.182238) (xy 439.850276 -304.187606) (xy 439.850276 -304.682144) (xy 441.794392 -304.682144)
			(xy 441.794392 -304.187606) (xy 441.794921 -304.182314) (xy 441.80232 -304.174745) (xy 441.8076 -304.174144)
			(xy 442.323728 -304.174144) (xy 442.33154 -304.173852) (xy 442.346412 -304.169052) (xy 442.352938 -304.164746)
			(xy 442.374027 -304.150397) (xy 442.419688 -304.127666) (xy 442.468294 -304.112207) (xy 442.518697 -304.104384)
			(xy 442.569703 -304.104384) (xy 442.620106 -304.112207) (xy 442.668712 -304.127666) (xy 442.714373 -304.150397)
			(xy 442.735462 -304.164746) (xy 442.742006 -304.169016) (xy 442.756866 -304.173813) (xy 442.764672 -304.174144)
			(xy 443.2808 -304.174144) (xy 443.286051 -304.17469) (xy 443.293491 -304.182103) (xy 443.294008 -304.187352)
			(xy 443.294008 -304.18786) (xy 443.294008 -304.682144) (xy 445.89446 -304.682144) (xy 445.89446 -304.187606)
			(xy 445.894929 -304.182298) (xy 445.902369 -304.174725) (xy 445.907668 -304.174144) (xy 446.423796 -304.174144)
			(xy 446.431607 -304.173838) (xy 446.446479 -304.169048) (xy 446.453006 -304.164746) (xy 446.474095 -304.150397)
			(xy 446.519756 -304.127666) (xy 446.568362 -304.112207) (xy 446.618765 -304.104384) (xy 446.669771 -304.104384)
			(xy 446.720174 -304.112207) (xy 446.76878 -304.127666) (xy 446.814441 -304.150397) (xy 446.83553 -304.164746)
			(xy 446.842059 -304.169042) (xy 446.856931 -304.173823) (xy 446.86474 -304.174144) (xy 447.380868 -304.174144)
			(xy 447.386116 -304.174711) (xy 447.393557 -304.182108) (xy 447.394076 -304.187352) (xy 447.394076 -304.18786)
			(xy 447.394076 -304.682144) (xy 449.338192 -304.682144) (xy 449.338192 -304.187606) (xy 449.338721 -304.182314)
			(xy 449.34612 -304.174745) (xy 449.3514 -304.174144) (xy 449.867528 -304.174144) (xy 449.87534 -304.173852)
			(xy 449.890212 -304.169052) (xy 449.896738 -304.164746) (xy 449.917827 -304.150397) (xy 449.963488 -304.127666)
			(xy 450.012094 -304.112207) (xy 450.062497 -304.104384) (xy 450.113503 -304.104384) (xy 450.163906 -304.112207)
			(xy 450.212512 -304.127666) (xy 450.258173 -304.150397) (xy 450.279262 -304.164746) (xy 450.285806 -304.169016)
			(xy 450.300666 -304.173813) (xy 450.308472 -304.174144) (xy 450.8246 -304.174144) (xy 450.829851 -304.17469)
			(xy 450.837291 -304.182103) (xy 450.837808 -304.187352) (xy 450.837808 -304.18786) (xy 450.837808 -304.682144)
			(xy 453.43826 -304.682144) (xy 453.43826 -304.187606) (xy 453.438729 -304.182298) (xy 453.446169 -304.174725)
			(xy 453.451468 -304.174144) (xy 453.967596 -304.174144) (xy 453.975407 -304.173838) (xy 453.990279 -304.169048)
			(xy 453.996806 -304.164746) (xy 454.017895 -304.150397) (xy 454.063556 -304.127666) (xy 454.112162 -304.112207)
			(xy 454.162565 -304.104384) (xy 454.213571 -304.104384) (xy 454.263974 -304.112207) (xy 454.31258 -304.127666)
			(xy 454.358241 -304.150397) (xy 454.37933 -304.164746) (xy 454.385859 -304.169042) (xy 454.400731 -304.173823)
			(xy 454.40854 -304.174144) (xy 454.924668 -304.174144) (xy 454.929916 -304.174711) (xy 454.937357 -304.182108)
			(xy 454.937876 -304.187352) (xy 454.937876 -304.18786) (xy 454.937876 -304.682144) (xy 454.937431 -304.68742)
			(xy 454.929947 -304.694862) (xy 454.924668 -304.695352) (xy 454.408794 -304.695352) (xy 454.40092 -304.695644)
			(xy 454.385916 -304.700425) (xy 454.37933 -304.70475) (xy 454.358263 -304.719157) (xy 454.312614 -304.741982)
			(xy 454.264005 -304.757535) (xy 454.213586 -304.765449) (xy 454.188068 -304.765964) (xy 454.162548 -304.765464)
			(xy 454.112121 -304.757574) (xy 454.06351 -304.742017) (xy 454.017871 -304.719164) (xy 453.996806 -304.70475)
			(xy 453.990212 -304.700439) (xy 453.975214 -304.695649) (xy 453.967342 -304.695352) (xy 453.451468 -304.695352)
			(xy 453.446212 -304.694831) (xy 453.438774 -304.6874) (xy 453.43826 -304.682144) (xy 450.837808 -304.682144)
			(xy 450.837334 -304.687412) (xy 450.82987 -304.694852) (xy 450.8246 -304.695352) (xy 450.308726 -304.695352)
			(xy 450.300849 -304.695615) (xy 450.285845 -304.700415) (xy 450.279262 -304.70475) (xy 450.258186 -304.719143)
			(xy 450.21254 -304.741971) (xy 450.163934 -304.757528) (xy 450.113517 -304.765447) (xy 450.088 -304.765964)
			(xy 450.062479 -304.765498) (xy 450.012051 -304.757597) (xy 449.963439 -304.742031) (xy 449.917802 -304.719169)
			(xy 449.896738 -304.70475) (xy 449.890137 -304.700452) (xy 449.875144 -304.695654) (xy 449.867274 -304.695352)
			(xy 449.3514 -304.695352) (xy 449.346148 -304.69481) (xy 449.338708 -304.687394) (xy 449.338192 -304.682144)
			(xy 447.394076 -304.682144) (xy 447.393631 -304.68742) (xy 447.386147 -304.694862) (xy 447.380868 -304.695352)
			(xy 446.864994 -304.695352) (xy 446.85712 -304.695644) (xy 446.842116 -304.700425) (xy 446.83553 -304.70475)
			(xy 446.814463 -304.719157) (xy 446.768814 -304.741982) (xy 446.720205 -304.757535) (xy 446.669786 -304.765449)
			(xy 446.644268 -304.765964) (xy 446.618748 -304.765464) (xy 446.568321 -304.757574) (xy 446.51971 -304.742017)
			(xy 446.474071 -304.719164) (xy 446.453006 -304.70475) (xy 446.446412 -304.700439) (xy 446.431414 -304.695649)
			(xy 446.423542 -304.695352) (xy 445.907668 -304.695352) (xy 445.902412 -304.694831) (xy 445.894974 -304.6874)
			(xy 445.89446 -304.682144) (xy 443.294008 -304.682144) (xy 443.293534 -304.687412) (xy 443.28607 -304.694852)
			(xy 443.2808 -304.695352) (xy 442.764926 -304.695352) (xy 442.757049 -304.695615) (xy 442.742045 -304.700415)
			(xy 442.735462 -304.70475) (xy 442.714386 -304.719143) (xy 442.66874 -304.741971) (xy 442.620134 -304.757528)
			(xy 442.569717 -304.765447) (xy 442.5442 -304.765964) (xy 442.518679 -304.765498) (xy 442.468251 -304.757597)
			(xy 442.419639 -304.742031) (xy 442.374002 -304.719169) (xy 442.352938 -304.70475) (xy 442.346337 -304.700452)
			(xy 442.331344 -304.695654) (xy 442.323474 -304.695352) (xy 441.8076 -304.695352) (xy 441.802348 -304.69481)
			(xy 441.794908 -304.687394) (xy 441.794392 -304.682144) (xy 439.850276 -304.682144) (xy 439.849831 -304.68742)
			(xy 439.842347 -304.694862) (xy 439.837068 -304.695352) (xy 439.83656 -304.695352) (xy 439.32094 -304.695352)
			(xy 439.313064 -304.695621) (xy 439.29806 -304.700417) (xy 439.291476 -304.70475) (xy 439.270396 -304.719137)
			(xy 439.224752 -304.741966) (xy 439.176147 -304.757525) (xy 439.12573 -304.765446) (xy 439.100214 -304.765964)
			(xy 439.074693 -304.765491) (xy 439.024265 -304.757592) (xy 438.975653 -304.742028) (xy 438.930016 -304.719168)
			(xy 438.908952 -304.70475) (xy 438.90237 -304.700418) (xy 438.887363 -304.695641) (xy 438.879488 -304.695352)
			(xy 438.363614 -304.695352) (xy 438.35831 -304.694867) (xy 438.350737 -304.687438) (xy 438.350152 -304.682144)
			(xy 435.750208 -304.682144) (xy 435.749734 -304.687412) (xy 435.74227 -304.694852) (xy 435.737 -304.695352)
			(xy 435.736492 -304.695352) (xy 435.220872 -304.695352) (xy 435.212997 -304.695635) (xy 435.197993 -304.700422)
			(xy 435.191408 -304.70475) (xy 435.170347 -304.719166) (xy 435.124696 -304.741989) (xy 435.076085 -304.75754)
			(xy 435.025664 -304.765451) (xy 435.000146 -304.765964) (xy 434.974626 -304.765475) (xy 434.924198 -304.757581)
			(xy 434.875587 -304.742021) (xy 434.829949 -304.719166) (xy 434.808884 -304.70475) (xy 434.802295 -304.700431)
			(xy 434.787293 -304.695646) (xy 434.77942 -304.695352) (xy 434.263546 -304.695352) (xy 434.258245 -304.694845)
			(xy 434.250671 -304.687433) (xy 434.250084 -304.682144) (xy 432.305968 -304.682144) (xy 432.30553 -304.687422)
			(xy 432.298041 -304.694864) (xy 432.29276 -304.695352) (xy 431.776886 -304.695352) (xy 431.769012 -304.695641)
			(xy 431.754008 -304.700424) (xy 431.747422 -304.70475) (xy 431.726357 -304.71916) (xy 431.680708 -304.741984)
			(xy 431.632098 -304.757537) (xy 431.581678 -304.76545) (xy 431.55616 -304.765964) (xy 431.53064 -304.765468)
			(xy 431.480213 -304.757576) (xy 431.431601 -304.742018) (xy 431.385963 -304.719165) (xy 431.364898 -304.70475)
			(xy 431.358306 -304.700436) (xy 431.343306 -304.695648) (xy 431.335434 -304.695352) (xy 430.81956 -304.695352)
			(xy 430.814303 -304.694836) (xy 430.806865 -304.687401) (xy 430.806352 -304.682144) (xy 428.2059 -304.682144)
			(xy 428.205434 -304.687414) (xy 428.197964 -304.694854) (xy 428.192692 -304.695352) (xy 427.676818 -304.695352)
			(xy 427.668945 -304.695655) (xy 427.653941 -304.700428) (xy 427.647354 -304.70475) (xy 427.62628 -304.719147)
			(xy 427.580634 -304.741974) (xy 427.532027 -304.75753) (xy 427.481609 -304.765448) (xy 427.456092 -304.765964)
			(xy 427.430573 -304.765452) (xy 427.380146 -304.757565) (xy 427.331534 -304.742012) (xy 427.285895 -304.719163)
			(xy 427.26483 -304.70475) (xy 427.258231 -304.700449) (xy 427.243237 -304.695653) (xy 427.235366 -304.695352)
			(xy 426.719492 -304.695352) (xy 426.714239 -304.694815) (xy 426.706799 -304.687396) (xy 426.706284 -304.682144)
			(xy 424.762168 -304.682144) (xy 424.76173 -304.687422) (xy 424.754241 -304.694864) (xy 424.74896 -304.695352)
			(xy 424.748452 -304.695352) (xy 424.232832 -304.695352) (xy 424.224955 -304.695618) (xy 424.209952 -304.700416)
			(xy 424.203368 -304.70475) (xy 424.18229 -304.719141) (xy 424.136645 -304.741969) (xy 424.08804 -304.757527)
			(xy 424.037623 -304.765447) (xy 424.012106 -304.765964) (xy 423.986585 -304.765495) (xy 423.936157 -304.757595)
			(xy 423.887545 -304.742029) (xy 423.841908 -304.719168) (xy 423.820844 -304.70475) (xy 423.814264 -304.700415)
			(xy 423.799255 -304.69564) (xy 423.79138 -304.695352) (xy 423.275506 -304.695352) (xy 423.270201 -304.694872)
			(xy 423.262629 -304.687439) (xy 423.262044 -304.682144) (xy 420.6621 -304.682144) (xy 420.661634 -304.687414)
			(xy 420.654164 -304.694854) (xy 420.648892 -304.695352) (xy 420.648384 -304.695352) (xy 420.132764 -304.695352)
			(xy 420.124889 -304.695632) (xy 420.109885 -304.700421) (xy 420.1033 -304.70475) (xy 420.082213 -304.719127)
			(xy 420.036572 -304.741959) (xy 419.987969 -304.75752) (xy 419.937554 -304.765444) (xy 419.912038 -304.765964)
			(xy 419.886518 -304.765479) (xy 419.83609 -304.757584) (xy 419.787478 -304.742023) (xy 419.74184 -304.719166)
			(xy 419.720776 -304.70475) (xy 419.714189 -304.700428) (xy 419.699186 -304.695645) (xy 419.691312 -304.695352)
			(xy 419.175438 -304.695352) (xy 419.170137 -304.69485) (xy 419.162563 -304.687434) (xy 419.161976 -304.682144)
			(xy 417.21786 -304.682144) (xy 417.217598 -304.687494) (xy 417.210004 -304.695035) (xy 417.204652 -304.695352)
			(xy 415.731452 -304.695352) (xy 415.726194 -304.694841) (xy 415.718757 -304.687402) (xy 415.718244 -304.682144)
			(xy 413.117792 -304.682144) (xy 413.117333 -304.687416) (xy 413.109858 -304.694857) (xy 413.104584 -304.695352)
			(xy 411.631384 -304.695352) (xy 411.62613 -304.694821) (xy 411.618691 -304.687397) (xy 411.618176 -304.682144)
			(xy 392.981696 -304.682144) (xy 392.983216 -304.708977) (xy 392.98372 -304.780188) (xy 392.983216 -304.851399)
			(xy 392.975159 -304.993591) (xy 392.95907 -305.135101) (xy 392.935 -305.275473) (xy 392.903028 -305.414259)
			(xy 392.868629 -305.532536) (xy 411.618176 -305.532536) (xy 411.618176 -305.532028) (xy 411.618176 -305.037744)
			(xy 411.618555 -305.032421) (xy 411.626063 -305.024879) (xy 411.631384 -305.024536) (xy 413.104584 -305.024536)
			(xy 413.109925 -305.024842) (xy 413.117469 -305.032402) (xy 413.117792 -305.037744) (xy 413.117792 -305.532282)
			(xy 419.161976 -305.532282) (xy 419.161976 -305.037744) (xy 419.162355 -305.032421) (xy 419.169863 -305.024879)
			(xy 419.175184 -305.024536) (xy 419.175692 -305.024536) (xy 419.691566 -305.024536) (xy 419.699376 -305.024219)
			(xy 419.714248 -305.019436) (xy 419.720776 -305.015138) (xy 419.741865 -305.000789) (xy 419.787526 -304.978058)
			(xy 419.836132 -304.962599) (xy 419.886535 -304.954776) (xy 419.937541 -304.954776) (xy 419.987944 -304.962599)
			(xy 420.03655 -304.978058) (xy 420.082211 -305.000789) (xy 420.1033 -305.015138) (xy 420.109836 -305.019422)
			(xy 420.124702 -305.024211) (xy 420.13251 -305.024536) (xy 420.648638 -305.024536) (xy 420.653946 -305.024998)
			(xy 420.661514 -305.032445) (xy 420.6621 -305.037744) (xy 420.6621 -305.532282) (xy 420.662074 -305.532536)
			(xy 426.706284 -305.532536) (xy 426.706284 -305.532028) (xy 426.706284 -305.037744) (xy 426.706656 -305.032419)
			(xy 426.714169 -305.024876) (xy 426.719492 -305.024536) (xy 427.23562 -305.024536) (xy 427.243432 -305.024242)
			(xy 427.258304 -305.019444) (xy 427.26483 -305.015138) (xy 427.285919 -305.000789) (xy 427.33158 -304.978058)
			(xy 427.380186 -304.962599) (xy 427.430589 -304.954776) (xy 427.481595 -304.954776) (xy 427.531998 -304.962599)
			(xy 427.580604 -304.978058) (xy 427.626265 -305.000789) (xy 427.647354 -305.015138) (xy 427.653878 -305.019443)
			(xy 427.668754 -305.024219) (xy 427.676564 -305.024536) (xy 428.192692 -305.024536) (xy 428.198034 -305.024836)
			(xy 428.205578 -305.032401) (xy 428.2059 -305.037744) (xy 428.2059 -305.532282) (xy 434.250084 -305.532282)
			(xy 434.250084 -305.037744) (xy 434.250456 -305.032419) (xy 434.257969 -305.024876) (xy 434.263292 -305.024536)
			(xy 434.2638 -305.024536) (xy 434.779674 -305.024536) (xy 434.787484 -305.024222) (xy 434.802356 -305.019437)
			(xy 434.808884 -305.015138) (xy 434.829973 -305.000789) (xy 434.875634 -304.978058) (xy 434.92424 -304.962599)
			(xy 434.974643 -304.954776) (xy 435.025649 -304.954776) (xy 435.076052 -304.962599) (xy 435.124658 -304.978058)
			(xy 435.170319 -305.000789) (xy 435.191408 -305.015138) (xy 435.197942 -305.019425) (xy 435.21281 -305.024212)
			(xy 435.220618 -305.024536) (xy 435.736746 -305.024536) (xy 435.742043 -305.025059) (xy 435.749617 -305.03246)
			(xy 435.750208 -305.037744) (xy 435.750208 -305.532282) (xy 435.750181 -305.532536) (xy 441.794392 -305.532536)
			(xy 441.794392 -305.532028) (xy 441.794392 -305.037744) (xy 441.794756 -305.032418) (xy 441.802275 -305.024874)
			(xy 441.8076 -305.024536) (xy 442.323728 -305.024536) (xy 442.33154 -305.024245) (xy 442.346412 -305.019445)
			(xy 442.352938 -305.015138) (xy 442.374027 -305.000789) (xy 442.419688 -304.978058) (xy 442.468294 -304.962599)
			(xy 442.518697 -304.954776) (xy 442.569703 -304.954776) (xy 442.620106 -304.962599) (xy 442.668712 -304.978058)
			(xy 442.714373 -305.000789) (xy 442.735462 -305.015138) (xy 442.742006 -305.019407) (xy 442.756866 -305.024205)
			(xy 442.764672 -305.024536) (xy 443.2808 -305.024536) (xy 443.286143 -305.024831) (xy 443.293687 -305.0324)
			(xy 443.294008 -305.037744) (xy 443.294008 -305.532282) (xy 443.293982 -305.532536) (xy 449.338192 -305.532536)
			(xy 449.338192 -305.532028) (xy 449.338192 -305.037744) (xy 449.338556 -305.032418) (xy 449.346075 -305.024874)
			(xy 449.3514 -305.024536) (xy 449.867528 -305.024536) (xy 449.87534 -305.024245) (xy 449.890212 -305.019445)
			(xy 449.896738 -305.015138) (xy 449.917827 -305.000789) (xy 449.963488 -304.978058) (xy 450.012094 -304.962599)
			(xy 450.062497 -304.954776) (xy 450.113503 -304.954776) (xy 450.163906 -304.962599) (xy 450.212512 -304.978058)
			(xy 450.258173 -305.000789) (xy 450.279262 -305.015138) (xy 450.285806 -305.019407) (xy 450.300666 -305.024205)
			(xy 450.308472 -305.024536) (xy 450.8246 -305.024536) (xy 450.829943 -305.024831) (xy 450.837487 -305.0324)
			(xy 450.837808 -305.037744) (xy 450.837808 -305.532282) (xy 450.837271 -305.537573) (xy 450.829878 -305.545142)
			(xy 450.8246 -305.545744) (xy 450.308726 -305.545744) (xy 450.300916 -305.546062) (xy 450.286044 -305.550844)
			(xy 450.279516 -305.555142) (xy 450.258387 -305.569479) (xy 450.212666 -305.592209) (xy 450.163995 -305.607642)
			(xy 450.11353 -305.615413) (xy 450.088 -305.615848) (xy 450.06247 -305.615414) (xy 450.012006 -305.607638)
			(xy 449.963333 -305.592208) (xy 449.917606 -305.56949) (xy 449.896484 -305.555142) (xy 449.889953 -305.55085)
			(xy 449.875083 -305.546067) (xy 449.867274 -305.545744) (xy 449.3514 -305.545744) (xy 449.346146 -305.545209)
			(xy 449.338706 -305.537789) (xy 449.338192 -305.532536) (xy 443.293982 -305.532536) (xy 443.293471 -305.537573)
			(xy 443.286078 -305.545142) (xy 443.2808 -305.545744) (xy 442.764926 -305.545744) (xy 442.757116 -305.546062)
			(xy 442.742244 -305.550844) (xy 442.735716 -305.555142) (xy 442.714587 -305.569479) (xy 442.668866 -305.592209)
			(xy 442.620195 -305.607642) (xy 442.56973 -305.615413) (xy 442.5442 -305.615848) (xy 442.51867 -305.615414)
			(xy 442.468206 -305.607638) (xy 442.419533 -305.592208) (xy 442.373806 -305.56949) (xy 442.352684 -305.555142)
			(xy 442.346153 -305.55085) (xy 442.331283 -305.546067) (xy 442.323474 -305.545744) (xy 441.8076 -305.545744)
			(xy 441.802346 -305.545209) (xy 441.794906 -305.537789) (xy 441.794392 -305.532536) (xy 435.750181 -305.532536)
			(xy 435.749642 -305.537633) (xy 435.742094 -305.545217) (xy 435.736746 -305.545744) (xy 435.220872 -305.545744)
			(xy 435.21306 -305.546038) (xy 435.198188 -305.550837) (xy 435.191662 -305.555142) (xy 435.170548 -305.569503)
			(xy 435.124821 -305.592227) (xy 435.076146 -305.607654) (xy 435.025678 -305.615417) (xy 435.000146 -305.615848)
			(xy 434.974616 -305.615391) (xy 434.924153 -305.607622) (xy 434.875481 -305.592199) (xy 434.829752 -305.569487)
			(xy 434.80863 -305.555142) (xy 434.802089 -305.550868) (xy 434.787226 -305.546074) (xy 434.77942 -305.545744)
			(xy 434.263546 -305.545744) (xy 434.258113 -305.545388) (xy 434.250423 -305.537714) (xy 434.250084 -305.532282)
			(xy 428.2059 -305.532282) (xy 428.20537 -305.537575) (xy 428.197972 -305.545145) (xy 428.192692 -305.545744)
			(xy 427.676818 -305.545744) (xy 427.669008 -305.546058) (xy 427.654136 -305.550843) (xy 427.647608 -305.555142)
			(xy 427.626481 -305.569483) (xy 427.580759 -305.592212) (xy 427.532088 -305.607644) (xy 427.481623 -305.615413)
			(xy 427.456092 -305.615848) (xy 427.430561 -305.615418) (xy 427.380097 -305.607641) (xy 427.331425 -305.59221)
			(xy 427.285698 -305.569491) (xy 427.264576 -305.555142) (xy 427.258047 -305.550847) (xy 427.243175 -305.546066)
			(xy 427.235366 -305.545744) (xy 426.719492 -305.545744) (xy 426.714237 -305.545214) (xy 426.706797 -305.53779)
			(xy 426.706284 -305.532536) (xy 420.662074 -305.532536) (xy 420.661542 -305.537635) (xy 420.653989 -305.545219)
			(xy 420.648638 -305.545744) (xy 420.132764 -305.545744) (xy 420.124956 -305.546078) (xy 420.110084 -305.550849)
			(xy 420.103554 -305.555142) (xy 420.082442 -305.569506) (xy 420.036715 -305.59223) (xy 419.988039 -305.607656)
			(xy 419.93757 -305.615418) (xy 419.912038 -305.615848) (xy 419.886508 -305.615395) (xy 419.836045 -305.607625)
			(xy 419.787372 -305.5922) (xy 419.741644 -305.569488) (xy 419.720522 -305.555142) (xy 419.713982 -305.550865)
			(xy 419.699119 -305.546072) (xy 419.691312 -305.545744) (xy 419.175438 -305.545744) (xy 419.170004 -305.545394)
			(xy 419.162314 -305.537716) (xy 419.161976 -305.532282) (xy 413.117792 -305.532282) (xy 413.117269 -305.537577)
			(xy 413.109866 -305.545147) (xy 413.104584 -305.545744) (xy 411.631384 -305.545744) (xy 411.626128 -305.54522)
			(xy 411.618688 -305.537791) (xy 411.618176 -305.532536) (xy 392.868629 -305.532536) (xy 392.863255 -305.551014)
			(xy 392.815809 -305.685299) (xy 392.760842 -305.816686) (xy 392.698529 -305.944752) (xy 392.629071 -306.069087)
			(xy 392.55269 -306.189294) (xy 392.469631 -306.304987) (xy 392.407108 -306.38242) (xy 415.718244 -306.38242)
			(xy 415.718244 -305.887628) (xy 415.718808 -305.88238) (xy 415.726207 -305.874939) (xy 415.731452 -305.87442)
			(xy 417.204652 -305.87442) (xy 417.209985 -305.874762) (xy 417.21753 -305.882296) (xy 417.21786 -305.887628)
			(xy 417.21786 -306.382166) (xy 423.262044 -306.382166) (xy 423.262044 -305.887628) (xy 423.262608 -305.88238)
			(xy 423.270007 -305.874939) (xy 423.275252 -305.87442) (xy 423.27576 -305.87442) (xy 423.791634 -305.87442)
			(xy 423.799443 -305.874092) (xy 423.814315 -305.869317) (xy 423.820844 -305.865022) (xy 423.841933 -305.850673)
			(xy 423.887594 -305.827942) (xy 423.9362 -305.812483) (xy 423.986603 -305.80466) (xy 424.037609 -305.80466)
			(xy 424.088012 -305.812483) (xy 424.136618 -305.827942) (xy 424.182279 -305.850673) (xy 424.203368 -305.865022)
			(xy 424.209912 -305.869292) (xy 424.224772 -305.87409) (xy 424.232578 -305.87442) (xy 424.748706 -305.87442)
			(xy 424.754006 -305.874917) (xy 424.761576 -305.882338) (xy 424.762168 -305.887628) (xy 424.762168 -306.382166)
			(xy 424.762151 -306.38242) (xy 430.806352 -306.38242) (xy 430.806352 -306.381912) (xy 430.806352 -305.887628)
			(xy 430.806909 -305.882378) (xy 430.814313 -305.874936) (xy 430.81956 -305.87442) (xy 431.335688 -305.87442)
			(xy 431.343499 -305.874115) (xy 431.358371 -305.869324) (xy 431.364898 -305.865022) (xy 431.385987 -305.850673)
			(xy 431.431648 -305.827942) (xy 431.480254 -305.812483) (xy 431.530657 -305.80466) (xy 431.581663 -305.80466)
			(xy 431.632066 -305.812483) (xy 431.680672 -305.827942) (xy 431.726333 -305.850673) (xy 431.747422 -305.865022)
			(xy 431.753954 -305.869313) (xy 431.768823 -305.874098) (xy 431.776632 -305.87442) (xy 432.29276 -305.87442)
			(xy 432.298094 -305.874757) (xy 432.305639 -305.882295) (xy 432.305968 -305.887628) (xy 432.305968 -306.382166)
			(xy 438.350152 -306.382166) (xy 438.350152 -305.887628) (xy 438.350709 -305.882378) (xy 438.358113 -305.874936)
			(xy 438.36336 -305.87442) (xy 438.363868 -305.87442) (xy 438.879742 -305.87442) (xy 438.887551 -305.874095)
			(xy 438.902423 -305.869318) (xy 438.908952 -305.865022) (xy 438.930041 -305.850673) (xy 438.975702 -305.827942)
			(xy 439.024308 -305.812483) (xy 439.074711 -305.80466) (xy 439.125717 -305.80466) (xy 439.17612 -305.812483)
			(xy 439.224726 -305.827942) (xy 439.270387 -305.850673) (xy 439.291476 -305.865022) (xy 439.298018 -305.869295)
			(xy 439.31288 -305.874091) (xy 439.320686 -305.87442) (xy 439.836814 -305.87442) (xy 439.842115 -305.874912)
			(xy 439.849684 -305.882337) (xy 439.850276 -305.887628) (xy 439.850276 -306.382166) (xy 439.850258 -306.38242)
			(xy 445.89446 -306.38242) (xy 445.89446 -306.381912) (xy 445.89446 -305.887628) (xy 445.89501 -305.882376)
			(xy 445.902419 -305.874934) (xy 445.907668 -305.87442) (xy 446.423796 -305.87442) (xy 446.431607 -305.874118)
			(xy 446.446479 -305.869325) (xy 446.453006 -305.865022) (xy 446.474095 -305.850673) (xy 446.519756 -305.827942)
			(xy 446.568362 -305.812483) (xy 446.618765 -305.80466) (xy 446.669771 -305.80466) (xy 446.720174 -305.812483)
			(xy 446.76878 -305.827942) (xy 446.814441 -305.850673) (xy 446.83553 -305.865022) (xy 446.84206 -305.869316)
			(xy 446.856931 -305.874099) (xy 446.86474 -305.87442) (xy 447.380868 -305.87442) (xy 447.386203 -305.874751)
			(xy 447.393747 -305.882293) (xy 447.394076 -305.887628) (xy 447.394076 -306.382166) (xy 447.394051 -306.38242)
			(xy 453.43826 -306.38242) (xy 453.43826 -306.381912) (xy 453.43826 -305.887628) (xy 453.43881 -305.882376)
			(xy 453.446219 -305.874934) (xy 453.451468 -305.87442) (xy 453.967596 -305.87442) (xy 453.975407 -305.874118)
			(xy 453.990279 -305.869325) (xy 453.996806 -305.865022) (xy 454.017895 -305.850673) (xy 454.063556 -305.827942)
			(xy 454.112162 -305.812483) (xy 454.162565 -305.80466) (xy 454.213571 -305.80466) (xy 454.263974 -305.812483)
			(xy 454.31258 -305.827942) (xy 454.358241 -305.850673) (xy 454.37933 -305.865022) (xy 454.38586 -305.869316)
			(xy 454.400731 -305.874099) (xy 454.40854 -305.87442) (xy 454.924668 -305.87442) (xy 454.930003 -305.874751)
			(xy 454.937547 -305.882293) (xy 454.937876 -305.887628) (xy 454.937876 -306.382166) (xy 454.937356 -306.387462)
			(xy 454.929952 -306.395035) (xy 454.924668 -306.395628) (xy 454.408794 -306.395628) (xy 454.400983 -306.395934)
			(xy 454.386112 -306.400725) (xy 454.379584 -306.405026) (xy 454.358462 -306.419375) (xy 454.312739 -306.442103)
			(xy 454.264065 -306.457533) (xy 454.213599 -306.465299) (xy 454.188068 -306.465732) (xy 454.162537 -306.465317)
			(xy 454.112072 -306.457536) (xy 454.063399 -306.4421) (xy 454.017673 -306.419377) (xy 453.996552 -306.405026)
			(xy 453.990029 -306.40072) (xy 453.975152 -306.395946) (xy 453.967342 -306.395628) (xy 453.451468 -306.395628)
			(xy 453.446206 -306.395129) (xy 453.438767 -306.387682) (xy 453.43826 -306.38242) (xy 447.394051 -306.38242)
			(xy 447.393556 -306.387462) (xy 447.386152 -306.395035) (xy 447.380868 -306.395628) (xy 446.864994 -306.395628)
			(xy 446.857183 -306.395934) (xy 446.842312 -306.400725) (xy 446.835784 -306.405026) (xy 446.814662 -306.419375)
			(xy 446.768939 -306.442103) (xy 446.720265 -306.457533) (xy 446.669799 -306.465299) (xy 446.644268 -306.465732)
			(xy 446.618737 -306.465317) (xy 446.568272 -306.457536) (xy 446.519599 -306.4421) (xy 446.473873 -306.419377)
			(xy 446.452752 -306.405026) (xy 446.446229 -306.40072) (xy 446.431352 -306.395946) (xy 446.423542 -306.395628)
			(xy 445.907668 -306.395628) (xy 445.902406 -306.395129) (xy 445.894967 -306.387682) (xy 445.89446 -306.38242)
			(xy 439.850258 -306.38242) (xy 439.849899 -306.387593) (xy 439.84224 -306.39528) (xy 439.836814 -306.395628)
			(xy 439.32094 -306.395628) (xy 439.313131 -306.395954) (xy 439.298259 -306.400731) (xy 439.29173 -306.405026)
			(xy 439.270623 -306.419399) (xy 439.224894 -306.442121) (xy 439.176216 -306.457545) (xy 439.125746 -306.465303)
			(xy 439.100214 -306.465732) (xy 439.074684 -306.465294) (xy 439.02422 -306.45752) (xy 438.975547 -306.442091)
			(xy 438.92982 -306.419374) (xy 438.908698 -306.405026) (xy 438.902165 -306.400738) (xy 438.887296 -306.395953)
			(xy 438.879488 -306.395628) (xy 438.363614 -306.395628) (xy 438.358173 -306.395308) (xy 438.350484 -306.387608)
			(xy 438.350152 -306.382166) (xy 432.305968 -306.382166) (xy 432.305455 -306.387464) (xy 432.298047 -306.395037)
			(xy 432.29276 -306.395628) (xy 431.776886 -306.395628) (xy 431.769075 -306.395931) (xy 431.754203 -306.400724)
			(xy 431.747676 -306.405026) (xy 431.726557 -306.419379) (xy 431.680832 -306.442105) (xy 431.632158 -306.457535)
			(xy 431.581691 -306.4653) (xy 431.55616 -306.465732) (xy 431.530629 -306.465321) (xy 431.480164 -306.457539)
			(xy 431.431491 -306.442102) (xy 431.385765 -306.419377) (xy 431.364644 -306.405026) (xy 431.358123 -306.400717)
			(xy 431.343245 -306.395945) (xy 431.335434 -306.395628) (xy 430.81956 -306.395628) (xy 430.814297 -306.395134)
			(xy 430.806858 -306.387684) (xy 430.806352 -306.38242) (xy 424.762151 -306.38242) (xy 424.761799 -306.387595)
			(xy 424.754134 -306.395282) (xy 424.748706 -306.395628) (xy 424.232832 -306.395628) (xy 424.225023 -306.395951)
			(xy 424.210151 -306.40073) (xy 424.203622 -306.405026) (xy 424.18249 -306.419359) (xy 424.13677 -306.44209)
			(xy 424.0881 -306.457525) (xy 424.037636 -306.465296) (xy 424.012106 -306.465732) (xy 423.986576 -306.465298)
			(xy 423.936111 -306.457523) (xy 423.887439 -306.442093) (xy 423.841712 -306.419375) (xy 423.82059 -306.405026)
			(xy 423.814058 -306.400735) (xy 423.799188 -306.395952) (xy 423.79138 -306.395628) (xy 423.275506 -306.395628)
			(xy 423.270064 -306.395313) (xy 423.262375 -306.387609) (xy 423.262044 -306.382166) (xy 417.21786 -306.382166)
			(xy 417.217354 -306.387466) (xy 417.209941 -306.395039) (xy 417.204652 -306.395628) (xy 415.731452 -306.395628)
			(xy 415.726188 -306.395139) (xy 415.71875 -306.387685) (xy 415.718244 -306.38242) (xy 392.407108 -306.38242)
			(xy 392.380159 -306.415796) (xy 392.284562 -306.521365) (xy 392.183145 -306.621357) (xy 392.076233 -306.715451)
			(xy 391.964169 -306.803345) (xy 391.847313 -306.884759) (xy 391.726037 -306.959432) (xy 391.600731 -307.027123)
			(xy 391.471796 -307.087617) (xy 391.339645 -307.14072) (xy 391.204702 -307.186261) (xy 391.067398 -307.224095)
			(xy 391.029308 -307.232304) (xy 411.618176 -307.232304) (xy 411.618176 -306.737766) (xy 411.618605 -306.732449)
			(xy 411.626075 -306.724878) (xy 411.631384 -306.724304) (xy 413.104584 -306.724304) (xy 413.109917 -306.724639)
			(xy 413.11746 -306.732179) (xy 413.117792 -306.737512) (xy 413.117792 -306.73802) (xy 413.117792 -307.232304)
			(xy 419.161976 -307.232304) (xy 419.161976 -306.737766) (xy 419.16226 -306.732317) (xy 419.169988 -306.724631)
			(xy 419.175438 -306.724304) (xy 419.691566 -306.724304) (xy 419.699375 -306.723975) (xy 419.714246 -306.7192)
			(xy 419.720776 -306.714906) (xy 419.741865 -306.700557) (xy 419.787526 -306.677826) (xy 419.836132 -306.662367)
			(xy 419.886535 -306.654544) (xy 419.937541 -306.654544) (xy 419.987944 -306.662367) (xy 420.03655 -306.677826)
			(xy 420.082211 -306.700557) (xy 420.1033 -306.714906) (xy 420.109832 -306.719197) (xy 420.124702 -306.72398)
			(xy 420.13251 -306.724304) (xy 420.648638 -306.724304) (xy 420.653998 -306.724822) (xy 420.66158 -306.732406)
			(xy 420.6621 -306.737766) (xy 420.6621 -307.232304) (xy 426.706284 -307.232304) (xy 426.706284 -306.737766)
			(xy 426.706706 -306.732447) (xy 426.71418 -306.724876) (xy 426.719492 -306.724304) (xy 427.23562 -306.724304)
			(xy 427.243431 -306.723998) (xy 427.258302 -306.719207) (xy 427.26483 -306.714906) (xy 427.285919 -306.700557)
			(xy 427.33158 -306.677826) (xy 427.380186 -306.662367) (xy 427.430589 -306.654544) (xy 427.481595 -306.654544)
			(xy 427.531998 -306.662367) (xy 427.580604 -306.677826) (xy 427.626265 -306.700557) (xy 427.647354 -306.714906)
			(xy 427.653874 -306.719217) (xy 427.668753 -306.723988) (xy 427.676564 -306.724304) (xy 428.192692 -306.724304)
			(xy 428.198026 -306.724633) (xy 428.205568 -306.732178) (xy 428.2059 -306.737512) (xy 428.2059 -306.73802)
			(xy 428.2059 -307.232304) (xy 434.250084 -307.232304) (xy 434.250084 -306.737766) (xy 434.250361 -306.732315)
			(xy 434.258094 -306.724629) (xy 434.263546 -306.724304) (xy 434.779674 -306.724304) (xy 434.787483 -306.723979)
			(xy 434.802354 -306.719201) (xy 434.808884 -306.714906) (xy 434.829973 -306.700557) (xy 434.875634 -306.677826)
			(xy 434.92424 -306.662367) (xy 434.974643 -306.654544) (xy 435.025649 -306.654544) (xy 435.076052 -306.662367)
			(xy 435.124658 -306.677826) (xy 435.170319 -306.700557) (xy 435.191408 -306.714906) (xy 435.197938 -306.7192)
			(xy 435.212809 -306.723981) (xy 435.220618 -306.724304) (xy 435.736746 -306.724304) (xy 435.742107 -306.724816)
			(xy 435.749688 -306.732404) (xy 435.750208 -306.737766) (xy 435.750208 -307.232304) (xy 441.794392 -307.232304)
			(xy 441.794392 -306.737766) (xy 441.794895 -306.732469) (xy 441.802314 -306.724903) (xy 441.8076 -306.724304)
			(xy 442.323728 -306.724304) (xy 442.331539 -306.724001) (xy 442.34641 -306.719208) (xy 442.352938 -306.714906)
			(xy 442.374027 -306.700557) (xy 442.419688 -306.677826) (xy 442.468294 -306.662367) (xy 442.518697 -306.654544)
			(xy 442.569703 -306.654544) (xy 442.620106 -306.662367) (xy 442.668712 -306.677826) (xy 442.714373 -306.700557)
			(xy 442.735462 -306.714906) (xy 442.742002 -306.719182) (xy 442.756866 -306.723974) (xy 442.764672 -306.724304)
			(xy 443.2808 -306.724304) (xy 443.286135 -306.724628) (xy 443.293677 -306.732176) (xy 443.294008 -306.737512)
			(xy 443.294008 -306.73802) (xy 443.294008 -307.232304) (xy 449.338192 -307.232304) (xy 449.338192 -306.737766)
			(xy 449.338695 -306.732469) (xy 449.346114 -306.724903) (xy 449.3514 -306.724304) (xy 449.867528 -306.724304)
			(xy 449.875339 -306.724001) (xy 449.89021 -306.719208) (xy 449.896738 -306.714906) (xy 449.917827 -306.700557)
			(xy 449.963488 -306.677826) (xy 450.012094 -306.662367) (xy 450.062497 -306.654544) (xy 450.113503 -306.654544)
			(xy 450.163906 -306.662367) (xy 450.212512 -306.677826) (xy 450.258173 -306.700557) (xy 450.279262 -306.714906)
			(xy 450.285802 -306.719182) (xy 450.300666 -306.723974) (xy 450.308472 -306.724304) (xy 450.8246 -306.724304)
			(xy 450.829935 -306.724628) (xy 450.837477 -306.732176) (xy 450.837808 -306.737512) (xy 450.837808 -306.73802)
			(xy 450.837808 -307.232304) (xy 450.837308 -307.237567) (xy 450.829863 -307.24501) (xy 450.8246 -307.245512)
			(xy 450.308726 -307.245512) (xy 450.30085 -307.245782) (xy 450.285846 -307.250578) (xy 450.279262 -307.25491)
			(xy 450.258182 -307.269298) (xy 450.212539 -307.292129) (xy 450.163933 -307.307688) (xy 450.113517 -307.315607)
			(xy 450.088 -307.316124) (xy 450.062479 -307.315647) (xy 450.012052 -307.307748) (xy 449.963441 -307.292184)
			(xy 449.917803 -307.269326) (xy 449.896738 -307.25491) (xy 449.890139 -307.250608) (xy 449.875145 -307.245813)
			(xy 449.867274 -307.245512) (xy 449.3514 -307.245512) (xy 449.346138 -307.245006) (xy 449.338696 -307.237566)
			(xy 449.338192 -307.232304) (xy 443.294008 -307.232304) (xy 443.293508 -307.237567) (xy 443.286063 -307.24501)
			(xy 443.2808 -307.245512) (xy 442.764926 -307.245512) (xy 442.75705 -307.245782) (xy 442.742046 -307.250578)
			(xy 442.735462 -307.25491) (xy 442.714382 -307.269298) (xy 442.668739 -307.292129) (xy 442.620133 -307.307688)
			(xy 442.569717 -307.315607) (xy 442.5442 -307.316124) (xy 442.518679 -307.315647) (xy 442.468252 -307.307748)
			(xy 442.419641 -307.292184) (xy 442.374003 -307.269326) (xy 442.352938 -307.25491) (xy 442.346339 -307.250608)
			(xy 442.331345 -307.245813) (xy 442.323474 -307.245512) (xy 441.8076 -307.245512) (xy 441.802338 -307.245006)
			(xy 441.794896 -307.237566) (xy 441.794392 -307.232304) (xy 435.750208 -307.232304) (xy 435.749708 -307.237567)
			(xy 435.742263 -307.24501) (xy 435.737 -307.245512) (xy 435.736492 -307.245512) (xy 435.220872 -307.245512)
			(xy 435.212998 -307.245801) (xy 435.197994 -307.250585) (xy 435.191408 -307.25491) (xy 435.170344 -307.269322)
			(xy 435.124694 -307.292147) (xy 435.076084 -307.307699) (xy 435.025664 -307.315611) (xy 435.000146 -307.316124)
			(xy 434.974626 -307.315624) (xy 434.9242 -307.307732) (xy 434.875588 -307.292175) (xy 434.82995 -307.269323)
			(xy 434.808884 -307.25491) (xy 434.802297 -307.250587) (xy 434.787294 -307.245805) (xy 434.77942 -307.245512)
			(xy 434.263546 -307.245512) (xy 434.258236 -307.24504) (xy 434.25066 -307.237604) (xy 434.250084 -307.232304)
			(xy 428.2059 -307.232304) (xy 428.205575 -307.237639) (xy 428.198027 -307.24518) (xy 428.192692 -307.245512)
			(xy 427.676818 -307.245512) (xy 427.668945 -307.245822) (xy 427.653942 -307.250591) (xy 427.647354 -307.25491)
			(xy 427.626277 -307.269302) (xy 427.580632 -307.292131) (xy 427.532026 -307.307689) (xy 427.481609 -307.315608)
			(xy 427.456092 -307.316124) (xy 427.430573 -307.315601) (xy 427.380148 -307.307716) (xy 427.331536 -307.292165)
			(xy 427.285896 -307.26932) (xy 427.26483 -307.25491) (xy 427.258233 -307.250605) (xy 427.243237 -307.245812)
			(xy 427.235366 -307.245512) (xy 426.719492 -307.245512) (xy 426.714229 -307.245011) (xy 426.706787 -307.237567)
			(xy 426.706284 -307.232304) (xy 420.6621 -307.232304) (xy 420.661775 -307.237639) (xy 420.654227 -307.24518)
			(xy 420.648892 -307.245512) (xy 420.648384 -307.245512) (xy 420.132764 -307.245512) (xy 420.124889 -307.245798)
			(xy 420.109886 -307.250583) (xy 420.1033 -307.25491) (xy 420.08221 -307.269282) (xy 420.03657 -307.292116)
			(xy 419.987968 -307.307679) (xy 419.937554 -307.315604) (xy 419.912038 -307.316124) (xy 419.886518 -307.315628)
			(xy 419.836092 -307.307735) (xy 419.78748 -307.292176) (xy 419.741841 -307.269324) (xy 419.720776 -307.25491)
			(xy 419.714191 -307.250584) (xy 419.699186 -307.245804) (xy 419.691312 -307.245512) (xy 419.175438 -307.245512)
			(xy 419.170127 -307.245046) (xy 419.162551 -307.237605) (xy 419.161976 -307.232304) (xy 413.117792 -307.232304)
			(xy 413.117474 -307.237641) (xy 413.109921 -307.245182) (xy 413.104584 -307.245512) (xy 411.631384 -307.245512)
			(xy 411.62612 -307.245017) (xy 411.618679 -307.237568) (xy 411.618176 -307.232304) (xy 391.029308 -307.232304)
			(xy 390.928173 -307.2541) (xy 390.787474 -307.27618) (xy 390.645752 -307.290266) (xy 390.503459 -307.29631)
			(xy 390.361052 -307.294295) (xy 390.218987 -307.284226) (xy 390.07772 -307.266136) (xy 389.937702 -307.240083)
			(xy 389.799383 -307.20615) (xy 389.663204 -307.164445) (xy 389.529604 -307.115104) (xy 389.399008 -307.058283)
			(xy 389.271837 -306.994164) (xy 389.148497 -306.922954) (xy 389.029383 -306.844879) (xy 388.914877 -306.760191)
			(xy 388.805345 -306.66916) (xy 388.701139 -306.572079) (xy 388.602593 -306.469257) (xy 388.510021 -306.361024)
			(xy 388.423721 -306.247728) (xy 388.343969 -306.129731) (xy 388.27102 -306.007411) (xy 388.205108 -305.88116)
			(xy 388.146445 -305.751381) (xy 388.095218 -305.618492) (xy 388.051591 -305.482918) (xy 388.015704 -305.345092)
			(xy 387.987672 -305.205457) (xy 387.967584 -305.06446) (xy 387.955506 -304.922552) (xy 387.951476 -304.780188)
			(xy 334.545164 -304.780188) (xy 334.535027 -304.814711) (xy 334.51237 -304.864321) (xy 334.482884 -304.910202)
			(xy 334.447169 -304.951419) (xy 334.405952 -304.987134) (xy 334.360071 -305.01662) (xy 334.310461 -305.039277)
			(xy 334.258131 -305.054642) (xy 334.204147 -305.062404) (xy 334.149609 -305.062404) (xy 334.095625 -305.054642)
			(xy 334.043295 -305.039277) (xy 333.993685 -305.01662) (xy 333.947804 -304.987134) (xy 333.906587 -304.951419)
			(xy 333.870872 -304.910202) (xy 333.841386 -304.864321) (xy 333.818729 -304.814711) (xy 333.803364 -304.762381)
			(xy 333.795602 -304.708397) (xy 333.795116 -304.681128) (xy 331.781862 -304.681128) (xy 331.78344 -304.708977)
			(xy 331.783944 -304.780188) (xy 331.78344 -304.851399) (xy 331.775383 -304.993591) (xy 331.759294 -305.135101)
			(xy 331.735224 -305.275473) (xy 331.703252 -305.414259) (xy 331.663479 -305.551014) (xy 331.616033 -305.685299)
			(xy 331.561066 -305.816686) (xy 331.498753 -305.944752) (xy 331.429295 -306.069087) (xy 331.352914 -306.189294)
			(xy 331.269855 -306.304987) (xy 331.180383 -306.415796) (xy 331.164835 -306.432966) (xy 340.495636 -306.432966)
			(xy 340.495636 -305.569366) (xy 340.496122 -305.542115) (xy 340.503878 -305.488167) (xy 340.519233 -305.435872)
			(xy 340.541875 -305.386295) (xy 340.571341 -305.340445) (xy 340.607032 -305.299254) (xy 340.648223 -305.263563)
			(xy 340.694073 -305.234097) (xy 340.74365 -305.211455) (xy 340.795945 -305.1961) (xy 340.849893 -305.188344)
			(xy 340.904395 -305.188344) (xy 340.958343 -305.1961) (xy 341.010638 -305.211455) (xy 341.060215 -305.234097)
			(xy 341.106065 -305.263563) (xy 341.147256 -305.299254) (xy 341.182947 -305.340445) (xy 341.212413 -305.386295)
			(xy 341.235055 -305.435872) (xy 341.25041 -305.488167) (xy 341.258166 -305.542115) (xy 341.258652 -305.569366)
			(xy 341.258652 -306.432966) (xy 341.258166 -306.460217) (xy 341.25041 -306.514165) (xy 341.235055 -306.56646)
			(xy 341.212413 -306.616037) (xy 341.182947 -306.661887) (xy 341.147256 -306.703078) (xy 341.106065 -306.738769)
			(xy 341.060215 -306.768235) (xy 341.010638 -306.790877) (xy 340.958343 -306.806232) (xy 340.904395 -306.813988)
			(xy 340.849893 -306.813988) (xy 340.795945 -306.806232) (xy 340.74365 -306.790877) (xy 340.694073 -306.768235)
			(xy 340.648223 -306.738769) (xy 340.607032 -306.703078) (xy 340.571341 -306.661887) (xy 340.541875 -306.616037)
			(xy 340.519233 -306.56646) (xy 340.503878 -306.514165) (xy 340.496122 -306.460217) (xy 340.495636 -306.432966)
			(xy 331.164835 -306.432966) (xy 331.084786 -306.521365) (xy 330.983369 -306.621357) (xy 330.876457 -306.715451)
			(xy 330.764393 -306.803345) (xy 330.647537 -306.884759) (xy 330.526261 -306.959432) (xy 330.400955 -307.027123)
			(xy 330.27202 -307.087617) (xy 330.139869 -307.14072) (xy 330.004926 -307.186261) (xy 329.867622 -307.224095)
			(xy 329.728397 -307.2541) (xy 329.587698 -307.27618) (xy 329.445976 -307.290266) (xy 329.303683 -307.29631)
			(xy 329.161276 -307.294295) (xy 329.019211 -307.284226) (xy 328.877944 -307.266136) (xy 328.737926 -307.240083)
			(xy 328.599607 -307.20615) (xy 328.463428 -307.164445) (xy 328.329828 -307.115104) (xy 328.199232 -307.058283)
			(xy 328.072061 -306.994164) (xy 327.948721 -306.922954) (xy 327.829607 -306.844879) (xy 327.715101 -306.760191)
			(xy 327.605569 -306.66916) (xy 327.501363 -306.572079) (xy 327.402817 -306.469257) (xy 327.310245 -306.361024)
			(xy 327.223945 -306.247728) (xy 327.144193 -306.129731) (xy 327.071244 -306.007411) (xy 327.005332 -305.88116)
			(xy 326.946669 -305.751381) (xy 326.895442 -305.618492) (xy 326.851815 -305.482918) (xy 326.815928 -305.345092)
			(xy 326.787896 -305.205457) (xy 326.767808 -305.06446) (xy 326.75573 -304.922552) (xy 326.7517 -304.780188)
			(xy 145.04365 -304.780188) (xy 145.043652 -304.780442) (xy 145.043148 -304.851653) (xy 145.035091 -304.993845)
			(xy 145.019002 -305.135355) (xy 144.994932 -305.275727) (xy 144.96296 -305.414513) (xy 144.928635 -305.532536)
			(xy 163.678108 -305.532536) (xy 163.678108 -305.037998) (xy 163.678618 -305.032701) (xy 163.68603 -305.025132)
			(xy 163.691316 -305.024536) (xy 165.164516 -305.024536) (xy 165.169861 -305.02482) (xy 165.177404 -305.032397)
			(xy 165.177724 -305.037744) (xy 165.177724 -305.038252) (xy 165.177724 -305.532536) (xy 171.221908 -305.532536)
			(xy 171.221908 -305.037998) (xy 171.222446 -305.032641) (xy 171.230014 -305.025057) (xy 171.23537 -305.024536)
			(xy 171.751498 -305.024536) (xy 171.759309 -305.024232) (xy 171.774181 -305.01944) (xy 171.780708 -305.015138)
			(xy 171.801797 -305.000789) (xy 171.847458 -304.978058) (xy 171.896064 -304.962599) (xy 171.946467 -304.954776)
			(xy 171.997473 -304.954776) (xy 172.047876 -304.962599) (xy 172.096482 -304.978058) (xy 172.142143 -305.000789)
			(xy 172.163232 -305.015138) (xy 172.169761 -305.019434) (xy 172.184633 -305.024215) (xy 172.192442 -305.024536)
			(xy 172.70857 -305.024536) (xy 172.714 -305.024899) (xy 172.721688 -305.032569) (xy 172.722032 -305.037998)
			(xy 172.722032 -305.532536) (xy 178.766216 -305.532536) (xy 178.766216 -305.037998) (xy 178.766719 -305.032699)
			(xy 178.774136 -305.02513) (xy 178.779424 -305.024536) (xy 179.295552 -305.024536) (xy 179.303361 -305.024213)
			(xy 179.318233 -305.019434) (xy 179.324762 -305.015138) (xy 179.345851 -305.000789) (xy 179.391512 -304.978058)
			(xy 179.440118 -304.962599) (xy 179.490521 -304.954776) (xy 179.541527 -304.954776) (xy 179.59193 -304.962599)
			(xy 179.640536 -304.978058) (xy 179.686197 -305.000789) (xy 179.707286 -305.015138) (xy 179.713825 -305.019417)
			(xy 179.728689 -305.024209) (xy 179.736496 -305.024536) (xy 180.252624 -305.024536) (xy 180.25797 -305.024815)
			(xy 180.265512 -305.032396) (xy 180.265832 -305.037744) (xy 180.265832 -305.038252) (xy 180.265832 -305.532536)
			(xy 186.310016 -305.532536) (xy 186.310016 -305.037998) (xy 186.310547 -305.032639) (xy 186.31812 -305.025055)
			(xy 186.323478 -305.024536) (xy 186.839606 -305.024536) (xy 186.847417 -305.024235) (xy 186.862289 -305.019441)
			(xy 186.868816 -305.015138) (xy 186.889905 -305.000789) (xy 186.935566 -304.978058) (xy 186.984172 -304.962599)
			(xy 187.034575 -304.954776) (xy 187.085581 -304.954776) (xy 187.135984 -304.962599) (xy 187.18459 -304.978058)
			(xy 187.230251 -305.000789) (xy 187.25134 -305.015138) (xy 187.257867 -305.019437) (xy 187.27274 -305.024216)
			(xy 187.28055 -305.024536) (xy 187.796678 -305.024536) (xy 187.802109 -305.024894) (xy 187.809796 -305.032567)
			(xy 187.81014 -305.037998) (xy 187.81014 -305.532536) (xy 193.854324 -305.532536) (xy 193.854324 -305.037998)
			(xy 193.85482 -305.032697) (xy 193.862242 -305.025127) (xy 193.867532 -305.024536) (xy 194.38366 -305.024536)
			(xy 194.39147 -305.024216) (xy 194.406342 -305.019435) (xy 194.41287 -305.015138) (xy 194.433959 -305.000789)
			(xy 194.47962 -304.978058) (xy 194.528226 -304.962599) (xy 194.578629 -304.954776) (xy 194.629635 -304.954776)
			(xy 194.680038 -304.962599) (xy 194.728644 -304.978058) (xy 194.774305 -305.000789) (xy 194.795394 -305.015138)
			(xy 194.801931 -305.01942) (xy 194.816797 -305.02421) (xy 194.824604 -305.024536) (xy 195.340732 -305.024536)
			(xy 195.346079 -305.02481) (xy 195.353621 -305.032395) (xy 195.35394 -305.037744) (xy 195.35394 -305.038252)
			(xy 195.35394 -305.532536) (xy 201.398124 -305.532536) (xy 201.398124 -305.037998) (xy 201.39862 -305.032697)
			(xy 201.406042 -305.025127) (xy 201.411332 -305.024536) (xy 201.92746 -305.024536) (xy 201.93527 -305.024216)
			(xy 201.950142 -305.019435) (xy 201.95667 -305.015138) (xy 201.977759 -305.000789) (xy 202.02342 -304.978058)
			(xy 202.072026 -304.962599) (xy 202.122429 -304.954776) (xy 202.173435 -304.954776) (xy 202.223838 -304.962599)
			(xy 202.272444 -304.978058) (xy 202.318105 -305.000789) (xy 202.339194 -305.015138) (xy 202.345731 -305.01942)
			(xy 202.360597 -305.02421) (xy 202.368404 -305.024536) (xy 202.884532 -305.024536) (xy 202.889879 -305.02481)
			(xy 202.897421 -305.032395) (xy 202.89774 -305.037744) (xy 202.89774 -305.038252) (xy 202.89774 -305.532282)
			(xy 264.798048 -305.532282) (xy 264.798048 -305.037744) (xy 264.798619 -305.032497) (xy 264.806012 -305.025054)
			(xy 264.811256 -305.024536) (xy 264.811764 -305.024536) (xy 265.327638 -305.024536) (xy 265.335447 -305.024207)
			(xy 265.350319 -305.019433) (xy 265.356848 -305.015138) (xy 265.377937 -305.000789) (xy 265.423598 -304.978058)
			(xy 265.472204 -304.962599) (xy 265.522607 -304.954776) (xy 265.573613 -304.954776) (xy 265.624016 -304.962599)
			(xy 265.672622 -304.978058) (xy 265.718283 -305.000789) (xy 265.739372 -305.015138) (xy 265.745914 -305.019411)
			(xy 265.760776 -305.024207) (xy 265.768582 -305.024536) (xy 266.28471 -305.024536) (xy 266.290014 -305.025016)
			(xy 266.297585 -305.032449) (xy 266.298172 -305.037744) (xy 266.298172 -305.532282) (xy 266.298155 -305.532536)
			(xy 272.342356 -305.532536) (xy 272.342356 -305.532028) (xy 272.342356 -305.037744) (xy 272.342753 -305.032426)
			(xy 272.350249 -305.024885) (xy 272.355564 -305.024536) (xy 272.871692 -305.024536) (xy 272.879503 -305.02423)
			(xy 272.894375 -305.01944) (xy 272.900902 -305.015138) (xy 272.921991 -305.000789) (xy 272.967652 -304.978058)
			(xy 273.016258 -304.962599) (xy 273.066661 -304.954776) (xy 273.117667 -304.954776) (xy 273.16807 -304.962599)
			(xy 273.216676 -304.978058) (xy 273.262337 -305.000789) (xy 273.283426 -305.015138) (xy 273.289956 -305.019432)
			(xy 273.304827 -305.024214) (xy 273.312636 -305.024536) (xy 273.828764 -305.024536) (xy 273.834102 -305.024855)
			(xy 273.841648 -305.032406) (xy 273.841972 -305.037744) (xy 273.841972 -305.532282) (xy 273.841948 -305.532536)
			(xy 279.886156 -305.532536) (xy 279.886156 -305.532028) (xy 279.886156 -305.037744) (xy 279.886553 -305.032426)
			(xy 279.894049 -305.024885) (xy 279.899364 -305.024536) (xy 280.415492 -305.024536) (xy 280.423303 -305.02423)
			(xy 280.438175 -305.01944) (xy 280.444702 -305.015138) (xy 280.465791 -305.000789) (xy 280.511452 -304.978058)
			(xy 280.560058 -304.962599) (xy 280.610461 -304.954776) (xy 280.661467 -304.954776) (xy 280.71187 -304.962599)
			(xy 280.760476 -304.978058) (xy 280.806137 -305.000789) (xy 280.827226 -305.015138) (xy 280.833756 -305.019432)
			(xy 280.848627 -305.024214) (xy 280.856436 -305.024536) (xy 281.372564 -305.024536) (xy 281.377902 -305.024855)
			(xy 281.385448 -305.032406) (xy 281.385772 -305.037744) (xy 281.385772 -305.532282) (xy 287.429956 -305.532282)
			(xy 287.429956 -305.037744) (xy 287.430353 -305.032426) (xy 287.437849 -305.024885) (xy 287.443164 -305.024536)
			(xy 287.443672 -305.024536) (xy 287.959546 -305.024536) (xy 287.967355 -305.02421) (xy 287.982227 -305.019434)
			(xy 287.988756 -305.015138) (xy 288.009845 -305.000789) (xy 288.055506 -304.978058) (xy 288.104112 -304.962599)
			(xy 288.154515 -304.954776) (xy 288.205521 -304.954776) (xy 288.255924 -304.962599) (xy 288.30453 -304.978058)
			(xy 288.350191 -305.000789) (xy 288.37128 -305.015138) (xy 288.37782 -305.019414) (xy 288.392683 -305.024208)
			(xy 288.40049 -305.024536) (xy 288.916618 -305.024536) (xy 288.921923 -305.025011) (xy 288.929493 -305.032448)
			(xy 288.93008 -305.037744) (xy 288.93008 -305.532282) (xy 288.930054 -305.532536) (xy 294.974264 -305.532536)
			(xy 294.974264 -305.532028) (xy 294.974264 -305.037744) (xy 294.974654 -305.032424) (xy 294.982154 -305.024883)
			(xy 294.987472 -305.024536) (xy 295.5036 -305.024536) (xy 295.511411 -305.024233) (xy 295.526283 -305.019441)
			(xy 295.53281 -305.015138) (xy 295.553899 -305.000789) (xy 295.59956 -304.978058) (xy 295.648166 -304.962599)
			(xy 295.698569 -304.954776) (xy 295.749575 -304.954776) (xy 295.799978 -304.962599) (xy 295.848584 -304.978058)
			(xy 295.894245 -305.000789) (xy 295.915334 -305.015138) (xy 295.921862 -305.019435) (xy 295.936735 -305.024216)
			(xy 295.944544 -305.024536) (xy 296.460672 -305.024536) (xy 296.466011 -305.02485) (xy 296.473557 -305.032404)
			(xy 296.47388 -305.037744) (xy 296.47388 -305.532282) (xy 302.518064 -305.532282) (xy 302.518064 -305.037744)
			(xy 302.518454 -305.032424) (xy 302.525954 -305.024883) (xy 302.531272 -305.024536) (xy 304.004726 -305.024536)
			(xy 304.010032 -305.025006) (xy 304.017602 -305.032447) (xy 304.018188 -305.037744) (xy 304.018188 -305.532282)
			(xy 304.01764 -305.537638) (xy 304.01008 -305.545223) (xy 304.004726 -305.545744) (xy 302.531526 -305.545744)
			(xy 302.52609 -305.545402) (xy 302.518402 -305.537718) (xy 302.518064 -305.532282) (xy 296.47388 -305.532282)
			(xy 296.473367 -305.537579) (xy 296.465958 -305.54515) (xy 296.460672 -305.545744) (xy 295.944798 -305.545744)
			(xy 295.936987 -305.546049) (xy 295.922115 -305.55084) (xy 295.915588 -305.555142) (xy 295.894466 -305.569491)
			(xy 295.848743 -305.592218) (xy 295.800069 -305.607648) (xy 295.749603 -305.615415) (xy 295.724072 -305.615848)
			(xy 295.698541 -305.615428) (xy 295.648076 -305.607648) (xy 295.599404 -305.592214) (xy 295.553677 -305.569492)
			(xy 295.532556 -305.555142) (xy 295.526031 -305.550839) (xy 295.511156 -305.546063) (xy 295.503346 -305.545744)
			(xy 294.987472 -305.545744) (xy 294.982215 -305.545228) (xy 294.974775 -305.537793) (xy 294.974264 -305.532536)
			(xy 288.930054 -305.532536) (xy 288.92954 -305.53764) (xy 288.921974 -305.545225) (xy 288.916618 -305.545744)
			(xy 288.400744 -305.545744) (xy 288.392935 -305.546069) (xy 288.378063 -305.550847) (xy 288.371534 -305.555142)
			(xy 288.350428 -305.569515) (xy 288.304698 -305.592236) (xy 288.25602 -305.60766) (xy 288.20555 -305.615419)
			(xy 288.180018 -305.615848) (xy 288.154488 -305.615405) (xy 288.104024 -305.607632) (xy 288.055352 -305.592205)
			(xy 288.009624 -305.569489) (xy 287.988502 -305.555142) (xy 287.981967 -305.550857) (xy 287.9671 -305.546069)
			(xy 287.959292 -305.545744) (xy 287.443418 -305.545744) (xy 287.437981 -305.545407) (xy 287.430293 -305.537719)
			(xy 287.429956 -305.532282) (xy 281.385772 -305.532282) (xy 281.385266 -305.537581) (xy 281.377852 -305.545153)
			(xy 281.372564 -305.545744) (xy 280.85669 -305.545744) (xy 280.848879 -305.546046) (xy 280.834007 -305.550839)
			(xy 280.82748 -305.555142) (xy 280.806361 -305.569495) (xy 280.760636 -305.592221) (xy 280.711962 -305.60765)
			(xy 280.661495 -305.615416) (xy 280.635964 -305.615848) (xy 280.610433 -305.615432) (xy 280.559968 -305.607651)
			(xy 280.511296 -305.592215) (xy 280.465569 -305.569493) (xy 280.444448 -305.555142) (xy 280.437925 -305.550836)
			(xy 280.423048 -305.546062) (xy 280.415238 -305.545744) (xy 279.899364 -305.545744) (xy 279.894106 -305.545233)
			(xy 279.886667 -305.537794) (xy 279.886156 -305.532536) (xy 273.841948 -305.532536) (xy 273.841466 -305.537581)
			(xy 273.834052 -305.545153) (xy 273.828764 -305.545744) (xy 273.31289 -305.545744) (xy 273.305079 -305.546046)
			(xy 273.290207 -305.550839) (xy 273.28368 -305.555142) (xy 273.262561 -305.569495) (xy 273.216836 -305.592221)
			(xy 273.168162 -305.60765) (xy 273.117695 -305.615416) (xy 273.092164 -305.615848) (xy 273.066633 -305.615432)
			(xy 273.016168 -305.607651) (xy 272.967496 -305.592215) (xy 272.921769 -305.569493) (xy 272.900648 -305.555142)
			(xy 272.894125 -305.550836) (xy 272.879248 -305.546062) (xy 272.871438 -305.545744) (xy 272.355564 -305.545744)
			(xy 272.350306 -305.545233) (xy 272.342867 -305.537794) (xy 272.342356 -305.532536) (xy 266.298155 -305.532536)
			(xy 266.29781 -305.537712) (xy 266.290139 -305.545399) (xy 266.28471 -305.545744) (xy 265.768836 -305.545744)
			(xy 265.761027 -305.546066) (xy 265.746155 -305.550846) (xy 265.739626 -305.555142) (xy 265.718494 -305.569475)
			(xy 265.672774 -305.592206) (xy 265.624104 -305.60764) (xy 265.57364 -305.615412) (xy 265.54811 -305.615848)
			(xy 265.52258 -305.615409) (xy 265.472116 -305.607635) (xy 265.423443 -305.592206) (xy 265.377716 -305.56949)
			(xy 265.356594 -305.555142) (xy 265.350061 -305.550854) (xy 265.335192 -305.546068) (xy 265.327384 -305.545744)
			(xy 264.81151 -305.545744) (xy 264.806072 -305.545412) (xy 264.798384 -305.53772) (xy 264.798048 -305.532282)
			(xy 202.89774 -305.532282) (xy 202.89774 -305.532536) (xy 202.897232 -305.537795) (xy 202.889791 -305.545234)
			(xy 202.884532 -305.545744) (xy 202.368658 -305.545744) (xy 202.360783 -305.546022) (xy 202.345779 -305.550812)
			(xy 202.339194 -305.555142) (xy 202.318108 -305.56952) (xy 202.272466 -305.592352) (xy 202.223863 -305.607913)
			(xy 202.173448 -305.615837) (xy 202.147932 -305.616356) (xy 202.122411 -305.615875) (xy 202.071984 -305.607979)
			(xy 202.023372 -305.592417) (xy 201.977734 -305.569559) (xy 201.95667 -305.555142) (xy 201.950084 -305.550817)
			(xy 201.93508 -305.546036) (xy 201.927206 -305.545744) (xy 201.411332 -305.545744) (xy 201.406082 -305.545188)
			(xy 201.398639 -305.537784) (xy 201.398124 -305.532536) (xy 195.35394 -305.532536) (xy 195.353432 -305.537795)
			(xy 195.345991 -305.545234) (xy 195.340732 -305.545744) (xy 194.824858 -305.545744) (xy 194.816983 -305.546022)
			(xy 194.801979 -305.550812) (xy 194.795394 -305.555142) (xy 194.774308 -305.56952) (xy 194.728666 -305.592352)
			(xy 194.680063 -305.607913) (xy 194.629648 -305.615837) (xy 194.604132 -305.616356) (xy 194.578611 -305.615875)
			(xy 194.528184 -305.607979) (xy 194.479572 -305.592417) (xy 194.433934 -305.569559) (xy 194.41287 -305.555142)
			(xy 194.406284 -305.550817) (xy 194.39128 -305.546036) (xy 194.383406 -305.545744) (xy 193.867532 -305.545744)
			(xy 193.862282 -305.545188) (xy 193.854839 -305.537784) (xy 193.854324 -305.532536) (xy 187.81014 -305.532536)
			(xy 187.809632 -305.537795) (xy 187.802191 -305.545234) (xy 187.796932 -305.545744) (xy 187.796424 -305.545744)
			(xy 187.280804 -305.545744) (xy 187.27293 -305.546042) (xy 187.257926 -305.550819) (xy 187.25134 -305.555142)
			(xy 187.230269 -305.569544) (xy 187.184622 -305.59237) (xy 187.136014 -305.607925) (xy 187.085595 -305.615841)
			(xy 187.060078 -305.616356) (xy 187.034558 -305.615852) (xy 186.984132 -305.607963) (xy 186.93552 -305.592408)
			(xy 186.889881 -305.569556) (xy 186.868816 -305.555142) (xy 186.86222 -305.550835) (xy 186.847224 -305.546042)
			(xy 186.839352 -305.545744) (xy 186.323478 -305.545744) (xy 186.318167 -305.54529) (xy 186.310597 -305.537838)
			(xy 186.310016 -305.532536) (xy 180.265832 -305.532536) (xy 180.265331 -305.537797) (xy 180.257886 -305.545236)
			(xy 180.252624 -305.545744) (xy 179.73675 -305.545744) (xy 179.728874 -305.546019) (xy 179.71387 -305.550811)
			(xy 179.707286 -305.555142) (xy 179.686202 -305.569524) (xy 179.64056 -305.592355) (xy 179.591956 -305.607915)
			(xy 179.54154 -305.615837) (xy 179.516024 -305.616356) (xy 179.490503 -305.615879) (xy 179.440075 -305.607982)
			(xy 179.391464 -305.592419) (xy 179.345826 -305.56956) (xy 179.324762 -305.555142) (xy 179.318178 -305.550814)
			(xy 179.303172 -305.546034) (xy 179.295298 -305.545744) (xy 178.779424 -305.545744) (xy 178.774173 -305.545193)
			(xy 178.766731 -305.537785) (xy 178.766216 -305.532536) (xy 172.722032 -305.532536) (xy 172.721531 -305.537797)
			(xy 172.714086 -305.545236) (xy 172.708824 -305.545744) (xy 172.708316 -305.545744) (xy 172.192696 -305.545744)
			(xy 172.184822 -305.546039) (xy 172.169818 -305.550818) (xy 172.163232 -305.555142) (xy 172.142163 -305.569547)
			(xy 172.096515 -305.592373) (xy 172.047907 -305.607927) (xy 171.997487 -305.615841) (xy 171.97197 -305.616356)
			(xy 171.94645 -305.615856) (xy 171.896023 -305.607966) (xy 171.847411 -305.592409) (xy 171.801773 -305.569557)
			(xy 171.780708 -305.555142) (xy 171.774114 -305.550831) (xy 171.759116 -305.546041) (xy 171.751244 -305.545744)
			(xy 171.23537 -305.545744) (xy 171.230058 -305.545295) (xy 171.222488 -305.537839) (xy 171.221908 -305.532536)
			(xy 165.177724 -305.532536) (xy 165.177231 -305.537799) (xy 165.16978 -305.545239) (xy 165.164516 -305.545744)
			(xy 163.691316 -305.545744) (xy 163.686064 -305.545198) (xy 163.678622 -305.537786) (xy 163.678108 -305.532536)
			(xy 144.928635 -305.532536) (xy 144.923187 -305.551268) (xy 144.875741 -305.685553) (xy 144.820774 -305.81694)
			(xy 144.758461 -305.945006) (xy 144.689003 -306.069341) (xy 144.612622 -306.189548) (xy 144.529563 -306.305241)
			(xy 144.467245 -306.38242) (xy 167.778176 -306.38242) (xy 167.778176 -305.887882) (xy 167.778615 -305.882567)
			(xy 167.786077 -305.874995) (xy 167.791384 -305.87442) (xy 169.264584 -305.87442) (xy 169.269921 -305.87474)
			(xy 169.277465 -305.882291) (xy 169.277792 -305.887628) (xy 169.277792 -306.38242) (xy 175.321976 -306.38242)
			(xy 175.321976 -305.887882) (xy 175.322271 -305.882435) (xy 175.32999 -305.874748) (xy 175.335438 -305.87442)
			(xy 175.851566 -305.87442) (xy 175.859376 -305.874105) (xy 175.874248 -305.869321) (xy 175.880776 -305.865022)
			(xy 175.901865 -305.850673) (xy 175.947526 -305.827942) (xy 175.996132 -305.812483) (xy 176.046535 -305.80466)
			(xy 176.097541 -305.80466) (xy 176.147944 -305.812483) (xy 176.19655 -305.827942) (xy 176.242211 -305.850673)
			(xy 176.2633 -305.865022) (xy 176.269837 -305.869305) (xy 176.284703 -305.874094) (xy 176.29251 -305.87442)
			(xy 176.808638 -305.87442) (xy 176.814002 -305.874924) (xy 176.821584 -305.882517) (xy 176.8221 -305.887882)
			(xy 176.8221 -306.38242) (xy 182.866284 -306.38242) (xy 182.866284 -305.887882) (xy 182.866716 -305.882565)
			(xy 182.874183 -305.874993) (xy 182.879492 -305.87442) (xy 183.39562 -305.87442) (xy 183.403432 -305.874128)
			(xy 183.418304 -305.869328) (xy 183.42483 -305.865022) (xy 183.445919 -305.850673) (xy 183.49158 -305.827942)
			(xy 183.540186 -305.812483) (xy 183.590589 -305.80466) (xy 183.641595 -305.80466) (xy 183.691998 -305.812483)
			(xy 183.740604 -305.827942) (xy 183.786265 -305.850673) (xy 183.807354 -305.865022) (xy 183.813879 -305.869325)
			(xy 183.828754 -305.874102) (xy 183.836564 -305.87442) (xy 184.352692 -305.87442) (xy 184.35803 -305.874735)
			(xy 184.365573 -305.882289) (xy 184.3659 -305.887628) (xy 184.3659 -305.888136) (xy 184.3659 -306.38242)
			(xy 190.410084 -306.38242) (xy 190.410084 -305.887882) (xy 190.410372 -305.882433) (xy 190.418096 -305.874746)
			(xy 190.423546 -305.87442) (xy 190.939674 -305.87442) (xy 190.947485 -305.874109) (xy 190.962356 -305.869322)
			(xy 190.968884 -305.865022) (xy 190.989973 -305.850673) (xy 191.035634 -305.827942) (xy 191.08424 -305.812483)
			(xy 191.134643 -305.80466) (xy 191.185649 -305.80466) (xy 191.236052 -305.812483) (xy 191.284658 -305.827942)
			(xy 191.330319 -305.850673) (xy 191.351408 -305.865022) (xy 191.357943 -305.869308) (xy 191.37281 -305.874096)
			(xy 191.380618 -305.87442) (xy 191.896746 -305.87442) (xy 191.902111 -305.874918) (xy 191.909693 -305.882516)
			(xy 191.910208 -305.887882) (xy 191.910208 -306.38242) (xy 197.954392 -306.38242) (xy 197.954392 -305.887882)
			(xy 197.954905 -305.882587) (xy 197.962316 -305.875019) (xy 197.9676 -305.87442) (xy 198.483728 -305.87442)
			(xy 198.491541 -305.874131) (xy 198.506412 -305.86933) (xy 198.512938 -305.865022) (xy 198.534027 -305.850673)
			(xy 198.579688 -305.827942) (xy 198.628294 -305.812483) (xy 198.678697 -305.80466) (xy 198.729703 -305.80466)
			(xy 198.780106 -305.812483) (xy 198.828712 -305.827942) (xy 198.874373 -305.850673) (xy 198.895462 -305.865022)
			(xy 198.902007 -305.86929) (xy 198.916867 -305.874089) (xy 198.924672 -305.87442) (xy 199.4408 -305.87442)
			(xy 199.446139 -305.874729) (xy 199.453682 -305.882288) (xy 199.454008 -305.887628) (xy 199.454008 -305.888136)
			(xy 199.454008 -306.38242) (xy 205.498192 -306.38242) (xy 205.498192 -305.887882) (xy 205.498705 -305.882587)
			(xy 205.506116 -305.875019) (xy 205.5114 -305.87442) (xy 206.027528 -305.87442) (xy 206.035341 -305.874131)
			(xy 206.050212 -305.86933) (xy 206.056738 -305.865022) (xy 206.077827 -305.850673) (xy 206.123488 -305.827942)
			(xy 206.172094 -305.812483) (xy 206.222497 -305.80466) (xy 206.273503 -305.80466) (xy 206.323906 -305.812483)
			(xy 206.372512 -305.827942) (xy 206.418173 -305.850673) (xy 206.439262 -305.865022) (xy 206.445807 -305.86929)
			(xy 206.460667 -305.874089) (xy 206.468472 -305.87442) (xy 206.9846 -305.87442) (xy 206.989939 -305.874729)
			(xy 206.997482 -305.882288) (xy 206.997808 -305.887628) (xy 206.997808 -305.888136) (xy 206.997808 -306.382166)
			(xy 268.898116 -306.382166) (xy 268.898116 -305.887628) (xy 268.898448 -305.882294) (xy 268.90599 -305.874749)
			(xy 268.911324 -305.87442) (xy 268.911832 -305.87442) (xy 269.427706 -305.87442) (xy 269.435518 -305.874122)
			(xy 269.45039 -305.869327) (xy 269.456916 -305.865022) (xy 269.478005 -305.850673) (xy 269.523666 -305.827942)
			(xy 269.572272 -305.812483) (xy 269.622675 -305.80466) (xy 269.673681 -305.80466) (xy 269.724084 -305.812483)
			(xy 269.77269 -305.827942) (xy 269.818351 -305.850673) (xy 269.83944 -305.865022) (xy 269.845968 -305.86932)
			(xy 269.86084 -305.8741) (xy 269.86865 -305.87442) (xy 270.384778 -305.87442) (xy 270.390075 -305.874935)
			(xy 270.397646 -305.882343) (xy 270.39824 -305.887628) (xy 270.39824 -306.382166) (xy 270.398224 -306.38242)
			(xy 276.442424 -306.38242) (xy 276.442424 -306.381912) (xy 276.442424 -305.887628) (xy 276.442749 -305.882292)
			(xy 276.450296 -305.874747) (xy 276.455632 -305.87442) (xy 276.97176 -305.87442) (xy 276.97957 -305.874103)
			(xy 276.994442 -305.869321) (xy 277.00097 -305.865022) (xy 277.022059 -305.850673) (xy 277.06772 -305.827942)
			(xy 277.116326 -305.812483) (xy 277.166729 -305.80466) (xy 277.217735 -305.80466) (xy 277.268138 -305.812483)
			(xy 277.316744 -305.827942) (xy 277.362405 -305.850673) (xy 277.383494 -305.865022) (xy 277.390032 -305.869302)
			(xy 277.404897 -305.874094) (xy 277.412704 -305.87442) (xy 277.928832 -305.87442) (xy 277.934105 -305.874876)
			(xy 277.941548 -305.882352) (xy 277.94204 -305.887628) (xy 277.94204 -306.382166) (xy 277.942017 -306.38242)
			(xy 283.986224 -306.38242) (xy 283.986224 -306.381912) (xy 283.986224 -305.887628) (xy 283.986549 -305.882292)
			(xy 283.994096 -305.874747) (xy 283.999432 -305.87442) (xy 284.51556 -305.87442) (xy 284.52337 -305.874103)
			(xy 284.538242 -305.869321) (xy 284.54477 -305.865022) (xy 284.565859 -305.850673) (xy 284.61152 -305.827942)
			(xy 284.660126 -305.812483) (xy 284.710529 -305.80466) (xy 284.761535 -305.80466) (xy 284.811938 -305.812483)
			(xy 284.860544 -305.827942) (xy 284.906205 -305.850673) (xy 284.927294 -305.865022) (xy 284.933832 -305.869302)
			(xy 284.948697 -305.874094) (xy 284.956504 -305.87442) (xy 285.472632 -305.87442) (xy 285.477905 -305.874876)
			(xy 285.485348 -305.882352) (xy 285.48584 -305.887628) (xy 285.48584 -306.382166) (xy 291.530024 -306.382166)
			(xy 291.530024 -305.887628) (xy 291.530349 -305.882292) (xy 291.537896 -305.874747) (xy 291.543232 -305.87442)
			(xy 291.54374 -305.87442) (xy 292.059614 -305.87442) (xy 292.067426 -305.874126) (xy 292.082298 -305.869328)
			(xy 292.088824 -305.865022) (xy 292.109913 -305.850673) (xy 292.155574 -305.827942) (xy 292.20418 -305.812483)
			(xy 292.254583 -305.80466) (xy 292.305589 -305.80466) (xy 292.355992 -305.812483) (xy 292.404598 -305.827942)
			(xy 292.450259 -305.850673) (xy 292.471348 -305.865022) (xy 292.477874 -305.869323) (xy 292.492748 -305.874101)
			(xy 292.500558 -305.87442) (xy 293.016686 -305.87442) (xy 293.021984 -305.87493) (xy 293.029554 -305.882342)
			(xy 293.030148 -305.887628) (xy 293.030148 -306.382166) (xy 293.030132 -306.38242) (xy 299.074332 -306.38242)
			(xy 299.074332 -306.381912) (xy 299.074332 -305.887628) (xy 299.074649 -305.88229) (xy 299.082201 -305.874745)
			(xy 299.08754 -305.87442) (xy 299.603668 -305.87442) (xy 299.611478 -305.874106) (xy 299.62635 -305.869322)
			(xy 299.632878 -305.865022) (xy 299.653967 -305.850673) (xy 299.699628 -305.827942) (xy 299.748234 -305.812483)
			(xy 299.798637 -305.80466) (xy 299.849643 -305.80466) (xy 299.900046 -305.812483) (xy 299.948652 -305.827942)
			(xy 299.994313 -305.850673) (xy 300.015402 -305.865022) (xy 300.021938 -305.869305) (xy 300.036804 -305.874095)
			(xy 300.044612 -305.87442) (xy 300.56074 -305.87442) (xy 300.566014 -305.874871) (xy 300.573456 -305.882351)
			(xy 300.573948 -305.887628) (xy 300.573948 -306.382166) (xy 306.618132 -306.382166) (xy 306.618132 -305.887628)
			(xy 306.618449 -305.88229) (xy 306.626001 -305.874745) (xy 306.63134 -305.87442) (xy 306.631848 -305.87442)
			(xy 308.104794 -305.87442) (xy 308.110093 -305.874925) (xy 308.117663 -305.88234) (xy 308.118256 -305.887628)
			(xy 308.118256 -306.382166) (xy 308.117897 -306.387598) (xy 308.110225 -306.395286) (xy 308.104794 -306.395628)
			(xy 306.631594 -306.395628) (xy 306.62615 -306.395321) (xy 306.618463 -306.387611) (xy 306.618132 -306.382166)
			(xy 300.573948 -306.382166) (xy 300.573453 -306.387469) (xy 300.566032 -306.395043) (xy 300.56074 -306.395628)
			(xy 300.044866 -306.395628) (xy 300.037058 -306.395965) (xy 300.022186 -306.400735) (xy 300.015656 -306.405026)
			(xy 299.994542 -306.419387) (xy 299.948816 -306.442112) (xy 299.90014 -306.457539) (xy 299.849672 -306.465301)
			(xy 299.82414 -306.465732) (xy 299.79861 -306.465281) (xy 299.748147 -306.457511) (xy 299.699474 -306.442086)
			(xy 299.653746 -306.419372) (xy 299.632624 -306.405026) (xy 299.626085 -306.400748) (xy 299.611221 -306.395956)
			(xy 299.603414 -306.395628) (xy 299.08754 -306.395628) (xy 299.082218 -306.395248) (xy 299.074676 -306.38774)
			(xy 299.074332 -306.38242) (xy 293.030132 -306.38242) (xy 293.029797 -306.3876) (xy 293.022119 -306.395288)
			(xy 293.016686 -306.395628) (xy 292.500812 -306.395628) (xy 292.493002 -306.395942) (xy 292.47813 -306.400727)
			(xy 292.471602 -306.405026) (xy 292.450475 -306.419368) (xy 292.404754 -306.442097) (xy 292.356082 -306.457529)
			(xy 292.305617 -306.465298) (xy 292.280086 -306.465732) (xy 292.254555 -306.465308) (xy 292.204091 -306.45753)
			(xy 292.155418 -306.442097) (xy 292.109691 -306.419376) (xy 292.08857 -306.405026) (xy 292.082043 -306.400727)
			(xy 292.06717 -306.395949) (xy 292.05936 -306.395628) (xy 291.543486 -306.395628) (xy 291.538041 -306.395327)
			(xy 291.530354 -306.387612) (xy 291.530024 -306.382166) (xy 285.48584 -306.382166) (xy 285.485352 -306.387471)
			(xy 285.477926 -306.395045) (xy 285.472632 -306.395628) (xy 284.956758 -306.395628) (xy 284.94895 -306.395962)
			(xy 284.934078 -306.400734) (xy 284.927548 -306.405026) (xy 284.906436 -306.419391) (xy 284.860709 -306.442115)
			(xy 284.812033 -306.457541) (xy 284.761564 -306.465302) (xy 284.736032 -306.465732) (xy 284.710502 -306.465285)
			(xy 284.660038 -306.457513) (xy 284.611366 -306.442087) (xy 284.565638 -306.419373) (xy 284.544516 -306.405026)
			(xy 284.537979 -306.400745) (xy 284.523113 -306.395955) (xy 284.515306 -306.395628) (xy 283.999432 -306.395628)
			(xy 283.994109 -306.395254) (xy 283.986567 -306.387742) (xy 283.986224 -306.38242) (xy 277.942017 -306.38242)
			(xy 277.941552 -306.387471) (xy 277.934126 -306.395045) (xy 277.928832 -306.395628) (xy 277.412958 -306.395628)
			(xy 277.40515 -306.395962) (xy 277.390278 -306.400734) (xy 277.383748 -306.405026) (xy 277.362636 -306.419391)
			(xy 277.316909 -306.442115) (xy 277.268233 -306.457541) (xy 277.217764 -306.465302) (xy 277.192232 -306.465732)
			(xy 277.166702 -306.465285) (xy 277.116238 -306.457513) (xy 277.067566 -306.442087) (xy 277.021838 -306.419373)
			(xy 277.000716 -306.405026) (xy 276.994179 -306.400745) (xy 276.979313 -306.395955) (xy 276.971506 -306.395628)
			(xy 276.455632 -306.395628) (xy 276.450309 -306.395254) (xy 276.442767 -306.387742) (xy 276.442424 -306.38242)
			(xy 270.398224 -306.38242) (xy 270.397896 -306.387602) (xy 270.390213 -306.395291) (xy 270.384778 -306.395628)
			(xy 269.868904 -306.395628) (xy 269.861094 -306.395939) (xy 269.846222 -306.400726) (xy 269.839694 -306.405026)
			(xy 269.81857 -306.419371) (xy 269.772847 -306.442099) (xy 269.724175 -306.457531) (xy 269.673709 -306.465298)
			(xy 269.648178 -306.465732) (xy 269.622647 -306.465312) (xy 269.572182 -306.457532) (xy 269.52351 -306.442098)
			(xy 269.477783 -306.419376) (xy 269.456662 -306.405026) (xy 269.450137 -306.400724) (xy 269.435262 -306.395947)
			(xy 269.427452 -306.395628) (xy 268.911578 -306.395628) (xy 268.906132 -306.395332) (xy 268.898445 -306.387613)
			(xy 268.898116 -306.382166) (xy 206.997808 -306.382166) (xy 206.997808 -306.38242) (xy 206.997319 -306.387685)
			(xy 206.989866 -306.395127) (xy 206.9846 -306.395628) (xy 206.468726 -306.395628) (xy 206.46085 -306.395895)
			(xy 206.445846 -306.400693) (xy 206.439262 -306.405026) (xy 206.418184 -306.419416) (xy 206.372539 -306.442246)
			(xy 206.323934 -306.457804) (xy 206.273517 -306.465723) (xy 206.248 -306.46624) (xy 206.222479 -306.46576)
			(xy 206.172052 -306.457861) (xy 206.123441 -306.442298) (xy 206.077803 -306.419442) (xy 206.056738 -306.405026)
			(xy 206.050138 -306.400726) (xy 206.035145 -306.395929) (xy 206.027274 -306.395628) (xy 205.5114 -306.395628)
			(xy 205.506142 -306.395107) (xy 205.498701 -306.387677) (xy 205.498192 -306.38242) (xy 199.454008 -306.38242)
			(xy 199.453519 -306.387685) (xy 199.446066 -306.395127) (xy 199.4408 -306.395628) (xy 198.924926 -306.395628)
			(xy 198.91705 -306.395895) (xy 198.902046 -306.400693) (xy 198.895462 -306.405026) (xy 198.874384 -306.419416)
			(xy 198.828739 -306.442246) (xy 198.780134 -306.457804) (xy 198.729717 -306.465723) (xy 198.7042 -306.46624)
			(xy 198.678679 -306.46576) (xy 198.628252 -306.457861) (xy 198.579641 -306.442298) (xy 198.534003 -306.419442)
			(xy 198.512938 -306.405026) (xy 198.506338 -306.400726) (xy 198.491345 -306.395929) (xy 198.483474 -306.395628)
			(xy 197.9676 -306.395628) (xy 197.962342 -306.395107) (xy 197.954901 -306.387677) (xy 197.954392 -306.38242)
			(xy 191.910208 -306.38242) (xy 191.909719 -306.387685) (xy 191.902266 -306.395127) (xy 191.897 -306.395628)
			(xy 191.896492 -306.395628) (xy 191.380872 -306.395628) (xy 191.372997 -306.395915) (xy 191.357994 -306.400699)
			(xy 191.351408 -306.405026) (xy 191.330345 -306.41944) (xy 191.284695 -306.442264) (xy 191.236085 -306.457815)
			(xy 191.185664 -306.465727) (xy 191.160146 -306.46624) (xy 191.134626 -306.465737) (xy 191.0842 -306.457845)
			(xy 191.035589 -306.442289) (xy 190.98995 -306.419439) (xy 190.968884 -306.405026) (xy 190.962296 -306.400705)
			(xy 190.947293 -306.395922) (xy 190.93942 -306.395628) (xy 190.423546 -306.395628) (xy 190.41824 -306.395142)
			(xy 190.410665 -306.387716) (xy 190.410084 -306.38242) (xy 184.3659 -306.38242) (xy 184.365418 -306.387687)
			(xy 184.35796 -306.395129) (xy 184.352692 -306.395628) (xy 183.836818 -306.395628) (xy 183.828945 -306.395935)
			(xy 183.813941 -306.400706) (xy 183.807354 -306.405026) (xy 183.786278 -306.41942) (xy 183.740633 -306.442248)
			(xy 183.692026 -306.457806) (xy 183.641609 -306.465724) (xy 183.616092 -306.46624) (xy 183.590573 -306.465714)
			(xy 183.540148 -306.457829) (xy 183.491537 -306.44228) (xy 183.445897 -306.419436) (xy 183.42483 -306.405026)
			(xy 183.418232 -306.400722) (xy 183.403237 -306.395928) (xy 183.395366 -306.395628) (xy 182.879492 -306.395628)
			(xy 182.874233 -306.395113) (xy 182.866792 -306.387678) (xy 182.866284 -306.38242) (xy 176.8221 -306.38242)
			(xy 176.821618 -306.387687) (xy 176.81416 -306.395129) (xy 176.808892 -306.395628) (xy 176.808384 -306.395628)
			(xy 176.292764 -306.395628) (xy 176.284889 -306.395911) (xy 176.269885 -306.400698) (xy 176.2633 -306.405026)
			(xy 176.242211 -306.4194) (xy 176.196571 -306.442233) (xy 176.147968 -306.457796) (xy 176.097554 -306.46572)
			(xy 176.072038 -306.46624) (xy 176.046518 -306.465741) (xy 175.996092 -306.457848) (xy 175.947481 -306.442291)
			(xy 175.901842 -306.419439) (xy 175.880776 -306.405026) (xy 175.87419 -306.400702) (xy 175.859186 -306.39592)
			(xy 175.851312 -306.395628) (xy 175.335438 -306.395628) (xy 175.330131 -306.395148) (xy 175.322556 -306.387717)
			(xy 175.321976 -306.38242) (xy 169.277792 -306.38242) (xy 169.277317 -306.387689) (xy 169.269854 -306.395131)
			(xy 169.264584 -306.395628) (xy 167.791384 -306.395628) (xy 167.786124 -306.395118) (xy 167.778683 -306.38768)
			(xy 167.778176 -306.38242) (xy 144.467245 -306.38242) (xy 144.440091 -306.41605) (xy 144.344494 -306.521619)
			(xy 144.243077 -306.621611) (xy 144.136165 -306.715705) (xy 144.024101 -306.803599) (xy 143.907245 -306.885013)
			(xy 143.785969 -306.959686) (xy 143.660663 -307.027377) (xy 143.531728 -307.087871) (xy 143.399577 -307.140974)
			(xy 143.264634 -307.186515) (xy 143.12733 -307.224349) (xy 143.088061 -307.232812) (xy 163.678108 -307.232812)
			(xy 163.678108 -307.232304) (xy 163.678108 -306.73802) (xy 163.678442 -306.732686) (xy 163.685983 -306.725143)
			(xy 163.691316 -306.724812) (xy 165.164516 -306.724812) (xy 165.169855 -306.725118) (xy 165.177397 -306.73268)
			(xy 165.177724 -306.73802) (xy 165.177724 -307.232558) (xy 171.221908 -307.232558) (xy 171.221908 -306.73802)
			(xy 171.222242 -306.732686) (xy 171.229783 -306.725143) (xy 171.235116 -306.724812) (xy 171.235624 -306.724812)
			(xy 171.751498 -306.724812) (xy 171.75931 -306.724512) (xy 171.774182 -306.719718) (xy 171.780708 -306.715414)
			(xy 171.801797 -306.701065) (xy 171.847458 -306.678334) (xy 171.896064 -306.662875) (xy 171.946467 -306.655052)
			(xy 171.997473 -306.655052) (xy 172.047876 -306.662875) (xy 172.096482 -306.678334) (xy 172.142143 -306.701065)
			(xy 172.163232 -306.715414) (xy 172.169762 -306.719708) (xy 172.184633 -306.724491) (xy 172.192442 -306.724812)
			(xy 172.70857 -306.724812) (xy 172.713864 -306.72534) (xy 172.721435 -306.732738) (xy 172.722032 -306.73802)
			(xy 172.722032 -307.232558) (xy 172.722016 -307.232812) (xy 178.766216 -307.232812) (xy 178.766216 -307.232304)
			(xy 178.766216 -306.73802) (xy 178.766542 -306.732684) (xy 178.774088 -306.725141) (xy 178.779424 -306.724812)
			(xy 179.295552 -306.724812) (xy 179.303362 -306.724493) (xy 179.318234 -306.719712) (xy 179.324762 -306.715414)
			(xy 179.345851 -306.701065) (xy 179.391512 -306.678334) (xy 179.440118 -306.662875) (xy 179.490521 -306.655052)
			(xy 179.541527 -306.655052) (xy 179.59193 -306.662875) (xy 179.640536 -306.678334) (xy 179.686197 -306.701065)
			(xy 179.707286 -306.715414) (xy 179.713826 -306.71969) (xy 179.728689 -306.724484) (xy 179.736496 -306.724812)
			(xy 180.252624 -306.724812) (xy 180.257894 -306.725281) (xy 180.265337 -306.732748) (xy 180.265832 -306.73802)
			(xy 180.265832 -307.232558) (xy 186.310016 -307.232558) (xy 186.310016 -306.73802) (xy 186.310342 -306.732684)
			(xy 186.317888 -306.725141) (xy 186.323224 -306.724812) (xy 186.323732 -306.724812) (xy 186.839606 -306.724812)
			(xy 186.847418 -306.724516) (xy 186.86229 -306.719719) (xy 186.868816 -306.715414) (xy 186.889905 -306.701065)
			(xy 186.935566 -306.678334) (xy 186.984172 -306.662875) (xy 187.034575 -306.655052) (xy 187.085581 -306.655052)
			(xy 187.135984 -306.662875) (xy 187.18459 -306.678334) (xy 187.230251 -306.701065) (xy 187.25134 -306.715414)
			(xy 187.257868 -306.719711) (xy 187.272741 -306.724492) (xy 187.28055 -306.724812) (xy 187.796678 -306.724812)
			(xy 187.801973 -306.725334) (xy 187.809544 -306.732737) (xy 187.81014 -306.73802) (xy 187.81014 -307.232558)
			(xy 187.810124 -307.232812) (xy 193.854324 -307.232812) (xy 193.854324 -307.232304) (xy 193.854324 -306.73802)
			(xy 193.854643 -306.732683) (xy 193.862194 -306.725138) (xy 193.867532 -306.724812) (xy 194.38366 -306.724812)
			(xy 194.39147 -306.724496) (xy 194.406342 -306.719713) (xy 194.41287 -306.715414) (xy 194.433959 -306.701065)
			(xy 194.47962 -306.678334) (xy 194.528226 -306.662875) (xy 194.578629 -306.655052) (xy 194.629635 -306.655052)
			(xy 194.680038 -306.662875) (xy 194.728644 -306.678334) (xy 194.774305 -306.701065) (xy 194.795394 -306.715414)
			(xy 194.801933 -306.719694) (xy 194.816797 -306.724485) (xy 194.824604 -306.724812) (xy 195.340732 -306.724812)
			(xy 195.346003 -306.725275) (xy 195.353445 -306.732747) (xy 195.35394 -306.73802) (xy 195.35394 -307.232558)
			(xy 195.353916 -307.232812) (xy 201.398124 -307.232812) (xy 201.398124 -307.232304) (xy 201.398124 -306.73802)
			(xy 201.398443 -306.732683) (xy 201.405994 -306.725138) (xy 201.411332 -306.724812) (xy 201.92746 -306.724812)
			(xy 201.93527 -306.724496) (xy 201.950142 -306.719713) (xy 201.95667 -306.715414) (xy 201.977759 -306.701065)
			(xy 202.02342 -306.678334) (xy 202.072026 -306.662875) (xy 202.122429 -306.655052) (xy 202.173435 -306.655052)
			(xy 202.223838 -306.662875) (xy 202.272444 -306.678334) (xy 202.318105 -306.701065) (xy 202.339194 -306.715414)
			(xy 202.345733 -306.719694) (xy 202.360597 -306.724485) (xy 202.368404 -306.724812) (xy 202.884532 -306.724812)
			(xy 202.889803 -306.725275) (xy 202.897245 -306.732747) (xy 202.89774 -306.73802) (xy 202.89774 -307.232304)
			(xy 264.798048 -307.232304) (xy 264.798048 -306.737766) (xy 264.798529 -306.732396) (xy 264.806138 -306.724811)
			(xy 264.81151 -306.724304) (xy 265.327638 -306.724304) (xy 265.335446 -306.723963) (xy 265.350317 -306.719196)
			(xy 265.356848 -306.714906) (xy 265.377937 -306.700557) (xy 265.423598 -306.677826) (xy 265.472204 -306.662367)
			(xy 265.522607 -306.654544) (xy 265.573613 -306.654544) (xy 265.624016 -306.662367) (xy 265.672622 -306.677826)
			(xy 265.718283 -306.700557) (xy 265.739372 -306.714906) (xy 265.74591 -306.719186) (xy 265.760775 -306.723976)
			(xy 265.768582 -306.724304) (xy 266.28471 -306.724304) (xy 266.290067 -306.72484) (xy 266.29765 -306.73241)
			(xy 266.298172 -306.737766) (xy 266.298172 -307.232304) (xy 272.342356 -307.232304) (xy 272.342356 -306.737766)
			(xy 272.342802 -306.732454) (xy 272.35026 -306.724884) (xy 272.355564 -306.724304) (xy 272.871692 -306.724304)
			(xy 272.879502 -306.723986) (xy 272.894373 -306.719203) (xy 272.900902 -306.714906) (xy 272.921991 -306.700557)
			(xy 272.967652 -306.677826) (xy 273.016258 -306.662367) (xy 273.066661 -306.654544) (xy 273.117667 -306.654544)
			(xy 273.16807 -306.662367) (xy 273.216676 -306.677826) (xy 273.262337 -306.700557) (xy 273.283426 -306.714906)
			(xy 273.289952 -306.719207) (xy 273.304826 -306.723984) (xy 273.312636 -306.724304) (xy 273.828764 -306.724304)
			(xy 273.834094 -306.724652) (xy 273.841638 -306.732182) (xy 273.841972 -306.737512) (xy 273.841972 -306.73802)
			(xy 273.841972 -307.232304) (xy 279.886156 -307.232304) (xy 279.886156 -306.737766) (xy 279.886602 -306.732454)
			(xy 279.89406 -306.724884) (xy 279.899364 -306.724304) (xy 280.415492 -306.724304) (xy 280.423302 -306.723986)
			(xy 280.438173 -306.719203) (xy 280.444702 -306.714906) (xy 280.465791 -306.700557) (xy 280.511452 -306.677826)
			(xy 280.560058 -306.662367) (xy 280.610461 -306.654544) (xy 280.661467 -306.654544) (xy 280.71187 -306.662367)
			(xy 280.760476 -306.677826) (xy 280.806137 -306.700557) (xy 280.827226 -306.714906) (xy 280.833752 -306.719207)
			(xy 280.848626 -306.723984) (xy 280.856436 -306.724304) (xy 281.372564 -306.724304) (xy 281.377894 -306.724652)
			(xy 281.385438 -306.732182) (xy 281.385772 -306.737512) (xy 281.385772 -306.73802) (xy 281.385772 -307.232304)
			(xy 287.429956 -307.232304) (xy 287.429956 -306.737766) (xy 287.43043 -306.732394) (xy 287.438044 -306.724809)
			(xy 287.443418 -306.724304) (xy 287.959546 -306.724304) (xy 287.967354 -306.723967) (xy 287.982225 -306.719197)
			(xy 287.988756 -306.714906) (xy 288.009845 -306.700557) (xy 288.055506 -306.677826) (xy 288.104112 -306.662367)
			(xy 288.154515 -306.654544) (xy 288.205521 -306.654544) (xy 288.255924 -306.662367) (xy 288.30453 -306.677826)
			(xy 288.350191 -306.700557) (xy 288.37128 -306.714906) (xy 288.377816 -306.719189) (xy 288.392683 -306.723977)
			(xy 288.40049 -306.724304) (xy 288.916618 -306.724304) (xy 288.921976 -306.724835) (xy 288.929559 -306.732409)
			(xy 288.93008 -306.737766) (xy 288.93008 -307.232304) (xy 294.974264 -307.232304) (xy 294.974264 -306.737766)
			(xy 294.974703 -306.732452) (xy 294.982166 -306.724882) (xy 294.987472 -306.724304) (xy 295.5036 -306.724304)
			(xy 295.51141 -306.72399) (xy 295.526281 -306.719204) (xy 295.53281 -306.714906) (xy 295.553899 -306.700557)
			(xy 295.59956 -306.677826) (xy 295.648166 -306.662367) (xy 295.698569 -306.654544) (xy 295.749575 -306.654544)
			(xy 295.799978 -306.662367) (xy 295.848584 -306.677826) (xy 295.894245 -306.700557) (xy 295.915334 -306.714906)
			(xy 295.921858 -306.71921) (xy 295.936734 -306.723985) (xy 295.944544 -306.724304) (xy 296.460672 -306.724304)
			(xy 296.466003 -306.724647) (xy 296.473547 -306.732181) (xy 296.47388 -306.737512) (xy 296.47388 -306.73802)
			(xy 296.47388 -307.232304) (xy 302.518064 -307.232304) (xy 302.518064 -306.737766) (xy 302.51853 -306.732392)
			(xy 302.52615 -306.724806) (xy 302.531526 -306.724304) (xy 304.004726 -306.724304) (xy 304.010085 -306.72483)
			(xy 304.017667 -306.732407) (xy 304.018188 -306.737766) (xy 304.018188 -307.232304) (xy 304.017874 -307.237642)
			(xy 304.010318 -307.245183) (xy 304.00498 -307.245512) (xy 302.531526 -307.245512) (xy 302.526214 -307.245054)
			(xy 302.518638 -307.237607) (xy 302.518064 -307.232304) (xy 296.47388 -307.232304) (xy 296.473573 -307.237644)
			(xy 296.466012 -307.245186) (xy 296.460672 -307.245512) (xy 295.944798 -307.245512) (xy 295.936925 -307.245813)
			(xy 295.921921 -307.250588) (xy 295.915334 -307.25491) (xy 295.894262 -307.269311) (xy 295.848616 -307.292138)
			(xy 295.800008 -307.307693) (xy 295.749589 -307.315609) (xy 295.724072 -307.316124) (xy 295.698553 -307.315611)
			(xy 295.648127 -307.307723) (xy 295.599515 -307.29217) (xy 295.553876 -307.269322) (xy 295.53281 -307.25491)
			(xy 295.526217 -307.250597) (xy 295.511218 -307.245809) (xy 295.503346 -307.245512) (xy 294.987472 -307.245512)
			(xy 294.982207 -307.245024) (xy 294.974766 -307.23757) (xy 294.974264 -307.232304) (xy 288.93008 -307.232304)
			(xy 288.929773 -307.237644) (xy 288.922212 -307.245186) (xy 288.916872 -307.245512) (xy 288.916364 -307.245512)
			(xy 288.400744 -307.245512) (xy 288.392869 -307.24579) (xy 288.377865 -307.250581) (xy 288.37128 -307.25491)
			(xy 288.350195 -307.269291) (xy 288.304554 -307.292123) (xy 288.25595 -307.307684) (xy 288.205534 -307.315606)
			(xy 288.180018 -307.316124) (xy 288.154498 -307.315638) (xy 288.104071 -307.307742) (xy 288.055459 -307.29218)
			(xy 288.009821 -307.269325) (xy 287.988756 -307.25491) (xy 287.982176 -307.250576) (xy 287.967167 -307.245801)
			(xy 287.959292 -307.245512) (xy 287.443418 -307.245512) (xy 287.438105 -307.245059) (xy 287.43053 -307.237609)
			(xy 287.429956 -307.232304) (xy 281.385772 -307.232304) (xy 281.385472 -307.237646) (xy 281.377907 -307.245188)
			(xy 281.372564 -307.245512) (xy 280.85669 -307.245512) (xy 280.848816 -307.245809) (xy 280.833813 -307.250587)
			(xy 280.827226 -307.25491) (xy 280.806157 -307.269314) (xy 280.760509 -307.292141) (xy 280.711901 -307.307695)
			(xy 280.661481 -307.31561) (xy 280.635964 -307.316124) (xy 280.610445 -307.315615) (xy 280.560019 -307.307726)
			(xy 280.511407 -307.292171) (xy 280.465768 -307.269322) (xy 280.444702 -307.25491) (xy 280.438111 -307.250594)
			(xy 280.423111 -307.245808) (xy 280.415238 -307.245512) (xy 279.899364 -307.245512) (xy 279.894098 -307.245029)
			(xy 279.886658 -307.237571) (xy 279.886156 -307.232304) (xy 273.841972 -307.232304) (xy 273.841672 -307.237646)
			(xy 273.834107 -307.245188) (xy 273.828764 -307.245512) (xy 273.31289 -307.245512) (xy 273.305016 -307.245809)
			(xy 273.290013 -307.250587) (xy 273.283426 -307.25491) (xy 273.262357 -307.269314) (xy 273.216709 -307.292141)
			(xy 273.168101 -307.307695) (xy 273.117681 -307.31561) (xy 273.092164 -307.316124) (xy 273.066645 -307.315615)
			(xy 273.016219 -307.307726) (xy 272.967607 -307.292171) (xy 272.921968 -307.269322) (xy 272.900902 -307.25491)
			(xy 272.894311 -307.250594) (xy 272.879311 -307.245808) (xy 272.871438 -307.245512) (xy 272.355564 -307.245512)
			(xy 272.350298 -307.245029) (xy 272.342858 -307.237571) (xy 272.342356 -307.232304) (xy 266.298172 -307.232304)
			(xy 266.297872 -307.237646) (xy 266.290307 -307.245188) (xy 266.284964 -307.245512) (xy 266.284456 -307.245512)
			(xy 265.768836 -307.245512) (xy 265.76096 -307.245786) (xy 265.745957 -307.25058) (xy 265.739372 -307.25491)
			(xy 265.71829 -307.269294) (xy 265.672647 -307.292125) (xy 265.624042 -307.307685) (xy 265.573626 -307.315606)
			(xy 265.54811 -307.316124) (xy 265.52259 -307.315642) (xy 265.472163 -307.307744) (xy 265.423551 -307.292182)
			(xy 265.377913 -307.269326) (xy 265.356848 -307.25491) (xy 265.350269 -307.250573) (xy 265.335259 -307.2458)
			(xy 265.327384 -307.245512) (xy 264.81151 -307.245512) (xy 264.806196 -307.245064) (xy 264.798622 -307.23761)
			(xy 264.798048 -307.232304) (xy 202.89774 -307.232304) (xy 202.89774 -307.232558) (xy 202.897247 -307.237862)
			(xy 202.889825 -307.245436) (xy 202.884532 -307.24602) (xy 202.368658 -307.24602) (xy 202.36085 -307.246355)
			(xy 202.345978 -307.251126) (xy 202.339448 -307.255418) (xy 202.318336 -307.269782) (xy 202.272609 -307.292506)
			(xy 202.223933 -307.307932) (xy 202.173464 -307.315694) (xy 202.147932 -307.316124) (xy 202.122402 -307.315679)
			(xy 202.071938 -307.307907) (xy 202.023266 -307.29248) (xy 201.977538 -307.269765) (xy 201.956416 -307.255418)
			(xy 201.949879 -307.251136) (xy 201.935013 -307.246347) (xy 201.927206 -307.24602) (xy 201.411332 -307.24602)
			(xy 201.406007 -307.245653) (xy 201.398465 -307.238136) (xy 201.398124 -307.232812) (xy 195.353916 -307.232812)
			(xy 195.353447 -307.237862) (xy 195.346025 -307.245436) (xy 195.340732 -307.24602) (xy 194.824858 -307.24602)
			(xy 194.81705 -307.246355) (xy 194.802178 -307.251126) (xy 194.795648 -307.255418) (xy 194.774536 -307.269782)
			(xy 194.728809 -307.292506) (xy 194.680133 -307.307932) (xy 194.629664 -307.315694) (xy 194.604132 -307.316124)
			(xy 194.578602 -307.315679) (xy 194.528138 -307.307907) (xy 194.479466 -307.29248) (xy 194.433738 -307.269765)
			(xy 194.412616 -307.255418) (xy 194.406079 -307.251136) (xy 194.391213 -307.246347) (xy 194.383406 -307.24602)
			(xy 193.867532 -307.24602) (xy 193.862207 -307.245653) (xy 193.854665 -307.238136) (xy 193.854324 -307.232812)
			(xy 187.810124 -307.232812) (xy 187.80979 -307.237993) (xy 187.802112 -307.245682) (xy 187.796678 -307.24602)
			(xy 187.280804 -307.24602) (xy 187.272994 -307.246332) (xy 187.258122 -307.251119) (xy 187.251594 -307.255418)
			(xy 187.230469 -307.269762) (xy 187.184747 -307.292491) (xy 187.136074 -307.307923) (xy 187.085609 -307.31569)
			(xy 187.060078 -307.316124) (xy 187.034547 -307.315706) (xy 186.984082 -307.307926) (xy 186.935409 -307.292491)
			(xy 186.889683 -307.269769) (xy 186.868562 -307.255418) (xy 186.862037 -307.251115) (xy 186.847162 -307.246339)
			(xy 186.839352 -307.24602) (xy 186.323478 -307.24602) (xy 186.31803 -307.245731) (xy 186.310343 -307.238008)
			(xy 186.310016 -307.232558) (xy 180.265832 -307.232558) (xy 180.265346 -307.237864) (xy 180.257919 -307.245439)
			(xy 180.252624 -307.24602) (xy 179.73675 -307.24602) (xy 179.728942 -307.246352) (xy 179.71407 -307.251125)
			(xy 179.70754 -307.255418) (xy 179.68643 -307.269785) (xy 179.640702 -307.292509) (xy 179.592025 -307.307934)
			(xy 179.541556 -307.315695) (xy 179.516024 -307.316124) (xy 179.490494 -307.315683) (xy 179.44003 -307.307909)
			(xy 179.391357 -307.292482) (xy 179.34563 -307.269766) (xy 179.324508 -307.255418) (xy 179.317973 -307.251133)
			(xy 179.303106 -307.246346) (xy 179.295298 -307.24602) (xy 178.779424 -307.24602) (xy 178.774098 -307.245658)
			(xy 178.766556 -307.238137) (xy 178.766216 -307.232812) (xy 172.722016 -307.232812) (xy 172.72169 -307.237994)
			(xy 172.714006 -307.245685) (xy 172.70857 -307.24602) (xy 172.192696 -307.24602) (xy 172.184885 -307.246329)
			(xy 172.170014 -307.251118) (xy 172.163486 -307.255418) (xy 172.142363 -307.269766) (xy 172.09664 -307.292494)
			(xy 172.047967 -307.307924) (xy 171.997501 -307.315691) (xy 171.97197 -307.316124) (xy 171.946439 -307.31571)
			(xy 171.895974 -307.307928) (xy 171.847301 -307.292493) (xy 171.801575 -307.269769) (xy 171.780454 -307.255418)
			(xy 171.773931 -307.251112) (xy 171.759054 -307.246338) (xy 171.751244 -307.24602) (xy 171.23537 -307.24602)
			(xy 171.229921 -307.245737) (xy 171.222234 -307.238009) (xy 171.221908 -307.232558) (xy 165.177724 -307.232558)
			(xy 165.177245 -307.237866) (xy 165.169813 -307.245441) (xy 165.164516 -307.24602) (xy 163.691316 -307.24602)
			(xy 163.685989 -307.245664) (xy 163.678448 -307.238138) (xy 163.678108 -307.232812) (xy 143.088061 -307.232812)
			(xy 142.988105 -307.254354) (xy 142.847406 -307.276434) (xy 142.705684 -307.29052) (xy 142.563391 -307.296564)
			(xy 142.420984 -307.294549) (xy 142.278919 -307.28448) (xy 142.137652 -307.26639) (xy 141.997634 -307.240337)
			(xy 141.859315 -307.206404) (xy 141.723136 -307.164699) (xy 141.589536 -307.115358) (xy 141.45894 -307.058537)
			(xy 141.331769 -306.994418) (xy 141.208429 -306.923208) (xy 141.089315 -306.845133) (xy 140.974809 -306.760445)
			(xy 140.865277 -306.669414) (xy 140.761071 -306.572333) (xy 140.662525 -306.469511) (xy 140.569953 -306.361278)
			(xy 140.483653 -306.247982) (xy 140.403901 -306.129985) (xy 140.330952 -306.007665) (xy 140.26504 -305.881414)
			(xy 140.206377 -305.751635) (xy 140.15515 -305.618746) (xy 140.111523 -305.483172) (xy 140.075636 -305.345346)
			(xy 140.047604 -305.205711) (xy 140.027516 -305.064714) (xy 140.015438 -304.922806) (xy 140.011408 -304.780442)
			(xy 83.843876 -304.780442) (xy 83.843372 -304.851653) (xy 83.835315 -304.993845) (xy 83.819226 -305.135355)
			(xy 83.795156 -305.275727) (xy 83.763184 -305.414513) (xy 83.723411 -305.551268) (xy 83.675965 -305.685553)
			(xy 83.620998 -305.81694) (xy 83.558685 -305.945006) (xy 83.489227 -306.069341) (xy 83.412846 -306.189548)
			(xy 83.329787 -306.305241) (xy 83.240315 -306.41605) (xy 83.144718 -306.521619) (xy 83.043301 -306.621611)
			(xy 82.936389 -306.715705) (xy 82.824325 -306.803599) (xy 82.707469 -306.885013) (xy 82.586193 -306.959686)
			(xy 82.460887 -307.027377) (xy 82.331952 -307.087871) (xy 82.199801 -307.140974) (xy 82.064858 -307.186515)
			(xy 81.927554 -307.224349) (xy 81.788329 -307.254354) (xy 81.64763 -307.276434) (xy 81.505908 -307.29052)
			(xy 81.363615 -307.296564) (xy 81.221208 -307.294549) (xy 81.079143 -307.28448) (xy 80.937876 -307.26639)
			(xy 80.797858 -307.240337) (xy 80.659539 -307.206404) (xy 80.52336 -307.164699) (xy 80.38976 -307.115358)
			(xy 80.259164 -307.058537) (xy 80.131993 -306.994418) (xy 80.008653 -306.923208) (xy 79.889539 -306.845133)
			(xy 79.775033 -306.760445) (xy 79.665501 -306.669414) (xy 79.561295 -306.572333) (xy 79.462749 -306.469511)
			(xy 79.370177 -306.361278) (xy 79.283877 -306.247982) (xy 79.204125 -306.129985) (xy 79.131176 -306.007665)
			(xy 79.065264 -305.881414) (xy 79.006601 -305.751635) (xy 78.955374 -305.618746) (xy 78.911747 -305.483172)
			(xy 78.87586 -305.345346) (xy 78.847828 -305.205711) (xy 78.82774 -305.064714) (xy 78.815662 -304.922806)
			(xy 78.811632 -304.780442) (xy 2.509012 -304.780442) (xy 2.509012 -305.532536) (xy 16.85798 -305.532536)
			(xy 16.85798 -305.037998) (xy 16.858282 -305.032553) (xy 16.865996 -305.024864) (xy 16.871442 -305.024536)
			(xy 17.38757 -305.024536) (xy 17.39538 -305.02422) (xy 17.410252 -305.019437) (xy 17.41678 -305.015138)
			(xy 17.437869 -305.000789) (xy 17.48353 -304.978058) (xy 17.532136 -304.962599) (xy 17.582539 -304.954776)
			(xy 17.633545 -304.954776) (xy 17.683948 -304.962599) (xy 17.732554 -304.978058) (xy 17.778215 -305.000789)
			(xy 17.799304 -305.015138) (xy 17.805839 -305.019424) (xy 17.820706 -305.024211) (xy 17.828514 -305.024536)
			(xy 18.344642 -305.024536) (xy 18.350011 -305.025022) (xy 18.357594 -305.032628) (xy 18.358104 -305.037998)
			(xy 18.358104 -305.532536) (xy 24.402288 -305.532536) (xy 24.402288 -305.037998) (xy 24.402728 -305.032682)
			(xy 24.410188 -305.025109) (xy 24.415496 -305.024536) (xy 24.931624 -305.024536) (xy 24.939436 -305.024244)
			(xy 24.954308 -305.019444) (xy 24.960834 -305.015138) (xy 24.981923 -305.000789) (xy 25.027584 -304.978058)
			(xy 25.07619 -304.962599) (xy 25.126593 -304.954776) (xy 25.177599 -304.954776) (xy 25.228002 -304.962599)
			(xy 25.276608 -304.978058) (xy 25.322269 -305.000789) (xy 25.343358 -305.015138) (xy 25.349881 -305.019444)
			(xy 25.364757 -305.024219) (xy 25.372568 -305.024536) (xy 25.888696 -305.024536) (xy 25.894038 -305.024834)
			(xy 25.901582 -305.032401) (xy 25.901904 -305.037744) (xy 25.901904 -305.038252) (xy 25.901904 -305.532536)
			(xy 31.946088 -305.532536) (xy 31.946088 -305.037998) (xy 31.946528 -305.032682) (xy 31.953988 -305.025109)
			(xy 31.959296 -305.024536) (xy 32.475424 -305.024536) (xy 32.483236 -305.024244) (xy 32.498108 -305.019444)
			(xy 32.504634 -305.015138) (xy 32.525723 -305.000789) (xy 32.571384 -304.978058) (xy 32.61999 -304.962599)
			(xy 32.670393 -304.954776) (xy 32.721399 -304.954776) (xy 32.771802 -304.962599) (xy 32.820408 -304.978058)
			(xy 32.866069 -305.000789) (xy 32.887158 -305.015138) (xy 32.893681 -305.019444) (xy 32.908557 -305.024219)
			(xy 32.916368 -305.024536) (xy 33.432496 -305.024536) (xy 33.437838 -305.024834) (xy 33.445382 -305.032401)
			(xy 33.445704 -305.037744) (xy 33.445704 -305.038252) (xy 33.445704 -305.532536) (xy 39.489888 -305.532536)
			(xy 39.489888 -305.037998) (xy 39.490444 -305.032646) (xy 39.498 -305.025063) (xy 39.50335 -305.024536)
			(xy 40.019478 -305.024536) (xy 40.027288 -305.024224) (xy 40.04216 -305.019438) (xy 40.048688 -305.015138)
			(xy 40.069777 -305.000789) (xy 40.115438 -304.978058) (xy 40.164044 -304.962599) (xy 40.214447 -304.954776)
			(xy 40.265453 -304.954776) (xy 40.315856 -304.962599) (xy 40.364462 -304.978058) (xy 40.410123 -305.000789)
			(xy 40.431212 -305.015138) (xy 40.437745 -305.019427) (xy 40.452614 -305.024212) (xy 40.460422 -305.024536)
			(xy 40.97655 -305.024536) (xy 40.981919 -305.025017) (xy 40.989502 -305.032627) (xy 40.990012 -305.037998)
			(xy 40.990012 -305.532536) (xy 47.034196 -305.532536) (xy 47.034196 -305.037998) (xy 47.034716 -305.032704)
			(xy 47.042122 -305.025135) (xy 47.047404 -305.024536) (xy 47.563532 -305.024536) (xy 47.571341 -305.024204)
			(xy 47.586213 -305.019432) (xy 47.592742 -305.015138) (xy 47.613831 -305.000789) (xy 47.659492 -304.978058)
			(xy 47.708098 -304.962599) (xy 47.758501 -304.954776) (xy 47.809507 -304.954776) (xy 47.85991 -304.962599)
			(xy 47.908516 -304.978058) (xy 47.954177 -305.000789) (xy 47.975266 -305.015138) (xy 47.981809 -305.019409)
			(xy 47.99667 -305.024206) (xy 48.004476 -305.024536) (xy 48.520604 -305.024536) (xy 48.525948 -305.024829)
			(xy 48.533491 -305.032399) (xy 48.533812 -305.037744) (xy 48.533812 -305.038252) (xy 48.533812 -305.532536)
			(xy 54.577996 -305.532536) (xy 54.577996 -305.037998) (xy 54.578545 -305.032644) (xy 54.586106 -305.025061)
			(xy 54.591458 -305.024536) (xy 56.064658 -305.024536) (xy 56.070087 -305.024907) (xy 56.077775 -305.03257)
			(xy 56.07812 -305.037998) (xy 56.07812 -305.532536) (xy 56.07763 -305.5378) (xy 56.070177 -305.54524)
			(xy 56.064912 -305.545744) (xy 54.591458 -305.545744) (xy 54.586145 -305.545303) (xy 54.578575 -305.537841)
			(xy 54.577996 -305.532536) (xy 48.533812 -305.532536) (xy 48.533329 -305.537802) (xy 48.525871 -305.545242)
			(xy 48.520604 -305.545744) (xy 48.00473 -305.545744) (xy 47.996854 -305.54601) (xy 47.98185 -305.550809)
			(xy 47.975266 -305.555142) (xy 47.954188 -305.569533) (xy 47.908543 -305.592361) (xy 47.859938 -305.607919)
			(xy 47.809521 -305.615839) (xy 47.784004 -305.616356) (xy 47.758483 -305.615889) (xy 47.708055 -305.607989)
			(xy 47.659443 -305.592423) (xy 47.613806 -305.569561) (xy 47.592742 -305.555142) (xy 47.586163 -305.550806)
			(xy 47.571153 -305.546031) (xy 47.563278 -305.545744) (xy 47.047404 -305.545744) (xy 47.04215 -305.545206)
			(xy 47.03471 -305.537788) (xy 47.034196 -305.532536) (xy 40.990012 -305.532536) (xy 40.989529 -305.537802)
			(xy 40.982071 -305.545242) (xy 40.976804 -305.545744) (xy 40.976296 -305.545744) (xy 40.460676 -305.545744)
			(xy 40.452801 -305.54603) (xy 40.437797 -305.550815) (xy 40.431212 -305.555142) (xy 40.410149 -305.569556)
			(xy 40.364499 -305.592379) (xy 40.315889 -305.607931) (xy 40.265468 -305.615843) (xy 40.23995 -305.616356)
			(xy 40.21443 -305.615866) (xy 40.164002 -305.607973) (xy 40.115391 -305.592413) (xy 40.069753 -305.569558)
			(xy 40.048688 -305.555142) (xy 40.042098 -305.550824) (xy 40.027097 -305.546038) (xy 40.019224 -305.545744)
			(xy 39.50335 -305.545744) (xy 39.498048 -305.545242) (xy 39.490473 -305.537827) (xy 39.489888 -305.532536)
			(xy 33.445704 -305.532536) (xy 33.445229 -305.537804) (xy 33.437765 -305.545245) (xy 33.432496 -305.545744)
			(xy 32.916622 -305.545744) (xy 32.908749 -305.54605) (xy 32.893745 -305.550821) (xy 32.887158 -305.555142)
			(xy 32.866082 -305.569536) (xy 32.820437 -305.592364) (xy 32.77183 -305.607921) (xy 32.721413 -305.615839)
			(xy 32.695896 -305.616356) (xy 32.670375 -305.615893) (xy 32.619946 -305.607992) (xy 32.571335 -305.592424)
			(xy 32.525698 -305.569561) (xy 32.504634 -305.555142) (xy 32.498034 -305.550841) (xy 32.483041 -305.546045)
			(xy 32.47517 -305.545744) (xy 31.959296 -305.545744) (xy 31.954041 -305.545212) (xy 31.946601 -305.537789)
			(xy 31.946088 -305.532536) (xy 25.901904 -305.532536) (xy 25.901429 -305.537804) (xy 25.893965 -305.545245)
			(xy 25.888696 -305.545744) (xy 25.372822 -305.545744) (xy 25.364949 -305.54605) (xy 25.349945 -305.550821)
			(xy 25.343358 -305.555142) (xy 25.322282 -305.569536) (xy 25.276637 -305.592364) (xy 25.22803 -305.607921)
			(xy 25.177613 -305.615839) (xy 25.152096 -305.616356) (xy 25.126575 -305.615893) (xy 25.076146 -305.607992)
			(xy 25.027535 -305.592424) (xy 24.981898 -305.569561) (xy 24.960834 -305.555142) (xy 24.954234 -305.550841)
			(xy 24.939241 -305.546045) (xy 24.93137 -305.545744) (xy 24.415496 -305.545744) (xy 24.410241 -305.545212)
			(xy 24.402801 -305.537789) (xy 24.402288 -305.532536) (xy 18.358104 -305.532536) (xy 18.357629 -305.537804)
			(xy 18.350165 -305.545245) (xy 18.344896 -305.545744) (xy 18.344388 -305.545744) (xy 17.828768 -305.545744)
			(xy 17.820893 -305.546027) (xy 17.805889 -305.550814) (xy 17.799304 -305.555142) (xy 17.778215 -305.569516)
			(xy 17.732575 -305.592349) (xy 17.683972 -305.607911) (xy 17.633558 -305.615836) (xy 17.608042 -305.616356)
			(xy 17.582522 -305.61587) (xy 17.532094 -305.607976) (xy 17.483482 -305.592415) (xy 17.437844 -305.569558)
			(xy 17.41678 -305.555142) (xy 17.410192 -305.550821) (xy 17.395189 -305.546037) (xy 17.387316 -305.545744)
			(xy 16.871442 -305.545744) (xy 16.866139 -305.545247) (xy 16.858565 -305.537828) (xy 16.85798 -305.532536)
			(xy 2.509012 -305.532536) (xy 2.509012 -306.38242) (xy 20.958048 -306.38242) (xy 20.958048 -305.887882)
			(xy 20.958539 -305.882513) (xy 20.96614 -305.874928) (xy 20.97151 -305.87442) (xy 21.487638 -305.87442)
			(xy 21.495447 -305.874093) (xy 21.510319 -305.869318) (xy 21.516848 -305.865022) (xy 21.537937 -305.850673)
			(xy 21.583598 -305.827942) (xy 21.632204 -305.812483) (xy 21.682607 -305.80466) (xy 21.733613 -305.80466)
			(xy 21.784016 -305.812483) (xy 21.832622 -305.827942) (xy 21.878283 -305.850673) (xy 21.899372 -305.865022)
			(xy 21.905915 -305.869294) (xy 21.920776 -305.87409) (xy 21.928582 -305.87442) (xy 22.44471 -305.87442)
			(xy 22.450071 -305.874942) (xy 22.457655 -305.882522) (xy 22.458172 -305.887882) (xy 22.458172 -306.38242)
			(xy 28.502356 -306.38242) (xy 28.502356 -305.887882) (xy 28.502813 -305.882572) (xy 28.510263 -305.875001)
			(xy 28.515564 -305.87442) (xy 29.031692 -305.87442) (xy 29.039503 -305.874116) (xy 29.054375 -305.869325)
			(xy 29.060902 -305.865022) (xy 29.081991 -305.850673) (xy 29.127652 -305.827942) (xy 29.176258 -305.812483)
			(xy 29.226661 -305.80466) (xy 29.277667 -305.80466) (xy 29.32807 -305.812483) (xy 29.376676 -305.827942)
			(xy 29.422337 -305.850673) (xy 29.443426 -305.865022) (xy 29.449957 -305.869315) (xy 29.464827 -305.874098)
			(xy 29.472636 -305.87442) (xy 29.988764 -305.87442) (xy 29.994098 -305.874754) (xy 30.001643 -305.882294)
			(xy 30.001972 -305.887628) (xy 30.001972 -305.888136) (xy 30.001972 -306.38242) (xy 36.046156 -306.38242)
			(xy 36.046156 -305.887882) (xy 36.046613 -305.882572) (xy 36.054063 -305.875001) (xy 36.059364 -305.87442)
			(xy 36.575492 -305.87442) (xy 36.583303 -305.874116) (xy 36.598175 -305.869325) (xy 36.604702 -305.865022)
			(xy 36.625791 -305.850673) (xy 36.671452 -305.827942) (xy 36.720058 -305.812483) (xy 36.770461 -305.80466)
			(xy 36.821467 -305.80466) (xy 36.87187 -305.812483) (xy 36.920476 -305.827942) (xy 36.966137 -305.850673)
			(xy 36.987226 -305.865022) (xy 36.993757 -305.869315) (xy 37.008627 -305.874098) (xy 37.016436 -305.87442)
			(xy 37.532564 -305.87442) (xy 37.537898 -305.874754) (xy 37.545443 -305.882294) (xy 37.545772 -305.887628)
			(xy 37.545772 -305.888136) (xy 37.545772 -306.38242) (xy 43.589956 -306.38242) (xy 43.589956 -305.887882)
			(xy 43.59044 -305.882511) (xy 43.598046 -305.874926) (xy 43.603418 -305.87442) (xy 44.119546 -305.87442)
			(xy 44.127355 -305.874097) (xy 44.142228 -305.869319) (xy 44.148756 -305.865022) (xy 44.169845 -305.850673)
			(xy 44.215506 -305.827942) (xy 44.264112 -305.812483) (xy 44.314515 -305.80466) (xy 44.365521 -305.80466)
			(xy 44.415924 -305.812483) (xy 44.46453 -305.827942) (xy 44.510191 -305.850673) (xy 44.53128 -305.865022)
			(xy 44.537821 -305.869297) (xy 44.552684 -305.874092) (xy 44.56049 -305.87442) (xy 45.076618 -305.87442)
			(xy 45.08198 -305.874936) (xy 45.089564 -305.88252) (xy 45.09008 -305.887882) (xy 45.09008 -306.38242)
			(xy 51.134264 -306.38242) (xy 51.134264 -305.887882) (xy 51.134714 -305.88257) (xy 51.142168 -305.874998)
			(xy 51.147472 -305.87442) (xy 51.6636 -305.87442) (xy 51.671412 -305.87412) (xy 51.686283 -305.869326)
			(xy 51.69281 -305.865022) (xy 51.713899 -305.850673) (xy 51.75956 -305.827942) (xy 51.808166 -305.812483)
			(xy 51.858569 -305.80466) (xy 51.909575 -305.80466) (xy 51.959978 -305.812483) (xy 52.008584 -305.827942)
			(xy 52.054245 -305.850673) (xy 52.075334 -305.865022) (xy 52.081863 -305.869318) (xy 52.096735 -305.874099)
			(xy 52.104544 -305.87442) (xy 52.620672 -305.87442) (xy 52.626007 -305.874748) (xy 52.633552 -305.882293)
			(xy 52.63388 -305.887628) (xy 52.63388 -305.888136) (xy 52.63388 -306.38242) (xy 58.678064 -306.38242)
			(xy 58.678064 -305.887882) (xy 58.67837 -305.882438) (xy 58.686081 -305.874752) (xy 58.691526 -305.87442)
			(xy 60.164726 -305.87442) (xy 60.170089 -305.874931) (xy 60.177672 -305.882519) (xy 60.178188 -305.887882)
			(xy 60.178188 -306.38242) (xy 60.177717 -306.38769) (xy 60.170251 -306.395133) (xy 60.16498 -306.395628)
			(xy 60.164472 -306.395628) (xy 58.691526 -306.395628) (xy 58.686218 -306.395156) (xy 58.678643 -306.387719)
			(xy 58.678064 -306.38242) (xy 52.63388 -306.38242) (xy 52.633584 -306.387762) (xy 52.626015 -306.395303)
			(xy 52.620672 -306.395628) (xy 52.104798 -306.395628) (xy 52.096924 -306.395926) (xy 52.081921 -306.400703)
			(xy 52.075334 -306.405026) (xy 52.054264 -306.419428) (xy 52.008616 -306.442255) (xy 51.960008 -306.45781)
			(xy 51.909589 -306.465725) (xy 51.884072 -306.46624) (xy 51.858553 -306.465724) (xy 51.808127 -306.457836)
			(xy 51.759516 -306.442284) (xy 51.713876 -306.419437) (xy 51.69281 -306.405026) (xy 51.686216 -306.400715)
			(xy 51.671218 -306.395925) (xy 51.663346 -306.395628) (xy 51.147472 -306.395628) (xy 51.142211 -306.395126)
			(xy 51.134771 -306.387682) (xy 51.134264 -306.38242) (xy 45.09008 -306.38242) (xy 45.089784 -306.387762)
			(xy 45.082215 -306.395303) (xy 45.076872 -306.395628) (xy 45.076364 -306.395628) (xy 44.560744 -306.395628)
			(xy 44.552868 -306.395903) (xy 44.537865 -306.400696) (xy 44.53128 -306.405026) (xy 44.510197 -306.419409)
			(xy 44.464554 -306.44224) (xy 44.41595 -306.4578) (xy 44.365534 -306.465722) (xy 44.340018 -306.46624)
			(xy 44.314498 -306.465751) (xy 44.264071 -306.457855) (xy 44.21546 -306.442295) (xy 44.169821 -306.419441)
			(xy 44.148756 -306.405026) (xy 44.142174 -306.400694) (xy 44.127167 -306.395917) (xy 44.119292 -306.395628)
			(xy 43.603418 -306.395628) (xy 43.598108 -306.395161) (xy 43.590534 -306.38772) (xy 43.589956 -306.38242)
			(xy 37.545772 -306.38242) (xy 37.545483 -306.387764) (xy 37.537909 -306.395306) (xy 37.532564 -306.395628)
			(xy 37.01669 -306.395628) (xy 37.008816 -306.395923) (xy 36.993812 -306.400702) (xy 36.987226 -306.405026)
			(xy 36.966158 -306.419432) (xy 36.92051 -306.442258) (xy 36.871901 -306.457812) (xy 36.821482 -306.465726)
			(xy 36.795964 -306.46624) (xy 36.770445 -306.465728) (xy 36.720019 -306.457839) (xy 36.671408 -306.442285)
			(xy 36.625768 -306.419438) (xy 36.604702 -306.405026) (xy 36.59811 -306.400712) (xy 36.58311 -306.395924)
			(xy 36.575238 -306.395628) (xy 36.059364 -306.395628) (xy 36.054102 -306.395131) (xy 36.046663 -306.387683)
			(xy 36.046156 -306.38242) (xy 30.001972 -306.38242) (xy 30.001683 -306.387764) (xy 29.994109 -306.395306)
			(xy 29.988764 -306.395628) (xy 29.47289 -306.395628) (xy 29.465016 -306.395923) (xy 29.450012 -306.400702)
			(xy 29.443426 -306.405026) (xy 29.422358 -306.419432) (xy 29.37671 -306.442258) (xy 29.328101 -306.457812)
			(xy 29.277682 -306.465726) (xy 29.252164 -306.46624) (xy 29.226645 -306.465728) (xy 29.176219 -306.457839)
			(xy 29.127608 -306.442285) (xy 29.081968 -306.419438) (xy 29.060902 -306.405026) (xy 29.05431 -306.400712)
			(xy 29.03931 -306.395924) (xy 29.031438 -306.395628) (xy 28.515564 -306.395628) (xy 28.510302 -306.395131)
			(xy 28.502863 -306.387683) (xy 28.502356 -306.38242) (xy 22.458172 -306.38242) (xy 22.457883 -306.387764)
			(xy 22.450309 -306.395306) (xy 22.444964 -306.395628) (xy 22.444456 -306.395628) (xy 21.928836 -306.395628)
			(xy 21.92096 -306.395899) (xy 21.905956 -306.400695) (xy 21.899372 -306.405026) (xy 21.878291 -306.419412)
			(xy 21.832648 -306.442242) (xy 21.784043 -306.457802) (xy 21.733626 -306.465722) (xy 21.70811 -306.46624)
			(xy 21.68259 -306.465755) (xy 21.632163 -306.457858) (xy 21.583552 -306.442296) (xy 21.537913 -306.419441)
			(xy 21.516848 -306.405026) (xy 21.510268 -306.400691) (xy 21.495259 -306.395916) (xy 21.487384 -306.395628)
			(xy 20.97151 -306.395628) (xy 20.9662 -306.395166) (xy 20.958626 -306.387721) (xy 20.958048 -306.38242)
			(xy 2.509012 -306.38242) (xy 2.509012 -307.232558) (xy 16.85798 -307.232558) (xy 16.85798 -306.73802)
			(xy 16.858339 -306.732693) (xy 16.865862 -306.725152) (xy 16.871188 -306.724812) (xy 16.871696 -306.724812)
			(xy 17.38757 -306.724812) (xy 17.395381 -306.7245) (xy 17.410253 -306.719715) (xy 17.41678 -306.715414)
			(xy 17.437869 -306.701065) (xy 17.48353 -306.678334) (xy 17.532136 -306.662875) (xy 17.582539 -306.655052)
			(xy 17.633545 -306.655052) (xy 17.683948 -306.662875) (xy 17.732554 -306.678334) (xy 17.778215 -306.701065)
			(xy 17.799304 -306.715414) (xy 17.80584 -306.719697) (xy 17.820706 -306.724487) (xy 17.828514 -306.724812)
			(xy 18.344642 -306.724812) (xy 18.349945 -306.725292) (xy 18.357512 -306.732727) (xy 18.358104 -306.73802)
			(xy 18.358104 -307.232558) (xy 18.358077 -307.232812) (xy 24.402288 -307.232812) (xy 24.402288 -307.232304)
			(xy 24.402288 -306.73802) (xy 24.40264 -306.732691) (xy 24.410168 -306.725149) (xy 24.415496 -306.724812)
			(xy 24.931624 -306.724812) (xy 24.939437 -306.724523) (xy 24.954308 -306.719722) (xy 24.960834 -306.715414)
			(xy 24.981923 -306.701065) (xy 25.027584 -306.678334) (xy 25.07619 -306.662875) (xy 25.126593 -306.655052)
			(xy 25.177599 -306.655052) (xy 25.228002 -306.662875) (xy 25.276608 -306.678334) (xy 25.322269 -306.701065)
			(xy 25.343358 -306.715414) (xy 25.349882 -306.719718) (xy 25.364758 -306.724495) (xy 25.372568 -306.724812)
			(xy 25.888696 -306.724812) (xy 25.894033 -306.725132) (xy 25.901575 -306.732683) (xy 25.901904 -306.73802)
			(xy 25.901904 -307.232558) (xy 25.901878 -307.232812) (xy 31.946088 -307.232812) (xy 31.946088 -307.232304)
			(xy 31.946088 -306.73802) (xy 31.94644 -306.732691) (xy 31.953968 -306.725149) (xy 31.959296 -306.724812)
			(xy 32.475424 -306.724812) (xy 32.483237 -306.724523) (xy 32.498108 -306.719722) (xy 32.504634 -306.715414)
			(xy 32.525723 -306.701065) (xy 32.571384 -306.678334) (xy 32.61999 -306.662875) (xy 32.670393 -306.655052)
			(xy 32.721399 -306.655052) (xy 32.771802 -306.662875) (xy 32.820408 -306.678334) (xy 32.866069 -306.701065)
			(xy 32.887158 -306.715414) (xy 32.893682 -306.719718) (xy 32.908558 -306.724495) (xy 32.916368 -306.724812)
			(xy 33.432496 -306.724812) (xy 33.437833 -306.725132) (xy 33.445375 -306.732683) (xy 33.445704 -306.73802)
			(xy 33.445704 -307.232558) (xy 39.489888 -307.232558) (xy 39.489888 -306.73802) (xy 39.49024 -306.732691)
			(xy 39.497768 -306.725149) (xy 39.503096 -306.724812) (xy 39.503604 -306.724812) (xy 40.019478 -306.724812)
			(xy 40.027289 -306.724504) (xy 40.042161 -306.719716) (xy 40.048688 -306.715414) (xy 40.069777 -306.701065)
			(xy 40.115438 -306.678334) (xy 40.164044 -306.662875) (xy 40.214447 -306.655052) (xy 40.265453 -306.655052)
			(xy 40.315856 -306.662875) (xy 40.364462 -306.678334) (xy 40.410123 -306.701065) (xy 40.431212 -306.715414)
			(xy 40.437747 -306.7197) (xy 40.452614 -306.724488) (xy 40.460422 -306.724812) (xy 40.97655 -306.724812)
			(xy 40.981842 -306.725353) (xy 40.989414 -306.732742) (xy 40.990012 -306.73802) (xy 40.990012 -307.232558)
			(xy 40.989984 -307.232812) (xy 47.034196 -307.232812) (xy 47.034196 -307.232304) (xy 47.034196 -306.73802)
			(xy 47.03454 -306.732689) (xy 47.042074 -306.725147) (xy 47.047404 -306.724812) (xy 47.563532 -306.724812)
			(xy 47.571341 -306.724484) (xy 47.586213 -306.71971) (xy 47.592742 -306.715414) (xy 47.613831 -306.701065)
			(xy 47.659492 -306.678334) (xy 47.708098 -306.662875) (xy 47.758501 -306.655052) (xy 47.809507 -306.655052)
			(xy 47.85991 -306.662875) (xy 47.908516 -306.678334) (xy 47.954177 -306.701065) (xy 47.975266 -306.715414)
			(xy 47.981811 -306.719683) (xy 47.99667 -306.724481) (xy 48.004476 -306.724812) (xy 48.520604 -306.724812)
			(xy 48.525942 -306.725126) (xy 48.533483 -306.732682) (xy 48.533812 -306.73802) (xy 48.533812 -307.232558)
			(xy 54.577996 -307.232558) (xy 54.577996 -306.73802) (xy 54.57834 -306.732689) (xy 54.585874 -306.725147)
			(xy 54.591204 -306.724812) (xy 56.064658 -306.724812) (xy 56.069951 -306.725348) (xy 56.077522 -306.73274)
			(xy 56.07812 -306.73802) (xy 56.07812 -307.232558) (xy 56.077788 -307.237997) (xy 56.070097 -307.245688)
			(xy 56.064658 -307.24602) (xy 54.591458 -307.24602) (xy 54.586079 -307.245573) (xy 54.578493 -307.23794)
			(xy 54.577996 -307.232558) (xy 48.533812 -307.232558) (xy 48.533343 -307.237868) (xy 48.525905 -307.245445)
			(xy 48.520604 -307.24602) (xy 48.00473 -307.24602) (xy 47.996921 -307.246343) (xy 47.982049 -307.251122)
			(xy 47.97552 -307.255418) (xy 47.954388 -307.269751) (xy 47.908668 -307.292482) (xy 47.859998 -307.307917)
			(xy 47.809534 -307.315689) (xy 47.784004 -307.316124) (xy 47.758473 -307.315693) (xy 47.708009 -307.307916)
			(xy 47.659336 -307.292486) (xy 47.613609 -307.269767) (xy 47.592488 -307.255418) (xy 47.585957 -307.251125)
			(xy 47.571087 -307.246343) (xy 47.563278 -307.24602) (xy 47.047404 -307.24602) (xy 47.042145 -307.245504)
			(xy 47.034702 -307.238071) (xy 47.034196 -307.232812) (xy 40.989984 -307.232812) (xy 40.989427 -307.237905)
			(xy 40.981893 -307.24549) (xy 40.97655 -307.24602) (xy 40.460676 -307.24602) (xy 40.452865 -307.24632)
			(xy 40.437993 -307.251115) (xy 40.431466 -307.255418) (xy 40.410349 -307.269774) (xy 40.364624 -307.2925)
			(xy 40.315949 -307.307929) (xy 40.265481 -307.315693) (xy 40.23995 -307.316124) (xy 40.21442 -307.31567)
			(xy 40.163957 -307.3079) (xy 40.115284 -307.292477) (xy 40.069556 -307.269764) (xy 40.048434 -307.255418)
			(xy 40.041893 -307.251143) (xy 40.02703 -307.24635) (xy 40.019224 -307.24602) (xy 39.50335 -307.24602)
			(xy 39.49797 -307.245578) (xy 39.490385 -307.237941) (xy 39.489888 -307.232558) (xy 33.445704 -307.232558)
			(xy 33.445154 -307.237847) (xy 33.437771 -307.245418) (xy 33.432496 -307.24602) (xy 32.916622 -307.24602)
			(xy 32.908812 -307.246339) (xy 32.893941 -307.251121) (xy 32.887412 -307.255418) (xy 32.866282 -307.269754)
			(xy 32.820561 -307.292485) (xy 32.771891 -307.307919) (xy 32.721426 -307.315689) (xy 32.695896 -307.316124)
			(xy 32.670365 -307.315697) (xy 32.619901 -307.307919) (xy 32.571228 -307.292488) (xy 32.525501 -307.269767)
			(xy 32.50438 -307.255418) (xy 32.497851 -307.251122) (xy 32.482979 -307.246342) (xy 32.47517 -307.24602)
			(xy 31.959296 -307.24602) (xy 31.954036 -307.245509) (xy 31.946594 -307.238072) (xy 31.946088 -307.232812)
			(xy 25.901878 -307.232812) (xy 25.901354 -307.237847) (xy 25.893971 -307.245418) (xy 25.888696 -307.24602)
			(xy 25.372822 -307.24602) (xy 25.365012 -307.246339) (xy 25.350141 -307.251121) (xy 25.343612 -307.255418)
			(xy 25.322482 -307.269754) (xy 25.276761 -307.292485) (xy 25.228091 -307.307919) (xy 25.177626 -307.315689)
			(xy 25.152096 -307.316124) (xy 25.126565 -307.315697) (xy 25.076101 -307.307919) (xy 25.027428 -307.292488)
			(xy 24.981701 -307.269767) (xy 24.96058 -307.255418) (xy 24.954051 -307.251122) (xy 24.939179 -307.246342)
			(xy 24.93137 -307.24602) (xy 24.415496 -307.24602) (xy 24.410236 -307.245509) (xy 24.402794 -307.238072)
			(xy 24.402288 -307.232812) (xy 18.358077 -307.232812) (xy 18.357526 -307.237907) (xy 18.349988 -307.245493)
			(xy 18.344642 -307.24602) (xy 17.828768 -307.24602) (xy 17.82096 -307.246359) (xy 17.806089 -307.251127)
			(xy 17.799558 -307.255418) (xy 17.778443 -307.269778) (xy 17.732717 -307.292503) (xy 17.684042 -307.30793)
			(xy 17.633574 -307.315693) (xy 17.608042 -307.316124) (xy 17.582512 -307.315674) (xy 17.532049 -307.307903)
			(xy 17.483376 -307.292478) (xy 17.437648 -307.269764) (xy 17.416526 -307.255418) (xy 17.409987 -307.25114)
			(xy 17.395123 -307.246349) (xy 17.387316 -307.24602) (xy 16.871442 -307.24602) (xy 16.866003 -307.245688)
			(xy 16.858312 -307.237997) (xy 16.85798 -307.232558) (xy 2.509012 -307.232558) (xy 2.509012 -308.082442)
			(xy 20.958048 -308.082442) (xy 20.958048 -307.587904) (xy 20.958593 -307.582652) (xy 20.966006 -307.575212)
			(xy 20.971256 -307.574696) (xy 20.971764 -307.574696) (xy 21.487638 -307.574696) (xy 21.495446 -307.574357)
			(xy 21.510317 -307.569589) (xy 21.516848 -307.565298) (xy 21.537937 -307.550949) (xy 21.583598 -307.528218)
			(xy 21.632204 -307.512759) (xy 21.682607 -307.504936) (xy 21.733613 -307.504936) (xy 21.784016 -307.512759)
			(xy 21.832622 -307.528218) (xy 21.878283 -307.550949) (xy 21.899372 -307.565298) (xy 21.905911 -307.569577)
			(xy 21.920775 -307.574368) (xy 21.928582 -307.574696) (xy 22.44471 -307.574696) (xy 22.450005 -307.575211)
			(xy 22.457573 -307.58262) (xy 22.458172 -307.587904) (xy 22.458172 -308.082442) (xy 22.458149 -308.082696)
			(xy 28.502356 -308.082696) (xy 28.502356 -308.082188) (xy 28.502356 -307.587904) (xy 28.502894 -307.58265)
			(xy 28.510312 -307.57521) (xy 28.515564 -307.574696) (xy 29.031692 -307.574696) (xy 29.039502 -307.57438)
			(xy 29.054373 -307.569596) (xy 29.060902 -307.565298) (xy 29.081991 -307.550949) (xy 29.127652 -307.528218)
			(xy 29.176258 -307.512759) (xy 29.226661 -307.504936) (xy 29.277667 -307.504936) (xy 29.32807 -307.512759)
			(xy 29.376676 -307.528218) (xy 29.422337 -307.550949) (xy 29.443426 -307.565298) (xy 29.449953 -307.569598)
			(xy 29.464826 -307.574376) (xy 29.472636 -307.574696) (xy 29.988764 -307.574696) (xy 29.994092 -307.575051)
			(xy 30.001636 -307.582576) (xy 30.001972 -307.587904) (xy 30.001972 -308.082442) (xy 30.00195 -308.082696)
			(xy 36.046156 -308.082696) (xy 36.046156 -308.082188) (xy 36.046156 -307.587904) (xy 36.046694 -307.58265)
			(xy 36.054112 -307.57521) (xy 36.059364 -307.574696) (xy 36.575492 -307.574696) (xy 36.583302 -307.57438)
			(xy 36.598173 -307.569596) (xy 36.604702 -307.565298) (xy 36.625791 -307.550949) (xy 36.671452 -307.528218)
			(xy 36.720058 -307.512759) (xy 36.770461 -307.504936) (xy 36.821467 -307.504936) (xy 36.87187 -307.512759)
			(xy 36.920476 -307.528218) (xy 36.966137 -307.550949) (xy 36.987226 -307.565298) (xy 36.993753 -307.569598)
			(xy 37.008626 -307.574376) (xy 37.016436 -307.574696) (xy 37.532564 -307.574696) (xy 37.537892 -307.575051)
			(xy 37.545436 -307.582576) (xy 37.545772 -307.587904) (xy 37.545772 -308.082442) (xy 43.589956 -308.082442)
			(xy 43.589956 -307.587904) (xy 43.590494 -307.58265) (xy 43.597912 -307.57521) (xy 43.603164 -307.574696)
			(xy 43.603672 -307.574696) (xy 44.119546 -307.574696) (xy 44.127354 -307.57436) (xy 44.142226 -307.56959)
			(xy 44.148756 -307.565298) (xy 44.169845 -307.550949) (xy 44.215506 -307.528218) (xy 44.264112 -307.512759)
			(xy 44.314515 -307.504936) (xy 44.365521 -307.504936) (xy 44.415924 -307.512759) (xy 44.46453 -307.528218)
			(xy 44.510191 -307.550949) (xy 44.53128 -307.565298) (xy 44.537817 -307.56958) (xy 44.552683 -307.574369)
			(xy 44.56049 -307.574696) (xy 45.076618 -307.574696) (xy 45.081914 -307.575206) (xy 45.089482 -307.582619)
			(xy 45.09008 -307.587904) (xy 45.09008 -308.082442) (xy 45.090056 -308.082696) (xy 51.134264 -308.082696)
			(xy 51.134264 -308.082188) (xy 51.134264 -307.587904) (xy 51.134794 -307.582648) (xy 51.142218 -307.575207)
			(xy 51.147472 -307.574696) (xy 51.6636 -307.574696) (xy 51.67141 -307.574383) (xy 51.686282 -307.569597)
			(xy 51.69281 -307.565298) (xy 51.713899 -307.550949) (xy 51.75956 -307.528218) (xy 51.808166 -307.512759)
			(xy 51.858569 -307.504936) (xy 51.909575 -307.504936) (xy 51.959978 -307.512759) (xy 52.008584 -307.528218)
			(xy 52.054245 -307.550949) (xy 52.075334 -307.565298) (xy 52.081859 -307.569601) (xy 52.096734 -307.574377)
			(xy 52.104544 -307.574696) (xy 52.620672 -307.574696) (xy 52.626002 -307.575046) (xy 52.633544 -307.582575)
			(xy 52.63388 -307.587904) (xy 52.63388 -308.082442) (xy 58.678064 -308.082442) (xy 58.678064 -307.587904)
			(xy 58.678594 -307.582648) (xy 58.686018 -307.575207) (xy 58.691272 -307.574696) (xy 58.69178 -307.574696)
			(xy 60.164726 -307.574696) (xy 60.170023 -307.5752) (xy 60.17759 -307.582618) (xy 60.178188 -307.587904)
			(xy 60.178188 -308.082442) (xy 60.178164 -308.082696) (xy 167.778176 -308.082696) (xy 167.778176 -307.587904)
			(xy 167.778696 -307.582646) (xy 167.786126 -307.575204) (xy 167.791384 -307.574696) (xy 169.264584 -307.574696)
			(xy 169.269915 -307.575038) (xy 169.277457 -307.582573) (xy 169.277792 -307.587904) (xy 169.277792 -308.082442)
			(xy 175.321976 -308.082442) (xy 175.321976 -307.587904) (xy 175.322496 -307.582646) (xy 175.329926 -307.575204)
			(xy 175.335184 -307.574696) (xy 175.335692 -307.574696) (xy 175.851566 -307.574696) (xy 175.859375 -307.574369)
			(xy 175.874246 -307.569592) (xy 175.880776 -307.565298) (xy 175.901865 -307.550949) (xy 175.947526 -307.528218)
			(xy 175.996132 -307.512759) (xy 176.046535 -307.504936) (xy 176.097541 -307.504936) (xy 176.147944 -307.512759)
			(xy 176.19655 -307.528218) (xy 176.242211 -307.550949) (xy 176.2633 -307.565298) (xy 176.269832 -307.569588)
			(xy 176.284702 -307.574372) (xy 176.29251 -307.574696) (xy 176.808638 -307.574696) (xy 176.813937 -307.575192)
			(xy 176.821503 -307.582616) (xy 176.8221 -307.587904) (xy 176.8221 -308.082442) (xy 176.822075 -308.082696)
			(xy 182.866284 -308.082696) (xy 182.866284 -308.082188) (xy 182.866284 -307.587904) (xy 182.866797 -307.582644)
			(xy 182.874232 -307.575201) (xy 182.879492 -307.574696) (xy 183.39562 -307.574696) (xy 183.403431 -307.574391)
			(xy 183.418302 -307.569599) (xy 183.42483 -307.565298) (xy 183.445919 -307.550949) (xy 183.49158 -307.528218)
			(xy 183.540186 -307.512759) (xy 183.590589 -307.504936) (xy 183.641595 -307.504936) (xy 183.691998 -307.512759)
			(xy 183.740604 -307.528218) (xy 183.786265 -307.550949) (xy 183.807354 -307.565298) (xy 183.813874 -307.569609)
			(xy 183.828753 -307.57438) (xy 183.836564 -307.574696) (xy 184.352692 -307.574696) (xy 184.358024 -307.575032)
			(xy 184.365566 -307.582572) (xy 184.3659 -307.587904) (xy 184.3659 -308.082442) (xy 190.410084 -308.082442)
			(xy 190.410084 -307.587904) (xy 190.410597 -307.582644) (xy 190.418032 -307.575201) (xy 190.423292 -307.574696)
			(xy 190.4238 -307.574696) (xy 190.939674 -307.574696) (xy 190.947483 -307.574372) (xy 190.962355 -307.569593)
			(xy 190.968884 -307.565298) (xy 190.989973 -307.550949) (xy 191.035634 -307.528218) (xy 191.08424 -307.512759)
			(xy 191.134643 -307.504936) (xy 191.185649 -307.504936) (xy 191.236052 -307.512759) (xy 191.284658 -307.528218)
			(xy 191.330319 -307.550949) (xy 191.351408 -307.565298) (xy 191.357939 -307.569591) (xy 191.372809 -307.574373)
			(xy 191.380618 -307.574696) (xy 191.896746 -307.574696) (xy 191.902034 -307.575254) (xy 191.909605 -307.582631)
			(xy 191.910208 -307.587904) (xy 191.910208 -308.082442) (xy 191.910183 -308.082696) (xy 197.954392 -308.082696)
			(xy 197.954392 -308.082188) (xy 197.954392 -307.587904) (xy 197.95473 -307.582572) (xy 197.962268 -307.575031)
			(xy 197.9676 -307.574696) (xy 198.483728 -307.574696) (xy 198.491539 -307.574395) (xy 198.506411 -307.5696)
			(xy 198.512938 -307.565298) (xy 198.534027 -307.550949) (xy 198.579688 -307.528218) (xy 198.628294 -307.512759)
			(xy 198.678697 -307.504936) (xy 198.729703 -307.504936) (xy 198.780106 -307.512759) (xy 198.828712 -307.528218)
			(xy 198.874373 -307.550949) (xy 198.895462 -307.565298) (xy 198.902003 -307.569573) (xy 198.916866 -307.574366)
			(xy 198.924672 -307.574696) (xy 199.4408 -307.574696) (xy 199.446133 -307.575027) (xy 199.453675 -307.582571)
			(xy 199.454008 -307.587904) (xy 199.454008 -308.082442) (xy 199.453984 -308.082696) (xy 205.498192 -308.082696)
			(xy 205.498192 -308.082188) (xy 205.498192 -307.587904) (xy 205.49853 -307.582572) (xy 205.506068 -307.575031)
			(xy 205.5114 -307.574696) (xy 206.027528 -307.574696) (xy 206.035339 -307.574395) (xy 206.050211 -307.5696)
			(xy 206.056738 -307.565298) (xy 206.077827 -307.550949) (xy 206.123488 -307.528218) (xy 206.172094 -307.512759)
			(xy 206.222497 -307.504936) (xy 206.273503 -307.504936) (xy 206.323906 -307.512759) (xy 206.372512 -307.528218)
			(xy 206.418173 -307.550949) (xy 206.439262 -307.565298) (xy 206.445803 -307.569573) (xy 206.460666 -307.574366)
			(xy 206.468472 -307.574696) (xy 206.9846 -307.574696) (xy 206.989933 -307.575027) (xy 206.997475 -307.582571)
			(xy 206.997808 -307.587904) (xy 206.997808 -308.082188) (xy 268.898116 -308.082188) (xy 268.898116 -307.58765)
			(xy 268.898615 -307.582285) (xy 268.906212 -307.574704) (xy 268.911578 -307.574188) (xy 269.427706 -307.574188)
			(xy 269.435517 -307.573879) (xy 269.450388 -307.56909) (xy 269.456916 -307.56479) (xy 269.478005 -307.550441)
			(xy 269.523666 -307.52771) (xy 269.572272 -307.512251) (xy 269.622675 -307.504428) (xy 269.673681 -307.504428)
			(xy 269.724084 -307.512251) (xy 269.77269 -307.52771) (xy 269.818351 -307.550441) (xy 269.83944 -307.56479)
			(xy 269.845964 -307.569094) (xy 269.86084 -307.57387) (xy 269.86865 -307.574188) (xy 270.384778 -307.574188)
			(xy 270.390127 -307.57476) (xy 270.397711 -307.582304) (xy 270.39824 -307.58765) (xy 270.39824 -308.082188)
			(xy 276.442424 -308.082188) (xy 276.442424 -307.58765) (xy 276.442955 -307.582356) (xy 276.45035 -307.574783)
			(xy 276.455632 -307.574188) (xy 276.97176 -307.574188) (xy 276.979569 -307.57386) (xy 276.99444 -307.569084)
			(xy 277.00097 -307.56479) (xy 277.022059 -307.550441) (xy 277.06772 -307.52771) (xy 277.116326 -307.512251)
			(xy 277.166729 -307.504428) (xy 277.217735 -307.504428) (xy 277.268138 -307.512251) (xy 277.316744 -307.52771)
			(xy 277.362405 -307.550441) (xy 277.383494 -307.56479) (xy 277.390028 -307.569077) (xy 277.404896 -307.573863)
			(xy 277.412704 -307.574188) (xy 277.928832 -307.574188) (xy 277.934098 -307.574673) (xy 277.941538 -307.582129)
			(xy 277.94204 -307.587396) (xy 277.94204 -307.587904) (xy 277.94204 -308.082188) (xy 283.986224 -308.082188)
			(xy 283.986224 -307.58765) (xy 283.986755 -307.582356) (xy 283.99415 -307.574783) (xy 283.999432 -307.574188)
			(xy 284.51556 -307.574188) (xy 284.523369 -307.57386) (xy 284.53824 -307.569084) (xy 284.54477 -307.56479)
			(xy 284.565859 -307.550441) (xy 284.61152 -307.52771) (xy 284.660126 -307.512251) (xy 284.710529 -307.504428)
			(xy 284.761535 -307.504428) (xy 284.811938 -307.512251) (xy 284.860544 -307.52771) (xy 284.906205 -307.550441)
			(xy 284.927294 -307.56479) (xy 284.933828 -307.569077) (xy 284.948696 -307.573863) (xy 284.956504 -307.574188)
			(xy 285.472632 -307.574188) (xy 285.477898 -307.574673) (xy 285.485338 -307.582129) (xy 285.48584 -307.587396)
			(xy 285.48584 -307.587904) (xy 285.48584 -308.082188) (xy 291.530024 -308.082188) (xy 291.530024 -307.58765)
			(xy 291.530516 -307.582283) (xy 291.538118 -307.574702) (xy 291.543486 -307.574188) (xy 292.059614 -307.574188)
			(xy 292.067425 -307.573882) (xy 292.082296 -307.569091) (xy 292.088824 -307.56479) (xy 292.109913 -307.550441)
			(xy 292.155574 -307.52771) (xy 292.20418 -307.512251) (xy 292.254583 -307.504428) (xy 292.305589 -307.504428)
			(xy 292.355992 -307.512251) (xy 292.404598 -307.52771) (xy 292.450259 -307.550441) (xy 292.471348 -307.56479)
			(xy 292.47787 -307.569098) (xy 292.492747 -307.573871) (xy 292.500558 -307.574188) (xy 293.016686 -307.574188)
			(xy 293.022036 -307.574755) (xy 293.02962 -307.582302) (xy 293.030148 -307.58765) (xy 293.030148 -308.082188)
			(xy 299.074332 -308.082188) (xy 299.074332 -307.58765) (xy 299.074856 -307.582354) (xy 299.082256 -307.57478)
			(xy 299.08754 -307.574188) (xy 299.603668 -307.574188) (xy 299.611477 -307.573863) (xy 299.626349 -307.569085)
			(xy 299.632878 -307.56479) (xy 299.653967 -307.550441) (xy 299.699628 -307.52771) (xy 299.748234 -307.512251)
			(xy 299.798637 -307.504428) (xy 299.849643 -307.504428) (xy 299.900046 -307.512251) (xy 299.948652 -307.52771)
			(xy 299.994313 -307.550441) (xy 300.015402 -307.56479) (xy 300.021934 -307.56908) (xy 300.036804 -307.573864)
			(xy 300.044612 -307.574188) (xy 300.56074 -307.574188) (xy 300.566007 -307.574668) (xy 300.573447 -307.582128)
			(xy 300.573948 -307.587396) (xy 300.573948 -307.587904) (xy 300.573948 -308.082188) (xy 306.618132 -308.082188)
			(xy 306.618132 -307.58765) (xy 306.618617 -307.582281) (xy 306.626224 -307.574699) (xy 306.631594 -307.574188)
			(xy 308.104794 -307.574188) (xy 308.110145 -307.574749) (xy 308.117729 -307.582301) (xy 308.118256 -307.58765)
			(xy 308.118256 -308.082188) (xy 308.117702 -308.087438) (xy 308.110295 -308.094878) (xy 308.105048 -308.095396)
			(xy 308.10454 -308.095396) (xy 306.631594 -308.095396) (xy 306.626297 -308.094885) (xy 306.618729 -308.087473)
			(xy 306.618132 -308.082188) (xy 300.573948 -308.082188) (xy 300.573401 -308.08744) (xy 300.56599 -308.094881)
			(xy 300.56074 -308.095396) (xy 300.044866 -308.095396) (xy 300.03699 -308.095669) (xy 300.021986 -308.100462)
			(xy 300.015402 -308.104794) (xy 299.994318 -308.119175) (xy 299.948675 -308.142005) (xy 299.900071 -308.157565)
			(xy 299.849656 -308.165488) (xy 299.82414 -308.166008) (xy 299.79862 -308.165514) (xy 299.748193 -308.15762)
			(xy 299.699582 -308.142062) (xy 299.653943 -308.119208) (xy 299.632878 -308.104794) (xy 299.626294 -308.100467)
			(xy 299.611288 -308.095688) (xy 299.603414 -308.095396) (xy 299.08754 -308.095396) (xy 299.08221 -308.095045)
			(xy 299.074666 -308.087517) (xy 299.074332 -308.082188) (xy 293.030148 -308.082188) (xy 293.029601 -308.08744)
			(xy 293.02219 -308.094881) (xy 293.01694 -308.095396) (xy 293.016432 -308.095396) (xy 292.500812 -308.095396)
			(xy 292.492938 -308.095689) (xy 292.477933 -308.100468) (xy 292.471348 -308.104794) (xy 292.450279 -308.119198)
			(xy 292.404631 -308.142023) (xy 292.356022 -308.157576) (xy 292.305603 -308.165492) (xy 292.280086 -308.166008)
			(xy 292.254567 -308.165491) (xy 292.204141 -308.157604) (xy 292.15553 -308.142052) (xy 292.10989 -308.119205)
			(xy 292.088824 -308.104794) (xy 292.082229 -308.100485) (xy 292.067232 -308.095695) (xy 292.05936 -308.095396)
			(xy 291.543486 -308.095396) (xy 291.538188 -308.094891) (xy 291.53062 -308.087475) (xy 291.530024 -308.082188)
			(xy 285.48584 -308.082188) (xy 285.4853 -308.087442) (xy 285.477884 -308.094883) (xy 285.472632 -308.095396)
			(xy 284.956758 -308.095396) (xy 284.948882 -308.095665) (xy 284.933877 -308.100461) (xy 284.927294 -308.104794)
			(xy 284.906212 -308.119179) (xy 284.860568 -308.142007) (xy 284.811964 -308.157567) (xy 284.761548 -308.165489)
			(xy 284.736032 -308.166008) (xy 284.710512 -308.165518) (xy 284.660085 -308.157623) (xy 284.611473 -308.142063)
			(xy 284.565835 -308.119209) (xy 284.54477 -308.104794) (xy 284.538187 -308.100464) (xy 284.52318 -308.095687)
			(xy 284.515306 -308.095396) (xy 283.999432 -308.095396) (xy 283.994101 -308.09505) (xy 283.986558 -308.087518)
			(xy 283.986224 -308.082188) (xy 277.94204 -308.082188) (xy 277.9415 -308.087442) (xy 277.934084 -308.094883)
			(xy 277.928832 -308.095396) (xy 277.412958 -308.095396) (xy 277.405082 -308.095665) (xy 277.390077 -308.100461)
			(xy 277.383494 -308.104794) (xy 277.362412 -308.119179) (xy 277.316768 -308.142007) (xy 277.268164 -308.157567)
			(xy 277.217748 -308.165489) (xy 277.192232 -308.166008) (xy 277.166712 -308.165518) (xy 277.116285 -308.157623)
			(xy 277.067673 -308.142063) (xy 277.022035 -308.119209) (xy 277.00097 -308.104794) (xy 276.994387 -308.100464)
			(xy 276.97938 -308.095687) (xy 276.971506 -308.095396) (xy 276.455632 -308.095396) (xy 276.450301 -308.09505)
			(xy 276.442758 -308.087518) (xy 276.442424 -308.082188) (xy 270.39824 -308.082188) (xy 270.3977 -308.087442)
			(xy 270.390284 -308.094883) (xy 270.385032 -308.095396) (xy 270.384524 -308.095396) (xy 269.868904 -308.095396)
			(xy 269.861029 -308.095685) (xy 269.846025 -308.100467) (xy 269.83944 -308.104794) (xy 269.818373 -308.119202)
			(xy 269.772724 -308.142025) (xy 269.724115 -308.157578) (xy 269.673696 -308.165493) (xy 269.648178 -308.166008)
			(xy 269.622659 -308.165495) (xy 269.572233 -308.157607) (xy 269.523621 -308.142054) (xy 269.477982 -308.119206)
			(xy 269.456916 -308.104794) (xy 269.450323 -308.100482) (xy 269.435324 -308.095693) (xy 269.427452 -308.095396)
			(xy 268.911578 -308.095396) (xy 268.90628 -308.094896) (xy 268.898712 -308.087476) (xy 268.898116 -308.082188)
			(xy 206.997808 -308.082188) (xy 206.997808 -308.082442) (xy 206.997311 -308.08774) (xy 206.989888 -308.095306)
			(xy 206.9846 -308.095904) (xy 206.468726 -308.095904) (xy 206.460917 -308.096228) (xy 206.446045 -308.101007)
			(xy 206.439516 -308.105302) (xy 206.418384 -308.119635) (xy 206.372664 -308.142367) (xy 206.323994 -308.157802)
			(xy 206.27353 -308.165573) (xy 206.248 -308.166008) (xy 206.22247 -308.165564) (xy 206.172007 -308.157789)
			(xy 206.123335 -308.142362) (xy 206.077607 -308.119648) (xy 206.056484 -308.105302) (xy 206.049955 -308.101006)
			(xy 206.035083 -308.096226) (xy 206.027274 -308.095904) (xy 205.5114 -308.095904) (xy 205.506067 -308.095573)
			(xy 205.498525 -308.088029) (xy 205.498192 -308.082696) (xy 199.453984 -308.082696) (xy 199.453511 -308.08774)
			(xy 199.446088 -308.095306) (xy 199.4408 -308.095904) (xy 198.924926 -308.095904) (xy 198.917117 -308.096228)
			(xy 198.902245 -308.101007) (xy 198.895716 -308.105302) (xy 198.874584 -308.119635) (xy 198.828864 -308.142367)
			(xy 198.780194 -308.157802) (xy 198.72973 -308.165573) (xy 198.7042 -308.166008) (xy 198.67867 -308.165564)
			(xy 198.628207 -308.157789) (xy 198.579535 -308.142362) (xy 198.533807 -308.119648) (xy 198.512684 -308.105302)
			(xy 198.506155 -308.101006) (xy 198.491283 -308.096226) (xy 198.483474 -308.095904) (xy 197.9676 -308.095904)
			(xy 197.962267 -308.095573) (xy 197.954725 -308.088029) (xy 197.954392 -308.082696) (xy 191.910183 -308.082696)
			(xy 191.909682 -308.0878) (xy 191.902104 -308.095381) (xy 191.896746 -308.095904) (xy 191.380872 -308.095904)
			(xy 191.373061 -308.096205) (xy 191.358189 -308.101) (xy 191.351662 -308.105302) (xy 191.330545 -308.119658)
			(xy 191.28482 -308.142385) (xy 191.236145 -308.157813) (xy 191.185677 -308.165577) (xy 191.160146 -308.166008)
			(xy 191.134617 -308.165541) (xy 191.084155 -308.157773) (xy 191.035482 -308.142352) (xy 190.989753 -308.119645)
			(xy 190.96863 -308.105302) (xy 190.962091 -308.101024) (xy 190.947227 -308.096233) (xy 190.93942 -308.095904)
			(xy 190.423546 -308.095904) (xy 190.418127 -308.095494) (xy 190.410441 -308.087858) (xy 190.410084 -308.082442)
			(xy 184.3659 -308.082442) (xy 184.36541 -308.087742) (xy 184.357982 -308.095308) (xy 184.352692 -308.095904)
			(xy 183.836818 -308.095904) (xy 183.829009 -308.096225) (xy 183.814137 -308.101006) (xy 183.807608 -308.105302)
			(xy 183.786478 -308.119638) (xy 183.740758 -308.142369) (xy 183.692087 -308.157803) (xy 183.641622 -308.165573)
			(xy 183.616092 -308.166008) (xy 183.590562 -308.165568) (xy 183.540099 -308.157792) (xy 183.491426 -308.142363)
			(xy 183.445698 -308.119648) (xy 183.424576 -308.105302) (xy 183.418049 -308.101003) (xy 183.403176 -308.096225)
			(xy 183.395366 -308.095904) (xy 182.879492 -308.095904) (xy 182.874227 -308.09541) (xy 182.866785 -308.087961)
			(xy 182.866284 -308.082696) (xy 176.822075 -308.082696) (xy 176.821581 -308.087802) (xy 176.813998 -308.095383)
			(xy 176.808638 -308.095904) (xy 176.292764 -308.095904) (xy 176.284956 -308.096244) (xy 176.270085 -308.101012)
			(xy 176.263554 -308.105302) (xy 176.242439 -308.119661) (xy 176.196713 -308.142387) (xy 176.148038 -308.157815)
			(xy 176.09757 -308.165577) (xy 176.072038 -308.166008) (xy 176.046509 -308.165545) (xy 175.996046 -308.157776)
			(xy 175.947374 -308.142354) (xy 175.901645 -308.119645) (xy 175.880522 -308.105302) (xy 175.873985 -308.101021)
			(xy 175.859119 -308.096231) (xy 175.851312 -308.095904) (xy 175.335438 -308.095904) (xy 175.330089 -308.095329)
			(xy 175.322503 -308.087788) (xy 175.321976 -308.082442) (xy 169.277792 -308.082442) (xy 169.277309 -308.087744)
			(xy 169.269876 -308.095311) (xy 169.264584 -308.095904) (xy 167.791384 -308.095904) (xy 167.786118 -308.095416)
			(xy 167.778676 -308.087962) (xy 167.778176 -308.082696) (xy 60.178164 -308.082696) (xy 60.17768 -308.087805)
			(xy 60.170089 -308.095387) (xy 60.164726 -308.095904) (xy 58.691526 -308.095904) (xy 58.686175 -308.095337)
			(xy 58.678591 -308.08779) (xy 58.678064 -308.082442) (xy 52.63388 -308.082442) (xy 52.633407 -308.087747)
			(xy 52.625967 -308.095314) (xy 52.620672 -308.095904) (xy 52.104798 -308.095904) (xy 52.096988 -308.096216)
			(xy 52.082116 -308.101003) (xy 52.075588 -308.105302) (xy 52.054463 -308.119647) (xy 52.008741 -308.142376)
			(xy 51.960069 -308.157808) (xy 51.909603 -308.165575) (xy 51.884072 -308.166008) (xy 51.858542 -308.165578)
			(xy 51.808078 -308.157799) (xy 51.759406 -308.142367) (xy 51.713678 -308.11965) (xy 51.692556 -308.105302)
			(xy 51.686033 -308.100995) (xy 51.671157 -308.096222) (xy 51.663346 -308.095904) (xy 51.147472 -308.095904)
			(xy 51.142205 -308.095424) (xy 51.134764 -308.087964) (xy 51.134264 -308.082696) (xy 45.090056 -308.082696)
			(xy 45.089579 -308.087807) (xy 45.081984 -308.095389) (xy 45.076618 -308.095904) (xy 44.560744 -308.095904)
			(xy 44.552936 -308.096236) (xy 44.538064 -308.101009) (xy 44.531534 -308.105302) (xy 44.510424 -308.11967)
			(xy 44.464697 -308.142394) (xy 44.41602 -308.157819) (xy 44.36555 -308.165579) (xy 44.340018 -308.166008)
			(xy 44.314488 -308.165555) (xy 44.264026 -308.157783) (xy 44.215353 -308.142358) (xy 44.169625 -308.119647)
			(xy 44.148502 -308.105302) (xy 44.141969 -308.101013) (xy 44.1271 -308.096229) (xy 44.119292 -308.095904)
			(xy 43.603418 -308.095904) (xy 43.598066 -308.095342) (xy 43.590482 -308.087791) (xy 43.589956 -308.082442)
			(xy 37.545772 -308.082442) (xy 37.545306 -308.087749) (xy 37.537862 -308.095317) (xy 37.532564 -308.095904)
			(xy 37.01669 -308.095904) (xy 37.008879 -308.096213) (xy 36.994008 -308.101002) (xy 36.98748 -308.105302)
			(xy 36.966358 -308.11965) (xy 36.920635 -308.142379) (xy 36.871961 -308.157809) (xy 36.821495 -308.165575)
			(xy 36.795964 -308.166008) (xy 36.770433 -308.165582) (xy 36.71997 -308.157801) (xy 36.671297 -308.142369)
			(xy 36.62557 -308.11965) (xy 36.604448 -308.105302) (xy 36.597927 -308.100992) (xy 36.583049 -308.096221)
			(xy 36.575238 -308.095904) (xy 36.059364 -308.095904) (xy 36.054096 -308.095429) (xy 36.046655 -308.087965)
			(xy 36.046156 -308.082696) (xy 30.00195 -308.082696) (xy 30.001506 -308.087749) (xy 29.994062 -308.095317)
			(xy 29.988764 -308.095904) (xy 29.47289 -308.095904) (xy 29.465079 -308.096213) (xy 29.450208 -308.101002)
			(xy 29.44368 -308.105302) (xy 29.422558 -308.11965) (xy 29.376835 -308.142379) (xy 29.328161 -308.157809)
			(xy 29.277695 -308.165575) (xy 29.252164 -308.166008) (xy 29.226633 -308.165582) (xy 29.17617 -308.157801)
			(xy 29.127497 -308.142369) (xy 29.08177 -308.11965) (xy 29.060648 -308.105302) (xy 29.054127 -308.100992)
			(xy 29.039249 -308.096221) (xy 29.031438 -308.095904) (xy 28.515564 -308.095904) (xy 28.510296 -308.095429)
			(xy 28.502855 -308.087965) (xy 28.502356 -308.082696) (xy 22.458149 -308.082696) (xy 22.457679 -308.087809)
			(xy 22.450078 -308.095391) (xy 22.44471 -308.095904) (xy 21.928836 -308.095904) (xy 21.921027 -308.096232)
			(xy 21.906156 -308.101008) (xy 21.899626 -308.105302) (xy 21.878491 -308.11963) (xy 21.832772 -308.142363)
			(xy 21.784103 -308.157799) (xy 21.73364 -308.165572) (xy 21.70811 -308.166008) (xy 21.68258 -308.165559)
			(xy 21.632117 -308.157785) (xy 21.583445 -308.14236) (xy 21.537717 -308.119647) (xy 21.516594 -308.105302)
			(xy 21.510063 -308.10101) (xy 21.495193 -308.096227) (xy 21.487384 -308.095904) (xy 20.97151 -308.095904)
			(xy 20.966157 -308.095347) (xy 20.958574 -308.087793) (xy 20.958048 -308.082442) (xy 2.509012 -308.082442)
			(xy 2.509012 -308.93258) (xy 16.85798 -308.93258) (xy 16.85798 -308.438042) (xy 16.858312 -308.432603)
			(xy 16.866003 -308.424912) (xy 16.871442 -308.42458) (xy 17.38757 -308.42458) (xy 17.395379 -308.424257)
			(xy 17.410251 -308.419478) (xy 17.41678 -308.415182) (xy 17.437869 -308.400833) (xy 17.48353 -308.378102)
			(xy 17.532136 -308.362643) (xy 17.582539 -308.35482) (xy 17.633545 -308.35482) (xy 17.683948 -308.362643)
			(xy 17.732554 -308.378102) (xy 17.778215 -308.400833) (xy 17.799304 -308.415182) (xy 17.805837 -308.419472)
			(xy 17.820706 -308.424256) (xy 17.828514 -308.42458) (xy 18.344642 -308.42458) (xy 18.350021 -308.425027)
			(xy 18.357607 -308.43266) (xy 18.358104 -308.438042) (xy 18.358104 -308.93258) (xy 24.402288 -308.93258)
			(xy 24.402288 -308.438042) (xy 24.402757 -308.432732) (xy 24.410195 -308.425155) (xy 24.415496 -308.42458)
			(xy 24.931624 -308.42458) (xy 24.939435 -308.42428) (xy 24.954307 -308.419485) (xy 24.960834 -308.415182)
			(xy 24.981923 -308.400833) (xy 25.027584 -308.378102) (xy 25.07619 -308.362643) (xy 25.126593 -308.35482)
			(xy 25.177599 -308.35482) (xy 25.228002 -308.362643) (xy 25.276608 -308.378102) (xy 25.322269 -308.400833)
			(xy 25.343358 -308.415182) (xy 25.349879 -308.419492) (xy 25.364757 -308.424264) (xy 25.372568 -308.42458)
			(xy 25.888696 -308.42458) (xy 25.893955 -308.425096) (xy 25.901398 -308.432529) (xy 25.901904 -308.437788)
			(xy 25.901904 -308.438296) (xy 25.901904 -308.93258) (xy 31.946088 -308.93258) (xy 31.946088 -308.438042)
			(xy 31.946557 -308.432732) (xy 31.953995 -308.425155) (xy 31.959296 -308.42458) (xy 32.475424 -308.42458)
			(xy 32.483235 -308.42428) (xy 32.498107 -308.419485) (xy 32.504634 -308.415182) (xy 32.525723 -308.400833)
			(xy 32.571384 -308.378102) (xy 32.61999 -308.362643) (xy 32.670393 -308.35482) (xy 32.721399 -308.35482)
			(xy 32.771802 -308.362643) (xy 32.820408 -308.378102) (xy 32.866069 -308.400833) (xy 32.887158 -308.415182)
			(xy 32.893679 -308.419492) (xy 32.908557 -308.424264) (xy 32.916368 -308.42458) (xy 33.432496 -308.42458)
			(xy 33.437755 -308.425096) (xy 33.445198 -308.432529) (xy 33.445704 -308.437788) (xy 33.445704 -308.438296)
			(xy 33.445704 -308.93258) (xy 39.489888 -308.93258) (xy 39.489888 -308.438042) (xy 39.490473 -308.432695)
			(xy 39.498007 -308.42511) (xy 39.50335 -308.42458) (xy 40.019478 -308.42458) (xy 40.027288 -308.424261)
			(xy 40.042159 -308.419479) (xy 40.048688 -308.415182) (xy 40.069777 -308.400833) (xy 40.115438 -308.378102)
			(xy 40.164044 -308.362643) (xy 40.214447 -308.35482) (xy 40.265453 -308.35482) (xy 40.315856 -308.362643)
			(xy 40.364462 -308.378102) (xy 40.410123 -308.400833) (xy 40.431212 -308.415182) (xy 40.437743 -308.419475)
			(xy 40.452613 -308.424257) (xy 40.460422 -308.42458) (xy 40.97655 -308.42458) (xy 40.98193 -308.425022)
			(xy 40.989515 -308.432659) (xy 40.990012 -308.438042) (xy 40.990012 -308.93258) (xy 47.034196 -308.93258)
			(xy 47.034196 -308.438042) (xy 47.034746 -308.432753) (xy 47.042129 -308.425182) (xy 47.047404 -308.42458)
			(xy 47.563532 -308.42458) (xy 47.57134 -308.424241) (xy 47.586211 -308.419473) (xy 47.592742 -308.415182)
			(xy 47.613831 -308.400833) (xy 47.659492 -308.378102) (xy 47.708098 -308.362643) (xy 47.758501 -308.35482)
			(xy 47.809507 -308.35482) (xy 47.85991 -308.362643) (xy 47.908516 -308.378102) (xy 47.954177 -308.400833)
			(xy 47.975266 -308.415182) (xy 47.981807 -308.419457) (xy 47.99667 -308.42425) (xy 48.004476 -308.42458)
			(xy 48.520604 -308.42458) (xy 48.525864 -308.425091) (xy 48.533306 -308.432528) (xy 48.533812 -308.437788)
			(xy 48.533812 -308.438296) (xy 48.533812 -308.93258) (xy 54.577996 -308.93258) (xy 54.577996 -308.438042)
			(xy 54.578574 -308.432693) (xy 54.586112 -308.425107) (xy 54.591458 -308.42458) (xy 56.064658 -308.42458)
			(xy 56.070097 -308.424912) (xy 56.077788 -308.432603) (xy 56.07812 -308.438042) (xy 56.07812 -308.93258)
			(xy 56.077761 -308.937907) (xy 56.070238 -308.945448) (xy 56.064912 -308.945788) (xy 54.591458 -308.945788)
			(xy 54.586155 -308.945308) (xy 54.578588 -308.937873) (xy 54.577996 -308.93258) (xy 48.533812 -308.93258)
			(xy 48.53346 -308.937909) (xy 48.525932 -308.945451) (xy 48.520604 -308.945788) (xy 48.00473 -308.945788)
			(xy 47.996853 -308.946047) (xy 47.981849 -308.95085) (xy 47.975266 -308.955186) (xy 47.954191 -308.969582)
			(xy 47.908545 -308.992408) (xy 47.859938 -309.007964) (xy 47.809521 -309.015883) (xy 47.784004 -309.0164)
			(xy 47.758483 -309.015925) (xy 47.708056 -309.008026) (xy 47.659444 -308.992462) (xy 47.613806 -308.969603)
			(xy 47.592742 -308.955186) (xy 47.586166 -308.950844) (xy 47.571154 -308.946074) (xy 47.563278 -308.945788)
			(xy 47.047404 -308.945788) (xy 47.042067 -308.945468) (xy 47.034525 -308.937917) (xy 47.034196 -308.93258)
			(xy 40.990012 -308.93258) (xy 40.98966 -308.937909) (xy 40.982132 -308.945451) (xy 40.976804 -308.945788)
			(xy 40.976296 -308.945788) (xy 40.460676 -308.945788) (xy 40.452801 -308.946067) (xy 40.437796 -308.950856)
			(xy 40.431212 -308.955186) (xy 40.410152 -308.969605) (xy 40.364501 -308.992426) (xy 40.315889 -309.007976)
			(xy 40.265468 -309.015887) (xy 40.23995 -309.0164) (xy 40.21443 -309.015902) (xy 40.164004 -309.00801)
			(xy 40.115392 -308.992453) (xy 40.069753 -308.9696) (xy 40.048688 -308.955186) (xy 40.042102 -308.950862)
			(xy 40.027098 -308.946081) (xy 40.019224 -308.945788) (xy 39.50335 -308.945788) (xy 39.498058 -308.945247)
			(xy 39.490486 -308.937858) (xy 39.489888 -308.93258) (xy 33.445704 -308.93258) (xy 33.44536 -308.937911)
			(xy 33.437826 -308.945453) (xy 33.432496 -308.945788) (xy 32.916622 -308.945788) (xy 32.908748 -308.946086)
			(xy 32.893744 -308.950862) (xy 32.887158 -308.955186) (xy 32.866086 -308.969585) (xy 32.820439 -308.992411)
			(xy 32.771831 -309.007966) (xy 32.721413 -309.015883) (xy 32.695896 -309.0164) (xy 32.670375 -309.015929)
			(xy 32.619947 -309.008029) (xy 32.571336 -308.992464) (xy 32.525698 -308.969604) (xy 32.504634 -308.955186)
			(xy 32.498037 -308.95088) (xy 32.483041 -308.946088) (xy 32.47517 -308.945788) (xy 31.959296 -308.945788)
			(xy 31.953958 -308.945474) (xy 31.946417 -308.937918) (xy 31.946088 -308.93258) (xy 25.901904 -308.93258)
			(xy 25.90156 -308.937911) (xy 25.894026 -308.945453) (xy 25.888696 -308.945788) (xy 25.372822 -308.945788)
			(xy 25.364948 -308.946086) (xy 25.349944 -308.950862) (xy 25.343358 -308.955186) (xy 25.322286 -308.969585)
			(xy 25.276639 -308.992411) (xy 25.228031 -309.007966) (xy 25.177613 -309.015883) (xy 25.152096 -309.0164)
			(xy 25.126575 -309.015929) (xy 25.076147 -309.008029) (xy 25.027536 -308.992464) (xy 24.981898 -308.969604)
			(xy 24.960834 -308.955186) (xy 24.954237 -308.95088) (xy 24.939241 -308.946088) (xy 24.93137 -308.945788)
			(xy 24.415496 -308.945788) (xy 24.410158 -308.945474) (xy 24.402617 -308.937918) (xy 24.402288 -308.93258)
			(xy 18.358104 -308.93258) (xy 18.35776 -308.937911) (xy 18.350226 -308.945453) (xy 18.344896 -308.945788)
			(xy 18.344388 -308.945788) (xy 17.828768 -308.945788) (xy 17.820892 -308.946063) (xy 17.805888 -308.950855)
			(xy 17.799304 -308.955186) (xy 17.778219 -308.969565) (xy 17.732576 -308.992395) (xy 17.683973 -309.007956)
			(xy 17.633558 -309.01588) (xy 17.608042 -309.0164) (xy 17.582522 -309.015906) (xy 17.532095 -309.008013)
			(xy 17.483484 -308.992454) (xy 17.437845 -308.969601) (xy 17.41678 -308.955186) (xy 17.410196 -308.950859)
			(xy 17.39519 -308.94608) (xy 17.387316 -308.945788) (xy 16.871442 -308.945788) (xy 16.866149 -308.945252)
			(xy 16.858578 -308.93786) (xy 16.85798 -308.93258) (xy 2.509012 -308.93258) (xy 2.509012 -309.782464)
			(xy 20.958048 -309.782464) (xy 20.958048 -309.287926) (xy 20.958398 -309.282492) (xy 20.966077 -309.274804)
			(xy 20.97151 -309.274464) (xy 21.487638 -309.274464) (xy 21.495446 -309.27413) (xy 21.510318 -309.269358)
			(xy 21.516848 -309.265066) (xy 21.537937 -309.250717) (xy 21.583598 -309.227986) (xy 21.632204 -309.212527)
			(xy 21.682607 -309.204704) (xy 21.733613 -309.204704) (xy 21.784016 -309.212527) (xy 21.832622 -309.227986)
			(xy 21.878283 -309.250717) (xy 21.899372 -309.265066) (xy 21.905913 -309.269342) (xy 21.920776 -309.274135)
			(xy 21.928582 -309.274464) (xy 22.44471 -309.274464) (xy 22.450153 -309.274775) (xy 22.45784 -309.282483)
			(xy 22.458172 -309.287926) (xy 22.458172 -309.782464) (xy 28.502356 -309.782464) (xy 28.502356 -309.287926)
			(xy 28.502842 -309.282621) (xy 28.51027 -309.275048) (xy 28.515564 -309.274464) (xy 29.031692 -309.274464)
			(xy 29.039502 -309.274153) (xy 29.054374 -309.269366) (xy 29.060902 -309.265066) (xy 29.081991 -309.250717)
			(xy 29.127652 -309.227986) (xy 29.176258 -309.212527) (xy 29.226661 -309.204704) (xy 29.277667 -309.204704)
			(xy 29.32807 -309.212527) (xy 29.376676 -309.227986) (xy 29.422337 -309.250717) (xy 29.443426 -309.265066)
			(xy 29.449955 -309.269363) (xy 29.464827 -309.274143) (xy 29.472636 -309.274464) (xy 29.988764 -309.274464)
			(xy 29.994085 -309.274848) (xy 30.001626 -309.282353) (xy 30.001972 -309.287672) (xy 30.001972 -309.28818)
			(xy 30.001972 -309.782464) (xy 36.046156 -309.782464) (xy 36.046156 -309.287926) (xy 36.046642 -309.282621)
			(xy 36.05407 -309.275048) (xy 36.059364 -309.274464) (xy 36.575492 -309.274464) (xy 36.583302 -309.274153)
			(xy 36.598174 -309.269366) (xy 36.604702 -309.265066) (xy 36.625791 -309.250717) (xy 36.671452 -309.227986)
			(xy 36.720058 -309.212527) (xy 36.770461 -309.204704) (xy 36.821467 -309.204704) (xy 36.87187 -309.212527)
			(xy 36.920476 -309.227986) (xy 36.966137 -309.250717) (xy 36.987226 -309.265066) (xy 36.993755 -309.269363)
			(xy 37.008627 -309.274143) (xy 37.016436 -309.274464) (xy 37.532564 -309.274464) (xy 37.537885 -309.274848)
			(xy 37.545426 -309.282353) (xy 37.545772 -309.287672) (xy 37.545772 -309.28818) (xy 37.545772 -309.782464)
			(xy 43.589956 -309.782464) (xy 43.589956 -309.287926) (xy 43.590298 -309.28249) (xy 43.597982 -309.274802)
			(xy 43.603418 -309.274464) (xy 44.119546 -309.274464) (xy 44.127355 -309.274133) (xy 44.142226 -309.26936)
			(xy 44.148756 -309.265066) (xy 44.169845 -309.250717) (xy 44.215506 -309.227986) (xy 44.264112 -309.212527)
			(xy 44.314515 -309.204704) (xy 44.365521 -309.204704) (xy 44.415924 -309.212527) (xy 44.46453 -309.227986)
			(xy 44.510191 -309.250717) (xy 44.53128 -309.265066) (xy 44.537819 -309.269345) (xy 44.552683 -309.274136)
			(xy 44.56049 -309.274464) (xy 45.076618 -309.274464) (xy 45.082062 -309.27477) (xy 45.089748 -309.282481)
			(xy 45.09008 -309.287926) (xy 45.09008 -309.782464) (xy 51.134264 -309.782464) (xy 51.134264 -309.287926)
			(xy 51.134743 -309.282619) (xy 51.142175 -309.275045) (xy 51.147472 -309.274464) (xy 51.6636 -309.274464)
			(xy 51.671411 -309.274157) (xy 51.686282 -309.269367) (xy 51.69281 -309.265066) (xy 51.713899 -309.250717)
			(xy 51.75956 -309.227986) (xy 51.808166 -309.212527) (xy 51.858569 -309.204704) (xy 51.909575 -309.204704)
			(xy 51.959978 -309.212527) (xy 52.008584 -309.227986) (xy 52.054245 -309.250717) (xy 52.075334 -309.265066)
			(xy 52.081861 -309.269366) (xy 52.096734 -309.274144) (xy 52.104544 -309.274464) (xy 52.620672 -309.274464)
			(xy 52.625925 -309.27501) (xy 52.633367 -309.282422) (xy 52.63388 -309.287672) (xy 52.63388 -309.28818)
			(xy 52.63388 -309.782464) (xy 58.678064 -309.782464) (xy 58.678064 -309.287926) (xy 58.678399 -309.282488)
			(xy 58.686088 -309.274799) (xy 58.691526 -309.274464) (xy 60.164726 -309.274464) (xy 60.170099 -309.274936)
			(xy 60.177685 -309.282551) (xy 60.178188 -309.287926) (xy 60.178188 -309.504588) (xy 79.192628 -309.504588)
			(xy 79.192628 -308.640988) (xy 79.193114 -308.613737) (xy 79.20087 -308.559789) (xy 79.216225 -308.507494)
			(xy 79.238867 -308.457917) (xy 79.268333 -308.412067) (xy 79.304024 -308.370876) (xy 79.345215 -308.335185)
			(xy 79.391065 -308.305719) (xy 79.440642 -308.283077) (xy 79.492937 -308.267722) (xy 79.546885 -308.259966)
			(xy 79.601387 -308.259966) (xy 79.655335 -308.267722) (xy 79.70763 -308.283077) (xy 79.757207 -308.305719)
			(xy 79.803057 -308.335185) (xy 79.844248 -308.370876) (xy 79.879939 -308.412067) (xy 79.909405 -308.457917)
			(xy 79.92811 -308.498873) (xy 93.275072 -308.498873) (xy 93.275072 -308.444327) (xy 93.282834 -308.390335)
			(xy 93.298202 -308.337998) (xy 93.320862 -308.288381) (xy 93.350352 -308.242493) (xy 93.386073 -308.20127)
			(xy 93.427297 -308.16555) (xy 93.473184 -308.13606) (xy 93.522802 -308.113401) (xy 93.575139 -308.098034)
			(xy 93.629131 -308.090271) (xy 93.656404 -308.089808) (xy 94.520004 -308.089808) (xy 94.547271 -308.090355)
			(xy 94.60125 -308.098116) (xy 94.653575 -308.113481) (xy 94.703181 -308.136135) (xy 94.749058 -308.165619)
			(xy 94.790271 -308.201331) (xy 94.825983 -308.242546) (xy 94.855467 -308.288423) (xy 94.878121 -308.338029)
			(xy 94.893485 -308.390354) (xy 94.901246 -308.444333) (xy 94.901246 -308.498867) (xy 94.893485 -308.552846)
			(xy 94.878121 -308.605171) (xy 94.855467 -308.654777) (xy 94.825983 -308.700654) (xy 94.790271 -308.741869)
			(xy 94.749058 -308.777581) (xy 94.703181 -308.807065) (xy 94.653575 -308.829719) (xy 94.60125 -308.845084)
			(xy 94.547271 -308.852845) (xy 94.520004 -308.853332) (xy 93.656404 -308.853332) (xy 93.629131 -308.852929)
			(xy 93.575139 -308.845166) (xy 93.522802 -308.829799) (xy 93.473184 -308.80714) (xy 93.427297 -308.77765)
			(xy 93.386073 -308.74193) (xy 93.350352 -308.700707) (xy 93.320862 -308.654819) (xy 93.298202 -308.605202)
			(xy 93.282834 -308.552865) (xy 93.275072 -308.498873) (xy 79.92811 -308.498873) (xy 79.932047 -308.507494)
			(xy 79.947402 -308.559789) (xy 79.955158 -308.613737) (xy 79.955644 -308.640988) (xy 79.955644 -308.93258)
			(xy 163.678108 -308.93258) (xy 163.678108 -308.438042) (xy 163.678647 -308.43275) (xy 163.686037 -308.425179)
			(xy 163.691316 -308.42458) (xy 165.164516 -308.42458) (xy 165.169778 -308.425083) (xy 165.177219 -308.432526)
			(xy 165.177724 -308.437788) (xy 165.177724 -308.438296) (xy 165.177724 -308.93258) (xy 171.221908 -308.93258)
			(xy 171.221908 -308.438042) (xy 171.222305 -308.43262) (xy 171.22995 -308.424933) (xy 171.23537 -308.42458)
			(xy 171.751498 -308.42458) (xy 171.759308 -308.424269) (xy 171.77418 -308.419482) (xy 171.780708 -308.415182)
			(xy 171.801797 -308.400833) (xy 171.847458 -308.378102) (xy 171.896064 -308.362643) (xy 171.946467 -308.35482)
			(xy 171.997473 -308.35482) (xy 172.047876 -308.362643) (xy 172.096482 -308.378102) (xy 172.142143 -308.400833)
			(xy 172.163232 -308.415182) (xy 172.169758 -308.419482) (xy 172.184632 -308.42426) (xy 172.192442 -308.42458)
			(xy 172.70857 -308.42458) (xy 172.714011 -308.424904) (xy 172.721701 -308.432601) (xy 172.722032 -308.438042)
			(xy 172.722032 -308.93258) (xy 178.766216 -308.93258) (xy 178.766216 -308.438042) (xy 178.766748 -308.432748)
			(xy 178.774143 -308.425176) (xy 178.779424 -308.42458) (xy 179.295552 -308.42458) (xy 179.303361 -308.424249)
			(xy 179.318232 -308.419475) (xy 179.324762 -308.415182) (xy 179.345851 -308.400833) (xy 179.391512 -308.378102)
			(xy 179.440118 -308.362643) (xy 179.490521 -308.35482) (xy 179.541527 -308.35482) (xy 179.59193 -308.362643)
			(xy 179.640536 -308.378102) (xy 179.686197 -308.400833) (xy 179.707286 -308.415182) (xy 179.713823 -308.419465)
			(xy 179.728689 -308.424253) (xy 179.736496 -308.42458) (xy 180.252624 -308.42458) (xy 180.257887 -308.425078)
			(xy 180.265327 -308.432525) (xy 180.265832 -308.437788) (xy 180.265832 -308.438296) (xy 180.265832 -308.93258)
			(xy 186.310016 -308.93258) (xy 186.310016 -308.438042) (xy 186.310405 -308.432618) (xy 186.318056 -308.424931)
			(xy 186.323478 -308.42458) (xy 186.839606 -308.42458) (xy 186.847417 -308.424272) (xy 186.862288 -308.419483)
			(xy 186.868816 -308.415182) (xy 186.889905 -308.400833) (xy 186.935566 -308.378102) (xy 186.984172 -308.362643)
			(xy 187.034575 -308.35482) (xy 187.085581 -308.35482) (xy 187.135984 -308.362643) (xy 187.18459 -308.378102)
			(xy 187.230251 -308.400833) (xy 187.25134 -308.415182) (xy 187.257865 -308.419485) (xy 187.27274 -308.424261)
			(xy 187.28055 -308.42458) (xy 187.796678 -308.42458) (xy 187.80212 -308.424898) (xy 187.80981 -308.432599)
			(xy 187.81014 -308.438042) (xy 187.81014 -308.93258) (xy 193.854324 -308.93258) (xy 193.854324 -308.438042)
			(xy 193.854849 -308.432747) (xy 193.862249 -308.425174) (xy 193.867532 -308.42458) (xy 194.38366 -308.42458)
			(xy 194.391469 -308.424253) (xy 194.406341 -308.419477) (xy 194.41287 -308.415182) (xy 194.433959 -308.400833)
			(xy 194.47962 -308.378102) (xy 194.528226 -308.362643) (xy 194.578629 -308.35482) (xy 194.629635 -308.35482)
			(xy 194.680038 -308.362643) (xy 194.728644 -308.378102) (xy 194.774305 -308.400833) (xy 194.795394 -308.415182)
			(xy 194.801929 -308.419468) (xy 194.816796 -308.424254) (xy 194.824604 -308.42458) (xy 195.340732 -308.42458)
			(xy 195.345996 -308.425072) (xy 195.353436 -308.432524) (xy 195.35394 -308.437788) (xy 195.35394 -308.438296)
			(xy 195.35394 -308.93258) (xy 201.398124 -308.93258) (xy 201.398124 -308.438042) (xy 201.398649 -308.432747)
			(xy 201.406049 -308.425174) (xy 201.411332 -308.42458) (xy 201.92746 -308.42458) (xy 201.935269 -308.424253)
			(xy 201.950141 -308.419477) (xy 201.95667 -308.415182) (xy 201.977759 -308.400833) (xy 202.02342 -308.378102)
			(xy 202.072026 -308.362643) (xy 202.122429 -308.35482) (xy 202.173435 -308.35482) (xy 202.223838 -308.362643)
			(xy 202.272444 -308.378102) (xy 202.318105 -308.400833) (xy 202.339194 -308.415182) (xy 202.345729 -308.419468)
			(xy 202.360596 -308.424254) (xy 202.368404 -308.42458) (xy 202.884532 -308.42458) (xy 202.889796 -308.425072)
			(xy 202.897236 -308.432524) (xy 202.89774 -308.437788) (xy 202.89774 -308.438296) (xy 202.89774 -308.932326)
			(xy 264.798048 -308.932326) (xy 264.798048 -308.437788) (xy 264.798582 -308.432534) (xy 264.806004 -308.425095)
			(xy 264.811256 -308.42458) (xy 264.811764 -308.42458) (xy 265.327638 -308.42458) (xy 265.335446 -308.424243)
			(xy 265.350318 -308.419473) (xy 265.356848 -308.415182) (xy 265.377937 -308.400833) (xy 265.423598 -308.378102)
			(xy 265.472204 -308.362643) (xy 265.522607 -308.35482) (xy 265.573613 -308.35482) (xy 265.624016 -308.362643)
			(xy 265.672622 -308.378102) (xy 265.718283 -308.400833) (xy 265.739372 -308.415182) (xy 265.745912 -308.419459)
			(xy 265.760775 -308.424251) (xy 265.768582 -308.42458) (xy 266.28471 -308.42458) (xy 266.290025 -308.425021)
			(xy 266.297598 -308.432481) (xy 266.298172 -308.437788) (xy 266.298172 -308.932326) (xy 266.298148 -308.93258)
			(xy 272.342356 -308.93258) (xy 272.342356 -308.932072) (xy 272.342356 -308.437788) (xy 272.342883 -308.432533)
			(xy 272.350309 -308.425093) (xy 272.355564 -308.42458) (xy 272.871692 -308.42458) (xy 272.879502 -308.424266)
			(xy 272.894374 -308.419481) (xy 272.900902 -308.415182) (xy 272.921991 -308.400833) (xy 272.967652 -308.378102)
			(xy 273.016258 -308.362643) (xy 273.066661 -308.35482) (xy 273.117667 -308.35482) (xy 273.16807 -308.362643)
			(xy 273.216676 -308.378102) (xy 273.262337 -308.400833) (xy 273.283426 -308.415182) (xy 273.289954 -308.41948)
			(xy 273.304827 -308.424259) (xy 273.312636 -308.42458) (xy 273.828764 -308.42458) (xy 273.834089 -308.42495)
			(xy 273.841631 -308.432465) (xy 273.841972 -308.437788) (xy 273.841972 -308.932326) (xy 273.841949 -308.93258)
			(xy 279.886156 -308.93258) (xy 279.886156 -308.932072) (xy 279.886156 -308.437788) (xy 279.886683 -308.432533)
			(xy 279.894109 -308.425093) (xy 279.899364 -308.42458) (xy 280.415492 -308.42458) (xy 280.423302 -308.424266)
			(xy 280.438174 -308.419481) (xy 280.444702 -308.415182) (xy 280.465791 -308.400833) (xy 280.511452 -308.378102)
			(xy 280.560058 -308.362643) (xy 280.610461 -308.35482) (xy 280.661467 -308.35482) (xy 280.71187 -308.362643)
			(xy 280.760476 -308.378102) (xy 280.806137 -308.400833) (xy 280.827226 -308.415182) (xy 280.833754 -308.41948)
			(xy 280.848627 -308.424259) (xy 280.856436 -308.42458) (xy 281.372564 -308.42458) (xy 281.377889 -308.42495)
			(xy 281.385431 -308.432465) (xy 281.385772 -308.437788) (xy 281.385772 -308.932326) (xy 287.429956 -308.932326)
			(xy 287.429956 -308.437788) (xy 287.430483 -308.432533) (xy 287.437909 -308.425093) (xy 287.443164 -308.42458)
			(xy 287.443672 -308.42458) (xy 287.959546 -308.42458) (xy 287.967354 -308.424247) (xy 287.982226 -308.419474)
			(xy 287.988756 -308.415182) (xy 288.009845 -308.400833) (xy 288.055506 -308.378102) (xy 288.104112 -308.362643)
			(xy 288.154515 -308.35482) (xy 288.205521 -308.35482) (xy 288.255924 -308.362643) (xy 288.30453 -308.378102)
			(xy 288.350191 -308.400833) (xy 288.37128 -308.415182) (xy 288.377818 -308.419462) (xy 288.392683 -308.424252)
			(xy 288.40049 -308.42458) (xy 288.916618 -308.42458) (xy 288.921934 -308.425016) (xy 288.929506 -308.43248)
			(xy 288.93008 -308.437788) (xy 288.93008 -308.932326) (xy 288.930056 -308.93258) (xy 294.974264 -308.93258)
			(xy 294.974264 -308.932072) (xy 294.974264 -308.437788) (xy 294.974784 -308.432531) (xy 294.982215 -308.42509)
			(xy 294.987472 -308.42458) (xy 295.5036 -308.42458) (xy 295.51141 -308.42427) (xy 295.526282 -308.419482)
			(xy 295.53281 -308.415182) (xy 295.553899 -308.400833) (xy 295.59956 -308.378102) (xy 295.648166 -308.362643)
			(xy 295.698569 -308.35482) (xy 295.749575 -308.35482) (xy 295.799978 -308.362643) (xy 295.848584 -308.378102)
			(xy 295.894245 -308.400833) (xy 295.915334 -308.415182) (xy 295.92186 -308.419483) (xy 295.936734 -308.42426)
			(xy 295.944544 -308.42458) (xy 296.460672 -308.42458) (xy 296.465998 -308.424944) (xy 296.47354 -308.432463)
			(xy 296.47388 -308.437788) (xy 296.47388 -308.932326) (xy 302.518064 -308.932326) (xy 302.518064 -308.437788)
			(xy 302.518584 -308.432531) (xy 302.526015 -308.42509) (xy 302.531272 -308.42458) (xy 304.004726 -308.42458)
			(xy 304.010043 -308.425011) (xy 304.017614 -308.432479) (xy 304.018188 -308.437788) (xy 304.018188 -308.932326)
			(xy 304.017669 -308.937687) (xy 304.010087 -308.945269) (xy 304.004726 -308.945788) (xy 302.531526 -308.945788)
			(xy 302.526171 -308.945235) (xy 302.518586 -308.937679) (xy 302.518064 -308.932326) (xy 296.47388 -308.932326)
			(xy 296.473396 -308.937629) (xy 296.465965 -308.945197) (xy 296.460672 -308.945788) (xy 295.944798 -308.945788)
			(xy 295.936986 -308.946086) (xy 295.922114 -308.950881) (xy 295.915588 -308.955186) (xy 295.89447 -308.969541)
			(xy 295.848744 -308.992265) (xy 295.80007 -309.007693) (xy 295.749603 -309.015459) (xy 295.724072 -309.015892)
			(xy 295.698541 -309.015465) (xy 295.648077 -309.007685) (xy 295.599405 -308.992253) (xy 295.553678 -308.969534)
			(xy 295.532556 -308.955186) (xy 295.526029 -308.950887) (xy 295.511156 -308.946107) (xy 295.503346 -308.945788)
			(xy 294.987472 -308.945788) (xy 294.982201 -308.945322) (xy 294.974759 -308.937853) (xy 294.974264 -308.93258)
			(xy 288.930056 -308.93258) (xy 288.929569 -308.937689) (xy 288.921981 -308.945272) (xy 288.916618 -308.945788)
			(xy 288.400744 -308.945788) (xy 288.392934 -308.946106) (xy 288.378062 -308.950887) (xy 288.371534 -308.955186)
			(xy 288.350431 -308.969564) (xy 288.3047 -308.992283) (xy 288.256021 -309.007705) (xy 288.205551 -309.015463)
			(xy 288.180018 -309.015892) (xy 288.154488 -309.015441) (xy 288.104025 -309.007669) (xy 288.055353 -308.992244)
			(xy 288.009625 -308.969531) (xy 287.988502 -308.955186) (xy 287.981964 -308.950905) (xy 287.967099 -308.946114)
			(xy 287.959292 -308.945788) (xy 287.443418 -308.945788) (xy 287.438062 -308.94524) (xy 287.430477 -308.93768)
			(xy 287.429956 -308.932326) (xy 281.385772 -308.932326) (xy 281.385295 -308.93763) (xy 281.377859 -308.945199)
			(xy 281.372564 -308.945788) (xy 280.85669 -308.945788) (xy 280.848878 -308.946083) (xy 280.834006 -308.95088)
			(xy 280.82748 -308.955186) (xy 280.806364 -308.969544) (xy 280.760638 -308.992268) (xy 280.711963 -309.007695)
			(xy 280.661495 -309.01546) (xy 280.635964 -309.015892) (xy 280.610433 -309.015469) (xy 280.559969 -309.007688)
			(xy 280.511297 -308.992255) (xy 280.46557 -308.969535) (xy 280.444448 -308.955186) (xy 280.437922 -308.950884)
			(xy 280.423048 -308.946106) (xy 280.415238 -308.945788) (xy 279.899364 -308.945788) (xy 279.894092 -308.945327)
			(xy 279.886651 -308.937854) (xy 279.886156 -308.93258) (xy 273.841949 -308.93258) (xy 273.841495 -308.93763)
			(xy 273.834059 -308.945199) (xy 273.828764 -308.945788) (xy 273.31289 -308.945788) (xy 273.305078 -308.946083)
			(xy 273.290206 -308.95088) (xy 273.28368 -308.955186) (xy 273.262564 -308.969544) (xy 273.216838 -308.992268)
			(xy 273.168163 -309.007695) (xy 273.117695 -309.01546) (xy 273.092164 -309.015892) (xy 273.066633 -309.015469)
			(xy 273.016169 -309.007688) (xy 272.967497 -308.992255) (xy 272.92177 -308.969535) (xy 272.900648 -308.955186)
			(xy 272.894122 -308.950884) (xy 272.879248 -308.946106) (xy 272.871438 -308.945788) (xy 272.355564 -308.945788)
			(xy 272.350292 -308.945327) (xy 272.342851 -308.937854) (xy 272.342356 -308.93258) (xy 266.298148 -308.93258)
			(xy 266.297668 -308.937691) (xy 266.290075 -308.945274) (xy 266.28471 -308.945788) (xy 265.768836 -308.945788)
			(xy 265.761026 -308.946102) (xy 265.746154 -308.950886) (xy 265.739626 -308.955186) (xy 265.718497 -308.969524)
			(xy 265.672776 -308.992252) (xy 265.624105 -309.007685) (xy 265.57364 -309.015456) (xy 265.54811 -309.015892)
			(xy 265.52258 -309.015445) (xy 265.472117 -309.007672) (xy 265.423445 -308.992245) (xy 265.377717 -308.969532)
			(xy 265.356594 -308.955186) (xy 265.350058 -308.950902) (xy 265.335192 -308.946113) (xy 265.327384 -308.945788)
			(xy 264.81151 -308.945788) (xy 264.806154 -308.945245) (xy 264.798569 -308.937681) (xy 264.798048 -308.932326)
			(xy 202.89774 -308.932326) (xy 202.89774 -308.93258) (xy 202.897195 -308.937833) (xy 202.889783 -308.945275)
			(xy 202.884532 -308.945788) (xy 202.368658 -308.945788) (xy 202.360782 -308.946059) (xy 202.345778 -308.950853)
			(xy 202.339194 -308.955186) (xy 202.318112 -308.96957) (xy 202.272468 -308.992399) (xy 202.223864 -309.007958)
			(xy 202.173448 -309.015881) (xy 202.147932 -309.0164) (xy 202.122412 -309.015911) (xy 202.071985 -309.008016)
			(xy 202.023373 -308.992456) (xy 201.977735 -308.969601) (xy 201.95667 -308.955186) (xy 201.950088 -308.950855)
			(xy 201.935081 -308.946079) (xy 201.927206 -308.945788) (xy 201.411332 -308.945788) (xy 201.405999 -308.94545)
			(xy 201.398455 -308.937912) (xy 201.398124 -308.93258) (xy 195.35394 -308.93258) (xy 195.353395 -308.937833)
			(xy 195.345983 -308.945275) (xy 195.340732 -308.945788) (xy 194.824858 -308.945788) (xy 194.816982 -308.946059)
			(xy 194.801978 -308.950853) (xy 194.795394 -308.955186) (xy 194.774312 -308.96957) (xy 194.728668 -308.992399)
			(xy 194.680064 -309.007958) (xy 194.629648 -309.015881) (xy 194.604132 -309.0164) (xy 194.578612 -309.015911)
			(xy 194.528185 -309.008016) (xy 194.479573 -308.992456) (xy 194.433935 -308.969601) (xy 194.41287 -308.955186)
			(xy 194.406288 -308.950855) (xy 194.391281 -308.946079) (xy 194.383406 -308.945788) (xy 193.867532 -308.945788)
			(xy 193.862199 -308.94545) (xy 193.854655 -308.937912) (xy 193.854324 -308.93258) (xy 187.81014 -308.93258)
			(xy 187.809595 -308.937833) (xy 187.802183 -308.945275) (xy 187.796932 -308.945788) (xy 187.796424 -308.945788)
			(xy 187.280804 -308.945788) (xy 187.27293 -308.946078) (xy 187.257925 -308.950859) (xy 187.25134 -308.955186)
			(xy 187.230273 -308.969593) (xy 187.184624 -308.992417) (xy 187.136015 -309.00797) (xy 187.085595 -309.015885)
			(xy 187.060078 -309.0164) (xy 187.034559 -309.015888) (xy 186.984133 -309.008) (xy 186.935521 -308.992447)
			(xy 186.889882 -308.969598) (xy 186.868816 -308.955186) (xy 186.862223 -308.950873) (xy 186.847224 -308.946085)
			(xy 186.839352 -308.945788) (xy 186.323478 -308.945788) (xy 186.318178 -308.945295) (xy 186.310609 -308.93787)
			(xy 186.310016 -308.93258) (xy 180.265832 -308.93258) (xy 180.265295 -308.937835) (xy 180.257877 -308.945277)
			(xy 180.252624 -308.945788) (xy 179.73675 -308.945788) (xy 179.728874 -308.946055) (xy 179.713869 -308.950852)
			(xy 179.707286 -308.955186) (xy 179.686206 -308.969573) (xy 179.640562 -308.992401) (xy 179.591956 -309.00796)
			(xy 179.54154 -309.015881) (xy 179.516024 -309.0164) (xy 179.490504 -309.015915) (xy 179.440076 -309.008019)
			(xy 179.391465 -308.992458) (xy 179.345827 -308.969602) (xy 179.324762 -308.955186) (xy 179.318182 -308.950852)
			(xy 179.303173 -308.946077) (xy 179.295298 -308.945788) (xy 178.779424 -308.945788) (xy 178.77409 -308.945455)
			(xy 178.766547 -308.937914) (xy 178.766216 -308.93258) (xy 172.722032 -308.93258) (xy 172.721495 -308.937835)
			(xy 172.714077 -308.945277) (xy 172.708824 -308.945788) (xy 172.708316 -308.945788) (xy 172.192696 -308.945788)
			(xy 172.184821 -308.946075) (xy 172.169817 -308.950858) (xy 172.163232 -308.955186) (xy 172.142167 -308.969596)
			(xy 172.096517 -308.992419) (xy 172.047907 -309.007972) (xy 171.997488 -309.015885) (xy 171.97197 -309.0164)
			(xy 171.946451 -309.015892) (xy 171.896024 -309.008003) (xy 171.847413 -308.992449) (xy 171.801774 -308.969599)
			(xy 171.780708 -308.955186) (xy 171.774117 -308.95087) (xy 171.759117 -308.946084) (xy 171.751244 -308.945788)
			(xy 171.23537 -308.945788) (xy 171.230069 -308.9453) (xy 171.222501 -308.937871) (xy 171.221908 -308.93258)
			(xy 165.177724 -308.93258) (xy 165.177362 -308.937906) (xy 165.169841 -308.945447) (xy 165.164516 -308.945788)
			(xy 163.691316 -308.945788) (xy 163.685981 -308.94546) (xy 163.678438 -308.937915) (xy 163.678108 -308.93258)
			(xy 79.955644 -308.93258) (xy 79.955644 -309.504588) (xy 79.955158 -309.531839) (xy 79.947402 -309.585787)
			(xy 79.932047 -309.638082) (xy 79.909405 -309.687659) (xy 79.879939 -309.733509) (xy 79.844248 -309.7747)
			(xy 79.803057 -309.810391) (xy 79.757207 -309.839857) (xy 79.70763 -309.862499) (xy 79.655335 -309.877854)
			(xy 79.601387 -309.88561) (xy 79.546885 -309.88561) (xy 79.492937 -309.877854) (xy 79.440642 -309.862499)
			(xy 79.391065 -309.839857) (xy 79.345215 -309.810391) (xy 79.304024 -309.7747) (xy 79.268333 -309.733509)
			(xy 79.238867 -309.687659) (xy 79.216225 -309.638082) (xy 79.20087 -309.585787) (xy 79.193114 -309.531839)
			(xy 79.192628 -309.504588) (xy 60.178188 -309.504588) (xy 60.178188 -309.782464) (xy 60.177847 -309.787796)
			(xy 60.170312 -309.795341) (xy 60.16498 -309.795672) (xy 60.164472 -309.795672) (xy 58.691526 -309.795672)
			(xy 58.686228 -309.795161) (xy 58.678656 -309.787751) (xy 58.678064 -309.782464) (xy 52.63388 -309.782464)
			(xy 52.633546 -309.787798) (xy 52.626006 -309.795343) (xy 52.620672 -309.795672) (xy 52.104798 -309.795672)
			(xy 52.096924 -309.795963) (xy 52.081919 -309.800744) (xy 52.075334 -309.80507) (xy 52.054267 -309.819478)
			(xy 52.008618 -309.842302) (xy 51.960009 -309.857855) (xy 51.90959 -309.865769) (xy 51.884072 -309.866284)
			(xy 51.858552 -309.865778) (xy 51.808126 -309.857889) (xy 51.759514 -309.842334) (xy 51.713875 -309.819483)
			(xy 51.69281 -309.80507) (xy 51.686214 -309.800763) (xy 51.671218 -309.79597) (xy 51.663346 -309.795672)
			(xy 51.147472 -309.795672) (xy 51.142127 -309.795388) (xy 51.134586 -309.78781) (xy 51.134264 -309.782464)
			(xy 45.09008 -309.782464) (xy 45.089746 -309.787798) (xy 45.082206 -309.795343) (xy 45.076872 -309.795672)
			(xy 45.076364 -309.795672) (xy 44.560744 -309.795672) (xy 44.552868 -309.79594) (xy 44.537864 -309.800737)
			(xy 44.53128 -309.80507) (xy 44.5102 -309.819458) (xy 44.464556 -309.842286) (xy 44.415951 -309.857845)
			(xy 44.365534 -309.865766) (xy 44.340018 -309.866284) (xy 44.314497 -309.865805) (xy 44.26407 -309.857908)
			(xy 44.215458 -309.842345) (xy 44.16982 -309.819487) (xy 44.148756 -309.80507) (xy 44.142172 -309.800742)
			(xy 44.127166 -309.795962) (xy 44.119292 -309.795672) (xy 43.603418 -309.795672) (xy 43.598119 -309.795166)
			(xy 43.590547 -309.787752) (xy 43.589956 -309.782464) (xy 37.545772 -309.782464) (xy 37.545446 -309.7878)
			(xy 37.5379 -309.795346) (xy 37.532564 -309.795672) (xy 37.01669 -309.795672) (xy 37.008815 -309.795959)
			(xy 36.993811 -309.800743) (xy 36.987226 -309.80507) (xy 36.966161 -309.819481) (xy 36.920512 -309.842304)
			(xy 36.871902 -309.857857) (xy 36.821482 -309.86577) (xy 36.795964 -309.866284) (xy 36.770444 -309.865782)
			(xy 36.720018 -309.857892) (xy 36.671406 -309.842335) (xy 36.625767 -309.819484) (xy 36.604702 -309.80507)
			(xy 36.598108 -309.80076) (xy 36.58311 -309.795969) (xy 36.575238 -309.795672) (xy 36.059364 -309.795672)
			(xy 36.054088 -309.795225) (xy 36.046646 -309.787742) (xy 36.046156 -309.782464) (xy 30.001972 -309.782464)
			(xy 30.001646 -309.7878) (xy 29.9941 -309.795346) (xy 29.988764 -309.795672) (xy 29.47289 -309.795672)
			(xy 29.465015 -309.795959) (xy 29.450011 -309.800743) (xy 29.443426 -309.80507) (xy 29.422361 -309.819481)
			(xy 29.376712 -309.842304) (xy 29.328102 -309.857857) (xy 29.277682 -309.86577) (xy 29.252164 -309.866284)
			(xy 29.226644 -309.865782) (xy 29.176218 -309.857892) (xy 29.127606 -309.842335) (xy 29.081967 -309.819484)
			(xy 29.060902 -309.80507) (xy 29.054308 -309.80076) (xy 29.03931 -309.795969) (xy 29.031438 -309.795672)
			(xy 28.515564 -309.795672) (xy 28.510288 -309.795225) (xy 28.502846 -309.787742) (xy 28.502356 -309.782464)
			(xy 22.458172 -309.782464) (xy 22.457846 -309.7878) (xy 22.4503 -309.795346) (xy 22.444964 -309.795672)
			(xy 22.444456 -309.795672) (xy 21.928836 -309.795672) (xy 21.920959 -309.795936) (xy 21.905955 -309.800736)
			(xy 21.899372 -309.80507) (xy 21.878294 -309.819461) (xy 21.832649 -309.842289) (xy 21.784043 -309.857847)
			(xy 21.733627 -309.865766) (xy 21.70811 -309.866284) (xy 21.682589 -309.865809) (xy 21.632162 -309.857911)
			(xy 21.58355 -309.842346) (xy 21.537912 -309.819487) (xy 21.516848 -309.80507) (xy 21.510266 -309.800739)
			(xy 21.495259 -309.795961) (xy 21.487384 -309.795672) (xy 20.97151 -309.795672) (xy 20.96621 -309.795172)
			(xy 20.958639 -309.787753) (xy 20.958048 -309.782464) (xy 2.509012 -309.782464) (xy 2.509012 -310.632348)
			(xy 16.85798 -310.632348) (xy 16.85798 -310.13781) (xy 16.85829 -310.132366) (xy 16.865997 -310.124677)
			(xy 16.871442 -310.124348) (xy 17.38757 -310.124348) (xy 17.39538 -310.12403) (xy 17.410252 -310.119248)
			(xy 17.41678 -310.11495) (xy 17.437869 -310.100601) (xy 17.48353 -310.07787) (xy 17.532136 -310.062411)
			(xy 17.582539 -310.054588) (xy 17.633545 -310.054588) (xy 17.683948 -310.062411) (xy 17.732554 -310.07787)
			(xy 17.778215 -310.100601) (xy 17.799304 -310.11495) (xy 17.805838 -310.119237) (xy 17.820706 -310.124023)
			(xy 17.828514 -310.124348) (xy 18.344642 -310.124348) (xy 18.350014 -310.124823) (xy 18.357597 -310.132437)
			(xy 18.358104 -310.13781) (xy 18.358104 -310.632348) (xy 24.402288 -310.632348) (xy 24.402288 -310.13781)
			(xy 24.402736 -310.132496) (xy 24.41019 -310.124922) (xy 24.415496 -310.124348) (xy 24.931624 -310.124348)
			(xy 24.939436 -310.124053) (xy 24.954308 -310.119255) (xy 24.960834 -310.11495) (xy 24.981923 -310.100601)
			(xy 25.027584 -310.07787) (xy 25.07619 -310.062411) (xy 25.126593 -310.054588) (xy 25.177599 -310.054588)
			(xy 25.228002 -310.062411) (xy 25.276608 -310.07787) (xy 25.322269 -310.100601) (xy 25.343358 -310.11495)
			(xy 25.34988 -310.119257) (xy 25.364757 -310.124031) (xy 25.372568 -310.124348) (xy 25.888696 -310.124348)
			(xy 25.893948 -310.124893) (xy 25.901388 -310.132306) (xy 25.901904 -310.137556) (xy 25.901904 -310.138064)
			(xy 25.901904 -310.632348) (xy 31.946088 -310.632348) (xy 31.946088 -310.13781) (xy 31.946536 -310.132496)
			(xy 31.95399 -310.124922) (xy 31.959296 -310.124348) (xy 32.475424 -310.124348) (xy 32.483236 -310.124053)
			(xy 32.498108 -310.119255) (xy 32.504634 -310.11495) (xy 32.525723 -310.100601) (xy 32.571384 -310.07787)
			(xy 32.61999 -310.062411) (xy 32.670393 -310.054588) (xy 32.721399 -310.054588) (xy 32.771802 -310.062411)
			(xy 32.820408 -310.07787) (xy 32.866069 -310.100601) (xy 32.887158 -310.11495) (xy 32.89368 -310.119257)
			(xy 32.908557 -310.124031) (xy 32.916368 -310.124348) (xy 33.432496 -310.124348) (xy 33.437748 -310.124893)
			(xy 33.445188 -310.132306) (xy 33.445704 -310.137556) (xy 33.445704 -310.138064) (xy 33.445704 -310.632348)
			(xy 39.489888 -310.632348) (xy 39.489888 -310.13781) (xy 39.490452 -310.132459) (xy 39.498002 -310.124876)
			(xy 39.50335 -310.124348) (xy 40.019478 -310.124348) (xy 40.027288 -310.124034) (xy 40.04216 -310.119249)
			(xy 40.048688 -310.11495) (xy 40.069777 -310.100601) (xy 40.115438 -310.07787) (xy 40.164044 -310.062411)
			(xy 40.214447 -310.054588) (xy 40.265453 -310.054588) (xy 40.315856 -310.062411) (xy 40.364462 -310.07787)
			(xy 40.410123 -310.100601) (xy 40.431212 -310.11495) (xy 40.437745 -310.11924) (xy 40.452614 -310.124025)
			(xy 40.460422 -310.124348) (xy 40.97655 -310.124348) (xy 40.981922 -310.124818) (xy 40.989506 -310.132436)
			(xy 40.990012 -310.13781) (xy 40.990012 -310.632348) (xy 47.034196 -310.632348) (xy 47.034196 -310.13781)
			(xy 47.034724 -310.132517) (xy 47.042123 -310.124948) (xy 47.047404 -310.124348) (xy 47.563532 -310.124348)
			(xy 47.57134 -310.124014) (xy 47.586212 -310.119243) (xy 47.592742 -310.11495) (xy 47.613831 -310.100601)
			(xy 47.659492 -310.07787) (xy 47.708098 -310.062411) (xy 47.758501 -310.054588) (xy 47.809507 -310.054588)
			(xy 47.85991 -310.062411) (xy 47.908516 -310.07787) (xy 47.954177 -310.100601) (xy 47.975266 -310.11495)
			(xy 47.981809 -310.119222) (xy 47.99667 -310.124018) (xy 48.004476 -310.124348) (xy 48.520604 -310.124348)
			(xy 48.525857 -310.124887) (xy 48.533297 -310.132305) (xy 48.533812 -310.137556) (xy 48.533812 -310.138064)
			(xy 48.533812 -310.632348) (xy 54.577996 -310.632348) (xy 54.577996 -310.13781) (xy 54.578553 -310.132457)
			(xy 54.586107 -310.124874) (xy 54.591458 -310.124348) (xy 56.064658 -310.124348) (xy 56.07009 -310.124709)
			(xy 56.077779 -310.132379) (xy 56.07812 -310.13781) (xy 56.07812 -310.603646) (xy 98.925888 -310.603646)
			(xy 98.925888 -309.740046) (xy 98.926374 -309.712795) (xy 98.93413 -309.658847) (xy 98.949485 -309.606552)
			(xy 98.972127 -309.556975) (xy 99.001593 -309.511125) (xy 99.037284 -309.469934) (xy 99.078475 -309.434243)
			(xy 99.124325 -309.404777) (xy 99.173902 -309.382135) (xy 99.226197 -309.36678) (xy 99.280145 -309.359024)
			(xy 99.334647 -309.359024) (xy 99.388595 -309.36678) (xy 99.44089 -309.382135) (xy 99.490467 -309.404777)
			(xy 99.536317 -309.434243) (xy 99.577508 -309.469934) (xy 99.613199 -309.511125) (xy 99.642665 -309.556975)
			(xy 99.665307 -309.606552) (xy 99.680662 -309.658847) (xy 99.688418 -309.712795) (xy 99.688904 -309.740046)
			(xy 99.688904 -309.782464) (xy 167.778176 -309.782464) (xy 167.778176 -309.287926) (xy 167.778645 -309.282617)
			(xy 167.786084 -309.275042) (xy 167.791384 -309.274464) (xy 169.264584 -309.274464) (xy 169.269838 -309.275002)
			(xy 169.27728 -309.28242) (xy 169.277792 -309.287672) (xy 169.277792 -309.782464) (xy 175.321976 -309.782464)
			(xy 175.321976 -309.287926) (xy 175.3223 -309.282485) (xy 175.329997 -309.274796) (xy 175.335438 -309.274464)
			(xy 175.851566 -309.274464) (xy 175.859375 -309.274142) (xy 175.874247 -309.269362) (xy 175.880776 -309.265066)
			(xy 175.901865 -309.250717) (xy 175.947526 -309.227986) (xy 175.996132 -309.212527) (xy 176.046535 -309.204704)
			(xy 176.097541 -309.204704) (xy 176.147944 -309.212527) (xy 176.19655 -309.227986) (xy 176.242211 -309.250717)
			(xy 176.2633 -309.265066) (xy 176.269834 -309.269353) (xy 176.284702 -309.274139) (xy 176.29251 -309.274464)
			(xy 176.808638 -309.274464) (xy 176.814013 -309.274928) (xy 176.821598 -309.282549) (xy 176.8221 -309.287926)
			(xy 176.8221 -309.782464) (xy 182.866284 -309.782464) (xy 182.866284 -309.287926) (xy 182.866746 -309.282615)
			(xy 182.87419 -309.27504) (xy 182.879492 -309.274464) (xy 183.39562 -309.274464) (xy 183.403432 -309.274165)
			(xy 183.418303 -309.26937) (xy 183.42483 -309.265066) (xy 183.445919 -309.250717) (xy 183.49158 -309.227986)
			(xy 183.540186 -309.212527) (xy 183.590589 -309.204704) (xy 183.641595 -309.204704) (xy 183.691998 -309.212527)
			(xy 183.740604 -309.227986) (xy 183.786265 -309.250717) (xy 183.807354 -309.265066) (xy 183.813876 -309.269373)
			(xy 183.828753 -309.274147) (xy 183.836564 -309.274464) (xy 184.352692 -309.274464) (xy 184.357947 -309.274997)
			(xy 184.365389 -309.282418) (xy 184.3659 -309.287672) (xy 184.3659 -309.28818) (xy 184.3659 -309.782464)
			(xy 190.410084 -309.782464) (xy 190.410084 -309.287926) (xy 190.410401 -309.282483) (xy 190.418103 -309.274793)
			(xy 190.423546 -309.274464) (xy 190.939674 -309.274464) (xy 190.947484 -309.274145) (xy 190.962355 -309.269363)
			(xy 190.968884 -309.265066) (xy 190.989973 -309.250717) (xy 191.035634 -309.227986) (xy 191.08424 -309.212527)
			(xy 191.134643 -309.204704) (xy 191.185649 -309.204704) (xy 191.236052 -309.212527) (xy 191.284658 -309.227986)
			(xy 191.330319 -309.250717) (xy 191.351408 -309.265066) (xy 191.357941 -309.269356) (xy 191.37281 -309.27414)
			(xy 191.380618 -309.274464) (xy 191.896746 -309.274464) (xy 191.902122 -309.274923) (xy 191.909706 -309.282548)
			(xy 191.910208 -309.287926) (xy 191.910208 -309.782464) (xy 197.954392 -309.782464) (xy 197.954392 -309.287926)
			(xy 197.954935 -309.282636) (xy 197.962323 -309.275066) (xy 197.9676 -309.274464) (xy 198.483728 -309.274464)
			(xy 198.49154 -309.274168) (xy 198.506411 -309.269371) (xy 198.512938 -309.265066) (xy 198.534027 -309.250717)
			(xy 198.579688 -309.227986) (xy 198.628294 -309.212527) (xy 198.678697 -309.204704) (xy 198.729703 -309.204704)
			(xy 198.780106 -309.212527) (xy 198.828712 -309.227986) (xy 198.874373 -309.250717) (xy 198.895462 -309.265066)
			(xy 198.902005 -309.269338) (xy 198.916866 -309.274133) (xy 198.924672 -309.274464) (xy 199.4408 -309.274464)
			(xy 199.446056 -309.274992) (xy 199.453497 -309.282417) (xy 199.454008 -309.287672) (xy 199.454008 -309.28818)
			(xy 199.454008 -309.782464) (xy 205.498192 -309.782464) (xy 205.498192 -309.287926) (xy 205.498735 -309.282636)
			(xy 205.506123 -309.275066) (xy 205.5114 -309.274464) (xy 206.027528 -309.274464) (xy 206.03534 -309.274168)
			(xy 206.050211 -309.269371) (xy 206.056738 -309.265066) (xy 206.077827 -309.250717) (xy 206.123488 -309.227986)
			(xy 206.172094 -309.212527) (xy 206.222497 -309.204704) (xy 206.273503 -309.204704) (xy 206.323906 -309.212527)
			(xy 206.372512 -309.227986) (xy 206.418173 -309.250717) (xy 206.439262 -309.265066) (xy 206.445805 -309.269338)
			(xy 206.460666 -309.274133) (xy 206.468472 -309.274464) (xy 206.9846 -309.274464) (xy 206.989856 -309.274992)
			(xy 206.997297 -309.282417) (xy 206.997808 -309.287672) (xy 206.997808 -309.28818) (xy 206.997808 -309.78221)
			(xy 268.898116 -309.78221) (xy 268.898116 -309.287672) (xy 268.898578 -309.2824) (xy 268.90605 -309.274958)
			(xy 268.911324 -309.274464) (xy 268.911832 -309.274464) (xy 269.427706 -309.274464) (xy 269.435517 -309.274159)
			(xy 269.450389 -309.269368) (xy 269.456916 -309.265066) (xy 269.478005 -309.250717) (xy 269.523666 -309.227986)
			(xy 269.572272 -309.212527) (xy 269.622675 -309.204704) (xy 269.673681 -309.204704) (xy 269.724084 -309.212527)
			(xy 269.77269 -309.227986) (xy 269.818351 -309.250717) (xy 269.83944 -309.265066) (xy 269.845965 -309.269368)
			(xy 269.86084 -309.274145) (xy 269.86865 -309.274464) (xy 270.384778 -309.274464) (xy 270.390085 -309.274941)
			(xy 270.397659 -309.282375) (xy 270.39824 -309.287672) (xy 270.39824 -309.78221) (xy 270.398225 -309.782464)
			(xy 276.442424 -309.782464) (xy 276.442424 -309.781956) (xy 276.442424 -309.287672) (xy 276.442711 -309.282328)
			(xy 276.450287 -309.274787) (xy 276.455632 -309.274464) (xy 276.97176 -309.274464) (xy 276.979569 -309.274139)
			(xy 276.994441 -309.269361) (xy 277.00097 -309.265066) (xy 277.022059 -309.250717) (xy 277.06772 -309.227986)
			(xy 277.116326 -309.212527) (xy 277.166729 -309.204704) (xy 277.217735 -309.204704) (xy 277.268138 -309.212527)
			(xy 277.316744 -309.227986) (xy 277.362405 -309.250717) (xy 277.383494 -309.265066) (xy 277.39003 -309.26935)
			(xy 277.404896 -309.274138) (xy 277.412704 -309.274464) (xy 277.928832 -309.274464) (xy 277.934092 -309.274971)
			(xy 277.941531 -309.282412) (xy 277.94204 -309.287672) (xy 277.94204 -309.78221) (xy 277.942018 -309.782464)
			(xy 283.986224 -309.782464) (xy 283.986224 -309.781956) (xy 283.986224 -309.287672) (xy 283.986511 -309.282328)
			(xy 283.994087 -309.274787) (xy 283.999432 -309.274464) (xy 284.51556 -309.274464) (xy 284.523369 -309.274139)
			(xy 284.538241 -309.269361) (xy 284.54477 -309.265066) (xy 284.565859 -309.250717) (xy 284.61152 -309.227986)
			(xy 284.660126 -309.212527) (xy 284.710529 -309.204704) (xy 284.761535 -309.204704) (xy 284.811938 -309.212527)
			(xy 284.860544 -309.227986) (xy 284.906205 -309.250717) (xy 284.927294 -309.265066) (xy 284.93383 -309.26935)
			(xy 284.948696 -309.274138) (xy 284.956504 -309.274464) (xy 285.472632 -309.274464) (xy 285.477892 -309.274971)
			(xy 285.485331 -309.282412) (xy 285.48584 -309.287672) (xy 285.48584 -309.78221) (xy 291.530024 -309.78221)
			(xy 291.530024 -309.287672) (xy 291.530311 -309.282328) (xy 291.537887 -309.274787) (xy 291.543232 -309.274464)
			(xy 291.54374 -309.274464) (xy 292.059614 -309.274464) (xy 292.067425 -309.274162) (xy 292.082297 -309.269369)
			(xy 292.088824 -309.265066) (xy 292.109913 -309.250717) (xy 292.155574 -309.227986) (xy 292.20418 -309.212527)
			(xy 292.254583 -309.204704) (xy 292.305589 -309.204704) (xy 292.355992 -309.212527) (xy 292.404598 -309.227986)
			(xy 292.450259 -309.250717) (xy 292.471348 -309.265066) (xy 292.477872 -309.269371) (xy 292.492748 -309.274146)
			(xy 292.500558 -309.274464) (xy 293.016686 -309.274464) (xy 293.021994 -309.274935) (xy 293.029567 -309.282374)
			(xy 293.030148 -309.287672) (xy 293.030148 -309.78221) (xy 293.030133 -309.782464) (xy 299.074332 -309.782464)
			(xy 299.074332 -309.781956) (xy 299.074332 -309.287672) (xy 299.074612 -309.282326) (xy 299.082192 -309.274784)
			(xy 299.08754 -309.274464) (xy 299.603668 -309.274464) (xy 299.611477 -309.274143) (xy 299.626349 -309.269362)
			(xy 299.632878 -309.265066) (xy 299.653967 -309.250717) (xy 299.699628 -309.227986) (xy 299.748234 -309.212527)
			(xy 299.798637 -309.204704) (xy 299.849643 -309.204704) (xy 299.900046 -309.212527) (xy 299.948652 -309.227986)
			(xy 299.994313 -309.250717) (xy 300.015402 -309.265066) (xy 300.021936 -309.269353) (xy 300.036804 -309.274139)
			(xy 300.044612 -309.274464) (xy 300.56074 -309.274464) (xy 300.566001 -309.274965) (xy 300.57344 -309.282411)
			(xy 300.573948 -309.287672) (xy 300.573948 -309.78221) (xy 306.618132 -309.78221) (xy 306.618132 -309.287672)
			(xy 306.618412 -309.282326) (xy 306.625992 -309.274784) (xy 306.63134 -309.274464) (xy 306.631848 -309.274464)
			(xy 308.104794 -309.274464) (xy 308.110103 -309.27493) (xy 308.117676 -309.282372) (xy 308.118256 -309.287672)
			(xy 308.118256 -309.303166) (xy 341.51824 -309.303166) (xy 341.51824 -308.439566) (xy 341.518726 -308.412297)
			(xy 341.526488 -308.358313) (xy 341.541853 -308.305983) (xy 341.56451 -308.256373) (xy 341.593996 -308.210492)
			(xy 341.629711 -308.169275) (xy 341.670928 -308.13356) (xy 341.716809 -308.104074) (xy 341.766419 -308.081417)
			(xy 341.818749 -308.066052) (xy 341.872733 -308.05829) (xy 341.927271 -308.05829) (xy 341.981255 -308.066052)
			(xy 342.033585 -308.081417) (xy 342.035273 -308.082188) (xy 415.718244 -308.082188) (xy 415.718244 -307.58765)
			(xy 415.718757 -307.582351) (xy 415.726165 -307.574777) (xy 415.731452 -307.574188) (xy 417.204652 -307.574188)
			(xy 417.209977 -307.574559) (xy 417.21752 -307.582073) (xy 417.21786 -307.587396) (xy 417.21786 -308.082188)
			(xy 423.262044 -308.082188) (xy 423.262044 -307.58765) (xy 423.262518 -307.582279) (xy 423.270133 -307.574696)
			(xy 423.275506 -307.574188) (xy 423.791634 -307.574188) (xy 423.799442 -307.573848) (xy 423.814313 -307.56908)
			(xy 423.820844 -307.56479) (xy 423.841933 -307.550441) (xy 423.887594 -307.52771) (xy 423.9362 -307.512251)
			(xy 423.986603 -307.504428) (xy 424.037609 -307.504428) (xy 424.088012 -307.512251) (xy 424.136618 -307.52771)
			(xy 424.182279 -307.550441) (xy 424.203368 -307.56479) (xy 424.209908 -307.569067) (xy 424.224771 -307.573859)
			(xy 424.232578 -307.574188) (xy 424.748706 -307.574188) (xy 424.754059 -307.574741) (xy 424.761641 -307.582299)
			(xy 424.762168 -307.58765) (xy 424.762168 -308.082188) (xy 430.806352 -308.082188) (xy 430.806352 -307.58765)
			(xy 430.806858 -307.582349) (xy 430.814271 -307.574775) (xy 430.81956 -307.574188) (xy 431.335688 -307.574188)
			(xy 431.343498 -307.573871) (xy 431.358369 -307.569088) (xy 431.364898 -307.56479) (xy 431.385987 -307.550441)
			(xy 431.431648 -307.52771) (xy 431.480254 -307.512251) (xy 431.530657 -307.504428) (xy 431.581663 -307.504428)
			(xy 431.632066 -307.512251) (xy 431.680672 -307.52771) (xy 431.726333 -307.550441) (xy 431.747422 -307.56479)
			(xy 431.75395 -307.569088) (xy 431.768823 -307.573867) (xy 431.776632 -307.574188) (xy 432.29276 -307.574188)
			(xy 432.298086 -307.574553) (xy 432.305629 -307.582071) (xy 432.305968 -307.587396) (xy 432.305968 -307.587904)
			(xy 432.305968 -308.082188) (xy 438.350152 -308.082188) (xy 438.350152 -307.58765) (xy 438.350619 -307.582277)
			(xy 438.358238 -307.574693) (xy 438.363614 -307.574188) (xy 438.879742 -307.574188) (xy 438.88755 -307.573851)
			(xy 438.902422 -307.569081) (xy 438.908952 -307.56479) (xy 438.930041 -307.550441) (xy 438.975702 -307.52771)
			(xy 439.024308 -307.512251) (xy 439.074711 -307.504428) (xy 439.125717 -307.504428) (xy 439.17612 -307.512251)
			(xy 439.224726 -307.52771) (xy 439.270387 -307.550441) (xy 439.291476 -307.56479) (xy 439.298014 -307.56907)
			(xy 439.312879 -307.57386) (xy 439.320686 -307.574188) (xy 439.836814 -307.574188) (xy 439.842168 -307.574736)
			(xy 439.849749 -307.582298) (xy 439.850276 -307.58765) (xy 439.850276 -308.082188) (xy 445.89446 -308.082188)
			(xy 445.89446 -307.58765) (xy 445.894959 -307.582347) (xy 445.902376 -307.574772) (xy 445.907668 -307.574188)
			(xy 446.423796 -307.574188) (xy 446.431606 -307.573875) (xy 446.446478 -307.569089) (xy 446.453006 -307.56479)
			(xy 446.474095 -307.550441) (xy 446.519756 -307.52771) (xy 446.568362 -307.512251) (xy 446.618765 -307.504428)
			(xy 446.669771 -307.504428) (xy 446.720174 -307.512251) (xy 446.76878 -307.52771) (xy 446.814441 -307.550441)
			(xy 446.83553 -307.56479) (xy 446.842056 -307.569091) (xy 446.85693 -307.573868) (xy 446.86474 -307.574188)
			(xy 447.380868 -307.574188) (xy 447.386195 -307.574548) (xy 447.393737 -307.58207) (xy 447.394076 -307.587396)
			(xy 447.394076 -307.587904) (xy 447.394076 -308.082188) (xy 453.43826 -308.082188) (xy 453.43826 -307.58765)
			(xy 453.438759 -307.582347) (xy 453.446176 -307.574772) (xy 453.451468 -307.574188) (xy 453.967596 -307.574188)
			(xy 453.975406 -307.573875) (xy 453.990278 -307.569089) (xy 453.996806 -307.56479) (xy 454.017895 -307.550441)
			(xy 454.063556 -307.52771) (xy 454.112162 -307.512251) (xy 454.162565 -307.504428) (xy 454.213571 -307.504428)
			(xy 454.263974 -307.512251) (xy 454.31258 -307.52771) (xy 454.358241 -307.550441) (xy 454.37933 -307.56479)
			(xy 454.385856 -307.569091) (xy 454.40073 -307.573868) (xy 454.40854 -307.574188) (xy 454.924668 -307.574188)
			(xy 454.929995 -307.574548) (xy 454.937537 -307.58207) (xy 454.937876 -307.587396) (xy 454.937876 -307.587904)
			(xy 454.937876 -308.082188) (xy 454.937562 -308.087526) (xy 454.930007 -308.09507) (xy 454.924668 -308.095396)
			(xy 454.408794 -308.095396) (xy 454.400919 -308.095681) (xy 454.385915 -308.100465) (xy 454.37933 -308.104794)
			(xy 454.358266 -308.119206) (xy 454.312616 -308.142029) (xy 454.264006 -308.15758) (xy 454.213586 -308.165494)
			(xy 454.188068 -308.166008) (xy 454.162549 -308.1655) (xy 454.112122 -308.157611) (xy 454.063511 -308.142056)
			(xy 454.017872 -308.119207) (xy 453.996806 -308.104794) (xy 453.990215 -308.100478) (xy 453.975215 -308.095692)
			(xy 453.967342 -308.095396) (xy 453.451468 -308.095396) (xy 453.446198 -308.094925) (xy 453.438757 -308.087459)
			(xy 453.43826 -308.082188) (xy 447.394076 -308.082188) (xy 447.393762 -308.087526) (xy 447.386207 -308.09507)
			(xy 447.380868 -308.095396) (xy 446.864994 -308.095396) (xy 446.857119 -308.095681) (xy 446.842115 -308.100465)
			(xy 446.83553 -308.104794) (xy 446.814466 -308.119206) (xy 446.768816 -308.142029) (xy 446.720206 -308.15758)
			(xy 446.669786 -308.165494) (xy 446.644268 -308.166008) (xy 446.618749 -308.1655) (xy 446.568322 -308.157611)
			(xy 446.519711 -308.142056) (xy 446.474072 -308.119207) (xy 446.453006 -308.104794) (xy 446.446415 -308.100478)
			(xy 446.431415 -308.095692) (xy 446.423542 -308.095396) (xy 445.907668 -308.095396) (xy 445.902398 -308.094925)
			(xy 445.894957 -308.087459) (xy 445.89446 -308.082188) (xy 439.850276 -308.082188) (xy 439.849962 -308.087526)
			(xy 439.842407 -308.09507) (xy 439.837068 -308.095396) (xy 439.83656 -308.095396) (xy 439.32094 -308.095396)
			(xy 439.313063 -308.095658) (xy 439.298059 -308.100458) (xy 439.291476 -308.104794) (xy 439.270399 -308.119186)
			(xy 439.224754 -308.142013) (xy 439.176148 -308.157571) (xy 439.125731 -308.16549) (xy 439.100214 -308.166008)
			(xy 439.074693 -308.165527) (xy 439.024266 -308.15763) (xy 438.975655 -308.142067) (xy 438.930017 -308.11921)
			(xy 438.908952 -308.104794) (xy 438.902373 -308.100457) (xy 438.887363 -308.095684) (xy 438.879488 -308.095396)
			(xy 438.363614 -308.095396) (xy 438.35832 -308.094872) (xy 438.35075 -308.08747) (xy 438.350152 -308.082188)
			(xy 432.305968 -308.082188) (xy 432.305661 -308.087528) (xy 432.298101 -308.095072) (xy 432.29276 -308.095396)
			(xy 431.776886 -308.095396) (xy 431.769011 -308.095677) (xy 431.754006 -308.100464) (xy 431.747422 -308.104794)
			(xy 431.72636 -308.11921) (xy 431.680709 -308.142031) (xy 431.632099 -308.157582) (xy 431.581678 -308.165494)
			(xy 431.55616 -308.166008) (xy 431.53064 -308.165504) (xy 431.480214 -308.157613) (xy 431.431603 -308.142058)
			(xy 431.385964 -308.119207) (xy 431.364898 -308.104794) (xy 431.358309 -308.100475) (xy 431.343307 -308.095691)
			(xy 431.335434 -308.095396) (xy 430.81956 -308.095396) (xy 430.814289 -308.094931) (xy 430.806848 -308.08746)
			(xy 430.806352 -308.082188) (xy 424.762168 -308.082188) (xy 424.761861 -308.087528) (xy 424.754301 -308.095072)
			(xy 424.74896 -308.095396) (xy 424.748452 -308.095396) (xy 424.232832 -308.095396) (xy 424.224955 -308.095654)
			(xy 424.209951 -308.100457) (xy 424.203368 -308.104794) (xy 424.182293 -308.11919) (xy 424.136647 -308.142016)
			(xy 424.08804 -308.157572) (xy 424.037623 -308.165491) (xy 424.012106 -308.166008) (xy 423.986585 -308.165531)
			(xy 423.936158 -308.157632) (xy 423.887546 -308.142069) (xy 423.841909 -308.119211) (xy 423.820844 -308.104794)
			(xy 423.814267 -308.100454) (xy 423.799256 -308.095683) (xy 423.79138 -308.095396) (xy 423.275506 -308.095396)
			(xy 423.270211 -308.094877) (xy 423.262641 -308.087471) (xy 423.262044 -308.082188) (xy 417.21786 -308.082188)
			(xy 417.21756 -308.08753) (xy 417.209995 -308.095075) (xy 417.204652 -308.095396) (xy 415.731452 -308.095396)
			(xy 415.726181 -308.094936) (xy 415.71874 -308.087462) (xy 415.718244 -308.082188) (xy 342.035273 -308.082188)
			(xy 342.083195 -308.104074) (xy 342.129076 -308.13356) (xy 342.170293 -308.169275) (xy 342.206008 -308.210492)
			(xy 342.235494 -308.256373) (xy 342.258151 -308.305983) (xy 342.273516 -308.358313) (xy 342.281278 -308.412297)
			(xy 342.281764 -308.439566) (xy 342.281764 -308.93258) (xy 411.618176 -308.93258) (xy 411.618176 -308.932072)
			(xy 411.618176 -308.437788) (xy 411.618685 -308.432528) (xy 411.626124 -308.425087) (xy 411.631384 -308.42458)
			(xy 413.104584 -308.42458) (xy 413.109911 -308.424936) (xy 413.117452 -308.432462) (xy 413.117792 -308.437788)
			(xy 413.117792 -308.932326) (xy 419.161976 -308.932326) (xy 419.161976 -308.437788) (xy 419.162485 -308.432528)
			(xy 419.169924 -308.425087) (xy 419.175184 -308.42458) (xy 419.175692 -308.42458) (xy 419.691566 -308.42458)
			(xy 419.699375 -308.424255) (xy 419.714247 -308.419477) (xy 419.720776 -308.415182) (xy 419.741865 -308.400833)
			(xy 419.787526 -308.378102) (xy 419.836132 -308.362643) (xy 419.886535 -308.35482) (xy 419.937541 -308.35482)
			(xy 419.987944 -308.362643) (xy 420.03655 -308.378102) (xy 420.082211 -308.400833) (xy 420.1033 -308.415182)
			(xy 420.109833 -308.41947) (xy 420.124702 -308.424255) (xy 420.13251 -308.42458) (xy 420.648638 -308.42458)
			(xy 420.653956 -308.425003) (xy 420.661527 -308.432477) (xy 420.6621 -308.437788) (xy 420.6621 -308.932326)
			(xy 420.662075 -308.93258) (xy 426.706284 -308.93258) (xy 426.706284 -308.932072) (xy 426.706284 -308.437788)
			(xy 426.706786 -308.432526) (xy 426.71423 -308.425084) (xy 426.719492 -308.42458) (xy 427.23562 -308.42458)
			(xy 427.243431 -308.424278) (xy 427.258303 -308.419484) (xy 427.26483 -308.415182) (xy 427.285919 -308.400833)
			(xy 427.33158 -308.378102) (xy 427.380186 -308.362643) (xy 427.430589 -308.35482) (xy 427.481595 -308.35482)
			(xy 427.531998 -308.362643) (xy 427.580604 -308.378102) (xy 427.626265 -308.400833) (xy 427.647354 -308.415182)
			(xy 427.653875 -308.419491) (xy 427.668753 -308.424263) (xy 427.676564 -308.42458) (xy 428.192692 -308.42458)
			(xy 428.197951 -308.425099) (xy 428.205393 -308.43253) (xy 428.2059 -308.437788) (xy 428.2059 -308.932326)
			(xy 434.250084 -308.932326) (xy 434.250084 -308.437788) (xy 434.250586 -308.432526) (xy 434.25803 -308.425084)
			(xy 434.263292 -308.42458) (xy 434.2638 -308.42458) (xy 434.779674 -308.42458) (xy 434.787483 -308.424259)
			(xy 434.802355 -308.419478) (xy 434.808884 -308.415182) (xy 434.829973 -308.400833) (xy 434.875634 -308.378102)
			(xy 434.92424 -308.362643) (xy 434.974643 -308.35482) (xy 435.025649 -308.35482) (xy 435.076052 -308.362643)
			(xy 435.124658 -308.378102) (xy 435.170319 -308.400833) (xy 435.191408 -308.415182) (xy 435.19794 -308.419473)
			(xy 435.21281 -308.424256) (xy 435.220618 -308.42458) (xy 435.736746 -308.42458) (xy 435.742053 -308.425064)
			(xy 435.74963 -308.432491) (xy 435.750208 -308.437788) (xy 435.750208 -308.932326) (xy 435.750183 -308.93258)
			(xy 441.794392 -308.93258) (xy 441.794392 -308.932072) (xy 441.794392 -308.437788) (xy 441.794887 -308.432524)
			(xy 441.802335 -308.425082) (xy 441.8076 -308.42458) (xy 442.323728 -308.42458) (xy 442.33154 -308.424282)
			(xy 442.346411 -308.419485) (xy 442.352938 -308.415182) (xy 442.374027 -308.400833) (xy 442.419688 -308.378102)
			(xy 442.468294 -308.362643) (xy 442.518697 -308.35482) (xy 442.569703 -308.35482) (xy 442.620106 -308.362643)
			(xy 442.668712 -308.378102) (xy 442.714373 -308.400833) (xy 442.735462 -308.415182) (xy 442.742004 -308.419455)
			(xy 442.756866 -308.42425) (xy 442.764672 -308.42458) (xy 443.2808 -308.42458) (xy 443.28606 -308.425094)
			(xy 443.293502 -308.432529) (xy 443.294008 -308.437788) (xy 443.294008 -308.932326) (xy 443.293984 -308.93258)
			(xy 449.338192 -308.93258) (xy 449.338192 -308.932072) (xy 449.338192 -308.437788) (xy 449.338687 -308.432524)
			(xy 449.346135 -308.425082) (xy 449.3514 -308.42458) (xy 449.867528 -308.42458) (xy 449.87534 -308.424282)
			(xy 449.890211 -308.419485) (xy 449.896738 -308.415182) (xy 449.917827 -308.400833) (xy 449.963488 -308.378102)
			(xy 450.012094 -308.362643) (xy 450.062497 -308.35482) (xy 450.113503 -308.35482) (xy 450.163906 -308.362643)
			(xy 450.212512 -308.378102) (xy 450.258173 -308.400833) (xy 450.279262 -308.415182) (xy 450.285804 -308.419455)
			(xy 450.300666 -308.42425) (xy 450.308472 -308.42458) (xy 450.8246 -308.42458) (xy 450.82986 -308.425094)
			(xy 450.837302 -308.432529) (xy 450.837808 -308.437788) (xy 450.837808 -308.932326) (xy 450.8373 -308.937622)
			(xy 450.829885 -308.945189) (xy 450.8246 -308.945788) (xy 450.308726 -308.945788) (xy 450.300915 -308.946098)
			(xy 450.286043 -308.950885) (xy 450.279516 -308.955186) (xy 450.25839 -308.969529) (xy 450.212667 -308.992256)
			(xy 450.163996 -309.007687) (xy 450.113531 -309.015457) (xy 450.088 -309.015892) (xy 450.06247 -309.01545)
			(xy 450.012007 -309.007675) (xy 449.963334 -308.992247) (xy 449.917606 -308.969533) (xy 449.896484 -308.955186)
			(xy 449.88995 -308.950898) (xy 449.875082 -308.946111) (xy 449.867274 -308.945788) (xy 449.3514 -308.945788)
			(xy 449.346063 -308.945471) (xy 449.338521 -308.937918) (xy 449.338192 -308.93258) (xy 443.293984 -308.93258)
			(xy 443.2935 -308.937622) (xy 443.286085 -308.945189) (xy 443.2808 -308.945788) (xy 442.764926 -308.945788)
			(xy 442.757115 -308.946098) (xy 442.742243 -308.950885) (xy 442.735716 -308.955186) (xy 442.71459 -308.969529)
			(xy 442.668867 -308.992256) (xy 442.620196 -309.007687) (xy 442.569731 -309.015457) (xy 442.5442 -309.015892)
			(xy 442.51867 -309.01545) (xy 442.468207 -309.007675) (xy 442.419534 -308.992247) (xy 442.373806 -308.969533)
			(xy 442.352684 -308.955186) (xy 442.34615 -308.950898) (xy 442.331282 -308.946111) (xy 442.323474 -308.945788)
			(xy 441.8076 -308.945788) (xy 441.802263 -308.945471) (xy 441.794721 -308.937918) (xy 441.794392 -308.93258)
			(xy 435.750183 -308.93258) (xy 435.749671 -308.937682) (xy 435.742101 -308.945263) (xy 435.736746 -308.945788)
			(xy 435.220872 -308.945788) (xy 435.213059 -308.946075) (xy 435.198187 -308.950878) (xy 435.191662 -308.955186)
			(xy 435.170551 -308.969552) (xy 435.124823 -308.992274) (xy 435.076147 -309.007699) (xy 435.025678 -309.015461)
			(xy 435.000146 -309.015892) (xy 434.974617 -309.015427) (xy 434.924154 -309.007659) (xy 434.875482 -308.992238)
			(xy 434.829753 -308.96953) (xy 434.80863 -308.955186) (xy 434.802086 -308.950916) (xy 434.787226 -308.946118)
			(xy 434.77942 -308.945788) (xy 434.263546 -308.945788) (xy 434.258123 -308.945393) (xy 434.250436 -308.937746)
			(xy 434.250084 -308.932326) (xy 428.2059 -308.932326) (xy 428.205399 -308.937624) (xy 428.197979 -308.945192)
			(xy 428.192692 -308.945788) (xy 427.676818 -308.945788) (xy 427.669007 -308.946095) (xy 427.654135 -308.950884)
			(xy 427.647608 -308.955186) (xy 427.626484 -308.969532) (xy 427.580761 -308.992258) (xy 427.532088 -309.007689)
			(xy 427.481623 -309.015458) (xy 427.456092 -309.015892) (xy 427.430562 -309.015455) (xy 427.380098 -309.007678)
			(xy 427.331426 -308.992249) (xy 427.285698 -308.969533) (xy 427.264576 -308.955186) (xy 427.258044 -308.950895)
			(xy 427.243175 -308.94611) (xy 427.235366 -308.945788) (xy 426.719492 -308.945788) (xy 426.714154 -308.945477)
			(xy 426.706612 -308.937919) (xy 426.706284 -308.93258) (xy 420.662075 -308.93258) (xy 420.661571 -308.937684)
			(xy 420.653995 -308.945266) (xy 420.648638 -308.945788) (xy 420.132764 -308.945788) (xy 420.124955 -308.946114)
			(xy 420.110083 -308.95089) (xy 420.103554 -308.955186) (xy 420.082445 -308.969555) (xy 420.036717 -308.992277)
			(xy 419.988039 -309.007701) (xy 419.93757 -309.015462) (xy 419.912038 -309.015892) (xy 419.886509 -309.015431)
			(xy 419.836046 -309.007662) (xy 419.787374 -308.99224) (xy 419.741645 -308.96953) (xy 419.720522 -308.955186)
			(xy 419.71398 -308.950913) (xy 419.699118 -308.946117) (xy 419.691312 -308.945788) (xy 419.175438 -308.945788)
			(xy 419.170014 -308.945398) (xy 419.162328 -308.937748) (xy 419.161976 -308.932326) (xy 413.117792 -308.932326)
			(xy 413.117298 -308.937626) (xy 413.109873 -308.945193) (xy 413.104584 -308.945788) (xy 411.631384 -308.945788)
			(xy 411.626045 -308.945482) (xy 411.618503 -308.93792) (xy 411.618176 -308.93258) (xy 342.281764 -308.93258)
			(xy 342.281764 -309.303166) (xy 342.281278 -309.330435) (xy 342.273516 -309.384419) (xy 342.258151 -309.436749)
			(xy 342.235494 -309.486359) (xy 342.206008 -309.53224) (xy 342.170293 -309.573457) (xy 342.129076 -309.609172)
			(xy 342.083195 -309.638658) (xy 342.033585 -309.661315) (xy 341.981255 -309.67668) (xy 341.927271 -309.684442)
			(xy 341.872733 -309.684442) (xy 341.818749 -309.67668) (xy 341.766419 -309.661315) (xy 341.716809 -309.638658)
			(xy 341.670928 -309.609172) (xy 341.629711 -309.573457) (xy 341.593996 -309.53224) (xy 341.56451 -309.486359)
			(xy 341.541853 -309.436749) (xy 341.526488 -309.384419) (xy 341.518726 -309.330435) (xy 341.51824 -309.303166)
			(xy 308.118256 -309.303166) (xy 308.118256 -309.78221) (xy 308.118232 -309.782464) (xy 415.718244 -309.782464)
			(xy 415.718244 -309.287672) (xy 415.718771 -309.282417) (xy 415.726198 -309.274979) (xy 415.731452 -309.274464)
			(xy 417.204652 -309.274464) (xy 417.209971 -309.274857) (xy 417.217513 -309.282355) (xy 417.21786 -309.287672)
			(xy 417.21786 -309.78221) (xy 423.262044 -309.78221) (xy 423.262044 -309.287672) (xy 423.262571 -309.282417)
			(xy 423.269998 -309.274979) (xy 423.275252 -309.274464) (xy 423.27576 -309.274464) (xy 423.791634 -309.274464)
			(xy 423.799442 -309.274128) (xy 423.814314 -309.269358) (xy 423.820844 -309.265066) (xy 423.841933 -309.250717)
			(xy 423.887594 -309.227986) (xy 423.9362 -309.212527) (xy 423.986603 -309.204704) (xy 424.037609 -309.204704)
			(xy 424.088012 -309.212527) (xy 424.136618 -309.227986) (xy 424.182279 -309.250717) (xy 424.203368 -309.265066)
			(xy 424.209909 -309.26934) (xy 424.224772 -309.274134) (xy 424.232578 -309.274464) (xy 424.748706 -309.274464)
			(xy 424.754017 -309.274922) (xy 424.761589 -309.28237) (xy 424.762168 -309.287672) (xy 424.762168 -309.78221)
			(xy 424.762144 -309.782464) (xy 430.806352 -309.782464) (xy 430.806352 -309.781956) (xy 430.806352 -309.287672)
			(xy 430.806872 -309.282415) (xy 430.814304 -309.274977) (xy 430.81956 -309.274464) (xy 431.335688 -309.274464)
			(xy 431.343498 -309.274151) (xy 431.35837 -309.269365) (xy 431.364898 -309.265066) (xy 431.385987 -309.250717)
			(xy 431.431648 -309.227986) (xy 431.480254 -309.212527) (xy 431.530657 -309.204704) (xy 431.581663 -309.204704)
			(xy 431.632066 -309.212527) (xy 431.680672 -309.227986) (xy 431.726333 -309.250717) (xy 431.747422 -309.265066)
			(xy 431.753951 -309.269361) (xy 431.768823 -309.274142) (xy 431.776632 -309.274464) (xy 432.29276 -309.274464)
			(xy 432.29808 -309.274851) (xy 432.305622 -309.282354) (xy 432.305968 -309.287672) (xy 432.305968 -309.78221)
			(xy 438.350152 -309.78221) (xy 438.350152 -309.287672) (xy 438.350672 -309.282415) (xy 438.358104 -309.274977)
			(xy 438.36336 -309.274464) (xy 438.363868 -309.274464) (xy 438.879742 -309.274464) (xy 438.88755 -309.274132)
			(xy 438.902422 -309.269359) (xy 438.908952 -309.265066) (xy 438.930041 -309.250717) (xy 438.975702 -309.227986)
			(xy 439.024308 -309.212527) (xy 439.074711 -309.204704) (xy 439.125717 -309.204704) (xy 439.17612 -309.212527)
			(xy 439.224726 -309.227986) (xy 439.270387 -309.250717) (xy 439.291476 -309.265066) (xy 439.298016 -309.269343)
			(xy 439.312879 -309.274135) (xy 439.320686 -309.274464) (xy 439.836814 -309.274464) (xy 439.842125 -309.274917)
			(xy 439.849697 -309.282369) (xy 439.850276 -309.287672) (xy 439.850276 -309.78221) (xy 439.850251 -309.782464)
			(xy 445.89446 -309.782464) (xy 445.89446 -309.781956) (xy 445.89446 -309.287672) (xy 445.894973 -309.282414)
			(xy 445.90241 -309.274974) (xy 445.907668 -309.274464) (xy 446.423796 -309.274464) (xy 446.431607 -309.274155)
			(xy 446.446478 -309.269366) (xy 446.453006 -309.265066) (xy 446.474095 -309.250717) (xy 446.519756 -309.227986)
			(xy 446.568362 -309.212527) (xy 446.618765 -309.204704) (xy 446.669771 -309.204704) (xy 446.720174 -309.212527)
			(xy 446.76878 -309.227986) (xy 446.814441 -309.250717) (xy 446.83553 -309.265066) (xy 446.842058 -309.269364)
			(xy 446.856931 -309.274143) (xy 446.86474 -309.274464) (xy 447.380868 -309.274464) (xy 447.386189 -309.274846)
			(xy 447.39373 -309.282352) (xy 447.394076 -309.287672) (xy 447.394076 -309.78221) (xy 447.394052 -309.782464)
			(xy 453.43826 -309.782464) (xy 453.43826 -309.781956) (xy 453.43826 -309.287672) (xy 453.438773 -309.282414)
			(xy 453.44621 -309.274974) (xy 453.451468 -309.274464) (xy 453.967596 -309.274464) (xy 453.975407 -309.274155)
			(xy 453.990278 -309.269366) (xy 453.996806 -309.265066) (xy 454.017895 -309.250717) (xy 454.063556 -309.227986)
			(xy 454.112162 -309.212527) (xy 454.162565 -309.204704) (xy 454.213571 -309.204704) (xy 454.263974 -309.212527)
			(xy 454.31258 -309.227986) (xy 454.358241 -309.250717) (xy 454.37933 -309.265066) (xy 454.385858 -309.269364)
			(xy 454.400731 -309.274143) (xy 454.40854 -309.274464) (xy 454.924668 -309.274464) (xy 454.929989 -309.274846)
			(xy 454.93753 -309.282352) (xy 454.937876 -309.287672) (xy 454.937876 -309.78221) (xy 454.937385 -309.787512)
			(xy 454.929959 -309.795081) (xy 454.924668 -309.795672) (xy 454.408794 -309.795672) (xy 454.400982 -309.795971)
			(xy 454.386111 -309.800766) (xy 454.379584 -309.80507) (xy 454.358466 -309.819425) (xy 454.312741 -309.842149)
			(xy 454.264066 -309.857578) (xy 454.213599 -309.865343) (xy 454.188068 -309.865776) (xy 454.162537 -309.865353)
			(xy 454.112073 -309.857573) (xy 454.063401 -309.84214) (xy 454.017674 -309.819419) (xy 453.996552 -309.80507)
			(xy 453.990026 -309.800768) (xy 453.975152 -309.79599) (xy 453.967342 -309.795672) (xy 453.451468 -309.795672)
			(xy 453.446123 -309.795391) (xy 453.438582 -309.787811) (xy 453.43826 -309.782464) (xy 447.394052 -309.782464)
			(xy 447.393585 -309.787512) (xy 447.386159 -309.795081) (xy 447.380868 -309.795672) (xy 446.864994 -309.795672)
			(xy 446.857182 -309.795971) (xy 446.842311 -309.800766) (xy 446.835784 -309.80507) (xy 446.814666 -309.819425)
			(xy 446.768941 -309.842149) (xy 446.720266 -309.857578) (xy 446.669799 -309.865343) (xy 446.644268 -309.865776)
			(xy 446.618737 -309.865353) (xy 446.568273 -309.857573) (xy 446.519601 -309.84214) (xy 446.473874 -309.819419)
			(xy 446.452752 -309.80507) (xy 446.446226 -309.800768) (xy 446.431352 -309.79599) (xy 446.423542 -309.795672)
			(xy 445.907668 -309.795672) (xy 445.902323 -309.795391) (xy 445.894782 -309.787811) (xy 445.89446 -309.782464)
			(xy 439.850251 -309.782464) (xy 439.849758 -309.787572) (xy 439.842176 -309.795156) (xy 439.836814 -309.795672)
			(xy 439.32094 -309.795672) (xy 439.31313 -309.795991) (xy 439.298258 -309.800772) (xy 439.29173 -309.80507)
			(xy 439.270627 -309.819448) (xy 439.224896 -309.842168) (xy 439.176217 -309.85759) (xy 439.125747 -309.865347)
			(xy 439.100214 -309.865776) (xy 439.074684 -309.86533) (xy 439.024221 -309.857557) (xy 438.975548 -309.84213)
			(xy 438.92982 -309.819416) (xy 438.908698 -309.80507) (xy 438.902162 -309.800786) (xy 438.887296 -309.795997)
			(xy 438.879488 -309.795672) (xy 438.363614 -309.795672) (xy 438.358184 -309.795312) (xy 438.350497 -309.78764)
			(xy 438.350152 -309.78221) (xy 432.305968 -309.78221) (xy 432.305484 -309.787514) (xy 432.298053 -309.795084)
			(xy 432.29276 -309.795672) (xy 431.776886 -309.795672) (xy 431.769074 -309.795968) (xy 431.754202 -309.800765)
			(xy 431.747676 -309.80507) (xy 431.72656 -309.819428) (xy 431.680834 -309.842152) (xy 431.632159 -309.85758)
			(xy 431.581691 -309.865344) (xy 431.55616 -309.865776) (xy 431.530629 -309.865357) (xy 431.480165 -309.857576)
			(xy 431.431492 -309.842141) (xy 431.385765 -309.81942) (xy 431.364644 -309.80507) (xy 431.35812 -309.800765)
			(xy 431.343244 -309.795989) (xy 431.335434 -309.795672) (xy 430.81956 -309.795672) (xy 430.814284 -309.795228)
			(xy 430.806841 -309.787743) (xy 430.806352 -309.782464) (xy 424.762144 -309.782464) (xy 424.761657 -309.787574)
			(xy 424.75407 -309.795158) (xy 424.748706 -309.795672) (xy 424.232832 -309.795672) (xy 424.225022 -309.795987)
			(xy 424.21015 -309.800771) (xy 424.203622 -309.80507) (xy 424.182493 -309.819408) (xy 424.136772 -309.842137)
			(xy 424.088101 -309.85757) (xy 424.037636 -309.86534) (xy 424.012106 -309.865776) (xy 423.986576 -309.865334)
			(xy 423.936112 -309.85756) (xy 423.88744 -309.842132) (xy 423.841712 -309.819417) (xy 423.82059 -309.80507)
			(xy 423.814056 -309.800783) (xy 423.799188 -309.795996) (xy 423.79138 -309.795672) (xy 423.275506 -309.795672)
			(xy 423.270145 -309.795147) (xy 423.26256 -309.78757) (xy 423.262044 -309.78221) (xy 417.21786 -309.78221)
			(xy 417.217383 -309.787515) (xy 417.209948 -309.795086) (xy 417.204652 -309.795672) (xy 415.731452 -309.795672)
			(xy 415.726175 -309.795233) (xy 415.718733 -309.787744) (xy 415.718244 -309.782464) (xy 308.118232 -309.782464)
			(xy 308.117756 -309.787577) (xy 308.110161 -309.795162) (xy 308.104794 -309.795672) (xy 306.631594 -309.795672)
			(xy 306.626232 -309.795155) (xy 306.618647 -309.787572) (xy 306.618132 -309.78221) (xy 300.573948 -309.78221)
			(xy 300.573482 -309.787518) (xy 300.566039 -309.795089) (xy 300.56074 -309.795672) (xy 300.044866 -309.795672)
			(xy 300.037057 -309.796002) (xy 300.022185 -309.800775) (xy 300.015656 -309.80507) (xy 299.994546 -309.819437)
			(xy 299.948818 -309.842159) (xy 299.900141 -309.857584) (xy 299.849672 -309.865345) (xy 299.82414 -309.865776)
			(xy 299.798611 -309.865317) (xy 299.748148 -309.857548) (xy 299.699475 -309.842125) (xy 299.653747 -309.819415)
			(xy 299.632624 -309.80507) (xy 299.626082 -309.800796) (xy 299.61122 -309.796001) (xy 299.603414 -309.795672)
			(xy 299.08754 -309.795672) (xy 299.082204 -309.795343) (xy 299.074659 -309.787799) (xy 299.074332 -309.782464)
			(xy 293.030133 -309.782464) (xy 293.029826 -309.78765) (xy 293.022126 -309.795336) (xy 293.016686 -309.795672)
			(xy 292.500812 -309.795672) (xy 292.493001 -309.795979) (xy 292.478129 -309.800768) (xy 292.471602 -309.80507)
			(xy 292.450479 -309.819417) (xy 292.404755 -309.842143) (xy 292.356083 -309.857574) (xy 292.305617 -309.865342)
			(xy 292.280086 -309.865776) (xy 292.254556 -309.865344) (xy 292.204092 -309.857567) (xy 292.155419 -309.842136)
			(xy 292.109692 -309.819418) (xy 292.08857 -309.80507) (xy 292.08204 -309.800775) (xy 292.067169 -309.795993)
			(xy 292.05936 -309.795672) (xy 291.543486 -309.795672) (xy 291.538123 -309.79516) (xy 291.530539 -309.787573)
			(xy 291.530024 -309.78221) (xy 285.48584 -309.78221) (xy 285.485381 -309.78752) (xy 285.477933 -309.795092)
			(xy 285.472632 -309.795672) (xy 284.956758 -309.795672) (xy 284.948949 -309.795998) (xy 284.934077 -309.800774)
			(xy 284.927548 -309.80507) (xy 284.90644 -309.81944) (xy 284.860711 -309.842162) (xy 284.812034 -309.857586)
			(xy 284.761564 -309.865346) (xy 284.736032 -309.865776) (xy 284.710502 -309.865321) (xy 284.660039 -309.857551)
			(xy 284.611367 -309.842127) (xy 284.565639 -309.819415) (xy 284.544516 -309.80507) (xy 284.537976 -309.800793)
			(xy 284.523113 -309.796) (xy 284.515306 -309.795672) (xy 283.999432 -309.795672) (xy 283.994095 -309.795348)
			(xy 283.98655 -309.787801) (xy 283.986224 -309.782464) (xy 277.942018 -309.782464) (xy 277.941581 -309.78752)
			(xy 277.934133 -309.795092) (xy 277.928832 -309.795672) (xy 277.412958 -309.795672) (xy 277.405149 -309.795998)
			(xy 277.390277 -309.800774) (xy 277.383748 -309.80507) (xy 277.36264 -309.81944) (xy 277.316911 -309.842162)
			(xy 277.268234 -309.857586) (xy 277.217764 -309.865346) (xy 277.192232 -309.865776) (xy 277.166702 -309.865321)
			(xy 277.116239 -309.857551) (xy 277.067567 -309.842127) (xy 277.021839 -309.819415) (xy 277.000716 -309.80507)
			(xy 276.994176 -309.800793) (xy 276.979313 -309.796) (xy 276.971506 -309.795672) (xy 276.455632 -309.795672)
			(xy 276.450295 -309.795348) (xy 276.44275 -309.787801) (xy 276.442424 -309.782464) (xy 270.398225 -309.782464)
			(xy 270.397925 -309.787652) (xy 270.39022 -309.795338) (xy 270.384778 -309.795672) (xy 269.868904 -309.795672)
			(xy 269.861093 -309.795975) (xy 269.846221 -309.800767) (xy 269.839694 -309.80507) (xy 269.818573 -309.81942)
			(xy 269.772849 -309.842146) (xy 269.724175 -309.857576) (xy 269.673709 -309.865343) (xy 269.648178 -309.865776)
			(xy 269.622647 -309.865348) (xy 269.572183 -309.857569) (xy 269.523511 -309.842138) (xy 269.477784 -309.819419)
			(xy 269.456662 -309.80507) (xy 269.450134 -309.800772) (xy 269.435261 -309.795992) (xy 269.427452 -309.795672)
			(xy 268.911578 -309.795672) (xy 268.906214 -309.795165) (xy 268.89863 -309.787575) (xy 268.898116 -309.78221)
			(xy 206.997808 -309.78221) (xy 206.997808 -309.782464) (xy 206.997449 -309.787792) (xy 206.989927 -309.795335)
			(xy 206.9846 -309.795672) (xy 206.468726 -309.795672) (xy 206.460849 -309.795932) (xy 206.445845 -309.800734)
			(xy 206.439262 -309.80507) (xy 206.418187 -309.819466) (xy 206.372541 -309.842292) (xy 206.323934 -309.857849)
			(xy 206.273517 -309.865767) (xy 206.248 -309.866284) (xy 206.222479 -309.865814) (xy 206.172051 -309.857914)
			(xy 206.123439 -309.842348) (xy 206.077802 -309.819488) (xy 206.056738 -309.80507) (xy 206.050136 -309.800774)
			(xy 206.035144 -309.795974) (xy 206.027274 -309.795672) (xy 205.5114 -309.795672) (xy 205.506059 -309.79537)
			(xy 205.498516 -309.787806) (xy 205.498192 -309.782464) (xy 199.454008 -309.782464) (xy 199.453649 -309.787792)
			(xy 199.446127 -309.795335) (xy 199.4408 -309.795672) (xy 198.924926 -309.795672) (xy 198.917049 -309.795932)
			(xy 198.902045 -309.800734) (xy 198.895462 -309.80507) (xy 198.874387 -309.819466) (xy 198.828741 -309.842292)
			(xy 198.780134 -309.857849) (xy 198.729717 -309.865767) (xy 198.7042 -309.866284) (xy 198.678679 -309.865814)
			(xy 198.628251 -309.857914) (xy 198.579639 -309.842348) (xy 198.534002 -309.819488) (xy 198.512938 -309.80507)
			(xy 198.506336 -309.800774) (xy 198.491344 -309.795974) (xy 198.483474 -309.795672) (xy 197.9676 -309.795672)
			(xy 197.962259 -309.79537) (xy 197.954716 -309.787806) (xy 197.954392 -309.782464) (xy 191.910208 -309.782464)
			(xy 191.909849 -309.787792) (xy 191.902327 -309.795335) (xy 191.897 -309.795672) (xy 191.896492 -309.795672)
			(xy 191.380872 -309.795672) (xy 191.372997 -309.795952) (xy 191.357993 -309.80074) (xy 191.351408 -309.80507)
			(xy 191.330348 -309.819489) (xy 191.284697 -309.84231) (xy 191.236085 -309.85786) (xy 191.185664 -309.865771)
			(xy 191.160146 -309.866284) (xy 191.134626 -309.865791) (xy 191.084199 -309.857898) (xy 191.035587 -309.842339)
			(xy 190.989949 -309.819485) (xy 190.968884 -309.80507) (xy 190.962294 -309.800753) (xy 190.947293 -309.795966)
			(xy 190.93942 -309.795672) (xy 190.423546 -309.795672) (xy 190.41825 -309.795148) (xy 190.410677 -309.787748)
			(xy 190.410084 -309.782464) (xy 184.3659 -309.782464) (xy 184.365548 -309.787793) (xy 184.358021 -309.795337)
			(xy 184.352692 -309.795672) (xy 183.836818 -309.795672) (xy 183.828944 -309.795971) (xy 183.81394 -309.800746)
			(xy 183.807354 -309.80507) (xy 183.786281 -309.819469) (xy 183.740635 -309.842295) (xy 183.692027 -309.857851)
			(xy 183.641609 -309.865768) (xy 183.616092 -309.866284) (xy 183.590573 -309.865768) (xy 183.540147 -309.857882)
			(xy 183.491535 -309.84233) (xy 183.445896 -309.819482) (xy 183.42483 -309.80507) (xy 183.418229 -309.80077)
			(xy 183.403237 -309.795973) (xy 183.395366 -309.795672) (xy 182.879492 -309.795672) (xy 182.87415 -309.795375)
			(xy 182.866607 -309.787807) (xy 182.866284 -309.782464) (xy 176.8221 -309.782464) (xy 176.821748 -309.787793)
			(xy 176.814221 -309.795337) (xy 176.808892 -309.795672) (xy 176.808384 -309.795672) (xy 176.292764 -309.795672)
			(xy 176.284888 -309.795948) (xy 176.269884 -309.800739) (xy 176.2633 -309.80507) (xy 176.242215 -309.819449)
			(xy 176.196572 -309.84228) (xy 176.147969 -309.857841) (xy 176.097554 -309.865764) (xy 176.072038 -309.866284)
			(xy 176.046518 -309.865795) (xy 175.996091 -309.857901) (xy 175.947479 -309.842341) (xy 175.901841 -309.819485)
			(xy 175.880776 -309.80507) (xy 175.874188 -309.80075) (xy 175.859185 -309.795965) (xy 175.851312 -309.795672)
			(xy 175.335438 -309.795672) (xy 175.330141 -309.795153) (xy 175.322569 -309.787749) (xy 175.321976 -309.782464)
			(xy 169.277792 -309.782464) (xy 169.277447 -309.787795) (xy 169.269915 -309.795339) (xy 169.264584 -309.795672)
			(xy 167.791384 -309.795672) (xy 167.786041 -309.795381) (xy 167.778498 -309.787809) (xy 167.778176 -309.782464)
			(xy 99.688904 -309.782464) (xy 99.688904 -310.603646) (xy 99.688418 -310.630897) (xy 99.688209 -310.632348)
			(xy 163.678108 -310.632348) (xy 163.678108 -310.13781) (xy 163.678626 -310.132514) (xy 163.686032 -310.124944)
			(xy 163.691316 -310.124348) (xy 165.164516 -310.124348) (xy 165.16977 -310.124879) (xy 165.177209 -310.132303)
			(xy 165.177724 -310.137556) (xy 165.177724 -310.138064) (xy 165.177724 -310.632348) (xy 171.221908 -310.632348)
			(xy 171.221908 -310.13781) (xy 171.222454 -310.132455) (xy 171.230016 -310.12487) (xy 171.23537 -310.124348)
			(xy 171.751498 -310.124348) (xy 171.759309 -310.124042) (xy 171.774181 -310.119252) (xy 171.780708 -310.11495)
			(xy 171.801797 -310.100601) (xy 171.847458 -310.07787) (xy 171.896064 -310.062411) (xy 171.946467 -310.054588)
			(xy 171.997473 -310.054588) (xy 172.047876 -310.062411) (xy 172.096482 -310.07787) (xy 172.142143 -310.100601)
			(xy 172.163232 -310.11495) (xy 172.16976 -310.119247) (xy 172.184633 -310.124027) (xy 172.192442 -310.124348)
			(xy 172.70857 -310.124348) (xy 172.714003 -310.124701) (xy 172.721691 -310.132377) (xy 172.722032 -310.13781)
			(xy 172.722032 -310.632348) (xy 178.766216 -310.632348) (xy 178.766216 -310.13781) (xy 178.766727 -310.132513)
			(xy 178.774138 -310.124942) (xy 178.779424 -310.124348) (xy 179.295552 -310.124348) (xy 179.303361 -310.124023)
			(xy 179.318233 -310.119246) (xy 179.324762 -310.11495) (xy 179.345851 -310.100601) (xy 179.391512 -310.07787)
			(xy 179.440118 -310.062411) (xy 179.490521 -310.054588) (xy 179.541527 -310.054588) (xy 179.59193 -310.062411)
			(xy 179.640536 -310.07787) (xy 179.686197 -310.100601) (xy 179.707286 -310.11495) (xy 179.713824 -310.11923)
			(xy 179.728689 -310.124021) (xy 179.736496 -310.124348) (xy 180.252624 -310.124348) (xy 180.257879 -310.124874)
			(xy 180.265318 -310.132302) (xy 180.265832 -310.137556) (xy 180.265832 -310.138064) (xy 180.265832 -310.632348)
			(xy 186.310016 -310.632348) (xy 186.310016 -310.13781) (xy 186.310555 -310.132453) (xy 186.318122 -310.124868)
			(xy 186.323478 -310.124348) (xy 186.839606 -310.124348) (xy 186.847417 -310.124046) (xy 186.862289 -310.119253)
			(xy 186.868816 -310.11495) (xy 186.889905 -310.100601) (xy 186.935566 -310.07787) (xy 186.984172 -310.062411)
			(xy 187.034575 -310.054588) (xy 187.085581 -310.054588) (xy 187.135984 -310.062411) (xy 187.18459 -310.07787)
			(xy 187.230251 -310.100601) (xy 187.25134 -310.11495) (xy 187.257866 -310.11925) (xy 187.27274 -310.124029)
			(xy 187.28055 -310.124348) (xy 187.796678 -310.124348) (xy 187.802112 -310.124695) (xy 187.8098 -310.132376)
			(xy 187.81014 -310.13781) (xy 187.81014 -310.632348) (xy 193.854324 -310.632348) (xy 193.854324 -310.13781)
			(xy 193.854828 -310.132511) (xy 193.862244 -310.12494) (xy 193.867532 -310.124348) (xy 194.38366 -310.124348)
			(xy 194.391469 -310.124026) (xy 194.406341 -310.119247) (xy 194.41287 -310.11495) (xy 194.433959 -310.100601)
			(xy 194.47962 -310.07787) (xy 194.528226 -310.062411) (xy 194.578629 -310.054588) (xy 194.629635 -310.054588)
			(xy 194.680038 -310.062411) (xy 194.728644 -310.07787) (xy 194.774305 -310.100601) (xy 194.795394 -310.11495)
			(xy 194.801931 -310.119233) (xy 194.816797 -310.124022) (xy 194.824604 -310.124348) (xy 195.340732 -310.124348)
			(xy 195.345988 -310.124869) (xy 195.353426 -310.1323) (xy 195.35394 -310.137556) (xy 195.35394 -310.138064)
			(xy 195.35394 -310.632348) (xy 201.398124 -310.632348) (xy 201.398124 -310.13781) (xy 201.398628 -310.132511)
			(xy 201.406044 -310.12494) (xy 201.411332 -310.124348) (xy 201.92746 -310.124348) (xy 201.935269 -310.124026)
			(xy 201.950141 -310.119247) (xy 201.95667 -310.11495) (xy 201.977759 -310.100601) (xy 202.02342 -310.07787)
			(xy 202.072026 -310.062411) (xy 202.122429 -310.054588) (xy 202.173435 -310.054588) (xy 202.223838 -310.062411)
			(xy 202.272444 -310.07787) (xy 202.318105 -310.100601) (xy 202.339194 -310.11495) (xy 202.345731 -310.119233)
			(xy 202.360597 -310.124022) (xy 202.368404 -310.124348) (xy 202.884532 -310.124348) (xy 202.889788 -310.124869)
			(xy 202.897226 -310.1323) (xy 202.89774 -310.137556) (xy 202.89774 -310.138064) (xy 202.89774 -310.632094)
			(xy 264.798048 -310.632094) (xy 264.798048 -310.137556) (xy 264.798561 -310.132299) (xy 264.805999 -310.124861)
			(xy 264.811256 -310.124348) (xy 264.811764 -310.124348) (xy 265.327638 -310.124348) (xy 265.335447 -310.124017)
			(xy 265.350318 -310.119244) (xy 265.356848 -310.11495) (xy 265.377937 -310.100601) (xy 265.423598 -310.07787)
			(xy 265.472204 -310.062411) (xy 265.522607 -310.054588) (xy 265.573613 -310.054588) (xy 265.624016 -310.062411)
			(xy 265.672622 -310.07787) (xy 265.718283 -310.100601) (xy 265.739372 -310.11495) (xy 265.745913 -310.119224)
			(xy 265.760776 -310.124019) (xy 265.768582 -310.124348) (xy 266.28471 -310.124348) (xy 266.290017 -310.124817)
			(xy 266.297588 -310.132258) (xy 266.298172 -310.137556) (xy 266.298172 -310.632094) (xy 266.298147 -310.632348)
			(xy 272.342356 -310.632348) (xy 272.342356 -310.63184) (xy 272.342356 -310.137556) (xy 272.342862 -310.132297)
			(xy 272.350304 -310.124859) (xy 272.355564 -310.124348) (xy 272.871692 -310.124348) (xy 272.879503 -310.124039)
			(xy 272.894374 -310.119251) (xy 272.900902 -310.11495) (xy 272.921991 -310.100601) (xy 272.967652 -310.07787)
			(xy 273.016258 -310.062411) (xy 273.066661 -310.054588) (xy 273.117667 -310.054588) (xy 273.16807 -310.062411)
			(xy 273.216676 -310.07787) (xy 273.262337 -310.100601) (xy 273.283426 -310.11495) (xy 273.289955 -310.119245)
			(xy 273.304827 -310.124027) (xy 273.312636 -310.124348) (xy 273.828764 -310.124348) (xy 273.834012 -310.124914)
			(xy 273.841454 -310.132311) (xy 273.841972 -310.137556) (xy 273.841972 -310.632094) (xy 273.841948 -310.632348)
			(xy 279.886156 -310.632348) (xy 279.886156 -310.63184) (xy 279.886156 -310.137556) (xy 279.886662 -310.132297)
			(xy 279.894104 -310.124859) (xy 279.899364 -310.124348) (xy 280.415492 -310.124348) (xy 280.423303 -310.124039)
			(xy 280.438174 -310.119251) (xy 280.444702 -310.11495) (xy 280.465791 -310.100601) (xy 280.511452 -310.07787)
			(xy 280.560058 -310.062411) (xy 280.610461 -310.054588) (xy 280.661467 -310.054588) (xy 280.71187 -310.062411)
			(xy 280.760476 -310.07787) (xy 280.806137 -310.100601) (xy 280.827226 -310.11495) (xy 280.833755 -310.119245)
			(xy 280.848627 -310.124027) (xy 280.856436 -310.124348) (xy 281.372564 -310.124348) (xy 281.377812 -310.124914)
			(xy 281.385254 -310.132311) (xy 281.385772 -310.137556) (xy 281.385772 -310.632094) (xy 287.429956 -310.632094)
			(xy 287.429956 -310.137556) (xy 287.430462 -310.132297) (xy 287.437904 -310.124859) (xy 287.443164 -310.124348)
			(xy 287.443672 -310.124348) (xy 287.959546 -310.124348) (xy 287.967355 -310.12402) (xy 287.982227 -310.119245)
			(xy 287.988756 -310.11495) (xy 288.009845 -310.100601) (xy 288.055506 -310.07787) (xy 288.104112 -310.062411)
			(xy 288.154515 -310.054588) (xy 288.205521 -310.054588) (xy 288.255924 -310.062411) (xy 288.30453 -310.07787)
			(xy 288.350191 -310.100601) (xy 288.37128 -310.11495) (xy 288.37782 -310.119227) (xy 288.392683 -310.12402)
			(xy 288.40049 -310.124348) (xy 288.916618 -310.124348) (xy 288.921926 -310.124812) (xy 288.929497 -310.132257)
			(xy 288.93008 -310.137556) (xy 288.93008 -310.632094) (xy 288.930055 -310.632348) (xy 294.974264 -310.632348)
			(xy 294.974264 -310.63184) (xy 294.974264 -310.137556) (xy 294.974763 -310.132295) (xy 294.98221 -310.124856)
			(xy 294.987472 -310.124348) (xy 295.5036 -310.124348) (xy 295.511411 -310.124043) (xy 295.526283 -310.119252)
			(xy 295.53281 -310.11495) (xy 295.553899 -310.100601) (xy 295.59956 -310.07787) (xy 295.648166 -310.062411)
			(xy 295.698569 -310.054588) (xy 295.749575 -310.054588) (xy 295.799978 -310.062411) (xy 295.848584 -310.07787)
			(xy 295.894245 -310.100601) (xy 295.915334 -310.11495) (xy 295.921862 -310.119248) (xy 295.936735 -310.124028)
			(xy 295.944544 -310.124348) (xy 296.460672 -310.124348) (xy 296.465921 -310.124909) (xy 296.473362 -310.13231)
			(xy 296.47388 -310.137556) (xy 296.47388 -310.632094) (xy 302.518064 -310.632094) (xy 302.518064 -310.137556)
			(xy 302.518563 -310.132295) (xy 302.52601 -310.124856) (xy 302.531272 -310.124348) (xy 304.004726 -310.124348)
			(xy 304.010035 -310.124807) (xy 304.017605 -310.132256) (xy 304.018188 -310.137556) (xy 304.018188 -310.632094)
			(xy 304.017648 -310.637451) (xy 304.010082 -310.645036) (xy 304.004726 -310.645556) (xy 302.531526 -310.645556)
			(xy 302.526093 -310.645203) (xy 302.518405 -310.637526) (xy 302.518064 -310.632094) (xy 296.47388 -310.632094)
			(xy 296.473375 -310.637393) (xy 296.46596 -310.644963) (xy 296.460672 -310.645556) (xy 295.944798 -310.645556)
			(xy 295.936987 -310.64586) (xy 295.922115 -310.650652) (xy 295.915588 -310.654954) (xy 295.894467 -310.669305)
			(xy 295.848743 -310.692031) (xy 295.80007 -310.707461) (xy 295.749603 -310.715227) (xy 295.724072 -310.71566)
			(xy 295.698541 -310.715238) (xy 295.648077 -310.707458) (xy 295.599404 -310.692025) (xy 295.553677 -310.669304)
			(xy 295.532556 -310.654954) (xy 295.52603 -310.650652) (xy 295.511156 -310.645875) (xy 295.503346 -310.645556)
			(xy 294.987472 -310.645556) (xy 294.982217 -310.645029) (xy 294.974779 -310.637602) (xy 294.974264 -310.632348)
			(xy 288.930055 -310.632348) (xy 288.929548 -310.637453) (xy 288.921976 -310.645038) (xy 288.916618 -310.645556)
			(xy 288.400744 -310.645556) (xy 288.392935 -310.645879) (xy 288.378063 -310.650658) (xy 288.371534 -310.654954)
			(xy 288.350429 -310.669328) (xy 288.304699 -310.692049) (xy 288.256021 -310.707472) (xy 288.20555 -310.715231)
			(xy 288.180018 -310.71566) (xy 288.154488 -310.715215) (xy 288.104025 -310.707442) (xy 288.055352 -310.692015)
			(xy 288.009624 -310.669301) (xy 287.988502 -310.654954) (xy 287.981966 -310.65067) (xy 287.9671 -310.645882)
			(xy 287.959292 -310.645556) (xy 287.443418 -310.645556) (xy 287.437984 -310.645208) (xy 287.430297 -310.637528)
			(xy 287.429956 -310.632094) (xy 281.385772 -310.632094) (xy 281.385274 -310.637395) (xy 281.377854 -310.644965)
			(xy 281.372564 -310.645556) (xy 280.85669 -310.645556) (xy 280.848878 -310.645856) (xy 280.834007 -310.65065)
			(xy 280.82748 -310.654954) (xy 280.806362 -310.669308) (xy 280.760637 -310.692034) (xy 280.711962 -310.707462)
			(xy 280.661495 -310.715228) (xy 280.635964 -310.71566) (xy 280.610433 -310.715242) (xy 280.559968 -310.707461)
			(xy 280.511296 -310.692026) (xy 280.465569 -310.669304) (xy 280.444448 -310.654954) (xy 280.437924 -310.650649)
			(xy 280.423048 -310.645874) (xy 280.415238 -310.645556) (xy 279.899364 -310.645556) (xy 279.894109 -310.645034)
			(xy 279.886671 -310.637603) (xy 279.886156 -310.632348) (xy 273.841948 -310.632348) (xy 273.841474 -310.637395)
			(xy 273.834054 -310.644965) (xy 273.828764 -310.645556) (xy 273.31289 -310.645556) (xy 273.305078 -310.645856)
			(xy 273.290207 -310.65065) (xy 273.28368 -310.654954) (xy 273.262562 -310.669308) (xy 273.216837 -310.692034)
			(xy 273.168162 -310.707462) (xy 273.117695 -310.715228) (xy 273.092164 -310.71566) (xy 273.066633 -310.715242)
			(xy 273.016168 -310.707461) (xy 272.967496 -310.692026) (xy 272.921769 -310.669304) (xy 272.900648 -310.654954)
			(xy 272.894124 -310.650649) (xy 272.879248 -310.645874) (xy 272.871438 -310.645556) (xy 272.355564 -310.645556)
			(xy 272.350309 -310.645034) (xy 272.342871 -310.637603) (xy 272.342356 -310.632348) (xy 266.298147 -310.632348)
			(xy 266.297647 -310.637455) (xy 266.29007 -310.64504) (xy 266.28471 -310.645556) (xy 265.768836 -310.645556)
			(xy 265.761026 -310.645876) (xy 265.746155 -310.650657) (xy 265.739626 -310.654954) (xy 265.718495 -310.669288)
			(xy 265.672774 -310.692018) (xy 265.624104 -310.707453) (xy 265.57364 -310.715224) (xy 265.54811 -310.71566)
			(xy 265.52258 -310.715219) (xy 265.472116 -310.707445) (xy 265.423444 -310.692017) (xy 265.377716 -310.669301)
			(xy 265.356594 -310.654954) (xy 265.35006 -310.650667) (xy 265.335192 -310.64588) (xy 265.327384 -310.645556)
			(xy 264.81151 -310.645556) (xy 264.806075 -310.645214) (xy 264.798388 -310.637529) (xy 264.798048 -310.632094)
			(xy 202.89774 -310.632094) (xy 202.89774 -310.632348) (xy 202.89724 -310.637609) (xy 202.889793 -310.645047)
			(xy 202.884532 -310.645556) (xy 202.368658 -310.645556) (xy 202.360782 -310.645832) (xy 202.345779 -310.650624)
			(xy 202.339194 -310.654954) (xy 202.318109 -310.669334) (xy 202.272467 -310.692165) (xy 202.223863 -310.707726)
			(xy 202.173448 -310.715649) (xy 202.147932 -310.716168) (xy 202.122411 -310.715685) (xy 202.071984 -310.70779)
			(xy 202.023372 -310.692228) (xy 201.977734 -310.669371) (xy 201.95667 -310.654954) (xy 201.950084 -310.65063)
			(xy 201.93508 -310.645848) (xy 201.927206 -310.645556) (xy 201.411332 -310.645556) (xy 201.406084 -310.644989)
			(xy 201.398643 -310.637592) (xy 201.398124 -310.632348) (xy 195.35394 -310.632348) (xy 195.35344 -310.637609)
			(xy 195.345993 -310.645047) (xy 195.340732 -310.645556) (xy 194.824858 -310.645556) (xy 194.816982 -310.645832)
			(xy 194.801979 -310.650624) (xy 194.795394 -310.654954) (xy 194.774309 -310.669334) (xy 194.728667 -310.692165)
			(xy 194.680063 -310.707726) (xy 194.629648 -310.715649) (xy 194.604132 -310.716168) (xy 194.578611 -310.715685)
			(xy 194.528184 -310.70779) (xy 194.479572 -310.692228) (xy 194.433934 -310.669371) (xy 194.41287 -310.654954)
			(xy 194.406284 -310.65063) (xy 194.39128 -310.645848) (xy 194.383406 -310.645556) (xy 193.867532 -310.645556)
			(xy 193.862284 -310.644989) (xy 193.854843 -310.637592) (xy 193.854324 -310.632348) (xy 187.81014 -310.632348)
			(xy 187.80964 -310.637609) (xy 187.802193 -310.645047) (xy 187.796932 -310.645556) (xy 187.796424 -310.645556)
			(xy 187.280804 -310.645556) (xy 187.27293 -310.645852) (xy 187.257926 -310.65063) (xy 187.25134 -310.654954)
			(xy 187.23027 -310.669357) (xy 187.184622 -310.692183) (xy 187.136014 -310.707737) (xy 187.085595 -310.715653)
			(xy 187.060078 -310.716168) (xy 187.034558 -310.715662) (xy 186.984132 -310.707773) (xy 186.93552 -310.692218)
			(xy 186.889881 -310.669368) (xy 186.868816 -310.654954) (xy 186.862219 -310.650648) (xy 186.847223 -310.645855)
			(xy 186.839352 -310.645556) (xy 186.323478 -310.645556) (xy 186.31817 -310.645091) (xy 186.3106 -310.637647)
			(xy 186.310016 -310.632348) (xy 180.265832 -310.632348) (xy 180.265339 -310.637611) (xy 180.257888 -310.645049)
			(xy 180.252624 -310.645556) (xy 179.73675 -310.645556) (xy 179.728874 -310.645829) (xy 179.71387 -310.650623)
			(xy 179.707286 -310.654954) (xy 179.686203 -310.669337) (xy 179.64056 -310.692167) (xy 179.591956 -310.707727)
			(xy 179.54154 -310.715649) (xy 179.516024 -310.716168) (xy 179.490503 -310.715689) (xy 179.440076 -310.707792)
			(xy 179.391464 -310.692229) (xy 179.345826 -310.669371) (xy 179.324762 -310.654954) (xy 179.318178 -310.650627)
			(xy 179.303172 -310.645847) (xy 179.295298 -310.645556) (xy 178.779424 -310.645556) (xy 178.774176 -310.644994)
			(xy 178.766735 -310.637593) (xy 178.766216 -310.632348) (xy 172.722032 -310.632348) (xy 172.721539 -310.637611)
			(xy 172.714088 -310.645049) (xy 172.708824 -310.645556) (xy 172.708316 -310.645556) (xy 172.192696 -310.645556)
			(xy 172.184822 -310.645849) (xy 172.169818 -310.650629) (xy 172.163232 -310.654954) (xy 172.142164 -310.669361)
			(xy 172.096516 -310.692185) (xy 172.047907 -310.707739) (xy 171.997488 -310.715653) (xy 171.97197 -310.716168)
			(xy 171.94645 -310.715666) (xy 171.896024 -310.707776) (xy 171.847412 -310.69222) (xy 171.801773 -310.669368)
			(xy 171.780708 -310.654954) (xy 171.774113 -310.650645) (xy 171.759116 -310.645853) (xy 171.751244 -310.645556)
			(xy 171.23537 -310.645556) (xy 171.230061 -310.645096) (xy 171.222491 -310.637648) (xy 171.221908 -310.632348)
			(xy 165.177724 -310.632348) (xy 165.177239 -310.637613) (xy 165.169782 -310.645051) (xy 165.164516 -310.645556)
			(xy 163.691316 -310.645556) (xy 163.686067 -310.645) (xy 163.678626 -310.637595) (xy 163.678108 -310.632348)
			(xy 99.688209 -310.632348) (xy 99.680662 -310.684845) (xy 99.665307 -310.73714) (xy 99.642665 -310.786717)
			(xy 99.613199 -310.832567) (xy 99.577508 -310.873758) (xy 99.536317 -310.909449) (xy 99.490467 -310.938915)
			(xy 99.44089 -310.961557) (xy 99.388595 -310.976912) (xy 99.334647 -310.984668) (xy 99.280145 -310.984668)
			(xy 99.226197 -310.976912) (xy 99.173902 -310.961557) (xy 99.124325 -310.938915) (xy 99.078475 -310.909449)
			(xy 99.037284 -310.873758) (xy 99.001593 -310.832567) (xy 98.972127 -310.786717) (xy 98.949485 -310.73714)
			(xy 98.93413 -310.684845) (xy 98.926374 -310.630897) (xy 98.925888 -310.603646) (xy 56.07812 -310.603646)
			(xy 56.07812 -310.632348) (xy 56.077638 -310.637614) (xy 56.070179 -310.645053) (xy 56.064912 -310.645556)
			(xy 54.591458 -310.645556) (xy 54.586148 -310.645104) (xy 54.578579 -310.63765) (xy 54.577996 -310.632348)
			(xy 48.533812 -310.632348) (xy 48.533337 -310.637616) (xy 48.525873 -310.645055) (xy 48.520604 -310.645556)
			(xy 48.00473 -310.645556) (xy 47.996853 -310.64582) (xy 47.981849 -310.65062) (xy 47.975266 -310.654954)
			(xy 47.954189 -310.669346) (xy 47.908544 -310.692174) (xy 47.859938 -310.707732) (xy 47.809521 -310.715651)
			(xy 47.784004 -310.716168) (xy 47.758483 -310.715699) (xy 47.708055 -310.707799) (xy 47.659443 -310.692233)
			(xy 47.613806 -310.669372) (xy 47.592742 -310.654954) (xy 47.586162 -310.650619) (xy 47.571153 -310.645844)
			(xy 47.563278 -310.645556) (xy 47.047404 -310.645556) (xy 47.042153 -310.645008) (xy 47.034713 -310.637597)
			(xy 47.034196 -310.632348) (xy 40.990012 -310.632348) (xy 40.989537 -310.637616) (xy 40.982073 -310.645055)
			(xy 40.976804 -310.645556) (xy 40.976296 -310.645556) (xy 40.460676 -310.645556) (xy 40.452801 -310.64584)
			(xy 40.437797 -310.650626) (xy 40.431212 -310.654954) (xy 40.41015 -310.669369) (xy 40.3645 -310.692192)
			(xy 40.315889 -310.707743) (xy 40.265468 -310.715655) (xy 40.23995 -310.716168) (xy 40.21443 -310.715676)
			(xy 40.164003 -310.707783) (xy 40.115391 -310.692224) (xy 40.069753 -310.669369) (xy 40.048688 -310.654954)
			(xy 40.042098 -310.650637) (xy 40.027097 -310.64585) (xy 40.019224 -310.645556) (xy 39.50335 -310.645556)
			(xy 39.498051 -310.645043) (xy 39.490477 -310.637635) (xy 39.489888 -310.632348) (xy 33.445704 -310.632348)
			(xy 33.445237 -310.637618) (xy 33.437767 -310.645057) (xy 33.432496 -310.645556) (xy 32.916622 -310.645556)
			(xy 32.908749 -310.64586) (xy 32.893745 -310.650632) (xy 32.887158 -310.654954) (xy 32.866083 -310.669349)
			(xy 32.820437 -310.692177) (xy 32.771831 -310.707733) (xy 32.721413 -310.715651) (xy 32.695896 -310.716168)
			(xy 32.670375 -310.715703) (xy 32.619947 -310.707802) (xy 32.571335 -310.692235) (xy 32.525698 -310.669373)
			(xy 32.504634 -310.654954) (xy 32.498033 -310.650655) (xy 32.48304 -310.645857) (xy 32.47517 -310.645556)
			(xy 31.959296 -310.645556) (xy 31.954044 -310.645013) (xy 31.946605 -310.637598) (xy 31.946088 -310.632348)
			(xy 25.901904 -310.632348) (xy 25.901437 -310.637618) (xy 25.893967 -310.645057) (xy 25.888696 -310.645556)
			(xy 25.372822 -310.645556) (xy 25.364949 -310.64586) (xy 25.349945 -310.650632) (xy 25.343358 -310.654954)
			(xy 25.322283 -310.669349) (xy 25.276637 -310.692177) (xy 25.228031 -310.707733) (xy 25.177613 -310.715651)
			(xy 25.152096 -310.716168) (xy 25.126575 -310.715703) (xy 25.076147 -310.707802) (xy 25.027535 -310.692235)
			(xy 24.981898 -310.669373) (xy 24.960834 -310.654954) (xy 24.954233 -310.650655) (xy 24.93924 -310.645857)
			(xy 24.93137 -310.645556) (xy 24.415496 -310.645556) (xy 24.410244 -310.645013) (xy 24.402805 -310.637598)
			(xy 24.402288 -310.632348) (xy 18.358104 -310.632348) (xy 18.357637 -310.637618) (xy 18.350167 -310.645057)
			(xy 18.344896 -310.645556) (xy 18.344388 -310.645556) (xy 17.828768 -310.645556) (xy 17.820893 -310.645837)
			(xy 17.805889 -310.650625) (xy 17.799304 -310.654954) (xy 17.778216 -310.66933) (xy 17.732575 -310.692161)
			(xy 17.683972 -310.707724) (xy 17.633558 -310.715648) (xy 17.608042 -310.716168) (xy 17.582522 -310.71568)
			(xy 17.532094 -310.707786) (xy 17.483483 -310.692226) (xy 17.437845 -310.66937) (xy 17.41678 -310.654954)
			(xy 17.410192 -310.650634) (xy 17.395189 -310.645849) (xy 17.387316 -310.645556) (xy 16.871442 -310.645556)
			(xy 16.866142 -310.645048) (xy 16.858568 -310.637637) (xy 16.85798 -310.632348) (xy 2.509012 -310.632348)
			(xy 2.509012 -311.482486) (xy 20.958048 -311.482486) (xy 20.958048 -310.987948) (xy 20.958455 -310.982633)
			(xy 20.965943 -310.975092) (xy 20.971256 -310.97474) (xy 20.971764 -310.97474) (xy 21.487638 -310.97474)
			(xy 21.495447 -310.97441) (xy 21.510319 -310.969636) (xy 21.516848 -310.965342) (xy 21.537937 -310.950993)
			(xy 21.583598 -310.928262) (xy 21.632204 -310.912803) (xy 21.682607 -310.90498) (xy 21.733613 -310.90498)
			(xy 21.784016 -310.912803) (xy 21.832622 -310.928262) (xy 21.878283 -310.950993) (xy 21.899372 -310.965342)
			(xy 21.905914 -310.969616) (xy 21.920776 -310.974411) (xy 21.928582 -310.97474) (xy 22.44471 -310.97474)
			(xy 22.450015 -310.975217) (xy 22.457586 -310.982652) (xy 22.458172 -310.987948) (xy 22.458172 -311.482486)
			(xy 22.458155 -311.48274) (xy 28.502356 -311.48274) (xy 28.502356 -311.482232) (xy 28.502356 -310.987948)
			(xy 28.502756 -310.982631) (xy 28.510249 -310.97509) (xy 28.515564 -310.97474) (xy 29.031692 -310.97474)
			(xy 29.039503 -310.974433) (xy 29.054375 -310.969643) (xy 29.060902 -310.965342) (xy 29.081991 -310.950993)
			(xy 29.127652 -310.928262) (xy 29.176258 -310.912803) (xy 29.226661 -310.90498) (xy 29.277667 -310.90498)
			(xy 29.32807 -310.912803) (xy 29.376676 -310.928262) (xy 29.422337 -310.950993) (xy 29.443426 -310.965342)
			(xy 29.449956 -310.969636) (xy 29.464827 -310.974418) (xy 29.472636 -310.97474) (xy 29.988764 -310.97474)
			(xy 29.994103 -310.975056) (xy 30.001649 -310.982609) (xy 30.001972 -310.987948) (xy 30.001972 -311.482486)
			(xy 30.001948 -311.48274) (xy 36.046156 -311.48274) (xy 36.046156 -311.482232) (xy 36.046156 -310.987948)
			(xy 36.046556 -310.982631) (xy 36.054049 -310.97509) (xy 36.059364 -310.97474) (xy 36.575492 -310.97474)
			(xy 36.583303 -310.974433) (xy 36.598175 -310.969643) (xy 36.604702 -310.965342) (xy 36.625791 -310.950993)
			(xy 36.671452 -310.928262) (xy 36.720058 -310.912803) (xy 36.770461 -310.90498) (xy 36.821467 -310.90498)
			(xy 36.87187 -310.912803) (xy 36.920476 -310.928262) (xy 36.966137 -310.950993) (xy 36.987226 -310.965342)
			(xy 36.993756 -310.969636) (xy 37.008627 -310.974418) (xy 37.016436 -310.97474) (xy 37.532564 -310.97474)
			(xy 37.537903 -310.975056) (xy 37.545449 -310.982609) (xy 37.545772 -310.987948) (xy 37.545772 -311.482486)
			(xy 43.589956 -311.482486) (xy 43.589956 -310.987948) (xy 43.590356 -310.982631) (xy 43.597849 -310.97509)
			(xy 43.603164 -310.97474) (xy 43.603672 -310.97474) (xy 44.119546 -310.97474) (xy 44.127355 -310.974413)
			(xy 44.142227 -310.969637) (xy 44.148756 -310.965342) (xy 44.169845 -310.950993) (xy 44.215506 -310.928262)
			(xy 44.264112 -310.912803) (xy 44.314515 -310.90498) (xy 44.365521 -310.90498) (xy 44.415924 -310.912803)
			(xy 44.46453 -310.928262) (xy 44.510191 -310.950993) (xy 44.53128 -310.965342) (xy 44.53782 -310.969619)
			(xy 44.552683 -310.974412) (xy 44.56049 -310.97474) (xy 45.076618 -310.97474) (xy 45.081924 -310.975211)
			(xy 45.089495 -310.982651) (xy 45.09008 -310.987948) (xy 45.09008 -311.482486) (xy 45.090054 -311.48274)
			(xy 51.134264 -311.48274) (xy 51.134264 -311.482232) (xy 51.134264 -310.987948) (xy 51.134657 -310.982629)
			(xy 51.142155 -310.975087) (xy 51.147472 -310.97474) (xy 51.6636 -310.97474) (xy 51.671411 -310.974436)
			(xy 51.686283 -310.969644) (xy 51.69281 -310.965342) (xy 51.713899 -310.950993) (xy 51.75956 -310.928262)
			(xy 51.808166 -310.912803) (xy 51.858569 -310.90498) (xy 51.909575 -310.90498) (xy 51.959978 -310.912803)
			(xy 52.008584 -310.928262) (xy 52.054245 -310.950993) (xy 52.075334 -310.965342) (xy 52.081862 -310.969639)
			(xy 52.096735 -310.97442) (xy 52.104544 -310.97474) (xy 52.620672 -310.97474) (xy 52.626012 -310.97505)
			(xy 52.633558 -310.982607) (xy 52.63388 -310.987948) (xy 52.63388 -311.482486) (xy 58.678064 -311.482486)
			(xy 58.678064 -310.987948) (xy 58.678457 -310.982629) (xy 58.685955 -310.975087) (xy 58.691272 -310.97474)
			(xy 58.69178 -310.97474) (xy 60.164726 -310.97474) (xy 60.170033 -310.975206) (xy 60.177603 -310.98265)
			(xy 60.178188 -310.987948) (xy 60.178188 -311.482486) (xy 60.178162 -311.48274) (xy 167.778176 -311.48274)
			(xy 167.778176 -310.987948) (xy 167.778558 -310.982626) (xy 167.786064 -310.975083) (xy 167.791384 -310.97474)
			(xy 169.264584 -310.97474) (xy 169.269926 -310.975042) (xy 169.277471 -310.982605) (xy 169.277792 -310.987948)
			(xy 169.277792 -311.482486) (xy 175.321976 -311.482486) (xy 175.321976 -310.987948) (xy 175.322358 -310.982626)
			(xy 175.329864 -310.975083) (xy 175.335184 -310.97474) (xy 175.335692 -310.97474) (xy 175.851566 -310.97474)
			(xy 175.859376 -310.974422) (xy 175.874248 -310.96964) (xy 175.880776 -310.965342) (xy 175.901865 -310.950993)
			(xy 175.947526 -310.928262) (xy 175.996132 -310.912803) (xy 176.046535 -310.90498) (xy 176.097541 -310.90498)
			(xy 176.147944 -310.912803) (xy 176.19655 -310.928262) (xy 176.242211 -310.950993) (xy 176.2633 -310.965342)
			(xy 176.269836 -310.969626) (xy 176.284702 -310.974415) (xy 176.29251 -310.97474) (xy 176.808638 -310.97474)
			(xy 176.813947 -310.975198) (xy 176.821516 -310.982648) (xy 176.8221 -310.987948) (xy 176.8221 -311.482486)
			(xy 176.822074 -311.48274) (xy 182.866284 -311.48274) (xy 182.866284 -311.482232) (xy 182.866284 -310.987948)
			(xy 182.866659 -310.982624) (xy 182.87417 -310.975081) (xy 182.879492 -310.97474) (xy 183.39562 -310.97474)
			(xy 183.403432 -310.974445) (xy 183.418304 -310.969647) (xy 183.42483 -310.965342) (xy 183.445919 -310.950993)
			(xy 183.49158 -310.928262) (xy 183.540186 -310.912803) (xy 183.590589 -310.90498) (xy 183.641595 -310.90498)
			(xy 183.691998 -310.912803) (xy 183.740604 -310.928262) (xy 183.786265 -310.950993) (xy 183.807354 -310.965342)
			(xy 183.813878 -310.969647) (xy 183.828754 -310.974423) (xy 183.836564 -310.97474) (xy 184.352692 -310.97474)
			(xy 184.358035 -310.975037) (xy 184.365579 -310.982604) (xy 184.3659 -310.987948) (xy 184.3659 -311.482486)
			(xy 190.410084 -311.482486) (xy 190.410084 -310.987948) (xy 190.410459 -310.982624) (xy 190.41797 -310.975081)
			(xy 190.423292 -310.97474) (xy 190.4238 -310.97474) (xy 190.939674 -310.97474) (xy 190.947484 -310.974425)
			(xy 190.962356 -310.969641) (xy 190.968884 -310.965342) (xy 190.989973 -310.950993) (xy 191.035634 -310.928262)
			(xy 191.08424 -310.912803) (xy 191.134643 -310.90498) (xy 191.185649 -310.90498) (xy 191.236052 -310.912803)
			(xy 191.284658 -310.928262) (xy 191.330319 -310.950993) (xy 191.351408 -310.965342) (xy 191.357942 -310.969629)
			(xy 191.37281 -310.974416) (xy 191.380618 -310.97474) (xy 191.896746 -310.97474) (xy 191.902044 -310.975259)
			(xy 191.909618 -310.982663) (xy 191.910208 -310.987948) (xy 191.910208 -311.482486) (xy 191.910181 -311.48274)
			(xy 197.954392 -311.48274) (xy 197.954392 -311.482232) (xy 197.954392 -310.987948) (xy 197.954759 -310.982622)
			(xy 197.962276 -310.975079) (xy 197.9676 -310.97474) (xy 198.483728 -310.97474) (xy 198.49154 -310.974449)
			(xy 198.506412 -310.969648) (xy 198.512938 -310.965342) (xy 198.534027 -310.950993) (xy 198.579688 -310.928262)
			(xy 198.628294 -310.912803) (xy 198.678697 -310.90498) (xy 198.729703 -310.90498) (xy 198.780106 -310.912803)
			(xy 198.828712 -310.928262) (xy 198.874373 -310.950993) (xy 198.895462 -310.965342) (xy 198.902006 -310.969612)
			(xy 198.916866 -310.974409) (xy 198.924672 -310.97474) (xy 199.4408 -310.97474) (xy 199.446144 -310.975031)
			(xy 199.453688 -310.982603) (xy 199.454008 -310.987948) (xy 199.454008 -311.482486) (xy 199.453982 -311.48274)
			(xy 205.498192 -311.48274) (xy 205.498192 -311.482232) (xy 205.498192 -310.987948) (xy 205.498559 -310.982622)
			(xy 205.506076 -310.975079) (xy 205.5114 -310.97474) (xy 206.027528 -310.97474) (xy 206.03534 -310.974449)
			(xy 206.050212 -310.969648) (xy 206.056738 -310.965342) (xy 206.077827 -310.950993) (xy 206.123488 -310.928262)
			(xy 206.172094 -310.912803) (xy 206.222497 -310.90498) (xy 206.273503 -310.90498) (xy 206.323906 -310.912803)
			(xy 206.372512 -310.928262) (xy 206.418173 -310.950993) (xy 206.439262 -310.965342) (xy 206.445806 -310.969612)
			(xy 206.460666 -310.974409) (xy 206.468472 -310.97474) (xy 206.9846 -310.97474) (xy 206.989944 -310.975031)
			(xy 206.997488 -310.982603) (xy 206.997808 -310.987948) (xy 206.997808 -311.482232) (xy 268.898116 -311.482232)
			(xy 268.898116 -310.987694) (xy 268.898644 -310.982335) (xy 268.906219 -310.97475) (xy 268.911578 -310.974232)
			(xy 269.427706 -310.974232) (xy 269.435518 -310.973932) (xy 269.450389 -310.969138) (xy 269.456916 -310.964834)
			(xy 269.478005 -310.950485) (xy 269.523666 -310.927754) (xy 269.572272 -310.912295) (xy 269.622675 -310.904472)
			(xy 269.673681 -310.904472) (xy 269.724084 -310.912295) (xy 269.77269 -310.927754) (xy 269.818351 -310.950485)
			(xy 269.83944 -310.964834) (xy 269.845967 -310.969133) (xy 269.86084 -310.973912) (xy 269.86865 -310.974232)
			(xy 270.384778 -310.974232) (xy 270.390208 -310.974594) (xy 270.397895 -310.982264) (xy 270.39824 -310.987694)
			(xy 270.39824 -311.482232) (xy 276.442424 -311.482232) (xy 276.442424 -310.987694) (xy 276.442917 -310.982393)
			(xy 276.450341 -310.974823) (xy 276.455632 -310.974232) (xy 276.97176 -310.974232) (xy 276.97957 -310.973913)
			(xy 276.994442 -310.969132) (xy 277.00097 -310.964834) (xy 277.022059 -310.950485) (xy 277.06772 -310.927754)
			(xy 277.116326 -310.912295) (xy 277.166729 -310.904472) (xy 277.217735 -310.904472) (xy 277.268138 -310.912295)
			(xy 277.316744 -310.927754) (xy 277.362405 -310.950485) (xy 277.383494 -310.964834) (xy 277.390031 -310.969115)
			(xy 277.404897 -310.973906) (xy 277.412704 -310.974232) (xy 277.928832 -310.974232) (xy 277.934178 -310.974509)
			(xy 277.94172 -310.982092) (xy 277.94204 -310.98744) (xy 277.94204 -310.987948) (xy 277.94204 -311.482232)
			(xy 283.986224 -311.482232) (xy 283.986224 -310.987694) (xy 283.986717 -310.982393) (xy 283.994141 -310.974823)
			(xy 283.999432 -310.974232) (xy 284.51556 -310.974232) (xy 284.52337 -310.973913) (xy 284.538242 -310.969132)
			(xy 284.54477 -310.964834) (xy 284.565859 -310.950485) (xy 284.61152 -310.927754) (xy 284.660126 -310.912295)
			(xy 284.710529 -310.904472) (xy 284.761535 -310.904472) (xy 284.811938 -310.912295) (xy 284.860544 -310.927754)
			(xy 284.906205 -310.950485) (xy 284.927294 -310.964834) (xy 284.933831 -310.969115) (xy 284.948697 -310.973906)
			(xy 284.956504 -310.974232) (xy 285.472632 -310.974232) (xy 285.477978 -310.974509) (xy 285.48552 -310.982092)
			(xy 285.48584 -310.98744) (xy 285.48584 -310.987948) (xy 285.48584 -311.482232) (xy 291.530024 -311.482232)
			(xy 291.530024 -310.987694) (xy 291.530545 -310.982333) (xy 291.538125 -310.974748) (xy 291.543486 -310.974232)
			(xy 292.059614 -310.974232) (xy 292.067426 -310.973936) (xy 292.082298 -310.969139) (xy 292.088824 -310.964834)
			(xy 292.109913 -310.950485) (xy 292.155574 -310.927754) (xy 292.20418 -310.912295) (xy 292.254583 -310.904472)
			(xy 292.305589 -310.904472) (xy 292.355992 -310.912295) (xy 292.404598 -310.927754) (xy 292.450259 -310.950485)
			(xy 292.471348 -310.964834) (xy 292.477873 -310.969136) (xy 292.492748 -310.973914) (xy 292.500558 -310.974232)
			(xy 293.016686 -310.974232) (xy 293.022117 -310.974588) (xy 293.029804 -310.982263) (xy 293.030148 -310.987694)
			(xy 293.030148 -311.482232) (xy 299.074332 -311.482232) (xy 299.074332 -310.987694) (xy 299.074818 -310.982391)
			(xy 299.082247 -310.974821) (xy 299.08754 -310.974232) (xy 299.603668 -310.974232) (xy 299.611478 -310.973916)
			(xy 299.62635 -310.969133) (xy 299.632878 -310.964834) (xy 299.653967 -310.950485) (xy 299.699628 -310.927754)
			(xy 299.748234 -310.912295) (xy 299.798637 -310.904472) (xy 299.849643 -310.904472) (xy 299.900046 -310.912295)
			(xy 299.948652 -310.927754) (xy 299.994313 -310.950485) (xy 300.015402 -310.964834) (xy 300.021938 -310.969118)
			(xy 300.036804 -310.973907) (xy 300.044612 -310.974232) (xy 300.56074 -310.974232) (xy 300.566017 -310.974672)
			(xy 300.57346 -310.98216) (xy 300.573948 -310.98744) (xy 300.573948 -310.987948) (xy 300.573948 -311.482232)
			(xy 306.618132 -311.482232) (xy 306.618132 -310.987694) (xy 306.618646 -310.982331) (xy 306.626231 -310.974746)
			(xy 306.631594 -310.974232) (xy 308.104794 -310.974232) (xy 308.110156 -310.974754) (xy 308.117742 -310.982333)
			(xy 308.118256 -310.987694) (xy 308.118256 -311.482232) (xy 308.117731 -311.487487) (xy 308.110302 -311.494925)
			(xy 308.105048 -311.49544) (xy 308.10454 -311.49544) (xy 306.631594 -311.49544) (xy 306.626284 -311.494979)
			(xy 306.618712 -311.487533) (xy 306.618132 -311.482232) (xy 300.573948 -311.482232) (xy 300.573431 -311.487489)
			(xy 300.565997 -311.494927) (xy 300.56074 -311.49544) (xy 300.044866 -311.49544) (xy 300.036991 -311.495722)
			(xy 300.021987 -311.50051) (xy 300.015402 -311.504838) (xy 300.00236 -311.513728) (xy 347.772228 -311.513728)
			(xy 347.772228 -310.650128) (xy 347.772714 -310.622859) (xy 347.780476 -310.568875) (xy 347.795841 -310.516545)
			(xy 347.818498 -310.466935) (xy 347.847984 -310.421054) (xy 347.883699 -310.379837) (xy 347.924916 -310.344122)
			(xy 347.970797 -310.314636) (xy 348.020407 -310.291979) (xy 348.072737 -310.276614) (xy 348.126721 -310.268852)
			(xy 348.181259 -310.268852) (xy 348.235243 -310.276614) (xy 348.287573 -310.291979) (xy 348.337183 -310.314636)
			(xy 348.383064 -310.344122) (xy 348.424281 -310.379837) (xy 348.459996 -310.421054) (xy 348.489482 -310.466935)
			(xy 348.512139 -310.516545) (xy 348.527504 -310.568875) (xy 348.535266 -310.622859) (xy 348.535435 -310.632348)
			(xy 411.618176 -310.632348) (xy 411.618176 -310.63184) (xy 411.618176 -310.137556) (xy 411.618664 -310.132292)
			(xy 411.626119 -310.124853) (xy 411.631384 -310.124348) (xy 413.104584 -310.124348) (xy 413.109834 -310.124901)
			(xy 413.117275 -310.132308) (xy 413.117792 -310.137556) (xy 413.117792 -310.632094) (xy 419.161976 -310.632094)
			(xy 419.161976 -310.137556) (xy 419.162464 -310.132292) (xy 419.169919 -310.124853) (xy 419.175184 -310.124348)
			(xy 419.175692 -310.124348) (xy 419.691566 -310.124348) (xy 419.699376 -310.124028) (xy 419.714247 -310.119247)
			(xy 419.720776 -310.11495) (xy 419.741865 -310.100601) (xy 419.787526 -310.07787) (xy 419.836132 -310.062411)
			(xy 419.886535 -310.054588) (xy 419.937541 -310.054588) (xy 419.987944 -310.062411) (xy 420.03655 -310.07787)
			(xy 420.082211 -310.100601) (xy 420.1033 -310.11495) (xy 420.109835 -310.119235) (xy 420.124702 -310.124023)
			(xy 420.13251 -310.124348) (xy 420.648638 -310.124348) (xy 420.653949 -310.124799) (xy 420.661518 -310.132254)
			(xy 420.6621 -310.137556) (xy 420.6621 -310.632094) (xy 420.662074 -310.632348) (xy 426.706284 -310.632348)
			(xy 426.706284 -310.63184) (xy 426.706284 -310.137556) (xy 426.706765 -310.13229) (xy 426.714225 -310.12485)
			(xy 426.719492 -310.124348) (xy 427.23562 -310.124348) (xy 427.243432 -310.124052) (xy 427.258304 -310.119255)
			(xy 427.26483 -310.11495) (xy 427.285919 -310.100601) (xy 427.33158 -310.07787) (xy 427.380186 -310.062411)
			(xy 427.430589 -310.054588) (xy 427.481595 -310.054588) (xy 427.531998 -310.062411) (xy 427.580604 -310.07787)
			(xy 427.626265 -310.100601) (xy 427.647354 -310.11495) (xy 427.653877 -310.119256) (xy 427.668753 -310.124031)
			(xy 427.676564 -310.124348) (xy 428.192692 -310.124348) (xy 428.197943 -310.124895) (xy 428.205384 -310.132307)
			(xy 428.2059 -310.137556) (xy 428.2059 -310.632094) (xy 434.250084 -310.632094) (xy 434.250084 -310.137556)
			(xy 434.250565 -310.13229) (xy 434.258025 -310.12485) (xy 434.263292 -310.124348) (xy 434.2638 -310.124348)
			(xy 434.779674 -310.124348) (xy 434.787484 -310.124032) (xy 434.802356 -310.119248) (xy 434.808884 -310.11495)
			(xy 434.829973 -310.100601) (xy 434.875634 -310.07787) (xy 434.92424 -310.062411) (xy 434.974643 -310.054588)
			(xy 435.025649 -310.054588) (xy 435.076052 -310.062411) (xy 435.124658 -310.07787) (xy 435.170319 -310.100601)
			(xy 435.191408 -310.11495) (xy 435.197941 -310.119238) (xy 435.21281 -310.124024) (xy 435.220618 -310.124348)
			(xy 435.736746 -310.124348) (xy 435.742046 -310.12486) (xy 435.74962 -310.132268) (xy 435.750208 -310.137556)
			(xy 435.750208 -310.632094) (xy 435.750182 -310.632348) (xy 441.794392 -310.632348) (xy 441.794392 -310.63184)
			(xy 441.794392 -310.137556) (xy 441.794866 -310.132288) (xy 441.80233 -310.124848) (xy 441.8076 -310.124348)
			(xy 442.323728 -310.124348) (xy 442.33154 -310.124055) (xy 442.346412 -310.119256) (xy 442.352938 -310.11495)
			(xy 442.374027 -310.100601) (xy 442.419688 -310.07787) (xy 442.468294 -310.062411) (xy 442.518697 -310.054588)
			(xy 442.569703 -310.054588) (xy 442.620106 -310.062411) (xy 442.668712 -310.07787) (xy 442.714373 -310.100601)
			(xy 442.735462 -310.11495) (xy 442.742006 -310.119221) (xy 442.756866 -310.124017) (xy 442.764672 -310.124348)
			(xy 443.2808 -310.124348) (xy 443.286052 -310.12489) (xy 443.293492 -310.132306) (xy 443.294008 -310.137556)
			(xy 443.294008 -310.632094) (xy 443.293983 -310.632348) (xy 449.338192 -310.632348) (xy 449.338192 -310.63184)
			(xy 449.338192 -310.137556) (xy 449.338666 -310.132288) (xy 449.34613 -310.124848) (xy 449.3514 -310.124348)
			(xy 449.867528 -310.124348) (xy 449.87534 -310.124055) (xy 449.890212 -310.119256) (xy 449.896738 -310.11495)
			(xy 449.917827 -310.100601) (xy 449.963488 -310.07787) (xy 450.012094 -310.062411) (xy 450.062497 -310.054588)
			(xy 450.113503 -310.054588) (xy 450.163906 -310.062411) (xy 450.212512 -310.07787) (xy 450.258173 -310.100601)
			(xy 450.279262 -310.11495) (xy 450.285806 -310.119221) (xy 450.300666 -310.124017) (xy 450.308472 -310.124348)
			(xy 450.8246 -310.124348) (xy 450.829852 -310.12489) (xy 450.837292 -310.132306) (xy 450.837808 -310.137556)
			(xy 450.837808 -310.632094) (xy 450.837279 -310.637386) (xy 450.82988 -310.644955) (xy 450.8246 -310.645556)
			(xy 450.308726 -310.645556) (xy 450.300916 -310.645871) (xy 450.286044 -310.650655) (xy 450.279516 -310.654954)
			(xy 450.258388 -310.669293) (xy 450.212666 -310.692022) (xy 450.163995 -310.707455) (xy 450.11353 -310.715225)
			(xy 450.088 -310.71566) (xy 450.06247 -310.715224) (xy 450.012006 -310.707448) (xy 449.963333 -310.692019)
			(xy 449.917606 -310.669302) (xy 449.896484 -310.654954) (xy 449.889952 -310.650663) (xy 449.875083 -310.645879)
			(xy 449.867274 -310.645556) (xy 449.3514 -310.645556) (xy 449.346149 -310.64501) (xy 449.338709 -310.637597)
			(xy 449.338192 -310.632348) (xy 443.293983 -310.632348) (xy 443.293479 -310.637386) (xy 443.28608 -310.644955)
			(xy 443.2808 -310.645556) (xy 442.764926 -310.645556) (xy 442.757116 -310.645871) (xy 442.742244 -310.650655)
			(xy 442.735716 -310.654954) (xy 442.714588 -310.669293) (xy 442.668866 -310.692022) (xy 442.620195 -310.707455)
			(xy 442.56973 -310.715225) (xy 442.5442 -310.71566) (xy 442.51867 -310.715224) (xy 442.468206 -310.707448)
			(xy 442.419533 -310.692019) (xy 442.373806 -310.669302) (xy 442.352684 -310.654954) (xy 442.346152 -310.650663)
			(xy 442.331283 -310.645879) (xy 442.323474 -310.645556) (xy 441.8076 -310.645556) (xy 441.802349 -310.64501)
			(xy 441.794909 -310.637597) (xy 441.794392 -310.632348) (xy 435.750182 -310.632348) (xy 435.74965 -310.637446)
			(xy 435.742096 -310.64503) (xy 435.736746 -310.645556) (xy 435.220872 -310.645556) (xy 435.21306 -310.645848)
			(xy 435.198188 -310.650648) (xy 435.191662 -310.654954) (xy 435.170549 -310.669316) (xy 435.124822 -310.69204)
			(xy 435.076146 -310.707466) (xy 435.025678 -310.715229) (xy 435.000146 -310.71566) (xy 434.974617 -310.715201)
			(xy 434.924154 -310.707432) (xy 434.875481 -310.69201) (xy 434.829753 -310.669299) (xy 434.80863 -310.654954)
			(xy 434.802088 -310.650681) (xy 434.787226 -310.645886) (xy 434.77942 -310.645556) (xy 434.263546 -310.645556)
			(xy 434.258116 -310.645189) (xy 434.250427 -310.637523) (xy 434.250084 -310.632094) (xy 428.2059 -310.632094)
			(xy 428.205378 -310.637388) (xy 428.197974 -310.644957) (xy 428.192692 -310.645556) (xy 427.676818 -310.645556)
			(xy 427.669008 -310.645868) (xy 427.654136 -310.650654) (xy 427.647608 -310.654954) (xy 427.626482 -310.669296)
			(xy 427.58076 -310.692024) (xy 427.532088 -310.707456) (xy 427.481623 -310.715226) (xy 427.456092 -310.71566)
			(xy 427.430562 -310.715228) (xy 427.380097 -310.707451) (xy 427.331425 -310.692021) (xy 427.285698 -310.669302)
			(xy 427.264576 -310.654954) (xy 427.258046 -310.65066) (xy 427.243175 -310.645878) (xy 427.235366 -310.645556)
			(xy 426.719492 -310.645556) (xy 426.71424 -310.645016) (xy 426.7068 -310.637599) (xy 426.706284 -310.632348)
			(xy 420.662074 -310.632348) (xy 420.66155 -310.637448) (xy 420.65399 -310.645032) (xy 420.648638 -310.645556)
			(xy 420.132764 -310.645556) (xy 420.124955 -310.645888) (xy 420.110083 -310.65066) (xy 420.103554 -310.654954)
			(xy 420.082443 -310.66932) (xy 420.036715 -310.692043) (xy 419.988039 -310.707468) (xy 419.93757 -310.71523)
			(xy 419.912038 -310.71566) (xy 419.886508 -310.715205) (xy 419.836045 -310.707435) (xy 419.787373 -310.692011)
			(xy 419.741645 -310.669299) (xy 419.720522 -310.654954) (xy 419.713982 -310.650678) (xy 419.699119 -310.645885)
			(xy 419.691312 -310.645556) (xy 419.175438 -310.645556) (xy 419.170007 -310.645195) (xy 419.162318 -310.637524)
			(xy 419.161976 -310.632094) (xy 413.117792 -310.632094) (xy 413.117277 -310.63739) (xy 413.109868 -310.64496)
			(xy 413.104584 -310.645556) (xy 411.631384 -310.645556) (xy 411.626131 -310.645021) (xy 411.618692 -310.6376)
			(xy 411.618176 -310.632348) (xy 348.535435 -310.632348) (xy 348.535752 -310.650128) (xy 348.535752 -311.482232)
			(xy 415.718244 -311.482232) (xy 415.718244 -310.987694) (xy 415.71872 -310.982388) (xy 415.726156 -310.974817)
			(xy 415.731452 -310.974232) (xy 417.204652 -310.974232) (xy 417.209987 -310.974563) (xy 417.217534 -310.982105)
			(xy 417.21786 -310.98744) (xy 417.21786 -311.482232) (xy 423.262044 -311.482232) (xy 423.262044 -310.987694)
			(xy 423.262547 -310.982328) (xy 423.270139 -310.974742) (xy 423.275506 -310.974232) (xy 423.791634 -310.974232)
			(xy 423.799443 -310.973902) (xy 423.814315 -310.969128) (xy 423.820844 -310.964834) (xy 423.841933 -310.950485)
			(xy 423.887594 -310.927754) (xy 423.9362 -310.912295) (xy 423.986603 -310.904472) (xy 424.037609 -310.904472)
			(xy 424.088012 -310.912295) (xy 424.136618 -310.927754) (xy 424.182279 -310.950485) (xy 424.203368 -310.964834)
			(xy 424.209911 -310.969105) (xy 424.224772 -310.973902) (xy 424.232578 -310.974232) (xy 424.748706 -310.974232)
			(xy 424.754069 -310.974746) (xy 424.761654 -310.982331) (xy 424.762168 -310.987694) (xy 424.762168 -311.482232)
			(xy 430.806352 -311.482232) (xy 430.806352 -310.987694) (xy 430.80682 -310.982386) (xy 430.814262 -310.974815)
			(xy 430.81956 -310.974232) (xy 431.335688 -310.974232) (xy 431.343499 -310.973925) (xy 431.358371 -310.969135)
			(xy 431.364898 -310.964834) (xy 431.385987 -310.950485) (xy 431.431648 -310.927754) (xy 431.480254 -310.912295)
			(xy 431.530657 -310.904472) (xy 431.581663 -310.904472) (xy 431.632066 -310.912295) (xy 431.680672 -310.927754)
			(xy 431.726333 -310.950485) (xy 431.747422 -310.964834) (xy 431.753953 -310.969126) (xy 431.768823 -310.97391)
			(xy 431.776632 -310.974232) (xy 432.29276 -310.974232) (xy 432.298097 -310.974558) (xy 432.305642 -310.982103)
			(xy 432.305968 -310.98744) (xy 432.305968 -310.987948) (xy 432.305968 -311.482232) (xy 438.350152 -311.482232)
			(xy 438.350152 -310.987694) (xy 438.350477 -310.982255) (xy 438.358175 -310.974569) (xy 438.363614 -310.974232)
			(xy 438.879742 -310.974232) (xy 438.887551 -310.973905) (xy 438.902423 -310.969129) (xy 438.908952 -310.964834)
			(xy 438.930041 -310.950485) (xy 438.975702 -310.927754) (xy 439.024308 -310.912295) (xy 439.074711 -310.904472)
			(xy 439.125717 -310.904472) (xy 439.17612 -310.912295) (xy 439.224726 -310.927754) (xy 439.270387 -310.950485)
			(xy 439.291476 -310.964834) (xy 439.298017 -310.969108) (xy 439.31288 -310.973903) (xy 439.320686 -310.974232)
			(xy 439.836814 -310.974232) (xy 439.842178 -310.974741) (xy 439.849763 -310.98233) (xy 439.850276 -310.987694)
			(xy 439.850276 -311.482232) (xy 445.89446 -311.482232) (xy 445.89446 -310.987694) (xy 445.894921 -310.982384)
			(xy 445.902367 -310.974812) (xy 445.907668 -310.974232) (xy 446.423796 -310.974232) (xy 446.431607 -310.973928)
			(xy 446.446479 -310.969136) (xy 446.453006 -310.964834) (xy 446.474095 -310.950485) (xy 446.519756 -310.927754)
			(xy 446.568362 -310.912295) (xy 446.618765 -310.904472) (xy 446.669771 -310.904472) (xy 446.720174 -310.912295)
			(xy 446.76878 -310.927754) (xy 446.814441 -310.950485) (xy 446.83553 -310.964834) (xy 446.842059 -310.969129)
			(xy 446.856931 -310.973911) (xy 446.86474 -310.974232) (xy 447.380868 -310.974232) (xy 447.386206 -310.974552)
			(xy 447.393751 -310.982102) (xy 447.394076 -310.98744) (xy 447.394076 -310.987948) (xy 447.394076 -311.482232)
			(xy 453.43826 -311.482232) (xy 453.43826 -310.987694) (xy 453.438721 -310.982384) (xy 453.446167 -310.974812)
			(xy 453.451468 -310.974232) (xy 453.967596 -310.974232) (xy 453.975407 -310.973928) (xy 453.990279 -310.969136)
			(xy 453.996806 -310.964834) (xy 454.017895 -310.950485) (xy 454.063556 -310.927754) (xy 454.112162 -310.912295)
			(xy 454.162565 -310.904472) (xy 454.213571 -310.904472) (xy 454.263974 -310.912295) (xy 454.31258 -310.927754)
			(xy 454.358241 -310.950485) (xy 454.37933 -310.964834) (xy 454.385859 -310.969129) (xy 454.400731 -310.973911)
			(xy 454.40854 -310.974232) (xy 454.924668 -310.974232) (xy 454.930006 -310.974552) (xy 454.937551 -310.982102)
			(xy 454.937876 -310.98744) (xy 454.937876 -310.987948) (xy 454.937876 -311.482232) (xy 454.937423 -311.487506)
			(xy 454.929945 -311.494949) (xy 454.924668 -311.49544) (xy 454.408794 -311.49544) (xy 454.40092 -311.495735)
			(xy 454.385916 -311.500514) (xy 454.37933 -311.504838) (xy 454.358262 -311.519244) (xy 454.312614 -311.542069)
			(xy 454.264005 -311.557623) (xy 454.213586 -311.565537) (xy 454.188068 -311.566052) (xy 454.162549 -311.565536)
			(xy 454.112124 -311.557648) (xy 454.063512 -311.542095) (xy 454.017872 -311.519249) (xy 453.996806 -311.504838)
			(xy 453.990213 -311.500526) (xy 453.975214 -311.495737) (xy 453.967342 -311.49544) (xy 453.451468 -311.49544)
			(xy 453.446209 -311.49493) (xy 453.43877 -311.487491) (xy 453.43826 -311.482232) (xy 447.394076 -311.482232)
			(xy 447.393623 -311.487506) (xy 447.386145 -311.494949) (xy 447.380868 -311.49544) (xy 446.864994 -311.49544)
			(xy 446.85712 -311.495735) (xy 446.842116 -311.500514) (xy 446.83553 -311.504838) (xy 446.814462 -311.519244)
			(xy 446.768814 -311.542069) (xy 446.720205 -311.557623) (xy 446.669786 -311.565537) (xy 446.644268 -311.566052)
			(xy 446.618749 -311.565536) (xy 446.568324 -311.557648) (xy 446.519712 -311.542095) (xy 446.474072 -311.519249)
			(xy 446.453006 -311.504838) (xy 446.446413 -311.500526) (xy 446.431414 -311.495737) (xy 446.423542 -311.49544)
			(xy 445.907668 -311.49544) (xy 445.902409 -311.49493) (xy 445.89497 -311.487491) (xy 445.89446 -311.482232)
			(xy 439.850276 -311.482232) (xy 439.849823 -311.487506) (xy 439.842345 -311.494949) (xy 439.837068 -311.49544)
			(xy 439.83656 -311.49544) (xy 439.32094 -311.49544) (xy 439.313064 -311.495711) (xy 439.29806 -311.500506)
			(xy 439.291476 -311.504838) (xy 439.270395 -311.519224) (xy 439.224751 -311.542054) (xy 439.176147 -311.557613)
			(xy 439.12573 -311.565534) (xy 439.100214 -311.566052) (xy 439.074694 -311.565563) (xy 439.024267 -311.557667)
			(xy 438.975656 -311.542106) (xy 438.930017 -311.519252) (xy 438.908952 -311.504838) (xy 438.902371 -311.500505)
			(xy 438.887363 -311.495729) (xy 438.879488 -311.49544) (xy 438.363614 -311.49544) (xy 438.358307 -311.494965)
			(xy 438.350734 -311.487529) (xy 438.350152 -311.482232) (xy 432.305968 -311.482232) (xy 432.305691 -311.487578)
			(xy 432.298108 -311.49512) (xy 432.29276 -311.49544) (xy 431.776886 -311.49544) (xy 431.769012 -311.495731)
			(xy 431.754008 -311.500513) (xy 431.747422 -311.504838) (xy 431.726356 -311.519247) (xy 431.680707 -311.542072)
			(xy 431.632098 -311.557625) (xy 431.581678 -311.565538) (xy 431.55616 -311.566052) (xy 431.530641 -311.56554)
			(xy 431.480215 -311.557651) (xy 431.431604 -311.542097) (xy 431.385964 -311.519249) (xy 431.364898 -311.504838)
			(xy 431.358306 -311.500523) (xy 431.343306 -311.495736) (xy 431.335434 -311.49544) (xy 430.81956 -311.49544)
			(xy 430.8143 -311.494935) (xy 430.806862 -311.487492) (xy 430.806352 -311.482232) (xy 424.762168 -311.482232)
			(xy 424.761891 -311.487578) (xy 424.754308 -311.49512) (xy 424.74896 -311.49544) (xy 424.748452 -311.49544)
			(xy 424.232832 -311.49544) (xy 424.224956 -311.495708) (xy 424.209952 -311.500505) (xy 424.203368 -311.504838)
			(xy 424.182289 -311.519227) (xy 424.136645 -311.542056) (xy 424.088039 -311.557615) (xy 424.037623 -311.565535)
			(xy 424.012106 -311.566052) (xy 423.986586 -311.565567) (xy 423.936159 -311.557669) (xy 423.887548 -311.542108)
			(xy 423.841909 -311.519253) (xy 423.820844 -311.504838) (xy 423.814264 -311.500502) (xy 423.799255 -311.495728)
			(xy 423.79138 -311.49544) (xy 423.275506 -311.49544) (xy 423.270198 -311.494971) (xy 423.262625 -311.487531)
			(xy 423.262044 -311.482232) (xy 417.21786 -311.482232) (xy 417.21759 -311.48758) (xy 417.210002 -311.495122)
			(xy 417.204652 -311.49544) (xy 415.731452 -311.49544) (xy 415.726191 -311.49494) (xy 415.718753 -311.487493)
			(xy 415.718244 -311.482232) (xy 348.535752 -311.482232) (xy 348.535752 -311.513728) (xy 348.535266 -311.540997)
			(xy 348.527504 -311.594981) (xy 348.512139 -311.647311) (xy 348.489482 -311.696921) (xy 348.459996 -311.742802)
			(xy 348.424281 -311.784019) (xy 348.383064 -311.819734) (xy 348.337183 -311.84922) (xy 348.287573 -311.871877)
			(xy 348.235243 -311.887242) (xy 348.181259 -311.895004) (xy 348.126721 -311.895004) (xy 348.072737 -311.887242)
			(xy 348.020407 -311.871877) (xy 347.970797 -311.84922) (xy 347.924916 -311.819734) (xy 347.883699 -311.784019)
			(xy 347.847984 -311.742802) (xy 347.818498 -311.696921) (xy 347.795841 -311.647311) (xy 347.780476 -311.594981)
			(xy 347.772714 -311.540997) (xy 347.772228 -311.513728) (xy 300.00236 -311.513728) (xy 299.994314 -311.519213)
			(xy 299.948673 -311.542045) (xy 299.90007 -311.557608) (xy 299.849656 -311.565532) (xy 299.82414 -311.566052)
			(xy 299.79862 -311.56555) (xy 299.748194 -311.557658) (xy 299.699583 -311.542101) (xy 299.653944 -311.519251)
			(xy 299.632878 -311.504838) (xy 299.626291 -311.500515) (xy 299.611288 -311.495733) (xy 299.603414 -311.49544)
			(xy 299.08754 -311.49544) (xy 299.082221 -311.495049) (xy 299.07468 -311.487549) (xy 299.074332 -311.482232)
			(xy 293.030148 -311.482232) (xy 293.029631 -311.487489) (xy 293.022197 -311.494927) (xy 293.01694 -311.49544)
			(xy 293.016432 -311.49544) (xy 292.500812 -311.49544) (xy 292.492939 -311.495742) (xy 292.477935 -311.500516)
			(xy 292.471348 -311.504838) (xy 292.450275 -311.519236) (xy 292.404628 -311.542063) (xy 292.356021 -311.557619)
			(xy 292.305603 -311.565536) (xy 292.280086 -311.566052) (xy 292.254567 -311.565527) (xy 292.204142 -311.557641)
			(xy 292.155531 -311.542092) (xy 292.109891 -311.519248) (xy 292.088824 -311.504838) (xy 292.082227 -311.500533)
			(xy 292.067231 -311.49574) (xy 292.05936 -311.49544) (xy 291.543486 -311.49544) (xy 291.538176 -311.494984)
			(xy 291.530604 -311.487534) (xy 291.530024 -311.482232) (xy 285.48584 -311.482232) (xy 285.48533 -311.487491)
			(xy 285.477891 -311.49493) (xy 285.472632 -311.49544) (xy 284.956758 -311.49544) (xy 284.948883 -311.495719)
			(xy 284.933879 -311.500509) (xy 284.927294 -311.504838) (xy 284.906208 -311.519216) (xy 284.860566 -311.542048)
			(xy 284.811963 -311.557609) (xy 284.761548 -311.565533) (xy 284.736032 -311.566052) (xy 284.710512 -311.565554)
			(xy 284.660086 -311.55766) (xy 284.611475 -311.542103) (xy 284.565836 -311.519251) (xy 284.54477 -311.504838)
			(xy 284.538185 -311.500512) (xy 284.52318 -311.495732) (xy 284.515306 -311.49544) (xy 283.999432 -311.49544)
			(xy 283.994181 -311.494887) (xy 283.986738 -311.487481) (xy 283.986224 -311.482232) (xy 277.94204 -311.482232)
			(xy 277.94153 -311.487491) (xy 277.934091 -311.49493) (xy 277.928832 -311.49544) (xy 277.412958 -311.49544)
			(xy 277.405083 -311.495719) (xy 277.390079 -311.500509) (xy 277.383494 -311.504838) (xy 277.362408 -311.519216)
			(xy 277.316766 -311.542048) (xy 277.268163 -311.557609) (xy 277.217748 -311.565533) (xy 277.192232 -311.566052)
			(xy 277.166712 -311.565554) (xy 277.116286 -311.55766) (xy 277.067675 -311.542103) (xy 277.022036 -311.519251)
			(xy 277.00097 -311.504838) (xy 276.994385 -311.500512) (xy 276.97938 -311.495732) (xy 276.971506 -311.49544)
			(xy 276.455632 -311.49544) (xy 276.450381 -311.494887) (xy 276.442938 -311.487481) (xy 276.442424 -311.482232)
			(xy 270.39824 -311.482232) (xy 270.39773 -311.487491) (xy 270.390291 -311.49493) (xy 270.385032 -311.49544)
			(xy 270.384524 -311.49544) (xy 269.868904 -311.49544) (xy 269.86103 -311.495739) (xy 269.846027 -311.500515)
			(xy 269.83944 -311.504838) (xy 269.818369 -311.519239) (xy 269.772722 -311.542066) (xy 269.724114 -311.557621)
			(xy 269.673695 -311.565537) (xy 269.648178 -311.566052) (xy 269.622659 -311.565531) (xy 269.572234 -311.557644)
			(xy 269.523623 -311.542093) (xy 269.477983 -311.519248) (xy 269.456916 -311.504838) (xy 269.45032 -311.50053)
			(xy 269.435324 -311.495738) (xy 269.427452 -311.49544) (xy 268.911578 -311.49544) (xy 268.906266 -311.494989)
			(xy 268.898695 -311.487535) (xy 268.898116 -311.482232) (xy 206.997808 -311.482232) (xy 206.997808 -311.482486)
			(xy 206.997273 -311.487777) (xy 206.989879 -311.495346) (xy 206.9846 -311.495948) (xy 206.468726 -311.495948)
			(xy 206.460916 -311.496265) (xy 206.446044 -311.501048) (xy 206.439516 -311.505346) (xy 206.418387 -311.519684)
			(xy 206.372666 -311.542413) (xy 206.323995 -311.557847) (xy 206.27353 -311.565617) (xy 206.248 -311.566052)
			(xy 206.22247 -311.565618) (xy 206.172006 -311.557842) (xy 206.123333 -311.542412) (xy 206.077606 -311.519694)
			(xy 206.056484 -311.505346) (xy 206.049953 -311.501054) (xy 206.035083 -311.496271) (xy 206.027274 -311.495948)
			(xy 205.5114 -311.495948) (xy 205.506147 -311.495409) (xy 205.498707 -311.487992) (xy 205.498192 -311.48274)
			(xy 199.453982 -311.48274) (xy 199.453473 -311.487777) (xy 199.446079 -311.495346) (xy 199.4408 -311.495948)
			(xy 198.924926 -311.495948) (xy 198.917116 -311.496265) (xy 198.902244 -311.501048) (xy 198.895716 -311.505346)
			(xy 198.874587 -311.519684) (xy 198.828866 -311.542413) (xy 198.780195 -311.557847) (xy 198.72973 -311.565617)
			(xy 198.7042 -311.566052) (xy 198.67867 -311.565618) (xy 198.628206 -311.557842) (xy 198.579533 -311.542412)
			(xy 198.533806 -311.519694) (xy 198.512684 -311.505346) (xy 198.506153 -311.501054) (xy 198.491283 -311.496271)
			(xy 198.483474 -311.495948) (xy 197.9676 -311.495948) (xy 197.962347 -311.495409) (xy 197.954907 -311.487992)
			(xy 197.954392 -311.48274) (xy 191.910181 -311.48274) (xy 191.909645 -311.487837) (xy 191.902095 -311.495421)
			(xy 191.896746 -311.495948) (xy 191.380872 -311.495948) (xy 191.37306 -311.496242) (xy 191.358188 -311.50104)
			(xy 191.351662 -311.505346) (xy 191.330548 -311.519707) (xy 191.284822 -311.542431) (xy 191.236146 -311.557858)
			(xy 191.185678 -311.565621) (xy 191.160146 -311.566052) (xy 191.134617 -311.565595) (xy 191.084153 -311.557825)
			(xy 191.035481 -311.542402) (xy 190.989753 -311.519691) (xy 190.96863 -311.505346) (xy 190.962088 -311.501072)
			(xy 190.947226 -311.496278) (xy 190.93942 -311.495948) (xy 190.423546 -311.495948) (xy 190.418114 -311.495589)
			(xy 190.410424 -311.487917) (xy 190.410084 -311.482486) (xy 184.3659 -311.482486) (xy 184.365372 -311.487779)
			(xy 184.357973 -311.495349) (xy 184.352692 -311.495948) (xy 183.836818 -311.495948) (xy 183.829008 -311.496261)
			(xy 183.814136 -311.501047) (xy 183.807608 -311.505346) (xy 183.786481 -311.519687) (xy 183.740759 -311.542416)
			(xy 183.692088 -311.557848) (xy 183.641623 -311.565617) (xy 183.616092 -311.566052) (xy 183.590561 -311.565622)
			(xy 183.540097 -311.557844) (xy 183.491425 -311.542413) (xy 183.445698 -311.519695) (xy 183.424576 -311.505346)
			(xy 183.418046 -311.501051) (xy 183.403175 -311.49627) (xy 183.395366 -311.495948) (xy 182.879492 -311.495948)
			(xy 182.874238 -311.495415) (xy 182.866798 -311.487993) (xy 182.866284 -311.48274) (xy 176.822074 -311.48274)
			(xy 176.821544 -311.487839) (xy 176.813989 -311.495423) (xy 176.808638 -311.495948) (xy 176.292764 -311.495948)
			(xy 176.284956 -311.496281) (xy 176.270084 -311.501053) (xy 176.263554 -311.505346) (xy 176.242442 -311.519711)
			(xy 176.196715 -311.542434) (xy 176.148039 -311.55786) (xy 176.09757 -311.565622) (xy 176.072038 -311.566052)
			(xy 176.046508 -311.565599) (xy 175.996045 -311.557828) (xy 175.947373 -311.542404) (xy 175.901644 -311.519692)
			(xy 175.880522 -311.505346) (xy 175.873982 -311.501069) (xy 175.859119 -311.496276) (xy 175.851312 -311.495948)
			(xy 175.335438 -311.495948) (xy 175.330005 -311.495594) (xy 175.322316 -311.487919) (xy 175.321976 -311.482486)
			(xy 169.277792 -311.482486) (xy 169.277271 -311.487781) (xy 169.269867 -311.495351) (xy 169.264584 -311.495948)
			(xy 167.791384 -311.495948) (xy 167.786129 -311.49542) (xy 167.778689 -311.487994) (xy 167.778176 -311.48274)
			(xy 60.178162 -311.48274) (xy 60.177643 -311.487842) (xy 60.17008 -311.495427) (xy 60.164726 -311.495948)
			(xy 58.691526 -311.495948) (xy 58.686091 -311.495602) (xy 58.678403 -311.48792) (xy 58.678064 -311.482486)
			(xy 52.63388 -311.482486) (xy 52.63337 -311.487784) (xy 52.625958 -311.495354) (xy 52.620672 -311.495948)
			(xy 52.104798 -311.495948) (xy 52.096987 -311.496253) (xy 52.082115 -311.501044) (xy 52.075588 -311.505346)
			(xy 52.054467 -311.519696) (xy 52.008743 -311.542423) (xy 51.960069 -311.557853) (xy 51.909603 -311.565619)
			(xy 51.884072 -311.566052) (xy 51.858541 -311.565632) (xy 51.808076 -311.557851) (xy 51.759404 -311.542417)
			(xy 51.713677 -311.519696) (xy 51.692556 -311.505346) (xy 51.686031 -311.501044) (xy 51.671156 -311.496267)
			(xy 51.663346 -311.495948) (xy 51.147472 -311.495948) (xy 51.142215 -311.495428) (xy 51.134777 -311.487996)
			(xy 51.134264 -311.48274) (xy 45.090054 -311.48274) (xy 45.089542 -311.487844) (xy 45.081975 -311.495429)
			(xy 45.076618 -311.495948) (xy 44.560744 -311.495948) (xy 44.552935 -311.496272) (xy 44.538063 -311.50105)
			(xy 44.531534 -311.505346) (xy 44.510428 -311.519719) (xy 44.464699 -311.542441) (xy 44.41602 -311.557864)
			(xy 44.36555 -311.565623) (xy 44.340018 -311.566052) (xy 44.314488 -311.565609) (xy 44.264024 -311.557835)
			(xy 44.215352 -311.542408) (xy 44.169624 -311.519693) (xy 44.148502 -311.505346) (xy 44.141967 -311.501061)
			(xy 44.1271 -311.496273) (xy 44.119292 -311.495948) (xy 43.603418 -311.495948) (xy 43.597982 -311.495607)
			(xy 43.590294 -311.487922) (xy 43.589956 -311.482486) (xy 37.545772 -311.482486) (xy 37.545269 -311.487786)
			(xy 37.537853 -311.495357) (xy 37.532564 -311.495948) (xy 37.01669 -311.495948) (xy 37.008879 -311.496249)
			(xy 36.994007 -311.501043) (xy 36.98748 -311.505346) (xy 36.966361 -311.519699) (xy 36.920636 -311.542425)
			(xy 36.871962 -311.557854) (xy 36.821495 -311.56562) (xy 36.795964 -311.566052) (xy 36.770433 -311.565636)
			(xy 36.719968 -311.557854) (xy 36.671296 -311.542419) (xy 36.625569 -311.519696) (xy 36.604448 -311.505346)
			(xy 36.597925 -311.501041) (xy 36.583048 -311.496266) (xy 36.575238 -311.495948) (xy 36.059364 -311.495948)
			(xy 36.054107 -311.495433) (xy 36.046668 -311.487997) (xy 36.046156 -311.48274) (xy 30.001948 -311.48274)
			(xy 30.001469 -311.487786) (xy 29.994053 -311.495357) (xy 29.988764 -311.495948) (xy 29.47289 -311.495948)
			(xy 29.465079 -311.496249) (xy 29.450207 -311.501043) (xy 29.44368 -311.505346) (xy 29.422561 -311.519699)
			(xy 29.376836 -311.542425) (xy 29.328162 -311.557854) (xy 29.277695 -311.56562) (xy 29.252164 -311.566052)
			(xy 29.226633 -311.565636) (xy 29.176168 -311.557854) (xy 29.127496 -311.542419) (xy 29.081769 -311.519696)
			(xy 29.060648 -311.505346) (xy 29.054125 -311.501041) (xy 29.039248 -311.496266) (xy 29.031438 -311.495948)
			(xy 28.515564 -311.495948) (xy 28.510307 -311.495433) (xy 28.502868 -311.487997) (xy 28.502356 -311.48274)
			(xy 22.458155 -311.48274) (xy 22.457812 -311.487916) (xy 22.45014 -311.495603) (xy 22.44471 -311.495948)
			(xy 21.928836 -311.495948) (xy 21.921026 -311.496269) (xy 21.906155 -311.501049) (xy 21.899626 -311.505346)
			(xy 21.878494 -311.51968) (xy 21.832774 -311.54241) (xy 21.784104 -311.557844) (xy 21.73364 -311.565616)
			(xy 21.70811 -311.566052) (xy 21.68258 -311.565613) (xy 21.632116 -311.557838) (xy 21.583444 -311.54241)
			(xy 21.537716 -311.519693) (xy 21.516594 -311.505346) (xy 21.51006 -311.501058) (xy 21.495192 -311.496272)
			(xy 21.487384 -311.495948) (xy 20.97151 -311.495948) (xy 20.966073 -311.495613) (xy 20.958386 -311.487923)
			(xy 20.958048 -311.482486) (xy 2.509012 -311.482486) (xy 2.509012 -312.33237) (xy 16.85798 -312.33237)
			(xy 16.85798 -311.837832) (xy 16.858347 -311.832507) (xy 16.865864 -311.824965) (xy 16.871188 -311.824624)
			(xy 16.871696 -311.824624) (xy 17.38757 -311.824624) (xy 17.39538 -311.82431) (xy 17.410252 -311.819526)
			(xy 17.41678 -311.815226) (xy 17.437869 -311.800877) (xy 17.48353 -311.778146) (xy 17.532136 -311.762687)
			(xy 17.582539 -311.754864) (xy 17.633545 -311.754864) (xy 17.683948 -311.762687) (xy 17.732554 -311.778146)
			(xy 17.778215 -311.800877) (xy 17.799304 -311.815226) (xy 17.80584 -311.81951) (xy 17.820706 -311.824299)
			(xy 17.828514 -311.824624) (xy 18.344642 -311.824624) (xy 18.349948 -311.825093) (xy 18.357515 -311.832536)
			(xy 18.358104 -311.837832) (xy 18.358104 -312.33237) (xy 18.358077 -312.332624) (xy 24.402288 -312.332624)
			(xy 24.402288 -312.332116) (xy 24.402288 -311.837832) (xy 24.402648 -311.832505) (xy 24.41017 -311.824963)
			(xy 24.415496 -311.824624) (xy 24.931624 -311.824624) (xy 24.939436 -311.824333) (xy 24.954308 -311.819533)
			(xy 24.960834 -311.815226) (xy 24.981923 -311.800877) (xy 25.027584 -311.778146) (xy 25.07619 -311.762687)
			(xy 25.126593 -311.754864) (xy 25.177599 -311.754864) (xy 25.228002 -311.762687) (xy 25.276608 -311.778146)
			(xy 25.322269 -311.800877) (xy 25.343358 -311.815226) (xy 25.349882 -311.819531) (xy 25.364758 -311.824307)
			(xy 25.372568 -311.824624) (xy 25.888696 -311.824624) (xy 25.894035 -311.824933) (xy 25.901578 -311.832492)
			(xy 25.901904 -311.837832) (xy 25.901904 -312.33237) (xy 25.901878 -312.332624) (xy 31.946088 -312.332624)
			(xy 31.946088 -312.332116) (xy 31.946088 -311.837832) (xy 31.946448 -311.832505) (xy 31.95397 -311.824963)
			(xy 31.959296 -311.824624) (xy 32.475424 -311.824624) (xy 32.483236 -311.824333) (xy 32.498108 -311.819533)
			(xy 32.504634 -311.815226) (xy 32.525723 -311.800877) (xy 32.571384 -311.778146) (xy 32.61999 -311.762687)
			(xy 32.670393 -311.754864) (xy 32.721399 -311.754864) (xy 32.771802 -311.762687) (xy 32.820408 -311.778146)
			(xy 32.866069 -311.800877) (xy 32.887158 -311.815226) (xy 32.893682 -311.819531) (xy 32.908558 -311.824307)
			(xy 32.916368 -311.824624) (xy 33.432496 -311.824624) (xy 33.437835 -311.824933) (xy 33.445378 -311.832492)
			(xy 33.445704 -311.837832) (xy 33.445704 -312.33237) (xy 39.489888 -312.33237) (xy 39.489888 -311.837832)
			(xy 39.490248 -311.832505) (xy 39.49777 -311.824963) (xy 39.503096 -311.824624) (xy 39.503604 -311.824624)
			(xy 40.019478 -311.824624) (xy 40.027289 -311.824314) (xy 40.042161 -311.819527) (xy 40.048688 -311.815226)
			(xy 40.069777 -311.800877) (xy 40.115438 -311.778146) (xy 40.164044 -311.762687) (xy 40.214447 -311.754864)
			(xy 40.265453 -311.754864) (xy 40.315856 -311.762687) (xy 40.364462 -311.778146) (xy 40.410123 -311.800877)
			(xy 40.431212 -311.815226) (xy 40.437746 -311.819514) (xy 40.452614 -311.8243) (xy 40.460422 -311.824624)
			(xy 40.97655 -311.824624) (xy 40.981844 -311.825155) (xy 40.989417 -311.83255) (xy 40.990012 -311.837832)
			(xy 40.990012 -312.33237) (xy 40.989985 -312.332624) (xy 47.034196 -312.332624) (xy 47.034196 -312.332116)
			(xy 47.034196 -311.837832) (xy 47.034549 -311.832503) (xy 47.042076 -311.82496) (xy 47.047404 -311.824624)
			(xy 47.563532 -311.824624) (xy 47.571341 -311.824294) (xy 47.586213 -311.819521) (xy 47.592742 -311.815226)
			(xy 47.613831 -311.800877) (xy 47.659492 -311.778146) (xy 47.708098 -311.762687) (xy 47.758501 -311.754864)
			(xy 47.809507 -311.754864) (xy 47.85991 -311.762687) (xy 47.908516 -311.778146) (xy 47.954177 -311.800877)
			(xy 47.975266 -311.815226) (xy 47.98181 -311.819496) (xy 47.99667 -311.824294) (xy 48.004476 -311.824624)
			(xy 48.520604 -311.824624) (xy 48.525945 -311.824927) (xy 48.533487 -311.832491) (xy 48.533812 -311.837832)
			(xy 48.533812 -312.33237) (xy 54.577996 -312.33237) (xy 54.577996 -311.837832) (xy 54.578349 -311.832503)
			(xy 54.585876 -311.82496) (xy 54.591204 -311.824624) (xy 56.064658 -311.824624) (xy 56.069953 -311.825149)
			(xy 56.077526 -311.832549) (xy 56.07812 -311.837832) (xy 56.07812 -312.33237) (xy 56.078105 -312.332624)
			(xy 163.678108 -312.332624) (xy 163.678108 -312.332116) (xy 163.678108 -311.837832) (xy 163.67845 -311.8325)
			(xy 163.685985 -311.824956) (xy 163.691316 -311.824624) (xy 165.164516 -311.824624) (xy 165.169858 -311.824919)
			(xy 165.1774 -311.832488) (xy 165.177724 -311.837832) (xy 165.177724 -312.33237) (xy 171.221908 -312.33237)
			(xy 171.221908 -311.837832) (xy 171.22225 -311.8325) (xy 171.229785 -311.824956) (xy 171.235116 -311.824624)
			(xy 171.235624 -311.824624) (xy 171.751498 -311.824624) (xy 171.759309 -311.824322) (xy 171.774181 -311.819529)
			(xy 171.780708 -311.815226) (xy 171.801797 -311.800877) (xy 171.847458 -311.778146) (xy 171.896064 -311.762687)
			(xy 171.946467 -311.754864) (xy 171.997473 -311.754864) (xy 172.047876 -311.762687) (xy 172.096482 -311.778146)
			(xy 172.142143 -311.800877) (xy 172.163232 -311.815226) (xy 172.169761 -311.819521) (xy 172.184633 -311.824303)
			(xy 172.192442 -311.824624) (xy 172.70857 -311.824624) (xy 172.713867 -311.825141) (xy 172.721439 -311.832547)
			(xy 172.722032 -311.837832) (xy 172.722032 -312.33237) (xy 172.722016 -312.332624) (xy 178.766216 -312.332624)
			(xy 178.766216 -312.332116) (xy 178.766216 -311.837832) (xy 178.766551 -311.832498) (xy 178.77409 -311.824954)
			(xy 178.779424 -311.824624) (xy 179.295552 -311.824624) (xy 179.303362 -311.824303) (xy 179.318234 -311.819523)
			(xy 179.324762 -311.815226) (xy 179.345851 -311.800877) (xy 179.391512 -311.778146) (xy 179.440118 -311.762687)
			(xy 179.490521 -311.754864) (xy 179.541527 -311.754864) (xy 179.59193 -311.762687) (xy 179.640536 -311.778146)
			(xy 179.686197 -311.800877) (xy 179.707286 -311.815226) (xy 179.713826 -311.819504) (xy 179.728689 -311.824296)
			(xy 179.736496 -311.824624) (xy 180.252624 -311.824624) (xy 180.257967 -311.824914) (xy 180.265509 -311.832487)
			(xy 180.265832 -311.837832) (xy 180.265832 -312.33237) (xy 186.310016 -312.33237) (xy 186.310016 -311.837832)
			(xy 186.310351 -311.832498) (xy 186.31789 -311.824954) (xy 186.323224 -311.824624) (xy 186.323732 -311.824624)
			(xy 186.839606 -311.824624) (xy 186.847418 -311.824326) (xy 186.862289 -311.81953) (xy 186.868816 -311.815226)
			(xy 186.889905 -311.800877) (xy 186.935566 -311.778146) (xy 186.984172 -311.762687) (xy 187.034575 -311.754864)
			(xy 187.085581 -311.754864) (xy 187.135984 -311.762687) (xy 187.18459 -311.778146) (xy 187.230251 -311.800877)
			(xy 187.25134 -311.815226) (xy 187.257868 -311.819524) (xy 187.27274 -311.824304) (xy 187.28055 -311.824624)
			(xy 187.796678 -311.824624) (xy 187.801976 -311.825136) (xy 187.809547 -311.832546) (xy 187.81014 -311.837832)
			(xy 187.81014 -312.33237) (xy 187.810124 -312.332624) (xy 193.854324 -312.332624) (xy 193.854324 -312.332116)
			(xy 193.854324 -311.837832) (xy 193.854652 -311.832496) (xy 193.862196 -311.824952) (xy 193.867532 -311.824624)
			(xy 194.38366 -311.824624) (xy 194.39147 -311.824306) (xy 194.406342 -311.819524) (xy 194.41287 -311.815226)
			(xy 194.433959 -311.800877) (xy 194.47962 -311.778146) (xy 194.528226 -311.762687) (xy 194.578629 -311.754864)
			(xy 194.629635 -311.754864) (xy 194.680038 -311.762687) (xy 194.728644 -311.778146) (xy 194.774305 -311.800877)
			(xy 194.795394 -311.815226) (xy 194.801932 -311.819507) (xy 194.816797 -311.824298) (xy 194.824604 -311.824624)
			(xy 195.340732 -311.824624) (xy 195.346006 -311.825077) (xy 195.353449 -311.832555) (xy 195.35394 -311.837832)
			(xy 195.35394 -312.33237) (xy 195.353917 -312.332624) (xy 201.398124 -312.332624) (xy 201.398124 -312.332116)
			(xy 201.398124 -311.837832) (xy 201.398452 -311.832496) (xy 201.405996 -311.824952) (xy 201.411332 -311.824624)
			(xy 201.92746 -311.824624) (xy 201.93527 -311.824306) (xy 201.950142 -311.819524) (xy 201.95667 -311.815226)
			(xy 201.977759 -311.800877) (xy 202.02342 -311.778146) (xy 202.072026 -311.762687) (xy 202.122429 -311.754864)
			(xy 202.173435 -311.754864) (xy 202.223838 -311.762687) (xy 202.272444 -311.778146) (xy 202.318105 -311.800877)
			(xy 202.339194 -311.815226) (xy 202.345732 -311.819507) (xy 202.360597 -311.824298) (xy 202.368404 -311.824624)
			(xy 202.884532 -311.824624) (xy 202.889806 -311.825077) (xy 202.897249 -311.832555) (xy 202.89774 -311.837832)
			(xy 202.89774 -312.332116) (xy 264.798048 -312.332116) (xy 264.798048 -311.837578) (xy 264.798537 -311.832209)
			(xy 264.80614 -311.824624) (xy 264.81151 -311.824116) (xy 265.327638 -311.824116) (xy 265.335447 -311.82379)
			(xy 265.350319 -311.819014) (xy 265.356848 -311.814718) (xy 265.377937 -311.800369) (xy 265.423598 -311.777638)
			(xy 265.472204 -311.762179) (xy 265.522607 -311.754356) (xy 265.573613 -311.754356) (xy 265.624016 -311.762179)
			(xy 265.672622 -311.777638) (xy 265.718283 -311.800369) (xy 265.739372 -311.814718) (xy 265.745915 -311.818989)
			(xy 265.760776 -311.823786) (xy 265.768582 -311.824116) (xy 266.28471 -311.824116) (xy 266.29007 -311.824642)
			(xy 266.297654 -311.832219) (xy 266.298172 -311.837578) (xy 266.298172 -312.332116) (xy 272.342356 -312.332116)
			(xy 272.342356 -311.837578) (xy 272.34281 -311.832267) (xy 272.350262 -311.824697) (xy 272.355564 -311.824116)
			(xy 272.871692 -311.824116) (xy 272.879503 -311.823813) (xy 272.894375 -311.819021) (xy 272.900902 -311.814718)
			(xy 272.921991 -311.800369) (xy 272.967652 -311.777638) (xy 273.016258 -311.762179) (xy 273.066661 -311.754356)
			(xy 273.117667 -311.754356) (xy 273.16807 -311.762179) (xy 273.216676 -311.777638) (xy 273.262337 -311.800369)
			(xy 273.283426 -311.814718) (xy 273.289957 -311.81901) (xy 273.304827 -311.823794) (xy 273.312636 -311.824116)
			(xy 273.828764 -311.824116) (xy 273.834097 -311.824453) (xy 273.841642 -311.831991) (xy 273.841972 -311.837324)
			(xy 273.841972 -311.837832) (xy 273.841972 -312.332116) (xy 279.886156 -312.332116) (xy 279.886156 -311.837578)
			(xy 279.88661 -311.832267) (xy 279.894062 -311.824697) (xy 279.899364 -311.824116) (xy 280.415492 -311.824116)
			(xy 280.423303 -311.823813) (xy 280.438175 -311.819021) (xy 280.444702 -311.814718) (xy 280.465791 -311.800369)
			(xy 280.511452 -311.777638) (xy 280.560058 -311.762179) (xy 280.610461 -311.754356) (xy 280.661467 -311.754356)
			(xy 280.71187 -311.762179) (xy 280.760476 -311.777638) (xy 280.806137 -311.800369) (xy 280.827226 -311.814718)
			(xy 280.833757 -311.81901) (xy 280.848627 -311.823794) (xy 280.856436 -311.824116) (xy 281.372564 -311.824116)
			(xy 281.377897 -311.824453) (xy 281.385442 -311.831991) (xy 281.385772 -311.837324) (xy 281.385772 -311.837832)
			(xy 281.385772 -312.332116) (xy 287.429956 -312.332116) (xy 287.429956 -311.837578) (xy 287.430438 -311.832207)
			(xy 287.438046 -311.824622) (xy 287.443418 -311.824116) (xy 287.959546 -311.824116) (xy 287.967356 -311.823794)
			(xy 287.982228 -311.819015) (xy 287.988756 -311.814718) (xy 288.009845 -311.800369) (xy 288.055506 -311.777638)
			(xy 288.104112 -311.762179) (xy 288.154515 -311.754356) (xy 288.205521 -311.754356) (xy 288.255924 -311.762179)
			(xy 288.30453 -311.777638) (xy 288.350191 -311.800369) (xy 288.37128 -311.814718) (xy 288.377821 -311.818993)
			(xy 288.392684 -311.823787) (xy 288.40049 -311.824116) (xy 288.916618 -311.824116) (xy 288.921979 -311.824636)
			(xy 288.929562 -311.832217) (xy 288.93008 -311.837578) (xy 288.93008 -312.332116) (xy 294.974264 -312.332116)
			(xy 294.974264 -311.837578) (xy 294.974711 -311.832266) (xy 294.982168 -311.824694) (xy 294.987472 -311.824116)
			(xy 295.5036 -311.824116) (xy 295.511412 -311.823816) (xy 295.526283 -311.819022) (xy 295.53281 -311.814718)
			(xy 295.553899 -311.800369) (xy 295.59956 -311.777638) (xy 295.648166 -311.762179) (xy 295.698569 -311.754356)
			(xy 295.749575 -311.754356) (xy 295.799978 -311.762179) (xy 295.848584 -311.777638) (xy 295.894245 -311.800369)
			(xy 295.915334 -311.814718) (xy 295.921863 -311.819013) (xy 295.936735 -311.823795) (xy 295.944544 -311.824116)
			(xy 296.460672 -311.824116) (xy 296.466006 -311.824448) (xy 296.473551 -311.83199) (xy 296.47388 -311.837324)
			(xy 296.47388 -311.837832) (xy 296.47388 -312.332116) (xy 302.518064 -312.332116) (xy 302.518064 -311.837578)
			(xy 302.518367 -311.832134) (xy 302.526081 -311.824448) (xy 302.531526 -311.824116) (xy 304.004726 -311.824116)
			(xy 304.010088 -311.824631) (xy 304.017671 -311.832216) (xy 304.018188 -311.837578) (xy 304.018188 -312.332116)
			(xy 411.618176 -312.332116) (xy 411.618176 -311.837578) (xy 411.618613 -311.832263) (xy 411.626076 -311.824691)
			(xy 411.631384 -311.824116) (xy 413.104584 -311.824116) (xy 413.10992 -311.82444) (xy 413.117463 -311.831988)
			(xy 413.117792 -311.837324) (xy 413.117792 -311.837832) (xy 413.117792 -312.332116) (xy 419.161976 -312.332116)
			(xy 419.161976 -311.837578) (xy 419.162268 -311.832131) (xy 419.169989 -311.824444) (xy 419.175438 -311.824116)
			(xy 419.691566 -311.824116) (xy 419.699376 -311.823802) (xy 419.714248 -311.819018) (xy 419.720776 -311.814718)
			(xy 419.741865 -311.800369) (xy 419.787526 -311.777638) (xy 419.836132 -311.762179) (xy 419.886535 -311.754356)
			(xy 419.937541 -311.754356) (xy 419.987944 -311.762179) (xy 420.03655 -311.777638) (xy 420.082211 -311.800369)
			(xy 420.1033 -311.814718) (xy 420.109837 -311.819) (xy 420.124703 -311.82379) (xy 420.13251 -311.824116)
			(xy 420.648638 -311.824116) (xy 420.654001 -311.824623) (xy 420.661583 -311.832214) (xy 420.6621 -311.837578)
			(xy 420.6621 -312.332116) (xy 426.706284 -312.332116) (xy 426.706284 -311.837578) (xy 426.706714 -311.832261)
			(xy 426.714182 -311.824688) (xy 426.719492 -311.824116) (xy 427.23562 -311.824116) (xy 427.243432 -311.823825)
			(xy 427.258304 -311.819025) (xy 427.26483 -311.814718) (xy 427.285919 -311.800369) (xy 427.33158 -311.777638)
			(xy 427.380186 -311.762179) (xy 427.430589 -311.754356) (xy 427.481595 -311.754356) (xy 427.531998 -311.762179)
			(xy 427.580604 -311.777638) (xy 427.626265 -311.800369) (xy 427.647354 -311.814718) (xy 427.653879 -311.819021)
			(xy 427.668754 -311.823798) (xy 427.676564 -311.824116) (xy 428.192692 -311.824116) (xy 428.198029 -311.824434)
			(xy 428.205572 -311.831987) (xy 428.2059 -311.837324) (xy 428.2059 -311.837832) (xy 428.2059 -312.332116)
			(xy 434.250084 -312.332116) (xy 434.250084 -311.837578) (xy 434.250369 -311.832129) (xy 434.258095 -311.824442)
			(xy 434.263546 -311.824116) (xy 434.779674 -311.824116) (xy 434.787485 -311.823805) (xy 434.802357 -311.819019)
			(xy 434.808884 -311.814718) (xy 434.829973 -311.800369) (xy 434.875634 -311.777638) (xy 434.92424 -311.762179)
			(xy 434.974643 -311.754356) (xy 435.025649 -311.754356) (xy 435.076052 -311.762179) (xy 435.124658 -311.777638)
			(xy 435.170319 -311.800369) (xy 435.191408 -311.814718) (xy 435.197943 -311.819003) (xy 435.21281 -311.823792)
			(xy 435.220618 -311.824116) (xy 435.736746 -311.824116) (xy 435.74211 -311.824618) (xy 435.749692 -311.832213)
			(xy 435.750208 -311.837578) (xy 435.750208 -312.332116) (xy 441.794392 -312.332116) (xy 441.794392 -311.837578)
			(xy 441.794903 -311.832282) (xy 441.802316 -311.824715) (xy 441.8076 -311.824116) (xy 442.323728 -311.824116)
			(xy 442.331541 -311.823828) (xy 442.346412 -311.819026) (xy 442.352938 -311.814718) (xy 442.374027 -311.800369)
			(xy 442.419688 -311.777638) (xy 442.468294 -311.762179) (xy 442.518697 -311.754356) (xy 442.569703 -311.754356)
			(xy 442.620106 -311.762179) (xy 442.668712 -311.777638) (xy 442.714373 -311.800369) (xy 442.735462 -311.814718)
			(xy 442.742008 -311.818986) (xy 442.756867 -311.823785) (xy 442.764672 -311.824116) (xy 443.2808 -311.824116)
			(xy 443.286138 -311.824429) (xy 443.293681 -311.831985) (xy 443.294008 -311.837324) (xy 443.294008 -311.837832)
			(xy 443.294008 -312.332116) (xy 449.338192 -312.332116) (xy 449.338192 -311.837578) (xy 449.338703 -311.832282)
			(xy 449.346116 -311.824715) (xy 449.3514 -311.824116) (xy 449.867528 -311.824116) (xy 449.875341 -311.823828)
			(xy 449.890212 -311.819026) (xy 449.896738 -311.814718) (xy 449.917827 -311.800369) (xy 449.963488 -311.777638)
			(xy 450.012094 -311.762179) (xy 450.062497 -311.754356) (xy 450.113503 -311.754356) (xy 450.163906 -311.762179)
			(xy 450.212512 -311.777638) (xy 450.258173 -311.800369) (xy 450.279262 -311.814718) (xy 450.285808 -311.818986)
			(xy 450.300667 -311.823785) (xy 450.308472 -311.824116) (xy 450.8246 -311.824116) (xy 450.829938 -311.824429)
			(xy 450.837481 -311.831985) (xy 450.837808 -311.837324) (xy 450.837808 -311.837832) (xy 450.837808 -312.332116)
			(xy 450.837316 -312.337381) (xy 450.829865 -312.344822) (xy 450.8246 -312.345324) (xy 450.308726 -312.345324)
			(xy 450.30085 -312.345592) (xy 450.285846 -312.35039) (xy 450.279262 -312.354722) (xy 450.258183 -312.369112)
			(xy 450.212539 -312.391941) (xy 450.163934 -312.4075) (xy 450.113517 -312.415419) (xy 450.088 -312.415936)
			(xy 450.062479 -312.415457) (xy 450.012052 -312.407558) (xy 449.963441 -312.391995) (xy 449.917803 -312.369138)
			(xy 449.896738 -312.354722) (xy 449.890138 -312.350421) (xy 449.875145 -312.345625) (xy 449.867274 -312.345324)
			(xy 449.3514 -312.345324) (xy 449.346141 -312.344807) (xy 449.3387 -312.337374) (xy 449.338192 -312.332116)
			(xy 443.294008 -312.332116) (xy 443.293516 -312.337381) (xy 443.286065 -312.344822) (xy 443.2808 -312.345324)
			(xy 442.764926 -312.345324) (xy 442.75705 -312.345592) (xy 442.742046 -312.35039) (xy 442.735462 -312.354722)
			(xy 442.714383 -312.369112) (xy 442.668739 -312.391941) (xy 442.620134 -312.4075) (xy 442.569717 -312.415419)
			(xy 442.5442 -312.415936) (xy 442.518679 -312.415457) (xy 442.468252 -312.407558) (xy 442.419641 -312.391995)
			(xy 442.374003 -312.369138) (xy 442.352938 -312.354722) (xy 442.346338 -312.350421) (xy 442.331345 -312.345625)
			(xy 442.323474 -312.345324) (xy 441.8076 -312.345324) (xy 441.802341 -312.344807) (xy 441.7949 -312.337374)
			(xy 441.794392 -312.332116) (xy 435.750208 -312.332116) (xy 435.749716 -312.337381) (xy 435.742265 -312.344822)
			(xy 435.737 -312.345324) (xy 435.736492 -312.345324) (xy 435.220872 -312.345324) (xy 435.212998 -312.345611)
			(xy 435.197994 -312.350396) (xy 435.191408 -312.354722) (xy 435.170345 -312.369135) (xy 435.124695 -312.391959)
			(xy 435.076085 -312.407511) (xy 435.025664 -312.415423) (xy 435.000146 -312.415936) (xy 434.974626 -312.415434)
			(xy 434.9242 -312.407542) (xy 434.875589 -312.391985) (xy 434.82995 -312.369135) (xy 434.808884 -312.354722)
			(xy 434.802296 -312.3504) (xy 434.787293 -312.345617) (xy 434.77942 -312.345324) (xy 434.263546 -312.345324)
			(xy 434.258239 -312.344842) (xy 434.250663 -312.337413) (xy 434.250084 -312.332116) (xy 428.2059 -312.332116)
			(xy 428.205415 -312.337383) (xy 428.19796 -312.344825) (xy 428.192692 -312.345324) (xy 427.676818 -312.345324)
			(xy 427.668945 -312.345632) (xy 427.653941 -312.350402) (xy 427.647354 -312.354722) (xy 427.626278 -312.369115)
			(xy 427.580633 -312.391944) (xy 427.532026 -312.407502) (xy 427.481609 -312.41542) (xy 427.456092 -312.415936)
			(xy 427.430573 -312.415411) (xy 427.380148 -312.407526) (xy 427.331537 -312.391976) (xy 427.285897 -312.369132)
			(xy 427.26483 -312.354722) (xy 427.258232 -312.350418) (xy 427.243237 -312.345624) (xy 427.235366 -312.345324)
			(xy 426.719492 -312.345324) (xy 426.714232 -312.344812) (xy 426.706791 -312.337376) (xy 426.706284 -312.332116)
			(xy 420.6621 -312.332116) (xy 420.661615 -312.337383) (xy 420.65416 -312.344825) (xy 420.648892 -312.345324)
			(xy 420.648384 -312.345324) (xy 420.132764 -312.345324) (xy 420.124889 -312.345608) (xy 420.109885 -312.350395)
			(xy 420.1033 -312.354722) (xy 420.082211 -312.369096) (xy 420.03657 -312.391929) (xy 419.987968 -312.407492)
			(xy 419.937554 -312.415416) (xy 419.912038 -312.415936) (xy 419.886518 -312.415438) (xy 419.836092 -312.407545)
			(xy 419.78748 -312.391987) (xy 419.741842 -312.369135) (xy 419.720776 -312.354722) (xy 419.71419 -312.350397)
			(xy 419.699186 -312.345616) (xy 419.691312 -312.345324) (xy 419.175438 -312.345324) (xy 419.17013 -312.344847)
			(xy 419.162555 -312.337414) (xy 419.161976 -312.332116) (xy 413.117792 -312.332116) (xy 413.117315 -312.337385)
			(xy 413.109854 -312.344827) (xy 413.104584 -312.345324) (xy 411.631384 -312.345324) (xy 411.626123 -312.344818)
			(xy 411.618682 -312.337377) (xy 411.618176 -312.332116) (xy 304.018188 -312.332116) (xy 304.017882 -312.337455)
			(xy 304.01032 -312.344997) (xy 304.00498 -312.345324) (xy 302.531526 -312.345324) (xy 302.526217 -312.344855)
			(xy 302.518642 -312.337416) (xy 302.518064 -312.332116) (xy 296.47388 -312.332116) (xy 296.473581 -312.337457)
			(xy 296.466014 -312.344999) (xy 296.460672 -312.345324) (xy 295.944798 -312.345324) (xy 295.936925 -312.345623)
			(xy 295.921921 -312.350399) (xy 295.915334 -312.354722) (xy 295.894263 -312.369124) (xy 295.848616 -312.391951)
			(xy 295.800008 -312.407506) (xy 295.749589 -312.415421) (xy 295.724072 -312.415936) (xy 295.698553 -312.415421)
			(xy 295.648127 -312.407533) (xy 295.599516 -312.39198) (xy 295.553876 -312.369133) (xy 295.53281 -312.354722)
			(xy 295.526217 -312.35041) (xy 295.511218 -312.345621) (xy 295.503346 -312.345324) (xy 294.987472 -312.345324)
			(xy 294.98221 -312.344826) (xy 294.97477 -312.337379) (xy 294.974264 -312.332116) (xy 288.93008 -312.332116)
			(xy 288.929781 -312.337457) (xy 288.922214 -312.344999) (xy 288.916872 -312.345324) (xy 288.916364 -312.345324)
			(xy 288.400744 -312.345324) (xy 288.392868 -312.345599) (xy 288.377865 -312.350392) (xy 288.37128 -312.354722)
			(xy 288.350196 -312.369104) (xy 288.304554 -312.391935) (xy 288.25595 -312.407496) (xy 288.205534 -312.415418)
			(xy 288.180018 -312.415936) (xy 288.154498 -312.415448) (xy 288.104071 -312.407552) (xy 288.05546 -312.391991)
			(xy 288.009821 -312.369137) (xy 287.988756 -312.354722) (xy 287.982175 -312.35039) (xy 287.967167 -312.345613)
			(xy 287.959292 -312.345324) (xy 287.443418 -312.345324) (xy 287.438108 -312.344861) (xy 287.430533 -312.337417)
			(xy 287.429956 -312.332116) (xy 281.385772 -312.332116) (xy 281.385481 -312.337459) (xy 281.377909 -312.345002)
			(xy 281.372564 -312.345324) (xy 280.85669 -312.345324) (xy 280.848816 -312.345619) (xy 280.833812 -312.350398)
			(xy 280.827226 -312.354722) (xy 280.806157 -312.369127) (xy 280.76051 -312.391953) (xy 280.711901 -312.407507)
			(xy 280.661482 -312.415422) (xy 280.635964 -312.415936) (xy 280.610445 -312.415425) (xy 280.560019 -312.407536)
			(xy 280.511408 -312.391982) (xy 280.465768 -312.369134) (xy 280.444702 -312.354722) (xy 280.43811 -312.350407)
			(xy 280.42311 -312.34562) (xy 280.415238 -312.345324) (xy 279.899364 -312.345324) (xy 279.894101 -312.344831)
			(xy 279.886661 -312.33738) (xy 279.886156 -312.332116) (xy 273.841972 -312.332116) (xy 273.841681 -312.337459)
			(xy 273.834109 -312.345002) (xy 273.828764 -312.345324) (xy 273.31289 -312.345324) (xy 273.305016 -312.345619)
			(xy 273.290012 -312.350398) (xy 273.283426 -312.354722) (xy 273.262357 -312.369127) (xy 273.21671 -312.391953)
			(xy 273.168101 -312.407507) (xy 273.117682 -312.415422) (xy 273.092164 -312.415936) (xy 273.066645 -312.415425)
			(xy 273.016219 -312.407536) (xy 272.967608 -312.391982) (xy 272.921968 -312.369134) (xy 272.900902 -312.354722)
			(xy 272.89431 -312.350407) (xy 272.87931 -312.34562) (xy 272.871438 -312.345324) (xy 272.355564 -312.345324)
			(xy 272.350301 -312.344831) (xy 272.342861 -312.33738) (xy 272.342356 -312.332116) (xy 266.298172 -312.332116)
			(xy 266.297881 -312.337459) (xy 266.290309 -312.345002) (xy 266.284964 -312.345324) (xy 266.284456 -312.345324)
			(xy 265.768836 -312.345324) (xy 265.76096 -312.345596) (xy 265.745956 -312.350391) (xy 265.739372 -312.354722)
			(xy 265.718291 -312.369108) (xy 265.672647 -312.391938) (xy 265.624043 -312.407498) (xy 265.573626 -312.415418)
			(xy 265.54811 -312.415936) (xy 265.52259 -312.415452) (xy 265.472163 -312.407555) (xy 265.423551 -312.391993)
			(xy 265.377913 -312.369137) (xy 265.356848 -312.354722) (xy 265.350268 -312.350386) (xy 265.335259 -312.345612)
			(xy 265.327384 -312.345324) (xy 264.81151 -312.345324) (xy 264.806199 -312.344866) (xy 264.798625 -312.337418)
			(xy 264.798048 -312.332116) (xy 202.89774 -312.332116) (xy 202.89774 -312.33237) (xy 202.897255 -312.337675)
			(xy 202.889827 -312.345249) (xy 202.884532 -312.345832) (xy 202.368658 -312.345832) (xy 202.36085 -312.346165)
			(xy 202.345978 -312.350937) (xy 202.339448 -312.35523) (xy 202.318337 -312.369595) (xy 202.272609 -312.392319)
			(xy 202.223933 -312.407745) (xy 202.173464 -312.415506) (xy 202.147932 -312.415936) (xy 202.122402 -312.415489)
			(xy 202.071938 -312.407717) (xy 202.023266 -312.392291) (xy 201.977538 -312.369577) (xy 201.956416 -312.35523)
			(xy 201.949878 -312.350949) (xy 201.935013 -312.346159) (xy 201.927206 -312.345832) (xy 201.411332 -312.345832)
			(xy 201.40601 -312.345454) (xy 201.398469 -312.337945) (xy 201.398124 -312.332624) (xy 195.353917 -312.332624)
			(xy 195.353455 -312.337675) (xy 195.346027 -312.345249) (xy 195.340732 -312.345832) (xy 194.824858 -312.345832)
			(xy 194.81705 -312.346165) (xy 194.802178 -312.350937) (xy 194.795648 -312.35523) (xy 194.774537 -312.369595)
			(xy 194.728809 -312.392319) (xy 194.680133 -312.407745) (xy 194.629664 -312.415506) (xy 194.604132 -312.415936)
			(xy 194.578602 -312.415489) (xy 194.528138 -312.407717) (xy 194.479466 -312.392291) (xy 194.433738 -312.369577)
			(xy 194.412616 -312.35523) (xy 194.406078 -312.350949) (xy 194.391213 -312.346159) (xy 194.383406 -312.345832)
			(xy 193.867532 -312.345832) (xy 193.86221 -312.345454) (xy 193.854669 -312.337945) (xy 193.854324 -312.332624)
			(xy 187.810124 -312.332624) (xy 187.809798 -312.337806) (xy 187.802114 -312.345495) (xy 187.796678 -312.345832)
			(xy 187.280804 -312.345832) (xy 187.272993 -312.346142) (xy 187.258122 -312.35093) (xy 187.251594 -312.35523)
			(xy 187.23047 -312.369575) (xy 187.184747 -312.392304) (xy 187.136075 -312.407735) (xy 187.085609 -312.415502)
			(xy 187.060078 -312.415936) (xy 187.034547 -312.415516) (xy 186.984082 -312.407736) (xy 186.93541 -312.392302)
			(xy 186.889683 -312.36958) (xy 186.868562 -312.35523) (xy 186.862036 -312.350929) (xy 186.847162 -312.346151)
			(xy 186.839352 -312.345832) (xy 186.323478 -312.345832) (xy 186.318033 -312.345532) (xy 186.310346 -312.337816)
			(xy 186.310016 -312.33237) (xy 180.265832 -312.33237) (xy 180.265354 -312.337677) (xy 180.257921 -312.345252)
			(xy 180.252624 -312.345832) (xy 179.73675 -312.345832) (xy 179.728941 -312.346162) (xy 179.71407 -312.350936)
			(xy 179.70754 -312.35523) (xy 179.686431 -312.369599) (xy 179.640703 -312.392322) (xy 179.592026 -312.407746)
			(xy 179.541556 -312.415507) (xy 179.516024 -312.415936) (xy 179.490494 -312.415493) (xy 179.44003 -312.40772)
			(xy 179.391358 -312.392293) (xy 179.34563 -312.369577) (xy 179.324508 -312.35523) (xy 179.317972 -312.350946)
			(xy 179.303106 -312.346158) (xy 179.295298 -312.345832) (xy 178.779424 -312.345832) (xy 178.77417 -312.345292)
			(xy 178.766727 -312.337876) (xy 178.766216 -312.332624) (xy 172.722016 -312.332624) (xy 172.721697 -312.337808)
			(xy 172.714008 -312.345497) (xy 172.70857 -312.345832) (xy 172.192696 -312.345832) (xy 172.184885 -312.346138)
			(xy 172.170014 -312.350929) (xy 172.163486 -312.35523) (xy 172.142364 -312.369579) (xy 172.096641 -312.392306)
			(xy 172.047967 -312.407737) (xy 171.997501 -312.415503) (xy 171.97197 -312.415936) (xy 171.946439 -312.41552)
			(xy 171.895974 -312.407738) (xy 171.847302 -312.392304) (xy 171.801575 -312.369581) (xy 171.780454 -312.35523)
			(xy 171.77393 -312.350925) (xy 171.759054 -312.34615) (xy 171.751244 -312.345832) (xy 171.23537 -312.345832)
			(xy 171.229995 -312.345367) (xy 171.222409 -312.337747) (xy 171.221908 -312.33237) (xy 165.177724 -312.33237)
			(xy 165.177253 -312.337679) (xy 165.169815 -312.345254) (xy 165.164516 -312.345832) (xy 163.691316 -312.345832)
			(xy 163.686061 -312.345297) (xy 163.678619 -312.337878) (xy 163.678108 -312.332624) (xy 56.078105 -312.332624)
			(xy 56.077796 -312.337811) (xy 56.070099 -312.345501) (xy 56.064658 -312.345832) (xy 54.591458 -312.345832)
			(xy 54.586082 -312.345375) (xy 54.578497 -312.337749) (xy 54.577996 -312.33237) (xy 48.533812 -312.33237)
			(xy 48.533351 -312.337682) (xy 48.525907 -312.345257) (xy 48.520604 -312.345832) (xy 48.00473 -312.345832)
			(xy 47.996921 -312.346153) (xy 47.982049 -312.350934) (xy 47.97552 -312.35523) (xy 47.954389 -312.369564)
			(xy 47.908669 -312.392295) (xy 47.859998 -312.407729) (xy 47.809534 -312.415501) (xy 47.784004 -312.415936)
			(xy 47.758474 -312.415503) (xy 47.708009 -312.407727) (xy 47.659337 -312.392297) (xy 47.61361 -312.369578)
			(xy 47.592488 -312.35523) (xy 47.585957 -312.350939) (xy 47.571087 -312.346155) (xy 47.563278 -312.345832)
			(xy 47.047404 -312.345832) (xy 47.042148 -312.345305) (xy 47.034706 -312.337879) (xy 47.034196 -312.332624)
			(xy 40.989985 -312.332624) (xy 40.989435 -312.337718) (xy 40.981895 -312.345303) (xy 40.97655 -312.345832)
			(xy 40.460676 -312.345832) (xy 40.452864 -312.34613) (xy 40.437993 -312.350926) (xy 40.431466 -312.35523)
			(xy 40.41035 -312.369588) (xy 40.364624 -312.392313) (xy 40.315949 -312.407741) (xy 40.265481 -312.415505)
			(xy 40.23995 -312.415936) (xy 40.21442 -312.41548) (xy 40.163957 -312.407711) (xy 40.115285 -312.392287)
			(xy 40.069556 -312.369576) (xy 40.048434 -312.35523) (xy 40.041892 -312.350956) (xy 40.02703 -312.346162)
			(xy 40.019224 -312.345832) (xy 39.50335 -312.345832) (xy 39.497973 -312.34538) (xy 39.490388 -312.33775)
			(xy 39.489888 -312.33237) (xy 33.445704 -312.33237) (xy 33.445162 -312.33766) (xy 33.437773 -312.345231)
			(xy 33.432496 -312.345832) (xy 32.916622 -312.345832) (xy 32.908812 -312.346149) (xy 32.89394 -312.350932)
			(xy 32.887412 -312.35523) (xy 32.866283 -312.369568) (xy 32.820562 -312.392298) (xy 32.771891 -312.407731)
			(xy 32.721426 -312.415501) (xy 32.695896 -312.415936) (xy 32.670365 -312.415507) (xy 32.619901 -312.407729)
			(xy 32.571229 -312.392298) (xy 32.525501 -312.369579) (xy 32.50438 -312.35523) (xy 32.49785 -312.350935)
			(xy 32.482979 -312.346154) (xy 32.47517 -312.345832) (xy 31.959296 -312.345832) (xy 31.954038 -312.345311)
			(xy 31.946597 -312.337881) (xy 31.946088 -312.332624) (xy 25.901878 -312.332624) (xy 25.901362 -312.33766)
			(xy 25.893973 -312.345231) (xy 25.888696 -312.345832) (xy 25.372822 -312.345832) (xy 25.365012 -312.346149)
			(xy 25.35014 -312.350932) (xy 25.343612 -312.35523) (xy 25.322483 -312.369568) (xy 25.276762 -312.392298)
			(xy 25.228091 -312.407731) (xy 25.177626 -312.415501) (xy 25.152096 -312.415936) (xy 25.126565 -312.415507)
			(xy 25.076101 -312.407729) (xy 25.027429 -312.392298) (xy 24.981701 -312.369579) (xy 24.96058 -312.35523)
			(xy 24.95405 -312.350935) (xy 24.939179 -312.346154) (xy 24.93137 -312.345832) (xy 24.415496 -312.345832)
			(xy 24.410238 -312.345311) (xy 24.402797 -312.337881) (xy 24.402288 -312.332624) (xy 18.358077 -312.332624)
			(xy 18.357534 -312.33772) (xy 18.349989 -312.345305) (xy 18.344642 -312.345832) (xy 17.828768 -312.345832)
			(xy 17.82096 -312.346169) (xy 17.806088 -312.350939) (xy 17.799558 -312.35523) (xy 17.778444 -312.369591)
			(xy 17.732718 -312.392316) (xy 17.684042 -312.407743) (xy 17.633574 -312.415505) (xy 17.608042 -312.415936)
			(xy 17.582512 -312.415484) (xy 17.532049 -312.407713) (xy 17.483376 -312.392289) (xy 17.437648 -312.369576)
			(xy 17.416526 -312.35523) (xy 17.409986 -312.350953) (xy 17.395123 -312.346161) (xy 17.387316 -312.345832)
			(xy 16.871442 -312.345832) (xy 16.866006 -312.34549) (xy 16.858315 -312.337806) (xy 16.85798 -312.33237)
			(xy 2.509012 -312.33237) (xy 2.509012 -313.182508) (xy 20.958048 -313.182508) (xy 20.958048 -312.68797)
			(xy 20.958531 -312.6826) (xy 20.966139 -312.675015) (xy 20.97151 -312.674508) (xy 21.487638 -312.674508)
			(xy 21.495446 -312.674167) (xy 21.510317 -312.6694) (xy 21.516848 -312.66511) (xy 21.537937 -312.650761)
			(xy 21.583598 -312.62803) (xy 21.632204 -312.612571) (xy 21.682607 -312.604748) (xy 21.733613 -312.604748)
			(xy 21.784016 -312.612571) (xy 21.832622 -312.62803) (xy 21.878283 -312.650761) (xy 21.899372 -312.66511)
			(xy 21.90591 -312.66939) (xy 21.920775 -312.67418) (xy 21.928582 -312.674508) (xy 22.44471 -312.674508)
			(xy 22.450068 -312.675041) (xy 22.457651 -312.682613) (xy 22.458172 -312.68797) (xy 22.458172 -313.182508)
			(xy 28.502356 -313.182508) (xy 28.502356 -312.68797) (xy 28.502805 -312.682658) (xy 28.510261 -312.675088)
			(xy 28.515564 -312.674508) (xy 29.031692 -312.674508) (xy 29.039502 -312.67419) (xy 29.054373 -312.669407)
			(xy 29.060902 -312.66511) (xy 29.081991 -312.650761) (xy 29.127652 -312.62803) (xy 29.176258 -312.612571)
			(xy 29.226661 -312.604748) (xy 29.277667 -312.604748) (xy 29.32807 -312.612571) (xy 29.376676 -312.62803)
			(xy 29.422337 -312.650761) (xy 29.443426 -312.66511) (xy 29.449952 -312.669411) (xy 29.464826 -312.674188)
			(xy 29.472636 -312.674508) (xy 29.988764 -312.674508) (xy 29.994095 -312.674853) (xy 30.001639 -312.682385)
			(xy 30.001972 -312.687716) (xy 30.001972 -312.688224) (xy 30.001972 -313.182508) (xy 36.046156 -313.182508)
			(xy 36.046156 -312.68797) (xy 36.046605 -312.682658) (xy 36.054061 -312.675088) (xy 36.059364 -312.674508)
			(xy 36.575492 -312.674508) (xy 36.583302 -312.67419) (xy 36.598173 -312.669407) (xy 36.604702 -312.66511)
			(xy 36.625791 -312.650761) (xy 36.671452 -312.62803) (xy 36.720058 -312.612571) (xy 36.770461 -312.604748)
			(xy 36.821467 -312.604748) (xy 36.87187 -312.612571) (xy 36.920476 -312.62803) (xy 36.966137 -312.650761)
			(xy 36.987226 -312.66511) (xy 36.993752 -312.669411) (xy 37.008626 -312.674188) (xy 37.016436 -312.674508)
			(xy 37.532564 -312.674508) (xy 37.537895 -312.674853) (xy 37.545439 -312.682385) (xy 37.545772 -312.687716)
			(xy 37.545772 -312.688224) (xy 37.545772 -313.182508) (xy 43.589956 -313.182508) (xy 43.589956 -312.68797)
			(xy 43.590432 -312.682598) (xy 43.598044 -312.675013) (xy 43.603418 -312.674508) (xy 44.119546 -312.674508)
			(xy 44.127354 -312.67417) (xy 44.142225 -312.669401) (xy 44.148756 -312.66511) (xy 44.169845 -312.650761)
			(xy 44.215506 -312.62803) (xy 44.264112 -312.612571) (xy 44.314515 -312.604748) (xy 44.365521 -312.604748)
			(xy 44.415924 -312.612571) (xy 44.46453 -312.62803) (xy 44.510191 -312.650761) (xy 44.53128 -312.66511)
			(xy 44.537816 -312.669393) (xy 44.552683 -312.674181) (xy 44.56049 -312.674508) (xy 45.076618 -312.674508)
			(xy 45.081977 -312.675035) (xy 45.08956 -312.682612) (xy 45.09008 -312.68797) (xy 45.09008 -313.182508)
			(xy 51.134264 -313.182508) (xy 51.134264 -312.68797) (xy 51.134706 -312.682656) (xy 51.142166 -312.675086)
			(xy 51.147472 -312.674508) (xy 51.6636 -312.674508) (xy 51.67141 -312.674193) (xy 51.686281 -312.669408)
			(xy 51.69281 -312.66511) (xy 51.713899 -312.650761) (xy 51.75956 -312.62803) (xy 51.808166 -312.612571)
			(xy 51.858569 -312.604748) (xy 51.909575 -312.604748) (xy 51.959978 -312.612571) (xy 52.008584 -312.62803)
			(xy 52.054245 -312.650761) (xy 52.075334 -312.66511) (xy 52.081858 -312.669414) (xy 52.096734 -312.674189)
			(xy 52.104544 -312.674508) (xy 52.620672 -312.674508) (xy 52.626004 -312.674847) (xy 52.633548 -312.682384)
			(xy 52.63388 -312.687716) (xy 52.63388 -312.688224) (xy 52.63388 -313.182508) (xy 58.678064 -313.182508)
			(xy 58.678064 -312.68797) (xy 58.678533 -312.682596) (xy 58.68615 -312.675011) (xy 58.691526 -312.674508)
			(xy 60.164726 -312.674508) (xy 60.170086 -312.67503) (xy 60.177668 -312.68261) (xy 60.178188 -312.68797)
			(xy 60.178188 -313.182508) (xy 167.778176 -313.182508) (xy 167.778176 -312.68797) (xy 167.778607 -312.682654)
			(xy 167.786075 -312.675082) (xy 167.791384 -312.674508) (xy 169.264584 -312.674508) (xy 169.269918 -312.674839)
			(xy 169.277461 -312.682382) (xy 169.277792 -312.687716) (xy 169.277792 -313.182508) (xy 175.321976 -313.182508)
			(xy 175.321976 -312.68797) (xy 175.322263 -312.682522) (xy 175.329988 -312.674835) (xy 175.335438 -312.674508)
			(xy 175.851566 -312.674508) (xy 175.859375 -312.674179) (xy 175.874246 -312.669403) (xy 175.880776 -312.66511)
			(xy 175.901865 -312.650761) (xy 175.947526 -312.62803) (xy 175.996132 -312.612571) (xy 176.046535 -312.604748)
			(xy 176.097541 -312.604748) (xy 176.147944 -312.612571) (xy 176.19655 -312.62803) (xy 176.242211 -312.650761)
			(xy 176.2633 -312.66511) (xy 176.269832 -312.669401) (xy 176.284702 -312.674184) (xy 176.29251 -312.674508)
			(xy 176.808638 -312.674508) (xy 176.813999 -312.675022) (xy 176.821581 -312.682608) (xy 176.8221 -312.68797)
			(xy 176.8221 -313.182508) (xy 182.866284 -313.182508) (xy 182.866284 -312.68797) (xy 182.866708 -312.682652)
			(xy 182.874181 -312.67508) (xy 182.879492 -312.674508) (xy 183.39562 -312.674508) (xy 183.403431 -312.674201)
			(xy 183.418302 -312.66941) (xy 183.42483 -312.66511) (xy 183.445919 -312.650761) (xy 183.49158 -312.62803)
			(xy 183.540186 -312.612571) (xy 183.590589 -312.604748) (xy 183.641595 -312.604748) (xy 183.691998 -312.612571)
			(xy 183.740604 -312.62803) (xy 183.786265 -312.650761) (xy 183.807354 -312.66511) (xy 183.813874 -312.669422)
			(xy 183.828753 -312.674192) (xy 183.836564 -312.674508) (xy 184.352692 -312.674508) (xy 184.358027 -312.674834)
			(xy 184.36557 -312.682381) (xy 184.3659 -312.687716) (xy 184.3659 -312.688224) (xy 184.3659 -313.182508)
			(xy 190.410084 -313.182508) (xy 190.410084 -312.68797) (xy 190.410364 -312.68252) (xy 190.418094 -312.674833)
			(xy 190.423546 -312.674508) (xy 190.939674 -312.674508) (xy 190.947483 -312.674182) (xy 190.962354 -312.669404)
			(xy 190.968884 -312.66511) (xy 190.989973 -312.650761) (xy 191.035634 -312.62803) (xy 191.08424 -312.612571)
			(xy 191.134643 -312.604748) (xy 191.185649 -312.604748) (xy 191.236052 -312.612571) (xy 191.284658 -312.62803)
			(xy 191.330319 -312.650761) (xy 191.351408 -312.66511) (xy 191.357938 -312.669404) (xy 191.372809 -312.674185)
			(xy 191.380618 -312.674508) (xy 191.896746 -312.674508) (xy 191.902108 -312.675017) (xy 191.90969 -312.682607)
			(xy 191.910208 -312.68797) (xy 191.910208 -313.182508) (xy 197.954392 -313.182508) (xy 197.954392 -312.68797)
			(xy 197.954897 -312.682673) (xy 197.962314 -312.675107) (xy 197.9676 -312.674508) (xy 198.483728 -312.674508)
			(xy 198.491539 -312.674205) (xy 198.50641 -312.669411) (xy 198.512938 -312.66511) (xy 198.534027 -312.650761)
			(xy 198.579688 -312.62803) (xy 198.628294 -312.612571) (xy 198.678697 -312.604748) (xy 198.729703 -312.604748)
			(xy 198.780106 -312.612571) (xy 198.828712 -312.62803) (xy 198.874373 -312.650761) (xy 198.895462 -312.66511)
			(xy 198.902002 -312.669386) (xy 198.916866 -312.674178) (xy 198.924672 -312.674508) (xy 199.4408 -312.674508)
			(xy 199.446136 -312.674828) (xy 199.453678 -312.682379) (xy 199.454008 -312.687716) (xy 199.454008 -312.688224)
			(xy 199.454008 -313.182508) (xy 205.498192 -313.182508) (xy 205.498192 -312.68797) (xy 205.498697 -312.682673)
			(xy 205.506114 -312.675107) (xy 205.5114 -312.674508) (xy 206.027528 -312.674508) (xy 206.035339 -312.674205)
			(xy 206.05021 -312.669411) (xy 206.056738 -312.66511) (xy 206.077827 -312.650761) (xy 206.123488 -312.62803)
			(xy 206.172094 -312.612571) (xy 206.222497 -312.604748) (xy 206.273503 -312.604748) (xy 206.323906 -312.612571)
			(xy 206.372512 -312.62803) (xy 206.418173 -312.650761) (xy 206.439262 -312.66511) (xy 206.445802 -312.669386)
			(xy 206.460666 -312.674178) (xy 206.468472 -312.674508) (xy 206.9846 -312.674508) (xy 206.989936 -312.674828)
			(xy 206.997478 -312.682379) (xy 206.997808 -312.687716) (xy 206.997808 -312.688224) (xy 206.997808 -313.182254)
			(xy 268.898116 -313.182254) (xy 268.898116 -312.687716) (xy 268.89844 -312.68238) (xy 268.905988 -312.674837)
			(xy 268.911324 -312.674508) (xy 268.911832 -312.674508) (xy 269.427706 -312.674508) (xy 269.435516 -312.674196)
			(xy 269.450387 -312.669408) (xy 269.456916 -312.66511) (xy 269.478005 -312.650761) (xy 269.523666 -312.62803)
			(xy 269.572272 -312.612571) (xy 269.622675 -312.604748) (xy 269.673681 -312.604748) (xy 269.724084 -312.612571)
			(xy 269.77269 -312.62803) (xy 269.818351 -312.650761) (xy 269.83944 -312.66511) (xy 269.845963 -312.669416)
			(xy 269.86084 -312.67419) (xy 269.86865 -312.674508) (xy 270.384778 -312.674508) (xy 270.390072 -312.675034)
			(xy 270.397643 -312.682434) (xy 270.39824 -312.687716) (xy 270.39824 -313.182254) (xy 270.398224 -313.182508)
			(xy 276.442424 -313.182508) (xy 276.442424 -313.182) (xy 276.442424 -312.687716) (xy 276.442741 -312.682378)
			(xy 276.450294 -312.674834) (xy 276.455632 -312.674508) (xy 276.97176 -312.674508) (xy 276.979568 -312.674176)
			(xy 276.99444 -312.669402) (xy 277.00097 -312.66511) (xy 277.022059 -312.650761) (xy 277.06772 -312.62803)
			(xy 277.116326 -312.612571) (xy 277.166729 -312.604748) (xy 277.217735 -312.604748) (xy 277.268138 -312.612571)
			(xy 277.316744 -312.62803) (xy 277.362405 -312.650761) (xy 277.383494 -312.66511) (xy 277.390027 -312.669399)
			(xy 277.404896 -312.674183) (xy 277.412704 -312.674508) (xy 277.928832 -312.674508) (xy 277.934102 -312.674975)
			(xy 277.941544 -312.682444) (xy 277.94204 -312.687716) (xy 277.94204 -313.182254) (xy 277.942016 -313.182508)
			(xy 283.986224 -313.182508) (xy 283.986224 -313.182) (xy 283.986224 -312.687716) (xy 283.986541 -312.682378)
			(xy 283.994094 -312.674834) (xy 283.999432 -312.674508) (xy 284.51556 -312.674508) (xy 284.523368 -312.674176)
			(xy 284.53824 -312.669402) (xy 284.54477 -312.66511) (xy 284.565859 -312.650761) (xy 284.61152 -312.62803)
			(xy 284.660126 -312.612571) (xy 284.710529 -312.604748) (xy 284.761535 -312.604748) (xy 284.811938 -312.612571)
			(xy 284.860544 -312.62803) (xy 284.906205 -312.650761) (xy 284.927294 -312.66511) (xy 284.933827 -312.669399)
			(xy 284.948696 -312.674183) (xy 284.956504 -312.674508) (xy 285.472632 -312.674508) (xy 285.477902 -312.674975)
			(xy 285.485344 -312.682444) (xy 285.48584 -312.687716) (xy 285.48584 -313.182254) (xy 291.530024 -313.182254)
			(xy 291.530024 -312.687716) (xy 291.530341 -312.682378) (xy 291.537894 -312.674834) (xy 291.543232 -312.674508)
			(xy 291.54374 -312.674508) (xy 292.059614 -312.674508) (xy 292.067424 -312.674199) (xy 292.082296 -312.66941)
			(xy 292.088824 -312.66511) (xy 292.109913 -312.650761) (xy 292.155574 -312.62803) (xy 292.20418 -312.612571)
			(xy 292.254583 -312.604748) (xy 292.305589 -312.604748) (xy 292.355992 -312.612571) (xy 292.404598 -312.62803)
			(xy 292.450259 -312.650761) (xy 292.471348 -312.66511) (xy 292.477869 -312.669419) (xy 292.492747 -312.674191)
			(xy 292.500558 -312.674508) (xy 293.016686 -312.674508) (xy 293.021981 -312.675029) (xy 293.029551 -312.682433)
			(xy 293.030148 -312.687716) (xy 293.030148 -313.182254) (xy 293.030131 -313.182508) (xy 299.074332 -313.182508)
			(xy 299.074332 -313.182) (xy 299.074332 -312.687716) (xy 299.074641 -312.682376) (xy 299.0822 -312.674832)
			(xy 299.08754 -312.674508) (xy 299.603668 -312.674508) (xy 299.611477 -312.674179) (xy 299.626348 -312.669404)
			(xy 299.632878 -312.66511) (xy 299.653967 -312.650761) (xy 299.699628 -312.62803) (xy 299.748234 -312.612571)
			(xy 299.798637 -312.604748) (xy 299.849643 -312.604748) (xy 299.900046 -312.612571) (xy 299.948652 -312.62803)
			(xy 299.994313 -312.650761) (xy 300.015402 -312.66511) (xy 300.021933 -312.669402) (xy 300.036803 -312.674184)
			(xy 300.044612 -312.674508) (xy 300.56074 -312.674508) (xy 300.566012 -312.67497) (xy 300.573453 -312.682442)
			(xy 300.573948 -312.687716) (xy 300.573948 -313.182254) (xy 306.618132 -313.182254) (xy 306.618132 -312.687716)
			(xy 306.618441 -312.682376) (xy 306.626 -312.674832) (xy 306.63134 -312.674508) (xy 306.631848 -312.674508)
			(xy 308.104794 -312.674508) (xy 308.11009 -312.675023) (xy 308.11766 -312.682432) (xy 308.118256 -312.687716)
			(xy 308.118256 -313.182254) (xy 308.118239 -313.182508) (xy 415.718244 -313.182508) (xy 415.718244 -312.687716)
			(xy 415.7188 -312.682467) (xy 415.726205 -312.675026) (xy 415.731452 -312.674508) (xy 417.204652 -312.674508)
			(xy 417.209982 -312.674861) (xy 417.217526 -312.682387) (xy 417.21786 -312.687716) (xy 417.21786 -313.182254)
			(xy 423.262044 -313.182254) (xy 423.262044 -312.687716) (xy 423.2626 -312.682467) (xy 423.270005 -312.675026)
			(xy 423.275252 -312.674508) (xy 423.27576 -312.674508) (xy 423.791634 -312.674508) (xy 423.799441 -312.674165)
			(xy 423.814313 -312.669399) (xy 423.820844 -312.66511) (xy 423.841933 -312.650761) (xy 423.887594 -312.62803)
			(xy 423.9362 -312.612571) (xy 423.986603 -312.604748) (xy 424.037609 -312.604748) (xy 424.088012 -312.612571)
			(xy 424.136618 -312.62803) (xy 424.182279 -312.650761) (xy 424.203368 -312.66511) (xy 424.209907 -312.669389)
			(xy 424.224771 -312.674179) (xy 424.232578 -312.674508) (xy 424.748706 -312.674508) (xy 424.754003 -312.675015)
			(xy 424.761572 -312.68243) (xy 424.762168 -312.687716) (xy 424.762168 -313.182254) (xy 424.76215 -313.182508)
			(xy 430.806352 -313.182508) (xy 430.806352 -313.182) (xy 430.806352 -312.687716) (xy 430.806901 -312.682465)
			(xy 430.814311 -312.675024) (xy 430.81956 -312.674508) (xy 431.335688 -312.674508) (xy 431.343497 -312.674188)
			(xy 431.358369 -312.669406) (xy 431.364898 -312.66511) (xy 431.385987 -312.650761) (xy 431.431648 -312.62803)
			(xy 431.480254 -312.612571) (xy 431.530657 -312.604748) (xy 431.581663 -312.604748) (xy 431.632066 -312.612571)
			(xy 431.680672 -312.62803) (xy 431.726333 -312.650761) (xy 431.747422 -312.66511) (xy 431.753949 -312.669409)
			(xy 431.768822 -312.674187) (xy 431.776632 -312.674508) (xy 432.29276 -312.674508) (xy 432.298091 -312.674855)
			(xy 432.305635 -312.682386) (xy 432.305968 -312.687716) (xy 432.305968 -313.182254) (xy 438.350152 -313.182254)
			(xy 438.350152 -312.687716) (xy 438.350701 -312.682465) (xy 438.358111 -312.675024) (xy 438.36336 -312.674508)
			(xy 438.363868 -312.674508) (xy 438.879742 -312.674508) (xy 438.88755 -312.674168) (xy 438.902421 -312.6694)
			(xy 438.908952 -312.66511) (xy 438.930041 -312.650761) (xy 438.975702 -312.62803) (xy 439.024308 -312.612571)
			(xy 439.074711 -312.604748) (xy 439.125717 -312.604748) (xy 439.17612 -312.612571) (xy 439.224726 -312.62803)
			(xy 439.270387 -312.650761) (xy 439.291476 -312.66511) (xy 439.298013 -312.669392) (xy 439.312879 -312.67418)
			(xy 439.320686 -312.674508) (xy 439.836814 -312.674508) (xy 439.842112 -312.67501) (xy 439.849681 -312.682429)
			(xy 439.850276 -312.687716) (xy 439.850276 -313.182254) (xy 439.850258 -313.182508) (xy 445.89446 -313.182508)
			(xy 445.89446 -313.182) (xy 445.89446 -312.687716) (xy 445.895002 -312.682463) (xy 445.902417 -312.675021)
			(xy 445.907668 -312.674508) (xy 446.423796 -312.674508) (xy 446.431606 -312.674191) (xy 446.446477 -312.669407)
			(xy 446.453006 -312.66511) (xy 446.474095 -312.650761) (xy 446.519756 -312.62803) (xy 446.568362 -312.612571)
			(xy 446.618765 -312.604748) (xy 446.669771 -312.604748) (xy 446.720174 -312.612571) (xy 446.76878 -312.62803)
			(xy 446.814441 -312.650761) (xy 446.83553 -312.66511) (xy 446.842055 -312.669412) (xy 446.85693 -312.674188)
			(xy 446.86474 -312.674508) (xy 447.380868 -312.674508) (xy 447.3862 -312.67485) (xy 447.393744 -312.682385)
			(xy 447.394076 -312.687716) (xy 447.394076 -313.182254) (xy 447.394051 -313.182508) (xy 453.43826 -313.182508)
			(xy 453.43826 -313.182) (xy 453.43826 -312.687716) (xy 453.438802 -312.682463) (xy 453.446217 -312.675021)
			(xy 453.451468 -312.674508) (xy 453.967596 -312.674508) (xy 453.975406 -312.674191) (xy 453.990277 -312.669407)
			(xy 453.996806 -312.66511) (xy 454.017895 -312.650761) (xy 454.063556 -312.62803) (xy 454.112162 -312.612571)
			(xy 454.162565 -312.604748) (xy 454.213571 -312.604748) (xy 454.263974 -312.612571) (xy 454.31258 -312.62803)
			(xy 454.358241 -312.650761) (xy 454.37933 -312.66511) (xy 454.385855 -312.669412) (xy 454.40073 -312.674188)
			(xy 454.40854 -312.674508) (xy 454.924668 -312.674508) (xy 454.93 -312.67485) (xy 454.937544 -312.682385)
			(xy 454.937876 -312.687716) (xy 454.937876 -313.182254) (xy 454.937348 -313.187549) (xy 454.92995 -313.195122)
			(xy 454.924668 -313.195716) (xy 454.408794 -313.195716) (xy 454.400983 -313.196024) (xy 454.386112 -313.200814)
			(xy 454.379584 -313.205114) (xy 454.358461 -313.219462) (xy 454.312738 -313.24219) (xy 454.264065 -313.257621)
			(xy 454.213599 -313.265387) (xy 454.188068 -313.26582) (xy 454.162537 -313.265408) (xy 454.112072 -313.257626)
			(xy 454.063399 -313.24219) (xy 454.017673 -313.219465) (xy 453.996552 -313.205114) (xy 453.99003 -313.200807)
			(xy 453.975153 -313.196033) (xy 453.967342 -313.195716) (xy 453.451468 -313.195716) (xy 453.446203 -313.195227)
			(xy 453.438763 -313.187774) (xy 453.43826 -313.182508) (xy 447.394051 -313.182508) (xy 447.393548 -313.187549)
			(xy 447.38615 -313.195122) (xy 447.380868 -313.195716) (xy 446.864994 -313.195716) (xy 446.857183 -313.196024)
			(xy 446.842312 -313.200814) (xy 446.835784 -313.205114) (xy 446.814661 -313.219462) (xy 446.768938 -313.24219)
			(xy 446.720265 -313.257621) (xy 446.669799 -313.265387) (xy 446.644268 -313.26582) (xy 446.618737 -313.265408)
			(xy 446.568272 -313.257626) (xy 446.519599 -313.24219) (xy 446.473873 -313.219465) (xy 446.452752 -313.205114)
			(xy 446.44623 -313.200807) (xy 446.431353 -313.196033) (xy 446.423542 -313.195716) (xy 445.907668 -313.195716)
			(xy 445.902403 -313.195227) (xy 445.894963 -313.187774) (xy 445.89446 -313.182508) (xy 439.850258 -313.182508)
			(xy 439.849891 -313.187679) (xy 439.842238 -313.195367) (xy 439.836814 -313.195716) (xy 439.32094 -313.195716)
			(xy 439.313131 -313.196044) (xy 439.29826 -313.20082) (xy 439.29173 -313.205114) (xy 439.270622 -313.219485)
			(xy 439.224894 -313.242208) (xy 439.176216 -313.257632) (xy 439.125746 -313.265391) (xy 439.100214 -313.26582)
			(xy 439.074684 -313.265384) (xy 439.024219 -313.25761) (xy 438.975547 -313.24218) (xy 438.929819 -313.219462)
			(xy 438.908698 -313.205114) (xy 438.902165 -313.200824) (xy 438.887296 -313.19604) (xy 438.879488 -313.195716)
			(xy 438.363614 -313.195716) (xy 438.35817 -313.195407) (xy 438.35048 -313.187699) (xy 438.350152 -313.182254)
			(xy 432.305968 -313.182254) (xy 432.305447 -313.187551) (xy 432.298045 -313.195124) (xy 432.29276 -313.195716)
			(xy 431.776886 -313.195716) (xy 431.769075 -313.196021) (xy 431.754204 -313.200813) (xy 431.747676 -313.205114)
			(xy 431.726556 -313.219465) (xy 431.680832 -313.242193) (xy 431.632158 -313.257622) (xy 431.581691 -313.265388)
			(xy 431.55616 -313.26582) (xy 431.530629 -313.265412) (xy 431.480163 -313.257628) (xy 431.431491 -313.242191)
			(xy 431.385765 -313.219466) (xy 431.364644 -313.205114) (xy 431.358123 -313.200804) (xy 431.343245 -313.196032)
			(xy 431.335434 -313.195716) (xy 430.81956 -313.195716) (xy 430.814294 -313.195233) (xy 430.806854 -313.187775)
			(xy 430.806352 -313.182508) (xy 424.76215 -313.182508) (xy 424.761791 -313.187681) (xy 424.754132 -313.19537)
			(xy 424.748706 -313.195716) (xy 424.232832 -313.195716) (xy 424.225023 -313.19604) (xy 424.210151 -313.200819)
			(xy 424.203622 -313.205114) (xy 424.182489 -313.219445) (xy 424.13677 -313.242177) (xy 424.0881 -313.257613)
			(xy 424.037636 -313.265384) (xy 424.012106 -313.26582) (xy 423.986575 -313.265388) (xy 423.936111 -313.257612)
			(xy 423.887438 -313.242182) (xy 423.841711 -313.219463) (xy 423.82059 -313.205114) (xy 423.814059 -313.200821)
			(xy 423.799189 -313.196039) (xy 423.79138 -313.195716) (xy 423.275506 -313.195716) (xy 423.270061 -313.195412)
			(xy 423.262372 -313.1877) (xy 423.262044 -313.182254) (xy 417.21786 -313.182254) (xy 417.217346 -313.187553)
			(xy 417.209939 -313.195127) (xy 417.204652 -313.195716) (xy 415.731452 -313.195716) (xy 415.726185 -313.195238)
			(xy 415.718746 -313.187776) (xy 415.718244 -313.182508) (xy 308.118239 -313.182508) (xy 308.117889 -313.187684)
			(xy 308.110223 -313.195373) (xy 308.104794 -313.195716) (xy 306.631594 -313.195716) (xy 306.626147 -313.19542)
			(xy 306.618459 -313.187702) (xy 306.618132 -313.182254) (xy 300.573948 -313.182254) (xy 300.573445 -313.187556)
			(xy 300.56603 -313.19513) (xy 300.56074 -313.195716) (xy 300.044866 -313.195716) (xy 300.037058 -313.196055)
			(xy 300.022187 -313.200824) (xy 300.015656 -313.205114) (xy 299.994541 -313.219474) (xy 299.948815 -313.242199)
			(xy 299.90014 -313.257627) (xy 299.849672 -313.265389) (xy 299.82414 -313.26582) (xy 299.79861 -313.265371)
			(xy 299.748146 -313.257601) (xy 299.699474 -313.242175) (xy 299.653746 -313.219461) (xy 299.632624 -313.205114)
			(xy 299.626086 -313.200834) (xy 299.611221 -313.196044) (xy 299.603414 -313.195716) (xy 299.08754 -313.195716)
			(xy 299.082215 -313.195347) (xy 299.074672 -313.187832) (xy 299.074332 -313.182508) (xy 293.030131 -313.182508)
			(xy 293.029789 -313.187686) (xy 293.022117 -313.195376) (xy 293.016686 -313.195716) (xy 292.500812 -313.195716)
			(xy 292.493002 -313.196032) (xy 292.478131 -313.200816) (xy 292.471602 -313.205114) (xy 292.450474 -313.219454)
			(xy 292.404753 -313.242184) (xy 292.356082 -313.257617) (xy 292.305617 -313.265386) (xy 292.280086 -313.26582)
			(xy 292.254555 -313.265398) (xy 292.20409 -313.257619) (xy 292.155418 -313.242186) (xy 292.109691 -313.219464)
			(xy 292.08857 -313.205114) (xy 292.082044 -313.200814) (xy 292.06717 -313.196036) (xy 292.05936 -313.195716)
			(xy 291.543486 -313.195716) (xy 291.538038 -313.195425) (xy 291.53035 -313.187703) (xy 291.530024 -313.182254)
			(xy 285.48584 -313.182254) (xy 285.485344 -313.187557) (xy 285.477924 -313.195132) (xy 285.472632 -313.195716)
			(xy 284.956758 -313.195716) (xy 284.94895 -313.196052) (xy 284.934078 -313.200822) (xy 284.927548 -313.205114)
			(xy 284.906435 -313.219477) (xy 284.860709 -313.242202) (xy 284.812033 -313.257628) (xy 284.761564 -313.26539)
			(xy 284.736032 -313.26582) (xy 284.710502 -313.265375) (xy 284.660038 -313.257603) (xy 284.611365 -313.242177)
			(xy 284.565638 -313.219461) (xy 284.544516 -313.205114) (xy 284.537979 -313.200831) (xy 284.523113 -313.196043)
			(xy 284.515306 -313.195716) (xy 283.999432 -313.195716) (xy 283.994106 -313.195352) (xy 283.986564 -313.187833)
			(xy 283.986224 -313.182508) (xy 277.942016 -313.182508) (xy 277.941544 -313.187557) (xy 277.934124 -313.195132)
			(xy 277.928832 -313.195716) (xy 277.412958 -313.195716) (xy 277.40515 -313.196052) (xy 277.390278 -313.200822)
			(xy 277.383748 -313.205114) (xy 277.362635 -313.219477) (xy 277.316909 -313.242202) (xy 277.268233 -313.257628)
			(xy 277.217764 -313.26539) (xy 277.192232 -313.26582) (xy 277.166702 -313.265375) (xy 277.116238 -313.257603)
			(xy 277.067565 -313.242177) (xy 277.021838 -313.219461) (xy 277.000716 -313.205114) (xy 276.994179 -313.200831)
			(xy 276.979313 -313.196043) (xy 276.971506 -313.195716) (xy 276.455632 -313.195716) (xy 276.450306 -313.195352)
			(xy 276.442764 -313.187833) (xy 276.442424 -313.182508) (xy 270.398224 -313.182508) (xy 270.397888 -313.187688)
			(xy 270.390211 -313.195378) (xy 270.384778 -313.195716) (xy 269.868904 -313.195716) (xy 269.861094 -313.196029)
			(xy 269.846222 -313.200815) (xy 269.839694 -313.205114) (xy 269.818569 -313.219458) (xy 269.772847 -313.242187)
			(xy 269.724174 -313.257619) (xy 269.673709 -313.265386) (xy 269.648178 -313.26582) (xy 269.622647 -313.265403)
			(xy 269.572182 -313.257622) (xy 269.523509 -313.242188) (xy 269.477783 -313.219465) (xy 269.456662 -313.205114)
			(xy 269.450137 -313.200811) (xy 269.435262 -313.196035) (xy 269.427452 -313.195716) (xy 268.911578 -313.195716)
			(xy 268.906129 -313.195431) (xy 268.898442 -313.187705) (xy 268.898116 -313.182254) (xy 206.997808 -313.182254)
			(xy 206.997808 -313.182508) (xy 206.997311 -313.187772) (xy 206.989864 -313.195214) (xy 206.9846 -313.195716)
			(xy 206.468726 -313.195716) (xy 206.46085 -313.195985) (xy 206.445846 -313.200782) (xy 206.439262 -313.205114)
			(xy 206.418183 -313.219503) (xy 206.372539 -313.242333) (xy 206.323933 -313.257892) (xy 206.273517 -313.265811)
			(xy 206.248 -313.266328) (xy 206.222479 -313.26585) (xy 206.172052 -313.257951) (xy 206.123441 -313.242388)
			(xy 206.077803 -313.21953) (xy 206.056738 -313.205114) (xy 206.050139 -313.200812) (xy 206.035145 -313.196017)
			(xy 206.027274 -313.195716) (xy 205.5114 -313.195716) (xy 205.506139 -313.195206) (xy 205.498697 -313.187768)
			(xy 205.498192 -313.182508) (xy 199.454008 -313.182508) (xy 199.453511 -313.187772) (xy 199.446064 -313.195214)
			(xy 199.4408 -313.195716) (xy 198.924926 -313.195716) (xy 198.91705 -313.195985) (xy 198.902046 -313.200782)
			(xy 198.895462 -313.205114) (xy 198.874383 -313.219503) (xy 198.828739 -313.242333) (xy 198.780133 -313.257892)
			(xy 198.729717 -313.265811) (xy 198.7042 -313.266328) (xy 198.678679 -313.26585) (xy 198.628252 -313.257951)
			(xy 198.579641 -313.242388) (xy 198.534003 -313.21953) (xy 198.512938 -313.205114) (xy 198.506339 -313.200812)
			(xy 198.491345 -313.196017) (xy 198.483474 -313.195716) (xy 197.9676 -313.195716) (xy 197.962339 -313.195206)
			(xy 197.954897 -313.187768) (xy 197.954392 -313.182508) (xy 191.910208 -313.182508) (xy 191.909711 -313.187772)
			(xy 191.902264 -313.195214) (xy 191.897 -313.195716) (xy 191.896492 -313.195716) (xy 191.380872 -313.195716)
			(xy 191.372998 -313.196005) (xy 191.357994 -313.200788) (xy 191.351408 -313.205114) (xy 191.330344 -313.219526)
			(xy 191.284695 -313.242351) (xy 191.236084 -313.257903) (xy 191.185664 -313.265815) (xy 191.160146 -313.266328)
			(xy 191.134626 -313.265827) (xy 191.0842 -313.257935) (xy 191.035589 -313.242378) (xy 190.98995 -313.219527)
			(xy 190.968884 -313.205114) (xy 190.962297 -313.200791) (xy 190.947294 -313.196009) (xy 190.93942 -313.195716)
			(xy 190.423546 -313.195716) (xy 190.418237 -313.195241) (xy 190.410661 -313.187807) (xy 190.410084 -313.182508)
			(xy 184.3659 -313.182508) (xy 184.36541 -313.187774) (xy 184.357958 -313.195216) (xy 184.352692 -313.195716)
			(xy 183.836818 -313.195716) (xy 183.828945 -313.196025) (xy 183.813942 -313.200795) (xy 183.807354 -313.205114)
			(xy 183.786277 -313.219506) (xy 183.740632 -313.242336) (xy 183.692026 -313.257893) (xy 183.641609 -313.265812)
			(xy 183.616092 -313.266328) (xy 183.590573 -313.265804) (xy 183.540148 -313.257919) (xy 183.491536 -313.242369)
			(xy 183.445896 -313.219524) (xy 183.42483 -313.205114) (xy 183.418233 -313.200809) (xy 183.403237 -313.196016)
			(xy 183.395366 -313.195716) (xy 182.879492 -313.195716) (xy 182.87423 -313.195211) (xy 182.866789 -313.18777)
			(xy 182.866284 -313.182508) (xy 176.8221 -313.182508) (xy 176.82161 -313.187774) (xy 176.814158 -313.195216)
			(xy 176.808892 -313.195716) (xy 176.808384 -313.195716) (xy 176.292764 -313.195716) (xy 176.284889 -313.196001)
			(xy 176.269886 -313.200787) (xy 176.2633 -313.205114) (xy 176.24221 -313.219487) (xy 176.19657 -313.24232)
			(xy 176.147968 -313.257884) (xy 176.097554 -313.265808) (xy 176.072038 -313.266328) (xy 176.046518 -313.265831)
			(xy 175.996092 -313.257938) (xy 175.94748 -313.24238) (xy 175.901841 -313.219528) (xy 175.880776 -313.205114)
			(xy 175.874191 -313.200788) (xy 175.859186 -313.196008) (xy 175.851312 -313.195716) (xy 175.335438 -313.195716)
			(xy 175.330128 -313.195246) (xy 175.322552 -313.187808) (xy 175.321976 -313.182508) (xy 169.277792 -313.182508)
			(xy 169.277477 -313.187845) (xy 169.269922 -313.195387) (xy 169.264584 -313.195716) (xy 167.791384 -313.195716)
			(xy 167.786121 -313.195217) (xy 167.77868 -313.187771) (xy 167.778176 -313.182508) (xy 60.178188 -313.182508)
			(xy 60.177877 -313.187846) (xy 60.170319 -313.195388) (xy 60.16498 -313.195716) (xy 60.164472 -313.195716)
			(xy 58.691526 -313.195716) (xy 58.686215 -313.195254) (xy 58.67864 -313.18781) (xy 58.678064 -313.182508)
			(xy 52.63388 -313.182508) (xy 52.633576 -313.187848) (xy 52.626013 -313.19539) (xy 52.620672 -313.195716)
			(xy 52.104798 -313.195716) (xy 52.096925 -313.196016) (xy 52.081921 -313.200792) (xy 52.075334 -313.205114)
			(xy 52.054263 -313.219515) (xy 52.008616 -313.242342) (xy 51.960008 -313.257898) (xy 51.909589 -313.265813)
			(xy 51.884072 -313.266328) (xy 51.858553 -313.265814) (xy 51.808127 -313.257926) (xy 51.759516 -313.242373)
			(xy 51.713876 -313.219526) (xy 51.69281 -313.205114) (xy 51.686217 -313.200801) (xy 51.671218 -313.196013)
			(xy 51.663346 -313.195716) (xy 51.147472 -313.195716) (xy 51.142208 -313.195225) (xy 51.134767 -313.187773)
			(xy 51.134264 -313.182508) (xy 45.09008 -313.182508) (xy 45.089776 -313.187848) (xy 45.082213 -313.19539)
			(xy 45.076872 -313.195716) (xy 45.076364 -313.195716) (xy 44.560744 -313.195716) (xy 44.552869 -313.195993)
			(xy 44.537865 -313.200785) (xy 44.53128 -313.205114) (xy 44.510196 -313.219495) (xy 44.464554 -313.242327)
			(xy 44.41595 -313.257888) (xy 44.365534 -313.26581) (xy 44.340018 -313.266328) (xy 44.314498 -313.265841)
			(xy 44.264071 -313.257945) (xy 44.215459 -313.242384) (xy 44.169821 -313.219529) (xy 44.148756 -313.205114)
			(xy 44.142175 -313.20078) (xy 44.127167 -313.196005) (xy 44.119292 -313.195716) (xy 43.603418 -313.195716)
			(xy 43.598106 -313.19526) (xy 43.590531 -313.187811) (xy 43.589956 -313.182508) (xy 37.545772 -313.182508)
			(xy 37.545475 -313.18785) (xy 37.537907 -313.195393) (xy 37.532564 -313.195716) (xy 37.01669 -313.195716)
			(xy 37.008816 -313.196012) (xy 36.993812 -313.200791) (xy 36.987226 -313.205114) (xy 36.966157 -313.219518)
			(xy 36.920509 -313.242345) (xy 36.871901 -313.257899) (xy 36.821481 -313.265814) (xy 36.795964 -313.266328)
			(xy 36.770445 -313.265818) (xy 36.720019 -313.257929) (xy 36.671407 -313.242375) (xy 36.625768 -313.219526)
			(xy 36.604702 -313.205114) (xy 36.598111 -313.200798) (xy 36.583111 -313.196012) (xy 36.575238 -313.195716)
			(xy 36.059364 -313.195716) (xy 36.054099 -313.19523) (xy 36.046659 -313.187774) (xy 36.046156 -313.182508)
			(xy 30.001972 -313.182508) (xy 30.001675 -313.18785) (xy 29.994107 -313.195393) (xy 29.988764 -313.195716)
			(xy 29.47289 -313.195716) (xy 29.465016 -313.196012) (xy 29.450012 -313.200791) (xy 29.443426 -313.205114)
			(xy 29.422357 -313.219518) (xy 29.376709 -313.242345) (xy 29.328101 -313.257899) (xy 29.277681 -313.265814)
			(xy 29.252164 -313.266328) (xy 29.226645 -313.265818) (xy 29.176219 -313.257929) (xy 29.127607 -313.242375)
			(xy 29.081968 -313.219526) (xy 29.060902 -313.205114) (xy 29.054311 -313.200798) (xy 29.039311 -313.196012)
			(xy 29.031438 -313.195716) (xy 28.515564 -313.195716) (xy 28.510299 -313.19523) (xy 28.502859 -313.187774)
			(xy 28.502356 -313.182508) (xy 22.458172 -313.182508) (xy 22.457875 -313.18785) (xy 22.450307 -313.195393)
			(xy 22.444964 -313.195716) (xy 22.444456 -313.195716) (xy 21.928836 -313.195716) (xy 21.92096 -313.195989)
			(xy 21.905957 -313.200784) (xy 21.899372 -313.205114) (xy 21.87829 -313.219499) (xy 21.832647 -313.24233)
			(xy 21.784042 -313.257889) (xy 21.733626 -313.26581) (xy 21.70811 -313.266328) (xy 21.68259 -313.265845)
			(xy 21.632163 -313.257948) (xy 21.583551 -313.242386) (xy 21.537913 -313.21953) (xy 21.516848 -313.205114)
			(xy 21.510269 -313.200777) (xy 21.495259 -313.196004) (xy 21.487384 -313.195716) (xy 20.97151 -313.195716)
			(xy 20.966197 -313.195265) (xy 20.958623 -313.187813) (xy 20.958048 -313.182508) (xy 2.509012 -313.182508)
			(xy 2.509012 -314.032392) (xy 16.85798 -314.032392) (xy 16.85798 -313.537854) (xy 16.858424 -313.532474)
			(xy 16.866059 -313.524889) (xy 16.871442 -313.524392) (xy 17.38757 -313.524392) (xy 17.395379 -313.524067)
			(xy 17.410251 -313.519289) (xy 17.41678 -313.514994) (xy 17.437869 -313.500645) (xy 17.48353 -313.477914)
			(xy 17.532136 -313.462455) (xy 17.582539 -313.454632) (xy 17.633545 -313.454632) (xy 17.683948 -313.462455)
			(xy 17.732554 -313.477914) (xy 17.778215 -313.500645) (xy 17.799304 -313.514994) (xy 17.805836 -313.519285)
			(xy 17.820706 -313.524068) (xy 17.828514 -313.524392) (xy 18.344642 -313.524392) (xy 18.35 -313.524918)
			(xy 18.357581 -313.532496) (xy 18.358104 -313.537854) (xy 18.358104 -314.032392) (xy 20.958048 -314.032392)
			(xy 20.958048 -313.537854) (xy 20.958521 -313.532482) (xy 20.966136 -313.524899) (xy 20.97151 -313.524392)
			(xy 21.487638 -313.524392) (xy 21.495446 -313.524053) (xy 21.510317 -313.519284) (xy 21.516848 -313.514994)
			(xy 21.537937 -313.500645) (xy 21.583598 -313.477914) (xy 21.632204 -313.462455) (xy 21.682607 -313.454632)
			(xy 21.733613 -313.454632) (xy 21.784016 -313.462455) (xy 21.832622 -313.477914) (xy 21.878283 -313.500645)
			(xy 21.899372 -313.514994) (xy 21.905911 -313.519273) (xy 21.920775 -313.524064) (xy 21.928582 -313.524392)
			(xy 22.44471 -313.524392) (xy 22.450064 -313.524939) (xy 22.457647 -313.532501) (xy 22.458172 -313.537854)
			(xy 22.458172 -314.032392) (xy 24.402288 -314.032392) (xy 24.402288 -313.537854) (xy 24.402765 -313.532545)
			(xy 24.410197 -313.524968) (xy 24.415496 -313.524392) (xy 24.931624 -313.524392) (xy 24.939435 -313.52409)
			(xy 24.954306 -313.519296) (xy 24.960834 -313.514994) (xy 24.981923 -313.500645) (xy 25.027584 -313.477914)
			(xy 25.07619 -313.462455) (xy 25.126593 -313.454632) (xy 25.177599 -313.454632) (xy 25.228002 -313.462455)
			(xy 25.276608 -313.477914) (xy 25.322269 -313.500645) (xy 25.343358 -313.514994) (xy 25.349878 -313.519306)
			(xy 25.364757 -313.524076) (xy 25.372568 -313.524392) (xy 25.888696 -313.524392) (xy 25.894028 -313.52473)
			(xy 25.901569 -313.532268) (xy 25.901904 -313.5376) (xy 25.901904 -313.538108) (xy 25.901904 -314.032392)
			(xy 28.502356 -314.032392) (xy 28.502356 -313.537854) (xy 28.502861 -313.532553) (xy 28.510274 -313.524977)
			(xy 28.515564 -313.524392) (xy 29.031692 -313.524392) (xy 29.039502 -313.524076) (xy 29.054373 -313.519292)
			(xy 29.060902 -313.514994) (xy 29.081991 -313.500645) (xy 29.127652 -313.477914) (xy 29.176258 -313.462455)
			(xy 29.226661 -313.454632) (xy 29.277667 -313.454632) (xy 29.32807 -313.462455) (xy 29.376676 -313.477914)
			(xy 29.422337 -313.500645) (xy 29.443426 -313.514994) (xy 29.449953 -313.519293) (xy 29.464826 -313.524072)
			(xy 29.472636 -313.524392) (xy 29.988764 -313.524392) (xy 29.994092 -313.524751) (xy 30.001635 -313.532273)
			(xy 30.001972 -313.5376) (xy 30.001972 -313.538108) (xy 30.001972 -314.032392) (xy 31.946088 -314.032392)
			(xy 31.946088 -313.537854) (xy 31.946565 -313.532545) (xy 31.953997 -313.524968) (xy 31.959296 -313.524392)
			(xy 32.475424 -313.524392) (xy 32.483235 -313.52409) (xy 32.498106 -313.519296) (xy 32.504634 -313.514994)
			(xy 32.525723 -313.500645) (xy 32.571384 -313.477914) (xy 32.61999 -313.462455) (xy 32.670393 -313.454632)
			(xy 32.721399 -313.454632) (xy 32.771802 -313.462455) (xy 32.820408 -313.477914) (xy 32.866069 -313.500645)
			(xy 32.887158 -313.514994) (xy 32.893678 -313.519306) (xy 32.908557 -313.524076) (xy 32.916368 -313.524392)
			(xy 33.432496 -313.524392) (xy 33.437828 -313.52473) (xy 33.445369 -313.532268) (xy 33.445704 -313.5376)
			(xy 33.445704 -313.538108) (xy 33.445704 -314.032392) (xy 36.046156 -314.032392) (xy 36.046156 -313.537854)
			(xy 36.046661 -313.532553) (xy 36.054074 -313.524977) (xy 36.059364 -313.524392) (xy 36.575492 -313.524392)
			(xy 36.583302 -313.524076) (xy 36.598173 -313.519292) (xy 36.604702 -313.514994) (xy 36.625791 -313.500645)
			(xy 36.671452 -313.477914) (xy 36.720058 -313.462455) (xy 36.770461 -313.454632) (xy 36.821467 -313.454632)
			(xy 36.87187 -313.462455) (xy 36.920476 -313.477914) (xy 36.966137 -313.500645) (xy 36.987226 -313.514994)
			(xy 36.993753 -313.519293) (xy 37.008626 -313.524072) (xy 37.016436 -313.524392) (xy 37.532564 -313.524392)
			(xy 37.537892 -313.524751) (xy 37.545435 -313.532273) (xy 37.545772 -313.5376) (xy 37.545772 -313.538108)
			(xy 37.545772 -314.032392) (xy 39.489888 -314.032392) (xy 39.489888 -313.537854) (xy 39.490415 -313.532497)
			(xy 39.497993 -313.524916) (xy 39.50335 -313.524392) (xy 40.019478 -313.524392) (xy 40.027287 -313.52407)
			(xy 40.042159 -313.51929) (xy 40.048688 -313.514994) (xy 40.069777 -313.500645) (xy 40.115438 -313.477914)
			(xy 40.164044 -313.462455) (xy 40.214447 -313.454632) (xy 40.265453 -313.454632) (xy 40.315856 -313.462455)
			(xy 40.364462 -313.477914) (xy 40.410123 -313.500645) (xy 40.431212 -313.514994) (xy 40.437742 -313.519288)
			(xy 40.452613 -313.524069) (xy 40.460422 -313.524392) (xy 40.97655 -313.524392) (xy 40.981909 -313.524913)
			(xy 40.989489 -313.532495) (xy 40.990012 -313.537854) (xy 40.990012 -314.032392) (xy 43.589956 -314.032392)
			(xy 43.589956 -313.537854) (xy 43.590422 -313.53248) (xy 43.598042 -313.524896) (xy 43.603418 -313.524392)
			(xy 44.119546 -313.524392) (xy 44.127354 -313.524057) (xy 44.142226 -313.519286) (xy 44.148756 -313.514994)
			(xy 44.169845 -313.500645) (xy 44.215506 -313.477914) (xy 44.264112 -313.462455) (xy 44.314515 -313.454632)
			(xy 44.365521 -313.454632) (xy 44.415924 -313.462455) (xy 44.46453 -313.477914) (xy 44.510191 -313.500645)
			(xy 44.53128 -313.514994) (xy 44.537817 -313.519276) (xy 44.552683 -313.524065) (xy 44.56049 -313.524392)
			(xy 45.076618 -313.524392) (xy 45.081973 -313.524934) (xy 45.089555 -313.5325) (xy 45.09008 -313.537854)
			(xy 45.09008 -314.032392) (xy 47.034196 -314.032392) (xy 47.034196 -313.537854) (xy 47.034754 -313.532566)
			(xy 47.042131 -313.524995) (xy 47.047404 -313.524392) (xy 47.563532 -313.524392) (xy 47.57134 -313.524051)
			(xy 47.586211 -313.519284) (xy 47.592742 -313.514994) (xy 47.613831 -313.500645) (xy 47.659492 -313.477914)
			(xy 47.708098 -313.462455) (xy 47.758501 -313.454632) (xy 47.809507 -313.454632) (xy 47.85991 -313.462455)
			(xy 47.908516 -313.477914) (xy 47.954177 -313.500645) (xy 47.975266 -313.514994) (xy 47.981806 -313.51927)
			(xy 47.99667 -313.524063) (xy 48.004476 -313.524392) (xy 48.520604 -313.524392) (xy 48.525867 -313.524892)
			(xy 48.53331 -313.532337) (xy 48.533812 -313.5376) (xy 48.533812 -313.538108) (xy 48.533812 -314.032392)
			(xy 51.134264 -314.032392) (xy 51.134264 -313.537854) (xy 51.134762 -313.532551) (xy 51.14218 -313.524975)
			(xy 51.147472 -313.524392) (xy 51.6636 -313.524392) (xy 51.67141 -313.52408) (xy 51.686282 -313.519293)
			(xy 51.69281 -313.514994) (xy 51.713899 -313.500645) (xy 51.75956 -313.477914) (xy 51.808166 -313.462455)
			(xy 51.858569 -313.454632) (xy 51.909575 -313.454632) (xy 51.959978 -313.462455) (xy 52.008584 -313.477914)
			(xy 52.054245 -313.500645) (xy 52.075334 -313.514994) (xy 52.081859 -313.519297) (xy 52.096734 -313.524073)
			(xy 52.104544 -313.524392) (xy 52.620672 -313.524392) (xy 52.626001 -313.524745) (xy 52.633543 -313.532272)
			(xy 52.63388 -313.5376) (xy 52.63388 -313.538108) (xy 52.63388 -314.032392) (xy 54.577996 -314.032392)
			(xy 54.577996 -313.537854) (xy 54.578516 -313.532495) (xy 54.586098 -313.524914) (xy 54.591458 -313.524392)
			(xy 56.064658 -313.524392) (xy 56.070006 -313.524974) (xy 56.077591 -313.53251) (xy 56.07812 -313.537854)
			(xy 56.07812 -314.032392) (xy 58.678064 -314.032392) (xy 58.678064 -313.537854) (xy 58.678523 -313.532478)
			(xy 58.686148 -313.524894) (xy 58.691526 -313.524392) (xy 60.164726 -313.524392) (xy 60.170082 -313.524929)
			(xy 60.177663 -313.532499) (xy 60.178188 -313.537854) (xy 60.178188 -314.032392) (xy 60.177866 -314.037728)
			(xy 60.170316 -314.045271) (xy 60.16498 -314.0456) (xy 60.164472 -314.0456) (xy 58.691526 -314.0456)
			(xy 58.686234 -314.045064) (xy 58.678664 -314.037671) (xy 58.678064 -314.032392) (xy 56.07812 -314.032392)
			(xy 56.077601 -314.037651) (xy 56.07017 -314.045093) (xy 56.064912 -314.0456) (xy 54.591458 -314.0456)
			(xy 54.586158 -314.04511) (xy 54.578592 -314.037682) (xy 54.577996 -314.032392) (xy 52.63388 -314.032392)
			(xy 52.633565 -314.03773) (xy 52.626011 -314.045273) (xy 52.620672 -314.0456) (xy 52.104798 -314.0456)
			(xy 52.096925 -314.045903) (xy 52.081921 -314.050677) (xy 52.075334 -314.054998) (xy 52.054261 -314.069397)
			(xy 52.008615 -314.092225) (xy 51.960008 -314.107781) (xy 51.909589 -314.115697) (xy 51.884072 -314.116212)
			(xy 51.858553 -314.115701) (xy 51.808127 -314.107813) (xy 51.759515 -314.092259) (xy 51.713876 -314.06941)
			(xy 51.69281 -314.054998) (xy 51.686218 -314.050684) (xy 51.671218 -314.045897) (xy 51.663346 -314.0456)
			(xy 51.147472 -314.0456) (xy 51.142204 -314.045123) (xy 51.134762 -314.037661) (xy 51.134264 -314.032392)
			(xy 48.533812 -314.032392) (xy 48.533468 -314.037722) (xy 48.525934 -314.045263) (xy 48.520604 -314.0456)
			(xy 48.00473 -314.0456) (xy 47.996854 -314.045874) (xy 47.981851 -314.050668) (xy 47.975266 -314.054998)
			(xy 47.954184 -314.069383) (xy 47.908542 -314.092215) (xy 47.859937 -314.107774) (xy 47.80952 -314.115695)
			(xy 47.784004 -314.116212) (xy 47.758483 -314.115735) (xy 47.708056 -314.107836) (xy 47.659444 -314.092273)
			(xy 47.613807 -314.069415) (xy 47.592742 -314.054998) (xy 47.586165 -314.050657) (xy 47.571154 -314.045887)
			(xy 47.563278 -314.0456) (xy 47.047404 -314.0456) (xy 47.04207 -314.04527) (xy 47.034529 -314.037726)
			(xy 47.034196 -314.032392) (xy 45.09008 -314.032392) (xy 45.089765 -314.03773) (xy 45.082211 -314.045273)
			(xy 45.076872 -314.0456) (xy 45.076364 -314.0456) (xy 44.560744 -314.0456) (xy 44.552869 -314.04588)
			(xy 44.537865 -314.05067) (xy 44.53128 -314.054998) (xy 44.510195 -314.069377) (xy 44.464553 -314.09221)
			(xy 44.415949 -314.107771) (xy 44.365534 -314.115694) (xy 44.340018 -314.116212) (xy 44.314498 -314.115728)
			(xy 44.264071 -314.107832) (xy 44.215459 -314.09227) (xy 44.169821 -314.069414) (xy 44.148756 -314.054998)
			(xy 44.142176 -314.050663) (xy 44.127167 -314.045889) (xy 44.119292 -314.0456) (xy 43.603418 -314.0456)
			(xy 43.598125 -314.04507) (xy 43.590555 -314.037672) (xy 43.589956 -314.032392) (xy 40.990012 -314.032392)
			(xy 40.989668 -314.037722) (xy 40.982134 -314.045263) (xy 40.976804 -314.0456) (xy 40.976296 -314.0456)
			(xy 40.460676 -314.0456) (xy 40.452802 -314.045893) (xy 40.437798 -314.050674) (xy 40.431212 -314.054998)
			(xy 40.410146 -314.069407) (xy 40.364497 -314.092232) (xy 40.315888 -314.107786) (xy 40.265468 -314.115699)
			(xy 40.23995 -314.116212) (xy 40.21443 -314.115712) (xy 40.164004 -314.10782) (xy 40.115392 -314.092263)
			(xy 40.069753 -314.069412) (xy 40.048688 -314.054998) (xy 40.042101 -314.050675) (xy 40.027097 -314.045893)
			(xy 40.019224 -314.0456) (xy 39.50335 -314.0456) (xy 39.498061 -314.045048) (xy 39.49049 -314.037667)
			(xy 39.489888 -314.032392) (xy 37.545772 -314.032392) (xy 37.545464 -314.037732) (xy 37.537905 -314.045276)
			(xy 37.532564 -314.0456) (xy 37.01669 -314.0456) (xy 37.008817 -314.045899) (xy 36.993813 -314.050676)
			(xy 36.987226 -314.054998) (xy 36.966156 -314.069401) (xy 36.920509 -314.092228) (xy 36.8719 -314.107783)
			(xy 36.821481 -314.115698) (xy 36.795964 -314.116212) (xy 36.770445 -314.115705) (xy 36.720018 -314.107815)
			(xy 36.671407 -314.09226) (xy 36.625768 -314.069411) (xy 36.604702 -314.054998) (xy 36.598112 -314.050681)
			(xy 36.583111 -314.045895) (xy 36.575238 -314.0456) (xy 36.059364 -314.0456) (xy 36.054095 -314.045128)
			(xy 36.046654 -314.037663) (xy 36.046156 -314.032392) (xy 33.445704 -314.032392) (xy 33.445368 -314.037724)
			(xy 33.437828 -314.045266) (xy 33.432496 -314.0456) (xy 32.916622 -314.0456) (xy 32.90875 -314.045913)
			(xy 32.893746 -314.05068) (xy 32.887158 -314.054998) (xy 32.866079 -314.069387) (xy 32.820435 -314.092217)
			(xy 32.771829 -314.107776) (xy 32.721413 -314.115695) (xy 32.695896 -314.116212) (xy 32.670375 -314.115739)
			(xy 32.619948 -314.107839) (xy 32.571336 -314.092274) (xy 32.525698 -314.069415) (xy 32.504634 -314.054998)
			(xy 32.498037 -314.050693) (xy 32.483041 -314.0459) (xy 32.47517 -314.0456) (xy 31.959296 -314.0456)
			(xy 31.953961 -314.045275) (xy 31.94642 -314.037727) (xy 31.946088 -314.032392) (xy 30.001972 -314.032392)
			(xy 30.001664 -314.037732) (xy 29.994105 -314.045276) (xy 29.988764 -314.0456) (xy 29.47289 -314.0456)
			(xy 29.465017 -314.045899) (xy 29.450013 -314.050676) (xy 29.443426 -314.054998) (xy 29.422356 -314.069401)
			(xy 29.376709 -314.092228) (xy 29.3281 -314.107783) (xy 29.277681 -314.115698) (xy 29.252164 -314.116212)
			(xy 29.226645 -314.115705) (xy 29.176218 -314.107815) (xy 29.127607 -314.09226) (xy 29.081968 -314.069411)
			(xy 29.060902 -314.054998) (xy 29.054312 -314.050681) (xy 29.039311 -314.045895) (xy 29.031438 -314.0456)
			(xy 28.515564 -314.0456) (xy 28.510295 -314.045128) (xy 28.502854 -314.037663) (xy 28.502356 -314.032392)
			(xy 25.901904 -314.032392) (xy 25.901568 -314.037724) (xy 25.894028 -314.045266) (xy 25.888696 -314.0456)
			(xy 25.372822 -314.0456) (xy 25.36495 -314.045913) (xy 25.349946 -314.05068) (xy 25.343358 -314.054998)
			(xy 25.322279 -314.069387) (xy 25.276635 -314.092217) (xy 25.228029 -314.107776) (xy 25.177613 -314.115695)
			(xy 25.152096 -314.116212) (xy 25.126575 -314.115739) (xy 25.076148 -314.107839) (xy 25.027536 -314.092274)
			(xy 24.981898 -314.069415) (xy 24.960834 -314.054998) (xy 24.954237 -314.050693) (xy 24.939241 -314.0459)
			(xy 24.93137 -314.0456) (xy 24.415496 -314.0456) (xy 24.410161 -314.045275) (xy 24.40262 -314.037727)
			(xy 24.402288 -314.032392) (xy 22.458172 -314.032392) (xy 22.457864 -314.037732) (xy 22.450305 -314.045276)
			(xy 22.444964 -314.0456) (xy 22.444456 -314.0456) (xy 21.928836 -314.0456) (xy 21.920961 -314.045876)
			(xy 21.905957 -314.050669) (xy 21.899372 -314.054998) (xy 21.878289 -314.069381) (xy 21.832646 -314.092213)
			(xy 21.784042 -314.107773) (xy 21.733626 -314.115694) (xy 21.70811 -314.116212) (xy 21.682589 -314.115732)
			(xy 21.632162 -314.107834) (xy 21.583551 -314.092271) (xy 21.537913 -314.069414) (xy 21.516848 -314.054998)
			(xy 21.51027 -314.05066) (xy 21.49526 -314.045887) (xy 21.487384 -314.0456) (xy 20.97151 -314.0456)
			(xy 20.966216 -314.045075) (xy 20.958647 -314.037674) (xy 20.958048 -314.032392) (xy 18.358104 -314.032392)
			(xy 18.357768 -314.037724) (xy 18.350228 -314.045266) (xy 18.344896 -314.0456) (xy 18.344388 -314.0456)
			(xy 17.828768 -314.0456) (xy 17.820894 -314.04589) (xy 17.80589 -314.050673) (xy 17.799304 -314.054998)
			(xy 17.778212 -314.069367) (xy 17.732573 -314.092202) (xy 17.683971 -314.107766) (xy 17.633557 -314.115692)
			(xy 17.608042 -314.116212) (xy 17.582522 -314.115716) (xy 17.532096 -314.107823) (xy 17.483484 -314.092265)
			(xy 17.437845 -314.069412) (xy 17.41678 -314.054998) (xy 17.410195 -314.050672) (xy 17.39519 -314.045892)
			(xy 17.387316 -314.0456) (xy 16.871442 -314.0456) (xy 16.866152 -314.045053) (xy 16.858581 -314.037668)
			(xy 16.85798 -314.032392) (xy 2.509012 -314.032392) (xy 2.509012 -314.88253) (xy 16.85798 -314.88253)
			(xy 16.85798 -314.387992) (xy 16.858488 -314.382731) (xy 16.865927 -314.37529) (xy 16.871188 -314.374784)
			(xy 16.871696 -314.374784) (xy 17.38757 -314.374784) (xy 17.395379 -314.37446) (xy 17.410251 -314.369682)
			(xy 17.41678 -314.365386) (xy 17.437869 -314.351037) (xy 17.48353 -314.328306) (xy 17.532136 -314.312847)
			(xy 17.582539 -314.305024) (xy 17.633545 -314.305024) (xy 17.683948 -314.312847) (xy 17.732554 -314.328306)
			(xy 17.778215 -314.351037) (xy 17.799304 -314.365386) (xy 17.805836 -314.369676) (xy 17.820706 -314.37446)
			(xy 17.828514 -314.374784) (xy 18.344642 -314.374784) (xy 18.349962 -314.3752) (xy 18.357533 -314.382679)
			(xy 18.358104 -314.387992) (xy 18.358104 -314.88253) (xy 18.358079 -314.882784) (xy 24.402288 -314.882784)
			(xy 24.402288 -314.882276) (xy 24.402288 -314.387992) (xy 24.402789 -314.382729) (xy 24.410233 -314.375287)
			(xy 24.415496 -314.374784) (xy 24.931624 -314.374784) (xy 24.939435 -314.374483) (xy 24.954307 -314.369689)
			(xy 24.960834 -314.365386) (xy 24.981923 -314.351037) (xy 25.027584 -314.328306) (xy 25.07619 -314.312847)
			(xy 25.126593 -314.305024) (xy 25.177599 -314.305024) (xy 25.228002 -314.312847) (xy 25.276608 -314.328306)
			(xy 25.322269 -314.351037) (xy 25.343358 -314.365386) (xy 25.349878 -314.369697) (xy 25.364757 -314.374468)
			(xy 25.372568 -314.374784) (xy 25.888696 -314.374784) (xy 25.893956 -314.375297) (xy 25.901399 -314.382732)
			(xy 25.901904 -314.387992) (xy 25.901904 -314.88253) (xy 25.90188 -314.882784) (xy 31.946088 -314.882784)
			(xy 31.946088 -314.882276) (xy 31.946088 -314.387992) (xy 31.946589 -314.382729) (xy 31.954033 -314.375287)
			(xy 31.959296 -314.374784) (xy 32.475424 -314.374784) (xy 32.483235 -314.374483) (xy 32.498107 -314.369689)
			(xy 32.504634 -314.365386) (xy 32.525723 -314.351037) (xy 32.571384 -314.328306) (xy 32.61999 -314.312847)
			(xy 32.670393 -314.305024) (xy 32.721399 -314.305024) (xy 32.771802 -314.312847) (xy 32.820408 -314.328306)
			(xy 32.866069 -314.351037) (xy 32.887158 -314.365386) (xy 32.893678 -314.369697) (xy 32.908557 -314.374468)
			(xy 32.916368 -314.374784) (xy 33.432496 -314.374784) (xy 33.437756 -314.375297) (xy 33.445199 -314.382732)
			(xy 33.445704 -314.387992) (xy 33.445704 -314.88253) (xy 39.489888 -314.88253) (xy 39.489888 -314.387992)
			(xy 39.490389 -314.382729) (xy 39.497833 -314.375287) (xy 39.503096 -314.374784) (xy 39.503604 -314.374784)
			(xy 40.019478 -314.374784) (xy 40.027288 -314.374464) (xy 40.042159 -314.369683) (xy 40.048688 -314.365386)
			(xy 40.069777 -314.351037) (xy 40.115438 -314.328306) (xy 40.164044 -314.312847) (xy 40.214447 -314.305024)
			(xy 40.265453 -314.305024) (xy 40.315856 -314.312847) (xy 40.364462 -314.328306) (xy 40.410123 -314.351037)
			(xy 40.431212 -314.365386) (xy 40.437742 -314.369679) (xy 40.452613 -314.374461) (xy 40.460422 -314.374784)
			(xy 40.97655 -314.374784) (xy 40.981858 -314.375262) (xy 40.989435 -314.382694) (xy 40.990012 -314.387992)
			(xy 40.990012 -314.88253) (xy 40.989987 -314.882784) (xy 47.034196 -314.882784) (xy 47.034196 -314.882276)
			(xy 47.034196 -314.387992) (xy 47.03469 -314.382727) (xy 47.042139 -314.375285) (xy 47.047404 -314.374784)
			(xy 47.563532 -314.374784) (xy 47.57134 -314.374444) (xy 47.586211 -314.369676) (xy 47.592742 -314.365386)
			(xy 47.613831 -314.351037) (xy 47.659492 -314.328306) (xy 47.708098 -314.312847) (xy 47.758501 -314.305024)
			(xy 47.809507 -314.305024) (xy 47.85991 -314.312847) (xy 47.908516 -314.328306) (xy 47.954177 -314.351037)
			(xy 47.975266 -314.365386) (xy 47.981807 -314.369662) (xy 47.99667 -314.374455) (xy 48.004476 -314.374784)
			(xy 48.520604 -314.374784) (xy 48.525865 -314.375291) (xy 48.533307 -314.382731) (xy 48.533812 -314.387992)
			(xy 48.533812 -314.88253) (xy 54.577996 -314.88253) (xy 54.577996 -314.387992) (xy 54.57849 -314.382727)
			(xy 54.585939 -314.375285) (xy 54.591204 -314.374784) (xy 56.064658 -314.374784) (xy 56.069967 -314.375256)
			(xy 56.077544 -314.382692) (xy 56.07812 -314.387992) (xy 56.07812 -314.88253) (xy 56.077837 -314.887979)
			(xy 56.070109 -314.895666) (xy 56.064658 -314.895992) (xy 54.591458 -314.895992) (xy 54.586096 -314.895481)
			(xy 54.578515 -314.887892) (xy 54.577996 -314.88253) (xy 48.533812 -314.88253) (xy 48.533391 -314.887849)
			(xy 48.525916 -314.895421) (xy 48.520604 -314.895992) (xy 48.00473 -314.895992) (xy 47.996921 -314.89632)
			(xy 47.98205 -314.901096) (xy 47.97552 -314.90539) (xy 47.954393 -314.919731) (xy 47.908671 -314.942459)
			(xy 47.859999 -314.957891) (xy 47.809534 -314.965661) (xy 47.784004 -314.966096) (xy 47.758474 -314.965652)
			(xy 47.708011 -314.957877) (xy 47.659339 -314.94245) (xy 47.61361 -314.919736) (xy 47.592488 -314.90539)
			(xy 47.585959 -314.901094) (xy 47.571087 -314.896314) (xy 47.563278 -314.895992) (xy 47.047404 -314.895992)
			(xy 47.042068 -314.895669) (xy 47.034526 -314.88812) (xy 47.034196 -314.882784) (xy 40.989987 -314.882784)
			(xy 40.989475 -314.887886) (xy 40.981905 -314.895467) (xy 40.97655 -314.895992) (xy 40.460676 -314.895992)
			(xy 40.452865 -314.896297) (xy 40.437994 -314.901089) (xy 40.431466 -314.90539) (xy 40.410354 -314.919755)
			(xy 40.364627 -314.942477) (xy 40.31595 -314.957902) (xy 40.265482 -314.965665) (xy 40.23995 -314.966096)
			(xy 40.214421 -314.965629) (xy 40.163959 -314.957861) (xy 40.115286 -314.942441) (xy 40.069557 -314.919733)
			(xy 40.048434 -314.90539) (xy 40.041895 -314.901112) (xy 40.027031 -314.896321) (xy 40.019224 -314.895992)
			(xy 39.50335 -314.895992) (xy 39.497987 -314.895486) (xy 39.490406 -314.887893) (xy 39.489888 -314.88253)
			(xy 33.445704 -314.88253) (xy 33.445202 -314.887828) (xy 33.437783 -314.895395) (xy 33.432496 -314.895992)
			(xy 32.916622 -314.895992) (xy 32.908813 -314.896316) (xy 32.893942 -314.901095) (xy 32.887412 -314.90539)
			(xy 32.866288 -314.919735) (xy 32.820564 -314.942461) (xy 32.771892 -314.957892) (xy 32.721427 -314.965661)
			(xy 32.695896 -314.966096) (xy 32.670366 -314.965656) (xy 32.619903 -314.95788) (xy 32.57123 -314.942452)
			(xy 32.525502 -314.919737) (xy 32.50438 -314.90539) (xy 32.497853 -314.901091) (xy 32.482979 -314.896313)
			(xy 32.47517 -314.895992) (xy 31.959296 -314.895992) (xy 31.953959 -314.895674) (xy 31.946418 -314.888121)
			(xy 31.946088 -314.882784) (xy 25.90188 -314.882784) (xy 25.901402 -314.887828) (xy 25.893983 -314.895395)
			(xy 25.888696 -314.895992) (xy 25.372822 -314.895992) (xy 25.365013 -314.896316) (xy 25.350142 -314.901095)
			(xy 25.343612 -314.90539) (xy 25.322488 -314.919735) (xy 25.276764 -314.942461) (xy 25.228092 -314.957892)
			(xy 25.177627 -314.965661) (xy 25.152096 -314.966096) (xy 25.126566 -314.965656) (xy 25.076103 -314.95788)
			(xy 25.02743 -314.942452) (xy 24.981702 -314.919737) (xy 24.96058 -314.90539) (xy 24.954053 -314.901091)
			(xy 24.939179 -314.896313) (xy 24.93137 -314.895992) (xy 24.415496 -314.895992) (xy 24.410159 -314.895674)
			(xy 24.402618 -314.888121) (xy 24.402288 -314.882784) (xy 18.358079 -314.882784) (xy 18.357574 -314.887887)
			(xy 18.349999 -314.895469) (xy 18.344642 -314.895992) (xy 17.828768 -314.895992) (xy 17.820961 -314.896336)
			(xy 17.806089 -314.901101) (xy 17.799558 -314.90539) (xy 17.778449 -314.919758) (xy 17.73272 -314.942479)
			(xy 17.684043 -314.957904) (xy 17.633574 -314.965665) (xy 17.608042 -314.966096) (xy 17.582513 -314.965633)
			(xy 17.53205 -314.957864) (xy 17.483378 -314.942442) (xy 17.437649 -314.919734) (xy 17.416526 -314.90539)
			(xy 17.409989 -314.901109) (xy 17.395123 -314.89632) (xy 17.387316 -314.895992) (xy 16.871442 -314.895992)
			(xy 16.86602 -314.895595) (xy 16.858333 -314.88795) (xy 16.85798 -314.88253) (xy 2.509012 -314.88253)
			(xy 2.509012 -314.997338) (xy 98.330512 -314.997338) (xy 98.330512 -314.133738) (xy 98.330998 -314.106487)
			(xy 98.338754 -314.052539) (xy 98.354109 -314.000244) (xy 98.376751 -313.950667) (xy 98.406217 -313.904817)
			(xy 98.441908 -313.863626) (xy 98.483099 -313.827935) (xy 98.528949 -313.798469) (xy 98.578526 -313.775827)
			(xy 98.630821 -313.760472) (xy 98.684769 -313.752716) (xy 98.739271 -313.752716) (xy 98.793219 -313.760472)
			(xy 98.845514 -313.775827) (xy 98.895091 -313.798469) (xy 98.940941 -313.827935) (xy 98.982132 -313.863626)
			(xy 99.017823 -313.904817) (xy 99.047289 -313.950667) (xy 99.069931 -314.000244) (xy 99.07937 -314.032392)
			(xy 163.678108 -314.032392) (xy 163.678108 -313.537854) (xy 163.678656 -313.532564) (xy 163.686039 -313.524991)
			(xy 163.691316 -313.524392) (xy 165.164516 -313.524392) (xy 165.169781 -313.524884) (xy 165.177222 -313.532335)
			(xy 165.177724 -313.5376) (xy 165.177724 -313.538108) (xy 165.177724 -314.032392) (xy 167.778176 -314.032392)
			(xy 167.778176 -313.537854) (xy 167.778663 -313.532548) (xy 167.786089 -313.524972) (xy 167.791384 -313.524392)
			(xy 169.264584 -313.524392) (xy 169.269914 -313.524738) (xy 169.277456 -313.53227) (xy 169.277792 -313.5376)
			(xy 169.277792 -314.032392) (xy 171.221908 -314.032392) (xy 171.221908 -313.537854) (xy 171.222417 -313.532492)
			(xy 171.230007 -313.52491) (xy 171.23537 -313.524392) (xy 171.751498 -313.524392) (xy 171.759308 -313.524079)
			(xy 171.77418 -313.519293) (xy 171.780708 -313.514994) (xy 171.801797 -313.500645) (xy 171.847458 -313.477914)
			(xy 171.896064 -313.462455) (xy 171.946467 -313.454632) (xy 171.997473 -313.454632) (xy 172.047876 -313.462455)
			(xy 172.096482 -313.477914) (xy 172.142143 -313.500645) (xy 172.163232 -313.514994) (xy 172.169757 -313.519296)
			(xy 172.184632 -313.524072) (xy 172.192442 -313.524392) (xy 172.70857 -313.524392) (xy 172.713919 -313.524966)
			(xy 172.721504 -313.532508) (xy 172.722032 -313.537854) (xy 172.722032 -314.032392) (xy 175.321976 -314.032392)
			(xy 175.321976 -313.537854) (xy 175.322424 -313.532475) (xy 175.330056 -313.52489) (xy 175.335438 -313.524392)
			(xy 175.851566 -313.524392) (xy 175.859375 -313.524065) (xy 175.874246 -313.519288) (xy 175.880776 -313.514994)
			(xy 175.901865 -313.500645) (xy 175.947526 -313.477914) (xy 175.996132 -313.462455) (xy 176.046535 -313.454632)
			(xy 176.097541 -313.454632) (xy 176.147944 -313.462455) (xy 176.19655 -313.477914) (xy 176.242211 -313.500645)
			(xy 176.2633 -313.514994) (xy 176.269833 -313.519284) (xy 176.284702 -313.524068) (xy 176.29251 -313.524392)
			(xy 176.808638 -313.524392) (xy 176.813995 -313.524921) (xy 176.821576 -313.532497) (xy 176.8221 -313.537854)
			(xy 176.8221 -314.032392) (xy 178.766216 -314.032392) (xy 178.766216 -313.537854) (xy 178.766756 -313.532562)
			(xy 178.774145 -313.524989) (xy 178.779424 -313.524392) (xy 179.295552 -313.524392) (xy 179.30336 -313.524059)
			(xy 179.318232 -313.519287) (xy 179.324762 -313.514994) (xy 179.345851 -313.500645) (xy 179.391512 -313.477914)
			(xy 179.440118 -313.462455) (xy 179.490521 -313.454632) (xy 179.541527 -313.454632) (xy 179.59193 -313.462455)
			(xy 179.640536 -313.477914) (xy 179.686197 -313.500645) (xy 179.707286 -313.514994) (xy 179.713822 -313.519278)
			(xy 179.728688 -313.524066) (xy 179.736496 -313.524392) (xy 180.252624 -313.524392) (xy 180.25789 -313.524879)
			(xy 180.265331 -313.532334) (xy 180.265832 -313.5376) (xy 180.265832 -313.538108) (xy 180.265832 -314.032392)
			(xy 182.866284 -314.032392) (xy 182.866284 -313.537854) (xy 182.866764 -313.532546) (xy 182.874194 -313.524969)
			(xy 182.879492 -313.524392) (xy 183.39562 -313.524392) (xy 183.403431 -313.524088) (xy 183.418302 -313.519295)
			(xy 183.42483 -313.514994) (xy 183.445919 -313.500645) (xy 183.49158 -313.477914) (xy 183.540186 -313.462455)
			(xy 183.590589 -313.454632) (xy 183.641595 -313.454632) (xy 183.691998 -313.462455) (xy 183.740604 -313.477914)
			(xy 183.786265 -313.500645) (xy 183.807354 -313.514994) (xy 183.813875 -313.519304) (xy 183.828753 -313.524076)
			(xy 183.836564 -313.524392) (xy 184.352692 -313.524392) (xy 184.358023 -313.524732) (xy 184.365565 -313.532269)
			(xy 184.3659 -313.5376) (xy 184.3659 -313.538108) (xy 184.3659 -314.032392) (xy 186.310016 -314.032392)
			(xy 186.310016 -313.537854) (xy 186.310518 -313.53249) (xy 186.318113 -313.524908) (xy 186.323478 -313.524392)
			(xy 186.839606 -313.524392) (xy 186.847416 -313.524082) (xy 186.862288 -313.519294) (xy 186.868816 -313.514994)
			(xy 186.889905 -313.500645) (xy 186.935566 -313.477914) (xy 186.984172 -313.462455) (xy 187.034575 -313.454632)
			(xy 187.085581 -313.454632) (xy 187.135984 -313.462455) (xy 187.18459 -313.477914) (xy 187.230251 -313.500645)
			(xy 187.25134 -313.514994) (xy 187.257864 -313.519299) (xy 187.27274 -313.524074) (xy 187.28055 -313.524392)
			(xy 187.796678 -313.524392) (xy 187.802028 -313.524961) (xy 187.809612 -313.532506) (xy 187.81014 -313.537854)
			(xy 187.81014 -314.032392) (xy 190.410084 -314.032392) (xy 190.410084 -313.537854) (xy 190.410525 -313.532473)
			(xy 190.418162 -313.524888) (xy 190.423546 -313.524392) (xy 190.939674 -313.524392) (xy 190.947483 -313.524069)
			(xy 190.962355 -313.51929) (xy 190.968884 -313.514994) (xy 190.989973 -313.500645) (xy 191.035634 -313.477914)
			(xy 191.08424 -313.462455) (xy 191.134643 -313.454632) (xy 191.185649 -313.454632) (xy 191.236052 -313.462455)
			(xy 191.284658 -313.477914) (xy 191.330319 -313.500645) (xy 191.351408 -313.514994) (xy 191.357939 -313.519287)
			(xy 191.372809 -313.524069) (xy 191.380618 -313.524392) (xy 191.896746 -313.524392) (xy 191.902104 -313.524915)
			(xy 191.909685 -313.532496) (xy 191.910208 -313.537854) (xy 191.910208 -314.032392) (xy 193.854324 -314.032392)
			(xy 193.854324 -313.537854) (xy 193.854857 -313.53256) (xy 193.862251 -313.524987) (xy 193.867532 -313.524392)
			(xy 194.38366 -313.524392) (xy 194.391469 -313.524063) (xy 194.40634 -313.519288) (xy 194.41287 -313.514994)
			(xy 194.433959 -313.500645) (xy 194.47962 -313.477914) (xy 194.528226 -313.462455) (xy 194.578629 -313.454632)
			(xy 194.629635 -313.454632) (xy 194.680038 -313.462455) (xy 194.728644 -313.477914) (xy 194.774305 -313.500645)
			(xy 194.795394 -313.514994) (xy 194.801928 -313.519281) (xy 194.816796 -313.524067) (xy 194.824604 -313.524392)
			(xy 195.340732 -313.524392) (xy 195.345999 -313.524873) (xy 195.353439 -313.532332) (xy 195.35394 -313.5376)
			(xy 195.35394 -313.538108) (xy 195.35394 -314.032392) (xy 197.954392 -314.032392) (xy 197.954392 -313.537854)
			(xy 197.954954 -313.532567) (xy 197.962328 -313.524996) (xy 197.9676 -313.524392) (xy 198.483728 -313.524392)
			(xy 198.491539 -313.524092) (xy 198.506411 -313.519297) (xy 198.512938 -313.514994) (xy 198.534027 -313.500645)
			(xy 198.579688 -313.477914) (xy 198.628294 -313.462455) (xy 198.678697 -313.454632) (xy 198.729703 -313.454632)
			(xy 198.780106 -313.462455) (xy 198.828712 -313.477914) (xy 198.874373 -313.500645) (xy 198.895462 -313.514994)
			(xy 198.902003 -313.519269) (xy 198.916866 -313.524062) (xy 198.924672 -313.524392) (xy 199.4408 -313.524392)
			(xy 199.446063 -313.524895) (xy 199.453505 -313.532337) (xy 199.454008 -313.5376) (xy 199.454008 -313.538108)
			(xy 199.454008 -314.032392) (xy 201.398124 -314.032392) (xy 201.398124 -313.537854) (xy 201.398657 -313.53256)
			(xy 201.406051 -313.524987) (xy 201.411332 -313.524392) (xy 201.92746 -313.524392) (xy 201.935269 -313.524063)
			(xy 201.95014 -313.519288) (xy 201.95667 -313.514994) (xy 201.977759 -313.500645) (xy 202.02342 -313.477914)
			(xy 202.072026 -313.462455) (xy 202.122429 -313.454632) (xy 202.173435 -313.454632) (xy 202.223838 -313.462455)
			(xy 202.272444 -313.477914) (xy 202.318105 -313.500645) (xy 202.339194 -313.514994) (xy 202.345728 -313.519281)
			(xy 202.360596 -313.524067) (xy 202.368404 -313.524392) (xy 202.884532 -313.524392) (xy 202.889799 -313.524873)
			(xy 202.897239 -313.532332) (xy 202.89774 -313.5376) (xy 202.89774 -313.538108) (xy 202.89774 -314.032392)
			(xy 205.498192 -314.032392) (xy 205.498192 -313.537854) (xy 205.498754 -313.532567) (xy 205.506128 -313.524996)
			(xy 205.5114 -313.524392) (xy 206.027528 -313.524392) (xy 206.035339 -313.524092) (xy 206.050211 -313.519297)
			(xy 206.056738 -313.514994) (xy 206.077827 -313.500645) (xy 206.123488 -313.477914) (xy 206.172094 -313.462455)
			(xy 206.222497 -313.454632) (xy 206.273503 -313.454632) (xy 206.323906 -313.462455) (xy 206.372512 -313.477914)
			(xy 206.418173 -313.500645) (xy 206.439262 -313.514994) (xy 206.445803 -313.519269) (xy 206.460666 -313.524062)
			(xy 206.468472 -313.524392) (xy 206.9846 -313.524392) (xy 206.989863 -313.524895) (xy 206.997305 -313.532337)
			(xy 206.997808 -313.5376) (xy 206.997808 -313.538108) (xy 206.997808 -314.032138) (xy 264.798048 -314.032138)
			(xy 264.798048 -313.5376) (xy 264.79859 -313.532348) (xy 264.806006 -313.524908) (xy 264.811256 -313.524392)
			(xy 264.811764 -313.524392) (xy 265.327638 -313.524392) (xy 265.335446 -313.524053) (xy 265.350317 -313.519284)
			(xy 265.356848 -313.514994) (xy 265.377937 -313.500645) (xy 265.423598 -313.477914) (xy 265.472204 -313.462455)
			(xy 265.522607 -313.454632) (xy 265.573613 -313.454632) (xy 265.624016 -313.462455) (xy 265.672622 -313.477914)
			(xy 265.718283 -313.500645) (xy 265.739372 -313.514994) (xy 265.745911 -313.519273) (xy 265.760775 -313.524064)
			(xy 265.768582 -313.524392) (xy 266.28471 -313.524392) (xy 266.290004 -313.524911) (xy 266.297572 -313.532318)
			(xy 266.298172 -313.5376) (xy 266.298172 -314.032138) (xy 268.898116 -314.032138) (xy 268.898116 -313.5376)
			(xy 268.898429 -313.532262) (xy 268.905985 -313.524719) (xy 268.911324 -313.524392) (xy 268.911832 -313.524392)
			(xy 269.427706 -313.524392) (xy 269.435516 -313.524082) (xy 269.450388 -313.519294) (xy 269.456916 -313.514994)
			(xy 269.478005 -313.500645) (xy 269.523666 -313.477914) (xy 269.572272 -313.462455) (xy 269.622675 -313.454632)
			(xy 269.673681 -313.454632) (xy 269.724084 -313.462455) (xy 269.77269 -313.477914) (xy 269.818351 -313.500645)
			(xy 269.83944 -313.514994) (xy 269.845964 -313.519299) (xy 269.86084 -313.524074) (xy 269.86865 -313.524392)
			(xy 270.384778 -313.524392) (xy 270.390068 -313.524932) (xy 270.397638 -313.532323) (xy 270.39824 -313.5376)
			(xy 270.39824 -314.032138) (xy 270.398218 -314.032392) (xy 272.342356 -314.032392) (xy 272.342356 -314.031884)
			(xy 272.342356 -313.5376) (xy 272.342891 -313.532346) (xy 272.350311 -313.524906) (xy 272.355564 -313.524392)
			(xy 272.871692 -313.524392) (xy 272.879502 -313.524076) (xy 272.894373 -313.519292) (xy 272.900902 -313.514994)
			(xy 272.921991 -313.500645) (xy 272.967652 -313.477914) (xy 273.016258 -313.462455) (xy 273.066661 -313.454632)
			(xy 273.117667 -313.454632) (xy 273.16807 -313.462455) (xy 273.216676 -313.477914) (xy 273.262337 -313.500645)
			(xy 273.283426 -313.514994) (xy 273.289953 -313.519293) (xy 273.304826 -313.524072) (xy 273.312636 -313.524392)
			(xy 273.828764 -313.524392) (xy 273.834092 -313.524751) (xy 273.841635 -313.532273) (xy 273.841972 -313.5376)
			(xy 273.841972 -314.032138) (xy 273.84195 -314.032392) (xy 276.442424 -314.032392) (xy 276.442424 -314.031884)
			(xy 276.442424 -313.5376) (xy 276.44273 -313.53226) (xy 276.450291 -313.524717) (xy 276.455632 -313.524392)
			(xy 276.97176 -313.524392) (xy 276.979569 -313.524063) (xy 276.99444 -313.519288) (xy 277.00097 -313.514994)
			(xy 277.022059 -313.500645) (xy 277.06772 -313.477914) (xy 277.116326 -313.462455) (xy 277.166729 -313.454632)
			(xy 277.217735 -313.454632) (xy 277.268138 -313.462455) (xy 277.316744 -313.477914) (xy 277.362405 -313.500645)
			(xy 277.383494 -313.514994) (xy 277.390028 -313.519281) (xy 277.404896 -313.524067) (xy 277.412704 -313.524392)
			(xy 277.928832 -313.524392) (xy 277.934099 -313.524873) (xy 277.941539 -313.532332) (xy 277.94204 -313.5376)
			(xy 277.94204 -314.032138) (xy 277.942019 -314.032392) (xy 279.886156 -314.032392) (xy 279.886156 -314.031884)
			(xy 279.886156 -313.5376) (xy 279.886691 -313.532346) (xy 279.894111 -313.524906) (xy 279.899364 -313.524392)
			(xy 280.415492 -313.524392) (xy 280.423302 -313.524076) (xy 280.438173 -313.519292) (xy 280.444702 -313.514994)
			(xy 280.465791 -313.500645) (xy 280.511452 -313.477914) (xy 280.560058 -313.462455) (xy 280.610461 -313.454632)
			(xy 280.661467 -313.454632) (xy 280.71187 -313.462455) (xy 280.760476 -313.477914) (xy 280.806137 -313.500645)
			(xy 280.827226 -313.514994) (xy 280.833753 -313.519293) (xy 280.848626 -313.524072) (xy 280.856436 -313.524392)
			(xy 281.372564 -313.524392) (xy 281.377892 -313.524751) (xy 281.385435 -313.532273) (xy 281.385772 -313.5376)
			(xy 281.385772 -314.032138) (xy 281.38575 -314.032392) (xy 283.986224 -314.032392) (xy 283.986224 -314.031884)
			(xy 283.986224 -313.5376) (xy 283.98653 -313.53226) (xy 283.994091 -313.524717) (xy 283.999432 -313.524392)
			(xy 284.51556 -313.524392) (xy 284.523369 -313.524063) (xy 284.53824 -313.519288) (xy 284.54477 -313.514994)
			(xy 284.565859 -313.500645) (xy 284.61152 -313.477914) (xy 284.660126 -313.462455) (xy 284.710529 -313.454632)
			(xy 284.761535 -313.454632) (xy 284.811938 -313.462455) (xy 284.860544 -313.477914) (xy 284.906205 -313.500645)
			(xy 284.927294 -313.514994) (xy 284.933828 -313.519281) (xy 284.948696 -313.524067) (xy 284.956504 -313.524392)
			(xy 285.472632 -313.524392) (xy 285.477899 -313.524873) (xy 285.485339 -313.532332) (xy 285.48584 -313.5376)
			(xy 285.48584 -314.032138) (xy 287.429956 -314.032138) (xy 287.429956 -313.5376) (xy 287.430491 -313.532346)
			(xy 287.437911 -313.524906) (xy 287.443164 -313.524392) (xy 287.443672 -313.524392) (xy 287.959546 -313.524392)
			(xy 287.967354 -313.524057) (xy 287.982226 -313.519286) (xy 287.988756 -313.514994) (xy 288.009845 -313.500645)
			(xy 288.055506 -313.477914) (xy 288.104112 -313.462455) (xy 288.154515 -313.454632) (xy 288.205521 -313.454632)
			(xy 288.255924 -313.462455) (xy 288.30453 -313.477914) (xy 288.350191 -313.500645) (xy 288.37128 -313.514994)
			(xy 288.377817 -313.519276) (xy 288.392683 -313.524065) (xy 288.40049 -313.524392) (xy 288.916618 -313.524392)
			(xy 288.921913 -313.524905) (xy 288.929481 -313.532316) (xy 288.93008 -313.5376) (xy 288.93008 -314.032138)
			(xy 291.530024 -314.032138) (xy 291.530024 -313.5376) (xy 291.53033 -313.53226) (xy 291.537891 -313.524717)
			(xy 291.543232 -313.524392) (xy 291.54374 -313.524392) (xy 292.059614 -313.524392) (xy 292.067425 -313.524086)
			(xy 292.082296 -313.519295) (xy 292.088824 -313.514994) (xy 292.109913 -313.500645) (xy 292.155574 -313.477914)
			(xy 292.20418 -313.462455) (xy 292.254583 -313.454632) (xy 292.305589 -313.454632) (xy 292.355992 -313.462455)
			(xy 292.404598 -313.477914) (xy 292.450259 -313.500645) (xy 292.471348 -313.514994) (xy 292.47787 -313.519302)
			(xy 292.492747 -313.524075) (xy 292.500558 -313.524392) (xy 293.016686 -313.524392) (xy 293.021977 -313.524927)
			(xy 293.029546 -313.532321) (xy 293.030148 -313.5376) (xy 293.030148 -314.032138) (xy 293.030126 -314.032392)
			(xy 294.974264 -314.032392) (xy 294.974264 -314.031884) (xy 294.974264 -313.5376) (xy 294.974792 -313.532344)
			(xy 294.982217 -313.524903) (xy 294.987472 -313.524392) (xy 295.5036 -313.524392) (xy 295.51141 -313.52408)
			(xy 295.526282 -313.519293) (xy 295.53281 -313.514994) (xy 295.553899 -313.500645) (xy 295.59956 -313.477914)
			(xy 295.648166 -313.462455) (xy 295.698569 -313.454632) (xy 295.749575 -313.454632) (xy 295.799978 -313.462455)
			(xy 295.848584 -313.477914) (xy 295.894245 -313.500645) (xy 295.915334 -313.514994) (xy 295.921859 -313.519297)
			(xy 295.936734 -313.524073) (xy 295.944544 -313.524392) (xy 296.460672 -313.524392) (xy 296.466001 -313.524745)
			(xy 296.473543 -313.532272) (xy 296.47388 -313.5376) (xy 296.47388 -314.032138) (xy 296.473857 -314.032392)
			(xy 299.074332 -314.032392) (xy 299.074332 -314.031884) (xy 299.074332 -313.5376) (xy 299.074631 -313.532258)
			(xy 299.082197 -313.524715) (xy 299.08754 -313.524392) (xy 299.603668 -313.524392) (xy 299.611477 -313.524066)
			(xy 299.626349 -313.519289) (xy 299.632878 -313.514994) (xy 299.653967 -313.500645) (xy 299.699628 -313.477914)
			(xy 299.748234 -313.462455) (xy 299.798637 -313.454632) (xy 299.849643 -313.454632) (xy 299.900046 -313.462455)
			(xy 299.948652 -313.477914) (xy 299.994313 -313.500645) (xy 300.015402 -313.514994) (xy 300.021934 -313.519284)
			(xy 300.036804 -313.524068) (xy 300.044612 -313.524392) (xy 300.56074 -313.524392) (xy 300.566008 -313.524868)
			(xy 300.573448 -313.532331) (xy 300.573948 -313.5376) (xy 300.573948 -314.032138) (xy 302.518064 -314.032138)
			(xy 302.518064 -313.5376) (xy 302.518592 -313.532344) (xy 302.526017 -313.524903) (xy 302.531272 -313.524392)
			(xy 304.004726 -313.524392) (xy 304.010022 -313.5249) (xy 304.017589 -313.532315) (xy 304.018188 -313.5376)
			(xy 304.018188 -314.032138) (xy 306.618132 -314.032138) (xy 306.618132 -313.5376) (xy 306.618431 -313.532258)
			(xy 306.625997 -313.524715) (xy 306.63134 -313.524392) (xy 306.631848 -313.524392) (xy 308.104794 -313.524392)
			(xy 308.110086 -313.524921) (xy 308.117655 -313.53232) (xy 308.118256 -313.5376) (xy 308.118256 -314.032138)
			(xy 308.118233 -314.032392) (xy 411.618176 -314.032392) (xy 411.618176 -314.031884) (xy 411.618176 -313.5376)
			(xy 411.618693 -313.532341) (xy 411.626126 -313.5249) (xy 411.631384 -313.524392) (xy 413.104584 -313.524392)
			(xy 413.109914 -313.524738) (xy 413.117456 -313.53227) (xy 413.117792 -313.5376) (xy 413.117792 -314.032138)
			(xy 413.117769 -314.032392) (xy 415.718244 -314.032392) (xy 415.718244 -313.5376) (xy 415.71879 -313.532349)
			(xy 415.726203 -313.524909) (xy 415.731452 -313.524392) (xy 417.204652 -313.524392) (xy 417.209978 -313.524759)
			(xy 417.217521 -313.532276) (xy 417.21786 -313.5376) (xy 417.21786 -314.032138) (xy 419.161976 -314.032138)
			(xy 419.161976 -313.5376) (xy 419.162493 -313.532341) (xy 419.169926 -313.5249) (xy 419.175184 -313.524392)
			(xy 419.175692 -313.524392) (xy 419.691566 -313.524392) (xy 419.699375 -313.524065) (xy 419.714246 -313.519288)
			(xy 419.720776 -313.514994) (xy 419.741865 -313.500645) (xy 419.787526 -313.477914) (xy 419.836132 -313.462455)
			(xy 419.886535 -313.454632) (xy 419.937541 -313.454632) (xy 419.987944 -313.462455) (xy 420.03655 -313.477914)
			(xy 420.082211 -313.500645) (xy 420.1033 -313.514994) (xy 420.109833 -313.519284) (xy 420.124702 -313.524068)
			(xy 420.13251 -313.524392) (xy 420.648638 -313.524392) (xy 420.653936 -313.524892) (xy 420.661502 -313.532313)
			(xy 420.6621 -313.5376) (xy 420.6621 -314.032138) (xy 423.262044 -314.032138) (xy 423.262044 -313.5376)
			(xy 423.26259 -313.532349) (xy 423.270003 -313.524909) (xy 423.275252 -313.524392) (xy 423.27576 -313.524392)
			(xy 423.791634 -313.524392) (xy 423.799442 -313.524051) (xy 423.814313 -313.519284) (xy 423.820844 -313.514994)
			(xy 423.841933 -313.500645) (xy 423.887594 -313.477914) (xy 423.9362 -313.462455) (xy 423.986603 -313.454632)
			(xy 424.037609 -313.454632) (xy 424.088012 -313.462455) (xy 424.136618 -313.477914) (xy 424.182279 -313.500645)
			(xy 424.203368 -313.514994) (xy 424.209908 -313.519271) (xy 424.224771 -313.524063) (xy 424.232578 -313.524392)
			(xy 424.748706 -313.524392) (xy 424.754 -313.524913) (xy 424.761568 -313.532318) (xy 424.762168 -313.5376)
			(xy 424.762168 -314.032138) (xy 424.762145 -314.032392) (xy 426.706284 -314.032392) (xy 426.706284 -314.031884)
			(xy 426.706284 -313.5376) (xy 426.706794 -313.532339) (xy 426.714232 -313.524897) (xy 426.719492 -313.524392)
			(xy 427.23562 -313.524392) (xy 427.243431 -313.524088) (xy 427.258302 -313.519295) (xy 427.26483 -313.514994)
			(xy 427.285919 -313.500645) (xy 427.33158 -313.477914) (xy 427.380186 -313.462455) (xy 427.430589 -313.454632)
			(xy 427.481595 -313.454632) (xy 427.531998 -313.462455) (xy 427.580604 -313.477914) (xy 427.626265 -313.500645)
			(xy 427.647354 -313.514994) (xy 427.653875 -313.519304) (xy 427.668753 -313.524076) (xy 427.676564 -313.524392)
			(xy 428.192692 -313.524392) (xy 428.198023 -313.524732) (xy 428.205565 -313.532269) (xy 428.2059 -313.5376)
			(xy 428.2059 -314.032138) (xy 428.205876 -314.032392) (xy 430.806352 -314.032392) (xy 430.806352 -314.031884)
			(xy 430.806352 -313.5376) (xy 430.806891 -313.532347) (xy 430.814308 -313.524907) (xy 430.81956 -313.524392)
			(xy 431.335688 -313.524392) (xy 431.343498 -313.524075) (xy 431.358369 -313.519291) (xy 431.364898 -313.514994)
			(xy 431.385987 -313.500645) (xy 431.431648 -313.477914) (xy 431.480254 -313.462455) (xy 431.530657 -313.454632)
			(xy 431.581663 -313.454632) (xy 431.632066 -313.462455) (xy 431.680672 -313.477914) (xy 431.726333 -313.500645)
			(xy 431.747422 -313.514994) (xy 431.75395 -313.519292) (xy 431.768823 -313.524071) (xy 431.776632 -313.524392)
			(xy 432.29276 -313.524392) (xy 432.298087 -313.524754) (xy 432.30563 -313.532274) (xy 432.305968 -313.5376)
			(xy 432.305968 -314.032138) (xy 434.250084 -314.032138) (xy 434.250084 -313.5376) (xy 434.250594 -313.532339)
			(xy 434.258032 -313.524897) (xy 434.263292 -313.524392) (xy 434.2638 -313.524392) (xy 434.779674 -313.524392)
			(xy 434.787483 -313.524069) (xy 434.802355 -313.51929) (xy 434.808884 -313.514994) (xy 434.829973 -313.500645)
			(xy 434.875634 -313.477914) (xy 434.92424 -313.462455) (xy 434.974643 -313.454632) (xy 435.025649 -313.454632)
			(xy 435.076052 -313.462455) (xy 435.124658 -313.477914) (xy 435.170319 -313.500645) (xy 435.191408 -313.514994)
			(xy 435.197939 -313.519287) (xy 435.212809 -313.524069) (xy 435.220618 -313.524392) (xy 435.736746 -313.524392)
			(xy 435.742033 -313.524954) (xy 435.749604 -313.532328) (xy 435.750208 -313.5376) (xy 435.750208 -314.032138)
			(xy 438.350152 -314.032138) (xy 438.350152 -313.5376) (xy 438.350691 -313.532347) (xy 438.358108 -313.524907)
			(xy 438.36336 -313.524392) (xy 438.363868 -313.524392) (xy 438.879742 -313.524392) (xy 438.88755 -313.524055)
			(xy 438.902422 -313.519285) (xy 438.908952 -313.514994) (xy 438.930041 -313.500645) (xy 438.975702 -313.477914)
			(xy 439.024308 -313.462455) (xy 439.074711 -313.454632) (xy 439.125717 -313.454632) (xy 439.17612 -313.462455)
			(xy 439.224726 -313.477914) (xy 439.270387 -313.500645) (xy 439.291476 -313.514994) (xy 439.298014 -313.519274)
			(xy 439.312879 -313.524064) (xy 439.320686 -313.524392) (xy 439.836814 -313.524392) (xy 439.842109 -313.524908)
			(xy 439.849676 -313.532317) (xy 439.850276 -313.5376) (xy 439.850276 -314.032138) (xy 439.850252 -314.032392)
			(xy 441.794392 -314.032392) (xy 441.794392 -314.031884) (xy 441.794392 -313.5376) (xy 441.794895 -313.532337)
			(xy 441.802337 -313.524895) (xy 441.8076 -313.524392) (xy 442.323728 -313.524392) (xy 442.331539 -313.524092)
			(xy 442.346411 -313.519297) (xy 442.352938 -313.514994) (xy 442.374027 -313.500645) (xy 442.419688 -313.477914)
			(xy 442.468294 -313.462455) (xy 442.518697 -313.454632) (xy 442.569703 -313.454632) (xy 442.620106 -313.462455)
			(xy 442.668712 -313.477914) (xy 442.714373 -313.500645) (xy 442.735462 -313.514994) (xy 442.742003 -313.519269)
			(xy 442.756866 -313.524062) (xy 442.764672 -313.524392) (xy 443.2808 -313.524392) (xy 443.286063 -313.524895)
			(xy 443.293505 -313.532337) (xy 443.294008 -313.5376) (xy 443.294008 -314.032138) (xy 443.293984 -314.032392)
			(xy 445.89446 -314.032392) (xy 445.89446 -314.031884) (xy 445.89446 -313.5376) (xy 445.894992 -313.532345)
			(xy 445.902414 -313.524904) (xy 445.907668 -313.524392) (xy 446.423796 -313.524392) (xy 446.431606 -313.524078)
			(xy 446.446478 -313.519292) (xy 446.453006 -313.514994) (xy 446.474095 -313.500645) (xy 446.519756 -313.477914)
			(xy 446.568362 -313.462455) (xy 446.618765 -313.454632) (xy 446.669771 -313.454632) (xy 446.720174 -313.462455)
			(xy 446.76878 -313.477914) (xy 446.814441 -313.500645) (xy 446.83553 -313.514994) (xy 446.842056 -313.519295)
			(xy 446.85693 -313.524072) (xy 446.86474 -313.524392) (xy 447.380868 -313.524392) (xy 447.386196 -313.524748)
			(xy 447.393739 -313.532273) (xy 447.394076 -313.5376) (xy 447.394076 -314.032138) (xy 447.394053 -314.032392)
			(xy 449.338192 -314.032392) (xy 449.338192 -314.031884) (xy 449.338192 -313.5376) (xy 449.338695 -313.532337)
			(xy 449.346137 -313.524895) (xy 449.3514 -313.524392) (xy 449.867528 -313.524392) (xy 449.875339 -313.524092)
			(xy 449.890211 -313.519297) (xy 449.896738 -313.514994) (xy 449.917827 -313.500645) (xy 449.963488 -313.477914)
			(xy 450.012094 -313.462455) (xy 450.062497 -313.454632) (xy 450.113503 -313.454632) (xy 450.163906 -313.462455)
			(xy 450.212512 -313.477914) (xy 450.258173 -313.500645) (xy 450.279262 -313.514994) (xy 450.285803 -313.519269)
			(xy 450.300666 -313.524062) (xy 450.308472 -313.524392) (xy 450.8246 -313.524392) (xy 450.829863 -313.524895)
			(xy 450.837305 -313.532337) (xy 450.837808 -313.5376) (xy 450.837808 -314.032138) (xy 450.837784 -314.032392)
			(xy 453.43826 -314.032392) (xy 453.43826 -314.031884) (xy 453.43826 -313.5376) (xy 453.438792 -313.532345)
			(xy 453.446214 -313.524904) (xy 453.451468 -313.524392) (xy 453.967596 -313.524392) (xy 453.975406 -313.524078)
			(xy 453.990278 -313.519292) (xy 453.996806 -313.514994) (xy 454.017895 -313.500645) (xy 454.063556 -313.477914)
			(xy 454.112162 -313.462455) (xy 454.162565 -313.454632) (xy 454.213571 -313.454632) (xy 454.263974 -313.462455)
			(xy 454.31258 -313.477914) (xy 454.358241 -313.500645) (xy 454.37933 -313.514994) (xy 454.385856 -313.519295)
			(xy 454.40073 -313.524072) (xy 454.40854 -313.524392) (xy 454.924668 -313.524392) (xy 454.929996 -313.524748)
			(xy 454.937539 -313.532273) (xy 454.937876 -313.5376) (xy 454.937876 -314.032138) (xy 454.937404 -314.037443)
			(xy 454.929964 -314.045011) (xy 454.924668 -314.0456) (xy 454.408794 -314.0456) (xy 454.400984 -314.045911)
			(xy 454.386112 -314.050699) (xy 454.379584 -314.054998) (xy 454.35846 -314.069344) (xy 454.312738 -314.092073)
			(xy 454.264065 -314.107504) (xy 454.213599 -314.115271) (xy 454.188068 -314.115704) (xy 454.162537 -314.115276)
			(xy 454.112074 -314.107497) (xy 454.063401 -314.092065) (xy 454.017674 -314.069346) (xy 453.996552 -314.054998)
			(xy 453.990031 -314.050689) (xy 453.975153 -314.045917) (xy 453.967342 -314.0456) (xy 453.451468 -314.0456)
			(xy 453.446199 -314.045126) (xy 453.438758 -314.037662) (xy 453.43826 -314.032392) (xy 450.837784 -314.032392)
			(xy 450.837308 -314.037436) (xy 450.829887 -314.045002) (xy 450.8246 -314.0456) (xy 450.308726 -314.0456)
			(xy 450.300917 -314.045925) (xy 450.286045 -314.050703) (xy 450.279516 -314.054998) (xy 450.258383 -314.06933)
			(xy 450.212664 -314.092062) (xy 450.163994 -314.107497) (xy 450.11353 -314.115269) (xy 450.088 -314.115704)
			(xy 450.06247 -314.11526) (xy 450.012007 -314.107485) (xy 449.963335 -314.092058) (xy 449.917607 -314.069344)
			(xy 449.896484 -314.054998) (xy 449.889955 -314.050702) (xy 449.875083 -314.045922) (xy 449.867274 -314.0456)
			(xy 449.3514 -314.0456) (xy 449.346066 -314.045273) (xy 449.338524 -314.037726) (xy 449.338192 -314.032392)
			(xy 447.394053 -314.032392) (xy 447.393604 -314.037443) (xy 447.386164 -314.045011) (xy 447.380868 -314.0456)
			(xy 446.864994 -314.0456) (xy 446.857184 -314.045911) (xy 446.842312 -314.050699) (xy 446.835784 -314.054998)
			(xy 446.81466 -314.069344) (xy 446.768938 -314.092073) (xy 446.720265 -314.107504) (xy 446.669799 -314.115271)
			(xy 446.644268 -314.115704) (xy 446.618737 -314.115276) (xy 446.568274 -314.107497) (xy 446.519601 -314.092065)
			(xy 446.473874 -314.069346) (xy 446.452752 -314.054998) (xy 446.446231 -314.050689) (xy 446.431353 -314.045917)
			(xy 446.423542 -314.0456) (xy 445.907668 -314.0456) (xy 445.902399 -314.045126) (xy 445.894958 -314.037662)
			(xy 445.89446 -314.032392) (xy 443.293984 -314.032392) (xy 443.293508 -314.037436) (xy 443.286087 -314.045002)
			(xy 443.2808 -314.0456) (xy 442.764926 -314.0456) (xy 442.757117 -314.045925) (xy 442.742245 -314.050703)
			(xy 442.735716 -314.054998) (xy 442.714583 -314.06933) (xy 442.668864 -314.092062) (xy 442.620194 -314.107497)
			(xy 442.56973 -314.115269) (xy 442.5442 -314.115704) (xy 442.51867 -314.11526) (xy 442.468207 -314.107485)
			(xy 442.419535 -314.092058) (xy 442.373807 -314.069344) (xy 442.352684 -314.054998) (xy 442.346155 -314.050702)
			(xy 442.331283 -314.045922) (xy 442.323474 -314.0456) (xy 441.8076 -314.0456) (xy 441.802266 -314.045273)
			(xy 441.794724 -314.037726) (xy 441.794392 -314.032392) (xy 439.850252 -314.032392) (xy 439.849776 -314.037503)
			(xy 439.84218 -314.045086) (xy 439.836814 -314.0456) (xy 439.32094 -314.0456) (xy 439.313131 -314.045931)
			(xy 439.29826 -314.050705) (xy 439.29173 -314.054998) (xy 439.270621 -314.069367) (xy 439.224893 -314.092091)
			(xy 439.176216 -314.107516) (xy 439.125746 -314.115275) (xy 439.100214 -314.115704) (xy 439.074684 -314.115253)
			(xy 439.024221 -314.107481) (xy 438.975549 -314.092055) (xy 438.929821 -314.069343) (xy 438.908698 -314.054998)
			(xy 438.902166 -314.050707) (xy 438.887296 -314.045924) (xy 438.879488 -314.0456) (xy 438.363614 -314.0456)
			(xy 438.358261 -314.045044) (xy 438.350677 -314.037489) (xy 438.350152 -314.032138) (xy 435.750208 -314.032138)
			(xy 435.749679 -314.037495) (xy 435.742103 -314.045076) (xy 435.736746 -314.0456) (xy 435.220872 -314.0456)
			(xy 435.213061 -314.045902) (xy 435.19819 -314.050696) (xy 435.191662 -314.054998) (xy 435.170544 -314.069354)
			(xy 435.12482 -314.09208) (xy 435.076145 -314.107509) (xy 435.025677 -314.115273) (xy 435.000146 -314.115704)
			(xy 434.974617 -314.115237) (xy 434.924155 -314.107469) (xy 434.875482 -314.092049) (xy 434.829753 -314.069341)
			(xy 434.80863 -314.054998) (xy 434.802091 -314.050719) (xy 434.787227 -314.045929) (xy 434.77942 -314.0456)
			(xy 434.263546 -314.0456) (xy 434.258126 -314.045194) (xy 434.25044 -314.037555) (xy 434.250084 -314.032138)
			(xy 432.305968 -314.032138) (xy 432.305503 -314.037445) (xy 432.298058 -314.045013) (xy 432.29276 -314.0456)
			(xy 431.776886 -314.0456) (xy 431.769075 -314.045908) (xy 431.754204 -314.050698) (xy 431.747676 -314.054998)
			(xy 431.726554 -314.069347) (xy 431.680831 -314.092076) (xy 431.632158 -314.107506) (xy 431.581691 -314.115272)
			(xy 431.55616 -314.115704) (xy 431.530629 -314.11528) (xy 431.480165 -314.107499) (xy 431.431493 -314.092066)
			(xy 431.385766 -314.069347) (xy 431.364644 -314.054998) (xy 431.358124 -314.050686) (xy 431.343245 -314.045916)
			(xy 431.335434 -314.0456) (xy 430.81956 -314.0456) (xy 430.81429 -314.045131) (xy 430.80685 -314.037663)
			(xy 430.806352 -314.032392) (xy 428.205876 -314.032392) (xy 428.205407 -314.037438) (xy 428.197981 -314.045004)
			(xy 428.192692 -314.0456) (xy 427.676818 -314.0456) (xy 427.669009 -314.045921) (xy 427.654137 -314.050702)
			(xy 427.647608 -314.054998) (xy 427.626477 -314.069334) (xy 427.580757 -314.092065) (xy 427.532087 -314.107499)
			(xy 427.481622 -314.115269) (xy 427.456092 -314.115704) (xy 427.430562 -314.115264) (xy 427.380099 -314.107488)
			(xy 427.331426 -314.09206) (xy 427.285698 -314.069345) (xy 427.264576 -314.054998) (xy 427.258049 -314.050699)
			(xy 427.243176 -314.045921) (xy 427.235366 -314.0456) (xy 426.719492 -314.0456) (xy 426.714226 -314.04511)
			(xy 426.706784 -314.037658) (xy 426.706284 -314.032392) (xy 424.762145 -314.032392) (xy 424.761675 -314.037505)
			(xy 424.754074 -314.045088) (xy 424.748706 -314.0456) (xy 424.232832 -314.0456) (xy 424.225023 -314.045927)
			(xy 424.210152 -314.050704) (xy 424.203622 -314.054998) (xy 424.182488 -314.069328) (xy 424.136769 -314.09206)
			(xy 424.088099 -314.107496) (xy 424.037636 -314.115268) (xy 424.012106 -314.115704) (xy 423.986576 -314.115257)
			(xy 423.936113 -314.107483) (xy 423.887441 -314.092057) (xy 423.841713 -314.069344) (xy 423.82059 -314.054998)
			(xy 423.81406 -314.050704) (xy 423.799189 -314.045923) (xy 423.79138 -314.0456) (xy 423.275506 -314.0456)
			(xy 423.270152 -314.04505) (xy 423.262568 -314.03749) (xy 423.262044 -314.032138) (xy 420.6621 -314.032138)
			(xy 420.661579 -314.037497) (xy 420.653997 -314.045079) (xy 420.648638 -314.0456) (xy 420.132764 -314.0456)
			(xy 420.124956 -314.045941) (xy 420.110085 -314.050708) (xy 420.103554 -314.054998) (xy 420.082439 -314.069357)
			(xy 420.036713 -314.092083) (xy 419.988038 -314.107511) (xy 419.93757 -314.115273) (xy 419.912038 -314.115704)
			(xy 419.886509 -314.115241) (xy 419.836046 -314.107472) (xy 419.787374 -314.09205) (xy 419.741645 -314.069342)
			(xy 419.720522 -314.054998) (xy 419.713985 -314.050716) (xy 419.699119 -314.045927) (xy 419.691312 -314.0456)
			(xy 419.175438 -314.0456) (xy 419.170088 -314.045028) (xy 419.162502 -314.037485) (xy 419.161976 -314.032138)
			(xy 417.21786 -314.032138) (xy 417.217402 -314.037447) (xy 417.209952 -314.045016) (xy 417.204652 -314.0456)
			(xy 415.731452 -314.0456) (xy 415.726182 -314.045136) (xy 415.718741 -314.037664) (xy 415.718244 -314.032392)
			(xy 413.117769 -314.032392) (xy 413.117306 -314.037439) (xy 413.109875 -314.045006) (xy 413.104584 -314.0456)
			(xy 411.631384 -314.0456) (xy 411.626117 -314.045115) (xy 411.618675 -314.03766) (xy 411.618176 -314.032392)
			(xy 308.118233 -314.032392) (xy 308.117774 -314.037508) (xy 308.110165 -314.045092) (xy 308.104794 -314.0456)
			(xy 306.631594 -314.0456) (xy 306.626238 -314.045058) (xy 306.618655 -314.037492) (xy 306.618132 -314.032138)
			(xy 304.018188 -314.032138) (xy 304.017677 -314.0375) (xy 304.010089 -314.045082) (xy 304.004726 -314.0456)
			(xy 302.531526 -314.0456) (xy 302.526174 -314.045036) (xy 302.518589 -314.037487) (xy 302.518064 -314.032138)
			(xy 300.573948 -314.032138) (xy 300.5735 -314.03745) (xy 300.566043 -314.045019) (xy 300.56074 -314.0456)
			(xy 300.044866 -314.0456) (xy 300.037058 -314.045942) (xy 300.022187 -314.050708) (xy 300.015656 -314.054998)
			(xy 299.99454 -314.069356) (xy 299.948815 -314.092082) (xy 299.90014 -314.10751) (xy 299.849672 -314.115273)
			(xy 299.82414 -314.115704) (xy 299.798611 -314.11524) (xy 299.748148 -314.107471) (xy 299.699476 -314.09205)
			(xy 299.653747 -314.069341) (xy 299.632624 -314.054998) (xy 299.626087 -314.050717) (xy 299.611221 -314.045928)
			(xy 299.603414 -314.0456) (xy 299.08754 -314.0456) (xy 299.082211 -314.045245) (xy 299.074668 -314.03772)
			(xy 299.074332 -314.032392) (xy 296.473857 -314.032392) (xy 296.473404 -314.037442) (xy 296.465967 -314.04501)
			(xy 296.460672 -314.0456) (xy 295.944798 -314.0456) (xy 295.936988 -314.045913) (xy 295.922116 -314.050699)
			(xy 295.915588 -314.054998) (xy 295.894463 -314.069342) (xy 295.848741 -314.092072) (xy 295.800069 -314.107503)
			(xy 295.749603 -314.115271) (xy 295.724072 -314.115704) (xy 295.698542 -314.115274) (xy 295.648078 -314.107495)
			(xy 295.599406 -314.092064) (xy 295.553678 -314.069346) (xy 295.532556 -314.054998) (xy 295.526034 -314.050691)
			(xy 295.511157 -314.045918) (xy 295.503346 -314.0456) (xy 294.987472 -314.0456) (xy 294.982204 -314.045123)
			(xy 294.974762 -314.037661) (xy 294.974264 -314.032392) (xy 293.030126 -314.032392) (xy 293.029673 -314.03751)
			(xy 293.02206 -314.045094) (xy 293.016686 -314.0456) (xy 292.500812 -314.0456) (xy 292.493002 -314.045919)
			(xy 292.478131 -314.050701) (xy 292.471602 -314.054998) (xy 292.450473 -314.069336) (xy 292.404752 -314.092067)
			(xy 292.356081 -314.1075) (xy 292.305616 -314.11527) (xy 292.280086 -314.115704) (xy 292.254556 -314.115267)
			(xy 292.204092 -314.10749) (xy 292.15542 -314.092061) (xy 292.109692 -314.069345) (xy 292.08857 -314.054998)
			(xy 292.082045 -314.050696) (xy 292.06717 -314.04592) (xy 292.05936 -314.0456) (xy 291.543486 -314.0456)
			(xy 291.53813 -314.045063) (xy 291.530547 -314.037493) (xy 291.530024 -314.032138) (xy 288.93008 -314.032138)
			(xy 288.929576 -314.037502) (xy 288.921983 -314.045084) (xy 288.916618 -314.0456) (xy 288.400744 -314.0456)
			(xy 288.392936 -314.045932) (xy 288.378064 -314.050705) (xy 288.371534 -314.054998) (xy 288.350424 -314.069366)
			(xy 288.304697 -314.09209) (xy 288.25602 -314.107515) (xy 288.20555 -314.115275) (xy 288.180018 -314.115704)
			(xy 288.154488 -314.115251) (xy 288.104026 -314.107479) (xy 288.055353 -314.092055) (xy 288.009625 -314.069343)
			(xy 287.988502 -314.054998) (xy 287.981969 -314.050709) (xy 287.9671 -314.045924) (xy 287.959292 -314.0456)
			(xy 287.443418 -314.0456) (xy 287.438065 -314.045042) (xy 287.430481 -314.037489) (xy 287.429956 -314.032138)
			(xy 285.48584 -314.032138) (xy 285.4854 -314.037451) (xy 285.477938 -314.045021) (xy 285.472632 -314.0456)
			(xy 284.956758 -314.0456) (xy 284.94895 -314.045938) (xy 284.934079 -314.050707) (xy 284.927548 -314.054998)
			(xy 284.906434 -314.06936) (xy 284.860708 -314.092085) (xy 284.812032 -314.107512) (xy 284.761564 -314.115274)
			(xy 284.736032 -314.115704) (xy 284.710503 -314.115244) (xy 284.66004 -314.107474) (xy 284.611368 -314.092052)
			(xy 284.565639 -314.069342) (xy 284.544516 -314.054998) (xy 284.53798 -314.050714) (xy 284.523114 -314.045927)
			(xy 284.515306 -314.0456) (xy 283.999432 -314.0456) (xy 283.994102 -314.045251) (xy 283.986559 -314.037721)
			(xy 283.986224 -314.032392) (xy 281.38575 -314.032392) (xy 281.385303 -314.037444) (xy 281.377861 -314.045012)
			(xy 281.372564 -314.0456) (xy 280.85669 -314.0456) (xy 280.84888 -314.045909) (xy 280.834008 -314.050698)
			(xy 280.82748 -314.054998) (xy 280.806357 -314.069346) (xy 280.760634 -314.092074) (xy 280.711961 -314.107505)
			(xy 280.661495 -314.115271) (xy 280.635964 -314.115704) (xy 280.610433 -314.115278) (xy 280.559969 -314.107498)
			(xy 280.511297 -314.092065) (xy 280.46557 -314.069346) (xy 280.444448 -314.054998) (xy 280.437927 -314.050688)
			(xy 280.423049 -314.045917) (xy 280.415238 -314.0456) (xy 279.899364 -314.0456) (xy 279.894095 -314.045128)
			(xy 279.886654 -314.037663) (xy 279.886156 -314.032392) (xy 277.942019 -314.032392) (xy 277.9416 -314.037451)
			(xy 277.934138 -314.045021) (xy 277.928832 -314.0456) (xy 277.412958 -314.0456) (xy 277.40515 -314.045938)
			(xy 277.390279 -314.050707) (xy 277.383748 -314.054998) (xy 277.362634 -314.06936) (xy 277.316908 -314.092085)
			(xy 277.268232 -314.107512) (xy 277.217764 -314.115274) (xy 277.192232 -314.115704) (xy 277.166703 -314.115244)
			(xy 277.11624 -314.107474) (xy 277.067568 -314.092052) (xy 277.021839 -314.069342) (xy 277.000716 -314.054998)
			(xy 276.99418 -314.050714) (xy 276.979314 -314.045927) (xy 276.971506 -314.0456) (xy 276.455632 -314.0456)
			(xy 276.450302 -314.045251) (xy 276.442759 -314.037721) (xy 276.442424 -314.032392) (xy 273.84195 -314.032392)
			(xy 273.841503 -314.037444) (xy 273.834061 -314.045012) (xy 273.828764 -314.0456) (xy 273.31289 -314.0456)
			(xy 273.30508 -314.045909) (xy 273.290208 -314.050698) (xy 273.28368 -314.054998) (xy 273.262557 -314.069346)
			(xy 273.216834 -314.092074) (xy 273.168161 -314.107505) (xy 273.117695 -314.115271) (xy 273.092164 -314.115704)
			(xy 273.066633 -314.115278) (xy 273.016169 -314.107498) (xy 272.967497 -314.092065) (xy 272.92177 -314.069346)
			(xy 272.900648 -314.054998) (xy 272.894127 -314.050688) (xy 272.879249 -314.045917) (xy 272.871438 -314.0456)
			(xy 272.355564 -314.0456) (xy 272.350295 -314.045128) (xy 272.342854 -314.037663) (xy 272.342356 -314.032392)
			(xy 270.398218 -314.032392) (xy 270.397772 -314.037512) (xy 270.390154 -314.045096) (xy 270.384778 -314.0456)
			(xy 269.868904 -314.0456) (xy 269.861094 -314.045915) (xy 269.846223 -314.0507) (xy 269.839694 -314.054998)
			(xy 269.818567 -314.06934) (xy 269.772846 -314.09207) (xy 269.724174 -314.107502) (xy 269.673709 -314.11527)
			(xy 269.648178 -314.115704) (xy 269.622648 -314.115271) (xy 269.572184 -314.107493) (xy 269.523512 -314.092063)
			(xy 269.477784 -314.069345) (xy 269.456662 -314.054998) (xy 269.450138 -314.050693) (xy 269.435262 -314.045919)
			(xy 269.427452 -314.0456) (xy 268.911578 -314.0456) (xy 268.906221 -314.045068) (xy 268.898638 -314.037495)
			(xy 268.898116 -314.032138) (xy 266.298172 -314.032138) (xy 266.297676 -314.037504) (xy 266.290077 -314.045087)
			(xy 266.28471 -314.0456) (xy 265.768836 -314.0456) (xy 265.761027 -314.045929) (xy 265.746156 -314.050704)
			(xy 265.739626 -314.054998) (xy 265.71849 -314.069326) (xy 265.672772 -314.092059) (xy 265.624103 -314.107495)
			(xy 265.57364 -314.115268) (xy 265.54811 -314.115704) (xy 265.52258 -314.115255) (xy 265.472117 -314.107482)
			(xy 265.423445 -314.092056) (xy 265.377717 -314.069343) (xy 265.356594 -314.054998) (xy 265.350063 -314.050705)
			(xy 265.335193 -314.045923) (xy 265.327384 -314.0456) (xy 264.81151 -314.0456) (xy 264.806156 -314.045047)
			(xy 264.798572 -314.03749) (xy 264.798048 -314.032138) (xy 206.997808 -314.032138) (xy 206.997808 -314.032392)
			(xy 206.997468 -314.037723) (xy 206.989931 -314.045265) (xy 206.9846 -314.0456) (xy 206.468726 -314.0456)
			(xy 206.46085 -314.045872) (xy 206.445847 -314.050667) (xy 206.439262 -314.054998) (xy 206.418182 -314.069385)
			(xy 206.372538 -314.092216) (xy 206.323933 -314.107775) (xy 206.273517 -314.115695) (xy 206.248 -314.116212)
			(xy 206.222479 -314.115737) (xy 206.172052 -314.107838) (xy 206.12344 -314.092273) (xy 206.077802 -314.069415)
			(xy 206.056738 -314.054998) (xy 206.05014 -314.050695) (xy 206.035145 -314.045901) (xy 206.027274 -314.0456)
			(xy 205.5114 -314.0456) (xy 205.506066 -314.045273) (xy 205.498524 -314.037726) (xy 205.498192 -314.032392)
			(xy 202.89774 -314.032392) (xy 202.897203 -314.037646) (xy 202.889785 -314.045087) (xy 202.884532 -314.0456)
			(xy 202.368658 -314.0456) (xy 202.360783 -314.045886) (xy 202.34578 -314.050672) (xy 202.339194 -314.054998)
			(xy 202.318105 -314.069371) (xy 202.272465 -314.092205) (xy 202.223862 -314.107768) (xy 202.173448 -314.115692)
			(xy 202.147932 -314.116212) (xy 202.122412 -314.115721) (xy 202.071985 -314.107827) (xy 202.023374 -314.092267)
			(xy 201.977735 -314.069413) (xy 201.95667 -314.054998) (xy 201.950087 -314.050668) (xy 201.93508 -314.045891)
			(xy 201.927206 -314.0456) (xy 201.411332 -314.0456) (xy 201.406002 -314.045251) (xy 201.398459 -314.037721)
			(xy 201.398124 -314.032392) (xy 199.454008 -314.032392) (xy 199.453668 -314.037723) (xy 199.446131 -314.045265)
			(xy 199.4408 -314.0456) (xy 198.924926 -314.0456) (xy 198.91705 -314.045872) (xy 198.902047 -314.050667)
			(xy 198.895462 -314.054998) (xy 198.874382 -314.069385) (xy 198.828738 -314.092216) (xy 198.780133 -314.107775)
			(xy 198.729717 -314.115695) (xy 198.7042 -314.116212) (xy 198.678679 -314.115737) (xy 198.628252 -314.107838)
			(xy 198.57964 -314.092273) (xy 198.534002 -314.069415) (xy 198.512938 -314.054998) (xy 198.50634 -314.050695)
			(xy 198.491345 -314.045901) (xy 198.483474 -314.0456) (xy 197.9676 -314.0456) (xy 197.962266 -314.045273)
			(xy 197.954724 -314.037726) (xy 197.954392 -314.032392) (xy 195.35394 -314.032392) (xy 195.353403 -314.037646)
			(xy 195.345985 -314.045087) (xy 195.340732 -314.0456) (xy 194.824858 -314.0456) (xy 194.816983 -314.045886)
			(xy 194.80198 -314.050672) (xy 194.795394 -314.054998) (xy 194.774305 -314.069371) (xy 194.728665 -314.092205)
			(xy 194.680062 -314.107768) (xy 194.629648 -314.115692) (xy 194.604132 -314.116212) (xy 194.578612 -314.115721)
			(xy 194.528185 -314.107827) (xy 194.479574 -314.092267) (xy 194.433935 -314.069413) (xy 194.41287 -314.054998)
			(xy 194.406287 -314.050668) (xy 194.39128 -314.045891) (xy 194.383406 -314.0456) (xy 193.867532 -314.0456)
			(xy 193.862202 -314.045251) (xy 193.854659 -314.037721) (xy 193.854324 -314.032392) (xy 191.910208 -314.032392)
			(xy 191.909868 -314.037723) (xy 191.902331 -314.045265) (xy 191.897 -314.0456) (xy 191.896492 -314.0456)
			(xy 191.380872 -314.0456) (xy 191.372998 -314.045892) (xy 191.357994 -314.050673) (xy 191.351408 -314.054998)
			(xy 191.330343 -314.069408) (xy 191.284694 -314.092234) (xy 191.236084 -314.107787) (xy 191.185664 -314.115699)
			(xy 191.160146 -314.116212) (xy 191.134626 -314.115714) (xy 191.0842 -314.107822) (xy 191.035588 -314.092264)
			(xy 190.989949 -314.069412) (xy 190.968884 -314.054998) (xy 190.962298 -314.050674) (xy 190.947294 -314.045893)
			(xy 190.93942 -314.0456) (xy 190.423546 -314.0456) (xy 190.418256 -314.045051) (xy 190.410685 -314.037668)
			(xy 190.410084 -314.032392) (xy 187.81014 -314.032392) (xy 187.809603 -314.037646) (xy 187.802185 -314.045087)
			(xy 187.796932 -314.0456) (xy 187.796424 -314.0456) (xy 187.280804 -314.0456) (xy 187.272931 -314.045905)
			(xy 187.257927 -314.050678) (xy 187.25134 -314.054998) (xy 187.230266 -314.069394) (xy 187.18462 -314.092223)
			(xy 187.136013 -314.10778) (xy 187.085595 -314.115697) (xy 187.060078 -314.116212) (xy 187.034559 -314.115698)
			(xy 186.984133 -314.107811) (xy 186.935521 -314.092258) (xy 186.889882 -314.06941) (xy 186.868816 -314.054998)
			(xy 186.862223 -314.050686) (xy 186.847224 -314.045897) (xy 186.839352 -314.0456) (xy 186.323478 -314.0456)
			(xy 186.318181 -314.045096) (xy 186.310613 -314.037679) (xy 186.310016 -314.032392) (xy 184.3659 -314.032392)
			(xy 184.365567 -314.037725) (xy 184.358025 -314.045267) (xy 184.352692 -314.0456) (xy 183.836818 -314.0456)
			(xy 183.828946 -314.045911) (xy 183.813942 -314.050679) (xy 183.807354 -314.054998) (xy 183.786276 -314.069388)
			(xy 183.740632 -314.092219) (xy 183.692026 -314.107777) (xy 183.641609 -314.115695) (xy 183.616092 -314.116212)
			(xy 183.590573 -314.115691) (xy 183.540148 -314.107806) (xy 183.491536 -314.092255) (xy 183.445896 -314.069409)
			(xy 183.42483 -314.054998) (xy 183.418234 -314.050692) (xy 183.403237 -314.0459) (xy 183.395366 -314.0456)
			(xy 182.879492 -314.0456) (xy 182.874226 -314.04511) (xy 182.866784 -314.037658) (xy 182.866284 -314.032392)
			(xy 180.265832 -314.032392) (xy 180.265303 -314.037648) (xy 180.257879 -314.04509) (xy 180.252624 -314.0456)
			(xy 179.73675 -314.0456) (xy 179.728875 -314.045882) (xy 179.713872 -314.050671) (xy 179.707286 -314.054998)
			(xy 179.686199 -314.069375) (xy 179.640558 -314.092208) (xy 179.591955 -314.10777) (xy 179.54154 -314.115693)
			(xy 179.516024 -314.116212) (xy 179.490504 -314.115725) (xy 179.440077 -314.107829) (xy 179.391465 -314.092269)
			(xy 179.345827 -314.069413) (xy 179.324762 -314.054998) (xy 179.318181 -314.050665) (xy 179.303173 -314.045889)
			(xy 179.295298 -314.0456) (xy 178.779424 -314.0456) (xy 178.774093 -314.045256) (xy 178.76655 -314.037723)
			(xy 178.766216 -314.032392) (xy 176.8221 -314.032392) (xy 176.821767 -314.037725) (xy 176.814225 -314.045267)
			(xy 176.808892 -314.0456) (xy 176.808384 -314.0456) (xy 176.292764 -314.0456) (xy 176.28489 -314.045888)
			(xy 176.269886 -314.050672) (xy 176.2633 -314.054998) (xy 176.242209 -314.069369) (xy 176.196569 -314.092203)
			(xy 176.147968 -314.107767) (xy 176.097554 -314.115692) (xy 176.072038 -314.116212) (xy 176.046518 -314.115718)
			(xy 175.996091 -314.107825) (xy 175.94748 -314.092266) (xy 175.901841 -314.069412) (xy 175.880776 -314.054998)
			(xy 175.874192 -314.050671) (xy 175.859186 -314.045892) (xy 175.851312 -314.0456) (xy 175.335438 -314.0456)
			(xy 175.330148 -314.045056) (xy 175.322577 -314.037669) (xy 175.321976 -314.032392) (xy 172.722032 -314.032392)
			(xy 172.721503 -314.037648) (xy 172.714079 -314.04509) (xy 172.708824 -314.0456) (xy 172.708316 -314.0456)
			(xy 172.192696 -314.0456) (xy 172.184823 -314.045902) (xy 172.169819 -314.050677) (xy 172.163232 -314.054998)
			(xy 172.14216 -314.069398) (xy 172.096514 -314.092226) (xy 172.047906 -314.107782) (xy 171.997487 -314.115697)
			(xy 171.97197 -314.116212) (xy 171.946451 -314.115702) (xy 171.896025 -314.107813) (xy 171.847413 -314.092259)
			(xy 171.801774 -314.06941) (xy 171.780708 -314.054998) (xy 171.774117 -314.050683) (xy 171.759116 -314.045896)
			(xy 171.751244 -314.0456) (xy 171.23537 -314.0456) (xy 171.230071 -314.045102) (xy 171.222504 -314.03768)
			(xy 171.221908 -314.032392) (xy 169.277792 -314.032392) (xy 169.277466 -314.037727) (xy 169.269919 -314.04527)
			(xy 169.264584 -314.0456) (xy 167.791384 -314.0456) (xy 167.786117 -314.045115) (xy 167.778675 -314.03766)
			(xy 167.778176 -314.032392) (xy 165.177724 -314.032392) (xy 165.177202 -314.03765) (xy 165.169773 -314.045092)
			(xy 165.164516 -314.0456) (xy 163.691316 -314.0456) (xy 163.685984 -314.045262) (xy 163.678442 -314.037724)
			(xy 163.678108 -314.032392) (xy 99.07937 -314.032392) (xy 99.085286 -314.052539) (xy 99.093042 -314.106487)
			(xy 99.093528 -314.133738) (xy 99.093528 -314.882784) (xy 163.678108 -314.882784) (xy 163.678108 -314.882276)
			(xy 163.678108 -314.387992) (xy 163.678423 -314.382655) (xy 163.685978 -314.375113) (xy 163.691316 -314.374784)
			(xy 165.164516 -314.374784) (xy 165.169779 -314.375283) (xy 165.17722 -314.382729) (xy 165.177724 -314.387992)
			(xy 165.177724 -314.88253) (xy 171.221908 -314.88253) (xy 171.221908 -314.387992) (xy 171.222223 -314.382655)
			(xy 171.229778 -314.375113) (xy 171.235116 -314.374784) (xy 171.235624 -314.374784) (xy 171.751498 -314.374784)
			(xy 171.759308 -314.374472) (xy 171.77418 -314.369685) (xy 171.780708 -314.365386) (xy 171.801797 -314.351037)
			(xy 171.847458 -314.328306) (xy 171.896064 -314.312847) (xy 171.946467 -314.305024) (xy 171.997473 -314.305024)
			(xy 172.047876 -314.312847) (xy 172.096482 -314.328306) (xy 172.142143 -314.351037) (xy 172.163232 -314.365386)
			(xy 172.169758 -314.369687) (xy 172.184632 -314.374464) (xy 172.192442 -314.374784) (xy 172.70857 -314.374784)
			(xy 172.713881 -314.375248) (xy 172.721456 -314.38269) (xy 172.722032 -314.387992) (xy 172.722032 -314.88253)
			(xy 172.72201 -314.882784) (xy 178.766216 -314.882784) (xy 178.766216 -314.882276) (xy 178.766216 -314.387992)
			(xy 178.766524 -314.382653) (xy 178.774084 -314.375111) (xy 178.779424 -314.374784) (xy 179.295552 -314.374784)
			(xy 179.303361 -314.374453) (xy 179.318232 -314.369679) (xy 179.324762 -314.365386) (xy 179.345851 -314.351037)
			(xy 179.391512 -314.328306) (xy 179.440118 -314.312847) (xy 179.490521 -314.305024) (xy 179.541527 -314.305024)
			(xy 179.59193 -314.312847) (xy 179.640536 -314.328306) (xy 179.686197 -314.351037) (xy 179.707286 -314.365386)
			(xy 179.713822 -314.369669) (xy 179.728689 -314.374458) (xy 179.736496 -314.374784) (xy 180.252624 -314.374784)
			(xy 180.257888 -314.375278) (xy 180.265328 -314.382728) (xy 180.265832 -314.387992) (xy 180.265832 -314.88253)
			(xy 186.310016 -314.88253) (xy 186.310016 -314.387992) (xy 186.310324 -314.382653) (xy 186.317884 -314.375111)
			(xy 186.323224 -314.374784) (xy 186.323732 -314.374784) (xy 186.839606 -314.374784) (xy 186.847417 -314.374476)
			(xy 186.862288 -314.369686) (xy 186.868816 -314.365386) (xy 186.889905 -314.351037) (xy 186.935566 -314.328306)
			(xy 186.984172 -314.312847) (xy 187.034575 -314.305024) (xy 187.085581 -314.305024) (xy 187.135984 -314.312847)
			(xy 187.18459 -314.328306) (xy 187.230251 -314.351037) (xy 187.25134 -314.365386) (xy 187.257864 -314.36969)
			(xy 187.27274 -314.374465) (xy 187.28055 -314.374784) (xy 187.796678 -314.374784) (xy 187.80199 -314.375243)
			(xy 187.809565 -314.382689) (xy 187.81014 -314.387992) (xy 187.81014 -314.88253) (xy 187.810118 -314.882784)
			(xy 193.854324 -314.882784) (xy 193.854324 -314.882276) (xy 193.854324 -314.387992) (xy 193.854624 -314.382651)
			(xy 193.86219 -314.375108) (xy 193.867532 -314.374784) (xy 194.38366 -314.374784) (xy 194.391469 -314.374456)
			(xy 194.40634 -314.36968) (xy 194.41287 -314.365386) (xy 194.433959 -314.351037) (xy 194.47962 -314.328306)
			(xy 194.528226 -314.312847) (xy 194.578629 -314.305024) (xy 194.629635 -314.305024) (xy 194.680038 -314.312847)
			(xy 194.728644 -314.328306) (xy 194.774305 -314.351037) (xy 194.795394 -314.365386) (xy 194.801928 -314.369672)
			(xy 194.816796 -314.374459) (xy 194.824604 -314.374784) (xy 195.340732 -314.374784) (xy 195.345997 -314.375273)
			(xy 195.353437 -314.382726) (xy 195.35394 -314.387992) (xy 195.35394 -314.88253) (xy 195.353919 -314.882784)
			(xy 201.398124 -314.882784) (xy 201.398124 -314.882276) (xy 201.398124 -314.387992) (xy 201.398424 -314.382651)
			(xy 201.40599 -314.375108) (xy 201.411332 -314.374784) (xy 201.92746 -314.374784) (xy 201.935269 -314.374456)
			(xy 201.95014 -314.36968) (xy 201.95667 -314.365386) (xy 201.977759 -314.351037) (xy 202.02342 -314.328306)
			(xy 202.072026 -314.312847) (xy 202.122429 -314.305024) (xy 202.173435 -314.305024) (xy 202.223838 -314.312847)
			(xy 202.272444 -314.328306) (xy 202.318105 -314.351037) (xy 202.339194 -314.365386) (xy 202.345728 -314.369672)
			(xy 202.360596 -314.374459) (xy 202.368404 -314.374784) (xy 202.884532 -314.374784) (xy 202.889797 -314.375273)
			(xy 202.897237 -314.382726) (xy 202.89774 -314.387992) (xy 202.89774 -314.882276) (xy 264.798048 -314.882276)
			(xy 264.798048 -314.387738) (xy 264.798406 -314.382306) (xy 264.806079 -314.374617) (xy 264.81151 -314.374276)
			(xy 265.327638 -314.374276) (xy 265.335446 -314.37394) (xy 265.350318 -314.36917) (xy 265.356848 -314.364878)
			(xy 265.377937 -314.350529) (xy 265.423598 -314.327798) (xy 265.472204 -314.312339) (xy 265.522607 -314.304516)
			(xy 265.573613 -314.304516) (xy 265.624016 -314.312339) (xy 265.672622 -314.327798) (xy 265.718283 -314.350529)
			(xy 265.739372 -314.364878) (xy 265.745912 -314.369155) (xy 265.760775 -314.373947) (xy 265.768582 -314.374276)
			(xy 266.28471 -314.374276) (xy 266.290155 -314.374576) (xy 266.297843 -314.382291) (xy 266.298172 -314.387738)
			(xy 266.298172 -314.882276) (xy 272.342356 -314.882276) (xy 272.342356 -314.387738) (xy 272.34285 -314.382435)
			(xy 272.350272 -314.374861) (xy 272.355564 -314.374276) (xy 272.871692 -314.374276) (xy 272.879502 -314.373963)
			(xy 272.894374 -314.369177) (xy 272.900902 -314.364878) (xy 272.921991 -314.350529) (xy 272.967652 -314.327798)
			(xy 273.016258 -314.312339) (xy 273.066661 -314.304516) (xy 273.117667 -314.304516) (xy 273.16807 -314.312339)
			(xy 273.216676 -314.327798) (xy 273.262337 -314.350529) (xy 273.283426 -314.364878) (xy 273.289954 -314.369176)
			(xy 273.304827 -314.373955) (xy 273.312636 -314.374276) (xy 273.828764 -314.374276) (xy 273.834088 -314.374649)
			(xy 273.84163 -314.382162) (xy 273.841972 -314.387484) (xy 273.841972 -314.387992) (xy 273.841972 -314.882276)
			(xy 279.886156 -314.882276) (xy 279.886156 -314.387738) (xy 279.88665 -314.382435) (xy 279.894072 -314.374861)
			(xy 279.899364 -314.374276) (xy 280.415492 -314.374276) (xy 280.423302 -314.373963) (xy 280.438174 -314.369177)
			(xy 280.444702 -314.364878) (xy 280.465791 -314.350529) (xy 280.511452 -314.327798) (xy 280.560058 -314.312339)
			(xy 280.610461 -314.304516) (xy 280.661467 -314.304516) (xy 280.71187 -314.312339) (xy 280.760476 -314.327798)
			(xy 280.806137 -314.350529) (xy 280.827226 -314.364878) (xy 280.833754 -314.369176) (xy 280.848627 -314.373955)
			(xy 280.856436 -314.374276) (xy 281.372564 -314.374276) (xy 281.377888 -314.374649) (xy 281.38543 -314.382162)
			(xy 281.385772 -314.387484) (xy 281.385772 -314.387992) (xy 281.385772 -314.882276) (xy 287.429956 -314.882276)
			(xy 287.429956 -314.387738) (xy 287.430306 -314.382304) (xy 287.437984 -314.374614) (xy 287.443418 -314.374276)
			(xy 287.959546 -314.374276) (xy 287.967354 -314.373943) (xy 287.982226 -314.369171) (xy 287.988756 -314.364878)
			(xy 288.009845 -314.350529) (xy 288.055506 -314.327798) (xy 288.104112 -314.312339) (xy 288.154515 -314.304516)
			(xy 288.205521 -314.304516) (xy 288.255924 -314.312339) (xy 288.30453 -314.327798) (xy 288.350191 -314.350529)
			(xy 288.37128 -314.364878) (xy 288.377818 -314.369158) (xy 288.392683 -314.373948) (xy 288.40049 -314.374276)
			(xy 288.916618 -314.374276) (xy 288.922065 -314.374571) (xy 288.929752 -314.38229) (xy 288.93008 -314.387738)
			(xy 288.93008 -314.882276) (xy 294.974264 -314.882276) (xy 294.974264 -314.387738) (xy 294.974751 -314.382433)
			(xy 294.982177 -314.374858) (xy 294.987472 -314.374276) (xy 295.5036 -314.374276) (xy 295.511411 -314.373966)
			(xy 295.526282 -314.369178) (xy 295.53281 -314.364878) (xy 295.553899 -314.350529) (xy 295.59956 -314.327798)
			(xy 295.648166 -314.312339) (xy 295.698569 -314.304516) (xy 295.749575 -314.304516) (xy 295.799978 -314.312339)
			(xy 295.848584 -314.327798) (xy 295.894245 -314.350529) (xy 295.915334 -314.364878) (xy 295.92186 -314.369179)
			(xy 295.936734 -314.373956) (xy 295.944544 -314.374276) (xy 296.460672 -314.374276) (xy 296.465997 -314.374644)
			(xy 296.473538 -314.38216) (xy 296.47388 -314.387484) (xy 296.47388 -314.387992) (xy 296.47388 -314.882276)
			(xy 302.518064 -314.882276) (xy 302.518064 -314.387738) (xy 302.518407 -314.382302) (xy 302.52609 -314.374612)
			(xy 302.531526 -314.374276) (xy 304.004726 -314.374276) (xy 304.010174 -314.374565) (xy 304.01786 -314.382289)
			(xy 304.018188 -314.387738) (xy 304.018188 -314.882276) (xy 411.618176 -314.882276) (xy 411.618176 -314.387738)
			(xy 411.618653 -314.38243) (xy 411.626086 -314.374855) (xy 411.631384 -314.374276) (xy 413.104584 -314.374276)
			(xy 413.109841 -314.374804) (xy 413.117284 -314.382228) (xy 413.117792 -314.387484) (xy 413.117792 -314.387992)
			(xy 413.117792 -314.882276) (xy 419.161976 -314.882276) (xy 419.161976 -314.387738) (xy 419.162308 -314.382299)
			(xy 419.169999 -314.374608) (xy 419.175438 -314.374276) (xy 419.691566 -314.374276) (xy 419.699375 -314.373952)
			(xy 419.714247 -314.369174) (xy 419.720776 -314.364878) (xy 419.741865 -314.350529) (xy 419.787526 -314.327798)
			(xy 419.836132 -314.312339) (xy 419.886535 -314.304516) (xy 419.937541 -314.304516) (xy 419.987944 -314.312339)
			(xy 420.03655 -314.327798) (xy 420.082211 -314.350529) (xy 420.1033 -314.364878) (xy 420.109834 -314.369166)
			(xy 420.124702 -314.373951) (xy 420.13251 -314.374276) (xy 420.648638 -314.374276) (xy 420.654016 -314.374729)
			(xy 420.661601 -314.382358) (xy 420.6621 -314.387738) (xy 420.6621 -314.882276) (xy 426.706284 -314.882276)
			(xy 426.706284 -314.387738) (xy 426.706754 -314.382428) (xy 426.714192 -314.374852) (xy 426.719492 -314.374276)
			(xy 427.23562 -314.374276) (xy 427.243431 -314.373975) (xy 427.258303 -314.369181) (xy 427.26483 -314.364878)
			(xy 427.285919 -314.350529) (xy 427.33158 -314.327798) (xy 427.380186 -314.312339) (xy 427.430589 -314.304516)
			(xy 427.481595 -314.304516) (xy 427.531998 -314.312339) (xy 427.580604 -314.327798) (xy 427.626265 -314.350529)
			(xy 427.647354 -314.364878) (xy 427.653876 -314.369186) (xy 427.668753 -314.373959) (xy 427.676564 -314.374276)
			(xy 428.192692 -314.374276) (xy 428.19795 -314.374798) (xy 428.205392 -314.382227) (xy 428.2059 -314.387484)
			(xy 428.2059 -314.387992) (xy 428.2059 -314.882276) (xy 434.250084 -314.882276) (xy 434.250084 -314.387738)
			(xy 434.250409 -314.382297) (xy 434.258105 -314.374606) (xy 434.263546 -314.374276) (xy 434.779674 -314.374276)
			(xy 434.787484 -314.373956) (xy 434.802355 -314.369175) (xy 434.808884 -314.364878) (xy 434.829973 -314.350529)
			(xy 434.875634 -314.327798) (xy 434.92424 -314.312339) (xy 434.974643 -314.304516) (xy 435.025649 -314.304516)
			(xy 435.076052 -314.312339) (xy 435.124658 -314.327798) (xy 435.170319 -314.350529) (xy 435.191408 -314.364878)
			(xy 435.19794 -314.369169) (xy 435.21281 -314.373952) (xy 435.220618 -314.374276) (xy 435.736746 -314.374276)
			(xy 435.742125 -314.374724) (xy 435.74971 -314.382356) (xy 435.750208 -314.387738) (xy 435.750208 -314.882276)
			(xy 441.794392 -314.882276) (xy 441.794392 -314.387738) (xy 441.794943 -314.38245) (xy 441.802325 -314.374879)
			(xy 441.8076 -314.374276) (xy 442.323728 -314.374276) (xy 442.33154 -314.373978) (xy 442.346411 -314.369182)
			(xy 442.352938 -314.364878) (xy 442.374027 -314.350529) (xy 442.419688 -314.327798) (xy 442.468294 -314.312339)
			(xy 442.518697 -314.304516) (xy 442.569703 -314.304516) (xy 442.620106 -314.312339) (xy 442.668712 -314.327798)
			(xy 442.714373 -314.350529) (xy 442.735462 -314.364878) (xy 442.742004 -314.369151) (xy 442.756866 -314.373946)
			(xy 442.764672 -314.374276) (xy 443.2808 -314.374276) (xy 443.286059 -314.374793) (xy 443.2935 -314.382226)
			(xy 443.294008 -314.387484) (xy 443.294008 -314.387992) (xy 443.294008 -314.882276) (xy 449.338192 -314.882276)
			(xy 449.338192 -314.387738) (xy 449.338743 -314.38245) (xy 449.346125 -314.374879) (xy 449.3514 -314.374276)
			(xy 449.867528 -314.374276) (xy 449.87534 -314.373978) (xy 449.890211 -314.369182) (xy 449.896738 -314.364878)
			(xy 449.917827 -314.350529) (xy 449.963488 -314.327798) (xy 450.012094 -314.312339) (xy 450.062497 -314.304516)
			(xy 450.113503 -314.304516) (xy 450.163906 -314.312339) (xy 450.212512 -314.327798) (xy 450.258173 -314.350529)
			(xy 450.279262 -314.364878) (xy 450.285804 -314.369151) (xy 450.300666 -314.373946) (xy 450.308472 -314.374276)
			(xy 450.8246 -314.374276) (xy 450.829859 -314.374793) (xy 450.8373 -314.382226) (xy 450.837808 -314.387484)
			(xy 450.837808 -314.387992) (xy 450.837808 -314.882276) (xy 450.837457 -314.887605) (xy 450.829928 -314.895147)
			(xy 450.8246 -314.895484) (xy 450.308726 -314.895484) (xy 450.300849 -314.895742) (xy 450.285845 -314.900545)
			(xy 450.279262 -314.904882) (xy 450.258188 -314.919279) (xy 450.212542 -314.942105) (xy 450.163935 -314.957661)
			(xy 450.113517 -314.965579) (xy 450.088 -314.966096) (xy 450.062479 -314.965624) (xy 450.012051 -314.957724)
			(xy 449.96344 -314.942159) (xy 449.917802 -314.919299) (xy 449.896738 -314.904882) (xy 449.890141 -314.900577)
			(xy 449.875145 -314.895785) (xy 449.867274 -314.895484) (xy 449.3514 -314.895484) (xy 449.346062 -314.895171)
			(xy 449.338519 -314.887615) (xy 449.338192 -314.882276) (xy 443.294008 -314.882276) (xy 443.293657 -314.887605)
			(xy 443.286128 -314.895147) (xy 443.2808 -314.895484) (xy 442.764926 -314.895484) (xy 442.757049 -314.895742)
			(xy 442.742045 -314.900545) (xy 442.735462 -314.904882) (xy 442.714388 -314.919279) (xy 442.668742 -314.942105)
			(xy 442.620135 -314.957661) (xy 442.569717 -314.965579) (xy 442.5442 -314.966096) (xy 442.518679 -314.965624)
			(xy 442.468251 -314.957724) (xy 442.41964 -314.942159) (xy 442.374002 -314.919299) (xy 442.352938 -314.904882)
			(xy 442.346341 -314.900577) (xy 442.331345 -314.895785) (xy 442.323474 -314.895484) (xy 441.8076 -314.895484)
			(xy 441.802262 -314.895171) (xy 441.794719 -314.887615) (xy 441.794392 -314.882276) (xy 435.750208 -314.882276)
			(xy 435.749857 -314.887605) (xy 435.742328 -314.895147) (xy 435.737 -314.895484) (xy 435.736492 -314.895484)
			(xy 435.220872 -314.895484) (xy 435.212996 -314.895762) (xy 435.197992 -314.900552) (xy 435.191408 -314.904882)
			(xy 435.170349 -314.919302) (xy 435.124697 -314.942123) (xy 435.076086 -314.957673) (xy 435.025664 -314.965583)
			(xy 435.000146 -314.966096) (xy 434.974626 -314.965601) (xy 434.924199 -314.957708) (xy 434.875588 -314.94215)
			(xy 434.829949 -314.919296) (xy 434.808884 -314.904882) (xy 434.802299 -314.900556) (xy 434.787294 -314.895777)
			(xy 434.77942 -314.895484) (xy 434.263546 -314.895484) (xy 434.258253 -314.894949) (xy 434.25068 -314.887556)
			(xy 434.250084 -314.882276) (xy 428.2059 -314.882276) (xy 428.205556 -314.887607) (xy 428.198023 -314.89515)
			(xy 428.192692 -314.895484) (xy 427.676818 -314.895484) (xy 427.668944 -314.895781) (xy 427.65394 -314.900558)
			(xy 427.647354 -314.904882) (xy 427.626282 -314.919282) (xy 427.580635 -314.942108) (xy 427.532027 -314.957663)
			(xy 427.481609 -314.96558) (xy 427.456092 -314.966096) (xy 427.430573 -314.965578) (xy 427.380147 -314.957692)
			(xy 427.331535 -314.94214) (xy 427.285896 -314.919294) (xy 427.26483 -314.904882) (xy 427.258235 -314.900574)
			(xy 427.243237 -314.895783) (xy 427.235366 -314.895484) (xy 426.719492 -314.895484) (xy 426.714153 -314.895176)
			(xy 426.706611 -314.887616) (xy 426.706284 -314.882276) (xy 420.6621 -314.882276) (xy 420.661756 -314.887607)
			(xy 420.654223 -314.89515) (xy 420.648892 -314.895484) (xy 420.648384 -314.895484) (xy 420.132764 -314.895484)
			(xy 420.124888 -314.895758) (xy 420.109884 -314.90055) (xy 420.1033 -314.904882) (xy 420.082216 -314.919263)
			(xy 420.036573 -314.942093) (xy 419.987969 -314.957653) (xy 419.937554 -314.965576) (xy 419.912038 -314.966096)
			(xy 419.886518 -314.965605) (xy 419.836091 -314.957711) (xy 419.787479 -314.942151) (xy 419.741841 -314.919297)
			(xy 419.720776 -314.904882) (xy 419.714193 -314.900553) (xy 419.699186 -314.895775) (xy 419.691312 -314.895484)
			(xy 419.175438 -314.895484) (xy 419.170144 -314.894954) (xy 419.162572 -314.887557) (xy 419.161976 -314.882276)
			(xy 413.117792 -314.882276) (xy 413.117455 -314.887609) (xy 413.109917 -314.895152) (xy 413.104584 -314.895484)
			(xy 411.631384 -314.895484) (xy 411.626044 -314.895182) (xy 411.618502 -314.887617) (xy 411.618176 -314.882276)
			(xy 304.018188 -314.882276) (xy 304.017855 -314.88761) (xy 304.010314 -314.895153) (xy 304.00498 -314.895484)
			(xy 302.531526 -314.895484) (xy 302.526231 -314.894962) (xy 302.518659 -314.887559) (xy 302.518064 -314.882276)
			(xy 296.47388 -314.882276) (xy 296.473554 -314.887612) (xy 296.466008 -314.895156) (xy 296.460672 -314.895484)
			(xy 295.944798 -314.895484) (xy 295.936923 -314.895773) (xy 295.921919 -314.900555) (xy 295.915334 -314.904882)
			(xy 295.894268 -314.919291) (xy 295.848619 -314.942114) (xy 295.800009 -314.957667) (xy 295.74959 -314.965581)
			(xy 295.724072 -314.966096) (xy 295.698553 -314.965588) (xy 295.648126 -314.957699) (xy 295.599515 -314.942145)
			(xy 295.553876 -314.919295) (xy 295.53281 -314.904882) (xy 295.526219 -314.900566) (xy 295.511218 -314.89578)
			(xy 295.503346 -314.895484) (xy 294.987472 -314.895484) (xy 294.9822 -314.895022) (xy 294.974758 -314.88755)
			(xy 294.974264 -314.882276) (xy 288.93008 -314.882276) (xy 288.929754 -314.887612) (xy 288.922208 -314.895156)
			(xy 288.916872 -314.895484) (xy 288.916364 -314.895484) (xy 288.400744 -314.895484) (xy 288.392867 -314.89575)
			(xy 288.377863 -314.900548) (xy 288.37128 -314.904882) (xy 288.350201 -314.919271) (xy 288.304556 -314.942099)
			(xy 288.255951 -314.957657) (xy 288.205534 -314.965578) (xy 288.180018 -314.966096) (xy 288.154497 -314.965615)
			(xy 288.10407 -314.957718) (xy 288.055459 -314.942156) (xy 288.009821 -314.919298) (xy 287.988756 -314.904882)
			(xy 287.982177 -314.900545) (xy 287.967167 -314.895772) (xy 287.959292 -314.895484) (xy 287.443418 -314.895484)
			(xy 287.438122 -314.894968) (xy 287.430551 -314.887561) (xy 287.429956 -314.882276) (xy 281.385772 -314.882276)
			(xy 281.385453 -314.887614) (xy 281.377902 -314.895158) (xy 281.372564 -314.895484) (xy 280.85669 -314.895484)
			(xy 280.848815 -314.895769) (xy 280.833811 -314.900554) (xy 280.827226 -314.904882) (xy 280.806162 -314.919294)
			(xy 280.760512 -314.942117) (xy 280.711902 -314.957669) (xy 280.661482 -314.965582) (xy 280.635964 -314.966096)
			(xy 280.610444 -314.965592) (xy 280.560018 -314.957702) (xy 280.511406 -314.942146) (xy 280.465767 -314.919295)
			(xy 280.444702 -314.904882) (xy 280.438113 -314.900563) (xy 280.423111 -314.895779) (xy 280.415238 -314.895484)
			(xy 279.899364 -314.895484) (xy 279.894091 -314.895027) (xy 279.886649 -314.887551) (xy 279.886156 -314.882276)
			(xy 273.841972 -314.882276) (xy 273.841653 -314.887614) (xy 273.834102 -314.895158) (xy 273.828764 -314.895484)
			(xy 273.31289 -314.895484) (xy 273.305015 -314.895769) (xy 273.290011 -314.900554) (xy 273.283426 -314.904882)
			(xy 273.262362 -314.919294) (xy 273.216712 -314.942117) (xy 273.168102 -314.957669) (xy 273.117682 -314.965582)
			(xy 273.092164 -314.966096) (xy 273.066644 -314.965592) (xy 273.016218 -314.957702) (xy 272.967606 -314.942146)
			(xy 272.921967 -314.919295) (xy 272.900902 -314.904882) (xy 272.894313 -314.900563) (xy 272.879311 -314.895779)
			(xy 272.871438 -314.895484) (xy 272.355564 -314.895484) (xy 272.350291 -314.895027) (xy 272.342849 -314.887551)
			(xy 272.342356 -314.882276) (xy 266.298172 -314.882276) (xy 266.297853 -314.887614) (xy 266.290302 -314.895158)
			(xy 266.284964 -314.895484) (xy 266.284456 -314.895484) (xy 265.768836 -314.895484) (xy 265.760959 -314.895746)
			(xy 265.745955 -314.900547) (xy 265.739372 -314.904882) (xy 265.718295 -314.919275) (xy 265.67265 -314.942102)
			(xy 265.624044 -314.957659) (xy 265.573627 -314.965578) (xy 265.54811 -314.966096) (xy 265.522589 -314.965619)
			(xy 265.472162 -314.957721) (xy 265.42355 -314.942157) (xy 265.377912 -314.919299) (xy 265.356848 -314.904882)
			(xy 265.350271 -314.900542) (xy 265.33526 -314.895771) (xy 265.327384 -314.895484) (xy 264.81151 -314.895484)
			(xy 264.806213 -314.894973) (xy 264.798642 -314.887562) (xy 264.798048 -314.882276) (xy 202.89774 -314.882276)
			(xy 202.89774 -314.88253) (xy 202.897295 -314.887843) (xy 202.889836 -314.895413) (xy 202.884532 -314.895992)
			(xy 202.368658 -314.895992) (xy 202.36085 -314.896332) (xy 202.345979 -314.9011) (xy 202.339448 -314.90539)
			(xy 202.318341 -314.919762) (xy 202.272612 -314.942483) (xy 202.223934 -314.957906) (xy 202.173464 -314.965666)
			(xy 202.147932 -314.966096) (xy 202.122403 -314.965638) (xy 202.07194 -314.957867) (xy 202.023268 -314.942445)
			(xy 201.977539 -314.919734) (xy 201.956416 -314.90539) (xy 201.949881 -314.901105) (xy 201.935014 -314.896318)
			(xy 201.927206 -314.895992) (xy 201.411332 -314.895992) (xy 201.406 -314.89565) (xy 201.398456 -314.888115)
			(xy 201.398124 -314.882784) (xy 195.353919 -314.882784) (xy 195.353495 -314.887843) (xy 195.346036 -314.895413)
			(xy 195.340732 -314.895992) (xy 194.824858 -314.895992) (xy 194.81705 -314.896332) (xy 194.802179 -314.9011)
			(xy 194.795648 -314.90539) (xy 194.774541 -314.919762) (xy 194.728812 -314.942483) (xy 194.680134 -314.957906)
			(xy 194.629664 -314.965666) (xy 194.604132 -314.966096) (xy 194.578603 -314.965638) (xy 194.52814 -314.957867)
			(xy 194.479468 -314.942445) (xy 194.433739 -314.919734) (xy 194.412616 -314.90539) (xy 194.406081 -314.901105)
			(xy 194.391214 -314.896318) (xy 194.383406 -314.895992) (xy 193.867532 -314.895992) (xy 193.8622 -314.89565)
			(xy 193.854656 -314.888115) (xy 193.854324 -314.882784) (xy 187.810118 -314.882784) (xy 187.809667 -314.887903)
			(xy 187.802053 -314.895488) (xy 187.796678 -314.895992) (xy 187.280804 -314.895992) (xy 187.272994 -314.896309)
			(xy 187.258123 -314.901093) (xy 187.251594 -314.90539) (xy 187.230475 -314.919743) (xy 187.18475 -314.942467)
			(xy 187.136076 -314.957896) (xy 187.085609 -314.965663) (xy 187.060078 -314.966096) (xy 187.034548 -314.965665)
			(xy 186.984084 -314.957886) (xy 186.935412 -314.942455) (xy 186.889684 -314.919738) (xy 186.868562 -314.90539)
			(xy 186.862039 -314.901084) (xy 186.847162 -314.896311) (xy 186.839352 -314.895992) (xy 186.323478 -314.895992)
			(xy 186.318119 -314.895467) (xy 186.310536 -314.887889) (xy 186.310016 -314.88253) (xy 180.265832 -314.88253)
			(xy 180.265394 -314.887845) (xy 180.257931 -314.895416) (xy 180.252624 -314.895992) (xy 179.73675 -314.895992)
			(xy 179.728942 -314.896328) (xy 179.71407 -314.901099) (xy 179.70754 -314.90539) (xy 179.686436 -314.919766)
			(xy 179.640705 -314.942485) (xy 179.592027 -314.957908) (xy 179.541556 -314.965667) (xy 179.516024 -314.966096)
			(xy 179.490495 -314.965642) (xy 179.440032 -314.95787) (xy 179.391359 -314.942446) (xy 179.345631 -314.919735)
			(xy 179.324508 -314.90539) (xy 179.317975 -314.901102) (xy 179.303106 -314.896317) (xy 179.295298 -314.895992)
			(xy 178.779424 -314.895992) (xy 178.774091 -314.895655) (xy 178.766548 -314.888117) (xy 178.766216 -314.882784)
			(xy 172.72201 -314.882784) (xy 172.721567 -314.887905) (xy 172.713947 -314.895491) (xy 172.70857 -314.895992)
			(xy 172.192696 -314.895992) (xy 172.184886 -314.896305) (xy 172.170015 -314.901092) (xy 172.163486 -314.90539)
			(xy 172.142369 -314.919746) (xy 172.096643 -314.94247) (xy 172.047968 -314.957898) (xy 171.997501 -314.965663)
			(xy 171.97197 -314.966096) (xy 171.946439 -314.965669) (xy 171.895975 -314.957889) (xy 171.847303 -314.942457)
			(xy 171.801576 -314.919738) (xy 171.780454 -314.90539) (xy 171.773933 -314.901081) (xy 171.759055 -314.896309)
			(xy 171.751244 -314.895992) (xy 171.23537 -314.895992) (xy 171.23001 -314.895473) (xy 171.222427 -314.88789)
			(xy 171.221908 -314.88253) (xy 165.177724 -314.88253) (xy 165.177293 -314.887846) (xy 165.169825 -314.895418)
			(xy 165.164516 -314.895992) (xy 163.691316 -314.895992) (xy 163.685982 -314.895661) (xy 163.678439 -314.888118)
			(xy 163.678108 -314.882784) (xy 99.093528 -314.882784) (xy 99.093528 -314.997338) (xy 99.093042 -315.024589)
			(xy 99.085286 -315.078537) (xy 99.069931 -315.130832) (xy 99.047289 -315.180409) (xy 99.017823 -315.226259)
			(xy 98.982132 -315.26745) (xy 98.940941 -315.303141) (xy 98.895091 -315.332607) (xy 98.845514 -315.355249)
			(xy 98.793219 -315.370604) (xy 98.739271 -315.37836) (xy 98.684769 -315.37836) (xy 98.630821 -315.370604)
			(xy 98.578526 -315.355249) (xy 98.528949 -315.332607) (xy 98.483099 -315.303141) (xy 98.441908 -315.26745)
			(xy 98.406217 -315.226259) (xy 98.376751 -315.180409) (xy 98.354109 -315.130832) (xy 98.338754 -315.078537)
			(xy 98.330998 -315.024589) (xy 98.330512 -314.997338) (xy 2.509012 -314.997338) (xy 2.509012 -315.732414)
			(xy 20.958048 -315.732414) (xy 20.958048 -315.237876) (xy 20.958574 -315.232621) (xy 20.966002 -315.225182)
			(xy 20.971256 -315.224668) (xy 20.971764 -315.224668) (xy 21.487638 -315.224668) (xy 21.495446 -315.224333)
			(xy 21.510318 -315.219562) (xy 21.516848 -315.21527) (xy 21.537937 -315.200921) (xy 21.583598 -315.17819)
			(xy 21.632204 -315.162731) (xy 21.682607 -315.154908) (xy 21.733613 -315.154908) (xy 21.784016 -315.162731)
			(xy 21.832622 -315.17819) (xy 21.878283 -315.200921) (xy 21.899372 -315.21527) (xy 21.905912 -315.219546)
			(xy 21.920776 -315.224339) (xy 21.928582 -315.224668) (xy 22.44471 -315.224668) (xy 22.450022 -315.22512)
			(xy 22.457594 -315.232573) (xy 22.458172 -315.237876) (xy 22.458172 -315.732414) (xy 22.458148 -315.732668)
			(xy 28.502356 -315.732668) (xy 28.502356 -315.73216) (xy 28.502356 -315.237876) (xy 28.502875 -315.232619)
			(xy 28.510308 -315.22518) (xy 28.515564 -315.224668) (xy 29.031692 -315.224668) (xy 29.039502 -315.224356)
			(xy 29.054374 -315.21957) (xy 29.060902 -315.21527) (xy 29.081991 -315.200921) (xy 29.127652 -315.17819)
			(xy 29.176258 -315.162731) (xy 29.226661 -315.154908) (xy 29.277667 -315.154908) (xy 29.32807 -315.162731)
			(xy 29.376676 -315.17819) (xy 29.422337 -315.200921) (xy 29.443426 -315.21527) (xy 29.449954 -315.219567)
			(xy 29.464827 -315.224347) (xy 29.472636 -315.224668) (xy 29.988764 -315.224668) (xy 29.994086 -315.225049)
			(xy 30.001627 -315.232556) (xy 30.001972 -315.237876) (xy 30.001972 -315.732414) (xy 30.001949 -315.732668)
			(xy 36.046156 -315.732668) (xy 36.046156 -315.73216) (xy 36.046156 -315.237876) (xy 36.046675 -315.232619)
			(xy 36.054108 -315.22518) (xy 36.059364 -315.224668) (xy 36.575492 -315.224668) (xy 36.583302 -315.224356)
			(xy 36.598174 -315.21957) (xy 36.604702 -315.21527) (xy 36.625791 -315.200921) (xy 36.671452 -315.17819)
			(xy 36.720058 -315.162731) (xy 36.770461 -315.154908) (xy 36.821467 -315.154908) (xy 36.87187 -315.162731)
			(xy 36.920476 -315.17819) (xy 36.966137 -315.200921) (xy 36.987226 -315.21527) (xy 36.993754 -315.219567)
			(xy 37.008627 -315.224347) (xy 37.016436 -315.224668) (xy 37.532564 -315.224668) (xy 37.537886 -315.225049)
			(xy 37.545427 -315.232556) (xy 37.545772 -315.237876) (xy 37.545772 -315.732414) (xy 43.589956 -315.732414)
			(xy 43.589956 -315.237876) (xy 43.590475 -315.232619) (xy 43.597908 -315.22518) (xy 43.603164 -315.224668)
			(xy 43.603672 -315.224668) (xy 44.119546 -315.224668) (xy 44.127355 -315.224337) (xy 44.142226 -315.219563)
			(xy 44.148756 -315.21527) (xy 44.169845 -315.200921) (xy 44.215506 -315.17819) (xy 44.264112 -315.162731)
			(xy 44.314515 -315.154908) (xy 44.365521 -315.154908) (xy 44.415924 -315.162731) (xy 44.46453 -315.17819)
			(xy 44.510191 -315.200921) (xy 44.53128 -315.21527) (xy 44.537819 -315.219549) (xy 44.552683 -315.22434)
			(xy 44.56049 -315.224668) (xy 45.076618 -315.224668) (xy 45.081931 -315.225114) (xy 45.089503 -315.232571)
			(xy 45.09008 -315.237876) (xy 45.09008 -315.732414) (xy 45.090055 -315.732668) (xy 51.134264 -315.732668)
			(xy 51.134264 -315.73216) (xy 51.134264 -315.237876) (xy 51.134776 -315.232617) (xy 51.142213 -315.225178)
			(xy 51.147472 -315.224668) (xy 51.6636 -315.224668) (xy 51.671411 -315.22436) (xy 51.686282 -315.219571)
			(xy 51.69281 -315.21527) (xy 51.713899 -315.200921) (xy 51.75956 -315.17819) (xy 51.808166 -315.162731)
			(xy 51.858569 -315.154908) (xy 51.909575 -315.154908) (xy 51.959978 -315.162731) (xy 52.008584 -315.17819)
			(xy 52.054245 -315.200921) (xy 52.075334 -315.21527) (xy 52.081861 -315.21957) (xy 52.096734 -315.224348)
			(xy 52.104544 -315.224668) (xy 52.620672 -315.224668) (xy 52.625995 -315.225043) (xy 52.633536 -315.232555)
			(xy 52.63388 -315.237876) (xy 52.63388 -315.732414) (xy 58.678064 -315.732414) (xy 58.678064 -315.237876)
			(xy 58.678576 -315.232617) (xy 58.686013 -315.225178) (xy 58.691272 -315.224668) (xy 58.69178 -315.224668)
			(xy 60.164726 -315.224668) (xy 60.17004 -315.225109) (xy 60.177611 -315.23257) (xy 60.178188 -315.237876)
			(xy 60.178188 -315.732414) (xy 60.178163 -315.732668) (xy 167.778176 -315.732668) (xy 167.778176 -315.237876)
			(xy 167.778677 -315.232614) (xy 167.786122 -315.225174) (xy 167.791384 -315.224668) (xy 169.264584 -315.224668)
			(xy 169.269839 -315.225203) (xy 169.277281 -315.232622) (xy 169.277792 -315.237876) (xy 169.277792 -315.732414)
			(xy 175.321976 -315.732414) (xy 175.321976 -315.237876) (xy 175.322477 -315.232614) (xy 175.329922 -315.225174)
			(xy 175.335184 -315.224668) (xy 175.335692 -315.224668) (xy 175.851566 -315.224668) (xy 175.859375 -315.224345)
			(xy 175.874247 -315.219566) (xy 175.880776 -315.21527) (xy 175.901865 -315.200921) (xy 175.947526 -315.17819)
			(xy 175.996132 -315.162731) (xy 176.046535 -315.154908) (xy 176.097541 -315.154908) (xy 176.147944 -315.162731)
			(xy 176.19655 -315.17819) (xy 176.242211 -315.200921) (xy 176.2633 -315.21527) (xy 176.269834 -315.219557)
			(xy 176.284702 -315.224343) (xy 176.29251 -315.224668) (xy 176.808638 -315.224668) (xy 176.813953 -315.225101)
			(xy 176.821524 -315.232568) (xy 176.8221 -315.237876) (xy 176.8221 -315.732414) (xy 176.822075 -315.732668)
			(xy 182.866284 -315.732668) (xy 182.866284 -315.73216) (xy 182.866284 -315.237876) (xy 182.866778 -315.232612)
			(xy 182.874228 -315.225172) (xy 182.879492 -315.224668) (xy 183.39562 -315.224668) (xy 183.403431 -315.224368)
			(xy 183.418303 -315.219573) (xy 183.42483 -315.21527) (xy 183.445919 -315.200921) (xy 183.49158 -315.17819)
			(xy 183.540186 -315.162731) (xy 183.590589 -315.154908) (xy 183.641595 -315.154908) (xy 183.691998 -315.162731)
			(xy 183.740604 -315.17819) (xy 183.786265 -315.200921) (xy 183.807354 -315.21527) (xy 183.813876 -315.219578)
			(xy 183.828753 -315.224351) (xy 183.836564 -315.224668) (xy 184.352692 -315.224668) (xy 184.357948 -315.225197)
			(xy 184.36539 -315.232621) (xy 184.3659 -315.237876) (xy 184.3659 -315.732414) (xy 190.410084 -315.732414)
			(xy 190.410084 -315.237876) (xy 190.410578 -315.232612) (xy 190.418028 -315.225172) (xy 190.423292 -315.224668)
			(xy 190.4238 -315.224668) (xy 190.939674 -315.224668) (xy 190.947484 -315.224348) (xy 190.962355 -315.219567)
			(xy 190.968884 -315.21527) (xy 190.989973 -315.200921) (xy 191.035634 -315.17819) (xy 191.08424 -315.162731)
			(xy 191.134643 -315.154908) (xy 191.185649 -315.154908) (xy 191.236052 -315.162731) (xy 191.284658 -315.17819)
			(xy 191.330319 -315.200921) (xy 191.351408 -315.21527) (xy 191.35794 -315.21956) (xy 191.37281 -315.224344)
			(xy 191.380618 -315.224668) (xy 191.896746 -315.224668) (xy 191.90205 -315.225162) (xy 191.909626 -315.232583)
			(xy 191.910208 -315.237876) (xy 191.910208 -315.732414) (xy 191.910182 -315.732668) (xy 197.954392 -315.732668)
			(xy 197.954392 -315.73216) (xy 197.954392 -315.237876) (xy 197.954879 -315.23261) (xy 197.962334 -315.225169)
			(xy 197.9676 -315.224668) (xy 198.483728 -315.224668) (xy 198.49154 -315.224372) (xy 198.506411 -315.219574)
			(xy 198.512938 -315.21527) (xy 198.534027 -315.200921) (xy 198.579688 -315.17819) (xy 198.628294 -315.162731)
			(xy 198.678697 -315.154908) (xy 198.729703 -315.154908) (xy 198.780106 -315.162731) (xy 198.828712 -315.17819)
			(xy 198.874373 -315.200921) (xy 198.895462 -315.21527) (xy 198.902005 -315.219542) (xy 198.916866 -315.224337)
			(xy 198.924672 -315.224668) (xy 199.4408 -315.224668) (xy 199.446057 -315.225192) (xy 199.453498 -315.23262)
			(xy 199.454008 -315.237876) (xy 199.454008 -315.732414) (xy 199.453983 -315.732668) (xy 205.498192 -315.732668)
			(xy 205.498192 -315.73216) (xy 205.498192 -315.237876) (xy 205.498679 -315.23261) (xy 205.506134 -315.225169)
			(xy 205.5114 -315.224668) (xy 206.027528 -315.224668) (xy 206.03534 -315.224372) (xy 206.050211 -315.219574)
			(xy 206.056738 -315.21527) (xy 206.077827 -315.200921) (xy 206.123488 -315.17819) (xy 206.172094 -315.162731)
			(xy 206.222497 -315.154908) (xy 206.273503 -315.154908) (xy 206.323906 -315.162731) (xy 206.372512 -315.17819)
			(xy 206.418173 -315.200921) (xy 206.439262 -315.21527) (xy 206.445805 -315.219542) (xy 206.460666 -315.224337)
			(xy 206.468472 -315.224668) (xy 206.9846 -315.224668) (xy 206.989857 -315.225192) (xy 206.997298 -315.23262)
			(xy 206.997808 -315.237876) (xy 206.997808 -315.73216) (xy 268.898116 -315.73216) (xy 268.898116 -315.237622)
			(xy 268.898663 -315.232266) (xy 268.906224 -315.22468) (xy 268.911578 -315.22416) (xy 269.427706 -315.22416)
			(xy 269.435517 -315.223856) (xy 269.450389 -315.219064) (xy 269.456916 -315.214762) (xy 269.478005 -315.200413)
			(xy 269.523666 -315.177682) (xy 269.572272 -315.162223) (xy 269.622675 -315.1544) (xy 269.673681 -315.1544)
			(xy 269.724084 -315.162223) (xy 269.77269 -315.177682) (xy 269.818351 -315.200413) (xy 269.83944 -315.214762)
			(xy 269.845966 -315.219064) (xy 269.86084 -315.223841) (xy 269.86865 -315.22416) (xy 270.384778 -315.22416)
			(xy 270.390215 -315.224496) (xy 270.397904 -315.232185) (xy 270.39824 -315.237622) (xy 270.39824 -315.73216)
			(xy 276.442424 -315.73216) (xy 276.442424 -315.237622) (xy 276.442936 -315.232324) (xy 276.450346 -315.224753)
			(xy 276.455632 -315.22416) (xy 276.97176 -315.22416) (xy 276.979569 -315.223836) (xy 276.994441 -315.219058)
			(xy 277.00097 -315.214762) (xy 277.022059 -315.200413) (xy 277.06772 -315.177682) (xy 277.116326 -315.162223)
			(xy 277.166729 -315.1544) (xy 277.217735 -315.1544) (xy 277.268138 -315.162223) (xy 277.316744 -315.177682)
			(xy 277.362405 -315.200413) (xy 277.383494 -315.214762) (xy 277.39003 -315.219046) (xy 277.404896 -315.223834)
			(xy 277.412704 -315.22416) (xy 277.928832 -315.22416) (xy 277.934091 -315.22467) (xy 277.94153 -315.232109)
			(xy 277.94204 -315.237368) (xy 277.94204 -315.237876) (xy 277.94204 -315.73216) (xy 283.986224 -315.73216)
			(xy 283.986224 -315.237622) (xy 283.986736 -315.232324) (xy 283.994146 -315.224753) (xy 283.999432 -315.22416)
			(xy 284.51556 -315.22416) (xy 284.523369 -315.223836) (xy 284.538241 -315.219058) (xy 284.54477 -315.214762)
			(xy 284.565859 -315.200413) (xy 284.61152 -315.177682) (xy 284.660126 -315.162223) (xy 284.710529 -315.1544)
			(xy 284.761535 -315.1544) (xy 284.811938 -315.162223) (xy 284.860544 -315.177682) (xy 284.906205 -315.200413)
			(xy 284.927294 -315.214762) (xy 284.93383 -315.219046) (xy 284.948696 -315.223834) (xy 284.956504 -315.22416)
			(xy 285.472632 -315.22416) (xy 285.477891 -315.22467) (xy 285.48533 -315.232109) (xy 285.48584 -315.237368)
			(xy 285.48584 -315.237876) (xy 285.48584 -315.73216) (xy 291.530024 -315.73216) (xy 291.530024 -315.237622)
			(xy 291.530393 -315.232194) (xy 291.538059 -315.224507) (xy 291.543486 -315.22416) (xy 292.059614 -315.22416)
			(xy 292.067425 -315.223859) (xy 292.082297 -315.219065) (xy 292.088824 -315.214762) (xy 292.109913 -315.200413)
			(xy 292.155574 -315.177682) (xy 292.20418 -315.162223) (xy 292.254583 -315.1544) (xy 292.305589 -315.1544)
			(xy 292.355992 -315.162223) (xy 292.404598 -315.177682) (xy 292.450259 -315.200413) (xy 292.471348 -315.214762)
			(xy 292.477872 -315.219067) (xy 292.492748 -315.223842) (xy 292.500558 -315.22416) (xy 293.016686 -315.22416)
			(xy 293.022124 -315.224491) (xy 293.029812 -315.232184) (xy 293.030148 -315.237622) (xy 293.030148 -315.73216)
			(xy 299.074332 -315.73216) (xy 299.074332 -315.237622) (xy 299.074837 -315.232322) (xy 299.082251 -315.22475)
			(xy 299.08754 -315.22416) (xy 299.603668 -315.22416) (xy 299.611478 -315.223839) (xy 299.626349 -315.219059)
			(xy 299.632878 -315.214762) (xy 299.653967 -315.200413) (xy 299.699628 -315.177682) (xy 299.748234 -315.162223)
			(xy 299.798637 -315.1544) (xy 299.849643 -315.1544) (xy 299.900046 -315.162223) (xy 299.948652 -315.177682)
			(xy 299.994313 -315.200413) (xy 300.015402 -315.214762) (xy 300.021936 -315.219049) (xy 300.036804 -315.223835)
			(xy 300.044612 -315.22416) (xy 300.56074 -315.22416) (xy 300.566 -315.224665) (xy 300.573438 -315.232108)
			(xy 300.573948 -315.237368) (xy 300.573948 -315.237876) (xy 300.573948 -315.73216) (xy 306.618132 -315.73216)
			(xy 306.618132 -315.237622) (xy 306.618494 -315.232192) (xy 306.626164 -315.224505) (xy 306.631594 -315.22416)
			(xy 308.104794 -315.22416) (xy 308.110233 -315.224485) (xy 308.117921 -315.232182) (xy 308.118256 -315.237622)
			(xy 308.118256 -315.73216) (xy 415.718244 -315.73216) (xy 415.718244 -315.237622) (xy 415.718738 -315.232319)
			(xy 415.72616 -315.224747) (xy 415.731452 -315.22416) (xy 417.204652 -315.22416) (xy 417.20997 -315.224556)
			(xy 417.217512 -315.232052) (xy 417.21786 -315.237368) (xy 417.21786 -315.73216) (xy 423.262044 -315.73216)
			(xy 423.262044 -315.237622) (xy 423.262395 -315.232189) (xy 423.270073 -315.224501) (xy 423.275506 -315.22416)
			(xy 423.791634 -315.22416) (xy 423.799442 -315.223825) (xy 423.814314 -315.219054) (xy 423.820844 -315.214762)
			(xy 423.841933 -315.200413) (xy 423.887594 -315.177682) (xy 423.9362 -315.162223) (xy 423.986603 -315.1544)
			(xy 424.037609 -315.1544) (xy 424.088012 -315.162223) (xy 424.136618 -315.177682) (xy 424.182279 -315.200413)
			(xy 424.203368 -315.214762) (xy 424.20991 -315.219036) (xy 424.224772 -315.22383) (xy 424.232578 -315.22416)
			(xy 424.748706 -315.22416) (xy 424.754147 -315.224478) (xy 424.761834 -315.23218) (xy 424.762168 -315.237622)
			(xy 424.762168 -315.73216) (xy 430.806352 -315.73216) (xy 430.806352 -315.237622) (xy 430.806839 -315.232318)
			(xy 430.814266 -315.224744) (xy 430.81956 -315.22416) (xy 431.335688 -315.22416) (xy 431.343498 -315.223848)
			(xy 431.35837 -315.219062) (xy 431.364898 -315.214762) (xy 431.385987 -315.200413) (xy 431.431648 -315.177682)
			(xy 431.480254 -315.162223) (xy 431.530657 -315.1544) (xy 431.581663 -315.1544) (xy 431.632066 -315.162223)
			(xy 431.680672 -315.177682) (xy 431.726333 -315.200413) (xy 431.747422 -315.214762) (xy 431.753952 -315.219057)
			(xy 431.768823 -315.223838) (xy 431.776632 -315.22416) (xy 432.29276 -315.22416) (xy 432.298079 -315.224551)
			(xy 432.30562 -315.232051) (xy 432.305968 -315.237368) (xy 432.305968 -315.237876) (xy 432.305968 -315.73216)
			(xy 438.350152 -315.73216) (xy 438.350152 -315.237622) (xy 438.350496 -315.232187) (xy 438.358179 -315.224499)
			(xy 438.363614 -315.22416) (xy 438.879742 -315.22416) (xy 438.887551 -315.223828) (xy 438.902422 -315.219055)
			(xy 438.908952 -315.214762) (xy 438.930041 -315.200413) (xy 438.975702 -315.177682) (xy 439.024308 -315.162223)
			(xy 439.074711 -315.1544) (xy 439.125717 -315.1544) (xy 439.17612 -315.162223) (xy 439.224726 -315.177682)
			(xy 439.270387 -315.200413) (xy 439.291476 -315.214762) (xy 439.298016 -315.219039) (xy 439.312879 -315.223831)
			(xy 439.320686 -315.22416) (xy 439.836814 -315.22416) (xy 439.842256 -315.224472) (xy 439.849942 -315.232179)
			(xy 439.850276 -315.237622) (xy 439.850276 -315.73216) (xy 445.89446 -315.73216) (xy 445.89446 -315.237622)
			(xy 445.89494 -315.232316) (xy 445.902372 -315.224742) (xy 445.907668 -315.22416) (xy 446.423796 -315.22416)
			(xy 446.431607 -315.223852) (xy 446.446478 -315.219063) (xy 446.453006 -315.214762) (xy 446.474095 -315.200413)
			(xy 446.519756 -315.177682) (xy 446.568362 -315.162223) (xy 446.618765 -315.1544) (xy 446.669771 -315.1544)
			(xy 446.720174 -315.162223) (xy 446.76878 -315.177682) (xy 446.814441 -315.200413) (xy 446.83553 -315.214762)
			(xy 446.842058 -315.21906) (xy 446.856931 -315.223839) (xy 446.86474 -315.22416) (xy 447.380868 -315.22416)
			(xy 447.386119 -315.224713) (xy 447.393562 -315.232119) (xy 447.394076 -315.237368) (xy 447.394076 -315.237876)
			(xy 447.394076 -315.73216) (xy 453.43826 -315.73216) (xy 453.43826 -315.237622) (xy 453.43874 -315.232316)
			(xy 453.446172 -315.224742) (xy 453.451468 -315.22416) (xy 453.967596 -315.22416) (xy 453.975407 -315.223852)
			(xy 453.990278 -315.219063) (xy 453.996806 -315.214762) (xy 454.017895 -315.200413) (xy 454.063556 -315.177682)
			(xy 454.112162 -315.162223) (xy 454.162565 -315.1544) (xy 454.213571 -315.1544) (xy 454.263974 -315.162223)
			(xy 454.31258 -315.177682) (xy 454.358241 -315.200413) (xy 454.37933 -315.214762) (xy 454.385858 -315.21906)
			(xy 454.400731 -315.223839) (xy 454.40854 -315.22416) (xy 454.924668 -315.22416) (xy 454.929919 -315.224713)
			(xy 454.937362 -315.232119) (xy 454.937876 -315.237368) (xy 454.937876 -315.237876) (xy 454.937876 -315.73216)
			(xy 454.937543 -315.737495) (xy 454.930002 -315.74504) (xy 454.924668 -315.745368) (xy 454.408794 -315.745368)
			(xy 454.40092 -315.745658) (xy 454.385915 -315.75044) (xy 454.37933 -315.754766) (xy 454.358264 -315.769175)
			(xy 454.312615 -315.791999) (xy 454.264005 -315.807552) (xy 454.213586 -315.815465) (xy 454.188068 -315.81598)
			(xy 454.162548 -315.815477) (xy 454.112122 -315.807587) (xy 454.06351 -315.792031) (xy 454.017871 -315.76918)
			(xy 453.996806 -315.754766) (xy 453.990211 -315.750457) (xy 453.975214 -315.745665) (xy 453.967342 -315.745368)
			(xy 453.451468 -315.745368) (xy 453.446122 -315.745091) (xy 453.43858 -315.737508) (xy 453.43826 -315.73216)
			(xy 447.394076 -315.73216) (xy 447.393743 -315.737495) (xy 447.386202 -315.74504) (xy 447.380868 -315.745368)
			(xy 446.864994 -315.745368) (xy 446.85712 -315.745658) (xy 446.842115 -315.75044) (xy 446.83553 -315.754766)
			(xy 446.814464 -315.769175) (xy 446.768815 -315.791999) (xy 446.720205 -315.807552) (xy 446.669786 -315.815465)
			(xy 446.644268 -315.81598) (xy 446.618748 -315.815477) (xy 446.568322 -315.807587) (xy 446.51971 -315.792031)
			(xy 446.474071 -315.76918) (xy 446.453006 -315.754766) (xy 446.446411 -315.750457) (xy 446.431414 -315.745665)
			(xy 446.423542 -315.745368) (xy 445.907668 -315.745368) (xy 445.902322 -315.745091) (xy 445.89478 -315.737508)
			(xy 445.89446 -315.73216) (xy 439.850276 -315.73216) (xy 439.849943 -315.737495) (xy 439.842402 -315.74504)
			(xy 439.837068 -315.745368) (xy 439.83656 -315.745368) (xy 439.32094 -315.745368) (xy 439.313064 -315.745635)
			(xy 439.29806 -315.750433) (xy 439.291476 -315.754766) (xy 439.270397 -315.769155) (xy 439.224753 -315.791983)
			(xy 439.176147 -315.807542) (xy 439.125731 -315.815462) (xy 439.100214 -315.81598) (xy 439.074693 -315.815504)
			(xy 439.024266 -315.807606) (xy 438.975654 -315.792042) (xy 438.930016 -315.769183) (xy 438.908952 -315.754766)
			(xy 438.902369 -315.750436) (xy 438.887363 -315.745657) (xy 438.879488 -315.745368) (xy 438.363614 -315.745368)
			(xy 438.358313 -315.744868) (xy 438.350742 -315.73745) (xy 438.350152 -315.73216) (xy 432.305968 -315.73216)
			(xy 432.305642 -315.737497) (xy 432.298097 -315.745042) (xy 432.29276 -315.745368) (xy 431.776886 -315.745368)
			(xy 431.769011 -315.745654) (xy 431.754007 -315.750439) (xy 431.747422 -315.754766) (xy 431.726358 -315.769178)
			(xy 431.680708 -315.792001) (xy 431.632098 -315.807553) (xy 431.581678 -315.815466) (xy 431.55616 -315.81598)
			(xy 431.53064 -315.815481) (xy 431.480213 -315.80759) (xy 431.431602 -315.792033) (xy 431.385963 -315.76918)
			(xy 431.364898 -315.754766) (xy 431.358305 -315.750454) (xy 431.343306 -315.745664) (xy 431.335434 -315.745368)
			(xy 430.81956 -315.745368) (xy 430.814283 -315.744928) (xy 430.80684 -315.73744) (xy 430.806352 -315.73216)
			(xy 424.762168 -315.73216) (xy 424.761842 -315.737497) (xy 424.754297 -315.745042) (xy 424.74896 -315.745368)
			(xy 424.748452 -315.745368) (xy 424.232832 -315.745368) (xy 424.224955 -315.745631) (xy 424.209951 -315.750431)
			(xy 424.203368 -315.754766) (xy 424.182291 -315.769159) (xy 424.136646 -315.791986) (xy 424.08804 -315.807544)
			(xy 424.037623 -315.815463) (xy 424.012106 -315.81598) (xy 423.986585 -315.815508) (xy 423.936157 -315.807609)
			(xy 423.887546 -315.792044) (xy 423.841908 -315.769184) (xy 423.820844 -315.754766) (xy 423.814263 -315.750433)
			(xy 423.799255 -315.745656) (xy 423.79138 -315.745368) (xy 423.275506 -315.745368) (xy 423.270204 -315.744874)
			(xy 423.262633 -315.737451) (xy 423.262044 -315.73216) (xy 417.21786 -315.73216) (xy 417.217541 -315.737499)
			(xy 417.209991 -315.745045) (xy 417.204652 -315.745368) (xy 415.731452 -315.745368) (xy 415.726174 -315.744933)
			(xy 415.718732 -315.737441) (xy 415.718244 -315.73216) (xy 308.118256 -315.73216) (xy 308.117684 -315.737407)
			(xy 308.110291 -315.744849) (xy 308.105048 -315.745368) (xy 308.10454 -315.745368) (xy 306.631594 -315.745368)
			(xy 306.626291 -315.744882) (xy 306.618721 -315.737453) (xy 306.618132 -315.73216) (xy 300.573948 -315.73216)
			(xy 300.573383 -315.737408) (xy 300.565985 -315.744851) (xy 300.56074 -315.745368) (xy 300.044866 -315.745368)
			(xy 300.036991 -315.745646) (xy 300.021986 -315.750436) (xy 300.015402 -315.754766) (xy 299.994316 -315.769144)
			(xy 299.948674 -315.791975) (xy 299.900071 -315.807536) (xy 299.849656 -315.81546) (xy 299.82414 -315.81598)
			(xy 299.79862 -315.815491) (xy 299.748193 -315.807597) (xy 299.699581 -315.792037) (xy 299.653943 -315.769182)
			(xy 299.632878 -315.754766) (xy 299.626289 -315.750446) (xy 299.611287 -315.745661) (xy 299.603414 -315.745368)
			(xy 299.08754 -315.745368) (xy 299.082203 -315.745042) (xy 299.074658 -315.737497) (xy 299.074332 -315.73216)
			(xy 293.030148 -315.73216) (xy 293.029583 -315.737408) (xy 293.022185 -315.744851) (xy 293.01694 -315.745368)
			(xy 293.016432 -315.745368) (xy 292.500812 -315.745368) (xy 292.492938 -315.745665) (xy 292.477934 -315.750442)
			(xy 292.471348 -315.754766) (xy 292.450277 -315.769167) (xy 292.40463 -315.791993) (xy 292.356022 -315.807548)
			(xy 292.305603 -315.815464) (xy 292.280086 -315.81598) (xy 292.254567 -315.815468) (xy 292.20414 -315.807581)
			(xy 292.155529 -315.792027) (xy 292.10989 -315.769179) (xy 292.088824 -315.754766) (xy 292.082225 -315.750464)
			(xy 292.067231 -315.745668) (xy 292.05936 -315.745368) (xy 291.543486 -315.745368) (xy 291.538182 -315.744887)
			(xy 291.530612 -315.737454) (xy 291.530024 -315.73216) (xy 285.48584 -315.73216) (xy 285.485449 -315.737479)
			(xy 285.477949 -315.74502) (xy 285.472632 -315.745368) (xy 284.956758 -315.745368) (xy 284.948882 -315.745642)
			(xy 284.933878 -315.750435) (xy 284.927294 -315.754766) (xy 284.90621 -315.769147) (xy 284.860567 -315.791978)
			(xy 284.811963 -315.807538) (xy 284.761548 -315.815461) (xy 284.736032 -315.81598) (xy 284.710512 -315.815495)
			(xy 284.660084 -315.8076) (xy 284.611473 -315.792038) (xy 284.565835 -315.769182) (xy 284.54477 -315.754766)
			(xy 284.538183 -315.750443) (xy 284.52318 -315.74566) (xy 284.515306 -315.745368) (xy 283.999432 -315.745368)
			(xy 283.994094 -315.745048) (xy 283.986549 -315.737498) (xy 283.986224 -315.73216) (xy 277.94204 -315.73216)
			(xy 277.941649 -315.737479) (xy 277.934149 -315.74502) (xy 277.928832 -315.745368) (xy 277.412958 -315.745368)
			(xy 277.405082 -315.745642) (xy 277.390078 -315.750435) (xy 277.383494 -315.754766) (xy 277.36241 -315.769147)
			(xy 277.316767 -315.791978) (xy 277.268163 -315.807538) (xy 277.217748 -315.815461) (xy 277.192232 -315.81598)
			(xy 277.166712 -315.815495) (xy 277.116284 -315.8076) (xy 277.067673 -315.792038) (xy 277.022035 -315.769182)
			(xy 277.00097 -315.754766) (xy 276.994383 -315.750443) (xy 276.97938 -315.74566) (xy 276.971506 -315.745368)
			(xy 276.455632 -315.745368) (xy 276.450294 -315.745048) (xy 276.442749 -315.737498) (xy 276.442424 -315.73216)
			(xy 270.39824 -315.73216) (xy 270.397849 -315.737479) (xy 270.390349 -315.74502) (xy 270.385032 -315.745368)
			(xy 270.384524 -315.745368) (xy 269.868904 -315.745368) (xy 269.86103 -315.745662) (xy 269.846026 -315.750441)
			(xy 269.83944 -315.754766) (xy 269.818371 -315.769171) (xy 269.772723 -315.791995) (xy 269.724114 -315.80755)
			(xy 269.673695 -315.815465) (xy 269.648178 -315.81598) (xy 269.622659 -315.815472) (xy 269.572232 -315.807584)
			(xy 269.52362 -315.792029) (xy 269.477981 -315.769179) (xy 269.456916 -315.754766) (xy 269.450319 -315.750461)
			(xy 269.435323 -315.745667) (xy 269.427452 -315.745368) (xy 268.911578 -315.745368) (xy 268.906273 -315.744892)
			(xy 268.898704 -315.737455) (xy 268.898116 -315.73216) (xy 206.997808 -315.73216) (xy 206.997808 -315.732414)
			(xy 206.997292 -315.737709) (xy 206.989883 -315.745276) (xy 206.9846 -315.745876) (xy 206.468726 -315.745876)
			(xy 206.460916 -315.746188) (xy 206.446044 -315.750974) (xy 206.439516 -315.755274) (xy 206.418389 -315.769615)
			(xy 206.372667 -315.792343) (xy 206.323995 -315.807775) (xy 206.27353 -315.815545) (xy 206.248 -315.81598)
			(xy 206.22247 -315.815541) (xy 206.172006 -315.807765) (xy 206.123334 -315.792337) (xy 206.077606 -315.769621)
			(xy 206.056484 -315.755274) (xy 206.049951 -315.750985) (xy 206.035082 -315.746199) (xy 206.027274 -315.745876)
			(xy 205.5114 -315.745876) (xy 205.50606 -315.74557) (xy 205.498517 -315.738009) (xy 205.498192 -315.732668)
			(xy 199.453983 -315.732668) (xy 199.453492 -315.737709) (xy 199.446083 -315.745276) (xy 199.4408 -315.745876)
			(xy 198.924926 -315.745876) (xy 198.917116 -315.746188) (xy 198.902244 -315.750974) (xy 198.895716 -315.755274)
			(xy 198.874589 -315.769615) (xy 198.828867 -315.792343) (xy 198.780195 -315.807775) (xy 198.72973 -315.815545)
			(xy 198.7042 -315.81598) (xy 198.67867 -315.815541) (xy 198.628206 -315.807765) (xy 198.579534 -315.792337)
			(xy 198.533806 -315.769621) (xy 198.512684 -315.755274) (xy 198.506151 -315.750985) (xy 198.491282 -315.746199)
			(xy 198.483474 -315.745876) (xy 197.9676 -315.745876) (xy 197.96226 -315.74557) (xy 197.954717 -315.738009)
			(xy 197.954392 -315.732668) (xy 191.910182 -315.732668) (xy 191.909663 -315.737768) (xy 191.902099 -315.745351)
			(xy 191.896746 -315.745876) (xy 191.380872 -315.745876) (xy 191.373059 -315.746165) (xy 191.358188 -315.750967)
			(xy 191.351662 -315.755274) (xy 191.33055 -315.769638) (xy 191.284823 -315.792361) (xy 191.236146 -315.807787)
			(xy 191.185678 -315.815549) (xy 191.160146 -315.81598) (xy 191.134617 -315.815518) (xy 191.084154 -315.807749)
			(xy 191.035482 -315.792327) (xy 190.989753 -315.769618) (xy 190.96863 -315.755274) (xy 190.962087 -315.751003)
			(xy 190.947226 -315.746206) (xy 190.93942 -315.745876) (xy 190.423546 -315.745876) (xy 190.418121 -315.745491)
			(xy 190.410433 -315.737838) (xy 190.410084 -315.732414) (xy 184.3659 -315.732414) (xy 184.365391 -315.737711)
			(xy 184.357977 -315.745279) (xy 184.352692 -315.745876) (xy 183.836818 -315.745876) (xy 183.829007 -315.746185)
			(xy 183.814135 -315.750973) (xy 183.807608 -315.755274) (xy 183.786483 -315.769619) (xy 183.74076 -315.792346)
			(xy 183.692088 -315.807777) (xy 183.641623 -315.815546) (xy 183.616092 -315.81598) (xy 183.590562 -315.815545)
			(xy 183.540098 -315.807768) (xy 183.491426 -315.792338) (xy 183.445698 -315.769622) (xy 183.424576 -315.755274)
			(xy 183.418045 -315.750982) (xy 183.403175 -315.746198) (xy 183.395366 -315.745876) (xy 182.879492 -315.745876)
			(xy 182.874151 -315.745576) (xy 182.866608 -315.73801) (xy 182.866284 -315.732668) (xy 176.822075 -315.732668)
			(xy 176.821563 -315.73777) (xy 176.813993 -315.745353) (xy 176.808638 -315.745876) (xy 176.292764 -315.745876)
			(xy 176.284955 -315.746204) (xy 176.270083 -315.750979) (xy 176.263554 -315.755274) (xy 176.242444 -315.769642)
			(xy 176.196716 -315.792364) (xy 176.148039 -315.807788) (xy 176.09757 -315.81555) (xy 176.072038 -315.81598)
			(xy 176.046509 -315.815522) (xy 175.996046 -315.807752) (xy 175.947373 -315.792329) (xy 175.901645 -315.769619)
			(xy 175.880522 -315.755274) (xy 175.873981 -315.751) (xy 175.859118 -315.746205) (xy 175.851312 -315.745876)
			(xy 175.335438 -315.745876) (xy 175.330012 -315.745497) (xy 175.322324 -315.737839) (xy 175.321976 -315.732414)
			(xy 169.277792 -315.732414) (xy 169.27729 -315.737712) (xy 169.269871 -315.745281) (xy 169.264584 -315.745876)
			(xy 167.791384 -315.745876) (xy 167.786042 -315.745581) (xy 167.7785 -315.738012) (xy 167.778176 -315.732668)
			(xy 60.178163 -315.732668) (xy 60.177661 -315.737773) (xy 60.170085 -315.745357) (xy 60.164726 -315.745876)
			(xy 58.691526 -315.745876) (xy 58.686098 -315.745505) (xy 58.678411 -315.737841) (xy 58.678064 -315.732414)
			(xy 52.63388 -315.732414) (xy 52.633388 -315.737715) (xy 52.625963 -315.745284) (xy 52.620672 -315.745876)
			(xy 52.104798 -315.745876) (xy 52.096986 -315.746176) (xy 52.082115 -315.75097) (xy 52.075588 -315.755274)
			(xy 52.054469 -315.769627) (xy 52.008744 -315.792352) (xy 51.96007 -315.807781) (xy 51.909603 -315.815547)
			(xy 51.884072 -315.81598) (xy 51.858541 -315.815555) (xy 51.808077 -315.807775) (xy 51.759405 -315.792342)
			(xy 51.713678 -315.769623) (xy 51.692556 -315.755274) (xy 51.686029 -315.750974) (xy 51.671156 -315.746195)
			(xy 51.663346 -315.745876) (xy 51.147472 -315.745876) (xy 51.142128 -315.745589) (xy 51.134587 -315.738013)
			(xy 51.134264 -315.732668) (xy 45.090055 -315.732668) (xy 45.089561 -315.737775) (xy 45.081979 -315.745359)
			(xy 45.076618 -315.745876) (xy 44.560744 -315.745876) (xy 44.552934 -315.746196) (xy 44.538062 -315.750976)
			(xy 44.531534 -315.755274) (xy 44.51043 -315.769651) (xy 44.4647 -315.79237) (xy 44.416021 -315.807793)
			(xy 44.36555 -315.815551) (xy 44.340018 -315.81598) (xy 44.314488 -315.815532) (xy 44.264025 -315.807759)
			(xy 44.215353 -315.792333) (xy 44.169624 -315.76962) (xy 44.148502 -315.755274) (xy 44.141965 -315.750992)
			(xy 44.127099 -315.746202) (xy 44.119292 -315.745876) (xy 43.603418 -315.745876) (xy 43.597989 -315.74551)
			(xy 43.590303 -315.737842) (xy 43.589956 -315.732414) (xy 37.545772 -315.732414) (xy 37.545287 -315.737717)
			(xy 37.537857 -315.745286) (xy 37.532564 -315.745876) (xy 37.01669 -315.745876) (xy 37.008878 -315.746173)
			(xy 36.994006 -315.750969) (xy 36.98748 -315.755274) (xy 36.966363 -315.769631) (xy 36.920637 -315.792355)
			(xy 36.871963 -315.807783) (xy 36.821495 -315.815548) (xy 36.795964 -315.81598) (xy 36.770433 -315.815559)
			(xy 36.719969 -315.807778) (xy 36.671297 -315.792344) (xy 36.62557 -315.769623) (xy 36.604448 -315.755274)
			(xy 36.597923 -315.750971) (xy 36.583048 -315.746194) (xy 36.575238 -315.745876) (xy 36.059364 -315.745876)
			(xy 36.054089 -315.745426) (xy 36.046647 -315.737945) (xy 36.046156 -315.732668) (xy 30.001949 -315.732668)
			(xy 30.001487 -315.737717) (xy 29.994057 -315.745286) (xy 29.988764 -315.745876) (xy 29.47289 -315.745876)
			(xy 29.465078 -315.746173) (xy 29.450206 -315.750969) (xy 29.44368 -315.755274) (xy 29.422563 -315.769631)
			(xy 29.376837 -315.792355) (xy 29.328163 -315.807783) (xy 29.277695 -315.815548) (xy 29.252164 -315.81598)
			(xy 29.226633 -315.815559) (xy 29.176169 -315.807778) (xy 29.127497 -315.792344) (xy 29.08177 -315.769623)
			(xy 29.060648 -315.755274) (xy 29.054123 -315.750971) (xy 29.039248 -315.746194) (xy 29.031438 -315.745876)
			(xy 28.515564 -315.745876) (xy 28.510289 -315.745426) (xy 28.502847 -315.737945) (xy 28.502356 -315.732668)
			(xy 22.458148 -315.732668) (xy 22.45766 -315.737777) (xy 22.450073 -315.745361) (xy 22.44471 -315.745876)
			(xy 21.928836 -315.745876) (xy 21.921026 -315.746192) (xy 21.906154 -315.750975) (xy 21.899626 -315.755274)
			(xy 21.878496 -315.769611) (xy 21.832775 -315.79234) (xy 21.784104 -315.807773) (xy 21.73364 -315.815544)
			(xy 21.70811 -315.81598) (xy 21.68258 -315.815536) (xy 21.632117 -315.807762) (xy 21.583444 -315.792335)
			(xy 21.537716 -315.76962) (xy 21.516594 -315.755274) (xy 21.510059 -315.750989) (xy 21.495192 -315.746201)
			(xy 21.487384 -315.745876) (xy 20.97151 -315.745876) (xy 20.966151 -315.745344) (xy 20.958565 -315.737772)
			(xy 20.958048 -315.732414) (xy 2.509012 -315.732414) (xy 2.509012 -316.582552) (xy 16.85798 -316.582552)
			(xy 16.85798 -316.088014) (xy 16.858293 -316.082571) (xy 16.865998 -316.074882) (xy 16.871442 -316.074552)
			(xy 17.38757 -316.074552) (xy 17.39538 -316.074233) (xy 17.410251 -316.069452) (xy 17.41678 -316.065154)
			(xy 17.437869 -316.050805) (xy 17.48353 -316.028074) (xy 17.532136 -316.012615) (xy 17.582539 -316.004792)
			(xy 17.633545 -316.004792) (xy 17.683948 -316.012615) (xy 17.732554 -316.028074) (xy 17.778215 -316.050805)
			(xy 17.799304 -316.065154) (xy 17.805838 -316.069441) (xy 17.820706 -316.074227) (xy 17.828514 -316.074552)
			(xy 18.344642 -316.074552) (xy 18.350014 -316.075024) (xy 18.357599 -316.08264) (xy 18.358104 -316.088014)
			(xy 18.358104 -316.582552) (xy 24.402288 -316.582552) (xy 24.402288 -316.088014) (xy 24.402738 -316.0827)
			(xy 24.410191 -316.075126) (xy 24.415496 -316.074552) (xy 24.931624 -316.074552) (xy 24.939436 -316.074257)
			(xy 24.954308 -316.069459) (xy 24.960834 -316.065154) (xy 24.981923 -316.050805) (xy 25.027584 -316.028074)
			(xy 25.07619 -316.012615) (xy 25.126593 -316.004792) (xy 25.177599 -316.004792) (xy 25.228002 -316.012615)
			(xy 25.276608 -316.028074) (xy 25.322269 -316.050805) (xy 25.343358 -316.065154) (xy 25.34988 -316.069462)
			(xy 25.364757 -316.074235) (xy 25.372568 -316.074552) (xy 25.888696 -316.074552) (xy 25.893949 -316.075093)
			(xy 25.901389 -316.082509) (xy 25.901904 -316.08776) (xy 25.901904 -316.088268) (xy 25.901904 -316.582552)
			(xy 31.946088 -316.582552) (xy 31.946088 -316.088014) (xy 31.946538 -316.0827) (xy 31.953991 -316.075126)
			(xy 31.959296 -316.074552) (xy 32.475424 -316.074552) (xy 32.483236 -316.074257) (xy 32.498108 -316.069459)
			(xy 32.504634 -316.065154) (xy 32.525723 -316.050805) (xy 32.571384 -316.028074) (xy 32.61999 -316.012615)
			(xy 32.670393 -316.004792) (xy 32.721399 -316.004792) (xy 32.771802 -316.012615) (xy 32.820408 -316.028074)
			(xy 32.866069 -316.050805) (xy 32.887158 -316.065154) (xy 32.89368 -316.069462) (xy 32.908557 -316.074235)
			(xy 32.916368 -316.074552) (xy 33.432496 -316.074552) (xy 33.437749 -316.075093) (xy 33.445189 -316.082509)
			(xy 33.445704 -316.08776) (xy 33.445704 -316.088268) (xy 33.445704 -316.582552) (xy 39.489888 -316.582552)
			(xy 39.489888 -316.088014) (xy 39.490455 -316.082664) (xy 39.498002 -316.07508) (xy 39.50335 -316.074552)
			(xy 40.019478 -316.074552) (xy 40.027288 -316.074237) (xy 40.04216 -316.069453) (xy 40.048688 -316.065154)
			(xy 40.069777 -316.050805) (xy 40.115438 -316.028074) (xy 40.164044 -316.012615) (xy 40.214447 -316.004792)
			(xy 40.265453 -316.004792) (xy 40.315856 -316.012615) (xy 40.364462 -316.028074) (xy 40.410123 -316.050805)
			(xy 40.431212 -316.065154) (xy 40.437744 -316.069444) (xy 40.452614 -316.074229) (xy 40.460422 -316.074552)
			(xy 40.97655 -316.074552) (xy 40.981923 -316.075019) (xy 40.989507 -316.082638) (xy 40.990012 -316.088014)
			(xy 40.990012 -316.582552) (xy 47.034196 -316.582552) (xy 47.034196 -316.088014) (xy 47.034727 -316.082722)
			(xy 47.042124 -316.075152) (xy 47.047404 -316.074552) (xy 47.563532 -316.074552) (xy 47.57134 -316.074217)
			(xy 47.586212 -316.069447) (xy 47.592742 -316.065154) (xy 47.613831 -316.050805) (xy 47.659492 -316.028074)
			(xy 47.708098 -316.012615) (xy 47.758501 -316.004792) (xy 47.809507 -316.004792) (xy 47.85991 -316.012615)
			(xy 47.908516 -316.028074) (xy 47.954177 -316.050805) (xy 47.975266 -316.065154) (xy 47.981809 -316.069426)
			(xy 47.99667 -316.074222) (xy 48.004476 -316.074552) (xy 48.520604 -316.074552) (xy 48.525858 -316.075088)
			(xy 48.533298 -316.082508) (xy 48.533812 -316.08776) (xy 48.533812 -316.088268) (xy 48.533812 -316.582552)
			(xy 54.577996 -316.582552) (xy 54.577996 -316.088014) (xy 54.578555 -316.082662) (xy 54.586108 -316.075078)
			(xy 54.591458 -316.074552) (xy 56.064658 -316.074552) (xy 56.070091 -316.074909) (xy 56.07778 -316.082582)
			(xy 56.07812 -316.088014) (xy 56.07812 -316.582552) (xy 163.678108 -316.582552) (xy 163.678108 -316.088014)
			(xy 163.678629 -316.082719) (xy 163.686033 -316.075149) (xy 163.691316 -316.074552) (xy 165.164516 -316.074552)
			(xy 165.169771 -316.07508) (xy 165.177211 -316.082506) (xy 165.177724 -316.08776) (xy 165.177724 -316.088268)
			(xy 165.177724 -316.582552) (xy 171.221908 -316.582552) (xy 171.221908 -316.088014) (xy 171.222457 -316.082659)
			(xy 171.230017 -316.075074) (xy 171.23537 -316.074552) (xy 171.751498 -316.074552) (xy 171.759309 -316.074246)
			(xy 171.774181 -316.069456) (xy 171.780708 -316.065154) (xy 171.801797 -316.050805) (xy 171.847458 -316.028074)
			(xy 171.896064 -316.012615) (xy 171.946467 -316.004792) (xy 171.997473 -316.004792) (xy 172.047876 -316.012615)
			(xy 172.096482 -316.028074) (xy 172.142143 -316.050805) (xy 172.163232 -316.065154) (xy 172.16976 -316.069452)
			(xy 172.184633 -316.074231) (xy 172.192442 -316.074552) (xy 172.70857 -316.074552) (xy 172.714004 -316.074901)
			(xy 172.721693 -316.08258) (xy 172.722032 -316.088014) (xy 172.722032 -316.582552) (xy 178.766216 -316.582552)
			(xy 178.766216 -316.088014) (xy 178.76673 -316.082717) (xy 178.774139 -316.075147) (xy 178.779424 -316.074552)
			(xy 179.295552 -316.074552) (xy 179.303361 -316.074226) (xy 179.318233 -316.069449) (xy 179.324762 -316.065154)
			(xy 179.345851 -316.050805) (xy 179.391512 -316.028074) (xy 179.440118 -316.012615) (xy 179.490521 -316.004792)
			(xy 179.541527 -316.004792) (xy 179.59193 -316.012615) (xy 179.640536 -316.028074) (xy 179.686197 -316.050805)
			(xy 179.707286 -316.065154) (xy 179.713824 -316.069434) (xy 179.728689 -316.074225) (xy 179.736496 -316.074552)
			(xy 180.252624 -316.074552) (xy 180.25788 -316.075075) (xy 180.265319 -316.082505) (xy 180.265832 -316.08776)
			(xy 180.265832 -316.088268) (xy 180.265832 -316.582552) (xy 186.310016 -316.582552) (xy 186.310016 -316.088014)
			(xy 186.310557 -316.082657) (xy 186.318122 -316.075072) (xy 186.323478 -316.074552) (xy 186.839606 -316.074552)
			(xy 186.847417 -316.074249) (xy 186.862289 -316.069457) (xy 186.868816 -316.065154) (xy 186.889905 -316.050805)
			(xy 186.935566 -316.028074) (xy 186.984172 -316.012615) (xy 187.034575 -316.004792) (xy 187.085581 -316.004792)
			(xy 187.135984 -316.012615) (xy 187.18459 -316.028074) (xy 187.230251 -316.050805) (xy 187.25134 -316.065154)
			(xy 187.257866 -316.069455) (xy 187.27274 -316.074233) (xy 187.28055 -316.074552) (xy 187.796678 -316.074552)
			(xy 187.802113 -316.074896) (xy 187.809801 -316.082579) (xy 187.81014 -316.088014) (xy 187.81014 -316.582552)
			(xy 193.854324 -316.582552) (xy 193.854324 -316.088014) (xy 193.854831 -316.082715) (xy 193.862245 -316.075144)
			(xy 193.867532 -316.074552) (xy 194.38366 -316.074552) (xy 194.391469 -316.074229) (xy 194.406341 -316.06945)
			(xy 194.41287 -316.065154) (xy 194.433959 -316.050805) (xy 194.47962 -316.028074) (xy 194.528226 -316.012615)
			(xy 194.578629 -316.004792) (xy 194.629635 -316.004792) (xy 194.680038 -316.012615) (xy 194.728644 -316.028074)
			(xy 194.774305 -316.050805) (xy 194.795394 -316.065154) (xy 194.80193 -316.069437) (xy 194.816797 -316.074226)
			(xy 194.824604 -316.074552) (xy 195.340732 -316.074552) (xy 195.345989 -316.075069) (xy 195.353427 -316.082503)
			(xy 195.35394 -316.08776) (xy 195.35394 -316.088268) (xy 195.35394 -316.582552) (xy 201.398124 -316.582552)
			(xy 201.398124 -316.088014) (xy 201.398631 -316.082715) (xy 201.406045 -316.075144) (xy 201.411332 -316.074552)
			(xy 201.92746 -316.074552) (xy 201.935269 -316.074229) (xy 201.950141 -316.06945) (xy 201.95667 -316.065154)
			(xy 201.977759 -316.050805) (xy 202.02342 -316.028074) (xy 202.072026 -316.012615) (xy 202.122429 -316.004792)
			(xy 202.173435 -316.004792) (xy 202.223838 -316.012615) (xy 202.272444 -316.028074) (xy 202.318105 -316.050805)
			(xy 202.339194 -316.065154) (xy 202.34573 -316.069437) (xy 202.360597 -316.074226) (xy 202.368404 -316.074552)
			(xy 202.884532 -316.074552) (xy 202.889789 -316.075069) (xy 202.897227 -316.082503) (xy 202.89774 -316.08776)
			(xy 202.89774 -316.088268) (xy 202.89774 -316.582298) (xy 264.798048 -316.582298) (xy 264.798048 -316.08776)
			(xy 264.798564 -316.082503) (xy 264.805999 -316.075065) (xy 264.811256 -316.074552) (xy 264.811764 -316.074552)
			(xy 265.327638 -316.074552) (xy 265.335447 -316.07422) (xy 265.350318 -316.069447) (xy 265.356848 -316.065154)
			(xy 265.377937 -316.050805) (xy 265.423598 -316.028074) (xy 265.472204 -316.012615) (xy 265.522607 -316.004792)
			(xy 265.573613 -316.004792) (xy 265.624016 -316.012615) (xy 265.672622 -316.028074) (xy 265.718283 -316.050805)
			(xy 265.739372 -316.065154) (xy 265.745913 -316.069429) (xy 265.760776 -316.074223) (xy 265.768582 -316.074552)
			(xy 266.28471 -316.074552) (xy 266.290018 -316.075018) (xy 266.297589 -316.082461) (xy 266.298172 -316.08776)
			(xy 266.298172 -316.582298) (xy 266.298147 -316.582552) (xy 272.342356 -316.582552) (xy 272.342356 -316.582044)
			(xy 272.342356 -316.08776) (xy 272.342864 -316.082501) (xy 272.350305 -316.075063) (xy 272.355564 -316.074552)
			(xy 272.871692 -316.074552) (xy 272.879503 -316.074243) (xy 272.894374 -316.069454) (xy 272.900902 -316.065154)
			(xy 272.921991 -316.050805) (xy 272.967652 -316.028074) (xy 273.016258 -316.012615) (xy 273.066661 -316.004792)
			(xy 273.117667 -316.004792) (xy 273.16807 -316.012615) (xy 273.216676 -316.028074) (xy 273.262337 -316.050805)
			(xy 273.283426 -316.065154) (xy 273.289955 -316.069449) (xy 273.304827 -316.074231) (xy 273.312636 -316.074552)
			(xy 273.828764 -316.074552) (xy 273.834013 -316.075115) (xy 273.841455 -316.082514) (xy 273.841972 -316.08776)
			(xy 273.841972 -316.582298) (xy 273.841948 -316.582552) (xy 279.886156 -316.582552) (xy 279.886156 -316.582044)
			(xy 279.886156 -316.08776) (xy 279.886664 -316.082501) (xy 279.894105 -316.075063) (xy 279.899364 -316.074552)
			(xy 280.415492 -316.074552) (xy 280.423303 -316.074243) (xy 280.438174 -316.069454) (xy 280.444702 -316.065154)
			(xy 280.465791 -316.050805) (xy 280.511452 -316.028074) (xy 280.560058 -316.012615) (xy 280.610461 -316.004792)
			(xy 280.661467 -316.004792) (xy 280.71187 -316.012615) (xy 280.760476 -316.028074) (xy 280.806137 -316.050805)
			(xy 280.827226 -316.065154) (xy 280.833755 -316.069449) (xy 280.848627 -316.074231) (xy 280.856436 -316.074552)
			(xy 281.372564 -316.074552) (xy 281.377813 -316.075115) (xy 281.385255 -316.082514) (xy 281.385772 -316.08776)
			(xy 281.385772 -316.582298) (xy 287.429956 -316.582298) (xy 287.429956 -316.08776) (xy 287.430464 -316.082501)
			(xy 287.437905 -316.075063) (xy 287.443164 -316.074552) (xy 287.443672 -316.074552) (xy 287.959546 -316.074552)
			(xy 287.967355 -316.074223) (xy 287.982227 -316.069448) (xy 287.988756 -316.065154) (xy 288.009845 -316.050805)
			(xy 288.055506 -316.028074) (xy 288.104112 -316.012615) (xy 288.154515 -316.004792) (xy 288.205521 -316.004792)
			(xy 288.255924 -316.012615) (xy 288.30453 -316.028074) (xy 288.350191 -316.050805) (xy 288.37128 -316.065154)
			(xy 288.377819 -316.069432) (xy 288.392683 -316.074224) (xy 288.40049 -316.074552) (xy 288.916618 -316.074552)
			(xy 288.921927 -316.075012) (xy 288.929498 -316.08246) (xy 288.93008 -316.08776) (xy 288.93008 -316.582298)
			(xy 288.930055 -316.582552) (xy 294.974264 -316.582552) (xy 294.974264 -316.582044) (xy 294.974264 -316.08776)
			(xy 294.974765 -316.082499) (xy 294.982211 -316.07506) (xy 294.987472 -316.074552) (xy 295.5036 -316.074552)
			(xy 295.511411 -316.074247) (xy 295.526283 -316.069456) (xy 295.53281 -316.065154) (xy 295.553899 -316.050805)
			(xy 295.59956 -316.028074) (xy 295.648166 -316.012615) (xy 295.698569 -316.004792) (xy 295.749575 -316.004792)
			(xy 295.799978 -316.012615) (xy 295.848584 -316.028074) (xy 295.894245 -316.050805) (xy 295.915334 -316.065154)
			(xy 295.921861 -316.069452) (xy 295.936734 -316.074232) (xy 295.944544 -316.074552) (xy 296.460672 -316.074552)
			(xy 296.465922 -316.075109) (xy 296.473364 -316.082513) (xy 296.47388 -316.08776) (xy 296.47388 -316.582298)
			(xy 302.518064 -316.582298) (xy 302.518064 -316.08776) (xy 302.518565 -316.082499) (xy 302.526011 -316.07506)
			(xy 302.531272 -316.074552) (xy 304.004726 -316.074552) (xy 304.010036 -316.075007) (xy 304.017606 -316.082459)
			(xy 304.018188 -316.08776) (xy 304.018188 -316.582298) (xy 304.018163 -316.582552) (xy 411.618176 -316.582552)
			(xy 411.618176 -316.582044) (xy 411.618176 -316.08776) (xy 411.618666 -316.082496) (xy 411.626119 -316.075057)
			(xy 411.631384 -316.074552) (xy 413.104584 -316.074552) (xy 413.109835 -316.075101) (xy 413.117276 -316.082511)
			(xy 413.117792 -316.08776) (xy 413.117792 -316.582298) (xy 419.161976 -316.582298) (xy 419.161976 -316.08776)
			(xy 419.162466 -316.082496) (xy 419.169919 -316.075057) (xy 419.175184 -316.074552) (xy 419.175692 -316.074552)
			(xy 419.691566 -316.074552) (xy 419.699376 -316.074232) (xy 419.714247 -316.069451) (xy 419.720776 -316.065154)
			(xy 419.741865 -316.050805) (xy 419.787526 -316.028074) (xy 419.836132 -316.012615) (xy 419.886535 -316.004792)
			(xy 419.937541 -316.004792) (xy 419.987944 -316.012615) (xy 420.03655 -316.028074) (xy 420.082211 -316.050805)
			(xy 420.1033 -316.065154) (xy 420.109835 -316.069439) (xy 420.124702 -316.074227) (xy 420.13251 -316.074552)
			(xy 420.648638 -316.074552) (xy 420.65395 -316.075) (xy 420.661519 -316.082457) (xy 420.6621 -316.08776)
			(xy 420.6621 -316.582298) (xy 420.662074 -316.582552) (xy 426.706284 -316.582552) (xy 426.706284 -316.582044)
			(xy 426.706284 -316.08776) (xy 426.706767 -316.082494) (xy 426.714225 -316.075054) (xy 426.719492 -316.074552)
			(xy 427.23562 -316.074552) (xy 427.243432 -316.074255) (xy 427.258303 -316.069459) (xy 427.26483 -316.065154)
			(xy 427.285919 -316.050805) (xy 427.33158 -316.028074) (xy 427.380186 -316.012615) (xy 427.430589 -316.004792)
			(xy 427.481595 -316.004792) (xy 427.531998 -316.012615) (xy 427.580604 -316.028074) (xy 427.626265 -316.050805)
			(xy 427.647354 -316.065154) (xy 427.653877 -316.06946) (xy 427.668753 -316.074235) (xy 427.676564 -316.074552)
			(xy 428.192692 -316.074552) (xy 428.197944 -316.075096) (xy 428.205385 -316.08251) (xy 428.2059 -316.08776)
			(xy 428.2059 -316.582298) (xy 434.250084 -316.582298) (xy 434.250084 -316.08776) (xy 434.250567 -316.082494)
			(xy 434.258025 -316.075054) (xy 434.263292 -316.074552) (xy 434.2638 -316.074552) (xy 434.779674 -316.074552)
			(xy 434.787484 -316.074235) (xy 434.802356 -316.069452) (xy 434.808884 -316.065154) (xy 434.829973 -316.050805)
			(xy 434.875634 -316.028074) (xy 434.92424 -316.012615) (xy 434.974643 -316.004792) (xy 435.025649 -316.004792)
			(xy 435.076052 -316.012615) (xy 435.124658 -316.028074) (xy 435.170319 -316.050805) (xy 435.191408 -316.065154)
			(xy 435.197941 -316.069443) (xy 435.21281 -316.074228) (xy 435.220618 -316.074552) (xy 435.736746 -316.074552)
			(xy 435.742047 -316.075061) (xy 435.749621 -316.082471) (xy 435.750208 -316.08776) (xy 435.750208 -316.582298)
			(xy 435.750182 -316.582552) (xy 441.794392 -316.582552) (xy 441.794392 -316.582044) (xy 441.794392 -316.08776)
			(xy 441.794868 -316.082492) (xy 441.802331 -316.075052) (xy 441.8076 -316.074552) (xy 442.323728 -316.074552)
			(xy 442.33154 -316.074258) (xy 442.346412 -316.06946) (xy 442.352938 -316.065154) (xy 442.374027 -316.050805)
			(xy 442.419688 -316.028074) (xy 442.468294 -316.012615) (xy 442.518697 -316.004792) (xy 442.569703 -316.004792)
			(xy 442.620106 -316.012615) (xy 442.668712 -316.028074) (xy 442.714373 -316.050805) (xy 442.735462 -316.065154)
			(xy 442.742005 -316.069425) (xy 442.756866 -316.074221) (xy 442.764672 -316.074552) (xy 443.2808 -316.074552)
			(xy 443.286053 -316.075091) (xy 443.293493 -316.082508) (xy 443.294008 -316.08776) (xy 443.294008 -316.582298)
			(xy 443.293983 -316.582552) (xy 449.338192 -316.582552) (xy 449.338192 -316.582044) (xy 449.338192 -316.08776)
			(xy 449.338668 -316.082492) (xy 449.346131 -316.075052) (xy 449.3514 -316.074552) (xy 449.867528 -316.074552)
			(xy 449.87534 -316.074258) (xy 449.890212 -316.06946) (xy 449.896738 -316.065154) (xy 449.917827 -316.050805)
			(xy 449.963488 -316.028074) (xy 450.012094 -316.012615) (xy 450.062497 -316.004792) (xy 450.113503 -316.004792)
			(xy 450.163906 -316.012615) (xy 450.212512 -316.028074) (xy 450.258173 -316.050805) (xy 450.279262 -316.065154)
			(xy 450.285805 -316.069425) (xy 450.300666 -316.074221) (xy 450.308472 -316.074552) (xy 450.8246 -316.074552)
			(xy 450.829853 -316.075091) (xy 450.837293 -316.082508) (xy 450.837808 -316.08776) (xy 450.837808 -316.582298)
			(xy 450.837281 -316.587591) (xy 450.829881 -316.595159) (xy 450.8246 -316.59576) (xy 450.308726 -316.59576)
			(xy 450.300916 -316.596075) (xy 450.286044 -316.600859) (xy 450.279516 -316.605158) (xy 450.258388 -316.619497)
			(xy 450.212666 -316.642226) (xy 450.163995 -316.657659) (xy 450.11353 -316.665429) (xy 450.088 -316.665864)
			(xy 450.06247 -316.665428) (xy 450.012006 -316.657652) (xy 449.963333 -316.642222) (xy 449.917606 -316.619506)
			(xy 449.896484 -316.605158) (xy 449.889952 -316.600867) (xy 449.875082 -316.596083) (xy 449.867274 -316.59576)
			(xy 449.3514 -316.59576) (xy 449.346056 -316.595469) (xy 449.338512 -316.587897) (xy 449.338192 -316.582552)
			(xy 443.293983 -316.582552) (xy 443.293481 -316.587591) (xy 443.286081 -316.595159) (xy 443.2808 -316.59576)
			(xy 442.764926 -316.59576) (xy 442.757116 -316.596075) (xy 442.742244 -316.600859) (xy 442.735716 -316.605158)
			(xy 442.714588 -316.619497) (xy 442.668866 -316.642226) (xy 442.620195 -316.657659) (xy 442.56973 -316.665429)
			(xy 442.5442 -316.665864) (xy 442.51867 -316.665428) (xy 442.468206 -316.657652) (xy 442.419533 -316.642222)
			(xy 442.373806 -316.619506) (xy 442.352684 -316.605158) (xy 442.346152 -316.600867) (xy 442.331282 -316.596083)
			(xy 442.323474 -316.59576) (xy 441.8076 -316.59576) (xy 441.802256 -316.595469) (xy 441.794712 -316.587897)
			(xy 441.794392 -316.582552) (xy 435.750182 -316.582552) (xy 435.749653 -316.587651) (xy 435.742097 -316.595234)
			(xy 435.736746 -316.59576) (xy 435.220872 -316.59576) (xy 435.21306 -316.596051) (xy 435.198188 -316.600852)
			(xy 435.191662 -316.605158) (xy 435.170549 -316.619521) (xy 435.124822 -316.642244) (xy 435.076146 -316.65767)
			(xy 435.025678 -316.665433) (xy 435.000146 -316.665864) (xy 434.974617 -316.665404) (xy 434.924154 -316.657636)
			(xy 434.875481 -316.642213) (xy 434.829753 -316.619503) (xy 434.80863 -316.605158) (xy 434.802088 -316.600885)
			(xy 434.787226 -316.59609) (xy 434.77942 -316.59576) (xy 434.263546 -316.59576) (xy 434.258117 -316.59539)
			(xy 434.250428 -316.587726) (xy 434.250084 -316.582298) (xy 428.2059 -316.582298) (xy 428.20538 -316.587593)
			(xy 428.197975 -316.595161) (xy 428.192692 -316.59576) (xy 427.676818 -316.59576) (xy 427.669008 -316.596071)
			(xy 427.654136 -316.600858) (xy 427.647608 -316.605158) (xy 427.626482 -316.619501) (xy 427.58076 -316.642229)
			(xy 427.532088 -316.657661) (xy 427.481623 -316.66543) (xy 427.456092 -316.665864) (xy 427.430562 -316.665432)
			(xy 427.380098 -316.657654) (xy 427.331425 -316.642224) (xy 427.285698 -316.619506) (xy 427.264576 -316.605158)
			(xy 427.258046 -316.600864) (xy 427.243175 -316.596082) (xy 427.235366 -316.59576) (xy 426.719492 -316.59576)
			(xy 426.714147 -316.595474) (xy 426.706603 -316.587899) (xy 426.706284 -316.582552) (xy 420.662074 -316.582552)
			(xy 420.661552 -316.587653) (xy 420.653991 -316.595236) (xy 420.648638 -316.59576) (xy 420.132764 -316.59576)
			(xy 420.124955 -316.596091) (xy 420.110083 -316.600864) (xy 420.103554 -316.605158) (xy 420.082443 -316.619524)
			(xy 420.036715 -316.642247) (xy 419.988039 -316.657672) (xy 419.93757 -316.665434) (xy 419.912038 -316.665864)
			(xy 419.886508 -316.665408) (xy 419.836045 -316.657638) (xy 419.787373 -316.642215) (xy 419.741645 -316.619503)
			(xy 419.720522 -316.605158) (xy 419.713981 -316.600882) (xy 419.699119 -316.596089) (xy 419.691312 -316.59576)
			(xy 419.175438 -316.59576) (xy 419.170008 -316.595395) (xy 419.162319 -316.587727) (xy 419.161976 -316.582298)
			(xy 413.117792 -316.582298) (xy 413.117279 -316.587594) (xy 413.109869 -316.595164) (xy 413.104584 -316.59576)
			(xy 411.631384 -316.59576) (xy 411.626038 -316.595479) (xy 411.618495 -316.5879) (xy 411.618176 -316.582552)
			(xy 304.018163 -316.582552) (xy 304.017651 -316.587655) (xy 304.010082 -316.59524) (xy 304.004726 -316.59576)
			(xy 302.531526 -316.59576) (xy 302.526094 -316.595403) (xy 302.518406 -316.587729) (xy 302.518064 -316.582298)
			(xy 296.47388 -316.582298) (xy 296.473378 -316.587597) (xy 296.46596 -316.595167) (xy 296.460672 -316.59576)
			(xy 295.944798 -316.59576) (xy 295.936987 -316.596063) (xy 295.922115 -316.600855) (xy 295.915588 -316.605158)
			(xy 295.894468 -316.619509) (xy 295.848743 -316.642235) (xy 295.80007 -316.657665) (xy 295.749603 -316.665431)
			(xy 295.724072 -316.665864) (xy 295.698541 -316.665442) (xy 295.648077 -316.657661) (xy 295.599404 -316.642228)
			(xy 295.553677 -316.619507) (xy 295.532556 -316.605158) (xy 295.52603 -316.600857) (xy 295.511156 -316.596079)
			(xy 295.503346 -316.59576) (xy 294.987472 -316.59576) (xy 294.982124 -316.595487) (xy 294.974582 -316.587902)
			(xy 294.974264 -316.582552) (xy 288.930055 -316.582552) (xy 288.92955 -316.587657) (xy 288.921977 -316.595242)
			(xy 288.916618 -316.59576) (xy 288.400744 -316.59576) (xy 288.392935 -316.596082) (xy 288.378063 -316.600861)
			(xy 288.371534 -316.605158) (xy 288.350429 -316.619533) (xy 288.304699 -316.642253) (xy 288.256021 -316.657676)
			(xy 288.20555 -316.665435) (xy 288.180018 -316.665864) (xy 288.154488 -316.665419) (xy 288.104025 -316.657645)
			(xy 288.055352 -316.642219) (xy 288.009624 -316.619504) (xy 287.988502 -316.605158) (xy 287.981966 -316.600874)
			(xy 287.9671 -316.596086) (xy 287.959292 -316.59576) (xy 287.443418 -316.59576) (xy 287.437985 -316.595409)
			(xy 287.430298 -316.587731) (xy 287.429956 -316.582298) (xy 281.385772 -316.582298) (xy 281.385277 -316.587599)
			(xy 281.377854 -316.59517) (xy 281.372564 -316.59576) (xy 280.85669 -316.59576) (xy 280.848878 -316.59606)
			(xy 280.834007 -316.600854) (xy 280.82748 -316.605158) (xy 280.806362 -316.619513) (xy 280.760637 -316.642238)
			(xy 280.711962 -316.657667) (xy 280.661495 -316.665432) (xy 280.635964 -316.665864) (xy 280.610433 -316.665446)
			(xy 280.559968 -316.657664) (xy 280.511296 -316.64223) (xy 280.465569 -316.619508) (xy 280.444448 -316.605158)
			(xy 280.437924 -316.600854) (xy 280.423048 -316.596078) (xy 280.415238 -316.59576) (xy 279.899364 -316.59576)
			(xy 279.894015 -316.595493) (xy 279.886473 -316.587903) (xy 279.886156 -316.582552) (xy 273.841948 -316.582552)
			(xy 273.841477 -316.587599) (xy 273.834054 -316.59517) (xy 273.828764 -316.59576) (xy 273.31289 -316.59576)
			(xy 273.305078 -316.59606) (xy 273.290207 -316.600854) (xy 273.28368 -316.605158) (xy 273.262562 -316.619513)
			(xy 273.216837 -316.642238) (xy 273.168162 -316.657667) (xy 273.117695 -316.665432) (xy 273.092164 -316.665864)
			(xy 273.066633 -316.665446) (xy 273.016168 -316.657664) (xy 272.967496 -316.64223) (xy 272.921769 -316.619508)
			(xy 272.900648 -316.605158) (xy 272.894124 -316.600854) (xy 272.879248 -316.596078) (xy 272.871438 -316.59576)
			(xy 272.355564 -316.59576) (xy 272.350215 -316.595493) (xy 272.342673 -316.587903) (xy 272.342356 -316.582552)
			(xy 266.298147 -316.582552) (xy 266.297649 -316.587659) (xy 266.290071 -316.595245) (xy 266.28471 -316.59576)
			(xy 265.768836 -316.59576) (xy 265.761026 -316.596079) (xy 265.746154 -316.60086) (xy 265.739626 -316.605158)
			(xy 265.718495 -316.619493) (xy 265.672775 -316.642223) (xy 265.624104 -316.657657) (xy 265.57364 -316.665428)
			(xy 265.54811 -316.665864) (xy 265.52258 -316.665423) (xy 265.472116 -316.657648) (xy 265.423444 -316.64222)
			(xy 265.377716 -316.619505) (xy 265.356594 -316.605158) (xy 265.35006 -316.600871) (xy 265.335192 -316.596084)
			(xy 265.327384 -316.59576) (xy 264.81151 -316.59576) (xy 264.806076 -316.595414) (xy 264.798389 -316.587732)
			(xy 264.798048 -316.582298) (xy 202.89774 -316.582298) (xy 202.89774 -316.582552) (xy 202.897344 -316.58787)
			(xy 202.889848 -316.595412) (xy 202.884532 -316.59576) (xy 202.368658 -316.59576) (xy 202.360782 -316.596036)
			(xy 202.345778 -316.600828) (xy 202.339194 -316.605158) (xy 202.318109 -316.619538) (xy 202.272467 -316.642369)
			(xy 202.223863 -316.65793) (xy 202.173448 -316.665853) (xy 202.147932 -316.666372) (xy 202.122412 -316.665888)
			(xy 202.071984 -316.657993) (xy 202.023372 -316.642431) (xy 201.977734 -316.619574) (xy 201.95667 -316.605158)
			(xy 201.950084 -316.600834) (xy 201.93508 -316.596052) (xy 201.927206 -316.59576) (xy 201.411332 -316.59576)
			(xy 201.405992 -316.595447) (xy 201.398447 -316.587892) (xy 201.398124 -316.582552) (xy 195.35394 -316.582552)
			(xy 195.353544 -316.58787) (xy 195.346048 -316.595412) (xy 195.340732 -316.59576) (xy 194.824858 -316.59576)
			(xy 194.816982 -316.596036) (xy 194.801978 -316.600828) (xy 194.795394 -316.605158) (xy 194.774309 -316.619538)
			(xy 194.728667 -316.642369) (xy 194.680063 -316.65793) (xy 194.629648 -316.665853) (xy 194.604132 -316.666372)
			(xy 194.578612 -316.665888) (xy 194.528184 -316.657993) (xy 194.479572 -316.642431) (xy 194.433934 -316.619574)
			(xy 194.41287 -316.605158) (xy 194.406284 -316.600834) (xy 194.39128 -316.596052) (xy 194.383406 -316.59576)
			(xy 193.867532 -316.59576) (xy 193.862192 -316.595447) (xy 193.854647 -316.587892) (xy 193.854324 -316.582552)
			(xy 187.81014 -316.582552) (xy 187.809744 -316.58787) (xy 187.802248 -316.595412) (xy 187.796932 -316.59576)
			(xy 187.796424 -316.59576) (xy 187.280804 -316.59576) (xy 187.27293 -316.596055) (xy 187.257926 -316.600834)
			(xy 187.25134 -316.605158) (xy 187.23027 -316.619562) (xy 187.184623 -316.642387) (xy 187.136014 -316.657941)
			(xy 187.085595 -316.665857) (xy 187.060078 -316.666372) (xy 187.034558 -316.665865) (xy 186.984132 -316.657977)
			(xy 186.93552 -316.642422) (xy 186.889881 -316.619571) (xy 186.868816 -316.605158) (xy 186.862219 -316.600852)
			(xy 186.847223 -316.596059) (xy 186.839352 -316.59576) (xy 186.323478 -316.59576) (xy 186.318171 -316.595291)
			(xy 186.310601 -316.58785) (xy 186.310016 -316.582552) (xy 180.265832 -316.582552) (xy 180.265443 -316.587872)
			(xy 180.257942 -316.595414) (xy 180.252624 -316.59576) (xy 179.73675 -316.59576) (xy 179.728874 -316.596032)
			(xy 179.71387 -316.600826) (xy 179.707286 -316.605158) (xy 179.686204 -316.619542) (xy 179.64056 -316.642372)
			(xy 179.591956 -316.657932) (xy 179.54154 -316.665853) (xy 179.516024 -316.666372) (xy 179.490503 -316.665892)
			(xy 179.440076 -316.657996) (xy 179.391464 -316.642433) (xy 179.345826 -316.619575) (xy 179.324762 -316.605158)
			(xy 179.318177 -316.600831) (xy 179.303172 -316.596051) (xy 179.295298 -316.59576) (xy 178.779424 -316.59576)
			(xy 178.774083 -316.595452) (xy 178.766538 -316.587893) (xy 178.766216 -316.582552) (xy 172.722032 -316.582552)
			(xy 172.721643 -316.587872) (xy 172.714142 -316.595414) (xy 172.708824 -316.59576) (xy 172.708316 -316.59576)
			(xy 172.192696 -316.59576) (xy 172.184822 -316.596052) (xy 172.169818 -316.600832) (xy 172.163232 -316.605158)
			(xy 172.142165 -316.619565) (xy 172.096516 -316.64239) (xy 172.047907 -316.657943) (xy 171.997488 -316.665857)
			(xy 171.97197 -316.666372) (xy 171.94645 -316.665869) (xy 171.896024 -316.65798) (xy 171.847412 -316.642424)
			(xy 171.801773 -316.619572) (xy 171.780708 -316.605158) (xy 171.774113 -316.600849) (xy 171.759116 -316.596057)
			(xy 171.751244 -316.59576) (xy 171.23537 -316.59576) (xy 171.230062 -316.595297) (xy 171.222493 -316.587851)
			(xy 171.221908 -316.582552) (xy 165.177724 -316.582552) (xy 165.177342 -316.587874) (xy 165.169836 -316.595417)
			(xy 165.164516 -316.59576) (xy 163.691316 -316.59576) (xy 163.685974 -316.595458) (xy 163.678429 -316.587895)
			(xy 163.678108 -316.582552) (xy 56.07812 -316.582552) (xy 56.077742 -316.587875) (xy 56.070233 -316.595418)
			(xy 56.064912 -316.59576) (xy 54.591458 -316.59576) (xy 54.586149 -316.595305) (xy 54.57858 -316.587853)
			(xy 54.577996 -316.582552) (xy 48.533812 -316.582552) (xy 48.533441 -316.587877) (xy 48.525927 -316.59542)
			(xy 48.520604 -316.59576) (xy 48.00473 -316.59576) (xy 47.996853 -316.596023) (xy 47.981849 -316.600823)
			(xy 47.975266 -316.605158) (xy 47.954189 -316.61955) (xy 47.908544 -316.642378) (xy 47.859938 -316.657936)
			(xy 47.809521 -316.665855) (xy 47.784004 -316.666372) (xy 47.758483 -316.665903) (xy 47.708055 -316.658003)
			(xy 47.659443 -316.642437) (xy 47.613806 -316.619576) (xy 47.592742 -316.605158) (xy 47.586162 -316.600823)
			(xy 47.571153 -316.596048) (xy 47.563278 -316.59576) (xy 47.047404 -316.59576) (xy 47.042061 -316.595466)
			(xy 47.034517 -316.587896) (xy 47.034196 -316.582552) (xy 40.990012 -316.582552) (xy 40.989641 -316.587877)
			(xy 40.982127 -316.59542) (xy 40.976804 -316.59576) (xy 40.976296 -316.59576) (xy 40.460676 -316.59576)
			(xy 40.452801 -316.596043) (xy 40.437797 -316.60083) (xy 40.431212 -316.605158) (xy 40.41015 -316.619574)
			(xy 40.3645 -316.642396) (xy 40.315889 -316.657947) (xy 40.265468 -316.665859) (xy 40.23995 -316.666372)
			(xy 40.21443 -316.665879) (xy 40.164003 -316.657987) (xy 40.115391 -316.642428) (xy 40.069753 -316.619573)
			(xy 40.048688 -316.605158) (xy 40.042098 -316.600841) (xy 40.027097 -316.596054) (xy 40.019224 -316.59576)
			(xy 39.50335 -316.59576) (xy 39.498052 -316.595243) (xy 39.490478 -316.587838) (xy 39.489888 -316.582552)
			(xy 33.445704 -316.582552) (xy 33.44534 -316.587879) (xy 33.437822 -316.595423) (xy 33.432496 -316.59576)
			(xy 32.916622 -316.59576) (xy 32.908749 -316.596063) (xy 32.893745 -316.600836) (xy 32.887158 -316.605158)
			(xy 32.866083 -316.619554) (xy 32.820437 -316.642381) (xy 32.771831 -316.657937) (xy 32.721413 -316.665855)
			(xy 32.695896 -316.666372) (xy 32.670375 -316.665907) (xy 32.619947 -316.658005) (xy 32.571335 -316.642439)
			(xy 32.525698 -316.619577) (xy 32.504634 -316.605158) (xy 32.498033 -316.600859) (xy 32.48304 -316.596061)
			(xy 32.47517 -316.59576) (xy 31.959296 -316.59576) (xy 31.953951 -316.595471) (xy 31.946408 -316.587898)
			(xy 31.946088 -316.582552) (xy 25.901904 -316.582552) (xy 25.90154 -316.587879) (xy 25.894022 -316.595423)
			(xy 25.888696 -316.59576) (xy 25.372822 -316.59576) (xy 25.364949 -316.596063) (xy 25.349945 -316.600836)
			(xy 25.343358 -316.605158) (xy 25.322283 -316.619554) (xy 25.276637 -316.642381) (xy 25.228031 -316.657937)
			(xy 25.177613 -316.665855) (xy 25.152096 -316.666372) (xy 25.126575 -316.665907) (xy 25.076147 -316.658005)
			(xy 25.027535 -316.642439) (xy 24.981898 -316.619577) (xy 24.960834 -316.605158) (xy 24.954233 -316.600859)
			(xy 24.93924 -316.596061) (xy 24.93137 -316.59576) (xy 24.415496 -316.59576) (xy 24.410151 -316.595471)
			(xy 24.402608 -316.587898) (xy 24.402288 -316.582552) (xy 18.358104 -316.582552) (xy 18.35774 -316.587879)
			(xy 18.350222 -316.595423) (xy 18.344896 -316.59576) (xy 18.344388 -316.59576) (xy 17.828768 -316.59576)
			(xy 17.820893 -316.59604) (xy 17.805889 -316.600829) (xy 17.799304 -316.605158) (xy 17.778217 -316.619534)
			(xy 17.732575 -316.642366) (xy 17.683972 -316.657928) (xy 17.633558 -316.665852) (xy 17.608042 -316.666372)
			(xy 17.582522 -316.665883) (xy 17.532095 -316.657989) (xy 17.483483 -316.642429) (xy 17.437845 -316.619574)
			(xy 17.41678 -316.605158) (xy 17.410191 -316.600838) (xy 17.395189 -316.596053) (xy 17.387316 -316.59576)
			(xy 16.871442 -316.59576) (xy 16.866143 -316.595249) (xy 16.858569 -316.587839) (xy 16.85798 -316.582552)
			(xy 2.509012 -316.582552) (xy 2.509012 -317.432436) (xy 20.958048 -317.432436) (xy 20.958048 -316.937898)
			(xy 20.958379 -316.93246) (xy 20.966072 -316.924774) (xy 20.97151 -316.924436) (xy 21.487638 -316.924436)
			(xy 21.495447 -316.924107) (xy 21.510319 -316.919333) (xy 21.516848 -316.915038) (xy 21.537937 -316.900689)
			(xy 21.583598 -316.877958) (xy 21.632204 -316.862499) (xy 21.682607 -316.854676) (xy 21.733613 -316.854676)
			(xy 21.784016 -316.862499) (xy 21.832622 -316.877958) (xy 21.878283 -316.900689) (xy 21.899372 -316.915038)
			(xy 21.905914 -316.919311) (xy 21.920776 -316.924107) (xy 21.928582 -316.924436) (xy 22.44471 -316.924436)
			(xy 22.450075 -316.924944) (xy 22.45766 -316.932533) (xy 22.458172 -316.937898) (xy 22.458172 -317.432436)
			(xy 28.502356 -317.432436) (xy 28.502356 -316.937898) (xy 28.502824 -316.93259) (xy 28.510265 -316.925018)
			(xy 28.515564 -316.924436) (xy 29.031692 -316.924436) (xy 29.039503 -316.92413) (xy 29.054375 -316.91934)
			(xy 29.060902 -316.915038) (xy 29.081991 -316.900689) (xy 29.127652 -316.877958) (xy 29.176258 -316.862499)
			(xy 29.226661 -316.854676) (xy 29.277667 -316.854676) (xy 29.32807 -316.862499) (xy 29.376676 -316.877958)
			(xy 29.422337 -316.900689) (xy 29.443426 -316.915038) (xy 29.449956 -316.919332) (xy 29.464827 -316.924114)
			(xy 29.472636 -316.924436) (xy 29.988764 -316.924436) (xy 29.994102 -316.924755) (xy 30.001648 -316.932306)
			(xy 30.001972 -316.937644) (xy 30.001972 -316.938152) (xy 30.001972 -317.432436) (xy 36.046156 -317.432436)
			(xy 36.046156 -316.937898) (xy 36.046624 -316.93259) (xy 36.054065 -316.925018) (xy 36.059364 -316.924436)
			(xy 36.575492 -316.924436) (xy 36.583303 -316.92413) (xy 36.598175 -316.91934) (xy 36.604702 -316.915038)
			(xy 36.625791 -316.900689) (xy 36.671452 -316.877958) (xy 36.720058 -316.862499) (xy 36.770461 -316.854676)
			(xy 36.821467 -316.854676) (xy 36.87187 -316.862499) (xy 36.920476 -316.877958) (xy 36.966137 -316.900689)
			(xy 36.987226 -316.915038) (xy 36.993756 -316.919332) (xy 37.008627 -316.924114) (xy 37.016436 -316.924436)
			(xy 37.532564 -316.924436) (xy 37.537902 -316.924755) (xy 37.545448 -316.932306) (xy 37.545772 -316.937644)
			(xy 37.545772 -316.938152) (xy 37.545772 -317.432436) (xy 43.589956 -317.432436) (xy 43.589956 -316.937898)
			(xy 43.59028 -316.932459) (xy 43.597978 -316.924772) (xy 43.603418 -316.924436) (xy 44.119546 -316.924436)
			(xy 44.127355 -316.92411) (xy 44.142227 -316.919334) (xy 44.148756 -316.915038) (xy 44.169845 -316.900689)
			(xy 44.215506 -316.877958) (xy 44.264112 -316.862499) (xy 44.314515 -316.854676) (xy 44.365521 -316.854676)
			(xy 44.415924 -316.862499) (xy 44.46453 -316.877958) (xy 44.510191 -316.900689) (xy 44.53128 -316.915038)
			(xy 44.53782 -316.919314) (xy 44.552683 -316.924108) (xy 44.56049 -316.924436) (xy 45.076618 -316.924436)
			(xy 45.081984 -316.924938) (xy 45.089568 -316.932532) (xy 45.09008 -316.937898) (xy 45.09008 -317.432436)
			(xy 51.134264 -317.432436) (xy 51.134264 -316.937898) (xy 51.134725 -316.932588) (xy 51.142171 -316.925016)
			(xy 51.147472 -316.924436) (xy 51.6636 -316.924436) (xy 51.671411 -316.924133) (xy 51.686283 -316.919341)
			(xy 51.69281 -316.915038) (xy 51.713899 -316.900689) (xy 51.75956 -316.877958) (xy 51.808166 -316.862499)
			(xy 51.858569 -316.854676) (xy 51.909575 -316.854676) (xy 51.959978 -316.862499) (xy 52.008584 -316.877958)
			(xy 52.054245 -316.900689) (xy 52.075334 -316.915038) (xy 52.081862 -316.919335) (xy 52.096735 -316.924116)
			(xy 52.104544 -316.924436) (xy 52.620672 -316.924436) (xy 52.626011 -316.92475) (xy 52.633557 -316.932304)
			(xy 52.63388 -316.937644) (xy 52.63388 -316.938152) (xy 52.63388 -317.432436) (xy 58.678064 -317.432436)
			(xy 58.678064 -316.937898) (xy 58.67838 -316.932457) (xy 58.686084 -316.924769) (xy 58.691526 -316.924436)
			(xy 60.164726 -316.924436) (xy 60.170093 -316.924933) (xy 60.177676 -316.932531) (xy 60.178188 -316.937898)
			(xy 60.178188 -317.432436) (xy 167.778176 -317.432436) (xy 167.778176 -316.937898) (xy 167.778626 -316.932585)
			(xy 167.78608 -316.925012) (xy 167.791384 -316.924436) (xy 169.264584 -316.924436) (xy 169.269925 -316.924742)
			(xy 169.277469 -316.932302) (xy 169.277792 -316.937644) (xy 169.277792 -317.432436) (xy 175.321976 -317.432436)
			(xy 175.321976 -316.937898) (xy 175.322282 -316.932454) (xy 175.329993 -316.924765) (xy 175.335438 -316.924436)
			(xy 175.851566 -316.924436) (xy 175.859376 -316.924119) (xy 175.874248 -316.919336) (xy 175.880776 -316.915038)
			(xy 175.901865 -316.900689) (xy 175.947526 -316.877958) (xy 175.996132 -316.862499) (xy 176.046535 -316.854676)
			(xy 176.097541 -316.854676) (xy 176.147944 -316.862499) (xy 176.19655 -316.877958) (xy 176.242211 -316.900689)
			(xy 176.2633 -316.915038) (xy 176.269836 -316.919322) (xy 176.284702 -316.924111) (xy 176.29251 -316.924436)
			(xy 176.808638 -316.924436) (xy 176.814006 -316.924925) (xy 176.821589 -316.932529) (xy 176.8221 -316.937898)
			(xy 176.8221 -317.432436) (xy 182.866284 -317.432436) (xy 182.866284 -316.937898) (xy 182.866727 -316.932583)
			(xy 182.874186 -316.92501) (xy 182.879492 -316.924436) (xy 183.39562 -316.924436) (xy 183.403432 -316.924142)
			(xy 183.418304 -316.919344) (xy 183.42483 -316.915038) (xy 183.445919 -316.900689) (xy 183.49158 -316.877958)
			(xy 183.540186 -316.862499) (xy 183.590589 -316.854676) (xy 183.641595 -316.854676) (xy 183.691998 -316.862499)
			(xy 183.740604 -316.877958) (xy 183.786265 -316.900689) (xy 183.807354 -316.915038) (xy 183.813878 -316.919343)
			(xy 183.828754 -316.924119) (xy 183.836564 -316.924436) (xy 184.352692 -316.924436) (xy 184.358034 -316.924736)
			(xy 184.365578 -316.932301) (xy 184.3659 -316.937644) (xy 184.3659 -316.938152) (xy 184.3659 -317.432436)
			(xy 190.410084 -317.432436) (xy 190.410084 -316.937898) (xy 190.410382 -316.932452) (xy 190.418098 -316.924763)
			(xy 190.423546 -316.924436) (xy 190.939674 -316.924436) (xy 190.947484 -316.924122) (xy 190.962356 -316.919337)
			(xy 190.968884 -316.915038) (xy 190.989973 -316.900689) (xy 191.035634 -316.877958) (xy 191.08424 -316.862499)
			(xy 191.134643 -316.854676) (xy 191.185649 -316.854676) (xy 191.236052 -316.862499) (xy 191.284658 -316.877958)
			(xy 191.330319 -316.900689) (xy 191.351408 -316.915038) (xy 191.357942 -316.919325) (xy 191.37281 -316.924112)
			(xy 191.380618 -316.924436) (xy 191.896746 -316.924436) (xy 191.902115 -316.92492) (xy 191.909698 -316.932527)
			(xy 191.910208 -316.937898) (xy 191.910208 -317.432436) (xy 197.954392 -317.432436) (xy 197.954392 -316.937898)
			(xy 197.954916 -316.932605) (xy 197.962319 -316.925036) (xy 197.9676 -316.924436) (xy 198.483728 -316.924436)
			(xy 198.49154 -316.924145) (xy 198.506412 -316.919345) (xy 198.512938 -316.915038) (xy 198.534027 -316.900689)
			(xy 198.579688 -316.877958) (xy 198.628294 -316.862499) (xy 198.678697 -316.854676) (xy 198.729703 -316.854676)
			(xy 198.780106 -316.862499) (xy 198.828712 -316.877958) (xy 198.874373 -316.900689) (xy 198.895462 -316.915038)
			(xy 198.902006 -316.919307) (xy 198.916866 -316.924105) (xy 198.924672 -316.924436) (xy 199.4408 -316.924436)
			(xy 199.446143 -316.924731) (xy 199.453687 -316.9323) (xy 199.454008 -316.937644) (xy 199.454008 -316.938152)
			(xy 199.454008 -317.432436) (xy 205.498192 -317.432436) (xy 205.498192 -316.937898) (xy 205.498716 -316.932605)
			(xy 205.506119 -316.925036) (xy 205.5114 -316.924436) (xy 206.027528 -316.924436) (xy 206.03534 -316.924145)
			(xy 206.050212 -316.919345) (xy 206.056738 -316.915038) (xy 206.077827 -316.900689) (xy 206.123488 -316.877958)
			(xy 206.172094 -316.862499) (xy 206.222497 -316.854676) (xy 206.273503 -316.854676) (xy 206.323906 -316.862499)
			(xy 206.372512 -316.877958) (xy 206.418173 -316.900689) (xy 206.439262 -316.915038) (xy 206.445806 -316.919307)
			(xy 206.460666 -316.924105) (xy 206.468472 -316.924436) (xy 206.9846 -316.924436) (xy 206.989943 -316.924731)
			(xy 206.997487 -316.9323) (xy 206.997808 -316.937644) (xy 206.997808 -316.938152) (xy 206.997808 -317.432182)
			(xy 268.898116 -317.432182) (xy 268.898116 -316.937644) (xy 268.898459 -316.932312) (xy 268.905992 -316.924767)
			(xy 268.911324 -316.924436) (xy 268.911832 -316.924436) (xy 269.427706 -316.924436) (xy 269.435517 -316.924135)
			(xy 269.450389 -316.919341) (xy 269.456916 -316.915038) (xy 269.478005 -316.900689) (xy 269.523666 -316.877958)
			(xy 269.572272 -316.862499) (xy 269.622675 -316.854676) (xy 269.673681 -316.854676) (xy 269.724084 -316.862499)
			(xy 269.77269 -316.877958) (xy 269.818351 -316.900689) (xy 269.83944 -316.915038) (xy 269.845967 -316.919337)
			(xy 269.86084 -316.924116) (xy 269.86865 -316.924436) (xy 270.384778 -316.924436) (xy 270.390079 -316.924937)
			(xy 270.397651 -316.932354) (xy 270.39824 -316.937644) (xy 270.39824 -317.432182) (xy 270.398224 -317.432436)
			(xy 276.442424 -317.432436) (xy 276.442424 -317.431928) (xy 276.442424 -316.937644) (xy 276.44276 -316.93231)
			(xy 276.450298 -316.924764) (xy 276.455632 -316.924436) (xy 276.97176 -316.924436) (xy 276.97957 -316.924116)
			(xy 276.994442 -316.919335) (xy 277.00097 -316.915038) (xy 277.022059 -316.900689) (xy 277.06772 -316.877958)
			(xy 277.116326 -316.862499) (xy 277.166729 -316.854676) (xy 277.217735 -316.854676) (xy 277.268138 -316.862499)
			(xy 277.316744 -316.877958) (xy 277.362405 -316.900689) (xy 277.383494 -316.915038) (xy 277.390031 -316.91932)
			(xy 277.404897 -316.92411) (xy 277.412704 -316.924436) (xy 277.928832 -316.924436) (xy 277.934179 -316.92471)
			(xy 277.941721 -316.932295) (xy 277.94204 -316.937644) (xy 277.94204 -317.432182) (xy 277.942017 -317.432436)
			(xy 283.986224 -317.432436) (xy 283.986224 -317.431928) (xy 283.986224 -316.937644) (xy 283.98656 -316.93231)
			(xy 283.994098 -316.924764) (xy 283.999432 -316.924436) (xy 284.51556 -316.924436) (xy 284.52337 -316.924116)
			(xy 284.538242 -316.919335) (xy 284.54477 -316.915038) (xy 284.565859 -316.900689) (xy 284.61152 -316.877958)
			(xy 284.660126 -316.862499) (xy 284.710529 -316.854676) (xy 284.761535 -316.854676) (xy 284.811938 -316.862499)
			(xy 284.860544 -316.877958) (xy 284.906205 -316.900689) (xy 284.927294 -316.915038) (xy 284.933831 -316.91932)
			(xy 284.948697 -316.92411) (xy 284.956504 -316.924436) (xy 285.472632 -316.924436) (xy 285.477979 -316.92471)
			(xy 285.485521 -316.932295) (xy 285.48584 -316.937644) (xy 285.48584 -317.432182) (xy 291.530024 -317.432182)
			(xy 291.530024 -316.937644) (xy 291.53036 -316.93231) (xy 291.537898 -316.924764) (xy 291.543232 -316.924436)
			(xy 291.54374 -316.924436) (xy 292.059614 -316.924436) (xy 292.067426 -316.924139) (xy 292.082297 -316.919342)
			(xy 292.088824 -316.915038) (xy 292.109913 -316.900689) (xy 292.155574 -316.877958) (xy 292.20418 -316.862499)
			(xy 292.254583 -316.854676) (xy 292.305589 -316.854676) (xy 292.355992 -316.862499) (xy 292.404598 -316.877958)
			(xy 292.450259 -316.900689) (xy 292.471348 -316.915038) (xy 292.477873 -316.91934) (xy 292.492748 -316.924118)
			(xy 292.500558 -316.924436) (xy 293.016686 -316.924436) (xy 293.021988 -316.924932) (xy 293.029559 -316.932353)
			(xy 293.030148 -316.937644) (xy 293.030148 -317.432182) (xy 293.030132 -317.432436) (xy 299.074332 -317.432436)
			(xy 299.074332 -317.431928) (xy 299.074332 -316.937644) (xy 299.07466 -316.932308) (xy 299.082204 -316.924762)
			(xy 299.08754 -316.924436) (xy 299.603668 -316.924436) (xy 299.611478 -316.924119) (xy 299.62635 -316.919337)
			(xy 299.632878 -316.915038) (xy 299.653967 -316.900689) (xy 299.699628 -316.877958) (xy 299.748234 -316.862499)
			(xy 299.798637 -316.854676) (xy 299.849643 -316.854676) (xy 299.900046 -316.862499) (xy 299.948652 -316.877958)
			(xy 299.994313 -316.900689) (xy 300.015402 -316.915038) (xy 300.021937 -316.919323) (xy 300.036804 -316.924111)
			(xy 300.044612 -316.924436) (xy 300.56074 -316.924436) (xy 300.566089 -316.924704) (xy 300.57363 -316.932294)
			(xy 300.573948 -316.937644) (xy 300.573948 -317.432182) (xy 306.618132 -317.432182) (xy 306.618132 -316.937644)
			(xy 306.61846 -316.932308) (xy 306.626004 -316.924762) (xy 306.63134 -316.924436) (xy 306.631848 -316.924436)
			(xy 308.104794 -316.924436) (xy 308.110097 -316.924927) (xy 308.117668 -316.932352) (xy 308.118256 -316.937644)
			(xy 308.118256 -317.432182) (xy 308.11824 -317.432436) (xy 415.718244 -317.432436) (xy 415.718244 -316.937644)
			(xy 415.718819 -316.932398) (xy 415.72621 -316.924956) (xy 415.731452 -316.924436) (xy 417.204652 -316.924436)
			(xy 417.209988 -316.924764) (xy 417.217535 -316.932308) (xy 417.21786 -316.937644) (xy 417.21786 -317.432182)
			(xy 423.262044 -317.432182) (xy 423.262044 -316.937644) (xy 423.262619 -316.932398) (xy 423.27001 -316.924956)
			(xy 423.275252 -316.924436) (xy 423.27576 -316.924436) (xy 423.791634 -316.924436) (xy 423.799443 -316.924105)
			(xy 423.814315 -316.919332) (xy 423.820844 -316.915038) (xy 423.841933 -316.900689) (xy 423.887594 -316.877958)
			(xy 423.9362 -316.862499) (xy 423.986603 -316.854676) (xy 424.037609 -316.854676) (xy 424.088012 -316.862499)
			(xy 424.136618 -316.877958) (xy 424.182279 -316.900689) (xy 424.203368 -316.915038) (xy 424.209911 -316.91931)
			(xy 424.224772 -316.924106) (xy 424.232578 -316.924436) (xy 424.748706 -316.924436) (xy 424.75401 -316.924919)
			(xy 424.761581 -316.93235) (xy 424.762168 -316.937644) (xy 424.762168 -317.432182) (xy 424.762151 -317.432436)
			(xy 430.806352 -317.432436) (xy 430.806352 -317.431928) (xy 430.806352 -316.937644) (xy 430.806752 -316.932327)
			(xy 430.814246 -316.924786) (xy 430.81956 -316.924436) (xy 431.335688 -316.924436) (xy 431.343499 -316.924128)
			(xy 431.358371 -316.919339) (xy 431.364898 -316.915038) (xy 431.385987 -316.900689) (xy 431.431648 -316.877958)
			(xy 431.480254 -316.862499) (xy 431.530657 -316.854676) (xy 431.581663 -316.854676) (xy 431.632066 -316.862499)
			(xy 431.680672 -316.877958) (xy 431.726333 -316.900689) (xy 431.747422 -316.915038) (xy 431.753953 -316.91933)
			(xy 431.768823 -316.924114) (xy 431.776632 -316.924436) (xy 432.29276 -316.924436) (xy 432.298098 -316.924758)
			(xy 432.305643 -316.932306) (xy 432.305968 -316.937644) (xy 432.305968 -317.432182) (xy 438.350152 -317.432182)
			(xy 438.350152 -316.937644) (xy 438.350552 -316.932327) (xy 438.358046 -316.924786) (xy 438.36336 -316.924436)
			(xy 438.363868 -316.924436) (xy 438.879742 -316.924436) (xy 438.887551 -316.924108) (xy 438.902423 -316.919333)
			(xy 438.908952 -316.915038) (xy 438.930041 -316.900689) (xy 438.975702 -316.877958) (xy 439.024308 -316.862499)
			(xy 439.074711 -316.854676) (xy 439.125717 -316.854676) (xy 439.17612 -316.862499) (xy 439.224726 -316.877958)
			(xy 439.270387 -316.900689) (xy 439.291476 -316.915038) (xy 439.298017 -316.919313) (xy 439.31288 -316.924107)
			(xy 439.320686 -316.924436) (xy 439.836814 -316.924436) (xy 439.842119 -316.924914) (xy 439.849689 -316.932349)
			(xy 439.850276 -316.937644) (xy 439.850276 -317.432182) (xy 439.850259 -317.432436) (xy 445.89446 -317.432436)
			(xy 445.89446 -317.431928) (xy 445.89446 -316.937644) (xy 445.894853 -316.932325) (xy 445.902351 -316.924784)
			(xy 445.907668 -316.924436) (xy 446.423796 -316.924436) (xy 446.431607 -316.924131) (xy 446.446479 -316.91934)
			(xy 446.453006 -316.915038) (xy 446.474095 -316.900689) (xy 446.519756 -316.877958) (xy 446.568362 -316.862499)
			(xy 446.618765 -316.854676) (xy 446.669771 -316.854676) (xy 446.720174 -316.862499) (xy 446.76878 -316.877958)
			(xy 446.814441 -316.900689) (xy 446.83553 -316.915038) (xy 446.842059 -316.919334) (xy 446.856931 -316.924115)
			(xy 446.86474 -316.924436) (xy 447.380868 -316.924436) (xy 447.386207 -316.924753) (xy 447.393752 -316.932305)
			(xy 447.394076 -316.937644) (xy 447.394076 -317.432182) (xy 447.394052 -317.432436) (xy 453.43826 -317.432436)
			(xy 453.43826 -317.431928) (xy 453.43826 -316.937644) (xy 453.438653 -316.932325) (xy 453.446151 -316.924784)
			(xy 453.451468 -316.924436) (xy 453.967596 -316.924436) (xy 453.975407 -316.924131) (xy 453.990279 -316.91934)
			(xy 453.996806 -316.915038) (xy 454.017895 -316.900689) (xy 454.063556 -316.877958) (xy 454.112162 -316.862499)
			(xy 454.162565 -316.854676) (xy 454.213571 -316.854676) (xy 454.263974 -316.862499) (xy 454.31258 -316.877958)
			(xy 454.358241 -316.900689) (xy 454.37933 -316.915038) (xy 454.385859 -316.919334) (xy 454.400731 -316.924115)
			(xy 454.40854 -316.924436) (xy 454.924668 -316.924436) (xy 454.930007 -316.924753) (xy 454.937552 -316.932305)
			(xy 454.937876 -316.937644) (xy 454.937876 -317.432182) (xy 454.937367 -317.43748) (xy 454.929955 -317.445052)
			(xy 454.924668 -317.445644) (xy 454.408794 -317.445644) (xy 454.400983 -317.445948) (xy 454.386111 -317.45074)
			(xy 454.379584 -317.455042) (xy 454.358464 -317.469393) (xy 454.312739 -317.49212) (xy 454.264066 -317.507549)
			(xy 454.213599 -317.515315) (xy 454.188068 -317.515748) (xy 454.162537 -317.51533) (xy 454.112072 -317.507549)
			(xy 454.0634 -317.492115) (xy 454.017673 -317.469392) (xy 453.996552 -317.455042) (xy 453.990028 -317.450738)
			(xy 453.975152 -317.445962) (xy 453.967342 -317.445644) (xy 453.451468 -317.445644) (xy 453.44621 -317.44513)
			(xy 453.438771 -317.437694) (xy 453.43826 -317.432436) (xy 447.394052 -317.432436) (xy 447.393567 -317.43748)
			(xy 447.386155 -317.445052) (xy 447.380868 -317.445644) (xy 446.864994 -317.445644) (xy 446.857183 -317.445948)
			(xy 446.842311 -317.45074) (xy 446.835784 -317.455042) (xy 446.814664 -317.469393) (xy 446.768939 -317.49212)
			(xy 446.720266 -317.507549) (xy 446.669799 -317.515315) (xy 446.644268 -317.515748) (xy 446.618737 -317.51533)
			(xy 446.568272 -317.507549) (xy 446.5196 -317.492115) (xy 446.473873 -317.469392) (xy 446.452752 -317.455042)
			(xy 446.446228 -317.450738) (xy 446.431352 -317.445962) (xy 446.423542 -317.445644) (xy 445.907668 -317.445644)
			(xy 445.90241 -317.44513) (xy 445.894971 -317.437694) (xy 445.89446 -317.432436) (xy 439.850259 -317.432436)
			(xy 439.84991 -317.437611) (xy 439.842242 -317.445297) (xy 439.836814 -317.445644) (xy 439.32094 -317.445644)
			(xy 439.313131 -317.445967) (xy 439.298259 -317.450746) (xy 439.29173 -317.455042) (xy 439.270625 -317.469417)
			(xy 439.224895 -317.492138) (xy 439.176217 -317.507561) (xy 439.125746 -317.515319) (xy 439.100214 -317.515748)
			(xy 439.074684 -317.515307) (xy 439.02422 -317.507533) (xy 438.975548 -317.492105) (xy 438.92982 -317.469389)
			(xy 438.908698 -317.455042) (xy 438.902164 -317.450755) (xy 438.887296 -317.445969) (xy 438.879488 -317.445644)
			(xy 438.363614 -317.445644) (xy 438.358177 -317.44531) (xy 438.350489 -317.437619) (xy 438.350152 -317.432182)
			(xy 432.305968 -317.432182) (xy 432.305466 -317.437482) (xy 432.298049 -317.445054) (xy 432.29276 -317.445644)
			(xy 431.776886 -317.445644) (xy 431.769075 -317.445944) (xy 431.754203 -317.450739) (xy 431.747676 -317.455042)
			(xy 431.726558 -317.469397) (xy 431.680833 -317.492122) (xy 431.632159 -317.507551) (xy 431.581691 -317.515316)
			(xy 431.55616 -317.515748) (xy 431.530629 -317.515334) (xy 431.480164 -317.507552) (xy 431.431491 -317.492116)
			(xy 431.385765 -317.469393) (xy 431.364644 -317.455042) (xy 431.358122 -317.450735) (xy 431.343245 -317.445961)
			(xy 431.335434 -317.445644) (xy 430.81956 -317.445644) (xy 430.814301 -317.445136) (xy 430.806863 -317.437695)
			(xy 430.806352 -317.432436) (xy 424.762151 -317.432436) (xy 424.761809 -317.437613) (xy 424.754136 -317.4453)
			(xy 424.748706 -317.445644) (xy 424.232832 -317.445644) (xy 424.225022 -317.445964) (xy 424.210151 -317.450745)
			(xy 424.203622 -317.455042) (xy 424.182491 -317.469377) (xy 424.136771 -317.492107) (xy 424.0881 -317.507541)
			(xy 424.037636 -317.515312) (xy 424.012106 -317.515748) (xy 423.986576 -317.515311) (xy 423.936112 -317.507536)
			(xy 423.887439 -317.492107) (xy 423.841712 -317.46939) (xy 423.82059 -317.455042) (xy 423.814057 -317.450752)
			(xy 423.799188 -317.445968) (xy 423.79138 -317.445644) (xy 423.275506 -317.445644) (xy 423.270068 -317.445315)
			(xy 423.26238 -317.437621) (xy 423.262044 -317.432182) (xy 417.21786 -317.432182) (xy 417.217365 -317.437484)
			(xy 417.209943 -317.445056) (xy 417.204652 -317.445644) (xy 415.731452 -317.445644) (xy 415.726192 -317.445141)
			(xy 415.718755 -317.437696) (xy 415.718244 -317.432436) (xy 308.11824 -317.432436) (xy 308.117908 -317.437616)
			(xy 308.110228 -317.445303) (xy 308.104794 -317.445644) (xy 306.631594 -317.445644) (xy 306.626154 -317.445323)
			(xy 306.618467 -317.437623) (xy 306.618132 -317.432182) (xy 300.573948 -317.432182) (xy 300.573464 -317.437487)
			(xy 300.566035 -317.44506) (xy 300.56074 -317.445644) (xy 300.044866 -317.445644) (xy 300.037058 -317.445978)
			(xy 300.022186 -317.450749) (xy 300.015656 -317.455042) (xy 299.994543 -317.469405) (xy 299.948816 -317.492129)
			(xy 299.90014 -317.507555) (xy 299.849672 -317.515317) (xy 299.82414 -317.515748) (xy 299.79861 -317.515294)
			(xy 299.748147 -317.507524) (xy 299.699475 -317.4921) (xy 299.653746 -317.469388) (xy 299.632624 -317.455042)
			(xy 299.626084 -317.450765) (xy 299.611221 -317.445973) (xy 299.603414 -317.445644) (xy 299.08754 -317.445644)
			(xy 299.082222 -317.44525) (xy 299.074681 -317.437752) (xy 299.074332 -317.432436) (xy 293.030132 -317.432436)
			(xy 293.029807 -317.437618) (xy 293.022122 -317.445306) (xy 293.016686 -317.445644) (xy 292.500812 -317.445644)
			(xy 292.493002 -317.445956) (xy 292.47813 -317.450742) (xy 292.471602 -317.455042) (xy 292.450477 -317.469385)
			(xy 292.404754 -317.492114) (xy 292.356082 -317.507545) (xy 292.305617 -317.515314) (xy 292.280086 -317.515748)
			(xy 292.254555 -317.515321) (xy 292.204091 -317.507543) (xy 292.155418 -317.492111) (xy 292.109691 -317.469391)
			(xy 292.08857 -317.455042) (xy 292.082042 -317.450745) (xy 292.067169 -317.445965) (xy 292.05936 -317.445644)
			(xy 291.543486 -317.445644) (xy 291.538045 -317.445328) (xy 291.530359 -317.437624) (xy 291.530024 -317.432182)
			(xy 285.48584 -317.432182) (xy 285.485363 -317.437489) (xy 285.477929 -317.445062) (xy 285.472632 -317.445644)
			(xy 284.956758 -317.445644) (xy 284.948949 -317.445975) (xy 284.934078 -317.450748) (xy 284.927548 -317.455042)
			(xy 284.906438 -317.469409) (xy 284.86071 -317.492132) (xy 284.812033 -317.507557) (xy 284.761564 -317.515318)
			(xy 284.736032 -317.515748) (xy 284.710502 -317.515298) (xy 284.660039 -317.507527) (xy 284.611366 -317.492102)
			(xy 284.565638 -317.469388) (xy 284.544516 -317.455042) (xy 284.537978 -317.450762) (xy 284.523113 -317.445971)
			(xy 284.515306 -317.445644) (xy 283.999432 -317.445644) (xy 283.994182 -317.445088) (xy 283.986739 -317.437684)
			(xy 283.986224 -317.432436) (xy 277.942017 -317.432436) (xy 277.941563 -317.437489) (xy 277.934129 -317.445062)
			(xy 277.928832 -317.445644) (xy 277.412958 -317.445644) (xy 277.405149 -317.445975) (xy 277.390278 -317.450748)
			(xy 277.383748 -317.455042) (xy 277.362638 -317.469409) (xy 277.31691 -317.492132) (xy 277.268233 -317.507557)
			(xy 277.217764 -317.515318) (xy 277.192232 -317.515748) (xy 277.166702 -317.515298) (xy 277.116239 -317.507527)
			(xy 277.067566 -317.492102) (xy 277.021838 -317.469388) (xy 277.000716 -317.455042) (xy 276.994178 -317.450762)
			(xy 276.979313 -317.445971) (xy 276.971506 -317.445644) (xy 276.455632 -317.445644) (xy 276.450382 -317.445088)
			(xy 276.442939 -317.437684) (xy 276.442424 -317.432436) (xy 270.398224 -317.432436) (xy 270.397907 -317.43762)
			(xy 270.390216 -317.445308) (xy 270.384778 -317.445644) (xy 269.868904 -317.445644) (xy 269.861093 -317.445952)
			(xy 269.846222 -317.450741) (xy 269.839694 -317.455042) (xy 269.818571 -317.469389) (xy 269.772848 -317.492116)
			(xy 269.724175 -317.507547) (xy 269.673709 -317.515315) (xy 269.648178 -317.515748) (xy 269.622647 -317.515325)
			(xy 269.572183 -317.507546) (xy 269.52351 -317.492113) (xy 269.477783 -317.469392) (xy 269.456662 -317.455042)
			(xy 269.450136 -317.450742) (xy 269.435262 -317.445964) (xy 269.427452 -317.445644) (xy 268.911578 -317.445644)
			(xy 268.906207 -317.445162) (xy 268.898622 -317.437554) (xy 268.898116 -317.432182) (xy 206.997808 -317.432182)
			(xy 206.997808 -317.432436) (xy 206.997329 -317.437703) (xy 206.989868 -317.445143) (xy 206.9846 -317.445644)
			(xy 206.468726 -317.445644) (xy 206.460849 -317.445908) (xy 206.445846 -317.450708) (xy 206.439262 -317.455042)
			(xy 206.418185 -317.469434) (xy 206.37254 -317.492263) (xy 206.323934 -317.50782) (xy 206.273517 -317.515739)
			(xy 206.248 -317.516256) (xy 206.222479 -317.515791) (xy 206.17205 -317.507891) (xy 206.123439 -317.492324)
			(xy 206.077802 -317.469461) (xy 206.056738 -317.455042) (xy 206.050137 -317.450743) (xy 206.035144 -317.445946)
			(xy 206.027274 -317.445644) (xy 205.5114 -317.445644) (xy 205.506146 -317.445109) (xy 205.498706 -317.437689)
			(xy 205.498192 -317.432436) (xy 199.454008 -317.432436) (xy 199.453529 -317.437703) (xy 199.446068 -317.445143)
			(xy 199.4408 -317.445644) (xy 198.924926 -317.445644) (xy 198.917049 -317.445908) (xy 198.902046 -317.450708)
			(xy 198.895462 -317.455042) (xy 198.874385 -317.469434) (xy 198.82874 -317.492263) (xy 198.780134 -317.50782)
			(xy 198.729717 -317.515739) (xy 198.7042 -317.516256) (xy 198.678679 -317.515791) (xy 198.62825 -317.507891)
			(xy 198.579639 -317.492324) (xy 198.534002 -317.469461) (xy 198.512938 -317.455042) (xy 198.506337 -317.450743)
			(xy 198.491344 -317.445946) (xy 198.483474 -317.445644) (xy 197.9676 -317.445644) (xy 197.962346 -317.445109)
			(xy 197.954906 -317.437689) (xy 197.954392 -317.432436) (xy 191.910208 -317.432436) (xy 191.909729 -317.437703)
			(xy 191.902268 -317.445143) (xy 191.897 -317.445644) (xy 191.896492 -317.445644) (xy 191.380872 -317.445644)
			(xy 191.372997 -317.445928) (xy 191.357993 -317.450715) (xy 191.351408 -317.455042) (xy 191.330346 -317.469458)
			(xy 191.284696 -317.492281) (xy 191.236085 -317.507832) (xy 191.185664 -317.515743) (xy 191.160146 -317.516256)
			(xy 191.134626 -317.515768) (xy 191.084198 -317.507875) (xy 191.035586 -317.492314) (xy 190.989948 -317.469458)
			(xy 190.968884 -317.455042) (xy 190.962295 -317.450722) (xy 190.947293 -317.445938) (xy 190.93942 -317.445644)
			(xy 190.423546 -317.445644) (xy 190.418244 -317.445145) (xy 190.410669 -317.437727) (xy 190.410084 -317.432436)
			(xy 184.3659 -317.432436) (xy 184.365428 -317.437705) (xy 184.357963 -317.445146) (xy 184.352692 -317.445644)
			(xy 183.836818 -317.445644) (xy 183.828945 -317.445948) (xy 183.813941 -317.450721) (xy 183.807354 -317.455042)
			(xy 183.786279 -317.469438) (xy 183.740634 -317.492265) (xy 183.692027 -317.507822) (xy 183.641609 -317.51574)
			(xy 183.616092 -317.516256) (xy 183.590573 -317.515745) (xy 183.540146 -317.507858) (xy 183.491534 -317.492305)
			(xy 183.445895 -317.469455) (xy 183.42483 -317.455042) (xy 183.418231 -317.45074) (xy 183.403237 -317.445944)
			(xy 183.395366 -317.445644) (xy 182.879492 -317.445644) (xy 182.874237 -317.445114) (xy 182.866797 -317.43769)
			(xy 182.866284 -317.432436) (xy 176.8221 -317.432436) (xy 176.821628 -317.437705) (xy 176.814163 -317.445146)
			(xy 176.808892 -317.445644) (xy 176.808384 -317.445644) (xy 176.292764 -317.445644) (xy 176.284889 -317.445925)
			(xy 176.269885 -317.450714) (xy 176.2633 -317.455042) (xy 176.242212 -317.469418) (xy 176.196571 -317.49225)
			(xy 176.147968 -317.507812) (xy 176.097554 -317.515736) (xy 176.072038 -317.516256) (xy 176.046517 -317.515772)
			(xy 175.99609 -317.507877) (xy 175.947478 -317.492316) (xy 175.90184 -317.469459) (xy 175.880776 -317.455042)
			(xy 175.874189 -317.450719) (xy 175.859186 -317.445937) (xy 175.851312 -317.445644) (xy 175.335438 -317.445644)
			(xy 175.330135 -317.44515) (xy 175.322561 -317.437728) (xy 175.321976 -317.432436) (xy 169.277792 -317.432436)
			(xy 169.277327 -317.437707) (xy 169.269857 -317.445148) (xy 169.264584 -317.445644) (xy 167.791384 -317.445644)
			(xy 167.786128 -317.44512) (xy 167.778688 -317.437691) (xy 167.778176 -317.432436) (xy 60.178188 -317.432436)
			(xy 60.177727 -317.437708) (xy 60.170254 -317.445149) (xy 60.16498 -317.445644) (xy 60.164472 -317.445644)
			(xy 58.691526 -317.445644) (xy 58.686221 -317.445158) (xy 58.678648 -317.43773) (xy 58.678064 -317.432436)
			(xy 52.63388 -317.432436) (xy 52.633426 -317.43771) (xy 52.625948 -317.445152) (xy 52.620672 -317.445644)
			(xy 52.104798 -317.445644) (xy 52.096924 -317.44594) (xy 52.08192 -317.450718) (xy 52.075334 -317.455042)
			(xy 52.054265 -317.469446) (xy 52.008617 -317.492272) (xy 51.960009 -317.507826) (xy 51.909589 -317.515741)
			(xy 51.884072 -317.516256) (xy 51.858552 -317.515755) (xy 51.808125 -317.507865) (xy 51.759513 -317.492309)
			(xy 51.713875 -317.469456) (xy 51.69281 -317.455042) (xy 51.686215 -317.450732) (xy 51.671218 -317.445942)
			(xy 51.663346 -317.445644) (xy 51.147472 -317.445644) (xy 51.142215 -317.445128) (xy 51.134775 -317.437693)
			(xy 51.134264 -317.432436) (xy 45.09008 -317.432436) (xy 45.089626 -317.43771) (xy 45.082148 -317.445152)
			(xy 45.076872 -317.445644) (xy 45.076364 -317.445644) (xy 44.560744 -317.445644) (xy 44.552868 -317.445916)
			(xy 44.537864 -317.45071) (xy 44.53128 -317.455042) (xy 44.510198 -317.469426) (xy 44.464555 -317.492257)
			(xy 44.41595 -317.507816) (xy 44.365534 -317.515738) (xy 44.340018 -317.516256) (xy 44.314497 -317.515782)
			(xy 44.264069 -317.507884) (xy 44.215457 -317.49232) (xy 44.16982 -317.46946) (xy 44.148756 -317.455042)
			(xy 44.142174 -317.450711) (xy 44.127167 -317.445934) (xy 44.119292 -317.445644) (xy 43.603418 -317.445644)
			(xy 43.598112 -317.445163) (xy 43.590539 -317.437732) (xy 43.589956 -317.432436) (xy 37.545772 -317.432436)
			(xy 37.545325 -317.437712) (xy 37.537842 -317.445154) (xy 37.532564 -317.445644) (xy 37.01669 -317.445644)
			(xy 37.008816 -317.445936) (xy 36.993812 -317.450717) (xy 36.987226 -317.455042) (xy 36.966159 -317.46945)
			(xy 36.920511 -317.492275) (xy 36.871901 -317.507828) (xy 36.821482 -317.515742) (xy 36.795964 -317.516256)
			(xy 36.770444 -317.515759) (xy 36.720017 -317.507868) (xy 36.671405 -317.492311) (xy 36.625767 -317.469457)
			(xy 36.604702 -317.455042) (xy 36.598109 -317.450729) (xy 36.58311 -317.44594) (xy 36.575238 -317.445644)
			(xy 36.059364 -317.445644) (xy 36.054106 -317.445133) (xy 36.046667 -317.437694) (xy 36.046156 -317.432436)
			(xy 30.001972 -317.432436) (xy 30.001525 -317.437712) (xy 29.994042 -317.445154) (xy 29.988764 -317.445644)
			(xy 29.47289 -317.445644) (xy 29.465016 -317.445936) (xy 29.450012 -317.450717) (xy 29.443426 -317.455042)
			(xy 29.422359 -317.46945) (xy 29.376711 -317.492275) (xy 29.328101 -317.507828) (xy 29.277682 -317.515742)
			(xy 29.252164 -317.516256) (xy 29.226644 -317.515759) (xy 29.176217 -317.507868) (xy 29.127605 -317.492311)
			(xy 29.081967 -317.469457) (xy 29.060902 -317.455042) (xy 29.054309 -317.450729) (xy 29.03931 -317.44594)
			(xy 29.031438 -317.445644) (xy 28.515564 -317.445644) (xy 28.510306 -317.445133) (xy 28.502867 -317.437694)
			(xy 28.502356 -317.432436) (xy 22.458172 -317.432436) (xy 22.457725 -317.437712) (xy 22.450242 -317.445154)
			(xy 22.444964 -317.445644) (xy 22.444456 -317.445644) (xy 21.928836 -317.445644) (xy 21.92096 -317.445913)
			(xy 21.905956 -317.450709) (xy 21.899372 -317.455042) (xy 21.878292 -317.46943) (xy 21.832648 -317.492259)
			(xy 21.784043 -317.507818) (xy 21.733626 -317.515738) (xy 21.70811 -317.516256) (xy 21.682589 -317.515786)
			(xy 21.632161 -317.507887) (xy 21.583549 -317.492321) (xy 21.537912 -317.46946) (xy 21.516848 -317.455042)
			(xy 21.510267 -317.450708) (xy 21.495259 -317.445932) (xy 21.487384 -317.445644) (xy 20.97151 -317.445644)
			(xy 20.966203 -317.445169) (xy 20.95863 -317.437733) (xy 20.958048 -317.432436) (xy 2.509012 -317.432436)
			(xy 2.509012 -318.282574) (xy 16.85798 -318.282574) (xy 16.85798 -317.788036) (xy 16.85835 -317.782711)
			(xy 16.865865 -317.775169) (xy 16.871188 -317.774828) (xy 16.871696 -317.774828) (xy 17.38757 -317.774828)
			(xy 17.39538 -317.774514) (xy 17.410252 -317.769729) (xy 17.41678 -317.76543) (xy 17.437869 -317.751081)
			(xy 17.48353 -317.72835) (xy 17.532136 -317.712891) (xy 17.582539 -317.705068) (xy 17.633545 -317.705068)
			(xy 17.683948 -317.712891) (xy 17.732554 -317.72835) (xy 17.778215 -317.751081) (xy 17.799304 -317.76543)
			(xy 17.805839 -317.769715) (xy 17.820706 -317.774503) (xy 17.828514 -317.774828) (xy 18.344642 -317.774828)
			(xy 18.349949 -317.775294) (xy 18.357517 -317.782738) (xy 18.358104 -317.788036) (xy 18.358104 -318.282574)
			(xy 18.358077 -318.282828) (xy 24.402288 -318.282828) (xy 24.402288 -318.28232) (xy 24.402288 -317.788036)
			(xy 24.402651 -317.782709) (xy 24.410171 -317.775167) (xy 24.415496 -317.774828) (xy 24.931624 -317.774828)
			(xy 24.939436 -317.774536) (xy 24.954308 -317.769736) (xy 24.960834 -317.76543) (xy 24.981923 -317.751081)
			(xy 25.027584 -317.72835) (xy 25.07619 -317.712891) (xy 25.126593 -317.705068) (xy 25.177599 -317.705068)
			(xy 25.228002 -317.712891) (xy 25.276608 -317.72835) (xy 25.322269 -317.751081) (xy 25.343358 -317.76543)
			(xy 25.349881 -317.769736) (xy 25.364757 -317.774511) (xy 25.372568 -317.774828) (xy 25.888696 -317.774828)
			(xy 25.894036 -317.775133) (xy 25.90158 -317.782695) (xy 25.901904 -317.788036) (xy 25.901904 -318.282574)
			(xy 25.901878 -318.282828) (xy 31.946088 -318.282828) (xy 31.946088 -318.28232) (xy 31.946088 -317.788036)
			(xy 31.946451 -317.782709) (xy 31.953971 -317.775167) (xy 31.959296 -317.774828) (xy 32.475424 -317.774828)
			(xy 32.483236 -317.774536) (xy 32.498108 -317.769736) (xy 32.504634 -317.76543) (xy 32.525723 -317.751081)
			(xy 32.571384 -317.72835) (xy 32.61999 -317.712891) (xy 32.670393 -317.705068) (xy 32.721399 -317.705068)
			(xy 32.771802 -317.712891) (xy 32.820408 -317.72835) (xy 32.866069 -317.751081) (xy 32.887158 -317.76543)
			(xy 32.893681 -317.769736) (xy 32.908557 -317.774511) (xy 32.916368 -317.774828) (xy 33.432496 -317.774828)
			(xy 33.437836 -317.775133) (xy 33.44538 -317.782695) (xy 33.445704 -317.788036) (xy 33.445704 -318.282574)
			(xy 39.489888 -318.282574) (xy 39.489888 -317.788036) (xy 39.490251 -317.782709) (xy 39.497771 -317.775167)
			(xy 39.503096 -317.774828) (xy 39.503604 -317.774828) (xy 40.019478 -317.774828) (xy 40.027289 -317.774517)
			(xy 40.04216 -317.76973) (xy 40.048688 -317.76543) (xy 40.069777 -317.751081) (xy 40.115438 -317.72835)
			(xy 40.164044 -317.712891) (xy 40.214447 -317.705068) (xy 40.265453 -317.705068) (xy 40.315856 -317.712891)
			(xy 40.364462 -317.72835) (xy 40.410123 -317.751081) (xy 40.431212 -317.76543) (xy 40.437746 -317.769718)
			(xy 40.452614 -317.774504) (xy 40.460422 -317.774828) (xy 40.97655 -317.774828) (xy 40.981845 -317.775355)
			(xy 40.989418 -317.782753) (xy 40.990012 -317.788036) (xy 40.990012 -318.282574) (xy 40.989985 -318.282828)
			(xy 47.034196 -318.282828) (xy 47.034196 -318.28232) (xy 47.034196 -317.788036) (xy 47.034551 -317.782708)
			(xy 47.042076 -317.775164) (xy 47.047404 -317.774828) (xy 47.563532 -317.774828) (xy 47.571341 -317.774498)
			(xy 47.586213 -317.769724) (xy 47.592742 -317.76543) (xy 47.613831 -317.751081) (xy 47.659492 -317.72835)
			(xy 47.708098 -317.712891) (xy 47.758501 -317.705068) (xy 47.809507 -317.705068) (xy 47.85991 -317.712891)
			(xy 47.908516 -317.72835) (xy 47.954177 -317.751081) (xy 47.975266 -317.76543) (xy 47.98181 -317.7697)
			(xy 47.99667 -317.774498) (xy 48.004476 -317.774828) (xy 48.520604 -317.774828) (xy 48.525946 -317.775128)
			(xy 48.533488 -317.782693) (xy 48.533812 -317.788036) (xy 48.533812 -318.282574) (xy 54.577996 -318.282574)
			(xy 54.577996 -317.788036) (xy 54.578351 -317.782708) (xy 54.585876 -317.775164) (xy 54.591204 -317.774828)
			(xy 56.064658 -317.774828) (xy 56.069954 -317.77535) (xy 56.077527 -317.782752) (xy 56.07812 -317.788036)
			(xy 56.07812 -318.282574) (xy 56.078105 -318.282828) (xy 163.678108 -318.282828) (xy 163.678108 -318.28232)
			(xy 163.678108 -317.788036) (xy 163.678453 -317.782705) (xy 163.685985 -317.775161) (xy 163.691316 -317.774828)
			(xy 165.164516 -317.774828) (xy 165.169859 -317.775119) (xy 165.177402 -317.782691) (xy 165.177724 -317.788036)
			(xy 165.177724 -318.282574) (xy 171.221908 -318.282574) (xy 171.221908 -317.788036) (xy 171.222253 -317.782705)
			(xy 171.229785 -317.775161) (xy 171.235116 -317.774828) (xy 171.235624 -317.774828) (xy 171.751498 -317.774828)
			(xy 171.759309 -317.774525) (xy 171.774181 -317.769733) (xy 171.780708 -317.76543) (xy 171.801797 -317.751081)
			(xy 171.847458 -317.72835) (xy 171.896064 -317.712891) (xy 171.946467 -317.705068) (xy 171.997473 -317.705068)
			(xy 172.047876 -317.712891) (xy 172.096482 -317.72835) (xy 172.142143 -317.751081) (xy 172.163232 -317.76543)
			(xy 172.169761 -317.769726) (xy 172.184633 -317.774507) (xy 172.192442 -317.774828) (xy 172.70857 -317.774828)
			(xy 172.713868 -317.775342) (xy 172.72144 -317.78275) (xy 172.722032 -317.788036) (xy 172.722032 -318.282574)
			(xy 172.722016 -318.282828) (xy 178.766216 -318.282828) (xy 178.766216 -318.28232) (xy 178.766216 -317.788036)
			(xy 178.766553 -317.782703) (xy 178.774091 -317.775158) (xy 178.779424 -317.774828) (xy 179.295552 -317.774828)
			(xy 179.303362 -317.774506) (xy 179.318233 -317.769727) (xy 179.324762 -317.76543) (xy 179.345851 -317.751081)
			(xy 179.391512 -317.72835) (xy 179.440118 -317.712891) (xy 179.490521 -317.705068) (xy 179.541527 -317.705068)
			(xy 179.59193 -317.712891) (xy 179.640536 -317.72835) (xy 179.686197 -317.751081) (xy 179.707286 -317.76543)
			(xy 179.713825 -317.769708) (xy 179.728689 -317.7745) (xy 179.736496 -317.774828) (xy 180.252624 -317.774828)
			(xy 180.257968 -317.775114) (xy 180.26551 -317.78269) (xy 180.265832 -317.788036) (xy 180.265832 -318.282574)
			(xy 186.310016 -318.282574) (xy 186.310016 -317.788036) (xy 186.310353 -317.782703) (xy 186.317891 -317.775158)
			(xy 186.323224 -317.774828) (xy 186.323732 -317.774828) (xy 186.839606 -317.774828) (xy 186.847418 -317.774529)
			(xy 186.862289 -317.769734) (xy 186.868816 -317.76543) (xy 186.889905 -317.751081) (xy 186.935566 -317.72835)
			(xy 186.984172 -317.712891) (xy 187.034575 -317.705068) (xy 187.085581 -317.705068) (xy 187.135984 -317.712891)
			(xy 187.18459 -317.72835) (xy 187.230251 -317.751081) (xy 187.25134 -317.76543) (xy 187.257867 -317.769729)
			(xy 187.27274 -317.774508) (xy 187.28055 -317.774828) (xy 187.796678 -317.774828) (xy 187.801977 -317.775336)
			(xy 187.809549 -317.782749) (xy 187.81014 -317.788036) (xy 187.81014 -318.282574) (xy 187.810124 -318.282828)
			(xy 193.854324 -318.282828) (xy 193.854324 -318.28232) (xy 193.854324 -317.788036) (xy 193.854654 -317.782701)
			(xy 193.862197 -317.775156) (xy 193.867532 -317.774828) (xy 194.38366 -317.774828) (xy 194.39147 -317.774509)
			(xy 194.406342 -317.769728) (xy 194.41287 -317.76543) (xy 194.433959 -317.751081) (xy 194.47962 -317.72835)
			(xy 194.528226 -317.712891) (xy 194.578629 -317.705068) (xy 194.629635 -317.705068) (xy 194.680038 -317.712891)
			(xy 194.728644 -317.72835) (xy 194.774305 -317.751081) (xy 194.795394 -317.76543) (xy 194.801932 -317.769711)
			(xy 194.816797 -317.774502) (xy 194.824604 -317.774828) (xy 195.340732 -317.774828) (xy 195.346077 -317.775109)
			(xy 195.353618 -317.782689) (xy 195.35394 -317.788036) (xy 195.35394 -318.282574) (xy 195.353917 -318.282828)
			(xy 201.398124 -318.282828) (xy 201.398124 -318.28232) (xy 201.398124 -317.788036) (xy 201.398454 -317.782701)
			(xy 201.405997 -317.775156) (xy 201.411332 -317.774828) (xy 201.92746 -317.774828) (xy 201.93527 -317.774509)
			(xy 201.950142 -317.769728) (xy 201.95667 -317.76543) (xy 201.977759 -317.751081) (xy 202.02342 -317.72835)
			(xy 202.072026 -317.712891) (xy 202.122429 -317.705068) (xy 202.173435 -317.705068) (xy 202.223838 -317.712891)
			(xy 202.272444 -317.72835) (xy 202.318105 -317.751081) (xy 202.339194 -317.76543) (xy 202.345732 -317.769711)
			(xy 202.360597 -317.774502) (xy 202.368404 -317.774828) (xy 202.884532 -317.774828) (xy 202.889877 -317.775109)
			(xy 202.897418 -317.782689) (xy 202.89774 -317.788036) (xy 202.89774 -318.28232) (xy 264.798048 -318.28232)
			(xy 264.798048 -317.787782) (xy 264.798539 -317.782413) (xy 264.80614 -317.774828) (xy 264.81151 -317.77432)
			(xy 265.327638 -317.77432) (xy 265.335447 -317.773993) (xy 265.350319 -317.769218) (xy 265.356848 -317.764922)
			(xy 265.377937 -317.750573) (xy 265.423598 -317.727842) (xy 265.472204 -317.712383) (xy 265.522607 -317.70456)
			(xy 265.573613 -317.70456) (xy 265.624016 -317.712383) (xy 265.672622 -317.727842) (xy 265.718283 -317.750573)
			(xy 265.739372 -317.764922) (xy 265.745915 -317.769194) (xy 265.760776 -317.77399) (xy 265.768582 -317.77432)
			(xy 266.28471 -317.77432) (xy 266.290071 -317.774842) (xy 266.297655 -317.782422) (xy 266.298172 -317.787782)
			(xy 266.298172 -318.28232) (xy 272.342356 -318.28232) (xy 272.342356 -317.787782) (xy 272.342813 -317.782472)
			(xy 272.350263 -317.774901) (xy 272.355564 -317.77432) (xy 272.871692 -317.77432) (xy 272.879503 -317.774016)
			(xy 272.894375 -317.769225) (xy 272.900902 -317.764922) (xy 272.921991 -317.750573) (xy 272.967652 -317.727842)
			(xy 273.016258 -317.712383) (xy 273.066661 -317.70456) (xy 273.117667 -317.70456) (xy 273.16807 -317.712383)
			(xy 273.216676 -317.727842) (xy 273.262337 -317.750573) (xy 273.283426 -317.764922) (xy 273.289957 -317.769215)
			(xy 273.304827 -317.773998) (xy 273.312636 -317.77432) (xy 273.828764 -317.77432) (xy 273.834098 -317.774654)
			(xy 273.841643 -317.782194) (xy 273.841972 -317.787528) (xy 273.841972 -317.788036) (xy 273.841972 -318.28232)
			(xy 279.886156 -318.28232) (xy 279.886156 -317.787782) (xy 279.886613 -317.782472) (xy 279.894063 -317.774901)
			(xy 279.899364 -317.77432) (xy 280.415492 -317.77432) (xy 280.423303 -317.774016) (xy 280.438175 -317.769225)
			(xy 280.444702 -317.764922) (xy 280.465791 -317.750573) (xy 280.511452 -317.727842) (xy 280.560058 -317.712383)
			(xy 280.610461 -317.70456) (xy 280.661467 -317.70456) (xy 280.71187 -317.712383) (xy 280.760476 -317.727842)
			(xy 280.806137 -317.750573) (xy 280.827226 -317.764922) (xy 280.833757 -317.769215) (xy 280.848627 -317.773998)
			(xy 280.856436 -317.77432) (xy 281.372564 -317.77432) (xy 281.377898 -317.774654) (xy 281.385443 -317.782194)
			(xy 281.385772 -317.787528) (xy 281.385772 -317.788036) (xy 281.385772 -318.28232) (xy 287.429956 -318.28232)
			(xy 287.429956 -317.787782) (xy 287.43044 -317.782411) (xy 287.438046 -317.774826) (xy 287.443418 -317.77432)
			(xy 287.959546 -317.77432) (xy 287.967355 -317.773997) (xy 287.982228 -317.769219) (xy 287.988756 -317.764922)
			(xy 288.009845 -317.750573) (xy 288.055506 -317.727842) (xy 288.104112 -317.712383) (xy 288.154515 -317.70456)
			(xy 288.205521 -317.70456) (xy 288.255924 -317.712383) (xy 288.30453 -317.727842) (xy 288.350191 -317.750573)
			(xy 288.37128 -317.764922) (xy 288.377821 -317.769197) (xy 288.392684 -317.773992) (xy 288.40049 -317.77432)
			(xy 288.916618 -317.77432) (xy 288.92198 -317.774836) (xy 288.929564 -317.78242) (xy 288.93008 -317.787782)
			(xy 288.93008 -318.28232) (xy 294.974264 -318.28232) (xy 294.974264 -317.787782) (xy 294.974714 -317.78247)
			(xy 294.982168 -317.774898) (xy 294.987472 -317.77432) (xy 295.5036 -317.77432) (xy 295.511412 -317.77402)
			(xy 295.526283 -317.769226) (xy 295.53281 -317.764922) (xy 295.553899 -317.750573) (xy 295.59956 -317.727842)
			(xy 295.648166 -317.712383) (xy 295.698569 -317.70456) (xy 295.749575 -317.70456) (xy 295.799978 -317.712383)
			(xy 295.848584 -317.727842) (xy 295.894245 -317.750573) (xy 295.915334 -317.764922) (xy 295.921863 -317.769218)
			(xy 295.936735 -317.773999) (xy 295.944544 -317.77432) (xy 296.460672 -317.77432) (xy 296.466007 -317.774648)
			(xy 296.473552 -317.782193) (xy 296.47388 -317.787528) (xy 296.47388 -317.788036) (xy 296.47388 -318.28232)
			(xy 302.518064 -318.28232) (xy 302.518064 -317.787782) (xy 302.51837 -317.782338) (xy 302.526081 -317.774652)
			(xy 302.531526 -317.77432) (xy 304.004726 -317.77432) (xy 304.010089 -317.774831) (xy 304.017672 -317.782419)
			(xy 304.018188 -317.787782) (xy 304.018188 -318.28232) (xy 411.618176 -318.28232) (xy 411.618176 -317.787782)
			(xy 411.618615 -317.782467) (xy 411.626077 -317.774895) (xy 411.631384 -317.77432) (xy 413.104584 -317.77432)
			(xy 413.109921 -317.77464) (xy 413.117465 -317.782191) (xy 413.117792 -317.787528) (xy 413.117792 -317.788036)
			(xy 413.117792 -318.28232) (xy 419.161976 -318.28232) (xy 419.161976 -317.787782) (xy 419.162271 -317.782335)
			(xy 419.16999 -317.774648) (xy 419.175438 -317.77432) (xy 419.691566 -317.77432) (xy 419.699376 -317.774005)
			(xy 419.714248 -317.769221) (xy 419.720776 -317.764922) (xy 419.741865 -317.750573) (xy 419.787526 -317.727842)
			(xy 419.836132 -317.712383) (xy 419.886535 -317.70456) (xy 419.937541 -317.70456) (xy 419.987944 -317.712383)
			(xy 420.03655 -317.727842) (xy 420.082211 -317.750573) (xy 420.1033 -317.764922) (xy 420.109837 -317.769205)
			(xy 420.124703 -317.773994) (xy 420.13251 -317.77432) (xy 420.648638 -317.77432) (xy 420.654002 -317.774824)
			(xy 420.661584 -317.782417) (xy 420.6621 -317.787782) (xy 420.6621 -318.28232) (xy 426.706284 -318.28232)
			(xy 426.706284 -317.787782) (xy 426.706716 -317.782465) (xy 426.714183 -317.774893) (xy 426.719492 -317.77432)
			(xy 427.23562 -317.77432) (xy 427.243432 -317.774028) (xy 427.258304 -317.769228) (xy 427.26483 -317.764922)
			(xy 427.285919 -317.750573) (xy 427.33158 -317.727842) (xy 427.380186 -317.712383) (xy 427.430589 -317.70456)
			(xy 427.481595 -317.70456) (xy 427.531998 -317.712383) (xy 427.580604 -317.727842) (xy 427.626265 -317.750573)
			(xy 427.647354 -317.764922) (xy 427.653879 -317.769225) (xy 427.668754 -317.774002) (xy 427.676564 -317.77432)
			(xy 428.192692 -317.77432) (xy 428.19803 -317.774635) (xy 428.205573 -317.782189) (xy 428.2059 -317.787528)
			(xy 428.2059 -317.788036) (xy 428.2059 -318.28232) (xy 434.250084 -318.28232) (xy 434.250084 -317.787782)
			(xy 434.250372 -317.782333) (xy 434.258096 -317.774646) (xy 434.263546 -317.77432) (xy 434.779674 -317.77432)
			(xy 434.787485 -317.774009) (xy 434.802356 -317.769222) (xy 434.808884 -317.764922) (xy 434.829973 -317.750573)
			(xy 434.875634 -317.727842) (xy 434.92424 -317.712383) (xy 434.974643 -317.70456) (xy 435.025649 -317.70456)
			(xy 435.076052 -317.712383) (xy 435.124658 -317.727842) (xy 435.170319 -317.750573) (xy 435.191408 -317.764922)
			(xy 435.197943 -317.769208) (xy 435.21281 -317.773996) (xy 435.220618 -317.77432) (xy 435.736746 -317.77432)
			(xy 435.742111 -317.774818) (xy 435.749693 -317.782416) (xy 435.750208 -317.787782) (xy 435.750208 -318.28232)
			(xy 441.794392 -318.28232) (xy 441.794392 -317.787782) (xy 441.794905 -317.782487) (xy 441.802316 -317.774919)
			(xy 441.8076 -317.77432) (xy 442.323728 -317.77432) (xy 442.331541 -317.774031) (xy 442.346412 -317.76923)
			(xy 442.352938 -317.764922) (xy 442.374027 -317.750573) (xy 442.419688 -317.727842) (xy 442.468294 -317.712383)
			(xy 442.518697 -317.70456) (xy 442.569703 -317.70456) (xy 442.620106 -317.712383) (xy 442.668712 -317.727842)
			(xy 442.714373 -317.750573) (xy 442.735462 -317.764922) (xy 442.742007 -317.76919) (xy 442.756867 -317.773989)
			(xy 442.764672 -317.77432) (xy 443.2808 -317.77432) (xy 443.286139 -317.774629) (xy 443.293682 -317.782188)
			(xy 443.294008 -317.787528) (xy 443.294008 -317.788036) (xy 443.294008 -318.28232) (xy 449.338192 -318.28232)
			(xy 449.338192 -317.787782) (xy 449.338705 -317.782487) (xy 449.346116 -317.774919) (xy 449.3514 -317.77432)
			(xy 449.867528 -317.77432) (xy 449.875341 -317.774031) (xy 449.890212 -317.76923) (xy 449.896738 -317.764922)
			(xy 449.917827 -317.750573) (xy 449.963488 -317.727842) (xy 450.012094 -317.712383) (xy 450.062497 -317.70456)
			(xy 450.113503 -317.70456) (xy 450.163906 -317.712383) (xy 450.212512 -317.727842) (xy 450.258173 -317.750573)
			(xy 450.279262 -317.764922) (xy 450.285807 -317.76919) (xy 450.300667 -317.773989) (xy 450.308472 -317.77432)
			(xy 450.8246 -317.77432) (xy 450.829939 -317.774629) (xy 450.837482 -317.782188) (xy 450.837808 -317.787528)
			(xy 450.837808 -317.788036) (xy 450.837808 -318.28232) (xy 450.837319 -318.287585) (xy 450.829866 -318.295027)
			(xy 450.8246 -318.295528) (xy 450.308726 -318.295528) (xy 450.30085 -318.295795) (xy 450.285846 -318.300593)
			(xy 450.279262 -318.304926) (xy 450.258184 -318.319316) (xy 450.212539 -318.342146) (xy 450.163934 -318.357704)
			(xy 450.113517 -318.365623) (xy 450.088 -318.36614) (xy 450.062479 -318.36566) (xy 450.012052 -318.357761)
			(xy 449.963441 -318.342198) (xy 449.917803 -318.319342) (xy 449.896738 -318.304926) (xy 449.890138 -318.300626)
			(xy 449.875145 -318.295829) (xy 449.867274 -318.295528) (xy 449.3514 -318.295528) (xy 449.346142 -318.295007)
			(xy 449.338701 -318.287577) (xy 449.338192 -318.28232) (xy 443.294008 -318.28232) (xy 443.293519 -318.287585)
			(xy 443.286066 -318.295027) (xy 443.2808 -318.295528) (xy 442.764926 -318.295528) (xy 442.75705 -318.295795)
			(xy 442.742046 -318.300593) (xy 442.735462 -318.304926) (xy 442.714384 -318.319316) (xy 442.668739 -318.342146)
			(xy 442.620134 -318.357704) (xy 442.569717 -318.365623) (xy 442.5442 -318.36614) (xy 442.518679 -318.36566)
			(xy 442.468252 -318.357761) (xy 442.419641 -318.342198) (xy 442.374003 -318.319342) (xy 442.352938 -318.304926)
			(xy 442.346338 -318.300626) (xy 442.331345 -318.295829) (xy 442.323474 -318.295528) (xy 441.8076 -318.295528)
			(xy 441.802342 -318.295007) (xy 441.794901 -318.287577) (xy 441.794392 -318.28232) (xy 435.750208 -318.28232)
			(xy 435.749719 -318.287585) (xy 435.742266 -318.295027) (xy 435.737 -318.295528) (xy 435.736492 -318.295528)
			(xy 435.220872 -318.295528) (xy 435.212997 -318.295815) (xy 435.197994 -318.300599) (xy 435.191408 -318.304926)
			(xy 435.170345 -318.31934) (xy 435.124695 -318.342164) (xy 435.076085 -318.357715) (xy 435.025664 -318.365627)
			(xy 435.000146 -318.36614) (xy 434.974626 -318.365637) (xy 434.9242 -318.357745) (xy 434.875589 -318.342189)
			(xy 434.82995 -318.319339) (xy 434.808884 -318.304926) (xy 434.802296 -318.300605) (xy 434.787293 -318.295822)
			(xy 434.77942 -318.295528) (xy 434.263546 -318.295528) (xy 434.25824 -318.295042) (xy 434.250665 -318.287616)
			(xy 434.250084 -318.28232) (xy 428.2059 -318.28232) (xy 428.205418 -318.287587) (xy 428.19796 -318.295029)
			(xy 428.192692 -318.295528) (xy 427.676818 -318.295528) (xy 427.668945 -318.295835) (xy 427.653941 -318.300606)
			(xy 427.647354 -318.304926) (xy 427.626278 -318.31932) (xy 427.580633 -318.342148) (xy 427.532026 -318.357706)
			(xy 427.481609 -318.365624) (xy 427.456092 -318.36614) (xy 427.430573 -318.365614) (xy 427.380148 -318.357729)
			(xy 427.331537 -318.34218) (xy 427.285897 -318.319336) (xy 427.26483 -318.304926) (xy 427.258232 -318.300622)
			(xy 427.243237 -318.295828) (xy 427.235366 -318.295528) (xy 426.719492 -318.295528) (xy 426.714233 -318.295013)
			(xy 426.706792 -318.287578) (xy 426.706284 -318.28232) (xy 420.6621 -318.28232) (xy 420.661618 -318.287587)
			(xy 420.65416 -318.295029) (xy 420.648892 -318.295528) (xy 420.648384 -318.295528) (xy 420.132764 -318.295528)
			(xy 420.124889 -318.295811) (xy 420.109885 -318.300598) (xy 420.1033 -318.304926) (xy 420.082211 -318.3193)
			(xy 420.036571 -318.342133) (xy 419.987968 -318.357696) (xy 419.937554 -318.36562) (xy 419.912038 -318.36614)
			(xy 419.886518 -318.365641) (xy 419.836092 -318.357748) (xy 419.787481 -318.342191) (xy 419.741842 -318.319339)
			(xy 419.720776 -318.304926) (xy 419.71419 -318.300602) (xy 419.699186 -318.29582) (xy 419.691312 -318.295528)
			(xy 419.175438 -318.295528) (xy 419.170131 -318.295048) (xy 419.162556 -318.287617) (xy 419.161976 -318.28232)
			(xy 413.117792 -318.28232) (xy 413.117317 -318.287589) (xy 413.109854 -318.295031) (xy 413.104584 -318.295528)
			(xy 411.631384 -318.295528) (xy 411.626124 -318.295018) (xy 411.618683 -318.28758) (xy 411.618176 -318.28232)
			(xy 304.018188 -318.28232) (xy 304.017717 -318.28759) (xy 304.010251 -318.295033) (xy 304.00498 -318.295528)
			(xy 302.531526 -318.295528) (xy 302.526218 -318.295056) (xy 302.518643 -318.287619) (xy 302.518064 -318.28232)
			(xy 296.47388 -318.28232) (xy 296.473584 -318.287662) (xy 296.466015 -318.295203) (xy 296.460672 -318.295528)
			(xy 295.944798 -318.295528) (xy 295.936924 -318.295826) (xy 295.921921 -318.300603) (xy 295.915334 -318.304926)
			(xy 295.894264 -318.319328) (xy 295.848616 -318.342155) (xy 295.800008 -318.35771) (xy 295.749589 -318.365625)
			(xy 295.724072 -318.36614) (xy 295.698553 -318.365624) (xy 295.648127 -318.357736) (xy 295.599516 -318.342184)
			(xy 295.553876 -318.319337) (xy 295.53281 -318.304926) (xy 295.526216 -318.300615) (xy 295.511218 -318.295825)
			(xy 295.503346 -318.295528) (xy 294.987472 -318.295528) (xy 294.982211 -318.295026) (xy 294.974771 -318.287582)
			(xy 294.974264 -318.28232) (xy 288.93008 -318.28232) (xy 288.929784 -318.287662) (xy 288.922215 -318.295203)
			(xy 288.916872 -318.295528) (xy 288.916364 -318.295528) (xy 288.400744 -318.295528) (xy 288.392868 -318.295803)
			(xy 288.377865 -318.300596) (xy 288.37128 -318.304926) (xy 288.350197 -318.319309) (xy 288.304554 -318.34214)
			(xy 288.25595 -318.3577) (xy 288.205534 -318.365622) (xy 288.180018 -318.36614) (xy 288.154498 -318.365651)
			(xy 288.104071 -318.357755) (xy 288.05546 -318.342195) (xy 288.009821 -318.319341) (xy 287.988756 -318.304926)
			(xy 287.982174 -318.300594) (xy 287.967167 -318.295817) (xy 287.959292 -318.295528) (xy 287.443418 -318.295528)
			(xy 287.438108 -318.295061) (xy 287.430534 -318.28762) (xy 287.429956 -318.28232) (xy 281.385772 -318.28232)
			(xy 281.385483 -318.287664) (xy 281.377909 -318.295206) (xy 281.372564 -318.295528) (xy 280.85669 -318.295528)
			(xy 280.848816 -318.295823) (xy 280.833812 -318.300602) (xy 280.827226 -318.304926) (xy 280.806158 -318.319332)
			(xy 280.76051 -318.342158) (xy 280.711901 -318.357712) (xy 280.661482 -318.365626) (xy 280.635964 -318.36614)
			(xy 280.610445 -318.365628) (xy 280.560019 -318.357739) (xy 280.511408 -318.342185) (xy 280.465768 -318.319338)
			(xy 280.444702 -318.304926) (xy 280.43811 -318.300612) (xy 280.42311 -318.295824) (xy 280.415238 -318.295528)
			(xy 279.899364 -318.295528) (xy 279.894102 -318.295031) (xy 279.886663 -318.287583) (xy 279.886156 -318.28232)
			(xy 273.841972 -318.28232) (xy 273.841683 -318.287664) (xy 273.834109 -318.295206) (xy 273.828764 -318.295528)
			(xy 273.31289 -318.295528) (xy 273.305016 -318.295823) (xy 273.290012 -318.300602) (xy 273.283426 -318.304926)
			(xy 273.262358 -318.319332) (xy 273.21671 -318.342158) (xy 273.168101 -318.357712) (xy 273.117682 -318.365626)
			(xy 273.092164 -318.36614) (xy 273.066645 -318.365628) (xy 273.016219 -318.357739) (xy 272.967608 -318.342185)
			(xy 272.921968 -318.319338) (xy 272.900902 -318.304926) (xy 272.89431 -318.300612) (xy 272.87931 -318.295824)
			(xy 272.871438 -318.295528) (xy 272.355564 -318.295528) (xy 272.350302 -318.295031) (xy 272.342863 -318.287583)
			(xy 272.342356 -318.28232) (xy 266.298172 -318.28232) (xy 266.297883 -318.287664) (xy 266.290309 -318.295206)
			(xy 266.284964 -318.295528) (xy 266.284456 -318.295528) (xy 265.768836 -318.295528) (xy 265.76096 -318.295799)
			(xy 265.745956 -318.300595) (xy 265.739372 -318.304926) (xy 265.718291 -318.319312) (xy 265.672648 -318.342142)
			(xy 265.624043 -318.357702) (xy 265.573626 -318.365622) (xy 265.54811 -318.36614) (xy 265.52259 -318.365655)
			(xy 265.472163 -318.357758) (xy 265.423552 -318.342196) (xy 265.377913 -318.319341) (xy 265.356848 -318.304926)
			(xy 265.350268 -318.300591) (xy 265.335259 -318.295816) (xy 265.327384 -318.295528) (xy 264.81151 -318.295528)
			(xy 264.8062 -318.295066) (xy 264.798626 -318.287621) (xy 264.798048 -318.28232) (xy 202.89774 -318.28232)
			(xy 202.89774 -318.282574) (xy 202.897257 -318.28788) (xy 202.889827 -318.295453) (xy 202.884532 -318.296036)
			(xy 202.368658 -318.296036) (xy 202.36085 -318.296368) (xy 202.345978 -318.301141) (xy 202.339448 -318.305434)
			(xy 202.318337 -318.3198) (xy 202.27261 -318.342523) (xy 202.223933 -318.357949) (xy 202.173464 -318.36571)
			(xy 202.147932 -318.36614) (xy 202.122402 -318.365692) (xy 202.071939 -318.35792) (xy 202.023266 -318.342495)
			(xy 201.977538 -318.319781) (xy 201.956416 -318.305434) (xy 201.949878 -318.301154) (xy 201.935013 -318.296363)
			(xy 201.927206 -318.296036) (xy 201.411332 -318.296036) (xy 201.406011 -318.295654) (xy 201.39847 -318.288148)
			(xy 201.398124 -318.282828) (xy 195.353917 -318.282828) (xy 195.353457 -318.28788) (xy 195.346027 -318.295453)
			(xy 195.340732 -318.296036) (xy 194.824858 -318.296036) (xy 194.81705 -318.296368) (xy 194.802178 -318.301141)
			(xy 194.795648 -318.305434) (xy 194.774537 -318.3198) (xy 194.72881 -318.342523) (xy 194.680133 -318.357949)
			(xy 194.629664 -318.36571) (xy 194.604132 -318.36614) (xy 194.578602 -318.365692) (xy 194.528139 -318.35792)
			(xy 194.479466 -318.342495) (xy 194.433738 -318.319781) (xy 194.412616 -318.305434) (xy 194.406078 -318.301154)
			(xy 194.391213 -318.296363) (xy 194.383406 -318.296036) (xy 193.867532 -318.296036) (xy 193.862211 -318.295654)
			(xy 193.85467 -318.288148) (xy 193.854324 -318.282828) (xy 187.810124 -318.282828) (xy 187.809801 -318.288011)
			(xy 187.802115 -318.2957) (xy 187.796678 -318.296036) (xy 187.280804 -318.296036) (xy 187.272993 -318.296345)
			(xy 187.258122 -318.301134) (xy 187.251594 -318.305434) (xy 187.23047 -318.31978) (xy 187.184747 -318.342508)
			(xy 187.136075 -318.357939) (xy 187.085609 -318.365707) (xy 187.060078 -318.36614) (xy 187.034547 -318.365719)
			(xy 186.984082 -318.357939) (xy 186.93541 -318.342506) (xy 186.889683 -318.319784) (xy 186.868562 -318.305434)
			(xy 186.862036 -318.301133) (xy 186.847162 -318.296356) (xy 186.839352 -318.296036) (xy 186.323478 -318.296036)
			(xy 186.318034 -318.295733) (xy 186.310348 -318.288019) (xy 186.310016 -318.282574) (xy 180.265832 -318.282574)
			(xy 180.265356 -318.287882) (xy 180.257922 -318.295456) (xy 180.252624 -318.296036) (xy 179.73675 -318.296036)
			(xy 179.728941 -318.296365) (xy 179.71407 -318.30114) (xy 179.70754 -318.305434) (xy 179.686431 -318.319803)
			(xy 179.640703 -318.342526) (xy 179.592026 -318.357951) (xy 179.541556 -318.365711) (xy 179.516024 -318.36614)
			(xy 179.490494 -318.365696) (xy 179.44003 -318.357923) (xy 179.391358 -318.342496) (xy 179.34563 -318.319781)
			(xy 179.324508 -318.305434) (xy 179.317972 -318.301151) (xy 179.303105 -318.296362) (xy 179.295298 -318.296036)
			(xy 178.779424 -318.296036) (xy 178.774171 -318.295492) (xy 178.766729 -318.288079) (xy 178.766216 -318.282828)
			(xy 172.722016 -318.282828) (xy 172.7217 -318.288013) (xy 172.714009 -318.295702) (xy 172.70857 -318.296036)
			(xy 172.192696 -318.296036) (xy 172.184885 -318.296342) (xy 172.170013 -318.301132) (xy 172.163486 -318.305434)
			(xy 172.142364 -318.319783) (xy 172.096641 -318.342511) (xy 172.047967 -318.357941) (xy 171.997501 -318.365707)
			(xy 171.97197 -318.36614) (xy 171.946439 -318.365723) (xy 171.895974 -318.357942) (xy 171.847302 -318.342507)
			(xy 171.801575 -318.319785) (xy 171.780454 -318.305434) (xy 171.77393 -318.30113) (xy 171.759054 -318.296354)
			(xy 171.751244 -318.296036) (xy 171.23537 -318.296036) (xy 171.229996 -318.295567) (xy 171.222411 -318.28795)
			(xy 171.221908 -318.282574) (xy 165.177724 -318.282574) (xy 165.177255 -318.287883) (xy 165.169816 -318.295458)
			(xy 165.164516 -318.296036) (xy 163.691316 -318.296036) (xy 163.686062 -318.295498) (xy 163.67862 -318.28808)
			(xy 163.678108 -318.282828) (xy 56.078105 -318.282828) (xy 56.077799 -318.288016) (xy 56.0701 -318.295706)
			(xy 56.064658 -318.296036) (xy 54.591458 -318.296036) (xy 54.586083 -318.295575) (xy 54.578498 -318.287952)
			(xy 54.577996 -318.282574) (xy 48.533812 -318.282574) (xy 48.533354 -318.287886) (xy 48.525907 -318.295462)
			(xy 48.520604 -318.296036) (xy 48.00473 -318.296036) (xy 47.99692 -318.296357) (xy 47.982049 -318.301137)
			(xy 47.97552 -318.305434) (xy 47.954389 -318.319769) (xy 47.908669 -318.342499) (xy 47.859998 -318.357933)
			(xy 47.809534 -318.365705) (xy 47.784004 -318.36614) (xy 47.758474 -318.365706) (xy 47.708009 -318.35793)
			(xy 47.659337 -318.3425) (xy 47.61361 -318.319782) (xy 47.592488 -318.305434) (xy 47.585956 -318.301143)
			(xy 47.571087 -318.296359) (xy 47.563278 -318.296036) (xy 47.047404 -318.296036) (xy 47.042148 -318.295506)
			(xy 47.034707 -318.288082) (xy 47.034196 -318.282828) (xy 40.989985 -318.282828) (xy 40.989437 -318.287923)
			(xy 40.981896 -318.295507) (xy 40.97655 -318.296036) (xy 40.460676 -318.296036) (xy 40.452864 -318.296333)
			(xy 40.437993 -318.30113) (xy 40.431466 -318.305434) (xy 40.41035 -318.319792) (xy 40.364624 -318.342517)
			(xy 40.315949 -318.357945) (xy 40.265481 -318.365709) (xy 40.23995 -318.36614) (xy 40.21442 -318.365683)
			(xy 40.163957 -318.357914) (xy 40.115285 -318.342491) (xy 40.069556 -318.319779) (xy 40.048434 -318.305434)
			(xy 40.041892 -318.30116) (xy 40.02703 -318.296366) (xy 40.019224 -318.296036) (xy 39.50335 -318.296036)
			(xy 39.497974 -318.29558) (xy 39.49039 -318.287953) (xy 39.489888 -318.282574) (xy 33.445704 -318.282574)
			(xy 33.445165 -318.287865) (xy 33.437774 -318.295435) (xy 33.432496 -318.296036) (xy 32.916622 -318.296036)
			(xy 32.908812 -318.296353) (xy 32.893941 -318.301136) (xy 32.887412 -318.305434) (xy 32.866283 -318.319772)
			(xy 32.820562 -318.342502) (xy 32.771891 -318.357935) (xy 32.721426 -318.365705) (xy 32.695896 -318.36614)
			(xy 32.670365 -318.36571) (xy 32.619901 -318.357933) (xy 32.571229 -318.342502) (xy 32.525501 -318.319783)
			(xy 32.50438 -318.305434) (xy 32.49785 -318.30114) (xy 32.482979 -318.296358) (xy 32.47517 -318.296036)
			(xy 31.959296 -318.296036) (xy 31.954039 -318.295511) (xy 31.946599 -318.288084) (xy 31.946088 -318.282828)
			(xy 25.901878 -318.282828) (xy 25.901365 -318.287865) (xy 25.893974 -318.295435) (xy 25.888696 -318.296036)
			(xy 25.372822 -318.296036) (xy 25.365012 -318.296353) (xy 25.350141 -318.301136) (xy 25.343612 -318.305434)
			(xy 25.322483 -318.319772) (xy 25.276762 -318.342502) (xy 25.228091 -318.357935) (xy 25.177626 -318.365705)
			(xy 25.152096 -318.36614) (xy 25.126565 -318.36571) (xy 25.076101 -318.357933) (xy 25.027429 -318.342502)
			(xy 24.981701 -318.319783) (xy 24.96058 -318.305434) (xy 24.95405 -318.30114) (xy 24.939179 -318.296358)
			(xy 24.93137 -318.296036) (xy 24.415496 -318.296036) (xy 24.410239 -318.295511) (xy 24.402799 -318.288084)
			(xy 24.402288 -318.282828) (xy 18.358077 -318.282828) (xy 18.357537 -318.287925) (xy 18.34999 -318.295509)
			(xy 18.344642 -318.296036) (xy 17.828768 -318.296036) (xy 17.82096 -318.296373) (xy 17.806088 -318.301142)
			(xy 17.799558 -318.305434) (xy 17.778444 -318.319796) (xy 17.732718 -318.34252) (xy 17.684042 -318.357947)
			(xy 17.633574 -318.365709) (xy 17.608042 -318.36614) (xy 17.582512 -318.365687) (xy 17.532049 -318.357917)
			(xy 17.483376 -318.342493) (xy 17.437648 -318.31978) (xy 17.416526 -318.305434) (xy 17.409986 -318.301157)
			(xy 17.395123 -318.296365) (xy 17.387316 -318.296036) (xy 16.871442 -318.296036) (xy 16.866006 -318.29569)
			(xy 16.858317 -318.288009) (xy 16.85798 -318.282574) (xy 2.509012 -318.282574) (xy 2.509012 -336.9884)
			(xy 70.218517 -336.9884) (xy 70.222508 -336.904617) (xy 70.234446 -336.821593) (xy 70.254221 -336.74008)
			(xy 70.281655 -336.660815) (xy 70.3165 -336.584518) (xy 70.35844 -336.511878) (xy 70.407095 -336.443554)
			(xy 70.462025 -336.380164) (xy 70.522731 -336.322283) (xy 70.588664 -336.270435) (xy 70.659228 -336.225089)
			(xy 70.733783 -336.186656) (xy 70.811653 -336.155484) (xy 70.892134 -336.131855) (xy 70.974497 -336.115984)
			(xy 71.057995 -336.108014) (xy 71.099934 -336.107532) (xy 71.137123 -336.107938) (xy 71.211236 -336.114223)
			(xy 71.284556 -336.126727) (xy 71.356562 -336.145363) (xy 71.39178 -336.157316) (xy 71.399977 -336.15983)
			(xy 71.417111 -336.15983) (xy 71.425308 -336.157316) (xy 71.460496 -336.145371) (xy 71.532436 -336.126725)
			(xy 71.605692 -336.114215) (xy 71.679742 -336.107929) (xy 71.7169 -336.107532) (xy 71.717408 -336.107532)
			(xy 71.748142 -336.108294) (xy 71.757646 -336.056715) (xy 71.787316 -335.956115) (xy 71.807324 -335.907634)
			(xy 71.810983 -335.897931) (xy 71.810971 -335.877211) (xy 71.807324 -335.867502) (xy 71.790219 -335.826242)
			(xy 71.763427 -335.741032) (xy 71.74539 -335.653549) (xy 71.736293 -335.564691) (xy 71.735696 -335.52003)
			(xy 71.735696 -335.519268) (xy 71.736195 -335.477343) (xy 71.744165 -335.393872) (xy 71.760034 -335.311537)
			(xy 71.783657 -335.231083) (xy 71.814821 -335.153239) (xy 71.853244 -335.078709) (xy 71.898577 -335.00817)
			(xy 71.95041 -334.942259) (xy 72.008273 -334.881573) (xy 72.071643 -334.826663) (xy 72.139946 -334.778025)
			(xy 72.212563 -334.7361) (xy 72.288836 -334.701267) (xy 72.368075 -334.673842) (xy 72.449561 -334.654073)
			(xy 72.532558 -334.64214) (xy 72.616314 -334.638151) (xy 72.70007 -334.64214) (xy 72.783067 -334.654073)
			(xy 72.864553 -334.673842) (xy 72.943792 -334.701267) (xy 73.020065 -334.7361) (xy 73.092682 -334.778025)
			(xy 73.160985 -334.826663) (xy 73.224355 -334.881573) (xy 73.282218 -334.942259) (xy 73.334051 -335.00817)
			(xy 73.379384 -335.078709) (xy 73.417807 -335.153239) (xy 73.448971 -335.231083) (xy 73.472594 -335.311537)
			(xy 73.488463 -335.393872) (xy 73.496433 -335.477343) (xy 73.496932 -335.519268) (xy 73.496932 -335.52003)
			(xy 73.496371 -335.564694) (xy 73.487295 -335.653559) (xy 73.46926 -335.741047) (xy 73.442452 -335.826257)
			(xy 73.425304 -335.867502) (xy 73.421681 -335.877216) (xy 73.421669 -335.897926) (xy 73.425304 -335.907634)
			(xy 73.441139 -335.945575) (xy 73.466487 -336.02379) (xy 73.484436 -336.104027) (xy 73.494829 -336.185587)
			(xy 73.496678 -336.226658) (xy 73.496932 -336.24012) (xy 73.51141 -336.263234) (xy 73.61301 -336.31759)
			(xy 73.639934 -336.316828) (xy 73.651618 -336.309462) (xy 73.686811 -336.288202) (xy 73.76042 -336.251553)
			(xy 73.837094 -336.221845) (xy 73.91618 -336.199333) (xy 73.997005 -336.184209) (xy 74.07888 -336.1766)
			(xy 74.119994 -336.176112) (xy 74.161107 -336.176619) (xy 74.242983 -336.184205) (xy 74.32381 -336.199313)
			(xy 74.402898 -336.221815) (xy 74.479573 -336.251518) (xy 74.553179 -336.288168) (xy 74.623091 -336.331454)
			(xy 74.68871 -336.381006) (xy 74.749477 -336.4364) (xy 74.804874 -336.497166) (xy 74.854428 -336.562783)
			(xy 74.897716 -336.632693) (xy 74.934369 -336.706298) (xy 74.964075 -336.782971) (xy 74.986579 -336.862059)
			(xy 75.001691 -336.942885) (xy 75.005252 -336.9813) (xy 78.574105 -336.9813) (xy 78.578096 -336.897517)
			(xy 78.590033 -336.814493) (xy 78.609809 -336.732979) (xy 78.637243 -336.653715) (xy 78.672087 -336.577417)
			(xy 78.714027 -336.504776) (xy 78.762681 -336.436452) (xy 78.81761 -336.373061) (xy 78.878316 -336.31518)
			(xy 78.94425 -336.26333) (xy 79.014813 -336.217984) (xy 79.089367 -336.179549) (xy 79.167237 -336.148376)
			(xy 79.247718 -336.124747) (xy 79.330081 -336.108874) (xy 79.413579 -336.100902) (xy 79.455518 -336.10042)
			(xy 79.492708 -336.100802) (xy 79.566821 -336.107094) (xy 79.640141 -336.119606) (xy 79.712146 -336.138248)
			(xy 79.747364 -336.150204) (xy 79.755561 -336.152718) (xy 79.772695 -336.152718) (xy 79.780892 -336.150204)
			(xy 79.816103 -336.138226) (xy 79.888108 -336.119576) (xy 79.961431 -336.107072) (xy 80.035547 -336.100804)
			(xy 80.072738 -336.10042) (xy 80.10906 -336.101182) (xy 80.115245 -336.066241) (xy 80.132513 -335.997409)
			(xy 80.155273 -335.930194) (xy 80.169004 -335.897474) (xy 80.172641 -335.887764) (xy 80.172644 -335.86705)
			(xy 80.169004 -335.857342) (xy 80.151879 -335.81609) (xy 80.125092 -335.730877) (xy 80.107061 -335.643392)
			(xy 80.09797 -335.554532) (xy 80.097376 -335.50987) (xy 80.097376 -335.509108) (xy 80.097875 -335.467183)
			(xy 80.105845 -335.383712) (xy 80.121714 -335.301377) (xy 80.145337 -335.220923) (xy 80.176501 -335.143079)
			(xy 80.214924 -335.068549) (xy 80.260257 -334.99801) (xy 80.31209 -334.932099) (xy 80.369953 -334.871413)
			(xy 80.433323 -334.816503) (xy 80.501626 -334.767865) (xy 80.574243 -334.72594) (xy 80.650516 -334.691107)
			(xy 80.729755 -334.663682) (xy 80.811241 -334.643913) (xy 80.894238 -334.63198) (xy 80.977994 -334.627991)
			(xy 81.06175 -334.63198) (xy 81.144747 -334.643913) (xy 81.226233 -334.663682) (xy 81.305472 -334.691107)
			(xy 81.381745 -334.72594) (xy 81.454362 -334.767865) (xy 81.522665 -334.816503) (xy 81.586035 -334.871413)
			(xy 81.643898 -334.932099) (xy 81.695731 -334.99801) (xy 81.741064 -335.068549) (xy 81.779487 -335.143079)
			(xy 81.810651 -335.220923) (xy 81.834274 -335.301377) (xy 81.850143 -335.383712) (xy 81.858113 -335.467183)
			(xy 81.858612 -335.509108) (xy 81.858612 -335.50987) (xy 81.858066 -335.554534) (xy 81.848986 -335.6434)
			(xy 81.830947 -335.730888) (xy 81.804134 -335.816098) (xy 81.786984 -335.857342) (xy 81.783338 -335.867049)
			(xy 81.783341 -335.887765) (xy 81.786984 -335.897474) (xy 81.802748 -335.935334) (xy 81.827987 -336.013369)
			(xy 81.845871 -336.093411) (xy 81.856247 -336.174768) (xy 81.858104 -336.215736) (xy 81.858828 -336.22455)
			(xy 81.865419 -336.240944) (xy 81.877182 -336.254128) (xy 81.884774 -336.258662) (xy 81.973928 -336.306922)
			(xy 82.000852 -336.30616) (xy 82.012536 -336.299048) (xy 82.047432 -336.278305) (xy 82.120306 -336.242523)
			(xy 82.19614 -336.213534) (xy 82.2743 -336.191579) (xy 82.354137 -336.176843) (xy 82.434985 -336.169448)
			(xy 82.475578 -336.169) (xy 82.516691 -336.169534) (xy 82.598566 -336.177119) (xy 82.679391 -336.192225)
			(xy 82.758479 -336.214725) (xy 82.835153 -336.244426) (xy 82.908759 -336.281075) (xy 82.97867 -336.324359)
			(xy 83.044289 -336.373909) (xy 83.105056 -336.429302) (xy 83.160453 -336.490065) (xy 83.210007 -336.555681)
			(xy 83.253296 -336.625589) (xy 83.28995 -336.699193) (xy 83.319656 -336.775864) (xy 83.342161 -336.85495)
			(xy 83.357273 -336.935775) (xy 83.360149 -336.9668) (xy 86.931981 -336.9668) (xy 86.935971 -336.883042)
			(xy 86.947905 -336.800043) (xy 86.967674 -336.718554) (xy 86.9951 -336.639313) (xy 87.029935 -336.563039)
			(xy 87.071862 -336.490421) (xy 87.120503 -336.422117) (xy 87.175416 -336.358746) (xy 87.236104 -336.300883)
			(xy 87.302018 -336.24905) (xy 87.37256 -336.203717) (xy 87.447092 -336.165296) (xy 87.52494 -336.134133)
			(xy 87.605396 -336.110512) (xy 87.687734 -336.094645) (xy 87.771208 -336.086677) (xy 87.813134 -336.086196)
			(xy 87.81415 -336.086196) (xy 87.851207 -336.086587) (xy 87.925057 -336.092856) (xy 87.998119 -336.105302)
			(xy 88.069879 -336.123838) (xy 88.10498 -336.135726) (xy 88.113177 -336.13824) (xy 88.130311 -336.13824)
			(xy 88.138508 -336.135726) (xy 88.173727 -336.123789) (xy 88.245736 -336.1052) (xy 88.319058 -336.092757)
			(xy 88.393169 -336.086549) (xy 88.430354 -336.086196) (xy 88.454992 -336.08645) (xy 88.464629 -336.040549)
			(xy 88.49238 -335.950951) (xy 88.510364 -335.907634) (xy 88.514021 -335.89793) (xy 88.514009 -335.877211)
			(xy 88.510364 -335.867502) (xy 88.493256 -335.826243) (xy 88.466465 -335.741033) (xy 88.448429 -335.65355)
			(xy 88.439333 -335.564691) (xy 88.438736 -335.52003) (xy 88.438736 -335.519268) (xy 88.439235 -335.477343)
			(xy 88.447205 -335.393872) (xy 88.463074 -335.311537) (xy 88.486697 -335.231083) (xy 88.517861 -335.153239)
			(xy 88.556284 -335.078709) (xy 88.601617 -335.00817) (xy 88.65345 -334.942259) (xy 88.711313 -334.881573)
			(xy 88.774683 -334.826663) (xy 88.842986 -334.778025) (xy 88.915603 -334.7361) (xy 88.991876 -334.701267)
			(xy 89.071115 -334.673842) (xy 89.152601 -334.654073) (xy 89.235598 -334.64214) (xy 89.319354 -334.638151)
			(xy 89.40311 -334.64214) (xy 89.486107 -334.654073) (xy 89.567593 -334.673842) (xy 89.646832 -334.701267)
			(xy 89.723105 -334.7361) (xy 89.795722 -334.778025) (xy 89.864025 -334.826663) (xy 89.927395 -334.881573)
			(xy 89.985258 -334.942259) (xy 90.037091 -335.00817) (xy 90.082424 -335.078709) (xy 90.120847 -335.153239)
			(xy 90.152011 -335.231083) (xy 90.175634 -335.311537) (xy 90.191503 -335.393872) (xy 90.199473 -335.477343)
			(xy 90.199972 -335.519268) (xy 90.199972 -335.52003) (xy 90.199408 -335.564694) (xy 90.190332 -335.653559)
			(xy 90.172298 -335.741047) (xy 90.145491 -335.826257) (xy 90.128344 -335.867502) (xy 90.124724 -335.877216)
			(xy 90.124712 -335.897925) (xy 90.128344 -335.907634) (xy 90.14352 -335.944017) (xy 90.168055 -336.018939)
			(xy 90.185802 -336.095753) (xy 90.196619 -336.173844) (xy 90.198956 -336.213196) (xy 90.198956 -336.21345)
			(xy 90.199799 -336.222253) (xy 90.206694 -336.238523) (xy 90.218709 -336.251482) (xy 90.226388 -336.255868)
			(xy 90.316812 -336.302604) (xy 90.343482 -336.301334) (xy 90.355166 -336.293968) (xy 90.390883 -336.271832)
			(xy 90.465707 -336.233583) (xy 90.543804 -336.20256) (xy 90.624479 -336.17904) (xy 90.707013 -336.163233)
			(xy 90.790669 -336.155279) (xy 90.832686 -336.154776) (xy 90.833194 -336.154776) (xy 90.874302 -336.155218)
			(xy 90.956167 -336.162803) (xy 91.036983 -336.177907) (xy 91.116061 -336.200402) (xy 91.192727 -336.230097)
			(xy 91.266326 -336.266738) (xy 91.336231 -336.310013) (xy 91.401845 -336.359552) (xy 91.46261 -336.414933)
			(xy 91.518006 -336.475684) (xy 91.567562 -336.541286) (xy 91.610854 -336.61118) (xy 91.647513 -336.68477)
			(xy 91.677227 -336.761428) (xy 91.699742 -336.840501) (xy 91.714867 -336.921313) (xy 91.722471 -337.003176)
			(xy 91.722641 -337.0176) (xy 95.263181 -337.0176) (xy 95.267171 -336.933842) (xy 95.279105 -336.850843)
			(xy 95.298874 -336.769354) (xy 95.3263 -336.690113) (xy 95.361135 -336.613839) (xy 95.403062 -336.541221)
			(xy 95.451703 -336.472917) (xy 95.506616 -336.409546) (xy 95.567304 -336.351683) (xy 95.633218 -336.29985)
			(xy 95.70376 -336.254517) (xy 95.778292 -336.216096) (xy 95.85614 -336.184933) (xy 95.936596 -336.161312)
			(xy 96.018934 -336.145445) (xy 96.102408 -336.137477) (xy 96.144334 -336.136996) (xy 96.14535 -336.136996)
			(xy 96.182407 -336.137387) (xy 96.256257 -336.143656) (xy 96.329319 -336.156102) (xy 96.401079 -336.174638)
			(xy 96.43618 -336.186526) (xy 96.444377 -336.18904) (xy 96.461511 -336.18904) (xy 96.469708 -336.186526)
			(xy 96.504897 -336.174599) (xy 96.576843 -336.15602) (xy 96.650101 -336.143577) (xy 96.724146 -336.137359)
			(xy 96.7613 -336.136996) (xy 96.761808 -336.136996) (xy 96.796352 -336.137504) (xy 96.805918 -336.09484)
			(xy 96.832381 -336.0115) (xy 96.849184 -335.971134) (xy 96.852845 -335.961431) (xy 96.852833 -335.940711)
			(xy 96.849184 -335.931002) (xy 96.832077 -335.889743) (xy 96.805286 -335.804532) (xy 96.78725 -335.717049)
			(xy 96.778153 -335.628191) (xy 96.777556 -335.58353) (xy 96.777556 -335.582768) (xy 96.778055 -335.540843)
			(xy 96.786025 -335.457372) (xy 96.801894 -335.375037) (xy 96.825517 -335.294583) (xy 96.856681 -335.216739)
			(xy 96.895104 -335.142209) (xy 96.940437 -335.07167) (xy 96.99227 -335.005759) (xy 97.050133 -334.945073)
			(xy 97.113503 -334.890163) (xy 97.181806 -334.841525) (xy 97.254423 -334.7996) (xy 97.330696 -334.764767)
			(xy 97.409935 -334.737342) (xy 97.491421 -334.717573) (xy 97.574418 -334.70564) (xy 97.658174 -334.701651)
			(xy 97.74193 -334.70564) (xy 97.824927 -334.717573) (xy 97.906413 -334.737342) (xy 97.985652 -334.764767)
			(xy 98.061925 -334.7996) (xy 98.134542 -334.841525) (xy 98.202845 -334.890163) (xy 98.266215 -334.945073)
			(xy 98.324078 -335.005759) (xy 98.375911 -335.07167) (xy 98.421244 -335.142209) (xy 98.459667 -335.216739)
			(xy 98.490831 -335.294583) (xy 98.514454 -335.375037) (xy 98.530323 -335.457372) (xy 98.538293 -335.540843)
			(xy 98.538792 -335.582768) (xy 98.538792 -335.58353) (xy 98.538226 -335.628194) (xy 98.529151 -335.717059)
			(xy 98.511117 -335.804547) (xy 98.484311 -335.889757) (xy 98.467164 -335.931002) (xy 98.463542 -335.940716)
			(xy 98.463531 -335.961426) (xy 98.467164 -335.971134) (xy 98.48433 -336.012473) (xy 98.511159 -336.097874)
			(xy 98.529194 -336.185554) (xy 98.538249 -336.27461) (xy 98.538792 -336.319368) (xy 98.538552 -336.350973)
			(xy 98.534101 -336.414026) (xy 98.529902 -336.445352) (xy 98.528378 -336.45602) (xy 98.53422 -336.477102)
			(xy 98.590608 -336.543396) (xy 98.597904 -336.55118) (xy 98.617064 -336.560504) (xy 98.627692 -336.56143)
			(xy 98.6282 -336.56143) (xy 98.671147 -336.563026) (xy 98.756458 -336.573467) (xy 98.840365 -336.592088)
			(xy 98.922084 -336.618714) (xy 99.000854 -336.653099) (xy 99.07594 -336.69492) (xy 99.146643 -336.743788)
			(xy 99.212303 -336.799248) (xy 99.272307 -336.860782) (xy 99.326097 -336.927817) (xy 99.362614 -336.9836)
			(xy 318.155561 -336.9836) (xy 318.15955 -336.899842) (xy 318.171484 -336.816843) (xy 318.191253 -336.735354)
			(xy 318.218678 -336.656114) (xy 318.253512 -336.579839) (xy 318.295438 -336.50722) (xy 318.344078 -336.438916)
			(xy 318.398989 -336.375544) (xy 318.459676 -336.317679) (xy 318.525589 -336.265845) (xy 318.59613 -336.220511)
			(xy 318.670661 -336.182087) (xy 318.748507 -336.150922) (xy 318.828963 -336.127298) (xy 318.911301 -336.111429)
			(xy 318.994774 -336.103459) (xy 319.0367 -336.10296) (xy 319.037716 -336.10296) (xy 319.074773 -336.103363)
			(xy 319.148622 -336.109628) (xy 319.221685 -336.122071) (xy 319.293445 -336.140604) (xy 319.328546 -336.15249)
			(xy 319.336743 -336.155004) (xy 319.353877 -336.155004) (xy 319.362074 -336.15249) (xy 319.397267 -336.140575)
			(xy 319.469212 -336.121992) (xy 319.542468 -336.109546) (xy 319.616513 -336.103324) (xy 319.653666 -336.10296)
			(xy 319.654174 -336.10296) (xy 319.681606 -336.103214) (xy 319.687655 -336.066844) (xy 319.704988 -335.995173)
			(xy 319.728195 -335.925184) (xy 319.742312 -335.891124) (xy 319.745871 -335.881532) (xy 319.745875 -335.86109)
			(xy 319.742312 -335.8515) (xy 319.725303 -335.810117) (xy 319.698681 -335.724692) (xy 319.680772 -335.637026)
			(xy 319.671759 -335.548004) (xy 319.671192 -335.503266) (xy 319.671192 -335.503012) (xy 319.671696 -335.460664)
			(xy 319.679747 -335.37635) (xy 319.695776 -335.293184) (xy 319.719637 -335.211917) (xy 319.751116 -335.133287)
			(xy 319.789927 -335.058006) (xy 319.835717 -334.986754) (xy 319.888073 -334.920178) (xy 319.946521 -334.85888)
			(xy 320.010531 -334.803415) (xy 320.079523 -334.754286) (xy 320.152873 -334.711937) (xy 320.229916 -334.676753)
			(xy 320.309955 -334.649051) (xy 320.392264 -334.629083) (xy 320.476099 -334.61703) (xy 320.5607 -334.613)
			(xy 320.645301 -334.61703) (xy 320.729136 -334.629083) (xy 320.811445 -334.649051) (xy 320.891484 -334.676753)
			(xy 320.968527 -334.711937) (xy 321.041877 -334.754286) (xy 321.110869 -334.803415) (xy 321.174879 -334.85888)
			(xy 321.233327 -334.920178) (xy 321.285683 -334.986754) (xy 321.331473 -335.058006) (xy 321.370284 -335.133287)
			(xy 321.401763 -335.211917) (xy 321.425624 -335.293184) (xy 321.441653 -335.37635) (xy 321.449704 -335.460664)
			(xy 321.450208 -335.503012) (xy 321.450208 -335.503266) (xy 321.449645 -335.548004) (xy 321.440627 -335.637026)
			(xy 321.422721 -335.724694) (xy 321.396107 -335.810121) (xy 321.379088 -335.8515) (xy 321.375596 -335.861115)
			(xy 321.37573 -335.881553) (xy 321.379342 -335.891124) (xy 321.395061 -335.929255) (xy 321.42019 -336.007817)
			(xy 321.437947 -336.088366) (xy 321.448179 -336.170212) (xy 321.449954 -336.211418) (xy 321.450208 -336.22488)
			(xy 321.464178 -336.24774) (xy 321.564762 -336.303112) (xy 321.591432 -336.302604) (xy 321.603116 -336.295746)
			(xy 321.637431 -336.275914) (xy 321.708951 -336.241747) (xy 321.783227 -336.214078) (xy 321.859671 -336.193127)
			(xy 321.937675 -336.179058) (xy 322.016621 -336.171985) (xy 322.056252 -336.17154) (xy 322.05676 -336.17154)
			(xy 322.097864 -336.17199) (xy 322.179721 -336.179572) (xy 322.26053 -336.194675) (xy 322.3396 -336.21717)
			(xy 322.416257 -336.246866) (xy 322.489847 -336.283508) (xy 322.559742 -336.326784) (xy 322.625346 -336.376325)
			(xy 322.686098 -336.431708) (xy 322.74148 -336.492461) (xy 322.791021 -336.558064) (xy 322.834296 -336.62796)
			(xy 322.870938 -336.70155) (xy 322.900632 -336.778207) (xy 322.923127 -336.857278) (xy 322.938229 -336.938087)
			(xy 322.941787 -336.9765) (xy 326.511148 -336.9765) (xy 326.515138 -336.892742) (xy 326.527072 -336.809743)
			(xy 326.546841 -336.728254) (xy 326.574266 -336.649013) (xy 326.609099 -336.572737) (xy 326.651025 -336.500118)
			(xy 326.699664 -336.431814) (xy 326.754575 -336.368441) (xy 326.815262 -336.310576) (xy 326.881174 -336.258741)
			(xy 326.951715 -336.213406) (xy 327.026246 -336.174981) (xy 327.104092 -336.143815) (xy 327.184547 -336.12019)
			(xy 327.266885 -336.104319) (xy 327.350358 -336.096347) (xy 327.392284 -336.095848) (xy 327.3933 -336.095848)
			(xy 327.430357 -336.096256) (xy 327.504206 -336.10252) (xy 327.577268 -336.114961) (xy 327.649028 -336.133493)
			(xy 327.68413 -336.145378) (xy 327.692327 -336.147892) (xy 327.709461 -336.147892) (xy 327.717658 -336.145378)
			(xy 327.752881 -336.133453) (xy 327.824889 -336.114861) (xy 327.898209 -336.102415) (xy 327.972319 -336.096203)
			(xy 328.009504 -336.095848) (xy 328.043286 -336.096356) (xy 328.05281 -336.047304) (xy 328.081456 -335.951571)
			(xy 328.100436 -335.905348) (xy 328.10398 -335.895751) (xy 328.103994 -335.875314) (xy 328.100436 -335.865724)
			(xy 328.083404 -335.82435) (xy 328.056787 -335.738922) (xy 328.038886 -335.651253) (xy 328.02988 -335.562229)
			(xy 328.029316 -335.51749) (xy 328.029316 -335.517236) (xy 328.02982 -335.474888) (xy 328.037871 -335.390574)
			(xy 328.0539 -335.307408) (xy 328.077761 -335.226141) (xy 328.10924 -335.147511) (xy 328.148051 -335.07223)
			(xy 328.193841 -335.000978) (xy 328.246197 -334.934402) (xy 328.304645 -334.873104) (xy 328.368655 -334.817639)
			(xy 328.437647 -334.76851) (xy 328.510997 -334.726161) (xy 328.58804 -334.690977) (xy 328.668079 -334.663275)
			(xy 328.750388 -334.643307) (xy 328.834223 -334.631254) (xy 328.918824 -334.627224) (xy 329.003425 -334.631254)
			(xy 329.08726 -334.643307) (xy 329.169569 -334.663275) (xy 329.249608 -334.690977) (xy 329.326651 -334.726161)
			(xy 329.400001 -334.76851) (xy 329.468993 -334.817639) (xy 329.533003 -334.873104) (xy 329.591451 -334.934402)
			(xy 329.643807 -335.000978) (xy 329.689597 -335.07223) (xy 329.728408 -335.147511) (xy 329.759887 -335.226141)
			(xy 329.783748 -335.307408) (xy 329.799777 -335.390574) (xy 329.807828 -335.474888) (xy 329.808332 -335.517236)
			(xy 329.808332 -335.51749) (xy 329.807775 -335.562229) (xy 329.798756 -335.651251) (xy 329.780848 -335.738918)
			(xy 329.754231 -335.824345) (xy 329.737212 -335.865724) (xy 329.733624 -335.875308) (xy 329.733638 -335.895757)
			(xy 329.737212 -335.905348) (xy 329.752022 -335.941175) (xy 329.776095 -336.014872) (xy 329.793653 -336.090386)
			(xy 329.804563 -336.167144) (xy 329.807062 -336.20583) (xy 329.807824 -336.219038) (xy 329.822048 -336.24139)
			(xy 329.91044 -336.288888) (xy 329.918254 -336.292745) (xy 329.93547 -336.295369) (xy 329.95256 -336.292022)
			(xy 329.960224 -336.287872) (xy 329.994483 -336.268147) (xy 330.065868 -336.23417) (xy 330.139986 -336.206662)
			(xy 330.216254 -336.18584) (xy 330.294068 -336.171868) (xy 330.372815 -336.164856) (xy 330.412344 -336.164428)
			(xy 330.453448 -336.164825) (xy 330.535306 -336.172414) (xy 330.616114 -336.187524) (xy 330.695183 -336.210025)
			(xy 330.771839 -336.239726) (xy 330.845427 -336.276373) (xy 330.91532 -336.319653) (xy 330.980922 -336.369198)
			(xy 331.041672 -336.424584) (xy 331.097053 -336.48534) (xy 331.146592 -336.550946) (xy 331.189866 -336.620843)
			(xy 331.226507 -336.694434) (xy 331.256201 -336.771093) (xy 331.278695 -336.850164) (xy 331.293797 -336.930973)
			(xy 331.296671 -336.962) (xy 334.868517 -336.962) (xy 334.872507 -336.878219) (xy 334.884444 -336.795197)
			(xy 334.904219 -336.713686) (xy 334.931652 -336.634423) (xy 334.966495 -336.558127) (xy 335.008433 -336.485488)
			(xy 335.057086 -336.417165) (xy 335.112013 -336.353776) (xy 335.172717 -336.295895) (xy 335.238647 -336.244046)
			(xy 335.309208 -336.198699) (xy 335.38376 -336.160265) (xy 335.461628 -336.129092) (xy 335.542106 -336.105461)
			(xy 335.624466 -336.089588) (xy 335.707962 -336.081615) (xy 335.7499 -336.081116) (xy 335.78709 -336.081504)
			(xy 335.861203 -336.087794) (xy 335.934522 -336.100304) (xy 336.006528 -336.118945) (xy 336.041746 -336.1309)
			(xy 336.049943 -336.133414) (xy 336.067077 -336.133414) (xy 336.075274 -336.1309) (xy 336.110487 -336.118927)
			(xy 336.182491 -336.100276) (xy 336.255813 -336.08777) (xy 336.329929 -336.0815) (xy 336.36712 -336.081116)
			(xy 336.407506 -336.082132) (xy 336.417036 -336.036786) (xy 336.444265 -335.948213) (xy 336.461862 -335.905348)
			(xy 336.465474 -335.895775) (xy 336.465619 -335.875336) (xy 336.462116 -335.865724) (xy 336.445083 -335.824351)
			(xy 336.418467 -335.738922) (xy 336.400565 -335.651253) (xy 336.39156 -335.562229) (xy 336.390996 -335.51749)
			(xy 336.390996 -335.517236) (xy 336.3915 -335.474888) (xy 336.399551 -335.390574) (xy 336.41558 -335.307408)
			(xy 336.439441 -335.226141) (xy 336.47092 -335.147511) (xy 336.509731 -335.07223) (xy 336.555521 -335.000978)
			(xy 336.607877 -334.934402) (xy 336.666325 -334.873104) (xy 336.730335 -334.817639) (xy 336.799327 -334.76851)
			(xy 336.872677 -334.726161) (xy 336.94972 -334.690977) (xy 337.029759 -334.663275) (xy 337.112068 -334.643307)
			(xy 337.195903 -334.631254) (xy 337.280504 -334.627224) (xy 337.365105 -334.631254) (xy 337.44894 -334.643307)
			(xy 337.531249 -334.663275) (xy 337.611288 -334.690977) (xy 337.688331 -334.726161) (xy 337.761681 -334.76851)
			(xy 337.830673 -334.817639) (xy 337.894683 -334.873104) (xy 337.953131 -334.934402) (xy 338.005487 -335.000978)
			(xy 338.051277 -335.07223) (xy 338.090088 -335.147511) (xy 338.121567 -335.226141) (xy 338.145428 -335.307408)
			(xy 338.161457 -335.390574) (xy 338.169508 -335.474888) (xy 338.170012 -335.517236) (xy 338.170012 -335.51749)
			(xy 338.169456 -335.562229) (xy 338.160437 -335.651251) (xy 338.142528 -335.738918) (xy 338.115912 -335.824345)
			(xy 338.098892 -335.865724) (xy 338.095386 -335.875335) (xy 338.09553 -335.895777) (xy 338.099146 -335.905348)
			(xy 338.117792 -335.95091) (xy 338.146101 -336.045203) (xy 338.163844 -336.142042) (xy 338.16798 -336.191098)
			(xy 338.168919 -336.199672) (xy 338.175759 -336.215494) (xy 338.187449 -336.228161) (xy 338.194904 -336.2325)
			(xy 338.283042 -336.278728) (xy 338.309204 -336.27822) (xy 338.320634 -336.271616) (xy 338.354723 -336.252133)
			(xy 338.425722 -336.218592) (xy 338.499399 -336.191437) (xy 338.575183 -336.170878) (xy 338.652483 -336.157075)
			(xy 338.730699 -336.150137) (xy 338.76996 -336.149696) (xy 338.81107 -336.150191) (xy 338.89294 -336.157775)
			(xy 338.97376 -336.172882) (xy 339.052841 -336.195384) (xy 339.129508 -336.225088) (xy 339.203107 -336.261741)
			(xy 339.273008 -336.305029) (xy 339.338617 -336.354584) (xy 339.399372 -336.409982) (xy 339.454755 -336.470751)
			(xy 339.504294 -336.536372) (xy 339.547565 -336.606284) (xy 339.5842 -336.679891) (xy 339.613885 -336.756566)
			(xy 339.636368 -336.835652) (xy 339.651455 -336.916476) (xy 339.659019 -336.998348) (xy 339.659177 -337.0128)
			(xy 343.199717 -337.0128) (xy 343.203707 -336.929019) (xy 343.215644 -336.845997) (xy 343.235419 -336.764486)
			(xy 343.262852 -336.685223) (xy 343.297695 -336.608927) (xy 343.339633 -336.536288) (xy 343.388286 -336.467965)
			(xy 343.443213 -336.404576) (xy 343.503917 -336.346695) (xy 343.569847 -336.294846) (xy 343.640408 -336.249499)
			(xy 343.71496 -336.211065) (xy 343.792828 -336.179892) (xy 343.873306 -336.156261) (xy 343.955666 -336.140388)
			(xy 344.039162 -336.132415) (xy 344.0811 -336.131916) (xy 344.11829 -336.132304) (xy 344.192403 -336.138594)
			(xy 344.265722 -336.151104) (xy 344.337728 -336.169745) (xy 344.372946 -336.1817) (xy 344.381143 -336.184214)
			(xy 344.398277 -336.184214) (xy 344.406474 -336.1817) (xy 344.441687 -336.169727) (xy 344.513691 -336.151076)
			(xy 344.587013 -336.13857) (xy 344.661129 -336.1323) (xy 344.69832 -336.131916) (xy 344.712798 -336.13217)
			(xy 344.724169 -336.131792) (xy 344.744841 -336.122355) (xy 344.759419 -336.104924) (xy 344.762836 -336.09407)
			(xy 344.771457 -336.062103) (xy 344.792812 -335.999426) (xy 344.805508 -335.968848) (xy 344.809054 -335.959252)
			(xy 344.809067 -335.938814) (xy 344.805508 -335.929224) (xy 344.788475 -335.887851) (xy 344.761859 -335.802423)
			(xy 344.743957 -335.714753) (xy 344.734952 -335.625729) (xy 344.734388 -335.58099) (xy 344.734388 -335.580736)
			(xy 344.734892 -335.538388) (xy 344.742943 -335.454074) (xy 344.758972 -335.370908) (xy 344.782833 -335.289641)
			(xy 344.814312 -335.211011) (xy 344.853123 -335.13573) (xy 344.898913 -335.064478) (xy 344.951269 -334.997902)
			(xy 345.009717 -334.936604) (xy 345.073727 -334.881139) (xy 345.142719 -334.83201) (xy 345.216069 -334.789661)
			(xy 345.293112 -334.754477) (xy 345.373151 -334.726775) (xy 345.45546 -334.706807) (xy 345.539295 -334.694754)
			(xy 345.623896 -334.690724) (xy 345.708497 -334.694754) (xy 345.792332 -334.706807) (xy 345.874641 -334.726775)
			(xy 345.95468 -334.754477) (xy 346.031723 -334.789661) (xy 346.105073 -334.83201) (xy 346.174065 -334.881139)
			(xy 346.238075 -334.936604) (xy 346.296523 -334.997902) (xy 346.348879 -335.064478) (xy 346.394669 -335.13573)
			(xy 346.43348 -335.211011) (xy 346.464959 -335.289641) (xy 346.48882 -335.370908) (xy 346.504849 -335.454074)
			(xy 346.5129 -335.538388) (xy 346.513404 -335.580736) (xy 346.513404 -335.58099) (xy 346.512849 -335.625729)
			(xy 346.50383 -335.714751) (xy 346.485921 -335.802418) (xy 346.459304 -335.887845) (xy 346.442284 -335.929224)
			(xy 346.438698 -335.938808) (xy 346.438711 -335.959257) (xy 346.442284 -335.968848) (xy 346.459319 -336.010255)
			(xy 346.48595 -336.095744) (xy 346.503854 -336.183477) (xy 346.51285 -336.272565) (xy 346.513404 -336.317336)
			(xy 346.513182 -336.348682) (xy 346.508857 -336.411225) (xy 346.504768 -336.442304) (xy 346.503244 -336.452972)
			(xy 346.508832 -336.473546) (xy 346.56268 -336.539586) (xy 346.569651 -336.547336) (xy 346.588142 -336.55691)
			(xy 346.598494 -336.558128) (xy 346.599002 -336.558128) (xy 346.640786 -336.561293) (xy 346.723543 -336.574476)
			(xy 346.804694 -336.595383) (xy 346.883519 -336.62383) (xy 346.959319 -336.659564) (xy 347.031422 -336.702268)
			(xy 347.09919 -336.751564) (xy 347.162022 -336.807015) (xy 347.21936 -336.868129) (xy 347.270696 -336.934365)
			(xy 347.315576 -337.005135) (xy 347.353601 -337.079812) (xy 347.384434 -337.157734) (xy 347.407802 -337.238211)
			(xy 347.423499 -337.320529) (xy 347.431384 -337.403958) (xy 347.431868 -337.445858) (xy 347.431868 -337.446874)
			(xy 347.431339 -337.489485) (xy 347.423121 -337.57431) (xy 347.406824 -337.657959) (xy 347.382599 -337.739665)
			(xy 347.367098 -337.77936) (xy 347.363634 -337.789438) (xy 347.36443 -337.810709) (xy 347.368622 -337.820508)
			(xy 347.385666 -337.856788) (xy 347.413917 -337.931808) (xy 347.435302 -338.009067) (xy 347.449648 -338.087936)
			(xy 347.456838 -338.167776) (xy 347.457268 -338.207858) (xy 347.456674 -338.254253) (xy 347.447033 -338.346541)
			(xy 347.42784 -338.437325) (xy 347.399305 -338.525619) (xy 347.381068 -338.568284) (xy 347.377284 -338.578233)
			(xy 347.377268 -338.599491) (xy 347.381068 -338.609432) (xy 347.399296 -338.652101) (xy 347.427845 -338.740391)
			(xy 347.447043 -338.831174) (xy 347.456681 -338.923462) (xy 347.457268 -338.969858) (xy 347.456674 -339.016253)
			(xy 347.447033 -339.108541) (xy 347.42784 -339.199325) (xy 347.399305 -339.287619) (xy 347.381068 -339.330284)
			(xy 347.377284 -339.340233) (xy 347.377268 -339.361491) (xy 347.381068 -339.371432) (xy 347.39928 -339.414039)
			(xy 347.427799 -339.502205) (xy 347.446995 -339.592859) (xy 347.456658 -339.685018) (xy 347.457268 -339.73135)
			(xy 347.457268 -339.731858) (xy 347.456747 -339.772964) (xy 347.449167 -339.854825) (xy 347.434067 -339.935639)
			(xy 347.411576 -340.014714) (xy 347.381885 -340.091377) (xy 347.345249 -340.164975) (xy 347.30198 -340.234878)
			(xy 347.252446 -340.300492) (xy 347.19707 -340.361256) (xy 347.136324 -340.416653) (xy 347.070727 -340.466209)
			(xy 347.000838 -340.509502) (xy 346.927254 -340.546163) (xy 346.8506 -340.575879) (xy 346.771533 -340.598397)
			(xy 346.690725 -340.613525) (xy 346.608866 -340.621133) (xy 346.56776 -340.62162) (xy 346.525159 -340.621134)
			(xy 346.440349 -340.612975) (xy 346.356708 -340.596745) (xy 346.275001 -340.572593) (xy 346.195978 -340.540739)
			(xy 346.120362 -340.501477) (xy 346.048846 -340.455165) (xy 345.982085 -340.402229) (xy 345.920691 -340.343152)
			(xy 345.865226 -340.278476) (xy 345.840304 -340.243922) (xy 345.834713 -340.236567) (xy 345.819465 -340.226159)
			(xy 345.810586 -340.223602) (xy 345.769427 -340.213207) (xy 345.689122 -340.185668) (xy 345.611806 -340.150603)
			(xy 345.538183 -340.108332) (xy 345.468921 -340.05924) (xy 345.40465 -340.003772) (xy 345.345957 -339.942434)
			(xy 345.293373 -339.875784) (xy 345.247379 -339.804427) (xy 345.208391 -339.729013) (xy 345.176765 -339.650228)
			(xy 345.152789 -339.568788) (xy 345.136679 -339.485435) (xy 345.128584 -339.400926) (xy 345.128088 -339.358478)
			(xy 345.128088 -339.358224) (xy 345.128648 -339.313485) (xy 345.137666 -339.224464) (xy 345.155574 -339.136796)
			(xy 345.182189 -339.051369) (xy 345.199208 -339.00999) (xy 345.202787 -339.000403) (xy 345.202779 -338.979957)
			(xy 345.199208 -338.970366) (xy 345.182177 -338.928958) (xy 345.155545 -338.843469) (xy 345.13764 -338.755736)
			(xy 345.128642 -338.666649) (xy 345.128088 -338.621878) (xy 345.128637 -338.577108) (xy 345.137642 -338.488021)
			(xy 345.15555 -338.400289) (xy 345.182178 -338.314799) (xy 345.199208 -338.27339) (xy 345.202787 -338.263803)
			(xy 345.202779 -338.243357) (xy 345.199208 -338.233766) (xy 345.182177 -338.192358) (xy 345.155545 -338.106869)
			(xy 345.13764 -338.019136) (xy 345.128642 -337.930049) (xy 345.128088 -337.885278) (xy 345.128088 -337.87334)
			(xy 345.101609 -337.867394) (xy 345.049374 -337.852651) (xy 345.023694 -337.843876) (xy 345.015497 -337.841362)
			(xy 344.998363 -337.841362) (xy 344.990166 -337.843876) (xy 344.95495 -337.855837) (xy 344.882946 -337.874492)
			(xy 344.809626 -337.887) (xy 344.73551 -337.893274) (xy 344.69832 -337.89366) (xy 344.661131 -337.893262)
			(xy 344.587018 -337.886974) (xy 344.513698 -337.874467) (xy 344.441692 -337.855829) (xy 344.406474 -337.843876)
			(xy 344.398277 -337.841362) (xy 344.381143 -337.841362) (xy 344.372946 -337.843876) (xy 344.337731 -337.855842)
			(xy 344.265728 -337.874496) (xy 344.192406 -337.887003) (xy 344.11829 -337.893275) (xy 344.0811 -337.89366)
			(xy 344.039162 -337.893185) (xy 343.955666 -337.885212) (xy 343.873306 -337.869339) (xy 343.792828 -337.845708)
			(xy 343.71496 -337.814535) (xy 343.640408 -337.776101) (xy 343.569847 -337.730754) (xy 343.503917 -337.678905)
			(xy 343.443213 -337.621024) (xy 343.388286 -337.557635) (xy 343.339633 -337.489312) (xy 343.297695 -337.416673)
			(xy 343.262852 -337.340377) (xy 343.235419 -337.261114) (xy 343.215644 -337.179603) (xy 343.203707 -337.096581)
			(xy 343.199717 -337.0128) (xy 339.659177 -337.0128) (xy 339.659468 -337.039458) (xy 339.6589 -337.084228)
			(xy 339.649901 -337.173314) (xy 339.631999 -337.261046) (xy 339.605375 -337.346537) (xy 339.588348 -337.387946)
			(xy 339.584808 -337.397544) (xy 339.584792 -337.41798) (xy 339.588348 -337.42757) (xy 339.605388 -337.468975)
			(xy 339.632018 -337.554465) (xy 339.649921 -337.642198) (xy 339.658915 -337.731287) (xy 339.659468 -337.776058)
			(xy 339.6589 -337.820828) (xy 339.649901 -337.909914) (xy 339.631999 -337.997646) (xy 339.605375 -338.083137)
			(xy 339.588348 -338.124546) (xy 339.584808 -338.134144) (xy 339.584792 -338.15458) (xy 339.588348 -338.16417)
			(xy 339.605377 -338.205545) (xy 339.631995 -338.290972) (xy 339.649897 -338.378641) (xy 339.658904 -338.467665)
			(xy 339.659468 -338.512404) (xy 339.659468 -338.512658) (xy 339.658947 -338.553764) (xy 339.651367 -338.635625)
			(xy 339.636267 -338.716439) (xy 339.613776 -338.795514) (xy 339.584085 -338.872177) (xy 339.547449 -338.945775)
			(xy 339.50418 -339.015678) (xy 339.454646 -339.081292) (xy 339.39927 -339.142056) (xy 339.338524 -339.197453)
			(xy 339.272927 -339.247009) (xy 339.203038 -339.290302) (xy 339.129454 -339.326963) (xy 339.0528 -339.356679)
			(xy 338.973733 -339.379197) (xy 338.892925 -339.394325) (xy 338.811066 -339.401933) (xy 338.76996 -339.40242)
			(xy 338.728351 -339.40191) (xy 338.645495 -339.394139) (xy 338.563727 -339.378669) (xy 338.483759 -339.355636)
			(xy 338.40629 -339.325239) (xy 338.331996 -339.287745) (xy 338.296504 -339.266022) (xy 338.287367 -339.260856)
			(xy 338.26665 -339.257639) (xy 338.246374 -339.262975) (xy 338.23783 -339.26907) (xy 338.204174 -339.295024)
			(xy 338.132784 -339.341153) (xy 338.057318 -339.380258) (xy 337.978465 -339.411983) (xy 337.896945 -339.436039)
			(xy 337.8135 -339.452205) (xy 337.728894 -339.460335) (xy 337.686396 -339.46084) (xy 337.645286 -339.460351)
			(xy 337.563418 -339.452764) (xy 337.482599 -339.437653) (xy 337.403519 -339.415149) (xy 337.326853 -339.385443)
			(xy 337.253256 -339.348789) (xy 337.183356 -339.3055) (xy 337.117748 -339.255944) (xy 337.056994 -339.200546)
			(xy 337.001611 -339.139778) (xy 336.952073 -339.074158) (xy 336.908801 -339.004246) (xy 336.872166 -338.93064)
			(xy 336.842479 -338.853967) (xy 336.819995 -338.774881) (xy 336.804905 -338.694058) (xy 336.797338 -338.612188)
			(xy 336.796888 -338.571078) (xy 336.797437 -338.526308) (xy 336.806442 -338.437221) (xy 336.82435 -338.349489)
			(xy 336.850978 -338.263999) (xy 336.868008 -338.22259) (xy 336.871587 -338.213003) (xy 336.871579 -338.192557)
			(xy 336.868008 -338.182966) (xy 336.850977 -338.141558) (xy 336.824345 -338.056069) (xy 336.80644 -337.968336)
			(xy 336.797442 -337.879249) (xy 336.796888 -337.834478) (xy 336.796888 -337.82254) (xy 336.770409 -337.816594)
			(xy 336.718174 -337.801851) (xy 336.692494 -337.793076) (xy 336.684297 -337.790562) (xy 336.667163 -337.790562)
			(xy 336.658966 -337.793076) (xy 336.62375 -337.805037) (xy 336.551746 -337.823692) (xy 336.478426 -337.8362)
			(xy 336.40431 -337.842474) (xy 336.36712 -337.84286) (xy 336.329931 -337.842462) (xy 336.255818 -337.836174)
			(xy 336.182498 -337.823667) (xy 336.110492 -337.805029) (xy 336.075274 -337.793076) (xy 336.067077 -337.790562)
			(xy 336.049943 -337.790562) (xy 336.041746 -337.793076) (xy 336.006531 -337.805042) (xy 335.934528 -337.823696)
			(xy 335.861206 -337.836203) (xy 335.78709 -337.842475) (xy 335.7499 -337.84286) (xy 335.707962 -337.842385)
			(xy 335.624466 -337.834412) (xy 335.542106 -337.818539) (xy 335.461628 -337.794908) (xy 335.38376 -337.763735)
			(xy 335.309208 -337.725301) (xy 335.238647 -337.679954) (xy 335.172717 -337.628105) (xy 335.112013 -337.570224)
			(xy 335.057086 -337.506835) (xy 335.008433 -337.438512) (xy 334.966495 -337.365873) (xy 334.931652 -337.289577)
			(xy 334.904219 -337.210314) (xy 334.884444 -337.128803) (xy 334.872507 -337.045781) (xy 334.868517 -336.962)
			(xy 331.296671 -336.962) (xy 331.301379 -337.012832) (xy 331.301852 -337.053936) (xy 331.301852 -337.05419)
			(xy 331.301293 -337.098929) (xy 331.292274 -337.18795) (xy 331.274367 -337.275618) (xy 331.247751 -337.361045)
			(xy 331.230732 -337.402424) (xy 331.227148 -337.412009) (xy 331.227161 -337.432457) (xy 331.230732 -337.442048)
			(xy 331.247764 -337.483456) (xy 331.274397 -337.568945) (xy 331.292302 -337.656677) (xy 331.301298 -337.745765)
			(xy 331.301852 -337.790536) (xy 331.301312 -337.835307) (xy 331.292305 -337.924394) (xy 331.274395 -338.012126)
			(xy 331.247763 -338.097615) (xy 331.230732 -338.139024) (xy 331.227148 -338.148609) (xy 331.227161 -338.169057)
			(xy 331.230732 -338.178648) (xy 331.247759 -338.220024) (xy 331.274376 -338.305451) (xy 331.292279 -338.39312)
			(xy 331.301287 -338.482143) (xy 331.301852 -338.526882) (xy 331.301852 -338.527136) (xy 331.301368 -338.568238)
			(xy 331.29378 -338.65009) (xy 331.278673 -338.730894) (xy 331.256175 -338.809959) (xy 331.226478 -338.886611)
			(xy 331.189836 -338.960196) (xy 331.14656 -339.030087) (xy 331.097021 -339.095686) (xy 331.041641 -339.156436)
			(xy 330.980892 -339.211816) (xy 330.915293 -339.261356) (xy 330.845403 -339.304632) (xy 330.771818 -339.341275)
			(xy 330.695167 -339.370972) (xy 330.616102 -339.393471) (xy 330.535298 -339.408579) (xy 330.453446 -339.416167)
			(xy 330.412344 -339.416644) (xy 330.411582 -339.416644) (xy 330.370042 -339.416142) (xy 330.287326 -339.408361)
			(xy 330.205695 -339.392907) (xy 330.125859 -339.369913) (xy 330.048513 -339.339581) (xy 329.97433 -339.302172)
			(xy 329.938888 -339.2805) (xy 329.929757 -339.275322) (xy 329.909036 -339.272112) (xy 329.888759 -339.277452)
			(xy 329.880214 -339.283548) (xy 329.846565 -339.30947) (xy 329.775191 -339.355528) (xy 329.699752 -339.394575)
			(xy 329.620935 -339.426254) (xy 329.539458 -339.450278) (xy 329.456062 -339.466427) (xy 329.371506 -339.474554)
			(xy 329.329034 -339.475064) (xy 329.32878 -339.475064) (xy 329.287675 -339.474667) (xy 329.205817 -339.46708)
			(xy 329.125007 -339.451972) (xy 329.045936 -339.429472) (xy 328.969279 -339.399772) (xy 328.895689 -339.363126)
			(xy 328.825795 -339.319846) (xy 328.760192 -339.270301) (xy 328.69944 -339.214915) (xy 328.644058 -339.154159)
			(xy 328.594518 -339.088553) (xy 328.551243 -339.018655) (xy 328.514602 -338.945062) (xy 328.484908 -338.868403)
			(xy 328.462414 -338.789331) (xy 328.447312 -338.70852) (xy 328.43973 -338.626661) (xy 328.439272 -338.585556)
			(xy 328.439272 -338.585302) (xy 328.43986 -338.540564) (xy 328.44887 -338.451543) (xy 328.466769 -338.363876)
			(xy 328.493377 -338.278448) (xy 328.510392 -338.237068) (xy 328.513984 -338.227485) (xy 328.513968 -338.207035)
			(xy 328.510392 -338.197444) (xy 328.493353 -338.156039) (xy 328.466723 -338.070549) (xy 328.44882 -337.982815)
			(xy 328.439825 -337.893727) (xy 328.439272 -337.848956) (xy 328.439272 -337.837018) (xy 328.412793 -337.831074)
			(xy 328.360558 -337.81633) (xy 328.334878 -337.807554) (xy 328.326681 -337.80504) (xy 328.309547 -337.80504)
			(xy 328.30135 -337.807554) (xy 328.266125 -337.819474) (xy 328.194118 -337.838068) (xy 328.120798 -337.850516)
			(xy 328.046689 -337.856728) (xy 328.009504 -337.857084) (xy 327.97232 -337.856715) (xy 327.898212 -337.850493)
			(xy 327.824892 -337.838051) (xy 327.752881 -337.819476) (xy 327.717658 -337.807554) (xy 327.709461 -337.80504)
			(xy 327.692327 -337.80504) (xy 327.68413 -337.807554) (xy 327.649029 -337.819442) (xy 327.577272 -337.837992)
			(xy 327.504209 -337.850438) (xy 327.430358 -337.856691) (xy 327.3933 -337.857084) (xy 327.392284 -337.857084)
			(xy 327.350358 -337.856653) (xy 327.266885 -337.848681) (xy 327.184547 -337.83281) (xy 327.104092 -337.809185)
			(xy 327.026246 -337.778019) (xy 326.951715 -337.739594) (xy 326.881174 -337.694259) (xy 326.815262 -337.642424)
			(xy 326.754575 -337.584559) (xy 326.699664 -337.521186) (xy 326.651025 -337.452882) (xy 326.609099 -337.380263)
			(xy 326.574266 -337.303987) (xy 326.546841 -337.224746) (xy 326.527072 -337.143257) (xy 326.515138 -337.060258)
			(xy 326.511148 -336.9765) (xy 322.941787 -336.9765) (xy 322.94581 -337.019944) (xy 322.946268 -337.061048)
			(xy 322.946268 -337.061302) (xy 322.945685 -337.10604) (xy 322.936674 -337.195061) (xy 322.918774 -337.282729)
			(xy 322.892164 -337.368156) (xy 322.875148 -337.409536) (xy 322.871556 -337.419119) (xy 322.871574 -337.439569)
			(xy 322.875148 -337.44916) (xy 322.892185 -337.490566) (xy 322.918816 -337.576056) (xy 322.93672 -337.663789)
			(xy 322.945715 -337.752877) (xy 322.946268 -337.797648) (xy 322.945697 -337.842418) (xy 322.936698 -337.931504)
			(xy 322.918797 -338.019236) (xy 322.892175 -338.104727) (xy 322.875148 -338.146136) (xy 322.871556 -338.155719)
			(xy 322.871574 -338.176169) (xy 322.875148 -338.18576) (xy 322.892174 -338.227136) (xy 322.918792 -338.312563)
			(xy 322.936696 -338.400232) (xy 322.945704 -338.489255) (xy 322.946268 -338.533994) (xy 322.946268 -338.534248)
			(xy 322.945879 -338.575352) (xy 322.938289 -338.65721) (xy 322.923179 -338.738019) (xy 322.900678 -338.817088)
			(xy 322.870976 -338.893744) (xy 322.834329 -338.967333) (xy 322.791048 -339.037226) (xy 322.741503 -339.102828)
			(xy 322.686116 -339.163578) (xy 322.62536 -339.218959) (xy 322.559753 -339.268498) (xy 322.489856 -339.311772)
			(xy 322.416264 -339.348412) (xy 322.339605 -339.378106) (xy 322.260533 -339.400599) (xy 322.179723 -339.415702)
			(xy 322.097864 -339.423283) (xy 322.05676 -339.423756) (xy 322.055998 -339.423756) (xy 322.014458 -339.423244)
			(xy 321.931742 -339.415465) (xy 321.850112 -339.400013) (xy 321.770276 -339.377021) (xy 321.69293 -339.34669)
			(xy 321.618746 -339.309284) (xy 321.583304 -339.287612) (xy 321.574167 -339.282447) (xy 321.55345 -339.279232)
			(xy 321.533175 -339.284566) (xy 321.52463 -339.29066) (xy 321.491012 -339.316622) (xy 321.419631 -339.362677)
			(xy 321.344187 -339.401718) (xy 321.265365 -339.433392) (xy 321.183883 -339.457409) (xy 321.100483 -339.47355)
			(xy 321.015924 -339.48167) (xy 320.97345 -339.482176) (xy 320.973196 -339.482176) (xy 320.932092 -339.481752)
			(xy 320.850234 -339.474166) (xy 320.769426 -339.459059) (xy 320.690356 -339.436561) (xy 320.613699 -339.406863)
			(xy 320.54011 -339.370219) (xy 320.470216 -339.326941) (xy 320.404613 -339.277398) (xy 320.343861 -339.222013)
			(xy 320.288479 -339.161259) (xy 320.238939 -339.095655) (xy 320.195664 -339.025759) (xy 320.159022 -338.952168)
			(xy 320.129327 -338.87551) (xy 320.106832 -338.796439) (xy 320.091729 -338.71563) (xy 320.084147 -338.633772)
			(xy 320.083688 -338.592668) (xy 320.083688 -338.592414) (xy 320.084245 -338.547675) (xy 320.093264 -338.458653)
			(xy 320.111172 -338.370986) (xy 320.137789 -338.285559) (xy 320.154808 -338.24418) (xy 320.158393 -338.234595)
			(xy 320.158381 -338.214147) (xy 320.154808 -338.204556) (xy 320.137774 -338.163149) (xy 320.111142 -338.07766)
			(xy 320.093238 -337.989927) (xy 320.084242 -337.900839) (xy 320.083688 -337.856068) (xy 320.083688 -337.84413)
			(xy 320.057209 -337.838184) (xy 320.004974 -337.823441) (xy 319.979294 -337.814666) (xy 319.971097 -337.812152)
			(xy 319.953963 -337.812152) (xy 319.945766 -337.814666) (xy 319.910549 -337.82661) (xy 319.838539 -337.845197)
			(xy 319.765217 -337.857638) (xy 319.691106 -337.863844) (xy 319.65392 -337.864196) (xy 319.616736 -337.863827)
			(xy 319.542628 -337.857606) (xy 319.469308 -337.845164) (xy 319.397297 -337.826589) (xy 319.362074 -337.814666)
			(xy 319.353877 -337.812152) (xy 319.336743 -337.812152) (xy 319.328546 -337.814666) (xy 319.293452 -337.826578)
			(xy 319.221693 -337.845121) (xy 319.148627 -337.85756) (xy 319.074774 -337.863807) (xy 319.037716 -337.864196)
			(xy 319.0367 -337.864196) (xy 318.994774 -337.863741) (xy 318.911301 -337.855771) (xy 318.828963 -337.839902)
			(xy 318.748507 -337.816278) (xy 318.670661 -337.785113) (xy 318.59613 -337.746689) (xy 318.525589 -337.701355)
			(xy 318.459676 -337.649521) (xy 318.398989 -337.591656) (xy 318.344078 -337.528284) (xy 318.295438 -337.45998)
			(xy 318.253512 -337.387361) (xy 318.218678 -337.311086) (xy 318.191253 -337.231846) (xy 318.171484 -337.150357)
			(xy 318.15955 -337.067358) (xy 318.155561 -336.9836) (xy 99.362614 -336.9836) (xy 99.373171 -336.999727)
			(xy 99.41309 -337.075842) (xy 99.445481 -337.155452) (xy 99.470043 -337.237815) (xy 99.486546 -337.322163)
			(xy 99.494837 -337.40771) (xy 99.495356 -337.450684) (xy 99.494854 -337.493421) (xy 99.48668 -337.578504)
			(xy 99.470386 -337.662411) (xy 99.446122 -337.744369) (xy 99.430586 -337.784186) (xy 99.426944 -337.794219)
			(xy 99.427619 -337.815536) (xy 99.431856 -337.825334) (xy 99.448914 -337.861614) (xy 99.477225 -337.936624)
			(xy 99.498666 -338.013878) (xy 99.513065 -338.092749) (xy 99.520304 -338.172597) (xy 99.520756 -338.212684)
			(xy 99.520272 -338.252763) (xy 99.512982 -338.33259) (xy 99.498549 -338.411439) (xy 99.488244 -338.450174)
			(xy 99.485843 -338.460698) (xy 99.489132 -338.482012) (xy 99.494594 -338.491322) (xy 99.517345 -338.52734)
			(xy 99.556637 -338.602937) (xy 99.588514 -338.681946) (xy 99.612684 -338.763644) (xy 99.628925 -338.847279)
			(xy 99.637089 -338.932085) (xy 99.637596 -338.974684) (xy 99.637001 -339.021087) (xy 99.627302 -339.113385)
			(xy 99.608039 -339.204171) (xy 99.579422 -339.292455) (xy 99.561142 -339.33511) (xy 99.557344 -339.345055)
			(xy 99.557338 -339.366316) (xy 99.561142 -339.376258) (xy 99.579397 -339.418922) (xy 99.607993 -339.507209)
			(xy 99.627252 -339.597991) (xy 99.636966 -339.690283) (xy 99.637596 -339.736684) (xy 99.637118 -339.777779)
			(xy 99.629538 -339.859619) (xy 99.614439 -339.94041) (xy 99.591952 -340.019465) (xy 99.562267 -340.096107)
			(xy 99.525639 -340.169684) (xy 99.482378 -340.239568) (xy 99.432856 -340.305164) (xy 99.377493 -340.36591)
			(xy 99.316762 -340.421291) (xy 99.251181 -340.470833) (xy 99.18131 -340.514113) (xy 99.107743 -340.550763)
			(xy 99.031109 -340.58047) (xy 98.952062 -340.60298) (xy 98.871275 -340.618102) (xy 98.789437 -340.625707)
			(xy 98.748342 -340.626192) (xy 98.747834 -340.626192) (xy 98.704859 -340.625663) (xy 98.619309 -340.617375)
			(xy 98.534957 -340.600874) (xy 98.45259 -340.576313) (xy 98.372977 -340.543922) (xy 98.296859 -340.504001)
			(xy 98.224947 -340.456925) (xy 98.157912 -340.403131) (xy 98.096378 -340.343122) (xy 98.040919 -340.277458)
			(xy 98.01606 -340.242398) (xy 98.010455 -340.235056) (xy 97.995216 -340.224641) (xy 97.986342 -340.222078)
			(xy 97.94544 -340.211492) (xy 97.865683 -340.183605) (xy 97.788928 -340.148281) (xy 97.715869 -340.105839)
			(xy 97.647164 -340.05666) (xy 97.583432 -340.001188) (xy 97.525246 -339.939922) (xy 97.473132 -339.873416)
			(xy 97.427559 -339.802268) (xy 97.388937 -339.727119) (xy 97.357615 -339.648646) (xy 97.333875 -339.567557)
			(xy 97.317931 -339.484583) (xy 97.309927 -339.40047) (xy 97.309432 -339.358224) (xy 97.309829 -339.321956)
			(xy 97.315809 -339.249667) (xy 97.327648 -339.178103) (xy 97.336102 -339.142832) (xy 97.338115 -339.132729)
			(xy 97.334853 -339.112411) (xy 97.329752 -339.103462) (xy 97.30766 -339.067807) (xy 97.269551 -338.993079)
			(xy 97.238646 -338.915096) (xy 97.215218 -338.83455) (xy 97.199477 -338.752156) (xy 97.191562 -338.668646)
			(xy 97.191068 -338.626704) (xy 97.191648 -338.581935) (xy 97.200654 -338.49285) (xy 97.218554 -338.405119)
			(xy 97.245168 -338.319627) (xy 97.262188 -338.278216) (xy 97.265753 -338.268625) (xy 97.265754 -338.248182)
			(xy 97.262188 -338.238592) (xy 97.245172 -338.197246) (xy 97.218563 -338.111882) (xy 97.20066 -338.024278)
			(xy 97.191642 -337.935319) (xy 97.191068 -337.890612) (xy 97.191068 -337.889596) (xy 97.191322 -337.878166)
			(xy 97.164844 -337.872216) (xy 97.112609 -337.857476) (xy 97.086928 -337.848702) (xy 97.078731 -337.846188)
			(xy 97.061597 -337.846188) (xy 97.0534 -337.848702) (xy 97.01818 -337.860638) (xy 96.946171 -337.879227)
			(xy 96.87285 -337.89167) (xy 96.798739 -337.897878) (xy 96.761554 -337.898232) (xy 96.724369 -337.89788)
			(xy 96.650261 -337.891654) (xy 96.576941 -337.879206) (xy 96.504931 -337.860627) (xy 96.469708 -337.848702)
			(xy 96.461511 -337.846188) (xy 96.444377 -337.846188) (xy 96.43618 -337.848702) (xy 96.401082 -337.860602)
			(xy 96.329324 -337.879149) (xy 96.25626 -337.891592) (xy 96.182408 -337.897841) (xy 96.14535 -337.898232)
			(xy 96.144334 -337.898232) (xy 96.102408 -337.897723) (xy 96.018934 -337.889755) (xy 95.936596 -337.873888)
			(xy 95.85614 -337.850267) (xy 95.778292 -337.819104) (xy 95.70376 -337.780683) (xy 95.633218 -337.73535)
			(xy 95.567304 -337.683517) (xy 95.506616 -337.625654) (xy 95.451703 -337.562283) (xy 95.403062 -337.493979)
			(xy 95.361135 -337.421361) (xy 95.3263 -337.345087) (xy 95.298874 -337.265846) (xy 95.279105 -337.184357)
			(xy 95.267171 -337.101358) (xy 95.263181 -337.0176) (xy 91.722641 -337.0176) (xy 91.722956 -337.044284)
			(xy 91.722404 -337.089054) (xy 91.71339 -337.178139) (xy 91.695482 -337.26587) (xy 91.668861 -337.351361)
			(xy 91.651836 -337.392772) (xy 91.648282 -337.402366) (xy 91.648276 -337.422805) (xy 91.651836 -337.432396)
			(xy 91.668872 -337.473803) (xy 91.695506 -337.559291) (xy 91.71341 -337.647024) (xy 91.722404 -337.736113)
			(xy 91.722956 -337.780884) (xy 91.722404 -337.825654) (xy 91.71339 -337.914739) (xy 91.695482 -338.00247)
			(xy 91.668861 -338.087961) (xy 91.651836 -338.129372) (xy 91.648282 -338.138966) (xy 91.648276 -338.159405)
			(xy 91.651836 -338.168996) (xy 91.668872 -338.210403) (xy 91.695506 -338.295891) (xy 91.71341 -338.383624)
			(xy 91.722404 -338.472713) (xy 91.722956 -338.517484) (xy 91.722432 -338.558593) (xy 91.714846 -338.64046)
			(xy 91.699738 -338.721278) (xy 91.677236 -338.800357) (xy 91.647532 -338.877021) (xy 91.610881 -338.950618)
			(xy 91.567594 -339.020518) (xy 91.518041 -339.086125) (xy 91.462645 -339.146879) (xy 91.401879 -339.202262)
			(xy 91.336261 -339.251801) (xy 91.266352 -339.295073) (xy 91.192747 -339.331709) (xy 91.116076 -339.361396)
			(xy 91.036993 -339.383882) (xy 90.956172 -339.398973) (xy 90.874303 -339.406541) (xy 90.833194 -339.406992)
			(xy 90.791589 -339.406554) (xy 90.70874 -339.398816) (xy 90.626975 -339.383379) (xy 90.547007 -339.360379)
			(xy 90.469535 -339.330016) (xy 90.395235 -339.292555) (xy 90.359738 -339.270848) (xy 90.350631 -339.26562)
			(xy 90.329893 -339.262421) (xy 90.309608 -339.267785) (xy 90.301064 -339.273896) (xy 90.267427 -339.299833)
			(xy 90.196051 -339.345891) (xy 90.12061 -339.384937) (xy 90.041791 -339.416615) (xy 89.960312 -339.440636)
			(xy 89.876914 -339.456781) (xy 89.792357 -339.464905) (xy 89.749884 -339.465412) (xy 89.74963 -339.465412)
			(xy 89.708522 -339.464959) (xy 89.626657 -339.457377) (xy 89.545841 -339.442274) (xy 89.466762 -339.41978)
			(xy 89.390096 -339.390087) (xy 89.316497 -339.353447) (xy 89.246591 -339.310173) (xy 89.180976 -339.260635)
			(xy 89.120211 -339.205254) (xy 89.064815 -339.144504) (xy 89.015259 -339.078902) (xy 88.971967 -339.009008)
			(xy 88.935308 -338.935418) (xy 88.905594 -338.85876) (xy 88.883079 -338.779687) (xy 88.867956 -338.698875)
			(xy 88.860352 -338.617012) (xy 88.859868 -338.575904) (xy 88.860448 -338.531135) (xy 88.869454 -338.44205)
			(xy 88.887354 -338.354319) (xy 88.913968 -338.268827) (xy 88.930988 -338.227416) (xy 88.934553 -338.217825)
			(xy 88.934554 -338.197382) (xy 88.930988 -338.187792) (xy 88.913972 -338.146446) (xy 88.887363 -338.061082)
			(xy 88.86946 -337.973478) (xy 88.860442 -337.884519) (xy 88.859868 -337.839812) (xy 88.859868 -337.838796)
			(xy 88.860122 -337.827366) (xy 88.833644 -337.821416) (xy 88.781409 -337.806676) (xy 88.755728 -337.797902)
			(xy 88.747531 -337.795388) (xy 88.730397 -337.795388) (xy 88.7222 -337.797902) (xy 88.68698 -337.809838)
			(xy 88.614971 -337.828427) (xy 88.54165 -337.84087) (xy 88.467539 -337.847078) (xy 88.430354 -337.847432)
			(xy 88.393169 -337.84708) (xy 88.319061 -337.840854) (xy 88.245741 -337.828406) (xy 88.173731 -337.809827)
			(xy 88.138508 -337.797902) (xy 88.130311 -337.795388) (xy 88.113177 -337.795388) (xy 88.10498 -337.797902)
			(xy 88.069882 -337.809802) (xy 87.998124 -337.828349) (xy 87.92506 -337.840792) (xy 87.851208 -337.847041)
			(xy 87.81415 -337.847432) (xy 87.813134 -337.847432) (xy 87.771208 -337.846923) (xy 87.687734 -337.838955)
			(xy 87.605396 -337.823088) (xy 87.52494 -337.799467) (xy 87.447092 -337.768304) (xy 87.37256 -337.729883)
			(xy 87.302018 -337.68455) (xy 87.236104 -337.632717) (xy 87.175416 -337.574854) (xy 87.120503 -337.511483)
			(xy 87.071862 -337.443179) (xy 87.029935 -337.370561) (xy 86.9951 -337.294287) (xy 86.967674 -337.215046)
			(xy 86.947905 -337.133557) (xy 86.935971 -337.050558) (xy 86.931981 -336.9668) (xy 83.360149 -336.9668)
			(xy 83.364863 -337.017649) (xy 83.36534 -337.058762) (xy 83.364781 -337.103532) (xy 83.35577 -337.192617)
			(xy 83.337863 -337.280348) (xy 83.311243 -337.365839) (xy 83.29422 -337.40725) (xy 83.290679 -337.416847)
			(xy 83.290665 -337.437283) (xy 83.29422 -337.446874) (xy 83.311248 -337.488284) (xy 83.337884 -337.573771)
			(xy 83.355791 -337.661503) (xy 83.364787 -337.750591) (xy 83.36534 -337.795362) (xy 83.364781 -337.840132)
			(xy 83.35577 -337.929217) (xy 83.337863 -338.016948) (xy 83.311243 -338.102439) (xy 83.29422 -338.14385)
			(xy 83.290679 -338.153447) (xy 83.290665 -338.173883) (xy 83.29422 -338.183474) (xy 83.311248 -338.224884)
			(xy 83.337884 -338.310371) (xy 83.355791 -338.398103) (xy 83.364787 -338.487191) (xy 83.36534 -338.531962)
			(xy 83.364865 -338.573077) (xy 83.357281 -338.654956) (xy 83.342174 -338.735786) (xy 83.319674 -338.814878)
			(xy 83.289971 -338.891556) (xy 83.253319 -338.965166) (xy 83.210032 -339.03508) (xy 83.160479 -339.100701)
			(xy 83.105082 -339.16147) (xy 83.044313 -339.216869) (xy 82.978693 -339.266423) (xy 82.90878 -339.309712)
			(xy 82.83517 -339.346364) (xy 82.758493 -339.376068) (xy 82.679402 -339.398571) (xy 82.598572 -339.413679)
			(xy 82.516693 -339.421265) (xy 82.475578 -339.421724) (xy 82.433968 -339.421253) (xy 82.351111 -339.413475)
			(xy 82.269342 -339.397998) (xy 82.189374 -339.374957) (xy 82.111906 -339.344554) (xy 82.037613 -339.307053)
			(xy 82.002122 -339.285326) (xy 81.992978 -339.280175) (xy 81.972265 -339.276953) (xy 81.951992 -339.282282)
			(xy 81.943448 -339.288374) (xy 81.909821 -339.314367) (xy 81.838426 -339.360491) (xy 81.762954 -339.399592)
			(xy 81.684096 -339.431311) (xy 81.602571 -339.455361) (xy 81.519123 -339.471521) (xy 81.434513 -339.479643)
			(xy 81.392014 -339.480144) (xy 81.350899 -339.479688) (xy 81.269019 -339.472102) (xy 81.188189 -339.456993)
			(xy 81.109097 -339.434491) (xy 81.032419 -339.404786) (xy 80.95881 -339.368133) (xy 80.888896 -339.324845)
			(xy 80.823275 -339.27529) (xy 80.762506 -339.219892) (xy 80.707108 -339.159122) (xy 80.657553 -339.093501)
			(xy 80.614265 -339.023587) (xy 80.577612 -338.949977) (xy 80.547908 -338.873299) (xy 80.525406 -338.794207)
			(xy 80.510297 -338.713377) (xy 80.502712 -338.631497) (xy 80.502252 -338.590382) (xy 80.502826 -338.545613)
			(xy 80.511834 -338.456528) (xy 80.529735 -338.368797) (xy 80.556351 -338.283305) (xy 80.573372 -338.241894)
			(xy 80.576945 -338.232306) (xy 80.576939 -338.211861) (xy 80.573372 -338.20227) (xy 80.556348 -338.160927)
			(xy 80.529742 -338.075562) (xy 80.511841 -337.987957) (xy 80.502825 -337.898997) (xy 80.502252 -337.85429)
			(xy 80.502252 -337.853274) (xy 80.502506 -337.841844) (xy 80.476028 -337.835896) (xy 80.423793 -337.821155)
			(xy 80.398112 -337.81238) (xy 80.389915 -337.809866) (xy 80.372781 -337.809866) (xy 80.364584 -337.81238)
			(xy 80.329366 -337.824336) (xy 80.257364 -337.842992) (xy 80.184043 -337.855502) (xy 80.109928 -337.861777)
			(xy 80.072738 -337.862164) (xy 80.035549 -337.861761) (xy 79.961436 -337.855475) (xy 79.888116 -337.842969)
			(xy 79.81611 -337.824332) (xy 79.780892 -337.81238) (xy 79.772695 -337.809866) (xy 79.755561 -337.809866)
			(xy 79.747364 -337.81238) (xy 79.712148 -337.824342) (xy 79.640145 -337.842996) (xy 79.566824 -337.855505)
			(xy 79.492708 -337.861778) (xy 79.455518 -337.862164) (xy 79.413579 -337.861698) (xy 79.330081 -337.853726)
			(xy 79.247718 -337.837853) (xy 79.167237 -337.814224) (xy 79.089367 -337.783051) (xy 79.014813 -337.744616)
			(xy 78.94425 -337.69927) (xy 78.878316 -337.64742) (xy 78.81761 -337.589539) (xy 78.762681 -337.526148)
			(xy 78.714027 -337.457824) (xy 78.672087 -337.385183) (xy 78.637243 -337.308885) (xy 78.609809 -337.229621)
			(xy 78.590033 -337.148107) (xy 78.578096 -337.065083) (xy 78.574105 -336.9813) (xy 75.005252 -336.9813)
			(xy 75.00928 -337.024761) (xy 75.009756 -337.065874) (xy 75.009201 -337.110644) (xy 75.000188 -337.199729)
			(xy 74.982281 -337.28746) (xy 74.95566 -337.372951) (xy 74.938636 -337.414362) (xy 74.935088 -337.423957)
			(xy 74.935078 -337.444395) (xy 74.938636 -337.453986) (xy 74.955669 -337.495394) (xy 74.982303 -337.580882)
			(xy 75.000209 -337.668615) (xy 75.009203 -337.757703) (xy 75.009756 -337.802474) (xy 75.009201 -337.847244)
			(xy 75.000188 -337.936329) (xy 74.982281 -338.02406) (xy 74.95566 -338.109551) (xy 74.938636 -338.150962)
			(xy 74.935088 -338.160557) (xy 74.935078 -338.180995) (xy 74.938636 -338.190586) (xy 74.955669 -338.231994)
			(xy 74.982303 -338.317482) (xy 75.000209 -338.405215) (xy 75.009203 -338.494303) (xy 75.009756 -338.539074)
			(xy 75.009277 -338.580189) (xy 75.001692 -338.662067) (xy 74.986584 -338.742897) (xy 74.964083 -338.821988)
			(xy 74.93438 -338.898665) (xy 74.897729 -338.972274) (xy 74.854442 -339.042187) (xy 74.804888 -339.107809)
			(xy 74.749492 -339.168577) (xy 74.688724 -339.223976) (xy 74.623104 -339.27353) (xy 74.553192 -339.316819)
			(xy 74.479583 -339.353472) (xy 74.402907 -339.383177) (xy 74.323816 -339.40568) (xy 74.242987 -339.420789)
			(xy 74.161109 -339.428376) (xy 74.119994 -339.428836) (xy 74.078384 -339.428356) (xy 73.995528 -339.420579)
			(xy 73.913759 -339.405104) (xy 73.833791 -339.382065) (xy 73.756322 -339.351663) (xy 73.682029 -339.314164)
			(xy 73.646538 -339.292438) (xy 73.63743 -339.287211) (xy 73.616693 -339.284013) (xy 73.596408 -339.289376)
			(xy 73.587864 -339.295486) (xy 73.554233 -339.321473) (xy 73.482838 -339.367598) (xy 73.407368 -339.406699)
			(xy 73.32851 -339.438419) (xy 73.246986 -339.46247) (xy 73.163538 -339.47863) (xy 73.078929 -339.486754)
			(xy 73.03643 -339.487256) (xy 72.995315 -339.486773) (xy 72.913437 -339.479188) (xy 72.832607 -339.464081)
			(xy 72.753517 -339.44158) (xy 72.67684 -339.411877) (xy 72.60323 -339.375226) (xy 72.533317 -339.33194)
			(xy 72.467696 -339.282387) (xy 72.406927 -339.22699) (xy 72.351529 -339.166223) (xy 72.301974 -339.100603)
			(xy 72.258685 -339.030691) (xy 72.222032 -338.957082) (xy 72.192327 -338.880406) (xy 72.169824 -338.801316)
			(xy 72.154715 -338.720487) (xy 72.147128 -338.638609) (xy 72.146668 -338.597494) (xy 72.147245 -338.552725)
			(xy 72.156251 -338.46364) (xy 72.174152 -338.375909) (xy 72.200767 -338.290417) (xy 72.217788 -338.249006)
			(xy 72.221359 -338.239417) (xy 72.221356 -338.218972) (xy 72.217788 -338.209382) (xy 72.200768 -338.168037)
			(xy 72.174161 -338.082673) (xy 72.156259 -337.995068) (xy 72.147241 -337.906109) (xy 72.146668 -337.861402)
			(xy 72.146668 -337.860386) (xy 72.146922 -337.848956) (xy 72.120444 -337.843006) (xy 72.068209 -337.828266)
			(xy 72.042528 -337.819492) (xy 72.034331 -337.816978) (xy 72.017197 -337.816978) (xy 72.009 -337.819492)
			(xy 71.973781 -337.831444) (xy 71.901779 -337.850101) (xy 71.828459 -337.862612) (xy 71.754344 -337.868888)
			(xy 71.717154 -337.869276) (xy 71.679965 -337.868873) (xy 71.605852 -337.862587) (xy 71.532532 -337.850082)
			(xy 71.460526 -337.831445) (xy 71.425308 -337.819492) (xy 71.417111 -337.816978) (xy 71.399977 -337.816978)
			(xy 71.39178 -337.819492) (xy 71.356562 -337.83145) (xy 71.28456 -337.850105) (xy 71.211239 -337.862615)
			(xy 71.137124 -337.868889) (xy 71.099934 -337.869276) (xy 71.057995 -337.868786) (xy 70.974497 -337.860816)
			(xy 70.892134 -337.844945) (xy 70.811653 -337.821316) (xy 70.733783 -337.790144) (xy 70.659228 -337.751711)
			(xy 70.588664 -337.706365) (xy 70.522731 -337.654517) (xy 70.462025 -337.596636) (xy 70.407095 -337.533246)
			(xy 70.35844 -337.464922) (xy 70.3165 -337.392282) (xy 70.281655 -337.315985) (xy 70.254221 -337.23672)
			(xy 70.234446 -337.155207) (xy 70.222508 -337.072183) (xy 70.218517 -336.9884) (xy 2.509012 -336.9884)
			(xy 2.509012 -341.9277) (xy 103.538816 -341.9277) (xy 103.542807 -341.843921) (xy 103.554743 -341.760902)
			(xy 103.574517 -341.679392) (xy 103.601948 -341.600131) (xy 103.63679 -341.523837) (xy 103.678726 -341.4512)
			(xy 103.727376 -341.382878) (xy 103.7823 -341.319489) (xy 103.843001 -341.261608) (xy 103.908929 -341.20976)
			(xy 103.979486 -341.164412) (xy 104.054035 -341.125977) (xy 104.131899 -341.094802) (xy 104.212375 -341.071169)
			(xy 104.294732 -341.055293) (xy 104.378225 -341.047317) (xy 104.420162 -341.046816) (xy 104.457351 -341.047215)
			(xy 104.531464 -341.053502) (xy 104.604784 -341.066008) (xy 104.67679 -341.084646) (xy 104.712008 -341.0966)
			(xy 104.720205 -341.099114) (xy 104.737339 -341.099114) (xy 104.745536 -341.0966) (xy 104.780752 -341.084638)
			(xy 104.852755 -341.065983) (xy 104.926076 -341.053475) (xy 105.000192 -341.047202) (xy 105.037382 -341.046816)
			(xy 105.07218 -341.047578) (xy 105.081741 -341.004913) (xy 105.108207 -340.921573) (xy 105.125012 -340.881208)
			(xy 105.128629 -340.871492) (xy 105.128644 -340.850784) (xy 105.125012 -340.841076) (xy 105.107898 -340.799819)
			(xy 105.081109 -340.714608) (xy 105.063074 -340.627124) (xy 105.053979 -340.538265) (xy 105.053384 -340.493604)
			(xy 105.053384 -340.492842) (xy 105.053883 -340.450917) (xy 105.061853 -340.367446) (xy 105.077722 -340.285111)
			(xy 105.101345 -340.204657) (xy 105.132509 -340.126813) (xy 105.170932 -340.052283) (xy 105.216265 -339.981744)
			(xy 105.268098 -339.915833) (xy 105.325961 -339.855147) (xy 105.389331 -339.800237) (xy 105.457634 -339.751599)
			(xy 105.530251 -339.709674) (xy 105.606524 -339.674841) (xy 105.685763 -339.647416) (xy 105.767249 -339.627647)
			(xy 105.850246 -339.615714) (xy 105.934002 -339.611725) (xy 106.017758 -339.615714) (xy 106.100755 -339.627647)
			(xy 106.182241 -339.647416) (xy 106.26148 -339.674841) (xy 106.337753 -339.709674) (xy 106.41037 -339.751599)
			(xy 106.478673 -339.800237) (xy 106.542043 -339.855147) (xy 106.599906 -339.915833) (xy 106.651739 -339.981744)
			(xy 106.697072 -340.052283) (xy 106.735495 -340.126813) (xy 106.766659 -340.204657) (xy 106.790282 -340.285111)
			(xy 106.806151 -340.367446) (xy 106.814121 -340.450917) (xy 106.81462 -340.492842) (xy 106.81462 -340.493604)
			(xy 106.814051 -340.538267) (xy 106.804977 -340.627133) (xy 106.786945 -340.714621) (xy 106.760139 -340.799831)
			(xy 106.742992 -340.841076) (xy 106.739326 -340.850777) (xy 106.739342 -340.871499) (xy 106.742992 -340.881208)
			(xy 106.751628 -340.901528) (xy 106.756582 -340.912278) (xy 106.774248 -340.927996) (xy 106.797062 -340.934212)
			(xy 106.808778 -340.932516) (xy 106.8525 -340.924198) (xy 106.941059 -340.915292) (xy 106.985562 -340.914736)
			(xy 106.98607 -340.914736) (xy 107.027176 -340.915241) (xy 107.109038 -340.922823) (xy 107.189852 -340.937924)
			(xy 107.268928 -340.960416) (xy 107.345591 -340.990108) (xy 107.419189 -341.026745) (xy 107.489092 -341.070016)
			(xy 107.554706 -341.119551) (xy 107.61547 -341.174927) (xy 107.670867 -341.235674) (xy 107.720423 -341.301272)
			(xy 107.763716 -341.371161) (xy 107.800377 -341.444747) (xy 107.830093 -341.521401) (xy 107.85261 -341.60047)
			(xy 107.867738 -341.681278) (xy 107.875346 -341.763138) (xy 107.875832 -341.804244) (xy 107.875268 -341.849014)
			(xy 107.867795 -341.9229) (xy 351.475729 -341.9229) (xy 351.479719 -341.839138) (xy 351.491654 -341.756134)
			(xy 351.511424 -341.674641) (xy 351.538852 -341.595396) (xy 351.573688 -341.519117) (xy 351.615617 -341.446494)
			(xy 351.66426 -341.378187) (xy 351.719176 -341.314813) (xy 351.779867 -341.256945) (xy 351.845785 -341.205109)
			(xy 351.916331 -341.159774) (xy 351.990867 -341.12135) (xy 352.068718 -341.090185) (xy 352.149179 -341.066562)
			(xy 352.231522 -341.050694) (xy 352.314999 -341.042726) (xy 352.356928 -341.042244) (xy 352.357944 -341.042244)
			(xy 352.395001 -341.04264) (xy 352.46885 -341.048907) (xy 352.541913 -341.061352) (xy 352.613673 -341.079887)
			(xy 352.648774 -341.091774) (xy 352.656971 -341.094288) (xy 352.674105 -341.094288) (xy 352.682302 -341.091774)
			(xy 352.717522 -341.079841) (xy 352.789531 -341.06125) (xy 352.862852 -341.048806) (xy 352.936963 -341.042598)
			(xy 352.974148 -341.042244) (xy 352.988626 -341.042244) (xy 352.999994 -341.041829) (xy 353.020668 -341.032414)
			(xy 353.035248 -341.014994) (xy 353.038664 -341.004144) (xy 353.047281 -340.972176) (xy 353.068638 -340.909499)
			(xy 353.081336 -340.878922) (xy 353.084895 -340.86933) (xy 353.084899 -340.848889) (xy 353.081336 -340.839298)
			(xy 353.064328 -340.797915) (xy 353.037705 -340.71249) (xy 353.019796 -340.624824) (xy 353.010783 -340.535802)
			(xy 353.010216 -340.491064) (xy 353.010216 -340.49081) (xy 353.01072 -340.448462) (xy 353.018771 -340.364148)
			(xy 353.0348 -340.280982) (xy 353.058661 -340.199715) (xy 353.09014 -340.121085) (xy 353.128951 -340.045804)
			(xy 353.174741 -339.974552) (xy 353.227097 -339.907976) (xy 353.285545 -339.846678) (xy 353.349555 -339.791213)
			(xy 353.418547 -339.742084) (xy 353.491897 -339.699735) (xy 353.56894 -339.664551) (xy 353.648979 -339.636849)
			(xy 353.731288 -339.616881) (xy 353.815123 -339.604828) (xy 353.899724 -339.600798) (xy 353.984325 -339.604828)
			(xy 354.06816 -339.616881) (xy 354.150469 -339.636849) (xy 354.230508 -339.664551) (xy 354.307551 -339.699735)
			(xy 354.380901 -339.742084) (xy 354.449893 -339.791213) (xy 354.513903 -339.846678) (xy 354.572351 -339.907976)
			(xy 354.624707 -339.974552) (xy 354.670497 -340.045804) (xy 354.709308 -340.121085) (xy 354.740787 -340.199715)
			(xy 354.764648 -340.280982) (xy 354.780677 -340.364148) (xy 354.788728 -340.448462) (xy 354.789232 -340.49081)
			(xy 354.789232 -340.491064) (xy 354.788666 -340.535802) (xy 354.779649 -340.624824) (xy 354.761744 -340.712491)
			(xy 354.73513 -340.797919) (xy 354.718112 -340.839298) (xy 354.714539 -340.848887) (xy 354.714543 -340.869332)
			(xy 354.718112 -340.878922) (xy 354.735129 -340.920302) (xy 354.761749 -341.005728) (xy 354.779655 -341.093395)
			(xy 354.788666 -341.182417) (xy 354.789232 -341.227156) (xy 354.789232 -341.228172) (xy 354.789643 -341.238195)
			(xy 354.79731 -341.256718) (xy 354.811486 -341.270892) (xy 354.830009 -341.278557) (xy 354.840032 -341.278972)
			(xy 354.840286 -341.278972) (xy 354.84794 -341.278603) (xy 354.862532 -341.273956) (xy 354.868988 -341.269828)
			(xy 354.869242 -341.269828) (xy 354.906515 -341.244617) (xy 354.985224 -341.200991) (xy 355.067937 -341.165538)
			(xy 355.153807 -341.13862) (xy 355.241957 -341.120513) (xy 355.331485 -341.111402) (xy 355.37648 -341.110824)
			(xy 355.376988 -341.110824) (xy 355.418092 -341.111264) (xy 355.499949 -341.118848) (xy 355.580757 -341.133953)
			(xy 355.659827 -341.15645) (xy 355.736484 -341.186147) (xy 355.810073 -341.22279) (xy 355.879967 -341.266067)
			(xy 355.94557 -341.315609) (xy 356.006322 -341.370992) (xy 356.061704 -341.431745) (xy 356.111244 -341.497349)
			(xy 356.15452 -341.567245) (xy 356.191162 -341.640835) (xy 356.220857 -341.717492) (xy 356.243352 -341.796562)
			(xy 356.258455 -341.877371) (xy 356.266037 -341.959228) (xy 356.266496 -342.000332) (xy 356.266496 -342.000586)
			(xy 356.26594 -342.045325) (xy 356.256921 -342.134347) (xy 356.239013 -342.222014) (xy 356.212396 -342.307441)
			(xy 356.195376 -342.34882) (xy 356.191792 -342.358405) (xy 356.191804 -342.378853) (xy 356.195376 -342.388444)
			(xy 356.212409 -342.429852) (xy 356.239041 -342.515341) (xy 356.256946 -342.603073) (xy 356.265942 -342.692161)
			(xy 356.266496 -342.736932) (xy 356.265952 -342.781703) (xy 356.256945 -342.87079) (xy 356.239036 -342.958522)
			(xy 356.212407 -343.044011) (xy 356.195376 -343.08542) (xy 356.191792 -343.095005) (xy 356.191804 -343.115453)
			(xy 356.195376 -343.125044) (xy 356.212398 -343.166422) (xy 356.239017 -343.251848) (xy 356.256922 -343.339516)
			(xy 356.265931 -343.428539) (xy 356.266496 -343.473278) (xy 356.266496 -343.473532) (xy 356.266064 -343.514635)
			(xy 356.258476 -343.596491) (xy 356.243368 -343.677298) (xy 356.220868 -343.756366) (xy 356.191169 -343.83302)
			(xy 356.154525 -343.906608) (xy 356.111246 -343.9765) (xy 356.061704 -344.042101) (xy 356.00632 -344.102851)
			(xy 355.945567 -344.158232) (xy 355.879964 -344.207771) (xy 355.810069 -344.251046) (xy 355.73648 -344.287687)
			(xy 355.659824 -344.317382) (xy 355.580755 -344.339878) (xy 355.499948 -344.354982) (xy 355.418091 -344.362566)
			(xy 355.376988 -344.36304) (xy 355.376226 -344.36304) (xy 355.334685 -344.362565) (xy 355.251968 -344.35478)
			(xy 355.170337 -344.33932) (xy 355.090501 -344.316321) (xy 355.013156 -344.285984) (xy 354.938974 -344.248571)
			(xy 354.903532 -344.226896) (xy 354.894382 -344.221758) (xy 354.873674 -344.218535) (xy 354.853403 -344.223857)
			(xy 354.844858 -344.229944) (xy 354.811228 -344.255891) (xy 354.73985 -344.301947) (xy 354.664408 -344.340991)
			(xy 354.585588 -344.372667) (xy 354.504107 -344.396686) (xy 354.420709 -344.412831) (xy 354.336151 -344.420953)
			(xy 354.293678 -344.42146) (xy 354.293424 -344.42146) (xy 354.25232 -344.421025) (xy 354.170462 -344.413441)
			(xy 354.089653 -344.398337) (xy 354.010583 -344.375841) (xy 353.933926 -344.346144) (xy 353.860336 -344.309501)
			(xy 353.790441 -344.266224) (xy 353.724837 -344.216682) (xy 353.664085 -344.161298) (xy 353.608703 -344.100544)
			(xy 353.559163 -344.03494) (xy 353.515887 -343.965043) (xy 353.479246 -343.891453) (xy 353.449552 -343.814794)
			(xy 353.427057 -343.735723) (xy 353.411955 -343.654914) (xy 353.404374 -343.573056) (xy 353.403916 -343.531952)
			(xy 353.403916 -343.531698) (xy 353.4045 -343.48696) (xy 353.413511 -343.397939) (xy 353.431411 -343.310272)
			(xy 353.45802 -343.224844) (xy 353.475036 -343.183464) (xy 353.478628 -343.173881) (xy 353.47861 -343.153431)
			(xy 353.475036 -343.14384) (xy 353.457998 -343.102434) (xy 353.431368 -343.016945) (xy 353.413464 -342.929211)
			(xy 353.404469 -342.840123) (xy 353.403916 -342.795352) (xy 353.403916 -342.783414) (xy 353.377438 -342.777466)
			(xy 353.325203 -342.762725) (xy 353.299522 -342.75395) (xy 353.291325 -342.751436) (xy 353.274191 -342.751436)
			(xy 353.265994 -342.75395) (xy 353.230774 -342.765885) (xy 353.158765 -342.784475) (xy 353.085444 -342.796919)
			(xy 353.011333 -342.803127) (xy 352.974148 -342.80348) (xy 352.936964 -342.803098) (xy 352.862857 -342.79688)
			(xy 352.789537 -342.784441) (xy 352.717525 -342.76587) (xy 352.682302 -342.75395) (xy 352.674105 -342.751436)
			(xy 352.656971 -342.751436) (xy 352.648774 -342.75395) (xy 352.613678 -342.765853) (xy 352.541919 -342.784399)
			(xy 352.468854 -342.796841) (xy 352.395002 -342.80309) (xy 352.357944 -342.80348) (xy 352.356928 -342.80348)
			(xy 352.314999 -342.803074) (xy 352.231522 -342.795106) (xy 352.149179 -342.779238) (xy 352.068718 -342.755615)
			(xy 351.990867 -342.72445) (xy 351.916331 -342.686026) (xy 351.845785 -342.640691) (xy 351.779867 -342.588855)
			(xy 351.719176 -342.530987) (xy 351.66426 -342.467613) (xy 351.615617 -342.399306) (xy 351.573688 -342.326683)
			(xy 351.538852 -342.250404) (xy 351.511424 -342.171159) (xy 351.491654 -342.089666) (xy 351.479719 -342.006662)
			(xy 351.475729 -341.9229) (xy 107.867795 -341.9229) (xy 107.866258 -341.938099) (xy 107.848353 -342.02583)
			(xy 107.821735 -342.111321) (xy 107.804712 -342.152732) (xy 107.80112 -342.162315) (xy 107.801136 -342.182765)
			(xy 107.804712 -342.192356) (xy 107.821734 -342.233768) (xy 107.848372 -342.319255) (xy 107.86628 -342.406986)
			(xy 107.875278 -342.496074) (xy 107.875832 -342.540844) (xy 107.875405 -342.579435) (xy 107.868704 -342.656327)
			(xy 107.855365 -342.732349) (xy 107.835489 -342.806929) (xy 107.822746 -342.843358) (xy 107.81982 -342.852801)
			(xy 107.820595 -342.872535) (xy 107.82427 -342.881712) (xy 107.843314 -342.925129) (xy 107.873091 -343.015145)
			(xy 107.893121 -343.107819) (xy 107.903177 -343.202097) (xy 107.903772 -343.249504) (xy 107.903199 -343.294273)
			(xy 107.894192 -343.383358) (xy 107.87629 -343.471089) (xy 107.849674 -343.556581) (xy 107.832652 -343.597992)
			(xy 107.829086 -343.607582) (xy 107.829087 -343.628025) (xy 107.832652 -343.637616) (xy 107.849695 -343.67902)
			(xy 107.876327 -343.76451) (xy 107.894229 -343.852244) (xy 107.903221 -343.941333) (xy 107.903772 -343.986104)
			(xy 107.903338 -344.0272) (xy 107.895755 -344.109042) (xy 107.880654 -344.189835) (xy 107.858164 -344.268891)
			(xy 107.828477 -344.345534) (xy 107.791846 -344.419112) (xy 107.748583 -344.488997) (xy 107.699057 -344.554593)
			(xy 107.643692 -344.61534) (xy 107.582958 -344.670721) (xy 107.517374 -344.720262) (xy 107.447499 -344.763541)
			(xy 107.37393 -344.80019) (xy 107.297294 -344.829896) (xy 107.218244 -344.852405) (xy 107.137454 -344.867525)
			(xy 107.055614 -344.875128) (xy 107.014518 -344.875612) (xy 107.01401 -344.875612) (xy 106.971454 -344.875048)
			(xy 106.886731 -344.866913) (xy 106.803172 -344.850725) (xy 106.72154 -344.826633) (xy 106.642582 -344.794856)
			(xy 106.567018 -344.755685) (xy 106.49554 -344.709478) (xy 106.428801 -344.656658) (xy 106.36741 -344.597706)
			(xy 106.311928 -344.533162) (xy 106.262863 -344.463615) (xy 106.220663 -344.389701) (xy 106.202734 -344.351102)
			(xy 106.197143 -344.340314) (xy 106.178175 -344.325188) (xy 106.166412 -344.322146) (xy 106.123815 -344.31302)
			(xy 106.04054 -344.287419) (xy 105.960165 -344.253801) (xy 105.883461 -344.212489) (xy 105.811162 -344.163878)
			(xy 105.74396 -344.108434) (xy 105.682498 -344.046687) (xy 105.627365 -343.979229) (xy 105.579089 -343.906705)
			(xy 105.538133 -343.829811) (xy 105.504888 -343.749281) (xy 105.479672 -343.665888) (xy 105.462727 -343.58043)
			(xy 105.454216 -343.493725) (xy 105.453688 -343.450164) (xy 105.454253 -343.405394) (xy 105.463263 -343.316309)
			(xy 105.481167 -343.228578) (xy 105.507785 -343.143087) (xy 105.524808 -343.101676) (xy 105.528395 -343.092092)
			(xy 105.528382 -343.071643) (xy 105.524808 -343.062052) (xy 105.508891 -343.02338) (xy 105.483531 -342.943684)
			(xy 105.46577 -342.861957) (xy 105.460292 -342.820498) (xy 105.458558 -342.81058) (xy 105.448632 -342.793088)
			(xy 105.43277 -342.780723) (xy 105.423208 -342.777572) (xy 105.40795 -342.773353) (xy 105.377717 -342.763951)
			(xy 105.362756 -342.758776) (xy 105.354559 -342.756262) (xy 105.337425 -342.756262) (xy 105.329228 -342.758776)
			(xy 105.294015 -342.770747) (xy 105.222011 -342.789399) (xy 105.148689 -342.801905) (xy 105.074572 -342.808175)
			(xy 105.037382 -342.80856) (xy 105.000192 -342.808173) (xy 104.926079 -342.801882) (xy 104.85276 -342.789372)
			(xy 104.780754 -342.770731) (xy 104.745536 -342.758776) (xy 104.737339 -342.756262) (xy 104.720205 -342.756262)
			(xy 104.712008 -342.758776) (xy 104.676797 -342.770753) (xy 104.604792 -342.789403) (xy 104.531469 -342.801908)
			(xy 104.457353 -342.808176) (xy 104.420162 -342.80856) (xy 104.378225 -342.808083) (xy 104.294732 -342.800107)
			(xy 104.212375 -342.784231) (xy 104.131899 -342.760598) (xy 104.054035 -342.729423) (xy 103.979486 -342.690988)
			(xy 103.908929 -342.64564) (xy 103.843001 -342.593792) (xy 103.7823 -342.535911) (xy 103.727376 -342.472522)
			(xy 103.678726 -342.4042) (xy 103.63679 -342.331563) (xy 103.601948 -342.255269) (xy 103.574517 -342.176008)
			(xy 103.554743 -342.094498) (xy 103.542807 -342.011479) (xy 103.538816 -341.9277) (xy 2.509012 -341.9277)
			(xy 2.509012 -345.238324) (xy 88.42502 -345.238324) (xy 88.42502 -345.237562) (xy 88.425476 -345.196455)
			(xy 88.433064 -345.114592) (xy 88.448171 -345.033778) (xy 88.470668 -344.954703) (xy 88.500364 -344.87804)
			(xy 88.537005 -344.804443) (xy 88.58028 -344.73454) (xy 88.629818 -344.668927) (xy 88.685198 -344.608163)
			(xy 88.745947 -344.552768) (xy 88.811546 -344.503212) (xy 88.881438 -344.459919) (xy 88.955025 -344.423259)
			(xy 89.031681 -344.393542) (xy 89.110751 -344.371024) (xy 89.19156 -344.355896) (xy 89.273421 -344.348287)
			(xy 89.314528 -344.3478) (xy 89.358923 -344.348358) (xy 89.447268 -344.357247) (xy 89.534288 -344.374894)
			(xy 89.619117 -344.401123) (xy 89.660222 -344.417904) (xy 89.668919 -344.421068) (xy 89.687398 -344.421734)
			(xy 89.69629 -344.419174) (xy 89.742575 -344.404089) (xy 89.837607 -344.382956) (xy 89.934379 -344.372329)
			(xy 89.983056 -344.371676) (xy 90.021372 -344.372058) (xy 90.097725 -344.378586) (xy 90.173232 -344.391667)
			(xy 90.247331 -344.411203) (xy 90.283538 -344.423746) (xy 90.291854 -344.426332) (xy 90.309258 -344.426332)
			(xy 90.317574 -344.423746) (xy 90.353782 -344.41121) (xy 90.427885 -344.391692) (xy 90.503391 -344.378612)
			(xy 90.579741 -344.372068) (xy 90.618056 -344.371676) (xy 90.664451 -344.372276) (xy 90.756739 -344.381916)
			(xy 90.847523 -344.401107) (xy 90.935817 -344.429641) (xy 90.978482 -344.447876) (xy 90.988424 -344.451682)
			(xy 91.009688 -344.451682) (xy 91.01963 -344.447876) (xy 91.062298 -344.429645) (xy 91.150588 -344.401097)
			(xy 91.241371 -344.381901) (xy 91.33366 -344.372263) (xy 91.380056 -344.371676) (xy 91.418372 -344.372058)
			(xy 91.494725 -344.378586) (xy 91.570232 -344.391667) (xy 91.644331 -344.411203) (xy 91.680538 -344.423746)
			(xy 91.688854 -344.426332) (xy 91.706258 -344.426332) (xy 91.714574 -344.423746) (xy 91.750782 -344.41121)
			(xy 91.824885 -344.391692) (xy 91.900391 -344.378612) (xy 91.976741 -344.372068) (xy 92.015056 -344.371676)
			(xy 92.053372 -344.372058) (xy 92.129725 -344.378586) (xy 92.205232 -344.391667) (xy 92.279331 -344.411203)
			(xy 92.315538 -344.423746) (xy 92.323854 -344.426332) (xy 92.341258 -344.426332) (xy 92.349574 -344.423746)
			(xy 92.385691 -344.411238) (xy 92.459606 -344.391753) (xy 92.534918 -344.378674) (xy 92.611074 -344.372097)
			(xy 92.649294 -344.371676) (xy 92.650056 -344.371676) (xy 92.691158 -344.372194) (xy 92.773012 -344.379775)
			(xy 92.853817 -344.394876) (xy 92.932883 -344.417369) (xy 93.009537 -344.447061) (xy 93.083125 -344.4837)
			(xy 93.153018 -344.526972) (xy 93.21862 -344.576508) (xy 93.279371 -344.631887) (xy 93.334753 -344.692634)
			(xy 93.384294 -344.758233) (xy 93.427571 -344.828123) (xy 93.464215 -344.901708) (xy 93.493912 -344.97836)
			(xy 93.51641 -345.057425) (xy 93.531517 -345.138229) (xy 93.539103 -345.220082) (xy 93.539564 -345.261184)
			(xy 93.539564 -345.261692) (xy 93.539139 -345.302203) (xy 93.531771 -345.38289) (xy 93.517086 -345.462571)
			(xy 93.495207 -345.540583) (xy 93.466315 -345.616279) (xy 93.448886 -345.652852) (xy 93.444973 -345.661871)
			(xy 93.443532 -345.68146) (xy 93.446092 -345.690952) (xy 93.460285 -345.736019) (xy 93.480192 -345.828387)
			(xy 93.490186 -345.922345) (xy 93.490796 -345.96959) (xy 93.490238 -346.015229) (xy 93.480936 -346.106032)
			(xy 93.462388 -346.195406) (xy 93.44914 -346.239084) (xy 93.446696 -346.248096) (xy 93.447735 -346.266724)
			(xy 93.451172 -346.275406) (xy 93.469867 -346.318487) (xy 93.49915 -346.407722) (xy 93.518862 -346.499547)
			(xy 93.527728 -346.583) (xy 200.85558 -346.583) (xy 200.856207 -346.536598) (xy 200.865897 -346.444301)
			(xy 200.88515 -346.353515) (xy 200.913758 -346.26523) (xy 200.932034 -346.222574) (xy 200.935843 -346.212632)
			(xy 200.935843 -346.191368) (xy 200.932034 -346.181426) (xy 200.913772 -346.138765) (xy 200.885179 -346.050477)
			(xy 200.865922 -345.959694) (xy 200.856209 -345.867401) (xy 200.85558 -345.821) (xy 200.856064 -345.779859)
			(xy 200.863695 -345.69793) (xy 200.878855 -345.617056) (xy 200.901414 -345.537926) (xy 200.931179 -345.461215)
			(xy 200.967897 -345.38758) (xy 200.989184 -345.35237) (xy 200.993752 -345.344157) (xy 200.997195 -345.3257)
			(xy 200.993752 -345.307243) (xy 200.989184 -345.29903) (xy 200.967885 -345.263826) (xy 200.931155 -345.190194)
			(xy 200.901383 -345.113484) (xy 200.878824 -345.034352) (xy 200.86367 -344.953474) (xy 200.856051 -344.871542)
			(xy 200.85558 -344.8304) (xy 200.856207 -344.783998) (xy 200.865897 -344.691701) (xy 200.88515 -344.600915)
			(xy 200.913758 -344.51263) (xy 200.932034 -344.469974) (xy 200.935843 -344.460032) (xy 200.935843 -344.438768)
			(xy 200.932034 -344.428826) (xy 200.913772 -344.386165) (xy 200.885179 -344.297877) (xy 200.865922 -344.207094)
			(xy 200.856209 -344.114801) (xy 200.85558 -344.0684) (xy 200.856084 -344.026039) (xy 200.864137 -343.941702)
			(xy 200.880171 -343.858512) (xy 200.904039 -343.777222) (xy 200.935527 -343.69857) (xy 200.974349 -343.623267)
			(xy 201.020152 -343.551995) (xy 201.072523 -343.485399) (xy 201.130988 -343.424084) (xy 201.195016 -343.368603)
			(xy 201.264028 -343.31946) (xy 201.337398 -343.2771) (xy 201.414463 -343.241905) (xy 201.494525 -343.214196)
			(xy 201.576858 -343.194222) (xy 201.660717 -343.182165) (xy 201.745342 -343.178134) (xy 201.829967 -343.182165)
			(xy 201.913826 -343.194222) (xy 201.996159 -343.214196) (xy 202.076221 -343.241905) (xy 202.153286 -343.2771)
			(xy 202.226656 -343.31946) (xy 202.295668 -343.368603) (xy 202.359696 -343.424084) (xy 202.418161 -343.485399)
			(xy 202.470532 -343.551995) (xy 202.516335 -343.623267) (xy 202.555157 -343.69857) (xy 202.586645 -343.777222)
			(xy 202.610513 -343.858512) (xy 202.626547 -343.941702) (xy 202.6346 -344.026039) (xy 202.635104 -344.0684)
			(xy 202.634479 -344.114802) (xy 202.624789 -344.2071) (xy 202.605534 -344.297885) (xy 202.576926 -344.38617)
			(xy 202.55865 -344.428826) (xy 202.554842 -344.438768) (xy 202.554842 -344.460032) (xy 202.55865 -344.469974)
			(xy 202.576911 -344.512635) (xy 202.605505 -344.600923) (xy 202.624762 -344.691706) (xy 202.634475 -344.783999)
			(xy 202.635104 -344.8304) (xy 202.634622 -344.871541) (xy 202.626991 -344.95347) (xy 202.611831 -345.034344)
			(xy 202.589272 -345.113474) (xy 202.559506 -345.190185) (xy 202.522787 -345.263821) (xy 202.5015 -345.29903)
			(xy 202.496933 -345.307243) (xy 202.493491 -345.3257) (xy 202.496933 -345.344157) (xy 202.5015 -345.35237)
			(xy 202.522797 -345.387575) (xy 202.559528 -345.461207) (xy 202.5893 -345.537917) (xy 202.61186 -345.617049)
			(xy 202.627014 -345.697926) (xy 202.634633 -345.779858) (xy 202.635104 -345.821) (xy 202.634479 -345.867402)
			(xy 202.624789 -345.9597) (xy 202.605534 -346.050485) (xy 202.576926 -346.13877) (xy 202.55865 -346.181426)
			(xy 202.554842 -346.191368) (xy 202.554842 -346.212632) (xy 202.55865 -346.222574) (xy 202.576911 -346.265235)
			(xy 202.605505 -346.353523) (xy 202.624762 -346.444306) (xy 202.634475 -346.536599) (xy 202.635104 -346.583)
			(xy 202.6346 -346.625361) (xy 202.626547 -346.709698) (xy 202.610513 -346.792888) (xy 202.586645 -346.874178)
			(xy 202.555157 -346.95283) (xy 202.516335 -347.028133) (xy 202.470532 -347.099405) (xy 202.418161 -347.166001)
			(xy 202.359696 -347.227316) (xy 202.295668 -347.282797) (xy 202.226656 -347.33194) (xy 202.153286 -347.3743)
			(xy 202.076221 -347.409495) (xy 201.996159 -347.437204) (xy 201.913826 -347.457178) (xy 201.829967 -347.469235)
			(xy 201.745342 -347.473267) (xy 201.660717 -347.469235) (xy 201.576858 -347.457178) (xy 201.494525 -347.437204)
			(xy 201.414463 -347.409495) (xy 201.337398 -347.3743) (xy 201.264028 -347.33194) (xy 201.195016 -347.282797)
			(xy 201.130988 -347.227316) (xy 201.072523 -347.166001) (xy 201.020152 -347.099405) (xy 200.974349 -347.028133)
			(xy 200.935527 -346.95283) (xy 200.904039 -346.874178) (xy 200.880171 -346.792888) (xy 200.864137 -346.709698)
			(xy 200.856084 -346.625361) (xy 200.85558 -346.583) (xy 93.527728 -346.583) (xy 93.528784 -346.592938)
			(xy 93.529404 -346.639896) (xy 93.528944 -346.681007) (xy 93.521356 -346.762877) (xy 93.506246 -346.843698)
			(xy 93.483741 -346.92278) (xy 93.454034 -346.999447) (xy 93.417379 -347.073045) (xy 93.374088 -347.142947)
			(xy 93.324531 -347.208555) (xy 93.269131 -347.26931) (xy 93.20836 -347.324693) (xy 93.142737 -347.374232)
			(xy 93.072823 -347.417503) (xy 92.999214 -347.454137) (xy 92.922539 -347.483822) (xy 92.843451 -347.506304)
			(xy 92.762626 -347.521391) (xy 92.680753 -347.528955) (xy 92.639642 -347.529404) (xy 92.601326 -347.529024)
			(xy 92.524973 -347.522495) (xy 92.449466 -347.509414) (xy 92.375367 -347.489878) (xy 92.33916 -347.477334)
			(xy 92.330844 -347.474748) (xy 92.31344 -347.474748) (xy 92.305124 -347.477334) (xy 92.268906 -347.489842)
			(xy 92.194807 -347.509368) (xy 92.119304 -347.522455) (xy 92.042956 -347.529008) (xy 92.004642 -347.529404)
			(xy 91.961529 -347.52892) (xy 91.875703 -347.520642) (xy 91.791081 -347.504091) (xy 91.70846 -347.479423)
			(xy 91.668346 -347.463618) (xy 91.658977 -347.460281) (xy 91.639107 -347.460281) (xy 91.629738 -347.463618)
			(xy 91.589623 -347.479419) (xy 91.506999 -347.504075) (xy 91.422379 -347.520627) (xy 91.336554 -347.528919)
			(xy 91.293442 -347.529404) (xy 91.255126 -347.529024) (xy 91.178773 -347.522495) (xy 91.103266 -347.509414)
			(xy 91.029167 -347.489878) (xy 90.99296 -347.477334) (xy 90.984644 -347.474748) (xy 90.96724 -347.474748)
			(xy 90.958924 -347.477334) (xy 90.922706 -347.489842) (xy 90.848607 -347.509368) (xy 90.773104 -347.522455)
			(xy 90.696756 -347.529008) (xy 90.658442 -347.529404) (xy 90.620126 -347.529024) (xy 90.543773 -347.522495)
			(xy 90.468266 -347.509414) (xy 90.394167 -347.489878) (xy 90.35796 -347.477334) (xy 90.349644 -347.474748)
			(xy 90.33224 -347.474748) (xy 90.323924 -347.477334) (xy 90.287706 -347.489842) (xy 90.213607 -347.509368)
			(xy 90.138104 -347.522455) (xy 90.061756 -347.529008) (xy 90.023442 -347.529404) (xy 89.985126 -347.529024)
			(xy 89.908773 -347.522495) (xy 89.833266 -347.509414) (xy 89.759167 -347.489878) (xy 89.72296 -347.477334)
			(xy 89.714644 -347.474748) (xy 89.69724 -347.474748) (xy 89.688924 -347.477334) (xy 89.652807 -347.489842)
			(xy 89.578892 -347.509327) (xy 89.50358 -347.522407) (xy 89.427424 -347.528983) (xy 89.389204 -347.529404)
			(xy 89.388442 -347.529404) (xy 89.347337 -347.528847) (xy 89.265478 -347.521267) (xy 89.184667 -347.506168)
			(xy 89.105593 -347.483678) (xy 89.028932 -347.453989) (xy 88.955336 -347.417355) (xy 88.885433 -347.374087)
			(xy 88.81982 -347.324556) (xy 88.759057 -347.269183) (xy 88.70366 -347.20844) (xy 88.654104 -347.142846)
			(xy 88.61081 -347.07296) (xy 88.574148 -346.999378) (xy 88.54443 -346.922728) (xy 88.52191 -346.843663)
			(xy 88.506779 -346.762857) (xy 88.499168 -346.681001) (xy 88.49868 -346.639896) (xy 88.49928 -346.594251)
			(xy 88.508675 -346.503445) (xy 88.527305 -346.414075) (xy 88.54059 -346.370402) (xy 88.543039 -346.361391)
			(xy 88.541996 -346.342762) (xy 88.538558 -346.33408) (xy 88.519895 -346.290993) (xy 88.490688 -346.201748)
			(xy 88.471043 -346.109924) (xy 88.461176 -346.016541) (xy 88.46058 -345.96959) (xy 88.460997 -345.930463)
			(xy 88.467845 -345.852508) (xy 88.481506 -345.775455) (xy 88.501874 -345.699897) (xy 88.514936 -345.663012)
			(xy 88.517951 -345.653293) (xy 88.516917 -345.632991) (xy 88.512904 -345.623642) (xy 88.496039 -345.587523)
			(xy 88.46806 -345.512874) (xy 88.44687 -345.436021) (xy 88.432638 -345.357582) (xy 88.425479 -345.278184)
			(xy 88.42502 -345.238324) (xy 2.509012 -345.238324) (xy 2.509012 -348.70949) (xy 28.410141 -348.70949)
			(xy 28.414132 -348.625708) (xy 28.426069 -348.542686) (xy 28.445844 -348.461173) (xy 28.473277 -348.38191)
			(xy 28.508121 -348.305613) (xy 28.550059 -348.232974) (xy 28.598712 -348.16465) (xy 28.65364 -348.101261)
			(xy 28.714345 -348.043379) (xy 28.780276 -347.99153) (xy 28.850838 -347.946183) (xy 28.92539 -347.907749)
			(xy 29.003259 -347.876576) (xy 29.083738 -347.852945) (xy 29.166099 -347.837072) (xy 29.249596 -347.829099)
			(xy 29.291534 -347.828616) (xy 29.328723 -347.829023) (xy 29.402836 -347.835307) (xy 29.476156 -347.847812)
			(xy 29.548162 -347.866448) (xy 29.58338 -347.8784) (xy 29.591577 -347.880914) (xy 29.608711 -347.880914)
			(xy 29.616908 -347.8784) (xy 29.652035 -347.866473) (xy 29.723849 -347.847849) (xy 29.796976 -347.835339)
			(xy 29.870898 -347.829031) (xy 29.907992 -347.828616) (xy 29.909516 -347.828616) (xy 29.916374 -347.82887)
			(xy 29.922431 -347.792721) (xy 29.939716 -347.721486) (xy 29.962803 -347.651915) (xy 29.976826 -347.61805)
			(xy 29.980289 -347.608427) (xy 29.980173 -347.587996) (xy 29.976572 -347.578426) (xy 29.959544 -347.537016)
			(xy 29.932908 -347.451529) (xy 29.915001 -347.363797) (xy 29.906005 -347.274709) (xy 29.905452 -347.229938)
			(xy 29.905933 -347.189355) (xy 29.913331 -347.108527) (xy 29.928059 -347.028709) (xy 29.949995 -346.950564)
			(xy 29.978957 -346.874741) (xy 30.014703 -346.801871) (xy 30.056938 -346.732559) (xy 30.10531 -346.667382)
			(xy 30.159416 -346.606881) (xy 30.218807 -346.551559) (xy 30.28299 -346.501876) (xy 30.351431 -346.458245)
			(xy 30.38729 -346.439236) (xy 30.395816 -346.434265) (xy 30.408633 -346.419285) (xy 30.414885 -346.400588)
			(xy 30.414722 -346.390722) (xy 30.41396 -346.365322) (xy 30.414481 -346.337437) (xy 30.422793 -346.28229)
			(xy 30.439231 -346.228998) (xy 30.463429 -346.178752) (xy 30.494845 -346.132673) (xy 30.532778 -346.091791)
			(xy 30.57638 -346.057019) (xy 30.624678 -346.029134) (xy 30.676593 -346.008759) (xy 30.730964 -345.996349)
			(xy 30.786578 -345.992182) (xy 30.842192 -345.996349) (xy 30.896563 -346.008759) (xy 30.948478 -346.029134)
			(xy 30.996776 -346.057019) (xy 31.040378 -346.091791) (xy 31.078311 -346.132673) (xy 31.109727 -346.178752)
			(xy 31.133925 -346.228998) (xy 31.150363 -346.28229) (xy 31.158675 -346.337437) (xy 31.159196 -346.365322)
			(xy 31.158688 -346.383356) (xy 31.15866 -346.393249) (xy 31.165282 -346.411875) (xy 31.178455 -346.426614)
			(xy 31.187136 -346.431362) (xy 31.224041 -346.449965) (xy 31.294555 -346.49308) (xy 31.360766 -346.542551)
			(xy 31.4221 -346.597952) (xy 31.47803 -346.658805) (xy 31.528073 -346.724585) (xy 31.571797 -346.794724)
			(xy 31.608825 -346.868616) (xy 31.638837 -346.945626) (xy 31.661575 -347.025088) (xy 31.676842 -347.106317)
			(xy 31.684507 -347.188612) (xy 31.684976 -347.229938) (xy 31.684414 -347.274708) (xy 31.675404 -347.363793)
			(xy 31.657499 -347.451524) (xy 31.630879 -347.537015) (xy 31.613856 -347.578426) (xy 31.61027 -347.58801)
			(xy 31.610284 -347.608459) (xy 31.613856 -347.61805) (xy 31.630031 -347.657368) (xy 31.655701 -347.738424)
			(xy 31.673532 -347.821557) (xy 31.68336 -347.906011) (xy 31.684722 -347.948504) (xy 31.684976 -347.96222)
			(xy 31.6992 -347.985588) (xy 31.788862 -348.034102) (xy 31.796927 -348.038113) (xy 31.814734 -348.040741)
			(xy 31.832352 -348.037052) (xy 31.84017 -348.032578) (xy 31.875522 -348.010993) (xy 31.949529 -347.973778)
			(xy 32.026677 -347.943609) (xy 32.106297 -347.920748) (xy 32.187699 -347.905393) (xy 32.270176 -347.897677)
			(xy 32.311594 -347.897196) (xy 32.352707 -347.897719) (xy 32.434582 -347.905305) (xy 32.515408 -347.920413)
			(xy 32.594495 -347.942914) (xy 32.671169 -347.972616) (xy 32.744775 -348.009266) (xy 32.814686 -348.05255)
			(xy 32.880304 -348.102101) (xy 32.941071 -348.157495) (xy 32.996468 -348.218259) (xy 33.046022 -348.283875)
			(xy 33.089311 -348.353783) (xy 33.125965 -348.427387) (xy 33.155671 -348.504059) (xy 33.178176 -348.583145)
			(xy 33.193289 -348.66397) (xy 33.197509 -348.70949) (xy 36.690541 -348.70949) (xy 36.694532 -348.625708)
			(xy 36.706469 -348.542686) (xy 36.726244 -348.461173) (xy 36.753677 -348.38191) (xy 36.788521 -348.305613)
			(xy 36.830459 -348.232974) (xy 36.879112 -348.16465) (xy 36.93404 -348.101261) (xy 36.994745 -348.043379)
			(xy 37.060676 -347.99153) (xy 37.131238 -347.946183) (xy 37.20579 -347.907749) (xy 37.283659 -347.876576)
			(xy 37.364138 -347.852945) (xy 37.446499 -347.837072) (xy 37.529996 -347.829099) (xy 37.571934 -347.828616)
			(xy 37.609123 -347.829023) (xy 37.683236 -347.835307) (xy 37.756556 -347.847812) (xy 37.828562 -347.866448)
			(xy 37.86378 -347.8784) (xy 37.871977 -347.880914) (xy 37.889111 -347.880914) (xy 37.897308 -347.8784)
			(xy 37.93549 -347.865472) (xy 38.013674 -347.845816) (xy 38.093328 -347.833391) (xy 38.133528 -347.830394)
			(xy 38.144516 -347.829167) (xy 38.163935 -347.818636) (xy 38.177169 -347.800949) (xy 38.18001 -347.790262)
			(xy 38.189419 -347.748079) (xy 38.215379 -347.665637) (xy 38.231826 -347.62567) (xy 38.235335 -347.61606)
			(xy 38.235189 -347.595617) (xy 38.231572 -347.586046) (xy 38.21455 -347.544634) (xy 38.187912 -347.459147)
			(xy 38.170004 -347.371416) (xy 38.161006 -347.282328) (xy 38.160452 -347.237558) (xy 38.160956 -347.195197)
			(xy 38.169009 -347.11086) (xy 38.185043 -347.02767) (xy 38.208911 -346.94638) (xy 38.240399 -346.867728)
			(xy 38.279221 -346.792425) (xy 38.325024 -346.721153) (xy 38.377395 -346.654557) (xy 38.43586 -346.593242)
			(xy 38.499888 -346.537761) (xy 38.5689 -346.488618) (xy 38.64227 -346.446258) (xy 38.719335 -346.411063)
			(xy 38.799397 -346.383354) (xy 38.88173 -346.36338) (xy 38.965589 -346.351323) (xy 39.050214 -346.347292)
			(xy 39.134839 -346.351323) (xy 39.218698 -346.36338) (xy 39.301031 -346.383354) (xy 39.381093 -346.411063)
			(xy 39.458158 -346.446258) (xy 39.531528 -346.488618) (xy 39.60054 -346.537761) (xy 39.664568 -346.593242)
			(xy 39.723033 -346.654557) (xy 39.775404 -346.721153) (xy 39.821207 -346.792425) (xy 39.860029 -346.867728)
			(xy 39.891517 -346.94638) (xy 39.915385 -347.02767) (xy 39.931419 -347.11086) (xy 39.939472 -347.195197)
			(xy 39.939976 -347.237558) (xy 39.939421 -347.282328) (xy 39.930409 -347.371413) (xy 39.912502 -347.459144)
			(xy 39.88588 -347.544635) (xy 39.868856 -347.586046) (xy 39.865251 -347.595621) (xy 39.865104 -347.616057)
			(xy 39.868602 -347.62567) (xy 39.88516 -347.665899) (xy 39.911278 -347.748887) (xy 39.929176 -347.834027)
			(xy 39.938683 -347.920507) (xy 39.939722 -347.963998) (xy 39.939722 -347.964252) (xy 39.94031 -347.973302)
			(xy 39.94696 -347.990157) (xy 39.959055 -348.003648) (xy 39.9669 -348.008194) (xy 40.058086 -348.056454)
			(xy 40.086026 -348.05493) (xy 40.09771 -348.04731) (xy 40.134305 -348.023444) (xy 40.211348 -347.98223)
			(xy 40.292061 -347.948768) (xy 40.375665 -347.923381) (xy 40.461356 -347.906311) (xy 40.548307 -347.897725)
			(xy 40.591994 -347.897196) (xy 40.633107 -347.897719) (xy 40.714982 -347.905305) (xy 40.795808 -347.920413)
			(xy 40.874895 -347.942914) (xy 40.951569 -347.972616) (xy 41.025175 -348.009266) (xy 41.095086 -348.05255)
			(xy 41.160704 -348.102101) (xy 41.221471 -348.157495) (xy 41.276868 -348.218259) (xy 41.326422 -348.283875)
			(xy 41.369711 -348.353783) (xy 41.406365 -348.427387) (xy 41.436071 -348.504059) (xy 41.458576 -348.583145)
			(xy 41.473689 -348.66397) (xy 41.47791 -348.7095) (xy 44.996301 -348.7095) (xy 45.000292 -348.625716)
			(xy 45.01223 -348.54269) (xy 45.032006 -348.461175) (xy 45.05944 -348.381909) (xy 45.094286 -348.30561)
			(xy 45.136227 -348.232969) (xy 45.184883 -348.164644) (xy 45.239813 -348.101253) (xy 45.30052 -348.043371)
			(xy 45.366455 -347.991522) (xy 45.43702 -347.946175) (xy 45.511576 -347.907741) (xy 45.589448 -347.876568)
			(xy 45.66993 -347.852939) (xy 45.752294 -347.837068) (xy 45.835794 -347.829098) (xy 45.877734 -347.828616)
			(xy 45.914923 -347.829023) (xy 45.989036 -347.835307) (xy 46.062356 -347.847812) (xy 46.134362 -347.866448)
			(xy 46.16958 -347.8784) (xy 46.177777 -347.880914) (xy 46.194911 -347.880914) (xy 46.203108 -347.8784)
			(xy 46.238327 -347.866445) (xy 46.310329 -347.847789) (xy 46.383649 -347.835279) (xy 46.457764 -347.829003)
			(xy 46.494954 -347.828616) (xy 46.496732 -347.82887) (xy 46.506097 -347.78788) (xy 46.53154 -347.707736)
			(xy 46.547532 -347.66885) (xy 46.551076 -347.659253) (xy 46.55109 -347.638816) (xy 46.547532 -347.629226)
			(xy 46.530501 -347.587817) (xy 46.503866 -347.502329) (xy 46.485961 -347.414597) (xy 46.476965 -347.325509)
			(xy 46.476412 -347.280738) (xy 46.476916 -347.238377) (xy 46.484969 -347.15404) (xy 46.501003 -347.07085)
			(xy 46.524871 -346.98956) (xy 46.556359 -346.910908) (xy 46.595181 -346.835605) (xy 46.640984 -346.764333)
			(xy 46.693355 -346.697737) (xy 46.75182 -346.636422) (xy 46.815848 -346.580941) (xy 46.88486 -346.531798)
			(xy 46.95823 -346.489438) (xy 47.035295 -346.454243) (xy 47.115357 -346.426534) (xy 47.19769 -346.40656)
			(xy 47.281549 -346.394503) (xy 47.366174 -346.390472) (xy 47.450799 -346.394503) (xy 47.534658 -346.40656)
			(xy 47.616991 -346.426534) (xy 47.697053 -346.454243) (xy 47.774118 -346.489438) (xy 47.847488 -346.531798)
			(xy 47.9165 -346.580941) (xy 47.980528 -346.636422) (xy 48.038993 -346.697737) (xy 48.091364 -346.764333)
			(xy 48.137167 -346.835605) (xy 48.175989 -346.910908) (xy 48.207477 -346.98956) (xy 48.231345 -347.07085)
			(xy 48.247379 -347.15404) (xy 48.255432 -347.238377) (xy 48.255936 -347.280738) (xy 48.25537 -347.325508)
			(xy 48.24636 -347.414592) (xy 48.228456 -347.502324) (xy 48.201838 -347.587815) (xy 48.184816 -347.629226)
			(xy 48.181232 -347.638811) (xy 48.181246 -347.659259) (xy 48.184816 -347.66885) (xy 48.199304 -347.703977)
			(xy 48.222973 -347.776187) (xy 48.2404 -347.850153) (xy 48.251457 -347.925335) (xy 48.254158 -347.963236)
			(xy 48.255104 -347.972078) (xy 48.26215 -347.988388) (xy 48.274337 -348.001315) (xy 48.282098 -348.005654)
			(xy 48.37303 -348.051374) (xy 48.3997 -348.04985) (xy 48.41113 -348.04223) (xy 48.447343 -348.019182)
			(xy 48.523387 -347.979349) (xy 48.602912 -347.947022) (xy 48.685181 -347.922504) (xy 48.769429 -347.90602)
			(xy 48.854872 -347.897725) (xy 48.897794 -347.897196) (xy 48.938907 -347.897719) (xy 49.020782 -347.905305)
			(xy 49.101608 -347.920413) (xy 49.180695 -347.942914) (xy 49.257369 -347.972616) (xy 49.330975 -348.009266)
			(xy 49.400886 -348.05255) (xy 49.466504 -348.102101) (xy 49.527271 -348.157495) (xy 49.582668 -348.218259)
			(xy 49.632222 -348.283875) (xy 49.675511 -348.353783) (xy 49.712165 -348.427387) (xy 49.741871 -348.504059)
			(xy 49.764376 -348.583145) (xy 49.779489 -348.66397) (xy 49.78371 -348.7095) (xy 53.352901 -348.7095)
			(xy 53.356892 -348.625716) (xy 53.36883 -348.54269) (xy 53.388606 -348.461175) (xy 53.41604 -348.381909)
			(xy 53.450886 -348.30561) (xy 53.492827 -348.232969) (xy 53.541483 -348.164644) (xy 53.596413 -348.101253)
			(xy 53.65712 -348.043371) (xy 53.723055 -347.991522) (xy 53.79362 -347.946175) (xy 53.868176 -347.907741)
			(xy 53.946048 -347.876568) (xy 54.02653 -347.852939) (xy 54.108894 -347.837068) (xy 54.192394 -347.829098)
			(xy 54.234334 -347.828616) (xy 54.271523 -347.829023) (xy 54.345636 -347.835307) (xy 54.418956 -347.847812)
			(xy 54.490962 -347.866448) (xy 54.52618 -347.8784) (xy 54.534377 -347.880914) (xy 54.551511 -347.880914)
			(xy 54.559708 -347.8784) (xy 54.594654 -347.86653) (xy 54.66609 -347.847969) (xy 54.738831 -347.835458)
			(xy 54.812365 -347.829087) (xy 54.849268 -347.828616) (xy 54.85384 -347.82887) (xy 54.854348 -347.82887)
			(xy 54.863907 -347.782599) (xy 54.89152 -347.692237) (xy 54.909466 -347.64853) (xy 54.912939 -347.63891)
			(xy 54.912815 -347.618477) (xy 54.909212 -347.608906) (xy 54.892173 -347.5675) (xy 54.865541 -347.482011)
			(xy 54.847637 -347.394278) (xy 54.838644 -347.305189) (xy 54.838092 -347.260418) (xy 54.838596 -347.218057)
			(xy 54.846649 -347.13372) (xy 54.862683 -347.05053) (xy 54.886551 -346.96924) (xy 54.918039 -346.890588)
			(xy 54.956861 -346.815285) (xy 55.002664 -346.744013) (xy 55.055035 -346.677417) (xy 55.1135 -346.616102)
			(xy 55.177528 -346.560621) (xy 55.24654 -346.511478) (xy 55.31991 -346.469118) (xy 55.396975 -346.433923)
			(xy 55.477037 -346.406214) (xy 55.55937 -346.38624) (xy 55.643229 -346.374183) (xy 55.727854 -346.370152)
			(xy 55.812479 -346.374183) (xy 55.896338 -346.38624) (xy 55.978671 -346.406214) (xy 56.058733 -346.433923)
			(xy 56.135798 -346.469118) (xy 56.209168 -346.511478) (xy 56.27818 -346.560621) (xy 56.342208 -346.616102)
			(xy 56.400673 -346.677417) (xy 56.453044 -346.744013) (xy 56.498847 -346.815285) (xy 56.537669 -346.890588)
			(xy 56.569157 -346.96924) (xy 56.593025 -347.05053) (xy 56.609059 -347.13372) (xy 56.617112 -347.218057)
			(xy 56.617616 -347.260418) (xy 56.617044 -347.305187) (xy 56.608037 -347.394272) (xy 56.590134 -347.482003)
			(xy 56.563518 -347.567495) (xy 56.546496 -347.608906) (xy 56.542919 -347.618493) (xy 56.542926 -347.63894)
			(xy 56.546496 -347.64853) (xy 56.561684 -347.685398) (xy 56.586189 -347.761282) (xy 56.603812 -347.839053)
			(xy 56.614411 -347.918088) (xy 56.6166 -347.957902) (xy 56.617108 -347.971364) (xy 56.63184 -347.994224)
			(xy 56.734456 -348.047564) (xy 56.761634 -348.04604) (xy 56.773064 -348.038674) (xy 56.808981 -348.016152)
			(xy 56.88432 -347.977266) (xy 56.963017 -347.945725) (xy 57.044358 -347.921816) (xy 57.127605 -347.905754)
			(xy 57.212003 -347.897686) (xy 57.254394 -347.897196) (xy 57.295507 -347.897719) (xy 57.377382 -347.905305)
			(xy 57.458208 -347.920413) (xy 57.537295 -347.942914) (xy 57.613969 -347.972616) (xy 57.687575 -348.009266)
			(xy 57.757486 -348.05255) (xy 57.823104 -348.102101) (xy 57.883871 -348.157495) (xy 57.939268 -348.218259)
			(xy 57.988822 -348.283875) (xy 58.032111 -348.353783) (xy 58.068765 -348.427387) (xy 58.098471 -348.504059)
			(xy 58.120976 -348.583145) (xy 58.136089 -348.66397) (xy 58.14031 -348.7095) (xy 61.684101 -348.7095)
			(xy 61.688092 -348.625716) (xy 61.70003 -348.54269) (xy 61.719806 -348.461175) (xy 61.74724 -348.381909)
			(xy 61.782086 -348.30561) (xy 61.824027 -348.232969) (xy 61.872683 -348.164644) (xy 61.927613 -348.101253)
			(xy 61.98832 -348.043371) (xy 62.054255 -347.991522) (xy 62.12482 -347.946175) (xy 62.199376 -347.907741)
			(xy 62.277248 -347.876568) (xy 62.35773 -347.852939) (xy 62.440094 -347.837068) (xy 62.523594 -347.829098)
			(xy 62.565534 -347.828616) (xy 62.602723 -347.829023) (xy 62.676836 -347.835307) (xy 62.750156 -347.847812)
			(xy 62.822162 -347.866448) (xy 62.85738 -347.8784) (xy 62.865577 -347.880914) (xy 62.882711 -347.880914)
			(xy 62.890908 -347.8784) (xy 62.926096 -347.866455) (xy 62.998036 -347.847809) (xy 63.071292 -347.835299)
			(xy 63.145342 -347.829013) (xy 63.1825 -347.828616) (xy 63.183008 -347.828616) (xy 63.206122 -347.829124)
			(xy 63.215205 -347.793715) (xy 63.238479 -347.724411) (xy 63.252604 -347.690694) (xy 63.256229 -347.680981)
			(xy 63.25624 -347.66027) (xy 63.252604 -347.650562) (xy 63.235485 -347.609307) (xy 63.208697 -347.524095)
			(xy 63.190664 -347.436611) (xy 63.181571 -347.347751) (xy 63.180976 -347.30309) (xy 63.180976 -347.302328)
			(xy 63.181475 -347.260403) (xy 63.189445 -347.176932) (xy 63.205314 -347.094597) (xy 63.228937 -347.014143)
			(xy 63.260101 -346.936299) (xy 63.298524 -346.861769) (xy 63.343857 -346.79123) (xy 63.39569 -346.725319)
			(xy 63.453553 -346.664633) (xy 63.516923 -346.609723) (xy 63.585226 -346.561085) (xy 63.657843 -346.51916)
			(xy 63.734116 -346.484327) (xy 63.813355 -346.456902) (xy 63.894841 -346.437133) (xy 63.977838 -346.4252)
			(xy 64.061594 -346.421211) (xy 64.14535 -346.4252) (xy 64.228347 -346.437133) (xy 64.309833 -346.456902)
			(xy 64.389072 -346.484327) (xy 64.465345 -346.51916) (xy 64.537962 -346.561085) (xy 64.606265 -346.609723)
			(xy 64.669635 -346.664633) (xy 64.727498 -346.725319) (xy 64.779331 -346.79123) (xy 64.824664 -346.861769)
			(xy 64.863087 -346.936299) (xy 64.894251 -347.014143) (xy 64.917874 -347.094597) (xy 64.933743 -347.176932)
			(xy 64.941713 -347.260403) (xy 64.942212 -347.302328) (xy 64.942212 -347.30309) (xy 64.941639 -347.347753)
			(xy 64.932567 -347.436619) (xy 64.914535 -347.524107) (xy 64.88773 -347.609317) (xy 64.870584 -347.650562)
			(xy 64.866927 -347.660266) (xy 64.866937 -347.680985) (xy 64.870584 -347.690694) (xy 64.888862 -347.734789)
			(xy 64.91689 -347.826038) (xy 64.934892 -347.919782) (xy 64.939418 -347.9673) (xy 64.940434 -347.980508)
			(xy 64.955674 -348.00286) (xy 65.046352 -348.047056) (xy 65.054393 -348.050544) (xy 65.071798 -348.052482)
			(xy 65.088843 -348.048463) (xy 65.09639 -348.044008) (xy 65.096644 -348.043754) (xy 65.132959 -348.020439)
			(xy 65.209305 -347.980191) (xy 65.289189 -347.947525) (xy 65.371861 -347.922748) (xy 65.456544 -347.906093)
			(xy 65.542442 -347.897716) (xy 65.585594 -347.897196) (xy 65.626707 -347.897719) (xy 65.708582 -347.905305)
			(xy 65.789408 -347.920413) (xy 65.868495 -347.942914) (xy 65.945169 -347.972616) (xy 66.018775 -348.009266)
			(xy 66.088686 -348.05255) (xy 66.154304 -348.102101) (xy 66.215071 -348.157495) (xy 66.270468 -348.218259)
			(xy 66.320022 -348.283875) (xy 66.363311 -348.353783) (xy 66.399965 -348.427387) (xy 66.429671 -348.504059)
			(xy 66.452176 -348.583145) (xy 66.467289 -348.66397) (xy 66.474879 -348.745845) (xy 66.475356 -348.786958)
			(xy 66.474795 -348.831728) (xy 66.467942 -348.89948) (xy 81.294224 -348.89948) (xy 81.294687 -348.858913)
			(xy 81.30208 -348.778118) (xy 81.316804 -348.698332) (xy 81.338734 -348.620219) (xy 81.36769 -348.544429)
			(xy 81.385156 -348.507812) (xy 81.389058 -348.498717) (xy 81.390365 -348.478988) (xy 81.387696 -348.469458)
			(xy 81.373498 -348.424437) (xy 81.353605 -348.332151) (xy 81.343609 -348.238277) (xy 81.342992 -348.191074)
			(xy 81.343496 -348.148713) (xy 81.351549 -348.064376) (xy 81.367583 -347.981186) (xy 81.391451 -347.899896)
			(xy 81.422939 -347.821244) (xy 81.461761 -347.745941) (xy 81.507564 -347.674669) (xy 81.559935 -347.608073)
			(xy 81.6184 -347.546758) (xy 81.682428 -347.491277) (xy 81.75144 -347.442134) (xy 81.82481 -347.399774)
			(xy 81.901875 -347.364579) (xy 81.981937 -347.33687) (xy 82.06427 -347.316896) (xy 82.148129 -347.304839)
			(xy 82.232754 -347.300808) (xy 82.317379 -347.304839) (xy 82.401238 -347.316896) (xy 82.483571 -347.33687)
			(xy 82.563633 -347.364579) (xy 82.640698 -347.399774) (xy 82.714068 -347.442134) (xy 82.78308 -347.491277)
			(xy 82.847108 -347.546758) (xy 82.905573 -347.608073) (xy 82.957944 -347.674669) (xy 83.003747 -347.745941)
			(xy 83.042569 -347.821244) (xy 83.074057 -347.899896) (xy 83.097925 -347.981186) (xy 83.113959 -348.064376)
			(xy 83.122012 -348.148713) (xy 83.122516 -348.191074) (xy 83.12207 -348.231641) (xy 83.114672 -348.312437)
			(xy 83.099945 -348.392223) (xy 83.07801 -348.470336) (xy 83.049051 -348.546125) (xy 83.031584 -348.582742)
			(xy 83.027707 -348.591846) (xy 83.026383 -348.611567) (xy 83.029044 -348.621096) (xy 83.043232 -348.66612)
			(xy 83.063129 -348.758404) (xy 83.073129 -348.852278) (xy 83.073245 -348.861126) (xy 83.956144 -348.861126)
			(xy 83.956552 -348.820564) (xy 83.963891 -348.739773) (xy 83.978566 -348.659987) (xy 84.000454 -348.581872)
			(xy 84.029373 -348.506078) (xy 84.046822 -348.469458) (xy 84.05073 -348.460437) (xy 84.052174 -348.440849)
			(xy 84.049616 -348.431358) (xy 84.035467 -348.386455) (xy 84.015597 -348.294425) (xy 84.005567 -348.200811)
			(xy 84.004912 -348.153736) (xy 84.004912 -348.15272) (xy 84.005416 -348.110372) (xy 84.013467 -348.026058)
			(xy 84.029496 -347.942892) (xy 84.053357 -347.861625) (xy 84.084836 -347.782995) (xy 84.123647 -347.707714)
			(xy 84.169437 -347.636462) (xy 84.221793 -347.569886) (xy 84.280241 -347.508588) (xy 84.344251 -347.453123)
			(xy 84.413243 -347.403994) (xy 84.486593 -347.361645) (xy 84.563636 -347.326461) (xy 84.643675 -347.298759)
			(xy 84.725984 -347.278791) (xy 84.809819 -347.266738) (xy 84.89442 -347.262708) (xy 84.979021 -347.266738)
			(xy 85.062856 -347.278791) (xy 85.145165 -347.298759) (xy 85.225204 -347.326461) (xy 85.302247 -347.361645)
			(xy 85.375597 -347.403994) (xy 85.444589 -347.453123) (xy 85.508599 -347.508588) (xy 85.567047 -347.569886)
			(xy 85.619403 -347.636462) (xy 85.665193 -347.707714) (xy 85.704004 -347.782995) (xy 85.735483 -347.861625)
			(xy 85.759344 -347.942892) (xy 85.775373 -348.026058) (xy 85.783424 -348.110372) (xy 85.783928 -348.15272)
			(xy 85.783928 -348.153228) (xy 85.783471 -348.193738) (xy 85.77611 -348.274424) (xy 85.761432 -348.354104)
			(xy 85.73956 -348.432117) (xy 85.710675 -348.507814) (xy 85.69325 -348.544388) (xy 85.689318 -348.553401)
			(xy 85.687887 -348.572996) (xy 85.690456 -348.582488) (xy 85.70466 -348.627551) (xy 85.721282 -348.7047)
			(xy 275.231844 -348.7047) (xy 275.235834 -348.620942) (xy 275.247768 -348.537942) (xy 275.267537 -348.456452)
			(xy 275.294962 -348.377211) (xy 275.329796 -348.300935) (xy 275.371722 -348.228316) (xy 275.420361 -348.16001)
			(xy 275.475273 -348.096638) (xy 275.53596 -348.038772) (xy 275.601873 -347.986937) (xy 275.672414 -347.941602)
			(xy 275.746946 -347.903177) (xy 275.824792 -347.872011) (xy 275.905248 -347.848386) (xy 275.987586 -347.832515)
			(xy 276.071059 -347.824543) (xy 276.112986 -347.824044) (xy 276.114002 -347.824044) (xy 276.151059 -347.824452)
			(xy 276.224908 -347.830716) (xy 276.29797 -347.843157) (xy 276.36973 -347.861689) (xy 276.404832 -347.873574)
			(xy 276.413029 -347.876088) (xy 276.430163 -347.876088) (xy 276.43836 -347.873574) (xy 276.478966 -347.8599)
			(xy 276.562216 -347.839604) (xy 276.647042 -347.827484) (xy 276.68982 -347.82506) (xy 276.700434 -347.823969)
			(xy 276.719453 -347.814348) (xy 276.732947 -347.797851) (xy 276.736302 -347.787722) (xy 276.744404 -347.759433)
			(xy 276.763852 -347.703889) (xy 276.775164 -347.676724) (xy 276.778721 -347.667131) (xy 276.778725 -347.646691)
			(xy 276.775164 -347.6371) (xy 276.758127 -347.595694) (xy 276.731493 -347.510205) (xy 276.713589 -347.422472)
			(xy 276.704596 -347.333383) (xy 276.704044 -347.288612) (xy 276.704548 -347.246251) (xy 276.712601 -347.161914)
			(xy 276.728635 -347.078724) (xy 276.752503 -346.997434) (xy 276.783991 -346.918782) (xy 276.822813 -346.843479)
			(xy 276.868616 -346.772207) (xy 276.920987 -346.705611) (xy 276.979452 -346.644296) (xy 277.04348 -346.588815)
			(xy 277.112492 -346.539672) (xy 277.185862 -346.497312) (xy 277.262927 -346.462117) (xy 277.342989 -346.434408)
			(xy 277.425322 -346.414434) (xy 277.509181 -346.402377) (xy 277.593806 -346.398346) (xy 277.678431 -346.402377)
			(xy 277.76229 -346.414434) (xy 277.844623 -346.434408) (xy 277.924685 -346.462117) (xy 278.00175 -346.497312)
			(xy 278.07512 -346.539672) (xy 278.144132 -346.588815) (xy 278.20816 -346.644296) (xy 278.266625 -346.705611)
			(xy 278.318996 -346.772207) (xy 278.364799 -346.843479) (xy 278.403621 -346.918782) (xy 278.435109 -346.997434)
			(xy 278.458977 -347.078724) (xy 278.475011 -347.161914) (xy 278.483064 -347.246251) (xy 278.483568 -347.288612)
			(xy 278.482998 -347.333381) (xy 278.47399 -347.422466) (xy 278.456088 -347.510198) (xy 278.42947 -347.595689)
			(xy 278.412448 -347.6371) (xy 278.408812 -347.646665) (xy 278.408686 -347.667111) (xy 278.412194 -347.676724)
			(xy 278.426408 -347.711074) (xy 278.449728 -347.781668) (xy 278.467082 -347.85396) (xy 278.478348 -347.927447)
			(xy 278.481282 -347.964506) (xy 278.482267 -347.973327) (xy 278.489457 -347.989544) (xy 278.501708 -348.002373)
			(xy 278.509476 -348.00667) (xy 278.600662 -348.051628) (xy 278.62784 -348.049596) (xy 278.639016 -348.04223)
			(xy 278.675581 -348.018458) (xy 278.752524 -347.977387) (xy 278.833117 -347.944041) (xy 278.916586 -347.91874)
			(xy 279.00213 -347.901729) (xy 279.088929 -347.893169) (xy 279.132538 -347.892624) (xy 279.133046 -347.892624)
			(xy 279.174153 -347.893069) (xy 279.256016 -347.900657) (xy 279.336831 -347.915765) (xy 279.415907 -347.938263)
			(xy 279.49257 -347.96796) (xy 279.566167 -348.004602) (xy 279.63607 -348.047877) (xy 279.701683 -348.097416)
			(xy 279.762447 -348.152796) (xy 279.817842 -348.213546) (xy 279.867398 -348.279147) (xy 279.91069 -348.349039)
			(xy 279.947351 -348.422627) (xy 279.977067 -348.499283) (xy 279.999585 -348.578353) (xy 280.014712 -348.659164)
			(xy 280.018945 -348.7047) (xy 283.512244 -348.7047) (xy 283.516234 -348.620942) (xy 283.528168 -348.537942)
			(xy 283.547937 -348.456452) (xy 283.575362 -348.377211) (xy 283.610196 -348.300935) (xy 283.652122 -348.228316)
			(xy 283.700761 -348.16001) (xy 283.755673 -348.096638) (xy 283.81636 -348.038772) (xy 283.882273 -347.986937)
			(xy 283.952814 -347.941602) (xy 284.027346 -347.903177) (xy 284.105192 -347.872011) (xy 284.185648 -347.848386)
			(xy 284.267986 -347.832515) (xy 284.351459 -347.824543) (xy 284.393386 -347.824044) (xy 284.394402 -347.824044)
			(xy 284.431459 -347.824452) (xy 284.505308 -347.830716) (xy 284.57837 -347.843157) (xy 284.65013 -347.861689)
			(xy 284.685232 -347.873574) (xy 284.693429 -347.876088) (xy 284.710563 -347.876088) (xy 284.71876 -347.873574)
			(xy 284.756938 -347.860634) (xy 284.835124 -347.840982) (xy 284.91478 -347.828562) (xy 284.95498 -347.825568)
			(xy 284.965838 -347.82436) (xy 284.985096 -347.814096) (xy 284.99831 -347.79673) (xy 285.001208 -347.786198)
			(xy 285.010486 -347.747118) (xy 285.035162 -347.670674) (xy 285.050484 -347.633544) (xy 285.054028 -347.623948)
			(xy 285.05404 -347.603511) (xy 285.050484 -347.59392) (xy 285.033454 -347.552511) (xy 285.006819 -347.467023)
			(xy 284.988912 -347.379291) (xy 284.979917 -347.290203) (xy 284.979364 -347.245432) (xy 284.979868 -347.203071)
			(xy 284.987921 -347.118734) (xy 285.003955 -347.035544) (xy 285.027823 -346.954254) (xy 285.059311 -346.875602)
			(xy 285.098133 -346.800299) (xy 285.143936 -346.729027) (xy 285.196307 -346.662431) (xy 285.254772 -346.601116)
			(xy 285.3188 -346.545635) (xy 285.387812 -346.496492) (xy 285.461182 -346.454132) (xy 285.538247 -346.418937)
			(xy 285.618309 -346.391228) (xy 285.700642 -346.371254) (xy 285.784501 -346.359197) (xy 285.869126 -346.355166)
			(xy 285.953751 -346.359197) (xy 286.03761 -346.371254) (xy 286.119943 -346.391228) (xy 286.200005 -346.418937)
			(xy 286.27707 -346.454132) (xy 286.35044 -346.496492) (xy 286.419452 -346.545635) (xy 286.48348 -346.601116)
			(xy 286.541945 -346.662431) (xy 286.594316 -346.729027) (xy 286.640119 -346.800299) (xy 286.678941 -346.875602)
			(xy 286.710429 -346.954254) (xy 286.734297 -347.035544) (xy 286.750331 -347.118734) (xy 286.758384 -347.203071)
			(xy 286.758888 -347.245432) (xy 286.758323 -347.290202) (xy 286.749314 -347.379287) (xy 286.73141 -347.467018)
			(xy 286.704791 -347.552509) (xy 286.687768 -347.59392) (xy 286.684185 -347.603505) (xy 286.684197 -347.623953)
			(xy 286.687768 -347.633544) (xy 286.703871 -347.672618) (xy 286.72945 -347.753174) (xy 286.747275 -347.835792)
			(xy 286.757183 -347.919728) (xy 286.758634 -347.961966) (xy 286.758888 -347.975936) (xy 286.77362 -347.999558)
			(xy 286.86506 -348.047056) (xy 286.873276 -348.050887) (xy 286.891249 -348.053129) (xy 286.908879 -348.048973)
			(xy 286.916622 -348.044262) (xy 286.916876 -348.044008) (xy 286.95358 -348.019938) (xy 287.030887 -347.978361)
			(xy 287.111915 -347.944605) (xy 287.195876 -347.918998) (xy 287.281951 -347.901791) (xy 287.369303 -347.893149)
			(xy 287.413192 -347.892624) (xy 287.413446 -347.892624) (xy 287.454553 -347.893069) (xy 287.536416 -347.900657)
			(xy 287.617231 -347.915765) (xy 287.696307 -347.938263) (xy 287.77297 -347.96796) (xy 287.846567 -348.004602)
			(xy 287.91647 -348.047877) (xy 287.982083 -348.097416) (xy 288.042847 -348.152796) (xy 288.098242 -348.213546)
			(xy 288.147798 -348.279147) (xy 288.19109 -348.349039) (xy 288.227751 -348.422627) (xy 288.257467 -348.499283)
			(xy 288.279985 -348.578353) (xy 288.295112 -348.659164) (xy 288.299345 -348.7047) (xy 291.818044 -348.7047)
			(xy 291.822034 -348.620942) (xy 291.833968 -348.537942) (xy 291.853737 -348.456452) (xy 291.881162 -348.377211)
			(xy 291.915996 -348.300935) (xy 291.957922 -348.228316) (xy 292.006561 -348.16001) (xy 292.061473 -348.096638)
			(xy 292.12216 -348.038772) (xy 292.188073 -347.986937) (xy 292.258614 -347.941602) (xy 292.333146 -347.903177)
			(xy 292.410992 -347.872011) (xy 292.491448 -347.848386) (xy 292.573786 -347.832515) (xy 292.657259 -347.824543)
			(xy 292.699186 -347.824044) (xy 292.700202 -347.824044) (xy 292.737259 -347.824452) (xy 292.811108 -347.830716)
			(xy 292.88417 -347.843157) (xy 292.95593 -347.861689) (xy 292.991032 -347.873574) (xy 292.999229 -347.876088)
			(xy 293.016363 -347.876088) (xy 293.02456 -347.873574) (xy 293.057737 -347.862322) (xy 293.125493 -347.844496)
			(xy 293.194454 -347.832123) (xy 293.229284 -347.828362) (xy 293.240044 -347.82673) (xy 293.258819 -347.815766)
			(xy 293.271409 -347.798041) (xy 293.273988 -347.787468) (xy 293.28351 -347.742121) (xy 293.310744 -347.653548)
			(xy 293.328344 -347.610684) (xy 293.331924 -347.601098) (xy 293.331914 -347.580651) (xy 293.328344 -347.57106)
			(xy 293.311293 -347.529659) (xy 293.284663 -347.444168) (xy 293.266763 -347.356433) (xy 293.257774 -347.267343)
			(xy 293.257224 -347.222572) (xy 293.257728 -347.180211) (xy 293.265781 -347.095874) (xy 293.281815 -347.012684)
			(xy 293.305683 -346.931394) (xy 293.337171 -346.852742) (xy 293.375993 -346.777439) (xy 293.421796 -346.706167)
			(xy 293.474167 -346.639571) (xy 293.532632 -346.578256) (xy 293.59666 -346.522775) (xy 293.665672 -346.473632)
			(xy 293.739042 -346.431272) (xy 293.816107 -346.396077) (xy 293.896169 -346.368368) (xy 293.978502 -346.348394)
			(xy 294.062361 -346.336337) (xy 294.146986 -346.332306) (xy 294.231611 -346.336337) (xy 294.31547 -346.348394)
			(xy 294.397803 -346.368368) (xy 294.477865 -346.396077) (xy 294.55493 -346.431272) (xy 294.6283 -346.473632)
			(xy 294.697312 -346.522775) (xy 294.76134 -346.578256) (xy 294.819805 -346.639571) (xy 294.872176 -346.706167)
			(xy 294.917979 -346.777439) (xy 294.956801 -346.852742) (xy 294.988289 -346.931394) (xy 295.012157 -347.012684)
			(xy 295.028191 -347.095874) (xy 295.036244 -347.180211) (xy 295.036748 -347.222572) (xy 295.036192 -347.267342)
			(xy 295.027179 -347.356427) (xy 295.009272 -347.444158) (xy 294.982652 -347.529649) (xy 294.965628 -347.57106)
			(xy 294.962081 -347.580656) (xy 294.96207 -347.601093) (xy 294.965628 -347.610684) (xy 294.982659 -347.652092)
			(xy 295.009295 -347.73758) (xy 295.0272 -347.825313) (xy 295.036195 -347.914401) (xy 295.036748 -347.959172)
			(xy 295.036494 -347.977206) (xy 295.03624 -347.991684) (xy 295.050718 -348.016576) (xy 295.157144 -348.071948)
			(xy 295.185846 -348.069916) (xy 295.19753 -348.061534) (xy 295.230035 -348.038582) (xy 295.298406 -347.997866)
			(xy 295.370142 -347.963421) (xy 295.444669 -347.935524) (xy 295.521391 -347.914398) (xy 295.599693 -347.900211)
			(xy 295.67895 -347.893078) (xy 295.718738 -347.892624) (xy 295.719246 -347.892624) (xy 295.760353 -347.893069)
			(xy 295.842216 -347.900657) (xy 295.923031 -347.915765) (xy 296.002107 -347.938263) (xy 296.07877 -347.96796)
			(xy 296.152367 -348.004602) (xy 296.22227 -348.047877) (xy 296.287883 -348.097416) (xy 296.348647 -348.152796)
			(xy 296.404042 -348.213546) (xy 296.453598 -348.279147) (xy 296.49689 -348.349039) (xy 296.533551 -348.422627)
			(xy 296.563267 -348.499283) (xy 296.585785 -348.578353) (xy 296.600912 -348.659164) (xy 296.605145 -348.7047)
			(xy 300.174644 -348.7047) (xy 300.178634 -348.620942) (xy 300.190568 -348.537942) (xy 300.210337 -348.456452)
			(xy 300.237762 -348.377211) (xy 300.272596 -348.300935) (xy 300.314522 -348.228316) (xy 300.363161 -348.16001)
			(xy 300.418073 -348.096638) (xy 300.47876 -348.038772) (xy 300.544673 -347.986937) (xy 300.615214 -347.941602)
			(xy 300.689746 -347.903177) (xy 300.767592 -347.872011) (xy 300.848048 -347.848386) (xy 300.930386 -347.832515)
			(xy 301.013859 -347.824543) (xy 301.055786 -347.824044) (xy 301.056802 -347.824044) (xy 301.093859 -347.824452)
			(xy 301.167708 -347.830716) (xy 301.24077 -347.843157) (xy 301.31253 -347.861689) (xy 301.347632 -347.873574)
			(xy 301.355829 -347.876088) (xy 301.372963 -347.876088) (xy 301.38116 -347.873574) (xy 301.419296 -347.860641)
			(xy 301.497398 -347.840993) (xy 301.576968 -347.828568) (xy 301.617126 -347.825568) (xy 301.627844 -347.824451)
			(xy 301.646914 -347.814446) (xy 301.660249 -347.797535) (xy 301.663354 -347.787214) (xy 301.672203 -347.75314)
			(xy 301.694583 -347.686387) (xy 301.708058 -347.653864) (xy 301.711569 -347.644255) (xy 301.711421 -347.623811)
			(xy 301.707804 -347.61424) (xy 301.690776 -347.57283) (xy 301.66414 -347.487343) (xy 301.646234 -347.39961)
			(xy 301.637237 -347.310523) (xy 301.636684 -347.265752) (xy 301.637188 -347.223391) (xy 301.645241 -347.139054)
			(xy 301.661275 -347.055864) (xy 301.685143 -346.974574) (xy 301.716631 -346.895922) (xy 301.755453 -346.820619)
			(xy 301.801256 -346.749347) (xy 301.853627 -346.682751) (xy 301.912092 -346.621436) (xy 301.97612 -346.565955)
			(xy 302.045132 -346.516812) (xy 302.118502 -346.474452) (xy 302.195567 -346.439257) (xy 302.275629 -346.411548)
			(xy 302.357962 -346.391574) (xy 302.441821 -346.379517) (xy 302.526446 -346.375486) (xy 302.611071 -346.379517)
			(xy 302.69493 -346.391574) (xy 302.777263 -346.411548) (xy 302.857325 -346.439257) (xy 302.93439 -346.474452)
			(xy 303.00776 -346.516812) (xy 303.076772 -346.565955) (xy 303.1408 -346.621436) (xy 303.199265 -346.682751)
			(xy 303.251636 -346.749347) (xy 303.297439 -346.820619) (xy 303.336261 -346.895922) (xy 303.367749 -346.974574)
			(xy 303.391617 -347.055864) (xy 303.407651 -347.139054) (xy 303.415704 -347.223391) (xy 303.416208 -347.265752)
			(xy 303.415649 -347.310522) (xy 303.406637 -347.399607) (xy 303.388731 -347.487338) (xy 303.362111 -347.572829)
			(xy 303.345088 -347.61424) (xy 303.341549 -347.623838) (xy 303.341532 -347.644274) (xy 303.345088 -347.653864)
			(xy 303.36051 -347.691224) (xy 303.385289 -347.768163) (xy 303.402976 -347.847034) (xy 303.413426 -347.927187)
			(xy 303.415446 -347.967554) (xy 303.415954 -347.981524) (xy 303.430686 -348.004638) (xy 303.535334 -348.057216)
			(xy 303.562766 -348.055184) (xy 303.574196 -348.04731) (xy 303.611146 -348.022772) (xy 303.689046 -347.980345)
			(xy 303.770779 -347.945874) (xy 303.855535 -347.919702) (xy 303.942473 -347.902087) (xy 304.030732 -347.893205)
			(xy 304.075084 -347.892624) (xy 304.075846 -347.892624) (xy 304.116953 -347.893069) (xy 304.198816 -347.900657)
			(xy 304.279631 -347.915765) (xy 304.358707 -347.938263) (xy 304.43537 -347.96796) (xy 304.508967 -348.004602)
			(xy 304.57887 -348.047877) (xy 304.644483 -348.097416) (xy 304.705247 -348.152796) (xy 304.760642 -348.213546)
			(xy 304.810198 -348.279147) (xy 304.85349 -348.349039) (xy 304.890151 -348.422627) (xy 304.919867 -348.499283)
			(xy 304.942385 -348.578353) (xy 304.957512 -348.659164) (xy 304.961745 -348.7047) (xy 308.505844 -348.7047)
			(xy 308.509834 -348.620942) (xy 308.521768 -348.537942) (xy 308.541537 -348.456452) (xy 308.568962 -348.377211)
			(xy 308.603796 -348.300935) (xy 308.645722 -348.228316) (xy 308.694361 -348.16001) (xy 308.749273 -348.096638)
			(xy 308.80996 -348.038772) (xy 308.875873 -347.986937) (xy 308.946414 -347.941602) (xy 309.020946 -347.903177)
			(xy 309.098792 -347.872011) (xy 309.179248 -347.848386) (xy 309.261586 -347.832515) (xy 309.345059 -347.824543)
			(xy 309.386986 -347.824044) (xy 309.388002 -347.824044) (xy 309.425059 -347.824452) (xy 309.498908 -347.830716)
			(xy 309.57197 -347.843157) (xy 309.64373 -347.861689) (xy 309.678832 -347.873574) (xy 309.687029 -347.876088)
			(xy 309.704163 -347.876088) (xy 309.71236 -347.873574) (xy 309.752087 -347.860214) (xy 309.833476 -347.84017)
			(xy 309.916402 -347.827952) (xy 309.958232 -347.825314) (xy 309.969008 -347.824123) (xy 309.988202 -347.814097)
			(xy 310.001607 -347.79709) (xy 310.004714 -347.786706) (xy 310.013576 -347.75276) (xy 310.035956 -347.686262)
			(xy 310.049418 -347.653864) (xy 310.052931 -347.644255) (xy 310.052783 -347.623811) (xy 310.049164 -347.61424)
			(xy 310.03214 -347.572829) (xy 310.005503 -347.487342) (xy 309.987595 -347.39961) (xy 309.978598 -347.310522)
			(xy 309.978044 -347.265752) (xy 309.978548 -347.223391) (xy 309.986601 -347.139054) (xy 310.002635 -347.055864)
			(xy 310.026503 -346.974574) (xy 310.057991 -346.895922) (xy 310.096813 -346.820619) (xy 310.142616 -346.749347)
			(xy 310.194987 -346.682751) (xy 310.253452 -346.621436) (xy 310.31748 -346.565955) (xy 310.386492 -346.516812)
			(xy 310.459862 -346.474452) (xy 310.536927 -346.439257) (xy 310.616989 -346.411548) (xy 310.699322 -346.391574)
			(xy 310.783181 -346.379517) (xy 310.867806 -346.375486) (xy 310.952431 -346.379517) (xy 311.03629 -346.391574)
			(xy 311.118623 -346.411548) (xy 311.198685 -346.439257) (xy 311.27575 -346.474452) (xy 311.34912 -346.516812)
			(xy 311.418132 -346.565955) (xy 311.48216 -346.621436) (xy 311.540625 -346.682751) (xy 311.592996 -346.749347)
			(xy 311.638799 -346.820619) (xy 311.677621 -346.895922) (xy 311.709109 -346.974574) (xy 311.732977 -347.055864)
			(xy 311.749011 -347.139054) (xy 311.757064 -347.223391) (xy 311.757568 -347.265752) (xy 311.757012 -347.310522)
			(xy 311.748 -347.399607) (xy 311.730093 -347.487338) (xy 311.703472 -347.572829) (xy 311.686448 -347.61424)
			(xy 311.682911 -347.623839) (xy 311.682894 -347.644274) (xy 311.686448 -347.653864) (xy 311.701578 -347.690518)
			(xy 311.725997 -347.765967) (xy 311.743615 -347.843288) (xy 311.754293 -347.921869) (xy 311.756552 -347.961458)
			(xy 311.757251 -347.970429) (xy 311.764179 -347.987026) (xy 311.776392 -348.000229) (xy 311.784238 -348.004638)
			(xy 311.875678 -348.050866) (xy 311.902856 -348.049088) (xy 311.914286 -348.041468) (xy 311.950798 -348.017804)
			(xy 312.027605 -347.976914) (xy 312.10804 -347.943725) (xy 312.191333 -347.918554) (xy 312.276687 -347.901641)
			(xy 312.363285 -347.893148) (xy 312.406792 -347.892624) (xy 312.407046 -347.892624) (xy 312.448153 -347.893069)
			(xy 312.530016 -347.900657) (xy 312.610831 -347.915765) (xy 312.689907 -347.938263) (xy 312.76657 -347.96796)
			(xy 312.840167 -348.004602) (xy 312.91007 -348.047877) (xy 312.975683 -348.097416) (xy 313.036447 -348.152796)
			(xy 313.091842 -348.213546) (xy 313.141398 -348.279147) (xy 313.18469 -348.349039) (xy 313.221351 -348.422627)
			(xy 313.251067 -348.499283) (xy 313.273585 -348.578353) (xy 313.288712 -348.659164) (xy 313.296321 -348.741025)
			(xy 313.296808 -348.782132) (xy 313.296242 -348.826902) (xy 313.287233 -348.915987) (xy 313.269329 -349.003718)
			(xy 313.242711 -349.089209) (xy 313.225688 -349.13062) (xy 313.222104 -349.140205) (xy 313.222115 -349.160653)
			(xy 313.225688 -349.170244) (xy 313.242711 -349.211656) (xy 313.269347 -349.297143) (xy 313.287256 -349.384874)
			(xy 313.291976 -349.43161) (xy 326.552821 -349.43161) (xy 326.556826 -349.325861) (xy 326.568816 -349.220718)
			(xy 326.588725 -349.116783) (xy 326.616436 -349.014651) (xy 326.651793 -348.914907) (xy 326.694591 -348.818123)
			(xy 326.744587 -348.724853) (xy 326.801494 -348.635632) (xy 326.864985 -348.550969) (xy 326.934697 -348.471351)
			(xy 327.010231 -348.397233) (xy 327.091154 -348.32904) (xy 327.177003 -348.267162) (xy 327.267286 -348.211955)
			(xy 327.361485 -348.163733) (xy 327.459062 -348.122773) (xy 327.559457 -348.089311) (xy 327.662095 -348.063537)
			(xy 327.766388 -348.045599) (xy 327.871739 -348.0356) (xy 327.977545 -348.033597) (xy 328.083199 -348.039602)
			(xy 328.188096 -348.053581) (xy 328.291636 -348.075452) (xy 328.393225 -348.105092) (xy 328.492282 -348.14233)
			(xy 328.588239 -348.186952) (xy 328.680546 -348.238704) (xy 328.768675 -348.297289) (xy 328.852121 -348.362371)
			(xy 328.930405 -348.433577) (xy 329.00308 -348.5105) (xy 329.06973 -348.5927) (xy 329.129972 -348.679704)
			(xy 329.183461 -348.771015) (xy 329.229892 -348.86611) (xy 329.268997 -348.964444) (xy 329.300554 -349.065455)
			(xy 329.324381 -349.168562) (xy 329.340342 -349.273176) (xy 329.348346 -349.378698) (xy 329.348846 -349.43161)
			(xy 334.012801 -349.43161) (xy 334.016806 -349.325861) (xy 334.028796 -349.220718) (xy 334.048705 -349.116783)
			(xy 334.076416 -349.014651) (xy 334.111773 -348.914907) (xy 334.154571 -348.818123) (xy 334.204567 -348.724853)
			(xy 334.261474 -348.635632) (xy 334.324965 -348.550969) (xy 334.394677 -348.471351) (xy 334.470211 -348.397233)
			(xy 334.551134 -348.32904) (xy 334.636983 -348.267162) (xy 334.727266 -348.211955) (xy 334.821465 -348.163733)
			(xy 334.919042 -348.122773) (xy 335.019437 -348.089311) (xy 335.122075 -348.063537) (xy 335.226368 -348.045599)
			(xy 335.331719 -348.0356) (xy 335.437525 -348.033597) (xy 335.543179 -348.039602) (xy 335.648076 -348.053581)
			(xy 335.751616 -348.075452) (xy 335.853205 -348.105092) (xy 335.952262 -348.14233) (xy 336.048219 -348.186952)
			(xy 336.140526 -348.238704) (xy 336.228655 -348.297289) (xy 336.312101 -348.362371) (xy 336.390385 -348.433577)
			(xy 336.46306 -348.5105) (xy 336.52971 -348.5927) (xy 336.589952 -348.679704) (xy 336.643441 -348.771015)
			(xy 336.689872 -348.86611) (xy 336.728977 -348.964444) (xy 336.760534 -349.065455) (xy 336.784361 -349.168562)
			(xy 336.800322 -349.273176) (xy 336.808326 -349.378698) (xy 336.808826 -349.43161) (xy 336.808326 -349.484522)
			(xy 336.800322 -349.590044) (xy 336.784361 -349.694658) (xy 336.760534 -349.797765) (xy 336.728977 -349.898776)
			(xy 336.689872 -349.99711) (xy 336.643441 -350.092205) (xy 336.589952 -350.183516) (xy 336.52971 -350.27052)
			(xy 336.46306 -350.35272) (xy 336.390385 -350.429643) (xy 336.312101 -350.500849) (xy 336.228655 -350.565931)
			(xy 336.140526 -350.624516) (xy 336.048219 -350.676268) (xy 335.952262 -350.72089) (xy 335.853205 -350.758128)
			(xy 335.751616 -350.787768) (xy 335.648076 -350.809639) (xy 335.543179 -350.823618) (xy 335.437525 -350.829623)
			(xy 335.331719 -350.82762) (xy 335.226368 -350.817621) (xy 335.122075 -350.799683) (xy 335.019437 -350.773909)
			(xy 334.919042 -350.740447) (xy 334.821465 -350.699487) (xy 334.727266 -350.651265) (xy 334.636983 -350.596058)
			(xy 334.551134 -350.53418) (xy 334.470211 -350.465987) (xy 334.394677 -350.391869) (xy 334.324965 -350.312251)
			(xy 334.261474 -350.227588) (xy 334.204567 -350.138367) (xy 334.154571 -350.045097) (xy 334.111773 -349.948313)
			(xy 334.076416 -349.848569) (xy 334.048705 -349.746437) (xy 334.028796 -349.642502) (xy 334.016806 -349.537359)
			(xy 334.012801 -349.43161) (xy 329.348846 -349.43161) (xy 329.348346 -349.484522) (xy 329.340342 -349.590044)
			(xy 329.324381 -349.694658) (xy 329.300554 -349.797765) (xy 329.268997 -349.898776) (xy 329.229892 -349.99711)
			(xy 329.183461 -350.092205) (xy 329.129972 -350.183516) (xy 329.06973 -350.27052) (xy 329.00308 -350.35272)
			(xy 328.930405 -350.429643) (xy 328.852121 -350.500849) (xy 328.768675 -350.565931) (xy 328.680546 -350.624516)
			(xy 328.588239 -350.676268) (xy 328.492282 -350.72089) (xy 328.393225 -350.758128) (xy 328.291636 -350.787768)
			(xy 328.188096 -350.809639) (xy 328.083199 -350.823618) (xy 327.977545 -350.829623) (xy 327.871739 -350.82762)
			(xy 327.766388 -350.817621) (xy 327.662095 -350.799683) (xy 327.559457 -350.773909) (xy 327.459062 -350.740447)
			(xy 327.361485 -350.699487) (xy 327.267286 -350.651265) (xy 327.177003 -350.596058) (xy 327.091154 -350.53418)
			(xy 327.010231 -350.465987) (xy 326.934697 -350.391869) (xy 326.864985 -350.312251) (xy 326.801494 -350.227588)
			(xy 326.744587 -350.138367) (xy 326.694591 -350.045097) (xy 326.651793 -349.948313) (xy 326.616436 -349.848569)
			(xy 326.588725 -349.746437) (xy 326.568816 -349.642502) (xy 326.556826 -349.537359) (xy 326.552821 -349.43161)
			(xy 313.291976 -349.43161) (xy 313.296254 -349.473962) (xy 313.296808 -349.518732) (xy 313.296242 -349.563502)
			(xy 313.287233 -349.652587) (xy 313.269329 -349.740318) (xy 313.242711 -349.825809) (xy 313.225688 -349.86722)
			(xy 313.222104 -349.876805) (xy 313.222115 -349.897253) (xy 313.225688 -349.906844) (xy 313.242711 -349.948256)
			(xy 313.269347 -350.033743) (xy 313.287256 -350.121474) (xy 313.296254 -350.210562) (xy 313.296808 -350.255332)
			(xy 313.296378 -350.296443) (xy 313.288787 -350.378314) (xy 313.273674 -350.459136) (xy 313.251166 -350.538217)
			(xy 313.221457 -350.614885) (xy 313.184799 -350.688483) (xy 313.141506 -350.758385) (xy 313.091947 -350.823993)
			(xy 313.036545 -350.884747) (xy 312.975772 -350.94013) (xy 312.910148 -350.989668) (xy 312.840233 -351.032938)
			(xy 312.766623 -351.069572) (xy 312.689946 -351.099257) (xy 312.610857 -351.121739) (xy 312.530031 -351.136827)
			(xy 312.448157 -351.144391) (xy 312.407046 -351.14484) (xy 312.365442 -351.14437) (xy 312.282594 -351.136637)
			(xy 312.200829 -351.121206) (xy 312.120862 -351.098211) (xy 312.043389 -351.067854) (xy 311.969088 -351.0304)
			(xy 311.93359 -351.008696) (xy 311.924458 -351.003521) (xy 311.903738 -351.00031) (xy 311.883461 -351.005649)
			(xy 311.874916 -351.011744) (xy 311.841266 -351.037664) (xy 311.769892 -351.083723) (xy 311.694453 -351.12277)
			(xy 311.615637 -351.15445) (xy 311.53416 -351.178473) (xy 311.450764 -351.194623) (xy 311.366208 -351.20275)
			(xy 311.323736 -351.20326) (xy 311.323482 -351.20326) (xy 311.282375 -351.202805) (xy 311.200511 -351.195219)
			(xy 311.119697 -351.180113) (xy 311.04062 -351.157617) (xy 310.963956 -351.127921) (xy 310.890359 -351.09128)
			(xy 310.820455 -351.048006) (xy 310.754841 -350.998468) (xy 310.694077 -350.943088) (xy 310.638682 -350.882339)
			(xy 310.589126 -350.816738) (xy 310.545833 -350.746846) (xy 310.509173 -350.673258) (xy 310.479458 -350.596602)
			(xy 310.456941 -350.517531) (xy 310.441814 -350.43672) (xy 310.434206 -350.354859) (xy 310.43372 -350.313752)
			(xy 310.434279 -350.268982) (xy 310.44329 -350.179897) (xy 310.461196 -350.092166) (xy 310.487816 -350.006675)
			(xy 310.50484 -349.965264) (xy 310.508432 -349.955681) (xy 310.508415 -349.935231) (xy 310.50484 -349.92564)
			(xy 310.487836 -349.884289) (xy 310.461225 -349.798927) (xy 310.443318 -349.711324) (xy 310.434296 -349.622367)
			(xy 310.43372 -349.57766) (xy 310.43372 -349.576644) (xy 310.433974 -349.565214) (xy 310.407495 -349.559269)
			(xy 310.35526 -349.544526) (xy 310.32958 -349.53575) (xy 310.321383 -349.533236) (xy 310.304249 -349.533236)
			(xy 310.296052 -349.53575) (xy 310.260836 -349.547697) (xy 310.188826 -349.566284) (xy 310.115503 -349.578724)
			(xy 310.041392 -349.584928) (xy 310.004206 -349.58528) (xy 309.967022 -349.584911) (xy 309.892914 -349.578689)
			(xy 309.819594 -349.566246) (xy 309.747583 -349.547672) (xy 309.71236 -349.53575) (xy 309.704163 -349.533236)
			(xy 309.687029 -349.533236) (xy 309.678832 -349.53575) (xy 309.64373 -349.547637) (xy 309.571974 -349.566187)
			(xy 309.498911 -349.578634) (xy 309.42506 -349.584887) (xy 309.388002 -349.58528) (xy 309.386986 -349.58528)
			(xy 309.345059 -349.584857) (xy 309.261586 -349.576885) (xy 309.179248 -349.561014) (xy 309.098792 -349.537389)
			(xy 309.020946 -349.506223) (xy 308.946414 -349.467798) (xy 308.875873 -349.422463) (xy 308.80996 -349.370628)
			(xy 308.749273 -349.312762) (xy 308.694361 -349.24939) (xy 308.645722 -349.181084) (xy 308.603796 -349.108465)
			(xy 308.568962 -349.032189) (xy 308.541537 -348.952948) (xy 308.521768 -348.871458) (xy 308.509834 -348.788458)
			(xy 308.505844 -348.7047) (xy 304.961745 -348.7047) (xy 304.965121 -348.741025) (xy 304.965608 -348.782132)
			(xy 304.965042 -348.826902) (xy 304.956033 -348.915987) (xy 304.938129 -349.003718) (xy 304.911511 -349.089209)
			(xy 304.894488 -349.13062) (xy 304.890904 -349.140205) (xy 304.890915 -349.160653) (xy 304.894488 -349.170244)
			(xy 304.911511 -349.211656) (xy 304.938147 -349.297143) (xy 304.956056 -349.384874) (xy 304.965054 -349.473962)
			(xy 304.965608 -349.518732) (xy 304.965042 -349.563502) (xy 304.956033 -349.652587) (xy 304.938129 -349.740318)
			(xy 304.911511 -349.825809) (xy 304.894488 -349.86722) (xy 304.890904 -349.876805) (xy 304.890915 -349.897253)
			(xy 304.894488 -349.906844) (xy 304.911511 -349.948256) (xy 304.938147 -350.033743) (xy 304.956056 -350.121474)
			(xy 304.965054 -350.210562) (xy 304.965608 -350.255332) (xy 304.965178 -350.296443) (xy 304.957587 -350.378314)
			(xy 304.942474 -350.459136) (xy 304.919966 -350.538217) (xy 304.890257 -350.614885) (xy 304.853599 -350.688483)
			(xy 304.810306 -350.758385) (xy 304.760747 -350.823993) (xy 304.705345 -350.884747) (xy 304.644572 -350.94013)
			(xy 304.578948 -350.989668) (xy 304.509033 -351.032938) (xy 304.435423 -351.069572) (xy 304.358746 -351.099257)
			(xy 304.279657 -351.121739) (xy 304.198831 -351.136827) (xy 304.116957 -351.144391) (xy 304.075846 -351.14484)
			(xy 304.034242 -351.14437) (xy 303.951394 -351.136637) (xy 303.869629 -351.121206) (xy 303.789662 -351.098211)
			(xy 303.712189 -351.067854) (xy 303.637888 -351.0304) (xy 303.60239 -351.008696) (xy 303.593258 -351.003521)
			(xy 303.572538 -351.00031) (xy 303.552261 -351.005649) (xy 303.543716 -351.011744) (xy 303.510066 -351.037664)
			(xy 303.438692 -351.083723) (xy 303.363253 -351.12277) (xy 303.284437 -351.15445) (xy 303.20296 -351.178473)
			(xy 303.119564 -351.194623) (xy 303.035008 -351.20275) (xy 302.992536 -351.20326) (xy 302.992282 -351.20326)
			(xy 302.951175 -351.202805) (xy 302.869311 -351.195219) (xy 302.788497 -351.180113) (xy 302.70942 -351.157617)
			(xy 302.632756 -351.127921) (xy 302.559159 -351.09128) (xy 302.489255 -351.048006) (xy 302.423641 -350.998468)
			(xy 302.362877 -350.943088) (xy 302.307482 -350.882339) (xy 302.257926 -350.816738) (xy 302.214633 -350.746846)
			(xy 302.177973 -350.673258) (xy 302.148258 -350.596602) (xy 302.125741 -350.517531) (xy 302.110614 -350.43672)
			(xy 302.103006 -350.354859) (xy 302.10252 -350.313752) (xy 302.103079 -350.268982) (xy 302.11209 -350.179897)
			(xy 302.129996 -350.092166) (xy 302.156616 -350.006675) (xy 302.17364 -349.965264) (xy 302.177232 -349.955681)
			(xy 302.177215 -349.935231) (xy 302.17364 -349.92564) (xy 302.156636 -349.884289) (xy 302.130025 -349.798927)
			(xy 302.112118 -349.711324) (xy 302.103096 -349.622367) (xy 302.10252 -349.57766) (xy 302.10252 -349.576644)
			(xy 302.102774 -349.565214) (xy 302.076295 -349.559269) (xy 302.02406 -349.544526) (xy 301.99838 -349.53575)
			(xy 301.990183 -349.533236) (xy 301.973049 -349.533236) (xy 301.964852 -349.53575) (xy 301.929636 -349.547697)
			(xy 301.857626 -349.566284) (xy 301.784303 -349.578724) (xy 301.710192 -349.584928) (xy 301.673006 -349.58528)
			(xy 301.635822 -349.584911) (xy 301.561714 -349.578689) (xy 301.488394 -349.566246) (xy 301.416383 -349.547672)
			(xy 301.38116 -349.53575) (xy 301.372963 -349.533236) (xy 301.355829 -349.533236) (xy 301.347632 -349.53575)
			(xy 301.31253 -349.547637) (xy 301.240774 -349.566187) (xy 301.167711 -349.578634) (xy 301.09386 -349.584887)
			(xy 301.056802 -349.58528) (xy 301.055786 -349.58528) (xy 301.013859 -349.584857) (xy 300.930386 -349.576885)
			(xy 300.848048 -349.561014) (xy 300.767592 -349.537389) (xy 300.689746 -349.506223) (xy 300.615214 -349.467798)
			(xy 300.544673 -349.422463) (xy 300.47876 -349.370628) (xy 300.418073 -349.312762) (xy 300.363161 -349.24939)
			(xy 300.314522 -349.181084) (xy 300.272596 -349.108465) (xy 300.237762 -349.032189) (xy 300.210337 -348.952948)
			(xy 300.190568 -348.871458) (xy 300.178634 -348.788458) (xy 300.174644 -348.7047) (xy 296.605145 -348.7047)
			(xy 296.608521 -348.741025) (xy 296.609008 -348.782132) (xy 296.608442 -348.826902) (xy 296.599433 -348.915987)
			(xy 296.581529 -349.003718) (xy 296.554911 -349.089209) (xy 296.537888 -349.13062) (xy 296.534304 -349.140205)
			(xy 296.534315 -349.160653) (xy 296.537888 -349.170244) (xy 296.554911 -349.211656) (xy 296.581547 -349.297143)
			(xy 296.599456 -349.384874) (xy 296.608454 -349.473962) (xy 296.609008 -349.518732) (xy 296.608442 -349.563502)
			(xy 296.599433 -349.652587) (xy 296.581529 -349.740318) (xy 296.554911 -349.825809) (xy 296.537888 -349.86722)
			(xy 296.534304 -349.876805) (xy 296.534315 -349.897253) (xy 296.537888 -349.906844) (xy 296.554911 -349.948256)
			(xy 296.581547 -350.033743) (xy 296.599456 -350.121474) (xy 296.608454 -350.210562) (xy 296.609008 -350.255332)
			(xy 296.608578 -350.296443) (xy 296.600987 -350.378314) (xy 296.585874 -350.459136) (xy 296.563366 -350.538217)
			(xy 296.533657 -350.614885) (xy 296.496999 -350.688483) (xy 296.453706 -350.758385) (xy 296.404147 -350.823993)
			(xy 296.348745 -350.884747) (xy 296.287972 -350.94013) (xy 296.222348 -350.989668) (xy 296.152433 -351.032938)
			(xy 296.078823 -351.069572) (xy 296.002146 -351.099257) (xy 295.923057 -351.121739) (xy 295.842231 -351.136827)
			(xy 295.760357 -351.144391) (xy 295.719246 -351.14484) (xy 295.677642 -351.14437) (xy 295.594794 -351.136637)
			(xy 295.513029 -351.121206) (xy 295.433062 -351.098211) (xy 295.355589 -351.067854) (xy 295.281288 -351.0304)
			(xy 295.24579 -351.008696) (xy 295.236658 -351.003521) (xy 295.215938 -351.00031) (xy 295.195661 -351.005649)
			(xy 295.187116 -351.011744) (xy 295.153466 -351.037664) (xy 295.082092 -351.083723) (xy 295.006653 -351.12277)
			(xy 294.927837 -351.15445) (xy 294.84636 -351.178473) (xy 294.762964 -351.194623) (xy 294.678408 -351.20275)
			(xy 294.635936 -351.20326) (xy 294.635682 -351.20326) (xy 294.594575 -351.202805) (xy 294.512711 -351.195219)
			(xy 294.431897 -351.180113) (xy 294.35282 -351.157617) (xy 294.276156 -351.127921) (xy 294.202559 -351.09128)
			(xy 294.132655 -351.048006) (xy 294.067041 -350.998468) (xy 294.006277 -350.943088) (xy 293.950882 -350.882339)
			(xy 293.901326 -350.816738) (xy 293.858033 -350.746846) (xy 293.821373 -350.673258) (xy 293.791658 -350.596602)
			(xy 293.769141 -350.517531) (xy 293.754014 -350.43672) (xy 293.746406 -350.354859) (xy 293.74592 -350.313752)
			(xy 293.746479 -350.268982) (xy 293.75549 -350.179897) (xy 293.773396 -350.092166) (xy 293.800016 -350.006675)
			(xy 293.81704 -349.965264) (xy 293.820632 -349.955681) (xy 293.820615 -349.935231) (xy 293.81704 -349.92564)
			(xy 293.800036 -349.884289) (xy 293.773425 -349.798927) (xy 293.755518 -349.711324) (xy 293.746496 -349.622367)
			(xy 293.74592 -349.57766) (xy 293.74592 -349.576644) (xy 293.746174 -349.565214) (xy 293.719695 -349.559269)
			(xy 293.66746 -349.544526) (xy 293.64178 -349.53575) (xy 293.633583 -349.533236) (xy 293.616449 -349.533236)
			(xy 293.608252 -349.53575) (xy 293.573036 -349.547697) (xy 293.501026 -349.566284) (xy 293.427703 -349.578724)
			(xy 293.353592 -349.584928) (xy 293.316406 -349.58528) (xy 293.279222 -349.584911) (xy 293.205114 -349.578689)
			(xy 293.131794 -349.566246) (xy 293.059783 -349.547672) (xy 293.02456 -349.53575) (xy 293.016363 -349.533236)
			(xy 292.999229 -349.533236) (xy 292.991032 -349.53575) (xy 292.95593 -349.547637) (xy 292.884174 -349.566187)
			(xy 292.811111 -349.578634) (xy 292.73726 -349.584887) (xy 292.700202 -349.58528) (xy 292.699186 -349.58528)
			(xy 292.657259 -349.584857) (xy 292.573786 -349.576885) (xy 292.491448 -349.561014) (xy 292.410992 -349.537389)
			(xy 292.333146 -349.506223) (xy 292.258614 -349.467798) (xy 292.188073 -349.422463) (xy 292.12216 -349.370628)
			(xy 292.061473 -349.312762) (xy 292.006561 -349.24939) (xy 291.957922 -349.181084) (xy 291.915996 -349.108465)
			(xy 291.881162 -349.032189) (xy 291.853737 -348.952948) (xy 291.833968 -348.871458) (xy 291.822034 -348.788458)
			(xy 291.818044 -348.7047) (xy 288.299345 -348.7047) (xy 288.302721 -348.741025) (xy 288.303208 -348.782132)
			(xy 288.302642 -348.826902) (xy 288.293633 -348.915987) (xy 288.275729 -349.003718) (xy 288.249111 -349.089209)
			(xy 288.232088 -349.13062) (xy 288.228504 -349.140205) (xy 288.228515 -349.160653) (xy 288.232088 -349.170244)
			(xy 288.249111 -349.211656) (xy 288.275747 -349.297143) (xy 288.293656 -349.384874) (xy 288.302654 -349.473962)
			(xy 288.303208 -349.518732) (xy 288.302642 -349.563502) (xy 288.293633 -349.652587) (xy 288.275729 -349.740318)
			(xy 288.249111 -349.825809) (xy 288.232088 -349.86722) (xy 288.228504 -349.876805) (xy 288.228515 -349.897253)
			(xy 288.232088 -349.906844) (xy 288.249111 -349.948256) (xy 288.275747 -350.033743) (xy 288.293656 -350.121474)
			(xy 288.302654 -350.210562) (xy 288.303208 -350.255332) (xy 288.302778 -350.296443) (xy 288.295187 -350.378314)
			(xy 288.280074 -350.459136) (xy 288.257566 -350.538217) (xy 288.227857 -350.614885) (xy 288.191199 -350.688483)
			(xy 288.147906 -350.758385) (xy 288.098347 -350.823993) (xy 288.042945 -350.884747) (xy 287.982172 -350.94013)
			(xy 287.916548 -350.989668) (xy 287.846633 -351.032938) (xy 287.773023 -351.069572) (xy 287.696346 -351.099257)
			(xy 287.617257 -351.121739) (xy 287.536431 -351.136827) (xy 287.454557 -351.144391) (xy 287.413446 -351.14484)
			(xy 287.371842 -351.14437) (xy 287.288994 -351.136637) (xy 287.207229 -351.121206) (xy 287.127262 -351.098211)
			(xy 287.049789 -351.067854) (xy 286.975488 -351.0304) (xy 286.93999 -351.008696) (xy 286.930858 -351.003521)
			(xy 286.910138 -351.00031) (xy 286.889861 -351.005649) (xy 286.881316 -351.011744) (xy 286.847666 -351.037664)
			(xy 286.776292 -351.083723) (xy 286.700853 -351.12277) (xy 286.622037 -351.15445) (xy 286.54056 -351.178473)
			(xy 286.457164 -351.194623) (xy 286.372608 -351.20275) (xy 286.330136 -351.20326) (xy 286.329882 -351.20326)
			(xy 286.288775 -351.202805) (xy 286.206911 -351.195219) (xy 286.126097 -351.180113) (xy 286.04702 -351.157617)
			(xy 285.970356 -351.127921) (xy 285.896759 -351.09128) (xy 285.826855 -351.048006) (xy 285.761241 -350.998468)
			(xy 285.700477 -350.943088) (xy 285.645082 -350.882339) (xy 285.595526 -350.816738) (xy 285.552233 -350.746846)
			(xy 285.515573 -350.673258) (xy 285.485858 -350.596602) (xy 285.463341 -350.517531) (xy 285.448214 -350.43672)
			(xy 285.440606 -350.354859) (xy 285.44012 -350.313752) (xy 285.440679 -350.268982) (xy 285.44969 -350.179897)
			(xy 285.467596 -350.092166) (xy 285.494216 -350.006675) (xy 285.51124 -349.965264) (xy 285.514832 -349.955681)
			(xy 285.514815 -349.935231) (xy 285.51124 -349.92564) (xy 285.494236 -349.884289) (xy 285.467625 -349.798927)
			(xy 285.449718 -349.711324) (xy 285.440696 -349.622367) (xy 285.44012 -349.57766) (xy 285.44012 -349.576644)
			(xy 285.440374 -349.565214) (xy 285.413895 -349.559269) (xy 285.36166 -349.544526) (xy 285.33598 -349.53575)
			(xy 285.327783 -349.533236) (xy 285.310649 -349.533236) (xy 285.302452 -349.53575) (xy 285.267236 -349.547697)
			(xy 285.195226 -349.566284) (xy 285.121903 -349.578724) (xy 285.047792 -349.584928) (xy 285.010606 -349.58528)
			(xy 284.973422 -349.584911) (xy 284.899314 -349.578689) (xy 284.825994 -349.566246) (xy 284.753983 -349.547672)
			(xy 284.71876 -349.53575) (xy 284.710563 -349.533236) (xy 284.693429 -349.533236) (xy 284.685232 -349.53575)
			(xy 284.65013 -349.547637) (xy 284.578374 -349.566187) (xy 284.505311 -349.578634) (xy 284.43146 -349.584887)
			(xy 284.394402 -349.58528) (xy 284.393386 -349.58528) (xy 284.351459 -349.584857) (xy 284.267986 -349.576885)
			(xy 284.185648 -349.561014) (xy 284.105192 -349.537389) (xy 284.027346 -349.506223) (xy 283.952814 -349.467798)
			(xy 283.882273 -349.422463) (xy 283.81636 -349.370628) (xy 283.755673 -349.312762) (xy 283.700761 -349.24939)
			(xy 283.652122 -349.181084) (xy 283.610196 -349.108465) (xy 283.575362 -349.032189) (xy 283.547937 -348.952948)
			(xy 283.528168 -348.871458) (xy 283.516234 -348.788458) (xy 283.512244 -348.7047) (xy 280.018945 -348.7047)
			(xy 280.022321 -348.741025) (xy 280.022808 -348.782132) (xy 280.022242 -348.826902) (xy 280.013233 -348.915987)
			(xy 279.995329 -349.003718) (xy 279.968711 -349.089209) (xy 279.951688 -349.13062) (xy 279.948104 -349.140205)
			(xy 279.948115 -349.160653) (xy 279.951688 -349.170244) (xy 279.968711 -349.211656) (xy 279.995347 -349.297143)
			(xy 280.013256 -349.384874) (xy 280.022254 -349.473962) (xy 280.022808 -349.518732) (xy 280.022242 -349.563502)
			(xy 280.013233 -349.652587) (xy 279.995329 -349.740318) (xy 279.968711 -349.825809) (xy 279.951688 -349.86722)
			(xy 279.948104 -349.876805) (xy 279.948115 -349.897253) (xy 279.951688 -349.906844) (xy 279.968711 -349.948256)
			(xy 279.995347 -350.033743) (xy 280.013256 -350.121474) (xy 280.022254 -350.210562) (xy 280.022808 -350.255332)
			(xy 280.022378 -350.296443) (xy 280.014787 -350.378314) (xy 279.999674 -350.459136) (xy 279.977166 -350.538217)
			(xy 279.947457 -350.614885) (xy 279.910799 -350.688483) (xy 279.867506 -350.758385) (xy 279.817947 -350.823993)
			(xy 279.762545 -350.884747) (xy 279.701772 -350.94013) (xy 279.636148 -350.989668) (xy 279.566233 -351.032938)
			(xy 279.492623 -351.069572) (xy 279.415946 -351.099257) (xy 279.336857 -351.121739) (xy 279.256031 -351.136827)
			(xy 279.174157 -351.144391) (xy 279.133046 -351.14484) (xy 279.091442 -351.14437) (xy 279.008594 -351.136637)
			(xy 278.926829 -351.121206) (xy 278.846862 -351.098211) (xy 278.769389 -351.067854) (xy 278.695088 -351.0304)
			(xy 278.65959 -351.008696) (xy 278.650458 -351.003521) (xy 278.629738 -351.00031) (xy 278.609461 -351.005649)
			(xy 278.600916 -351.011744) (xy 278.567266 -351.037664) (xy 278.495892 -351.083723) (xy 278.420453 -351.12277)
			(xy 278.341637 -351.15445) (xy 278.26016 -351.178473) (xy 278.176764 -351.194623) (xy 278.092208 -351.20275)
			(xy 278.049736 -351.20326) (xy 278.049482 -351.20326) (xy 278.008375 -351.202805) (xy 277.926511 -351.195219)
			(xy 277.845697 -351.180113) (xy 277.76662 -351.157617) (xy 277.689956 -351.127921) (xy 277.616359 -351.09128)
			(xy 277.546455 -351.048006) (xy 277.480841 -350.998468) (xy 277.420077 -350.943088) (xy 277.364682 -350.882339)
			(xy 277.315126 -350.816738) (xy 277.271833 -350.746846) (xy 277.235173 -350.673258) (xy 277.205458 -350.596602)
			(xy 277.182941 -350.517531) (xy 277.167814 -350.43672) (xy 277.160206 -350.354859) (xy 277.15972 -350.313752)
			(xy 277.160279 -350.268982) (xy 277.16929 -350.179897) (xy 277.187196 -350.092166) (xy 277.213816 -350.006675)
			(xy 277.23084 -349.965264) (xy 277.234432 -349.955681) (xy 277.234415 -349.935231) (xy 277.23084 -349.92564)
			(xy 277.213836 -349.884289) (xy 277.187225 -349.798927) (xy 277.169318 -349.711324) (xy 277.160296 -349.622367)
			(xy 277.15972 -349.57766) (xy 277.15972 -349.576644) (xy 277.159974 -349.565214) (xy 277.133495 -349.559269)
			(xy 277.08126 -349.544526) (xy 277.05558 -349.53575) (xy 277.047383 -349.533236) (xy 277.030249 -349.533236)
			(xy 277.022052 -349.53575) (xy 276.986836 -349.547697) (xy 276.914826 -349.566284) (xy 276.841503 -349.578724)
			(xy 276.767392 -349.584928) (xy 276.730206 -349.58528) (xy 276.693022 -349.584911) (xy 276.618914 -349.578689)
			(xy 276.545594 -349.566246) (xy 276.473583 -349.547672) (xy 276.43836 -349.53575) (xy 276.430163 -349.533236)
			(xy 276.413029 -349.533236) (xy 276.404832 -349.53575) (xy 276.36973 -349.547637) (xy 276.297974 -349.566187)
			(xy 276.224911 -349.578634) (xy 276.15106 -349.584887) (xy 276.114002 -349.58528) (xy 276.112986 -349.58528)
			(xy 276.071059 -349.584857) (xy 275.987586 -349.576885) (xy 275.905248 -349.561014) (xy 275.824792 -349.537389)
			(xy 275.746946 -349.506223) (xy 275.672414 -349.467798) (xy 275.601873 -349.422463) (xy 275.53596 -349.370628)
			(xy 275.475273 -349.312762) (xy 275.420361 -349.24939) (xy 275.371722 -349.181084) (xy 275.329796 -349.108465)
			(xy 275.294962 -349.032189) (xy 275.267537 -348.952948) (xy 275.247768 -348.871458) (xy 275.235834 -348.788458)
			(xy 275.231844 -348.7047) (xy 85.721282 -348.7047) (xy 85.724562 -348.719921) (xy 85.734552 -348.813881)
			(xy 85.73516 -348.861126) (xy 85.734613 -348.906766) (xy 85.725307 -348.997569) (xy 85.706754 -349.086942)
			(xy 85.693504 -349.13062) (xy 85.691044 -349.139629) (xy 85.692095 -349.15826) (xy 85.695536 -349.166942)
			(xy 85.714247 -349.210016) (xy 85.743525 -349.299254) (xy 85.763232 -349.391081) (xy 85.77315 -349.484473)
			(xy 85.773768 -349.531432) (xy 85.77323 -349.574377) (xy 85.764932 -349.659867) (xy 85.748446 -349.744161)
			(xy 85.723925 -349.826477) (xy 85.708236 -349.866458) (xy 85.704966 -349.875707) (xy 85.704968 -349.895308)
			(xy 85.708236 -349.904558) (xy 85.723959 -349.944561) (xy 85.748521 -350.026936) (xy 85.765013 -350.111298)
			(xy 85.773281 -350.196858) (xy 85.773768 -350.239838) (xy 85.773264 -350.282199) (xy 85.765211 -350.366536)
			(xy 85.749177 -350.449726) (xy 85.725309 -350.531016) (xy 85.693821 -350.609668) (xy 85.654999 -350.684971)
			(xy 85.609196 -350.756243) (xy 85.556825 -350.822839) (xy 85.49836 -350.884154) (xy 85.434332 -350.939635)
			(xy 85.36532 -350.988778) (xy 85.29195 -351.031138) (xy 85.214885 -351.066333) (xy 85.134823 -351.094042)
			(xy 85.05249 -351.114016) (xy 84.968631 -351.126073) (xy 84.884006 -351.130105) (xy 84.799381 -351.126073)
			(xy 84.715522 -351.114016) (xy 84.633189 -351.094042) (xy 84.553127 -351.066333) (xy 84.476062 -351.031138)
			(xy 84.402692 -350.988778) (xy 84.33368 -350.939635) (xy 84.269652 -350.884154) (xy 84.211187 -350.822839)
			(xy 84.158816 -350.756243) (xy 84.113013 -350.684971) (xy 84.074191 -350.609668) (xy 84.042703 -350.531016)
			(xy 84.018835 -350.449726) (xy 84.002801 -350.366536) (xy 83.994748 -350.282199) (xy 83.994244 -350.239838)
			(xy 83.994769 -350.196861) (xy 84.003053 -350.111306) (xy 84.01954 -350.026947) (xy 84.044076 -349.944568)
			(xy 84.059776 -349.904558) (xy 84.063037 -349.895306) (xy 84.06304 -349.875708) (xy 84.059776 -349.866458)
			(xy 84.044053 -349.826489) (xy 84.019511 -349.744174) (xy 84.003027 -349.659876) (xy 83.994754 -349.57438)
			(xy 83.994244 -349.531432) (xy 83.994855 -349.485787) (xy 84.004246 -349.394981) (xy 84.022872 -349.305612)
			(xy 84.036154 -349.261938) (xy 84.038586 -349.252923) (xy 84.037555 -349.234298) (xy 84.034122 -349.225616)
			(xy 84.015469 -349.182525) (xy 83.98626 -349.093282) (xy 83.966612 -349.001459) (xy 83.956742 -348.908077)
			(xy 83.956144 -348.861126) (xy 83.073245 -348.861126) (xy 83.073748 -348.89948) (xy 83.073141 -348.945125)
			(xy 83.063748 -349.035931) (xy 83.045121 -349.1253) (xy 83.031838 -349.168974) (xy 83.0294 -349.177987)
			(xy 83.030435 -349.196614) (xy 83.03387 -349.205296) (xy 83.052527 -349.248385) (xy 83.081735 -349.337629)
			(xy 83.101382 -349.429453) (xy 83.111251 -349.522835) (xy 83.111848 -349.569786) (xy 83.111412 -349.610119)
			(xy 83.104141 -349.690457) (xy 83.08963 -349.769807) (xy 83.067997 -349.847519) (xy 83.039422 -349.922954)
			(xy 83.022186 -349.959422) (xy 83.017653 -349.970011) (xy 83.017661 -349.993024) (xy 83.022186 -350.003618)
			(xy 83.039397 -350.040069) (xy 83.067953 -350.115455) (xy 83.089579 -350.193114) (xy 83.104099 -350.27241)
			(xy 83.111393 -350.352693) (xy 83.111848 -350.393) (xy 83.111344 -350.435361) (xy 83.103291 -350.519698)
			(xy 83.087257 -350.602888) (xy 83.063389 -350.684178) (xy 83.031901 -350.76283) (xy 82.993079 -350.838133)
			(xy 82.947276 -350.909405) (xy 82.894905 -350.976001) (xy 82.83644 -351.037316) (xy 82.772412 -351.092797)
			(xy 82.7034 -351.14194) (xy 82.63003 -351.1843) (xy 82.552965 -351.219495) (xy 82.472903 -351.247204)
			(xy 82.39057 -351.267178) (xy 82.306711 -351.279235) (xy 82.222086 -351.283267) (xy 82.137461 -351.279235)
			(xy 82.053602 -351.267178) (xy 81.971269 -351.247204) (xy 81.891207 -351.219495) (xy 81.814142 -351.1843)
			(xy 81.740772 -351.14194) (xy 81.67176 -351.092797) (xy 81.607732 -351.037316) (xy 81.549267 -350.976001)
			(xy 81.496896 -350.909405) (xy 81.451093 -350.838133) (xy 81.412271 -350.76283) (xy 81.380783 -350.684178)
			(xy 81.356915 -350.602888) (xy 81.340881 -350.519698) (xy 81.332828 -350.435361) (xy 81.332324 -350.393)
			(xy 81.332778 -350.35266) (xy 81.340081 -350.272312) (xy 81.354637 -350.192956) (xy 81.376326 -350.115246)
			(xy 81.404968 -350.039822) (xy 81.42224 -350.003364) (xy 81.426812 -349.992711) (xy 81.426828 -349.969558)
			(xy 81.42224 -349.958914) (xy 81.405059 -349.922483) (xy 81.376548 -349.847143) (xy 81.35497 -349.769534)
			(xy 81.340501 -349.69029) (xy 81.33326 -349.610063) (xy 81.332832 -349.569786) (xy 81.333382 -349.524146)
			(xy 81.342687 -349.433343) (xy 81.361239 -349.34397) (xy 81.374488 -349.300292) (xy 81.376942 -349.291282)
			(xy 81.375896 -349.272652) (xy 81.372456 -349.26397) (xy 81.353748 -349.220894) (xy 81.32447 -349.131657)
			(xy 81.304762 -349.039831) (xy 81.294843 -348.946439) (xy 81.294224 -348.89948) (xy 66.467942 -348.89948)
			(xy 66.465784 -348.920813) (xy 66.447878 -349.008544) (xy 66.421259 -349.094035) (xy 66.404236 -349.135446)
			(xy 66.400697 -349.145044) (xy 66.400681 -349.16548) (xy 66.404236 -349.17507) (xy 66.421263 -349.21648)
			(xy 66.4479 -349.301967) (xy 66.465806 -349.3897) (xy 66.474803 -349.478787) (xy 66.475356 -349.523558)
			(xy 66.474795 -349.568328) (xy 66.465784 -349.657413) (xy 66.447878 -349.745144) (xy 66.421259 -349.830635)
			(xy 66.404236 -349.872046) (xy 66.400697 -349.881644) (xy 66.400681 -349.90208) (xy 66.404236 -349.91167)
			(xy 66.421263 -349.95308) (xy 66.4479 -350.038567) (xy 66.465806 -350.1263) (xy 66.474803 -350.215387)
			(xy 66.475356 -350.260158) (xy 66.474861 -350.301272) (xy 66.467278 -350.383151) (xy 66.452172 -350.46398)
			(xy 66.429672 -350.54307) (xy 66.39997 -350.619748) (xy 66.36332 -350.693357) (xy 66.320034 -350.76327)
			(xy 66.270482 -350.828891) (xy 66.215086 -350.88966) (xy 66.154319 -350.945059) (xy 66.0887 -350.994614)
			(xy 66.018788 -351.037902) (xy 65.94518 -351.074555) (xy 65.868505 -351.10426) (xy 65.789415 -351.126764)
			(xy 65.708586 -351.141873) (xy 65.626708 -351.14946) (xy 65.585594 -351.14992) (xy 65.543984 -351.149442)
			(xy 65.461127 -351.141665) (xy 65.379358 -351.12619) (xy 65.299391 -351.10315) (xy 65.221922 -351.072748)
			(xy 65.147629 -351.035248) (xy 65.112138 -351.013522) (xy 65.10303 -351.008297) (xy 65.082293 -351.005101)
			(xy 65.062008 -351.010462) (xy 65.053464 -351.01657) (xy 65.019831 -351.042555) (xy 64.948437 -351.08868)
			(xy 64.872967 -351.127782) (xy 64.79411 -351.159503) (xy 64.712585 -351.183553) (xy 64.629138 -351.199714)
			(xy 64.544529 -351.207838) (xy 64.50203 -351.20834) (xy 64.460915 -351.207873) (xy 64.379035 -351.200288)
			(xy 64.298205 -351.185181) (xy 64.219114 -351.162679) (xy 64.142436 -351.132976) (xy 64.068826 -351.096324)
			(xy 63.998912 -351.053036) (xy 63.93329 -351.003482) (xy 63.872521 -350.948084) (xy 63.817123 -350.887316)
			(xy 63.767568 -350.821695) (xy 63.72428 -350.751781) (xy 63.687628 -350.678172) (xy 63.657923 -350.601494)
			(xy 63.635421 -350.522403) (xy 63.620313 -350.441573) (xy 63.612727 -350.359693) (xy 63.612268 -350.318578)
			(xy 63.61284 -350.273809) (xy 63.621847 -350.184724) (xy 63.63975 -350.096993) (xy 63.666366 -350.011501)
			(xy 63.683388 -349.97009) (xy 63.686968 -349.960503) (xy 63.68696 -349.940056) (xy 63.683388 -349.930466)
			(xy 63.666363 -349.889123) (xy 63.639757 -349.803758) (xy 63.621856 -349.716153) (xy 63.612841 -349.627193)
			(xy 63.612268 -349.582486) (xy 63.612268 -349.58147) (xy 63.612522 -349.57004) (xy 63.586044 -349.564091)
			(xy 63.533809 -349.54935) (xy 63.508128 -349.540576) (xy 63.499931 -349.538062) (xy 63.482797 -349.538062)
			(xy 63.4746 -349.540576) (xy 63.43938 -349.552528) (xy 63.367379 -349.571185) (xy 63.294059 -349.583696)
			(xy 63.219944 -349.589972) (xy 63.182754 -349.59036) (xy 63.145565 -349.589952) (xy 63.071452 -349.583667)
			(xy 62.998133 -349.571163) (xy 62.926126 -349.552528) (xy 62.890908 -349.540576) (xy 62.882711 -349.538062)
			(xy 62.865577 -349.538062) (xy 62.85738 -349.540576) (xy 62.822162 -349.552533) (xy 62.75016 -349.571189)
			(xy 62.676839 -349.583699) (xy 62.602724 -349.589973) (xy 62.565534 -349.59036) (xy 62.523594 -349.589902)
			(xy 62.440094 -349.581932) (xy 62.35773 -349.566061) (xy 62.277248 -349.542432) (xy 62.199376 -349.511259)
			(xy 62.12482 -349.472825) (xy 62.054255 -349.427478) (xy 61.98832 -349.375629) (xy 61.927613 -349.317747)
			(xy 61.872683 -349.254356) (xy 61.824027 -349.186031) (xy 61.782086 -349.11339) (xy 61.74724 -349.037091)
			(xy 61.719806 -348.957825) (xy 61.70003 -348.87631) (xy 61.688092 -348.793284) (xy 61.684101 -348.7095)
			(xy 58.14031 -348.7095) (xy 58.143679 -348.745845) (xy 58.144156 -348.786958) (xy 58.143595 -348.831728)
			(xy 58.134584 -348.920813) (xy 58.116678 -349.008544) (xy 58.090059 -349.094035) (xy 58.073036 -349.135446)
			(xy 58.069497 -349.145044) (xy 58.069481 -349.16548) (xy 58.073036 -349.17507) (xy 58.090063 -349.21648)
			(xy 58.1167 -349.301967) (xy 58.134606 -349.3897) (xy 58.143603 -349.478787) (xy 58.144156 -349.523558)
			(xy 58.143595 -349.568328) (xy 58.134584 -349.657413) (xy 58.116678 -349.745144) (xy 58.090059 -349.830635)
			(xy 58.073036 -349.872046) (xy 58.069497 -349.881644) (xy 58.069481 -349.90208) (xy 58.073036 -349.91167)
			(xy 58.090063 -349.95308) (xy 58.1167 -350.038567) (xy 58.134606 -350.1263) (xy 58.143603 -350.215387)
			(xy 58.144156 -350.260158) (xy 58.143661 -350.301272) (xy 58.136078 -350.383151) (xy 58.120972 -350.46398)
			(xy 58.098472 -350.54307) (xy 58.06877 -350.619748) (xy 58.03212 -350.693357) (xy 57.988834 -350.76327)
			(xy 57.939282 -350.828891) (xy 57.883886 -350.88966) (xy 57.823119 -350.945059) (xy 57.7575 -350.994614)
			(xy 57.687588 -351.037902) (xy 57.61398 -351.074555) (xy 57.537305 -351.10426) (xy 57.458215 -351.126764)
			(xy 57.377386 -351.141873) (xy 57.295508 -351.14946) (xy 57.254394 -351.14992) (xy 57.212784 -351.149442)
			(xy 57.129927 -351.141665) (xy 57.048158 -351.12619) (xy 56.968191 -351.10315) (xy 56.890722 -351.072748)
			(xy 56.816429 -351.035248) (xy 56.780938 -351.013522) (xy 56.77183 -351.008297) (xy 56.751093 -351.005101)
			(xy 56.730808 -351.010462) (xy 56.722264 -351.01657) (xy 56.688631 -351.042555) (xy 56.617237 -351.08868)
			(xy 56.541767 -351.127782) (xy 56.46291 -351.159503) (xy 56.381385 -351.183553) (xy 56.297938 -351.199714)
			(xy 56.213329 -351.207838) (xy 56.17083 -351.20834) (xy 56.129715 -351.207873) (xy 56.047835 -351.200288)
			(xy 55.967005 -351.185181) (xy 55.887914 -351.162679) (xy 55.811236 -351.132976) (xy 55.737626 -351.096324)
			(xy 55.667712 -351.053036) (xy 55.60209 -351.003482) (xy 55.541321 -350.948084) (xy 55.485923 -350.887316)
			(xy 55.436368 -350.821695) (xy 55.39308 -350.751781) (xy 55.356428 -350.678172) (xy 55.326723 -350.601494)
			(xy 55.304221 -350.522403) (xy 55.289113 -350.441573) (xy 55.281527 -350.359693) (xy 55.281068 -350.318578)
			(xy 55.28164 -350.273809) (xy 55.290647 -350.184724) (xy 55.30855 -350.096993) (xy 55.335166 -350.011501)
			(xy 55.352188 -349.97009) (xy 55.355768 -349.960503) (xy 55.35576 -349.940056) (xy 55.352188 -349.930466)
			(xy 55.335163 -349.889123) (xy 55.308557 -349.803758) (xy 55.290656 -349.716153) (xy 55.281641 -349.627193)
			(xy 55.281068 -349.582486) (xy 55.281068 -349.58147) (xy 55.281322 -349.57004) (xy 55.254844 -349.564091)
			(xy 55.202609 -349.54935) (xy 55.176928 -349.540576) (xy 55.168731 -349.538062) (xy 55.151597 -349.538062)
			(xy 55.1434 -349.540576) (xy 55.10818 -349.552528) (xy 55.036179 -349.571185) (xy 54.962859 -349.583696)
			(xy 54.888744 -349.589972) (xy 54.851554 -349.59036) (xy 54.814365 -349.589952) (xy 54.740252 -349.583667)
			(xy 54.666933 -349.571163) (xy 54.594926 -349.552528) (xy 54.559708 -349.540576) (xy 54.551511 -349.538062)
			(xy 54.534377 -349.538062) (xy 54.52618 -349.540576) (xy 54.490962 -349.552533) (xy 54.41896 -349.571189)
			(xy 54.345639 -349.583699) (xy 54.271524 -349.589973) (xy 54.234334 -349.59036) (xy 54.192394 -349.589902)
			(xy 54.108894 -349.581932) (xy 54.02653 -349.566061) (xy 53.946048 -349.542432) (xy 53.868176 -349.511259)
			(xy 53.79362 -349.472825) (xy 53.723055 -349.427478) (xy 53.65712 -349.375629) (xy 53.596413 -349.317747)
			(xy 53.541483 -349.254356) (xy 53.492827 -349.186031) (xy 53.450886 -349.11339) (xy 53.41604 -349.037091)
			(xy 53.388606 -348.957825) (xy 53.36883 -348.87631) (xy 53.356892 -348.793284) (xy 53.352901 -348.7095)
			(xy 49.78371 -348.7095) (xy 49.787079 -348.745845) (xy 49.787556 -348.786958) (xy 49.786995 -348.831728)
			(xy 49.777984 -348.920813) (xy 49.760078 -349.008544) (xy 49.733459 -349.094035) (xy 49.716436 -349.135446)
			(xy 49.712897 -349.145044) (xy 49.712881 -349.16548) (xy 49.716436 -349.17507) (xy 49.733463 -349.21648)
			(xy 49.7601 -349.301967) (xy 49.778006 -349.3897) (xy 49.787003 -349.478787) (xy 49.787556 -349.523558)
			(xy 49.786995 -349.568328) (xy 49.777984 -349.657413) (xy 49.760078 -349.745144) (xy 49.733459 -349.830635)
			(xy 49.716436 -349.872046) (xy 49.712897 -349.881644) (xy 49.712881 -349.90208) (xy 49.716436 -349.91167)
			(xy 49.733463 -349.95308) (xy 49.7601 -350.038567) (xy 49.778006 -350.1263) (xy 49.787003 -350.215387)
			(xy 49.787556 -350.260158) (xy 49.787061 -350.301272) (xy 49.779478 -350.383151) (xy 49.764372 -350.46398)
			(xy 49.741872 -350.54307) (xy 49.71217 -350.619748) (xy 49.67552 -350.693357) (xy 49.632234 -350.76327)
			(xy 49.582682 -350.828891) (xy 49.527286 -350.88966) (xy 49.466519 -350.945059) (xy 49.4009 -350.994614)
			(xy 49.330988 -351.037902) (xy 49.25738 -351.074555) (xy 49.180705 -351.10426) (xy 49.101615 -351.126764)
			(xy 49.020786 -351.141873) (xy 48.938908 -351.14946) (xy 48.897794 -351.14992) (xy 48.856184 -351.149442)
			(xy 48.773327 -351.141665) (xy 48.691558 -351.12619) (xy 48.611591 -351.10315) (xy 48.534122 -351.072748)
			(xy 48.459829 -351.035248) (xy 48.424338 -351.013522) (xy 48.41523 -351.008297) (xy 48.394493 -351.005101)
			(xy 48.374208 -351.010462) (xy 48.365664 -351.01657) (xy 48.332031 -351.042555) (xy 48.260637 -351.08868)
			(xy 48.185167 -351.127782) (xy 48.10631 -351.159503) (xy 48.024785 -351.183553) (xy 47.941338 -351.199714)
			(xy 47.856729 -351.207838) (xy 47.81423 -351.20834) (xy 47.773115 -351.207873) (xy 47.691235 -351.200288)
			(xy 47.610405 -351.185181) (xy 47.531314 -351.162679) (xy 47.454636 -351.132976) (xy 47.381026 -351.096324)
			(xy 47.311112 -351.053036) (xy 47.24549 -351.003482) (xy 47.184721 -350.948084) (xy 47.129323 -350.887316)
			(xy 47.079768 -350.821695) (xy 47.03648 -350.751781) (xy 46.999828 -350.678172) (xy 46.970123 -350.601494)
			(xy 46.947621 -350.522403) (xy 46.932513 -350.441573) (xy 46.924927 -350.359693) (xy 46.924468 -350.318578)
			(xy 46.92504 -350.273809) (xy 46.934047 -350.184724) (xy 46.95195 -350.096993) (xy 46.978566 -350.011501)
			(xy 46.995588 -349.97009) (xy 46.999168 -349.960503) (xy 46.99916 -349.940056) (xy 46.995588 -349.930466)
			(xy 46.978563 -349.889123) (xy 46.951957 -349.803758) (xy 46.934056 -349.716153) (xy 46.925041 -349.627193)
			(xy 46.924468 -349.582486) (xy 46.924468 -349.58147) (xy 46.924722 -349.57004) (xy 46.898244 -349.564091)
			(xy 46.846009 -349.54935) (xy 46.820328 -349.540576) (xy 46.812131 -349.538062) (xy 46.794997 -349.538062)
			(xy 46.7868 -349.540576) (xy 46.75158 -349.552528) (xy 46.679579 -349.571185) (xy 46.606259 -349.583696)
			(xy 46.532144 -349.589972) (xy 46.494954 -349.59036) (xy 46.457765 -349.589952) (xy 46.383652 -349.583667)
			(xy 46.310333 -349.571163) (xy 46.238326 -349.552528) (xy 46.203108 -349.540576) (xy 46.194911 -349.538062)
			(xy 46.177777 -349.538062) (xy 46.16958 -349.540576) (xy 46.134362 -349.552533) (xy 46.06236 -349.571189)
			(xy 45.989039 -349.583699) (xy 45.914924 -349.589973) (xy 45.877734 -349.59036) (xy 45.835794 -349.589902)
			(xy 45.752294 -349.581932) (xy 45.66993 -349.566061) (xy 45.589448 -349.542432) (xy 45.511576 -349.511259)
			(xy 45.43702 -349.472825) (xy 45.366455 -349.427478) (xy 45.30052 -349.375629) (xy 45.239813 -349.317747)
			(xy 45.184883 -349.254356) (xy 45.136227 -349.186031) (xy 45.094286 -349.11339) (xy 45.05944 -349.037091)
			(xy 45.032006 -348.957825) (xy 45.01223 -348.87631) (xy 45.000292 -348.793284) (xy 44.996301 -348.7095)
			(xy 41.47791 -348.7095) (xy 41.481279 -348.745845) (xy 41.481756 -348.786958) (xy 41.481195 -348.831728)
			(xy 41.472184 -348.920813) (xy 41.454278 -349.008544) (xy 41.427659 -349.094035) (xy 41.410636 -349.135446)
			(xy 41.407097 -349.145044) (xy 41.407081 -349.16548) (xy 41.410636 -349.17507) (xy 41.427663 -349.21648)
			(xy 41.4543 -349.301967) (xy 41.472206 -349.3897) (xy 41.481203 -349.478787) (xy 41.481756 -349.523558)
			(xy 41.481195 -349.568328) (xy 41.472184 -349.657413) (xy 41.454278 -349.745144) (xy 41.427659 -349.830635)
			(xy 41.410636 -349.872046) (xy 41.407097 -349.881644) (xy 41.407081 -349.90208) (xy 41.410636 -349.91167)
			(xy 41.427663 -349.95308) (xy 41.4543 -350.038567) (xy 41.472206 -350.1263) (xy 41.481203 -350.215387)
			(xy 41.481756 -350.260158) (xy 41.481261 -350.301272) (xy 41.473678 -350.383151) (xy 41.458572 -350.46398)
			(xy 41.436072 -350.54307) (xy 41.40637 -350.619748) (xy 41.36972 -350.693357) (xy 41.326434 -350.76327)
			(xy 41.276882 -350.828891) (xy 41.221486 -350.88966) (xy 41.160719 -350.945059) (xy 41.0951 -350.994614)
			(xy 41.025188 -351.037902) (xy 40.95158 -351.074555) (xy 40.874905 -351.10426) (xy 40.795815 -351.126764)
			(xy 40.714986 -351.141873) (xy 40.633108 -351.14946) (xy 40.591994 -351.14992) (xy 40.550384 -351.149442)
			(xy 40.467527 -351.141665) (xy 40.385758 -351.12619) (xy 40.305791 -351.10315) (xy 40.228322 -351.072748)
			(xy 40.154029 -351.035248) (xy 40.118538 -351.013522) (xy 40.10943 -351.008297) (xy 40.088693 -351.005101)
			(xy 40.068408 -351.010462) (xy 40.059864 -351.01657) (xy 40.026231 -351.042555) (xy 39.954837 -351.08868)
			(xy 39.879367 -351.127782) (xy 39.80051 -351.159503) (xy 39.718985 -351.183553) (xy 39.635538 -351.199714)
			(xy 39.550929 -351.207838) (xy 39.50843 -351.20834) (xy 39.467315 -351.207873) (xy 39.385435 -351.200288)
			(xy 39.304605 -351.185181) (xy 39.225514 -351.162679) (xy 39.148836 -351.132976) (xy 39.075226 -351.096324)
			(xy 39.005312 -351.053036) (xy 38.93969 -351.003482) (xy 38.878921 -350.948084) (xy 38.823523 -350.887316)
			(xy 38.773968 -350.821695) (xy 38.73068 -350.751781) (xy 38.694028 -350.678172) (xy 38.664323 -350.601494)
			(xy 38.641821 -350.522403) (xy 38.626713 -350.441573) (xy 38.619127 -350.359693) (xy 38.618668 -350.318578)
			(xy 38.61924 -350.273809) (xy 38.628247 -350.184724) (xy 38.64615 -350.096993) (xy 38.672766 -350.011501)
			(xy 38.689788 -349.97009) (xy 38.693368 -349.960503) (xy 38.69336 -349.940056) (xy 38.689788 -349.930466)
			(xy 38.672763 -349.889123) (xy 38.646157 -349.803758) (xy 38.628256 -349.716153) (xy 38.619241 -349.627193)
			(xy 38.618668 -349.582486) (xy 38.618668 -349.58147) (xy 38.618922 -349.57004) (xy 38.592444 -349.564091)
			(xy 38.540209 -349.54935) (xy 38.514528 -349.540576) (xy 38.506331 -349.538062) (xy 38.489197 -349.538062)
			(xy 38.481 -349.540576) (xy 38.44578 -349.552528) (xy 38.373779 -349.571185) (xy 38.300459 -349.583696)
			(xy 38.226344 -349.589972) (xy 38.189154 -349.59036) (xy 38.151965 -349.589952) (xy 38.077852 -349.583667)
			(xy 38.004533 -349.571163) (xy 37.932526 -349.552528) (xy 37.897308 -349.540576) (xy 37.889111 -349.538062)
			(xy 37.871977 -349.538062) (xy 37.86378 -349.540576) (xy 37.828562 -349.552533) (xy 37.75656 -349.571189)
			(xy 37.683239 -349.583699) (xy 37.609124 -349.589973) (xy 37.571934 -349.59036) (xy 37.529996 -349.589881)
			(xy 37.446499 -349.581908) (xy 37.364138 -349.566035) (xy 37.283659 -349.542404) (xy 37.20579 -349.511231)
			(xy 37.131238 -349.472797) (xy 37.060676 -349.42745) (xy 36.994745 -349.375601) (xy 36.93404 -349.317719)
			(xy 36.879112 -349.25433) (xy 36.830459 -349.186006) (xy 36.788521 -349.113367) (xy 36.753677 -349.03707)
			(xy 36.726244 -348.957807) (xy 36.706469 -348.876294) (xy 36.694532 -348.793272) (xy 36.690541 -348.70949)
			(xy 33.197509 -348.70949) (xy 33.200879 -348.745845) (xy 33.201356 -348.786958) (xy 33.200795 -348.831728)
			(xy 33.191784 -348.920813) (xy 33.173878 -349.008544) (xy 33.147259 -349.094035) (xy 33.130236 -349.135446)
			(xy 33.126697 -349.145044) (xy 33.126681 -349.16548) (xy 33.130236 -349.17507) (xy 33.147263 -349.21648)
			(xy 33.1739 -349.301967) (xy 33.191806 -349.3897) (xy 33.200803 -349.478787) (xy 33.201356 -349.523558)
			(xy 33.200795 -349.568328) (xy 33.191784 -349.657413) (xy 33.173878 -349.745144) (xy 33.147259 -349.830635)
			(xy 33.130236 -349.872046) (xy 33.126697 -349.881644) (xy 33.126681 -349.90208) (xy 33.130236 -349.91167)
			(xy 33.147263 -349.95308) (xy 33.1739 -350.038567) (xy 33.191806 -350.1263) (xy 33.200803 -350.215387)
			(xy 33.201356 -350.260158) (xy 33.200861 -350.301272) (xy 33.193278 -350.383151) (xy 33.178172 -350.46398)
			(xy 33.155672 -350.54307) (xy 33.12597 -350.619748) (xy 33.08932 -350.693357) (xy 33.046034 -350.76327)
			(xy 32.996482 -350.828891) (xy 32.941086 -350.88966) (xy 32.880319 -350.945059) (xy 32.8147 -350.994614)
			(xy 32.744788 -351.037902) (xy 32.67118 -351.074555) (xy 32.594505 -351.10426) (xy 32.515415 -351.126764)
			(xy 32.434586 -351.141873) (xy 32.352708 -351.14946) (xy 32.311594 -351.14992) (xy 32.269984 -351.149442)
			(xy 32.187127 -351.141665) (xy 32.105358 -351.12619) (xy 32.025391 -351.10315) (xy 31.947922 -351.072748)
			(xy 31.873629 -351.035248) (xy 31.838138 -351.013522) (xy 31.82903 -351.008297) (xy 31.808293 -351.005101)
			(xy 31.788008 -351.010462) (xy 31.779464 -351.01657) (xy 31.745831 -351.042555) (xy 31.674437 -351.08868)
			(xy 31.598967 -351.127782) (xy 31.52011 -351.159503) (xy 31.438585 -351.183553) (xy 31.355138 -351.199714)
			(xy 31.270529 -351.207838) (xy 31.22803 -351.20834) (xy 31.186915 -351.207873) (xy 31.105035 -351.200288)
			(xy 31.024205 -351.185181) (xy 30.945114 -351.162679) (xy 30.868436 -351.132976) (xy 30.794826 -351.096324)
			(xy 30.724912 -351.053036) (xy 30.65929 -351.003482) (xy 30.598521 -350.948084) (xy 30.543123 -350.887316)
			(xy 30.493568 -350.821695) (xy 30.45028 -350.751781) (xy 30.413628 -350.678172) (xy 30.383923 -350.601494)
			(xy 30.361421 -350.522403) (xy 30.346313 -350.441573) (xy 30.338727 -350.359693) (xy 30.338268 -350.318578)
			(xy 30.33884 -350.273809) (xy 30.347847 -350.184724) (xy 30.36575 -350.096993) (xy 30.392366 -350.011501)
			(xy 30.409388 -349.97009) (xy 30.412968 -349.960503) (xy 30.41296 -349.940056) (xy 30.409388 -349.930466)
			(xy 30.392363 -349.889123) (xy 30.365757 -349.803758) (xy 30.347856 -349.716153) (xy 30.338841 -349.627193)
			(xy 30.338268 -349.582486) (xy 30.338268 -349.58147) (xy 30.338522 -349.57004) (xy 30.312044 -349.564091)
			(xy 30.259809 -349.54935) (xy 30.234128 -349.540576) (xy 30.225931 -349.538062) (xy 30.208797 -349.538062)
			(xy 30.2006 -349.540576) (xy 30.16538 -349.552528) (xy 30.093379 -349.571185) (xy 30.020059 -349.583696)
			(xy 29.945944 -349.589972) (xy 29.908754 -349.59036) (xy 29.871565 -349.589952) (xy 29.797452 -349.583667)
			(xy 29.724133 -349.571163) (xy 29.652126 -349.552528) (xy 29.616908 -349.540576) (xy 29.608711 -349.538062)
			(xy 29.591577 -349.538062) (xy 29.58338 -349.540576) (xy 29.548162 -349.552533) (xy 29.47616 -349.571189)
			(xy 29.402839 -349.583699) (xy 29.328724 -349.589973) (xy 29.291534 -349.59036) (xy 29.249596 -349.589881)
			(xy 29.166099 -349.581908) (xy 29.083738 -349.566035) (xy 29.003259 -349.542404) (xy 28.92539 -349.511231)
			(xy 28.850838 -349.472797) (xy 28.780276 -349.42745) (xy 28.714345 -349.375601) (xy 28.65364 -349.317719)
			(xy 28.598712 -349.25433) (xy 28.550059 -349.186006) (xy 28.508121 -349.113367) (xy 28.473277 -349.03707)
			(xy 28.445844 -348.957807) (xy 28.426069 -348.876294) (xy 28.414132 -348.793272) (xy 28.410141 -348.70949)
			(xy 2.509012 -348.70949) (xy 2.509012 -351.637854) (xy 73.92162 -351.637854) (xy 73.922073 -351.597287)
			(xy 73.929469 -351.516491) (xy 73.944194 -351.436705) (xy 73.966127 -351.358593) (xy 73.995085 -351.282803)
			(xy 74.012552 -351.246186) (xy 74.016468 -351.237096) (xy 74.017766 -351.217362) (xy 74.015092 -351.207832)
			(xy 74.000912 -351.162806) (xy 73.981012 -351.070523) (xy 73.971009 -350.97665) (xy 73.970388 -350.929448)
			(xy 73.970892 -350.887087) (xy 73.978945 -350.80275) (xy 73.994979 -350.71956) (xy 74.018847 -350.63827)
			(xy 74.050335 -350.559618) (xy 74.089157 -350.484315) (xy 74.13496 -350.413043) (xy 74.187331 -350.346447)
			(xy 74.245796 -350.285132) (xy 74.309824 -350.229651) (xy 74.378836 -350.180508) (xy 74.452206 -350.138148)
			(xy 74.529271 -350.102953) (xy 74.609333 -350.075244) (xy 74.691666 -350.05527) (xy 74.775525 -350.043213)
			(xy 74.86015 -350.039182) (xy 74.944775 -350.043213) (xy 75.028634 -350.05527) (xy 75.110967 -350.075244)
			(xy 75.191029 -350.102953) (xy 75.268094 -350.138148) (xy 75.341464 -350.180508) (xy 75.410476 -350.229651)
			(xy 75.474504 -350.285132) (xy 75.532969 -350.346447) (xy 75.58534 -350.413043) (xy 75.631143 -350.484315)
			(xy 75.669965 -350.559618) (xy 75.701453 -350.63827) (xy 75.725321 -350.71956) (xy 75.741355 -350.80275)
			(xy 75.749408 -350.887087) (xy 75.749912 -350.929448) (xy 75.749456 -350.970015) (xy 75.742061 -351.05081)
			(xy 75.727336 -351.130596) (xy 75.705403 -351.208709) (xy 75.676446 -351.284499) (xy 75.65898 -351.321116)
			(xy 75.655063 -351.330206) (xy 75.653765 -351.34994) (xy 75.65644 -351.35947) (xy 75.670621 -351.404496)
			(xy 75.69052 -351.496779) (xy 75.700524 -351.590652) (xy 75.70064 -351.5995) (xy 76.58354 -351.5995)
			(xy 76.583977 -351.558938) (xy 76.59131 -351.478148) (xy 76.605978 -351.398363) (xy 76.62786 -351.320247)
			(xy 76.656772 -351.244452) (xy 76.674218 -351.207832) (xy 76.67814 -351.198816) (xy 76.679575 -351.179224)
			(xy 76.677012 -351.169732) (xy 76.662856 -351.124831) (xy 76.642989 -351.0328) (xy 76.632962 -350.939185)
			(xy 76.632308 -350.89211) (xy 76.632308 -350.891094) (xy 76.632812 -350.848746) (xy 76.640863 -350.764432)
			(xy 76.656892 -350.681266) (xy 76.680753 -350.599999) (xy 76.712232 -350.521369) (xy 76.751043 -350.446088)
			(xy 76.796833 -350.374836) (xy 76.849189 -350.30826) (xy 76.907637 -350.246962) (xy 76.971647 -350.191497)
			(xy 77.040639 -350.142368) (xy 77.113989 -350.100019) (xy 77.191032 -350.064835) (xy 77.271071 -350.037133)
			(xy 77.35338 -350.017165) (xy 77.437215 -350.005112) (xy 77.521816 -350.001082) (xy 77.606417 -350.005112)
			(xy 77.690252 -350.017165) (xy 77.772561 -350.037133) (xy 77.8526 -350.064835) (xy 77.929643 -350.100019)
			(xy 78.002993 -350.142368) (xy 78.071985 -350.191497) (xy 78.135995 -350.246962) (xy 78.194443 -350.30826)
			(xy 78.246799 -350.374836) (xy 78.292589 -350.446088) (xy 78.3314 -350.521369) (xy 78.362879 -350.599999)
			(xy 78.38674 -350.681266) (xy 78.402769 -350.764432) (xy 78.41082 -350.848746) (xy 78.411324 -350.891094)
			(xy 78.411324 -350.891602) (xy 78.410897 -350.932113) (xy 78.403528 -351.0128) (xy 78.388844 -351.09248)
			(xy 78.366965 -351.170492) (xy 78.338074 -351.246189) (xy 78.320646 -351.282762) (xy 78.316728 -351.291779)
			(xy 78.315288 -351.31137) (xy 78.317852 -351.320862) (xy 78.33205 -351.365927) (xy 78.351954 -351.458296)
			(xy 78.361947 -351.552255) (xy 78.362556 -351.5995) (xy 78.362003 -351.645139) (xy 78.352699 -351.735943)
			(xy 78.334149 -351.825316) (xy 78.3209 -351.868994) (xy 78.318454 -351.878006) (xy 78.319496 -351.896634)
			(xy 78.322932 -351.905316) (xy 78.341634 -351.948394) (xy 78.370914 -352.03763) (xy 78.390624 -352.129456)
			(xy 78.400545 -352.222848) (xy 78.401164 -352.269806) (xy 78.400653 -352.312784) (xy 78.392364 -352.398339)
			(xy 78.375873 -352.482698) (xy 78.351334 -352.565076) (xy 78.335632 -352.605086) (xy 78.332346 -352.614331)
			(xy 78.332359 -352.633935) (xy 78.335632 -352.643186) (xy 78.351338 -352.683162) (xy 78.375884 -352.765474)
			(xy 78.392373 -352.84977) (xy 78.400651 -352.935265) (xy 78.401164 -352.978212) (xy 78.40066 -353.020573)
			(xy 78.392607 -353.10491) (xy 78.376573 -353.1881) (xy 78.352705 -353.26939) (xy 78.346936 -353.2838)
			(xy 182.729656 -353.2838) (xy 182.733646 -353.200045) (xy 182.745579 -353.117047) (xy 182.765347 -353.035561)
			(xy 182.792771 -352.956321) (xy 182.827603 -352.880048) (xy 182.869527 -352.807431) (xy 182.918163 -352.739127)
			(xy 182.973072 -352.675756) (xy 183.033756 -352.617891) (xy 183.099666 -352.566056) (xy 183.170204 -352.520721)
			(xy 183.244732 -352.482296) (xy 183.322575 -352.451129) (xy 183.403028 -352.427503) (xy 183.485362 -352.411631)
			(xy 183.568833 -352.403656) (xy 183.610758 -352.403156) (xy 183.611774 -352.403156) (xy 183.648831 -352.403571)
			(xy 183.72268 -352.409833) (xy 183.795742 -352.422272) (xy 183.867502 -352.440802) (xy 183.902604 -352.452686)
			(xy 183.910801 -352.4552) (xy 183.927935 -352.4552) (xy 183.936132 -352.452686) (xy 183.964337 -352.443048)
			(xy 184.021791 -352.42716) (xy 184.05094 -352.420936) (xy 184.060579 -352.41851) (xy 184.077071 -352.407448)
			(xy 184.088123 -352.390948) (xy 184.090564 -352.381312) (xy 184.100088 -352.337416) (xy 184.126813 -352.251655)
			(xy 184.143904 -352.210116) (xy 184.147468 -352.200525) (xy 184.147469 -352.180082) (xy 184.143904 -352.170492)
			(xy 184.126892 -352.12911) (xy 184.100271 -352.043685) (xy 184.082363 -351.956018) (xy 184.073351 -351.866996)
			(xy 184.072784 -351.822258) (xy 184.072784 -351.822004) (xy 184.073288 -351.779656) (xy 184.081339 -351.695342)
			(xy 184.097368 -351.612176) (xy 184.121229 -351.530909) (xy 184.152708 -351.452279) (xy 184.191519 -351.376998)
			(xy 184.237309 -351.305746) (xy 184.289665 -351.23917) (xy 184.348113 -351.177872) (xy 184.412123 -351.122407)
			(xy 184.481115 -351.073278) (xy 184.554465 -351.030929) (xy 184.631508 -350.995745) (xy 184.711547 -350.968043)
			(xy 184.793856 -350.948075) (xy 184.877691 -350.936022) (xy 184.962292 -350.931992) (xy 185.046893 -350.936022)
			(xy 185.130728 -350.948075) (xy 185.213037 -350.968043) (xy 185.293076 -350.995745) (xy 185.370119 -351.030929)
			(xy 185.443469 -351.073278) (xy 185.512461 -351.122407) (xy 185.576471 -351.177872) (xy 185.634919 -351.23917)
			(xy 185.687275 -351.305746) (xy 185.733065 -351.376998) (xy 185.771876 -351.452279) (xy 185.803355 -351.530909)
			(xy 185.827216 -351.612176) (xy 185.843245 -351.695342) (xy 185.851296 -351.779656) (xy 185.8518 -351.822004)
			(xy 185.8518 -351.822258) (xy 185.851234 -351.866996) (xy 185.842218 -351.956018) (xy 185.824312 -352.043685)
			(xy 185.797698 -352.129113) (xy 185.78068 -352.170492) (xy 185.777112 -352.180082) (xy 185.777113 -352.200525)
			(xy 185.78068 -352.210116) (xy 185.797704 -352.251527) (xy 185.824339 -352.337015) (xy 185.842246 -352.424746)
			(xy 185.851245 -352.513834) (xy 185.8518 -352.558604) (xy 185.85116 -352.609084) (xy 185.839825 -352.709404)
			(xy 185.829194 -352.758756) (xy 185.826997 -352.771225) (xy 185.833664 -352.795617) (xy 185.841894 -352.805238)
			(xy 185.882534 -352.847656) (xy 185.889646 -352.846132) (xy 185.898412 -352.843862) (xy 185.913646 -352.834103)
			(xy 185.919364 -352.827082) (xy 185.944527 -352.794419) (xy 185.999939 -352.733355) (xy 186.060764 -352.67768)
			(xy 186.126478 -352.627872) (xy 186.196519 -352.584357) (xy 186.270286 -352.547509) (xy 186.347146 -352.517645)
			(xy 186.426439 -352.49502) (xy 186.507485 -352.479828) (xy 186.589589 -352.472201) (xy 186.630818 -352.471736)
			(xy 186.671925 -352.472195) (xy 186.753788 -352.479781) (xy 186.834603 -352.494887) (xy 186.913679 -352.517383)
			(xy 186.990343 -352.547078) (xy 187.06394 -352.583719) (xy 187.133844 -352.626993) (xy 187.199457 -352.676531)
			(xy 187.260221 -352.73191) (xy 187.315617 -352.792659) (xy 187.365173 -352.85826) (xy 187.408465 -352.928152)
			(xy 187.445126 -353.001739) (xy 187.474841 -353.078395) (xy 187.497359 -353.157466) (xy 187.512486 -353.238276)
			(xy 187.519078 -353.3092) (xy 191.056256 -353.3092) (xy 191.060246 -353.225443) (xy 191.07218 -353.142444)
			(xy 191.091948 -353.060956) (xy 191.119373 -352.981715) (xy 191.154206 -352.90544) (xy 191.196132 -352.832822)
			(xy 191.244771 -352.764518) (xy 191.299682 -352.701146) (xy 191.360368 -352.643281) (xy 191.42628 -352.591447)
			(xy 191.49682 -352.546112) (xy 191.57135 -352.507688) (xy 191.649196 -352.476522) (xy 191.729651 -352.452897)
			(xy 191.811988 -352.437027) (xy 191.89546 -352.429055) (xy 191.937386 -352.428556) (xy 191.938402 -352.428556)
			(xy 191.975459 -352.428963) (xy 192.049308 -352.435227) (xy 192.12237 -352.447669) (xy 192.194131 -352.466201)
			(xy 192.229232 -352.478086) (xy 192.237429 -352.4806) (xy 192.254563 -352.4806) (xy 192.26276 -352.478086)
			(xy 192.290041 -352.468747) (xy 192.345585 -352.453243) (xy 192.373758 -352.447098) (xy 192.383527 -352.444576)
			(xy 192.400163 -352.433196) (xy 192.411142 -352.416293) (xy 192.413382 -352.406458) (xy 192.422838 -352.357349)
			(xy 192.451357 -352.261489) (xy 192.470278 -352.215196) (xy 192.473919 -352.205632) (xy 192.474045 -352.185185)
			(xy 192.470532 -352.175572) (xy 192.453515 -352.134192) (xy 192.426895 -352.048766) (xy 192.408989 -351.961099)
			(xy 192.399978 -351.872077) (xy 192.399412 -351.827338) (xy 192.399412 -351.827084) (xy 192.399916 -351.784736)
			(xy 192.407967 -351.700422) (xy 192.423996 -351.617256) (xy 192.447857 -351.535989) (xy 192.479336 -351.457359)
			(xy 192.518147 -351.382078) (xy 192.563937 -351.310826) (xy 192.616293 -351.24425) (xy 192.674741 -351.182952)
			(xy 192.738751 -351.127487) (xy 192.807743 -351.078358) (xy 192.881093 -351.036009) (xy 192.958136 -351.000825)
			(xy 193.038175 -350.973123) (xy 193.120484 -350.953155) (xy 193.204319 -350.941102) (xy 193.28892 -350.937072)
			(xy 193.373521 -350.941102) (xy 193.457356 -350.953155) (xy 193.539665 -350.973123) (xy 193.619704 -351.000825)
			(xy 193.696747 -351.036009) (xy 193.770097 -351.078358) (xy 193.839089 -351.127487) (xy 193.903099 -351.182952)
			(xy 193.961547 -351.24425) (xy 194.013903 -351.310826) (xy 194.059693 -351.382078) (xy 194.098504 -351.457359)
			(xy 194.129983 -351.535989) (xy 194.153844 -351.617256) (xy 194.169873 -351.700422) (xy 194.177924 -351.784736)
			(xy 194.178428 -351.827084) (xy 194.178428 -351.827338) (xy 194.177853 -351.872076) (xy 194.168839 -351.961098)
			(xy 194.150936 -352.048765) (xy 194.124325 -352.134193) (xy 194.107308 -352.175572) (xy 194.10375 -352.185165)
			(xy 194.103744 -352.205606) (xy 194.107308 -352.215196) (xy 194.12436 -352.256596) (xy 194.150986 -352.342088)
			(xy 194.165052 -352.41103) (xy 206.449676 -352.41103) (xy 206.449676 -351.54743) (xy 206.450162 -351.520179)
			(xy 206.457918 -351.466231) (xy 206.473273 -351.413936) (xy 206.495915 -351.364359) (xy 206.525381 -351.318509)
			(xy 206.561072 -351.277318) (xy 206.602263 -351.241627) (xy 206.648113 -351.212161) (xy 206.69769 -351.189519)
			(xy 206.749985 -351.174164) (xy 206.803933 -351.166408) (xy 206.858435 -351.166408) (xy 206.912383 -351.174164)
			(xy 206.964678 -351.189519) (xy 207.014255 -351.212161) (xy 207.060105 -351.241627) (xy 207.101296 -351.277318)
			(xy 207.136987 -351.318509) (xy 207.166453 -351.364359) (xy 207.189095 -351.413936) (xy 207.20445 -351.466231)
			(xy 207.212206 -351.520179) (xy 207.212692 -351.54743) (xy 207.212692 -352.41103) (xy 207.212206 -352.438281)
			(xy 207.20445 -352.492229) (xy 207.189095 -352.544524) (xy 207.166453 -352.594101) (xy 207.136987 -352.639951)
			(xy 207.101296 -352.681142) (xy 207.060105 -352.716833) (xy 207.014255 -352.746299) (xy 206.964678 -352.768941)
			(xy 206.912383 -352.784296) (xy 206.858435 -352.792052) (xy 206.803933 -352.792052) (xy 206.749985 -352.784296)
			(xy 206.69769 -352.768941) (xy 206.648113 -352.746299) (xy 206.602263 -352.716833) (xy 206.561072 -352.681142)
			(xy 206.525381 -352.639951) (xy 206.495915 -352.594101) (xy 206.473273 -352.544524) (xy 206.457918 -352.492229)
			(xy 206.450162 -352.438281) (xy 206.449676 -352.41103) (xy 194.165052 -352.41103) (xy 194.168886 -352.429823)
			(xy 194.177877 -352.518913) (xy 194.178428 -352.563684) (xy 194.178055 -352.600778) (xy 194.171875 -352.674709)
			(xy 194.159556 -352.747868) (xy 194.150742 -352.783902) (xy 194.149 -352.792252) (xy 194.15051 -352.809229)
			(xy 194.157543 -352.824754) (xy 194.163188 -352.831146) (xy 194.203574 -352.874326) (xy 194.216274 -352.871532)
			(xy 194.225043 -352.869274) (xy 194.240276 -352.859506) (xy 194.245992 -352.852482) (xy 194.271138 -352.819805)
			(xy 194.326552 -352.758742) (xy 194.387379 -352.703068) (xy 194.453095 -352.65326) (xy 194.523138 -352.609746)
			(xy 194.596907 -352.5729) (xy 194.673768 -352.543037) (xy 194.753063 -352.520414) (xy 194.834111 -352.505225)
			(xy 194.916217 -352.4976) (xy 194.957446 -352.497136) (xy 194.998553 -352.497569) (xy 195.080417 -352.505157)
			(xy 195.161232 -352.520265) (xy 195.240309 -352.542764) (xy 195.316973 -352.572461) (xy 195.390571 -352.609104)
			(xy 195.460474 -352.652379) (xy 195.526087 -352.701919) (xy 195.586851 -352.757301) (xy 195.642247 -352.818051)
			(xy 195.691802 -352.883653) (xy 195.735094 -352.953546) (xy 195.744851 -352.973132) (xy 338.849208 -352.973132)
			(xy 338.849825 -352.926972) (xy 338.859426 -352.835153) (xy 338.878488 -352.744823) (xy 338.906804 -352.656953)
			(xy 338.9249 -352.614484) (xy 338.928699 -352.60454) (xy 338.928703 -352.583278) (xy 338.9249 -352.573336)
			(xy 338.90688 -352.530918) (xy 338.878719 -352.443158) (xy 338.859786 -352.352956) (xy 338.850284 -352.26128)
			(xy 338.849716 -352.215196) (xy 338.850295 -352.1688) (xy 338.859941 -352.076512) (xy 338.879138 -351.985728)
			(xy 338.907678 -351.897435) (xy 338.925916 -351.85477) (xy 338.929722 -351.844828) (xy 338.929721 -351.823565)
			(xy 338.925916 -351.813622) (xy 338.907694 -351.771019) (xy 338.879176 -351.682852) (xy 338.859983 -351.592196)
			(xy 338.850324 -351.500036) (xy 338.849716 -351.453704) (xy 338.849716 -351.453196) (xy 338.850148 -351.412092)
			(xy 338.857734 -351.330235) (xy 338.87284 -351.249427) (xy 338.895338 -351.170357) (xy 338.925036 -351.093701)
			(xy 338.96168 -351.020112) (xy 339.004958 -350.950218) (xy 339.0545 -350.884616) (xy 339.109884 -350.823864)
			(xy 339.170637 -350.768482) (xy 339.236241 -350.718942) (xy 339.306137 -350.675666) (xy 339.379727 -350.639025)
			(xy 339.456384 -350.609329) (xy 339.535454 -350.586834) (xy 339.616263 -350.57173) (xy 339.69812 -350.564147)
			(xy 339.739224 -350.563688) (xy 339.739732 -350.563688) (xy 339.786063 -350.564321) (xy 339.87822 -350.573985)
			(xy 339.968874 -350.593172) (xy 340.057044 -350.621677) (xy 340.09965 -350.639888) (xy 340.109592 -350.643694)
			(xy 340.130856 -350.643694) (xy 340.140798 -350.639888) (xy 340.183457 -350.621635) (xy 340.27175 -350.593093)
			(xy 340.362537 -350.573902) (xy 340.454828 -350.564272) (xy 340.501224 -350.563688) (xy 340.547619 -350.564298)
			(xy 340.639906 -350.573935) (xy 340.73069 -350.593123) (xy 340.818984 -350.621654) (xy 340.86165 -350.639888)
			(xy 340.871592 -350.643694) (xy 340.892856 -350.643694) (xy 340.902798 -350.639888) (xy 340.945457 -350.621635)
			(xy 341.03375 -350.593093) (xy 341.124537 -350.573902) (xy 341.216828 -350.564272) (xy 341.263224 -350.563688)
			(xy 341.309619 -350.564298) (xy 341.401906 -350.573935) (xy 341.49269 -350.593123) (xy 341.580984 -350.621654)
			(xy 341.62365 -350.639888) (xy 341.633592 -350.643694) (xy 341.654856 -350.643694) (xy 341.664798 -350.639888)
			(xy 341.707457 -350.621635) (xy 341.79575 -350.593093) (xy 341.886537 -350.573902) (xy 341.978828 -350.564272)
			(xy 342.025224 -350.563688) (xy 342.071619 -350.564298) (xy 342.163906 -350.573935) (xy 342.25469 -350.593123)
			(xy 342.342984 -350.621654) (xy 342.38565 -350.639888) (xy 342.395592 -350.643694) (xy 342.416856 -350.643694)
			(xy 342.426798 -350.639888) (xy 342.469457 -350.621635) (xy 342.55775 -350.593093) (xy 342.648537 -350.573902)
			(xy 342.740828 -350.564272) (xy 342.787224 -350.563688) (xy 342.833689 -350.564308) (xy 342.926112 -350.573988)
			(xy 343.017025 -350.593241) (xy 343.105438 -350.621857) (xy 343.148158 -350.640142) (xy 343.156911 -350.643584)
			(xy 343.175683 -350.644482) (xy 343.184734 -350.64192) (xy 343.230109 -350.62753) (xy 343.323147 -350.607378)
			(xy 343.417806 -350.597287) (xy 343.465404 -350.596708) (xy 343.506508 -350.597148) (xy 343.588364 -350.604734)
			(xy 343.669172 -350.61984) (xy 343.748241 -350.642338) (xy 343.824897 -350.672035) (xy 343.898486 -350.708679)
			(xy 343.968379 -350.751956) (xy 344.033982 -350.801498) (xy 344.094733 -350.856881) (xy 344.150115 -350.917634)
			(xy 344.199655 -350.983237) (xy 344.242931 -351.053132) (xy 344.279573 -351.126721) (xy 344.309269 -351.203378)
			(xy 344.331765 -351.282448) (xy 344.346869 -351.363255) (xy 344.354453 -351.445112) (xy 344.354912 -351.486216)
			(xy 344.354912 -351.486724) (xy 344.354311 -351.533056) (xy 344.344638 -351.625214) (xy 344.325441 -351.715868)
			(xy 344.296928 -351.804037) (xy 344.278712 -351.846642) (xy 344.274897 -351.856581) (xy 344.274903 -351.877848)
			(xy 344.278712 -351.88779) (xy 344.296962 -351.93045) (xy 344.325505 -352.018743) (xy 344.344696 -352.109529)
			(xy 344.354328 -352.20182) (xy 344.354912 -352.248216) (xy 344.354328 -352.294369) (xy 344.344776 -352.386179)
			(xy 344.325776 -352.476508) (xy 344.297531 -352.564386) (xy 344.279474 -352.606864) (xy 344.275648 -352.6168)
			(xy 344.275662 -352.638069) (xy 344.279474 -352.648012) (xy 344.29749 -352.690438) (xy 344.325707 -352.77819)
			(xy 344.344711 -352.868387) (xy 344.354297 -352.960064) (xy 344.354912 -353.006152) (xy 344.354402 -353.047262)
			(xy 344.34922 -353.1032) (xy 423.453493 -353.1032) (xy 423.457484 -353.019415) (xy 423.469422 -352.936388)
			(xy 423.489198 -352.854872) (xy 423.516634 -352.775605) (xy 423.55148 -352.699305) (xy 423.593421 -352.626663)
			(xy 423.642078 -352.558337) (xy 423.697009 -352.494945) (xy 423.757718 -352.437063) (xy 423.823654 -352.385213)
			(xy 423.89422 -352.339866) (xy 423.968777 -352.301432) (xy 424.04665 -352.270259) (xy 424.127133 -352.24663)
			(xy 424.209499 -352.230759) (xy 424.293 -352.222789) (xy 424.33494 -352.222308) (xy 424.372129 -352.222714)
			(xy 424.446242 -352.228999) (xy 424.519562 -352.241503) (xy 424.591568 -352.260139) (xy 424.626786 -352.272092)
			(xy 424.634983 -352.274606) (xy 424.652117 -352.274606) (xy 424.660314 -352.272092) (xy 424.687596 -352.262757)
			(xy 424.74314 -352.24725) (xy 424.771312 -352.241104) (xy 424.781089 -352.238609) (xy 424.797722 -352.227214)
			(xy 424.808697 -352.210302) (xy 424.810936 -352.200464) (xy 424.820391 -352.151355) (xy 424.84891 -352.055495)
			(xy 424.867832 -352.009202) (xy 424.871403 -351.999613) (xy 424.871399 -351.979169) (xy 424.867832 -351.969578)
			(xy 424.850786 -351.928175) (xy 424.824155 -351.842685) (xy 424.806254 -351.754951) (xy 424.797263 -351.665861)
			(xy 424.796712 -351.62109) (xy 424.797216 -351.578729) (xy 424.805269 -351.494392) (xy 424.821303 -351.411202)
			(xy 424.845171 -351.329912) (xy 424.876659 -351.25126) (xy 424.915481 -351.175957) (xy 424.961284 -351.104685)
			(xy 425.013655 -351.038089) (xy 425.07212 -350.976774) (xy 425.136148 -350.921293) (xy 425.20516 -350.87215)
			(xy 425.27853 -350.82979) (xy 425.355595 -350.794595) (xy 425.435657 -350.766886) (xy 425.51799 -350.746912)
			(xy 425.601849 -350.734855) (xy 425.686474 -350.730824) (xy 425.771099 -350.734855) (xy 425.854958 -350.746912)
			(xy 425.937291 -350.766886) (xy 426.017353 -350.794595) (xy 426.094418 -350.82979) (xy 426.167788 -350.87215)
			(xy 426.2368 -350.921293) (xy 426.300828 -350.976774) (xy 426.359293 -351.038089) (xy 426.411664 -351.104685)
			(xy 426.457467 -351.175957) (xy 426.496289 -351.25126) (xy 426.527777 -351.329912) (xy 426.551645 -351.411202)
			(xy 426.567679 -351.494392) (xy 426.575732 -351.578729) (xy 426.576236 -351.62109) (xy 426.575653 -351.665859)
			(xy 426.566649 -351.754944) (xy 426.548749 -351.842675) (xy 426.522136 -351.928167) (xy 426.505116 -351.969578)
			(xy 426.501559 -351.979171) (xy 426.501555 -351.999611) (xy 426.505116 -352.009202) (xy 426.522153 -352.050608)
			(xy 426.548787 -352.136097) (xy 426.566691 -352.22383) (xy 426.575684 -352.312919) (xy 426.576236 -352.35769)
			(xy 426.575843 -352.394784) (xy 426.569667 -352.468714) (xy 426.557358 -352.541873) (xy 426.54855 -352.577908)
			(xy 426.5467 -352.586267) (xy 426.54815 -352.603318) (xy 426.55512 -352.618947) (xy 426.560742 -352.625406)
			(xy 426.601128 -352.668332) (xy 426.613574 -352.665538) (xy 426.622391 -352.663274) (xy 426.637739 -352.653501)
			(xy 426.643546 -352.646488) (xy 426.66867 -352.613784) (xy 426.724067 -352.552685) (xy 426.784882 -352.496976)
			(xy 426.850593 -352.447136) (xy 426.920635 -352.403592) (xy 426.994408 -352.366719) (xy 427.071277 -352.336834)
			(xy 427.150582 -352.314192) (xy 427.231643 -352.298989) (xy 427.313763 -352.291354) (xy 427.355 -352.290888)
			(xy 427.396111 -352.291352) (xy 427.477981 -352.29894) (xy 427.558801 -352.314051) (xy 427.637882 -352.336556)
			(xy 427.714549 -352.366262) (xy 427.788147 -352.402918) (xy 427.858049 -352.446208) (xy 427.923657 -352.495765)
			(xy 427.984412 -352.551165) (xy 428.039795 -352.611935) (xy 428.089333 -352.677557) (xy 428.132604 -352.747471)
			(xy 428.169239 -352.82108) (xy 428.198924 -352.897755) (xy 428.221406 -352.976842) (xy 428.236494 -353.057667)
			(xy 428.243048 -353.1286) (xy 431.780208 -353.1286) (xy 431.784199 -353.04482) (xy 431.796136 -352.961799)
			(xy 431.815909 -352.880289) (xy 431.843342 -352.801027) (xy 431.878184 -352.724732) (xy 431.92012 -352.652094)
			(xy 431.968771 -352.583771) (xy 432.023696 -352.520381) (xy 432.084398 -352.4625) (xy 432.150327 -352.410651)
			(xy 432.220886 -352.365303) (xy 432.295436 -352.326868) (xy 432.373301 -352.295693) (xy 432.453778 -352.27206)
			(xy 432.536136 -352.256184) (xy 432.619631 -352.248208) (xy 432.661568 -352.247708) (xy 432.698757 -352.248106)
			(xy 432.77287 -352.254393) (xy 432.84619 -352.2669) (xy 432.918196 -352.285538) (xy 432.953414 -352.297492)
			(xy 432.961611 -352.300006) (xy 432.978745 -352.300006) (xy 432.986942 -352.297492) (xy 433.014223 -352.288155)
			(xy 433.069768 -352.27265) (xy 433.09794 -352.266504) (xy 433.107722 -352.264025) (xy 433.124353 -352.252622)
			(xy 433.135327 -352.235704) (xy 433.137564 -352.225864) (xy 433.147017 -352.176755) (xy 433.175537 -352.080895)
			(xy 433.19446 -352.034602) (xy 433.19803 -352.025013) (xy 433.198026 -352.004569) (xy 433.19446 -351.994978)
			(xy 433.177416 -351.953575) (xy 433.150784 -351.868085) (xy 433.132882 -351.780351) (xy 433.123891 -351.691261)
			(xy 433.12334 -351.64649) (xy 433.123844 -351.604129) (xy 433.131897 -351.519792) (xy 433.147931 -351.436602)
			(xy 433.171799 -351.355312) (xy 433.203287 -351.27666) (xy 433.242109 -351.201357) (xy 433.287912 -351.130085)
			(xy 433.340283 -351.063489) (xy 433.398748 -351.002174) (xy 433.462776 -350.946693) (xy 433.531788 -350.89755)
			(xy 433.605158 -350.85519) (xy 433.682223 -350.819995) (xy 433.762285 -350.792286) (xy 433.844618 -350.772312)
			(xy 433.928477 -350.760255) (xy 434.013102 -350.756224) (xy 434.097727 -350.760255) (xy 434.181586 -350.772312)
			(xy 434.263919 -350.792286) (xy 434.343981 -350.819995) (xy 434.421046 -350.85519) (xy 434.494416 -350.89755)
			(xy 434.563428 -350.946693) (xy 434.627456 -351.002174) (xy 434.685921 -351.063489) (xy 434.738292 -351.130085)
			(xy 434.784095 -351.201357) (xy 434.822917 -351.27666) (xy 434.854405 -351.355312) (xy 434.878273 -351.436602)
			(xy 434.894307 -351.519792) (xy 434.90236 -351.604129) (xy 434.902864 -351.64649) (xy 434.902279 -351.691259)
			(xy 434.893275 -351.780343) (xy 434.875376 -351.868074) (xy 434.848764 -351.953566) (xy 434.831744 -351.994978)
			(xy 434.828186 -352.00457) (xy 434.828182 -352.025011) (xy 434.831744 -352.034602) (xy 434.848782 -352.076008)
			(xy 434.875415 -352.161497) (xy 434.893319 -352.24923) (xy 434.902312 -352.338319) (xy 434.902864 -352.38309)
			(xy 434.90247 -352.420184) (xy 434.896295 -352.494114) (xy 434.883986 -352.567273) (xy 434.875178 -352.603308)
			(xy 434.873347 -352.611669) (xy 434.874795 -352.628716) (xy 434.881755 -352.644345) (xy 434.88737 -352.650806)
			(xy 434.927756 -352.693732) (xy 434.940202 -352.690938) (xy 434.94901 -352.688645) (xy 434.964363 -352.678893)
			(xy 434.970174 -352.671888) (xy 434.995281 -352.639171) (xy 435.05068 -352.578072) (xy 435.111497 -352.522364)
			(xy 435.17721 -352.472524) (xy 435.247255 -352.428982) (xy 435.321029 -352.39211) (xy 435.3979 -352.362226)
			(xy 435.477207 -352.339586) (xy 435.558269 -352.324385) (xy 435.64039 -352.316753) (xy 435.681628 -352.316288)
			(xy 435.722739 -352.316726) (xy 435.80461 -352.324316) (xy 435.885431 -352.339429) (xy 435.964512 -352.361936)
			(xy 436.041179 -352.391645) (xy 436.114778 -352.428302) (xy 436.184679 -352.471595) (xy 436.250287 -352.521154)
			(xy 436.311041 -352.576555) (xy 436.366424 -352.637327) (xy 436.415962 -352.70295) (xy 436.459233 -352.772865)
			(xy 436.495867 -352.846475) (xy 436.525552 -352.923151) (xy 436.548034 -353.00224) (xy 436.563122 -353.083066)
			(xy 436.570687 -353.164939) (xy 436.571136 -353.20605) (xy 436.570568 -353.25082) (xy 436.561569 -353.339906)
			(xy 436.543667 -353.427639) (xy 436.517044 -353.513129) (xy 436.500016 -353.554538) (xy 436.496425 -353.564121)
			(xy 436.496444 -353.58457) (xy 436.500016 -353.594162) (xy 436.517052 -353.635569) (xy 436.543684 -353.721058)
			(xy 436.561588 -353.808791) (xy 436.570583 -353.897879) (xy 436.571136 -353.94265) (xy 436.570568 -353.98742)
			(xy 436.561569 -354.076506) (xy 436.543667 -354.164239) (xy 436.517044 -354.249729) (xy 436.500016 -354.291138)
			(xy 436.496425 -354.300721) (xy 436.496444 -354.32117) (xy 436.500016 -354.330762) (xy 436.517046 -354.372136)
			(xy 436.543663 -354.457564) (xy 436.561565 -354.545233) (xy 436.570572 -354.634257) (xy 436.571136 -354.678996)
			(xy 436.571136 -354.67925) (xy 436.57064 -354.720357) (xy 436.56306 -354.80222) (xy 436.547959 -354.883035)
			(xy 436.525468 -354.962112) (xy 436.495777 -355.038776) (xy 436.45914 -355.112375) (xy 436.415869 -355.18228)
			(xy 436.366333 -355.247894) (xy 436.310956 -355.308659) (xy 436.250208 -355.364056) (xy 436.184609 -355.413612)
			(xy 436.114718 -355.456904) (xy 436.041131 -355.493565) (xy 435.964475 -355.523279) (xy 435.885405 -355.545796)
			(xy 435.804595 -355.560921) (xy 435.722735 -355.568527) (xy 435.681628 -355.569012) (xy 435.640018 -355.568519)
			(xy 435.557162 -355.560745) (xy 435.475393 -355.545272) (xy 435.395426 -355.522236) (xy 435.317957 -355.491836)
			(xy 435.243663 -355.454339) (xy 435.208172 -355.432614) (xy 435.199049 -355.42742) (xy 435.178322 -355.424214)
			(xy 435.158043 -355.429561) (xy 435.149498 -355.435662) (xy 435.115852 -355.46163) (xy 435.044461 -355.507757)
			(xy 434.968993 -355.546861) (xy 434.890138 -355.578584) (xy 434.808616 -355.602638) (xy 434.72517 -355.618802)
			(xy 434.640562 -355.626929) (xy 434.598064 -355.627432) (xy 434.556953 -355.626982) (xy 434.475084 -355.619391)
			(xy 434.394263 -355.604278) (xy 434.315183 -355.581771) (xy 434.238517 -355.552062) (xy 434.164919 -355.515405)
			(xy 434.095019 -355.472113) (xy 434.029411 -355.422555) (xy 433.968657 -355.367155) (xy 433.913275 -355.306384)
			(xy 433.863736 -355.240762) (xy 433.820465 -355.170848) (xy 433.783831 -355.09724) (xy 433.754145 -355.020565)
			(xy 433.731661 -354.941477) (xy 433.716572 -354.860653) (xy 433.709006 -354.778781) (xy 433.708556 -354.73767)
			(xy 433.709098 -354.692899) (xy 433.718104 -354.603812) (xy 433.736014 -354.51608) (xy 433.762645 -354.430591)
			(xy 433.779676 -354.389182) (xy 433.783256 -354.379596) (xy 433.783245 -354.359149) (xy 433.779676 -354.349558)
			(xy 433.762646 -354.308149) (xy 433.736013 -354.222661) (xy 433.718107 -354.134928) (xy 433.70911 -354.045841)
			(xy 433.708556 -354.00107) (xy 433.708556 -353.989132) (xy 433.682076 -353.983189) (xy 433.629842 -353.968444)
			(xy 433.604162 -353.959668) (xy 433.595965 -353.957154) (xy 433.578831 -353.957154) (xy 433.570634 -353.959668)
			(xy 433.535422 -353.971642) (xy 433.463417 -353.990292) (xy 433.390095 -354.002797) (xy 433.315979 -354.009067)
			(xy 433.278788 -354.009452) (xy 433.241598 -354.009064) (xy 433.167486 -354.002773) (xy 433.094166 -353.990263)
			(xy 433.02216 -353.971623) (xy 432.986942 -353.959668) (xy 432.978745 -353.957154) (xy 432.961611 -353.957154)
			(xy 432.953414 -353.959668) (xy 432.918203 -353.971647) (xy 432.846198 -353.990296) (xy 432.772875 -354.0028)
			(xy 432.698759 -354.009068) (xy 432.661568 -354.009452) (xy 432.619631 -354.008992) (xy 432.536136 -354.001016)
			(xy 432.453778 -353.98514) (xy 432.373301 -353.961507) (xy 432.295436 -353.930332) (xy 432.220886 -353.891897)
			(xy 432.150327 -353.846549) (xy 432.084398 -353.7947) (xy 432.023696 -353.736819) (xy 431.968771 -353.673429)
			(xy 431.92012 -353.605106) (xy 431.878184 -353.532468) (xy 431.843342 -353.456173) (xy 431.815909 -353.376911)
			(xy 431.796136 -353.295401) (xy 431.784199 -353.21238) (xy 431.780208 -353.1286) (xy 428.243048 -353.1286)
			(xy 428.244059 -353.139539) (xy 428.244508 -353.18065) (xy 428.243935 -353.22542) (xy 428.234936 -353.314506)
			(xy 428.217036 -353.402238) (xy 428.190415 -353.487729) (xy 428.173388 -353.529138) (xy 428.169793 -353.53872)
			(xy 428.169812 -353.559171) (xy 428.173388 -353.568762) (xy 428.190428 -353.610167) (xy 428.217058 -353.695657)
			(xy 428.23496 -353.783391) (xy 428.243955 -353.872479) (xy 428.244508 -353.91725) (xy 428.243935 -353.96202)
			(xy 428.234936 -354.051106) (xy 428.217036 -354.138838) (xy 428.190415 -354.224329) (xy 428.173388 -354.265738)
			(xy 428.169793 -354.27532) (xy 428.169812 -354.295771) (xy 428.173388 -354.305362) (xy 428.190417 -354.346737)
			(xy 428.217034 -354.432165) (xy 428.234937 -354.519833) (xy 428.243944 -354.608857) (xy 428.244508 -354.653596)
			(xy 428.244508 -354.65385) (xy 428.24394 -354.694955) (xy 428.23636 -354.776814) (xy 428.221262 -354.857624)
			(xy 428.198773 -354.936698) (xy 428.169085 -355.013359) (xy 428.132451 -355.086955) (xy 428.089184 -355.156857)
			(xy 428.039654 -355.22247) (xy 427.984281 -355.283233) (xy 427.923539 -355.33863) (xy 427.857946 -355.388186)
			(xy 427.788061 -355.431481) (xy 427.714479 -355.468143) (xy 427.63783 -355.497861) (xy 427.558765 -355.520382)
			(xy 427.47796 -355.535512) (xy 427.396104 -355.543124) (xy 427.355 -355.543612) (xy 427.31339 -355.543132)
			(xy 427.230533 -355.535356) (xy 427.148764 -355.519881) (xy 427.068797 -355.496842) (xy 426.991328 -355.46644)
			(xy 426.917035 -355.42894) (xy 426.881544 -355.407214) (xy 426.872433 -355.401996) (xy 426.851698 -355.398798)
			(xy 426.831415 -355.404156) (xy 426.82287 -355.410262) (xy 426.789234 -355.436243) (xy 426.717841 -355.482369)
			(xy 426.642371 -355.521471) (xy 426.563514 -355.553192) (xy 426.481991 -355.577244) (xy 426.398543 -355.593405)
			(xy 426.313935 -355.60153) (xy 426.271436 -355.602032) (xy 426.230327 -355.601513) (xy 426.148459 -355.593929)
			(xy 426.06764 -355.578822) (xy 425.98856 -355.556321) (xy 425.911894 -355.526617) (xy 425.838297 -355.489966)
			(xy 425.768396 -355.446679) (xy 425.702788 -355.397126) (xy 425.642034 -355.341729) (xy 425.58665 -355.280962)
			(xy 425.537111 -355.215344) (xy 425.49384 -355.145433) (xy 425.457204 -355.071828) (xy 425.427518 -354.995156)
			(xy 425.405034 -354.916071) (xy 425.389944 -354.835249) (xy 425.382378 -354.753379) (xy 425.381928 -354.71227)
			(xy 425.382471 -354.667499) (xy 425.391478 -354.578412) (xy 425.409387 -354.49068) (xy 425.436017 -354.40519)
			(xy 425.453048 -354.363782) (xy 425.45663 -354.354196) (xy 425.456619 -354.333749) (xy 425.453048 -354.324158)
			(xy 425.436017 -354.28275) (xy 425.409384 -354.197261) (xy 425.391479 -354.109528) (xy 425.382482 -354.020441)
			(xy 425.381928 -353.97567) (xy 425.381928 -353.963732) (xy 425.35545 -353.957782) (xy 425.303215 -353.943042)
			(xy 425.277534 -353.934268) (xy 425.269337 -353.931754) (xy 425.252203 -353.931754) (xy 425.244006 -353.934268)
			(xy 425.208787 -353.946222) (xy 425.136785 -353.964878) (xy 425.063465 -353.977388) (xy 424.98935 -353.983664)
			(xy 424.95216 -353.984052) (xy 424.914971 -353.983643) (xy 424.840858 -353.977359) (xy 424.767539 -353.964855)
			(xy 424.695532 -353.94622) (xy 424.660314 -353.934268) (xy 424.652117 -353.931754) (xy 424.634983 -353.931754)
			(xy 424.626786 -353.934268) (xy 424.591569 -353.946227) (xy 424.519566 -353.964882) (xy 424.446245 -353.977391)
			(xy 424.37213 -353.983665) (xy 424.33494 -353.984052) (xy 424.293 -353.983611) (xy 424.209499 -353.975641)
			(xy 424.127133 -353.95977) (xy 424.04665 -353.936141) (xy 423.968777 -353.904968) (xy 423.89422 -353.866534)
			(xy 423.823654 -353.821187) (xy 423.757718 -353.769337) (xy 423.697009 -353.711455) (xy 423.642078 -353.648063)
			(xy 423.593421 -353.579737) (xy 423.55148 -353.507095) (xy 423.516634 -353.430795) (xy 423.489198 -353.351528)
			(xy 423.469422 -353.270012) (xy 423.457484 -353.186985) (xy 423.453493 -353.1032) (xy 344.34922 -353.1032)
			(xy 344.346818 -353.129131) (xy 344.331712 -353.20995) (xy 344.309211 -353.289031) (xy 344.279508 -353.365698)
			(xy 344.242856 -353.439296) (xy 344.199569 -353.509197) (xy 344.150015 -353.574806) (xy 344.094618 -353.635561)
			(xy 344.03385 -353.690944) (xy 343.968231 -353.740483) (xy 343.898319 -353.783755) (xy 343.824713 -353.82039)
			(xy 343.748039 -353.850075) (xy 343.668954 -353.872558) (xy 343.58813 -353.887646) (xy 343.50626 -353.895211)
			(xy 343.46515 -353.89566) (xy 343.421566 -353.895134) (xy 343.334811 -353.886653) (xy 343.249302 -353.869729)
			(xy 343.165858 -353.844524) (xy 343.085279 -353.81128) (xy 343.046558 -353.791266) (xy 343.035092 -353.785848)
			(xy 343.009764 -353.785848) (xy 342.998298 -353.791266) (xy 342.959077 -353.812027) (xy 342.877306 -353.846516)
			(xy 342.792508 -353.872694) (xy 342.705525 -353.890299) (xy 342.617221 -353.899159) (xy 342.572848 -353.899724)
			(xy 342.534532 -353.899341) (xy 342.458179 -353.892813) (xy 342.382672 -353.879733) (xy 342.308573 -353.860197)
			(xy 342.272366 -353.847654) (xy 342.26405 -353.845068) (xy 342.246646 -353.845068) (xy 342.23833 -353.847654)
			(xy 342.202121 -353.860189) (xy 342.128019 -353.879707) (xy 342.052513 -353.892787) (xy 341.976163 -353.899332)
			(xy 341.937848 -353.899724) (xy 341.899532 -353.899341) (xy 341.823179 -353.892813) (xy 341.747672 -353.879733)
			(xy 341.673573 -353.860197) (xy 341.637366 -353.847654) (xy 341.62905 -353.845068) (xy 341.611646 -353.845068)
			(xy 341.60333 -353.847654) (xy 341.567121 -353.860189) (xy 341.493019 -353.879707) (xy 341.417513 -353.892787)
			(xy 341.341163 -353.899332) (xy 341.302848 -353.899724) (xy 341.264532 -353.899341) (xy 341.188179 -353.892813)
			(xy 341.112672 -353.879733) (xy 341.038573 -353.860197) (xy 341.002366 -353.847654) (xy 340.99405 -353.845068)
			(xy 340.976646 -353.845068) (xy 340.96833 -353.847654) (xy 340.932121 -353.860189) (xy 340.858019 -353.879707)
			(xy 340.782513 -353.892787) (xy 340.706163 -353.899332) (xy 340.667848 -353.899724) (xy 340.626539 -353.899263)
			(xy 340.544274 -353.89164) (xy 340.463071 -353.876418) (xy 340.38363 -353.853729) (xy 340.306637 -353.823768)
			(xy 340.232755 -353.786793) (xy 340.19744 -353.765358) (xy 340.189803 -353.761082) (xy 340.172701 -353.75742)
			(xy 340.155358 -353.759679) (xy 340.147402 -353.763326) (xy 340.109501 -353.782381) (xy 340.030769 -353.813979)
			(xy 339.949386 -353.837938) (xy 339.866091 -353.85404) (xy 339.781642 -353.862138) (xy 339.739224 -353.86264)
			(xy 339.73897 -353.86264) (xy 339.697862 -353.862216) (xy 339.615997 -353.854629) (xy 339.535181 -353.839522)
			(xy 339.456103 -353.817024) (xy 339.379438 -353.787327) (xy 339.30584 -353.750684) (xy 339.235936 -353.707408)
			(xy 339.170322 -353.657867) (xy 339.109558 -353.602485) (xy 339.054162 -353.541734) (xy 339.004606 -353.476131)
			(xy 338.961314 -353.406237) (xy 338.924655 -353.332646) (xy 338.89494 -353.255988) (xy 338.872425 -353.176916)
			(xy 338.857299 -353.096103) (xy 338.849693 -353.01424) (xy 338.849208 -352.973132) (xy 195.744851 -352.973132)
			(xy 195.771754 -353.027135) (xy 195.80147 -353.103792) (xy 195.823987 -353.182863) (xy 195.839114 -353.263674)
			(xy 195.846722 -353.345537) (xy 195.847208 -353.386644) (xy 195.846646 -353.431414) (xy 195.837635 -353.520499)
			(xy 195.81973 -353.60823) (xy 195.793111 -353.693721) (xy 195.776088 -353.735132) (xy 195.772497 -353.744715)
			(xy 195.772513 -353.765165) (xy 195.776088 -353.774756) (xy 195.793114 -353.816166) (xy 195.81975 -353.901654)
			(xy 195.837657 -353.989386) (xy 195.846654 -354.078474) (xy 195.847208 -354.123244) (xy 195.846646 -354.168014)
			(xy 195.837635 -354.257099) (xy 195.81973 -354.34483) (xy 195.793111 -354.430321) (xy 195.776088 -354.471732)
			(xy 195.772497 -354.481315) (xy 195.772513 -354.501765) (xy 195.776088 -354.511356) (xy 195.793114 -354.552766)
			(xy 195.81975 -354.638254) (xy 195.837657 -354.725986) (xy 195.846654 -354.815074) (xy 195.847208 -354.859844)
			(xy 195.84679 -354.900955) (xy 195.839198 -354.982827) (xy 195.824083 -355.063648) (xy 195.801575 -355.14273)
			(xy 195.771864 -355.219398) (xy 195.742079 -355.279198) (xy 285.476188 -355.279198) (xy 285.476597 -355.238082)
			(xy 285.484185 -355.1562) (xy 285.499295 -355.075367) (xy 285.5218 -354.996274) (xy 285.551507 -354.919594)
			(xy 285.588163 -354.845983) (xy 285.631455 -354.776069) (xy 285.681013 -354.710447) (xy 285.736414 -354.649677)
			(xy 285.797187 -354.594279) (xy 285.862811 -354.544725) (xy 285.932729 -354.501438) (xy 286.006342 -354.464786)
			(xy 286.083023 -354.435084) (xy 286.162118 -354.412584) (xy 286.242951 -354.397477) (xy 286.324834 -354.389894)
			(xy 286.36595 -354.389436) (xy 286.404239 -354.389856) (xy 286.480533 -354.39646) (xy 286.555976 -354.409605)
			(xy 286.630007 -354.429194) (xy 286.666178 -354.44176) (xy 286.674615 -354.444411) (xy 286.692285 -354.444411)
			(xy 286.700722 -354.44176) (xy 286.736903 -354.429226) (xy 286.810935 -354.409651) (xy 286.886373 -354.396501)
			(xy 286.962662 -354.389874) (xy 287.00095 -354.389436) (xy 287.039239 -354.389856) (xy 287.115533 -354.39646)
			(xy 287.190976 -354.409605) (xy 287.265007 -354.429194) (xy 287.301178 -354.44176) (xy 287.309615 -354.444411)
			(xy 287.327285 -354.444411) (xy 287.335722 -354.44176) (xy 287.371903 -354.429226) (xy 287.445935 -354.409651)
			(xy 287.521373 -354.396501) (xy 287.597662 -354.389874) (xy 287.63595 -354.389436) (xy 287.674239 -354.389856)
			(xy 287.750533 -354.39646) (xy 287.825976 -354.409605) (xy 287.900007 -354.429194) (xy 287.936178 -354.44176)
			(xy 287.944615 -354.444411) (xy 287.962285 -354.444411) (xy 287.970722 -354.44176) (xy 288.006903 -354.429226)
			(xy 288.080935 -354.409651) (xy 288.156373 -354.396501) (xy 288.232662 -354.389874) (xy 288.27095 -354.389436)
			(xy 288.309239 -354.389856) (xy 288.385533 -354.39646) (xy 288.460976 -354.409605) (xy 288.535007 -354.429194)
			(xy 288.571178 -354.44176) (xy 288.579615 -354.444411) (xy 288.597285 -354.444411) (xy 288.605722 -354.44176)
			(xy 288.641903 -354.429226) (xy 288.715935 -354.409651) (xy 288.791373 -354.396501) (xy 288.867662 -354.389874)
			(xy 288.90595 -354.389436) (xy 288.947064 -354.389946) (xy 289.028942 -354.397529) (xy 289.10977 -354.412634)
			(xy 289.18886 -354.435133) (xy 289.265537 -354.464834) (xy 289.339146 -354.501483) (xy 289.409059 -354.544768)
			(xy 289.47468 -354.594319) (xy 289.535449 -354.649714) (xy 289.590847 -354.71048) (xy 289.640402 -354.776098)
			(xy 289.683691 -354.846009) (xy 289.720345 -354.919615) (xy 289.75005 -354.99629) (xy 289.772554 -355.075379)
			(xy 289.787664 -355.156207) (xy 289.795251 -355.238084) (xy 289.795712 -355.279198) (xy 289.795298 -355.318061)
			(xy 289.788487 -355.395488) (xy 289.77495 -355.472025) (xy 289.75479 -355.547092) (xy 289.741864 -355.583744)
			(xy 289.739034 -355.592628) (xy 289.739308 -355.611259) (xy 289.742372 -355.620066) (xy 289.757559 -355.659473)
			(xy 289.781314 -355.740522) (xy 289.797291 -355.823456) (xy 289.805346 -355.907529) (xy 289.805872 -355.949758)
			(xy 289.805454 -355.988048) (xy 289.79885 -356.064341) (xy 289.785704 -356.139784) (xy 289.766114 -356.213815)
			(xy 289.753548 -356.249986) (xy 289.750918 -356.258428) (xy 289.750905 -356.276094) (xy 289.753548 -356.28453)
			(xy 289.766084 -356.32071) (xy 289.785659 -356.394742) (xy 289.798808 -356.470181) (xy 289.805435 -356.54647)
			(xy 289.805872 -356.584758) (xy 289.805362 -356.625872) (xy 289.797778 -356.707749) (xy 289.782672 -356.788578)
			(xy 289.760173 -356.867667) (xy 289.730472 -356.944344) (xy 289.693822 -357.017952) (xy 289.650537 -357.087865)
			(xy 289.600986 -357.153486) (xy 289.545592 -357.214255) (xy 289.484826 -357.269653) (xy 289.419208 -357.319208)
			(xy 289.349298 -357.362497) (xy 289.275691 -357.399151) (xy 289.199017 -357.428856) (xy 289.119928 -357.45136)
			(xy 289.039101 -357.466471) (xy 288.957224 -357.474059) (xy 288.91611 -357.47452) (xy 288.87782 -357.474114)
			(xy 288.801526 -357.467506) (xy 288.726084 -357.454357) (xy 288.652053 -357.434764) (xy 288.615882 -357.422196)
			(xy 288.607445 -357.419545) (xy 288.589775 -357.419545) (xy 288.581338 -357.422196) (xy 288.54516 -357.434739)
			(xy 288.471127 -357.454312) (xy 288.395688 -357.46746) (xy 288.319398 -357.474084) (xy 288.28111 -357.47452)
			(xy 288.24282 -357.474114) (xy 288.166526 -357.467506) (xy 288.091084 -357.454357) (xy 288.017053 -357.434764)
			(xy 287.980882 -357.422196) (xy 287.972445 -357.419545) (xy 287.954775 -357.419545) (xy 287.946338 -357.422196)
			(xy 287.91016 -357.434739) (xy 287.836127 -357.454312) (xy 287.760688 -357.46746) (xy 287.684398 -357.474084)
			(xy 287.64611 -357.47452) (xy 287.60782 -357.474114) (xy 287.531526 -357.467506) (xy 287.456084 -357.454357)
			(xy 287.382053 -357.434764) (xy 287.345882 -357.422196) (xy 287.337445 -357.419545) (xy 287.319775 -357.419545)
			(xy 287.311338 -357.422196) (xy 287.27516 -357.434739) (xy 287.201127 -357.454312) (xy 287.125688 -357.46746)
			(xy 287.049398 -357.474084) (xy 287.01111 -357.47452) (xy 286.97282 -357.474114) (xy 286.896526 -357.467506)
			(xy 286.821084 -357.454357) (xy 286.747053 -357.434764) (xy 286.710882 -357.422196) (xy 286.702445 -357.419545)
			(xy 286.684775 -357.419545) (xy 286.676338 -357.422196) (xy 286.64016 -357.434739) (xy 286.566127 -357.454312)
			(xy 286.490688 -357.46746) (xy 286.414398 -357.474084) (xy 286.37611 -357.47452) (xy 286.334994 -357.474092)
			(xy 286.253113 -357.466505) (xy 286.172281 -357.451395) (xy 286.093188 -357.428892) (xy 286.016509 -357.399186)
			(xy 285.942899 -357.362532) (xy 285.872984 -357.319241) (xy 285.807362 -357.269685) (xy 285.746593 -357.214284)
			(xy 285.691195 -357.153513) (xy 285.641641 -357.08789) (xy 285.598353 -357.017973) (xy 285.561701 -356.944361)
			(xy 285.531998 -356.867681) (xy 285.509497 -356.788588) (xy 285.49439 -356.707755) (xy 285.486807 -356.625874)
			(xy 285.486348 -356.584758) (xy 285.48677 -356.546469) (xy 285.493373 -356.470175) (xy 285.506518 -356.394732)
			(xy 285.526107 -356.320701) (xy 285.538672 -356.28453) (xy 285.541343 -356.276098) (xy 285.541329 -356.258423)
			(xy 285.538672 -356.249986) (xy 285.526141 -356.213804) (xy 285.506565 -356.139773) (xy 285.493414 -356.064334)
			(xy 285.486786 -355.988046) (xy 285.486348 -355.949758) (xy 285.486781 -355.910896) (xy 285.493587 -355.833469)
			(xy 285.507119 -355.756932) (xy 285.527272 -355.681865) (xy 285.540196 -355.645212) (xy 285.542998 -355.636321)
			(xy 285.542744 -355.617697) (xy 285.539688 -355.60889) (xy 285.524486 -355.569489) (xy 285.500735 -355.488437)
			(xy 285.484763 -355.405502) (xy 285.476712 -355.321427) (xy 285.476188 -355.279198) (xy 195.742079 -355.279198)
			(xy 195.735206 -355.292996) (xy 195.691912 -355.362897) (xy 195.642352 -355.428505) (xy 195.586949 -355.48926)
			(xy 195.526176 -355.544642) (xy 195.460551 -355.59418) (xy 195.390636 -355.637451) (xy 195.317025 -355.674085)
			(xy 195.240348 -355.703769) (xy 195.161258 -355.726251) (xy 195.080432 -355.741339) (xy 194.998557 -355.748903)
			(xy 194.957446 -355.749352) (xy 194.915842 -355.74888) (xy 194.832994 -355.741147) (xy 194.75123 -355.725716)
			(xy 194.671262 -355.702722) (xy 194.593789 -355.672366) (xy 194.519488 -355.634911) (xy 194.48399 -355.613208)
			(xy 194.474858 -355.608031) (xy 194.454138 -355.60482) (xy 194.433861 -355.61016) (xy 194.425316 -355.616256)
			(xy 194.391667 -355.642178) (xy 194.320293 -355.688236) (xy 194.244854 -355.727283) (xy 194.166037 -355.758962)
			(xy 194.08456 -355.782986) (xy 194.001164 -355.799135) (xy 193.916608 -355.807262) (xy 193.874136 -355.807772)
			(xy 193.873882 -355.807772) (xy 193.832775 -355.807305) (xy 193.750912 -355.799719) (xy 193.670098 -355.784614)
			(xy 193.591023 -355.762118) (xy 193.514359 -355.732423) (xy 193.440762 -355.695782) (xy 193.370859 -355.652509)
			(xy 193.305245 -355.602971) (xy 193.244482 -355.547592) (xy 193.189086 -355.486844) (xy 193.13953 -355.421244)
			(xy 193.096237 -355.351353) (xy 193.059577 -355.277766) (xy 193.029861 -355.201111) (xy 193.007343 -355.122041)
			(xy 192.992215 -355.041231) (xy 192.984607 -354.959371) (xy 192.98412 -354.918264) (xy 192.984683 -354.873494)
			(xy 192.993693 -354.784409) (xy 193.011598 -354.696678) (xy 193.038217 -354.611187) (xy 193.05524 -354.569776)
			(xy 193.058825 -354.560191) (xy 193.058812 -354.539743) (xy 193.05524 -354.530152) (xy 193.03824 -354.4888)
			(xy 193.011628 -354.403438) (xy 192.99372 -354.315836) (xy 192.984697 -354.226879) (xy 192.98412 -354.182172)
			(xy 192.98412 -354.181156) (xy 192.984374 -354.169726) (xy 192.957895 -354.163781) (xy 192.90566 -354.149038)
			(xy 192.87998 -354.140262) (xy 192.871783 -354.137748) (xy 192.854649 -354.137748) (xy 192.846452 -354.140262)
			(xy 192.811236 -354.152209) (xy 192.739226 -354.170796) (xy 192.665903 -354.183236) (xy 192.591792 -354.18944)
			(xy 192.554606 -354.189792) (xy 192.517422 -354.189422) (xy 192.443314 -354.1832) (xy 192.369994 -354.170758)
			(xy 192.297983 -354.152184) (xy 192.26276 -354.140262) (xy 192.254563 -354.137748) (xy 192.237429 -354.137748)
			(xy 192.229232 -354.140262) (xy 192.19413 -354.15215) (xy 192.122374 -354.1707) (xy 192.049311 -354.183146)
			(xy 191.97546 -354.189399) (xy 191.938402 -354.189792) (xy 191.937386 -354.189792) (xy 191.89546 -354.189345)
			(xy 191.811988 -354.181373) (xy 191.729651 -354.165503) (xy 191.649196 -354.141878) (xy 191.57135 -354.110712)
			(xy 191.49682 -354.072288) (xy 191.42628 -354.026953) (xy 191.360368 -353.975119) (xy 191.299682 -353.917254)
			(xy 191.244771 -353.853882) (xy 191.196132 -353.785578) (xy 191.154206 -353.71296) (xy 191.119373 -353.636685)
			(xy 191.091948 -353.557444) (xy 191.07218 -353.475956) (xy 191.060246 -353.392957) (xy 191.056256 -353.3092)
			(xy 187.519078 -353.3092) (xy 187.520094 -353.320137) (xy 187.52058 -353.361244) (xy 187.52002 -353.406014)
			(xy 187.511009 -353.495099) (xy 187.493104 -353.58283) (xy 187.466484 -353.668321) (xy 187.44946 -353.709732)
			(xy 187.44587 -353.719315) (xy 187.445886 -353.739765) (xy 187.44946 -353.749356) (xy 187.466484 -353.790767)
			(xy 187.493121 -353.876254) (xy 187.511029 -353.963986) (xy 187.520026 -354.053074) (xy 187.52058 -354.097844)
			(xy 187.52002 -354.142614) (xy 187.511009 -354.231699) (xy 187.493104 -354.31943) (xy 187.466484 -354.404921)
			(xy 187.44946 -354.446332) (xy 187.44587 -354.455915) (xy 187.445886 -354.476365) (xy 187.44946 -354.485956)
			(xy 187.466484 -354.527367) (xy 187.493121 -354.612854) (xy 187.511029 -354.700586) (xy 187.520026 -354.789674)
			(xy 187.52058 -354.834444) (xy 187.520189 -354.875556) (xy 187.512597 -354.957429) (xy 187.497482 -355.038252)
			(xy 187.474973 -355.117336) (xy 187.445261 -355.194004) (xy 187.408601 -355.267604) (xy 187.365306 -355.337506)
			(xy 187.315744 -355.403115) (xy 187.260339 -355.46387) (xy 187.199564 -355.519252) (xy 187.133937 -355.56879)
			(xy 187.064019 -355.61206) (xy 186.990406 -355.648693) (xy 186.913727 -355.678376) (xy 186.834635 -355.700857)
			(xy 186.753806 -355.715942) (xy 186.67193 -355.723505) (xy 186.630818 -355.723952) (xy 186.589214 -355.723494)
			(xy 186.506365 -355.715758) (xy 186.424601 -355.700325) (xy 186.344633 -355.677328) (xy 186.267161 -355.646969)
			(xy 186.192859 -355.609513) (xy 186.157362 -355.587808) (xy 186.148243 -355.582606) (xy 186.127514 -355.579404)
			(xy 186.107233 -355.584754) (xy 186.098688 -355.590856) (xy 186.065049 -355.616791) (xy 185.993673 -355.662848)
			(xy 185.918232 -355.701893) (xy 185.839413 -355.73357) (xy 185.757935 -355.757592) (xy 185.674537 -355.773739)
			(xy 185.589981 -355.781864) (xy 185.547508 -355.782372) (xy 185.547254 -355.782372) (xy 185.506147 -355.781931)
			(xy 185.424283 -355.774343) (xy 185.343469 -355.759235) (xy 185.264393 -355.736737) (xy 185.187729 -355.70704)
			(xy 185.114132 -355.670398) (xy 185.044229 -355.627122) (xy 184.978615 -355.577583) (xy 184.917852 -355.522202)
			(xy 184.862456 -355.461452) (xy 184.812901 -355.395851) (xy 184.769609 -355.325959) (xy 184.732948 -355.252371)
			(xy 184.703232 -355.175714) (xy 184.680715 -355.096644) (xy 184.665587 -355.015833) (xy 184.657979 -354.933971)
			(xy 184.657492 -354.892864) (xy 184.658057 -354.848094) (xy 184.667066 -354.759009) (xy 184.684971 -354.671278)
			(xy 184.711589 -354.585787) (xy 184.728612 -354.544376) (xy 184.732199 -354.534792) (xy 184.732185 -354.514343)
			(xy 184.728612 -354.504752) (xy 184.711616 -354.463398) (xy 184.685002 -354.378037) (xy 184.667093 -354.290435)
			(xy 184.658069 -354.201478) (xy 184.657492 -354.156772) (xy 184.657492 -354.155756) (xy 184.657746 -354.144326)
			(xy 184.631266 -354.138384) (xy 184.579032 -354.123639) (xy 184.553352 -354.114862) (xy 184.545155 -354.112348)
			(xy 184.528021 -354.112348) (xy 184.519824 -354.114862) (xy 184.484602 -354.126789) (xy 184.412594 -354.145381)
			(xy 184.339273 -354.157827) (xy 184.265163 -354.164037) (xy 184.227978 -354.164392) (xy 184.190794 -354.16403)
			(xy 184.116686 -354.157806) (xy 184.043366 -354.145361) (xy 183.971355 -354.126785) (xy 183.936132 -354.114862)
			(xy 183.927935 -354.112348) (xy 183.910801 -354.112348) (xy 183.902604 -354.114862) (xy 183.867505 -354.126757)
			(xy 183.795747 -354.145305) (xy 183.722684 -354.157749) (xy 183.648832 -354.164001) (xy 183.611774 -354.164392)
			(xy 183.610758 -354.164392) (xy 183.568833 -354.163944) (xy 183.485362 -354.155969) (xy 183.403028 -354.140097)
			(xy 183.322575 -354.11647) (xy 183.244732 -354.085304) (xy 183.170204 -354.046879) (xy 183.099666 -354.001544)
			(xy 183.033756 -353.949709) (xy 182.973072 -353.891844) (xy 182.918163 -353.828473) (xy 182.869527 -353.760169)
			(xy 182.827603 -353.687552) (xy 182.792771 -353.611278) (xy 182.765347 -353.532039) (xy 182.745579 -353.450553)
			(xy 182.733646 -353.367555) (xy 182.729656 -353.2838) (xy 78.346936 -353.2838) (xy 78.321217 -353.348042)
			(xy 78.282395 -353.423345) (xy 78.236592 -353.494617) (xy 78.184221 -353.561213) (xy 78.125756 -353.622528)
			(xy 78.061728 -353.678009) (xy 77.992716 -353.727152) (xy 77.919346 -353.769512) (xy 77.842281 -353.804707)
			(xy 77.762219 -353.832416) (xy 77.679886 -353.85239) (xy 77.596027 -353.864447) (xy 77.511402 -353.868479)
			(xy 77.426777 -353.864447) (xy 77.342918 -353.85239) (xy 77.260585 -353.832416) (xy 77.180523 -353.804707)
			(xy 77.103458 -353.769512) (xy 77.030088 -353.727152) (xy 76.961076 -353.678009) (xy 76.897048 -353.622528)
			(xy 76.838583 -353.561213) (xy 76.786212 -353.494617) (xy 76.740409 -353.423345) (xy 76.701587 -353.348042)
			(xy 76.670099 -353.26939) (xy 76.646231 -353.1881) (xy 76.630197 -353.10491) (xy 76.622144 -353.020573)
			(xy 76.62164 -352.978212) (xy 76.622159 -352.935266) (xy 76.630462 -352.849776) (xy 76.646954 -352.765482)
			(xy 76.671481 -352.683166) (xy 76.687172 -352.643186) (xy 76.690418 -352.63393) (xy 76.690431 -352.614336)
			(xy 76.687172 -352.605086) (xy 76.671432 -352.565089) (xy 76.646875 -352.482712) (xy 76.630388 -352.398348)
			(xy 76.622124 -352.312786) (xy 76.62164 -352.269806) (xy 76.622244 -352.224161) (xy 76.631638 -352.133355)
			(xy 76.650266 -352.043985) (xy 76.66355 -352.000312) (xy 76.665996 -351.9913) (xy 76.664956 -351.972672)
			(xy 76.661518 -351.96399) (xy 76.642856 -351.920903) (xy 76.61365 -351.831658) (xy 76.594004 -351.739834)
			(xy 76.584137 -351.646451) (xy 76.58354 -351.5995) (xy 75.70064 -351.5995) (xy 75.701144 -351.637854)
			(xy 75.70053 -351.683499) (xy 75.691141 -351.774304) (xy 75.672516 -351.863674) (xy 75.659234 -351.907348)
			(xy 75.65681 -351.916364) (xy 75.657836 -351.934988) (xy 75.661266 -351.94367) (xy 75.679947 -351.986749)
			(xy 75.709149 -352.075997) (xy 75.728789 -352.167824) (xy 75.738651 -352.261208) (xy 75.739244 -352.30816)
			(xy 75.738798 -352.348493) (xy 75.731529 -352.428831) (xy 75.71702 -352.508181) (xy 75.69539 -352.585893)
			(xy 75.666817 -352.661328) (xy 75.649582 -352.697796) (xy 75.645066 -352.708391) (xy 75.645063 -352.731399)
			(xy 75.649582 -352.741992) (xy 75.666819 -352.778431) (xy 75.69537 -352.853821) (xy 75.716991 -352.931483)
			(xy 75.731505 -353.010781) (xy 75.738793 -353.091066) (xy 75.739244 -353.131374) (xy 75.73874 -353.173735)
			(xy 75.730687 -353.258072) (xy 75.714653 -353.341262) (xy 75.690785 -353.422552) (xy 75.659297 -353.501204)
			(xy 75.620475 -353.576507) (xy 75.574672 -353.647779) (xy 75.522301 -353.714375) (xy 75.463836 -353.77569)
			(xy 75.399808 -353.831171) (xy 75.330796 -353.880314) (xy 75.257426 -353.922674) (xy 75.180361 -353.957869)
			(xy 75.100299 -353.985578) (xy 75.017966 -354.005552) (xy 74.934107 -354.017609) (xy 74.849482 -354.021641)
			(xy 74.764857 -354.017609) (xy 74.680998 -354.005552) (xy 74.598665 -353.985578) (xy 74.518603 -353.957869)
			(xy 74.441538 -353.922674) (xy 74.368168 -353.880314) (xy 74.299156 -353.831171) (xy 74.235128 -353.77569)
			(xy 74.176663 -353.714375) (xy 74.124292 -353.647779) (xy 74.078489 -353.576507) (xy 74.039667 -353.501204)
			(xy 74.008179 -353.422552) (xy 73.984311 -353.341262) (xy 73.968277 -353.258072) (xy 73.960224 -353.173735)
			(xy 73.95972 -353.131374) (xy 73.960164 -353.091034) (xy 73.96747 -353.010685) (xy 73.982028 -352.931329)
			(xy 74.003719 -352.85362) (xy 74.032363 -352.778196) (xy 74.049636 -352.741738) (xy 74.054225 -352.731091)
			(xy 74.054231 -352.707932) (xy 74.049636 -352.697288) (xy 74.032445 -352.660861) (xy 74.003936 -352.58552)
			(xy 73.98236 -352.50791) (xy 73.967893 -352.428665) (xy 73.960655 -352.348437) (xy 73.960228 -352.30816)
			(xy 73.960797 -352.262521) (xy 73.970094 -352.171718) (xy 73.988639 -352.082344) (xy 74.001884 -352.038666)
			(xy 74.004352 -352.029659) (xy 74.003297 -352.011026) (xy 73.999852 -352.002344) (xy 73.981136 -351.959272)
			(xy 73.95186 -351.870033) (xy 73.932154 -351.778206) (xy 73.922237 -351.684813) (xy 73.92162 -351.637854)
			(xy 2.509012 -351.637854) (xy 2.509012 -358.071674) (xy 14.438884 -358.071674) (xy 14.438884 -357.208074)
			(xy 14.43937 -357.180805) (xy 14.447132 -357.126821) (xy 14.462497 -357.074491) (xy 14.485154 -357.024881)
			(xy 14.51464 -356.979) (xy 14.550355 -356.937783) (xy 14.591572 -356.902068) (xy 14.637453 -356.872582)
			(xy 14.687063 -356.849925) (xy 14.739393 -356.83456) (xy 14.793377 -356.826798) (xy 14.847915 -356.826798)
			(xy 14.901899 -356.83456) (xy 14.954229 -356.849925) (xy 15.003839 -356.872582) (xy 15.04972 -356.902068)
			(xy 15.090937 -356.937783) (xy 15.126652 -356.979) (xy 15.156138 -357.024881) (xy 15.178795 -357.074491)
			(xy 15.19416 -357.126821) (xy 15.201922 -357.180805) (xy 15.202408 -357.208074) (xy 15.202408 -358.071674)
			(xy 15.201922 -358.098943) (xy 15.19416 -358.152927) (xy 15.178795 -358.205257) (xy 15.156138 -358.254867)
			(xy 15.126652 -358.300748) (xy 15.090937 -358.341965) (xy 15.04972 -358.37768) (xy 15.003839 -358.407166)
			(xy 14.954229 -358.429823) (xy 14.901899 -358.445188) (xy 14.847915 -358.45295) (xy 14.793377 -358.45295)
			(xy 14.739393 -358.445188) (xy 14.687063 -358.429823) (xy 14.637453 -358.407166) (xy 14.591572 -358.37768)
			(xy 14.550355 -358.341965) (xy 14.51464 -358.300748) (xy 14.485154 -358.254867) (xy 14.462497 -358.205257)
			(xy 14.447132 -358.152927) (xy 14.43937 -358.098943) (xy 14.438884 -358.071674) (xy 2.509012 -358.071674)
			(xy 2.509012 -358.549194) (xy 40.47998 -358.549194) (xy 40.480352 -358.511134) (xy 40.486825 -358.435291)
			(xy 40.499758 -358.360279) (xy 40.519056 -358.286646) (xy 40.544577 -358.214933) (xy 40.55999 -358.180132)
			(xy 40.563435 -358.171803) (xy 40.56487 -358.153848) (xy 40.562784 -358.14508) (xy 40.551663 -358.104882)
			(xy 40.536092 -358.022938) (xy 40.528245 -357.939897) (xy 40.527732 -357.898192) (xy 40.528135 -357.859902)
			(xy 40.534744 -357.783608) (xy 40.547894 -357.708165) (xy 40.567488 -357.634135) (xy 40.580056 -357.597964)
			(xy 40.58271 -357.589528) (xy 40.582708 -357.571857) (xy 40.580056 -357.56342) (xy 40.567506 -357.527245)
			(xy 40.547935 -357.453211) (xy 40.53479 -357.37777) (xy 40.528167 -357.30148) (xy 40.527732 -357.263192)
			(xy 40.528236 -357.220831) (xy 40.536289 -357.136494) (xy 40.552323 -357.053304) (xy 40.576191 -356.972014)
			(xy 40.607679 -356.893362) (xy 40.646501 -356.818059) (xy 40.692304 -356.746787) (xy 40.744675 -356.680191)
			(xy 40.80314 -356.618876) (xy 40.867168 -356.563395) (xy 40.93618 -356.514252) (xy 41.00955 -356.471892)
			(xy 41.086615 -356.436697) (xy 41.166677 -356.408988) (xy 41.24901 -356.389014) (xy 41.332869 -356.376957)
			(xy 41.417494 -356.372926) (xy 41.502119 -356.376957) (xy 41.585978 -356.389014) (xy 41.668311 -356.408988)
			(xy 41.748373 -356.436697) (xy 41.825438 -356.471892) (xy 41.898808 -356.514252) (xy 41.96782 -356.563395)
			(xy 42.031848 -356.618876) (xy 42.090313 -356.680191) (xy 42.142684 -356.746787) (xy 42.188487 -356.818059)
			(xy 42.227309 -356.893362) (xy 42.258797 -356.972014) (xy 42.282665 -357.053304) (xy 42.298699 -357.136494)
			(xy 42.306752 -357.220831) (xy 42.307256 -357.263192) (xy 42.306849 -357.301482) (xy 42.300241 -357.377776)
			(xy 42.287093 -357.453218) (xy 42.2675 -357.527249) (xy 42.254932 -357.56342) (xy 42.252286 -357.571858)
			(xy 42.252283 -357.589527) (xy 42.254932 -357.597964) (xy 42.267477 -357.634141) (xy 42.28705 -357.708174)
			(xy 42.300196 -357.783614) (xy 42.30682 -357.859904) (xy 42.307256 -357.898192) (xy 42.306876 -357.936251)
			(xy 42.300404 -358.012094) (xy 42.287473 -358.087107) (xy 42.268177 -358.160739) (xy 42.242658 -358.232452)
			(xy 42.227246 -358.267254) (xy 42.223809 -358.275586) (xy 42.222368 -358.293538) (xy 42.224452 -358.302306)
			(xy 42.23557 -358.342505) (xy 42.251142 -358.424449) (xy 42.258991 -358.507489) (xy 42.259032 -358.51084)
			(xy 43.046396 -358.51084) (xy 43.046759 -358.47278) (xy 43.053225 -358.396935) (xy 43.066156 -358.321921)
			(xy 43.085458 -358.248289) (xy 43.110988 -358.176577) (xy 43.126406 -358.141778) (xy 43.129746 -358.133421)
			(xy 43.131033 -358.115482) (xy 43.128946 -358.106726) (xy 43.117873 -358.066521) (xy 43.102375 -357.984574)
			(xy 43.094614 -357.901538) (xy 43.094148 -357.859838) (xy 43.094524 -357.821522) (xy 43.101053 -357.745169)
			(xy 43.114136 -357.669662) (xy 43.133673 -357.595562) (xy 43.146218 -357.559356) (xy 43.148787 -357.551035)
			(xy 43.148799 -357.533636) (xy 43.146218 -357.52532) (xy 43.13374 -357.489193) (xy 43.114246 -357.415282)
			(xy 43.101158 -357.339973) (xy 43.094573 -357.263819) (xy 43.094148 -357.2256) (xy 43.094148 -357.224838)
			(xy 43.094652 -357.18249) (xy 43.102703 -357.098176) (xy 43.118732 -357.01501) (xy 43.142593 -356.933743)
			(xy 43.174072 -356.855113) (xy 43.212883 -356.779832) (xy 43.258673 -356.70858) (xy 43.311029 -356.642004)
			(xy 43.369477 -356.580706) (xy 43.433487 -356.525241) (xy 43.502479 -356.476112) (xy 43.575829 -356.433763)
			(xy 43.652872 -356.398579) (xy 43.732911 -356.370877) (xy 43.81522 -356.350909) (xy 43.899055 -356.338856)
			(xy 43.983656 -356.334826) (xy 44.068257 -356.338856) (xy 44.152092 -356.350909) (xy 44.234401 -356.370877)
			(xy 44.31444 -356.398579) (xy 44.391483 -356.433763) (xy 44.464833 -356.476112) (xy 44.533825 -356.525241)
			(xy 44.597835 -356.580706) (xy 44.656283 -356.642004) (xy 44.708639 -356.70858) (xy 44.754429 -356.779832)
			(xy 44.79324 -356.855113) (xy 44.824719 -356.933743) (xy 44.84858 -357.01501) (xy 44.864609 -357.098176)
			(xy 44.87266 -357.18249) (xy 44.873164 -357.224838) (xy 44.873164 -357.2256) (xy 44.87277 -357.263821)
			(xy 44.866201 -357.339979) (xy 44.853113 -357.415292) (xy 44.833602 -357.489202) (xy 44.821094 -357.52532)
			(xy 44.818487 -357.533631) (xy 44.818499 -357.55104) (xy 44.821094 -357.559356) (xy 44.833623 -357.595567)
			(xy 44.853143 -357.669669) (xy 44.866225 -357.745173) (xy 44.872771 -357.821523) (xy 44.873164 -357.859838)
			(xy 44.872788 -357.897898) (xy 44.866324 -357.973742) (xy 44.853395 -358.048756) (xy 44.837736 -358.108504)
			(xy 46.991016 -358.108504) (xy 46.991397 -358.070445) (xy 46.997869 -357.994602) (xy 47.0108 -357.919589)
			(xy 47.030096 -357.845957) (xy 47.055615 -357.774244) (xy 47.071026 -357.739442) (xy 47.074466 -357.731111)
			(xy 47.075906 -357.713158) (xy 47.07382 -357.70439) (xy 47.0627 -357.664192) (xy 47.047129 -357.582247)
			(xy 47.039281 -357.499207) (xy 47.038768 -357.457502) (xy 47.039173 -357.419212) (xy 47.045781 -357.342918)
			(xy 47.05893 -357.267476) (xy 47.078524 -357.193445) (xy 47.091092 -357.157274) (xy 47.09374 -357.148837)
			(xy 47.093741 -357.131167) (xy 47.091092 -357.12273) (xy 47.078546 -357.086553) (xy 47.058974 -357.01252)
			(xy 47.045827 -356.93708) (xy 47.039204 -356.86079) (xy 47.038768 -356.822502) (xy 47.0392 -356.781386)
			(xy 47.046788 -356.699506) (xy 47.061898 -356.618674) (xy 47.084402 -356.539582) (xy 47.114108 -356.462904)
			(xy 47.150762 -356.389293) (xy 47.194052 -356.319379) (xy 47.243609 -356.253758) (xy 47.299008 -356.192989)
			(xy 47.359779 -356.137591) (xy 47.425402 -356.088036) (xy 47.495318 -356.044749) (xy 47.568929 -356.008097)
			(xy 47.645609 -355.978393) (xy 47.724702 -355.955891) (xy 47.805533 -355.940784) (xy 47.887414 -355.933199)
			(xy 47.92853 -355.93274) (xy 47.969637 -355.933252) (xy 48.051499 -355.940877) (xy 48.132307 -355.956023)
			(xy 48.211373 -355.97856) (xy 48.288023 -356.008296) (xy 48.325024 -356.026212) (xy 48.335846 -356.030917)
			(xy 48.359414 -356.030917) (xy 48.370236 -356.026212) (xy 48.407247 -356.008316) (xy 48.483894 -355.978575)
			(xy 48.562957 -355.956031) (xy 48.643763 -355.940876) (xy 48.725623 -355.93324) (xy 48.76673 -355.93274)
			(xy 48.80502 -355.933136) (xy 48.881314 -355.939747) (xy 48.956757 -355.952899) (xy 49.030787 -355.972495)
			(xy 49.066958 -355.985064) (xy 49.075395 -355.987715) (xy 49.093065 -355.987715) (xy 49.101502 -355.985064)
			(xy 49.137675 -355.972508) (xy 49.21171 -355.952938) (xy 49.287151 -355.939795) (xy 49.363442 -355.933174)
			(xy 49.40173 -355.93274) (xy 49.44002 -355.933136) (xy 49.516314 -355.939747) (xy 49.591757 -355.952899)
			(xy 49.665787 -355.972495) (xy 49.701958 -355.985064) (xy 49.710395 -355.987715) (xy 49.728065 -355.987715)
			(xy 49.736502 -355.985064) (xy 49.772675 -355.972508) (xy 49.84671 -355.952938) (xy 49.922151 -355.939795)
			(xy 49.998442 -355.933174) (xy 50.03673 -355.93274) (xy 50.07502 -355.933136) (xy 50.151314 -355.939747)
			(xy 50.226757 -355.952899) (xy 50.300787 -355.972495) (xy 50.336958 -355.985064) (xy 50.345395 -355.987715)
			(xy 50.363065 -355.987715) (xy 50.371502 -355.985064) (xy 50.407675 -355.972508) (xy 50.48171 -355.952938)
			(xy 50.557151 -355.939795) (xy 50.633442 -355.933174) (xy 50.67173 -355.93274) (xy 50.712845 -355.933184)
			(xy 50.794723 -355.940774) (xy 50.875552 -355.955886) (xy 50.954642 -355.978392) (xy 51.031318 -356.008098)
			(xy 51.104926 -356.044753) (xy 51.174838 -356.088043) (xy 51.240458 -356.137599) (xy 51.301225 -356.192997)
			(xy 51.356622 -356.253767) (xy 51.406175 -356.319388) (xy 51.449463 -356.389302) (xy 51.486115 -356.462911)
			(xy 51.515819 -356.539588) (xy 51.538321 -356.618679) (xy 51.55343 -356.699508) (xy 51.561017 -356.781387)
			(xy 51.561492 -356.822502) (xy 51.561091 -356.860792) (xy 51.554482 -356.937086) (xy 51.541332 -357.012529)
			(xy 51.521737 -357.086559) (xy 51.509168 -357.12273) (xy 51.506515 -357.131166) (xy 51.506516 -357.148837)
			(xy 51.509168 -357.157274) (xy 51.521713 -357.193451) (xy 51.541286 -357.267484) (xy 51.554433 -357.342924)
			(xy 51.561057 -357.419214) (xy 51.561492 -357.457502) (xy 51.561112 -357.495561) (xy 51.55464 -357.571404)
			(xy 51.541708 -357.646417) (xy 51.522413 -357.720049) (xy 51.496894 -357.791762) (xy 51.481482 -357.826564)
			(xy 51.478039 -357.834894) (xy 51.476603 -357.852848) (xy 51.478688 -357.861616) (xy 51.48981 -357.901814)
			(xy 51.50538 -357.983758) (xy 51.513227 -358.066799) (xy 51.51374 -358.108504) (xy 51.513251 -358.149614)
			(xy 51.505664 -358.231482) (xy 51.490553 -358.312301) (xy 51.468049 -358.391381) (xy 51.438343 -358.468047)
			(xy 51.401689 -358.541644) (xy 51.3584 -358.611544) (xy 51.308844 -358.677152) (xy 51.253446 -358.737906)
			(xy 51.192678 -358.793289) (xy 51.127058 -358.842827) (xy 51.057146 -358.886099) (xy 50.98354 -358.922734)
			(xy 50.906867 -358.952421) (xy 50.827781 -358.974905) (xy 50.746958 -358.989995) (xy 50.665088 -358.997562)
			(xy 50.623978 -358.998012) (xy 50.585661 -358.99765) (xy 50.509308 -358.991116) (xy 50.433801 -358.97803)
			(xy 50.359702 -358.958488) (xy 50.323496 -358.945942) (xy 50.31518 -358.943356) (xy 50.297776 -358.943356)
			(xy 50.28946 -358.945942) (xy 50.253248 -358.958468) (xy 50.179147 -358.977989) (xy 50.103642 -358.991071)
			(xy 50.027293 -358.997619) (xy 49.988978 -358.998012) (xy 49.950661 -358.99765) (xy 49.874308 -358.991116)
			(xy 49.798801 -358.97803) (xy 49.724702 -358.958488) (xy 49.688496 -358.945942) (xy 49.68018 -358.943356)
			(xy 49.662776 -358.943356) (xy 49.65446 -358.945942) (xy 49.618248 -358.958468) (xy 49.544147 -358.977989)
			(xy 49.468642 -358.991071) (xy 49.392293 -358.997619) (xy 49.353978 -358.998012) (xy 49.315661 -358.99765)
			(xy 49.239308 -358.991116) (xy 49.163801 -358.97803) (xy 49.089702 -358.958488) (xy 49.053496 -358.945942)
			(xy 49.04518 -358.943356) (xy 49.027776 -358.943356) (xy 49.01946 -358.945942) (xy 48.983339 -358.95844)
			(xy 48.909426 -358.977928) (xy 48.834115 -358.99101) (xy 48.757959 -358.99759) (xy 48.71974 -358.998012)
			(xy 48.718978 -358.998012) (xy 48.677876 -358.99753) (xy 48.596022 -358.989953) (xy 48.515216 -358.974857)
			(xy 48.436148 -358.95237) (xy 48.359491 -358.922685) (xy 48.322484 -358.904794) (xy 48.311662 -358.900089)
			(xy 48.288094 -358.900089) (xy 48.277272 -358.904794) (xy 48.240271 -358.922698) (xy 48.163612 -358.952379)
			(xy 48.084542 -358.974864) (xy 48.003735 -358.98996) (xy 47.92188 -358.997539) (xy 47.880778 -358.998012)
			(xy 47.839669 -358.997608) (xy 47.757803 -358.990022) (xy 47.676986 -358.974915) (xy 47.597907 -358.952416)
			(xy 47.52124 -358.922719) (xy 47.447641 -358.886075) (xy 47.377735 -358.842798) (xy 47.312121 -358.793256)
			(xy 47.251356 -358.737873) (xy 47.19596 -358.677119) (xy 47.146405 -358.611515) (xy 47.103114 -358.541618)
			(xy 47.066455 -358.468026) (xy 47.036742 -358.391366) (xy 47.014227 -358.312292) (xy 46.999104 -358.231477)
			(xy 46.9915 -358.149612) (xy 46.991016 -358.108504) (xy 44.837736 -358.108504) (xy 44.834097 -358.122388)
			(xy 44.808571 -358.1941) (xy 44.793154 -358.2289) (xy 44.789778 -358.237249) (xy 44.788481 -358.255202)
			(xy 44.790614 -358.263952) (xy 44.801704 -358.304153) (xy 44.817195 -358.386101) (xy 44.82495 -358.46914)
			(xy 44.825412 -358.51084) (xy 44.824852 -358.556303) (xy 44.815599 -358.646758) (xy 44.797171 -358.735798)
			(xy 44.78401 -358.779318) (xy 44.78146 -358.788893) (xy 44.783017 -358.808626) (xy 44.787058 -358.817672)
			(xy 44.805431 -358.855048) (xy 44.835897 -358.932566) (xy 44.858991 -359.012591) (xy 44.87451 -359.094423)
			(xy 44.882318 -359.177347) (xy 44.882816 -359.218992) (xy 44.882816 -359.219246) (xy 44.882312 -359.261594)
			(xy 44.874261 -359.345908) (xy 44.858232 -359.429074) (xy 44.834371 -359.510341) (xy 44.802892 -359.588971)
			(xy 44.764081 -359.664252) (xy 44.718291 -359.735504) (xy 44.665935 -359.80208) (xy 44.607487 -359.863378)
			(xy 44.543477 -359.918843) (xy 44.474485 -359.967972) (xy 44.401135 -360.010321) (xy 44.324092 -360.045505)
			(xy 44.244053 -360.073207) (xy 44.161744 -360.093175) (xy 44.077909 -360.105228) (xy 43.993308 -360.109259)
			(xy 43.908707 -360.105228) (xy 43.824872 -360.093175) (xy 43.742563 -360.073207) (xy 43.662524 -360.045505)
			(xy 43.585481 -360.010321) (xy 43.512131 -359.967972) (xy 43.443139 -359.918843) (xy 43.379129 -359.863378)
			(xy 43.320681 -359.80208) (xy 43.268325 -359.735504) (xy 43.222535 -359.664252) (xy 43.183724 -359.588971)
			(xy 43.152245 -359.510341) (xy 43.128384 -359.429074) (xy 43.112355 -359.345908) (xy 43.104304 -359.261594)
			(xy 43.1038 -359.219246) (xy 43.104356 -359.173782) (xy 43.113611 -359.083328) (xy 43.13204 -358.994288)
			(xy 43.145202 -358.950768) (xy 43.147759 -358.941194) (xy 43.146197 -358.921461) (xy 43.142154 -358.912414)
			(xy 43.123767 -358.875016) (xy 43.093286 -358.797449) (xy 43.070189 -358.717372) (xy 43.054676 -358.635487)
			(xy 43.046883 -358.552511) (xy 43.046396 -358.51084) (xy 42.259032 -358.51084) (xy 42.259504 -358.549194)
			(xy 42.258889 -358.594663) (xy 42.249552 -358.685121) (xy 42.231047 -358.774157) (xy 42.217848 -358.817672)
			(xy 42.215273 -358.827242) (xy 42.216849 -358.846979) (xy 42.220896 -358.856026) (xy 42.239309 -358.893418)
			(xy 42.269845 -358.970977) (xy 42.292996 -359.051051) (xy 42.308559 -359.132939) (xy 42.316398 -359.215923)
			(xy 42.316908 -359.2576) (xy 42.316404 -359.299961) (xy 42.308351 -359.384298) (xy 42.292317 -359.467488)
			(xy 42.268449 -359.548778) (xy 42.236961 -359.62743) (xy 42.198139 -359.702733) (xy 42.152336 -359.774005)
			(xy 42.099965 -359.840601) (xy 42.0415 -359.901916) (xy 41.977472 -359.957397) (xy 41.90846 -360.00654)
			(xy 41.83509 -360.0489) (xy 41.758025 -360.084095) (xy 41.677963 -360.111804) (xy 41.59563 -360.131778)
			(xy 41.511771 -360.143835) (xy 41.427146 -360.147867) (xy 41.342521 -360.143835) (xy 41.258662 -360.131778)
			(xy 41.176329 -360.111804) (xy 41.096267 -360.084095) (xy 41.019202 -360.0489) (xy 40.945832 -360.00654)
			(xy 40.87682 -359.957397) (xy 40.812792 -359.901916) (xy 40.754327 -359.840601) (xy 40.701956 -359.774005)
			(xy 40.656153 -359.702733) (xy 40.617331 -359.62743) (xy 40.585843 -359.548778) (xy 40.561975 -359.467488)
			(xy 40.545941 -359.384298) (xy 40.537888 -359.299961) (xy 40.537384 -359.2576) (xy 40.537998 -359.212131)
			(xy 40.547335 -359.121673) (xy 40.565841 -359.032637) (xy 40.57904 -358.989122) (xy 40.581619 -358.979553)
			(xy 40.580041 -358.959815) (xy 40.575992 -358.950768) (xy 40.557613 -358.91336) (xy 40.527071 -358.835806)
			(xy 40.503913 -358.755736) (xy 40.488342 -358.673851) (xy 40.480494 -358.59087) (xy 40.47998 -358.549194)
			(xy 2.509012 -358.549194) (xy 2.509012 -361.825848) (xy 5.986007 -361.825848) (xy 5.986007 -361.696708)
			(xy 5.993957 -361.567813) (xy 6.009827 -361.439653) (xy 6.033556 -361.312712) (xy 6.065055 -361.187473)
			(xy 6.104204 -361.06441) (xy 6.150855 -360.943991) (xy 6.20483 -360.826672) (xy 6.265925 -360.712898)
			(xy 6.333908 -360.603101) (xy 6.408522 -360.497698) (xy 6.489483 -360.397088) (xy 6.576483 -360.301653)
			(xy 6.669194 -360.211754) (xy 6.767264 -360.127733) (xy 6.870319 -360.049909) (xy 6.97797 -359.978577)
			(xy 7.089809 -359.914007) (xy 7.20541 -359.856445) (xy 7.324335 -359.806108) (xy 7.446134 -359.763188)
			(xy 7.570344 -359.727847) (xy 7.696493 -359.70022) (xy 7.824105 -359.680411) (xy 7.952694 -359.668495)
			(xy 8.081772 -359.664519) (xy 8.21085 -359.668495) (xy 8.339439 -359.680411) (xy 8.467051 -359.70022)
			(xy 8.5932 -359.727847) (xy 8.71741 -359.763188) (xy 8.839209 -359.806108) (xy 8.958134 -359.856445)
			(xy 9.073735 -359.914007) (xy 9.185574 -359.978577) (xy 9.293225 -360.049909) (xy 9.39628 -360.127733)
			(xy 9.49435 -360.211754) (xy 9.587061 -360.301653) (xy 9.674061 -360.397088) (xy 9.689764 -360.416602)
			(xy 12.542012 -360.416602) (xy 12.542012 -359.553002) (xy 12.542498 -359.525751) (xy 12.550254 -359.471803)
			(xy 12.565609 -359.419508) (xy 12.588251 -359.369931) (xy 12.617717 -359.324081) (xy 12.653408 -359.28289)
			(xy 12.694599 -359.247199) (xy 12.740449 -359.217733) (xy 12.790026 -359.195091) (xy 12.842321 -359.179736)
			(xy 12.896269 -359.17198) (xy 12.950771 -359.17198) (xy 13.004719 -359.179736) (xy 13.057014 -359.195091)
			(xy 13.106591 -359.217733) (xy 13.152441 -359.247199) (xy 13.193632 -359.28289) (xy 13.229323 -359.324081)
			(xy 13.258789 -359.369931) (xy 13.281431 -359.419508) (xy 13.296786 -359.471803) (xy 13.304542 -359.525751)
			(xy 13.305028 -359.553002) (xy 13.305028 -360.416602) (xy 13.304542 -360.443853) (xy 13.296786 -360.497801)
			(xy 13.281431 -360.550096) (xy 13.258789 -360.599673) (xy 13.229323 -360.645523) (xy 13.193632 -360.686714)
			(xy 13.152441 -360.722405) (xy 13.106591 -360.751871) (xy 13.057014 -360.774513) (xy 13.004719 -360.789868)
			(xy 12.950771 -360.797624) (xy 12.896269 -360.797624) (xy 12.842321 -360.789868) (xy 12.790026 -360.774513)
			(xy 12.740449 -360.751871) (xy 12.694599 -360.722405) (xy 12.653408 -360.686714) (xy 12.617717 -360.645523)
			(xy 12.588251 -360.599673) (xy 12.565609 -360.550096) (xy 12.550254 -360.497801) (xy 12.542498 -360.443853)
			(xy 12.542012 -360.416602) (xy 9.689764 -360.416602) (xy 9.755022 -360.497698) (xy 9.829636 -360.603101)
			(xy 9.897619 -360.712898) (xy 9.958714 -360.826672) (xy 10.012689 -360.943991) (xy 10.05934 -361.06441)
			(xy 10.098489 -361.187473) (xy 10.129988 -361.312712) (xy 10.153717 -361.439653) (xy 10.169587 -361.567813)
			(xy 10.177537 -361.696708) (xy 10.178034 -361.761278) (xy 10.177537 -361.825848) (xy 10.169587 -361.954743)
			(xy 10.153717 -362.082903) (xy 10.129988 -362.209844) (xy 10.098489 -362.335083) (xy 10.079022 -362.396278)
			(xy 165.733984 -362.396278) (xy 165.733984 -361.532678) (xy 165.73447 -361.505409) (xy 165.742232 -361.451425)
			(xy 165.757597 -361.399095) (xy 165.780254 -361.349485) (xy 165.80974 -361.303604) (xy 165.845455 -361.262387)
			(xy 165.886672 -361.226672) (xy 165.932553 -361.197186) (xy 165.982163 -361.174529) (xy 166.034493 -361.159164)
			(xy 166.088477 -361.151402) (xy 166.143015 -361.151402) (xy 166.196999 -361.159164) (xy 166.249329 -361.174529)
			(xy 166.298939 -361.197186) (xy 166.34482 -361.226672) (xy 166.386037 -361.262387) (xy 166.421752 -361.303604)
			(xy 166.451238 -361.349485) (xy 166.473895 -361.399095) (xy 166.48926 -361.451425) (xy 166.497022 -361.505409)
			(xy 166.497508 -361.532678) (xy 166.497508 -362.234988) (xy 185.144664 -362.234988) (xy 185.144664 -362.23448)
			(xy 185.145268 -362.188148) (xy 185.154941 -362.09599) (xy 185.174137 -362.005336) (xy 185.202649 -361.917167)
			(xy 185.220864 -361.874562) (xy 185.224678 -361.864622) (xy 185.224673 -361.843356) (xy 185.220864 -361.833414)
			(xy 185.202614 -361.790754) (xy 185.174071 -361.702461) (xy 185.15488 -361.611675) (xy 185.145248 -361.519384)
			(xy 185.144664 -361.472988) (xy 185.145245 -361.426592) (xy 185.154891 -361.334304) (xy 185.174088 -361.24352)
			(xy 185.202626 -361.155227) (xy 185.220864 -361.112562) (xy 185.224678 -361.102622) (xy 185.224673 -361.081356)
			(xy 185.220864 -361.071414) (xy 185.202636 -361.028813) (xy 185.17412 -360.940645) (xy 185.154929 -360.849989)
			(xy 185.145271 -360.757828) (xy 185.144664 -360.711496) (xy 185.144664 -360.710988) (xy 185.145155 -360.669886)
			(xy 185.152741 -360.588033) (xy 185.167846 -360.507229) (xy 185.190343 -360.428164) (xy 185.220039 -360.351511)
			(xy 185.25668 -360.277925) (xy 185.299955 -360.208034) (xy 185.349493 -360.142434) (xy 185.404873 -360.081684)
			(xy 185.465622 -360.026303) (xy 185.531221 -359.976764) (xy 185.601111 -359.933488) (xy 185.674696 -359.896845)
			(xy 185.751348 -359.867148) (xy 185.830414 -359.84465) (xy 185.911217 -359.829543) (xy 185.99307 -359.821956)
			(xy 186.034172 -359.82148) (xy 186.03468 -359.82148) (xy 186.081011 -359.822097) (xy 186.173169 -359.831765)
			(xy 186.263823 -359.850958) (xy 186.351992 -359.879466) (xy 186.394598 -359.89768) (xy 186.40454 -359.901486)
			(xy 186.425804 -359.901486) (xy 186.435746 -359.89768) (xy 186.478352 -359.879466) (xy 186.566519 -359.850947)
			(xy 186.657173 -359.831752) (xy 186.749332 -359.822089) (xy 186.795664 -359.82148) (xy 186.796172 -359.82148)
			(xy 186.837274 -359.821979) (xy 186.919129 -359.829561) (xy 186.999934 -359.844664) (xy 187.079001 -359.867158)
			(xy 187.155656 -359.896852) (xy 187.229243 -359.933492) (xy 187.299136 -359.976765) (xy 187.364738 -360.026303)
			(xy 187.425489 -360.081682) (xy 187.480872 -360.142431) (xy 187.530412 -360.208031) (xy 187.573689 -360.277922)
			(xy 187.610332 -360.351508) (xy 187.640029 -360.428161) (xy 187.662527 -360.507227) (xy 187.677633 -360.588032)
			(xy 187.685219 -360.669886) (xy 187.68568 -360.710988) (xy 187.68568 -360.711496) (xy 187.685072 -360.757828)
			(xy 187.684417 -360.764074) (xy 211.161635 -360.764074) (xy 211.16566 -360.621882) (xy 211.177723 -360.480146)
			(xy 211.197786 -360.33932) (xy 211.225784 -360.199854) (xy 211.261628 -360.062195) (xy 211.305202 -359.926785)
			(xy 211.356367 -359.794057) (xy 211.41496 -359.664436) (xy 211.480791 -359.538338) (xy 211.553652 -359.416166)
			(xy 211.633307 -359.298312) (xy 211.719503 -359.185153) (xy 211.811962 -359.077051) (xy 211.91039 -358.974354)
			(xy 212.014469 -358.87739) (xy 212.123868 -358.78647) (xy 212.238236 -358.701884) (xy 212.357205 -358.623904)
			(xy 212.480396 -358.55278) (xy 212.607413 -358.488739) (xy 212.73785 -358.431987) (xy 212.871289 -358.382705)
			(xy 213.007302 -358.341051) (xy 213.145454 -358.307159) (xy 213.285303 -358.281138) (xy 213.426399 -358.26307)
			(xy 213.568291 -358.253013) (xy 213.710526 -358.251) (xy 213.852646 -358.257037) (xy 213.994197 -358.271105)
			(xy 214.134726 -358.293159) (xy 214.273781 -358.323128) (xy 214.410919 -358.360916) (xy 214.545699 -358.406402)
			(xy 214.67769 -358.45944) (xy 214.806469 -358.519861) (xy 214.931623 -358.58747) (xy 215.052751 -358.662052)
			(xy 215.169467 -358.743368) (xy 215.281395 -358.831156) (xy 215.388177 -358.925136) (xy 215.489471 -359.025006)
			(xy 215.584952 -359.130448) (xy 215.674316 -359.241122) (xy 215.757274 -359.356675) (xy 215.833563 -359.476736)
			(xy 215.902937 -359.600921) (xy 215.965174 -359.728832) (xy 216.020075 -359.860059) (xy 216.067463 -359.994182)
			(xy 216.107188 -360.130771) (xy 216.139121 -360.269389) (xy 216.163162 -360.409591) (xy 216.179231 -360.550929)
			(xy 216.187279 -360.69295) (xy 216.187782 -360.764074) (xy 255.611635 -360.764074) (xy 255.61566 -360.621882)
			(xy 255.627723 -360.480146) (xy 255.647786 -360.33932) (xy 255.675784 -360.199854) (xy 255.711628 -360.062195)
			(xy 255.755202 -359.926785) (xy 255.806367 -359.794057) (xy 255.86496 -359.664436) (xy 255.930791 -359.538338)
			(xy 256.003652 -359.416166) (xy 256.083307 -359.298312) (xy 256.169503 -359.185153) (xy 256.261962 -359.077051)
			(xy 256.36039 -358.974354) (xy 256.464469 -358.87739) (xy 256.573868 -358.78647) (xy 256.688236 -358.701884)
			(xy 256.807205 -358.623904) (xy 256.930396 -358.55278) (xy 257.057413 -358.488739) (xy 257.18785 -358.431987)
			(xy 257.321289 -358.382705) (xy 257.457302 -358.341051) (xy 257.595454 -358.307159) (xy 257.735303 -358.281138)
			(xy 257.876399 -358.26307) (xy 258.018291 -358.253013) (xy 258.160526 -358.251) (xy 258.302646 -358.257037)
			(xy 258.444197 -358.271105) (xy 258.584726 -358.293159) (xy 258.723781 -358.323128) (xy 258.860919 -358.360916)
			(xy 258.995699 -358.406402) (xy 259.12769 -358.45944) (xy 259.256469 -358.519861) (xy 259.381623 -358.58747)
			(xy 259.502751 -358.662052) (xy 259.619467 -358.743368) (xy 259.652996 -358.769666) (xy 294.901627 -358.769666)
			(xy 294.905632 -358.663917) (xy 294.917622 -358.558774) (xy 294.937531 -358.454839) (xy 294.965242 -358.352707)
			(xy 295.000599 -358.252963) (xy 295.043397 -358.156179) (xy 295.093393 -358.062909) (xy 295.1503 -357.973688)
			(xy 295.213791 -357.889025) (xy 295.283503 -357.809407) (xy 295.359037 -357.735289) (xy 295.43996 -357.667096)
			(xy 295.525809 -357.605218) (xy 295.616092 -357.550011) (xy 295.710291 -357.501789) (xy 295.807868 -357.460829)
			(xy 295.908263 -357.427367) (xy 296.010901 -357.401593) (xy 296.115194 -357.383655) (xy 296.220545 -357.373656)
			(xy 296.326351 -357.371653) (xy 296.432005 -357.377658) (xy 296.536902 -357.391637) (xy 296.640442 -357.413508)
			(xy 296.742031 -357.443148) (xy 296.841088 -357.480386) (xy 296.937045 -357.525008) (xy 297.029352 -357.57676)
			(xy 297.117481 -357.635345) (xy 297.200927 -357.700427) (xy 297.279211 -357.771633) (xy 297.351886 -357.848556)
			(xy 297.418536 -357.930756) (xy 297.478778 -358.01776) (xy 297.532267 -358.109071) (xy 297.578698 -358.204166)
			(xy 297.617803 -358.3025) (xy 297.64936 -358.403511) (xy 297.673187 -358.506618) (xy 297.689148 -358.611232)
			(xy 297.697152 -358.716754) (xy 297.697652 -358.769666) (xy 297.697152 -358.822578) (xy 297.689148 -358.9281)
			(xy 297.673187 -359.032714) (xy 297.64936 -359.135821) (xy 297.617803 -359.236832) (xy 297.578698 -359.335166)
			(xy 297.532267 -359.430261) (xy 297.478778 -359.521572) (xy 297.418536 -359.608576) (xy 297.351886 -359.690776)
			(xy 297.279211 -359.767699) (xy 297.200927 -359.838905) (xy 297.117481 -359.903987) (xy 297.029352 -359.962572)
			(xy 296.937045 -360.014324) (xy 296.841088 -360.058946) (xy 296.742031 -360.096184) (xy 296.640442 -360.125824)
			(xy 296.536902 -360.147695) (xy 296.432005 -360.161674) (xy 296.326351 -360.167679) (xy 296.220545 -360.165676)
			(xy 296.115194 -360.155677) (xy 296.010901 -360.137739) (xy 295.908263 -360.111965) (xy 295.807868 -360.078503)
			(xy 295.710291 -360.037543) (xy 295.616092 -359.989321) (xy 295.525809 -359.934114) (xy 295.43996 -359.872236)
			(xy 295.359037 -359.804043) (xy 295.283503 -359.729925) (xy 295.213791 -359.650307) (xy 295.1503 -359.565644)
			(xy 295.093393 -359.476423) (xy 295.043397 -359.383153) (xy 295.000599 -359.286369) (xy 294.965242 -359.186625)
			(xy 294.937531 -359.084493) (xy 294.917622 -358.980558) (xy 294.905632 -358.875415) (xy 294.901627 -358.769666)
			(xy 259.652996 -358.769666) (xy 259.731395 -358.831156) (xy 259.838177 -358.925136) (xy 259.939471 -359.025006)
			(xy 260.034952 -359.130448) (xy 260.124316 -359.241122) (xy 260.207274 -359.356675) (xy 260.283563 -359.476736)
			(xy 260.352937 -359.600921) (xy 260.415174 -359.728832) (xy 260.470075 -359.860059) (xy 260.517463 -359.994182)
			(xy 260.557188 -360.130771) (xy 260.589121 -360.269389) (xy 260.613162 -360.409591) (xy 260.629231 -360.550929)
			(xy 260.637279 -360.69295) (xy 260.637782 -360.764074) (xy 260.637279 -360.835198) (xy 260.629231 -360.977219)
			(xy 260.613162 -361.118557) (xy 260.589121 -361.258759) (xy 260.557188 -361.397377) (xy 260.517463 -361.533966)
			(xy 260.470075 -361.668089) (xy 260.415174 -361.799316) (xy 260.401302 -361.827826) (xy 430.615097 -361.827826)
			(xy 430.619102 -361.722077) (xy 430.631092 -361.616934) (xy 430.651001 -361.512999) (xy 430.678712 -361.410867)
			(xy 430.714069 -361.311123) (xy 430.756867 -361.214339) (xy 430.806863 -361.121069) (xy 430.86377 -361.031848)
			(xy 430.927261 -360.947185) (xy 430.996973 -360.867567) (xy 431.072507 -360.793449) (xy 431.15343 -360.725256)
			(xy 431.239279 -360.663378) (xy 431.329562 -360.608171) (xy 431.423761 -360.559949) (xy 431.521338 -360.518989)
			(xy 431.621733 -360.485527) (xy 431.724371 -360.459753) (xy 431.828664 -360.441815) (xy 431.934015 -360.431816)
			(xy 432.039821 -360.429813) (xy 432.145475 -360.435818) (xy 432.250372 -360.449797) (xy 432.353912 -360.471668)
			(xy 432.455501 -360.501308) (xy 432.554558 -360.538546) (xy 432.650515 -360.583168) (xy 432.742822 -360.63492)
			(xy 432.830951 -360.693505) (xy 432.914397 -360.758587) (xy 432.992681 -360.829793) (xy 433.065356 -360.906716)
			(xy 433.132006 -360.988916) (xy 433.192248 -361.07592) (xy 433.245737 -361.167231) (xy 433.292168 -361.262326)
			(xy 433.331273 -361.36066) (xy 433.36283 -361.461671) (xy 433.370787 -361.496102) (xy 434.579776 -361.496102)
			(xy 434.580404 -361.4497) (xy 434.590093 -361.357403) (xy 434.609347 -361.266617) (xy 434.637954 -361.178332)
			(xy 434.65623 -361.135676) (xy 434.660038 -361.125734) (xy 434.660039 -361.10447) (xy 434.65623 -361.094528)
			(xy 434.637968 -361.051867) (xy 434.609375 -360.963579) (xy 434.590118 -360.872796) (xy 434.580405 -360.780503)
			(xy 434.579776 -360.734102) (xy 434.580404 -360.6877) (xy 434.590093 -360.595403) (xy 434.609347 -360.504617)
			(xy 434.637954 -360.416332) (xy 434.65623 -360.373676) (xy 434.660038 -360.363734) (xy 434.660039 -360.34247)
			(xy 434.65623 -360.332528) (xy 434.637968 -360.289867) (xy 434.609375 -360.201579) (xy 434.590118 -360.110796)
			(xy 434.580405 -360.018503) (xy 434.579776 -359.972102) (xy 434.5802 -359.930986) (xy 434.587788 -359.849105)
			(xy 434.602898 -359.768273) (xy 434.625402 -359.68918) (xy 434.655109 -359.612502) (xy 434.691763 -359.538891)
			(xy 434.735054 -359.468977) (xy 434.784611 -359.403355) (xy 434.840011 -359.342586) (xy 434.900783 -359.287188)
			(xy 434.966406 -359.237634) (xy 435.036323 -359.194346) (xy 435.109935 -359.157694) (xy 435.186615 -359.127991)
			(xy 435.265708 -359.10549) (xy 435.346541 -359.090383) (xy 435.428422 -359.082799) (xy 435.469538 -359.08234)
			(xy 435.51594 -359.082957) (xy 435.608238 -359.09265) (xy 435.699023 -359.111907) (xy 435.787308 -359.140517)
			(xy 435.829964 -359.158794) (xy 435.839906 -359.1626) (xy 435.86117 -359.1626) (xy 435.871112 -359.158794)
			(xy 435.913767 -359.140517) (xy 436.002057 -359.111928) (xy 436.092842 -359.092675) (xy 436.185137 -359.082967)
			(xy 436.231538 -359.08234) (xy 436.272653 -359.082777) (xy 436.354532 -359.090367) (xy 436.435361 -359.10548)
			(xy 436.514451 -359.127986) (xy 436.591127 -359.157693) (xy 436.664735 -359.194349) (xy 436.734647 -359.237639)
			(xy 436.800266 -359.287195) (xy 436.861034 -359.342595) (xy 436.91643 -359.403364) (xy 436.965984 -359.468986)
			(xy 437.009271 -359.5389) (xy 437.045923 -359.61251) (xy 437.075627 -359.689187) (xy 437.098129 -359.768278)
			(xy 437.113238 -359.849108) (xy 437.120825 -359.930987) (xy 437.1213 -359.972102) (xy 437.120676 -360.018504)
			(xy 437.110985 -360.110802) (xy 437.091731 -360.201587) (xy 437.063122 -360.289872) (xy 437.044846 -360.332528)
			(xy 437.041037 -360.34247) (xy 437.041038 -360.363734) (xy 437.044846 -360.373676) (xy 437.063108 -360.416337)
			(xy 437.091701 -360.504625) (xy 437.110959 -360.595408) (xy 437.120671 -360.687701) (xy 437.1213 -360.734102)
			(xy 437.120676 -360.780504) (xy 437.110985 -360.872802) (xy 437.091731 -360.963587) (xy 437.063122 -361.051872)
			(xy 437.044846 -361.094528) (xy 437.041037 -361.10447) (xy 437.041038 -361.125734) (xy 437.044846 -361.135676)
			(xy 437.063108 -361.178337) (xy 437.091701 -361.266625) (xy 437.110959 -361.357408) (xy 437.120671 -361.449701)
			(xy 437.1213 -361.496102) (xy 437.120789 -361.537215) (xy 437.113202 -361.619091) (xy 437.098093 -361.699917)
			(xy 437.075592 -361.779004) (xy 437.045889 -361.855678) (xy 437.009238 -361.929285) (xy 436.965952 -361.999196)
			(xy 436.916401 -362.064814) (xy 436.861007 -362.125581) (xy 436.800242 -362.180978) (xy 436.734625 -362.230532)
			(xy 436.664716 -362.273821) (xy 436.591111 -362.310474) (xy 436.514439 -362.34018) (xy 436.435352 -362.362685)
			(xy 436.354526 -362.377797) (xy 436.272651 -362.385387) (xy 436.231538 -362.385864) (xy 436.185135 -362.385256)
			(xy 436.092838 -362.37556) (xy 436.002052 -362.356301) (xy 435.913768 -362.327688) (xy 435.871112 -362.30941)
			(xy 435.86117 -362.305604) (xy 435.839906 -362.305604) (xy 435.829964 -362.30941) (xy 435.787299 -362.327662)
			(xy 435.699012 -362.356257) (xy 435.608231 -362.375517) (xy 435.515939 -362.385233) (xy 435.469538 -362.385864)
			(xy 435.428424 -362.385365) (xy 435.346546 -362.377782) (xy 435.265717 -362.362675) (xy 435.186627 -362.340175)
			(xy 435.10995 -362.310473) (xy 435.036341 -362.273823) (xy 434.966428 -362.230538) (xy 434.900807 -362.180986)
			(xy 434.840038 -362.12559) (xy 434.78464 -362.064824) (xy 434.735085 -361.999205) (xy 434.691796 -361.929294)
			(xy 434.655143 -361.855686) (xy 434.625438 -361.779011) (xy 434.602934 -361.699922) (xy 434.587824 -361.619094)
			(xy 434.580237 -361.537216) (xy 434.579776 -361.496102) (xy 433.370787 -361.496102) (xy 433.386657 -361.564778)
			(xy 433.402618 -361.669392) (xy 433.410622 -361.774914) (xy 433.411122 -361.827826) (xy 433.410622 -361.880738)
			(xy 433.402618 -361.98626) (xy 433.386657 -362.090874) (xy 433.36283 -362.193981) (xy 433.331273 -362.294992)
			(xy 433.292168 -362.393326) (xy 433.245737 -362.488421) (xy 433.192248 -362.579732) (xy 433.132006 -362.666736)
			(xy 433.065356 -362.748936) (xy 432.992681 -362.825859) (xy 432.914397 -362.897065) (xy 432.830951 -362.962147)
			(xy 432.742822 -363.020732) (xy 432.650515 -363.072484) (xy 432.554558 -363.117106) (xy 432.455501 -363.154344)
			(xy 432.353912 -363.183984) (xy 432.250372 -363.205855) (xy 432.145475 -363.219834) (xy 432.039821 -363.225839)
			(xy 431.934015 -363.223836) (xy 431.828664 -363.213837) (xy 431.724371 -363.195899) (xy 431.621733 -363.170125)
			(xy 431.521338 -363.136663) (xy 431.423761 -363.095703) (xy 431.329562 -363.047481) (xy 431.239279 -362.992274)
			(xy 431.15343 -362.930396) (xy 431.072507 -362.862203) (xy 430.996973 -362.788085) (xy 430.927261 -362.708467)
			(xy 430.86377 -362.623804) (xy 430.806863 -362.534583) (xy 430.756867 -362.441313) (xy 430.714069 -362.344529)
			(xy 430.678712 -362.244785) (xy 430.651001 -362.142653) (xy 430.631092 -362.038718) (xy 430.619102 -361.933575)
			(xy 430.615097 -361.827826) (xy 260.401302 -361.827826) (xy 260.352937 -361.927227) (xy 260.283563 -362.051412)
			(xy 260.207274 -362.171473) (xy 260.124316 -362.287026) (xy 260.034952 -362.3977) (xy 259.939471 -362.503142)
			(xy 259.838177 -362.603012) (xy 259.731395 -362.696992) (xy 259.619467 -362.78478) (xy 259.502751 -362.866096)
			(xy 259.381623 -362.940678) (xy 259.256469 -363.008287) (xy 259.12769 -363.068708) (xy 258.995699 -363.121746)
			(xy 258.860919 -363.167232) (xy 258.723781 -363.20502) (xy 258.584726 -363.234989) (xy 258.444197 -363.257043)
			(xy 258.302646 -363.271111) (xy 258.160526 -363.277148) (xy 258.018291 -363.275135) (xy 257.876399 -363.265078)
			(xy 257.735303 -363.24701) (xy 257.595454 -363.220989) (xy 257.457302 -363.187097) (xy 257.321289 -363.145443)
			(xy 257.18785 -363.096161) (xy 257.057413 -363.039409) (xy 256.930396 -362.975368) (xy 256.807205 -362.904244)
			(xy 256.688236 -362.826264) (xy 256.573868 -362.741678) (xy 256.464469 -362.650758) (xy 256.36039 -362.553794)
			(xy 256.261962 -362.451097) (xy 256.169503 -362.342995) (xy 256.083307 -362.229836) (xy 256.003652 -362.111982)
			(xy 255.930791 -361.98981) (xy 255.86496 -361.863712) (xy 255.806367 -361.734091) (xy 255.755202 -361.601363)
			(xy 255.711628 -361.465953) (xy 255.675784 -361.328294) (xy 255.647786 -361.188828) (xy 255.627723 -361.048002)
			(xy 255.61566 -360.906266) (xy 255.611635 -360.764074) (xy 216.187782 -360.764074) (xy 216.187279 -360.835198)
			(xy 216.179231 -360.977219) (xy 216.163162 -361.118557) (xy 216.139121 -361.258759) (xy 216.107188 -361.397377)
			(xy 216.067463 -361.533966) (xy 216.020075 -361.668089) (xy 215.965174 -361.799316) (xy 215.902937 -361.927227)
			(xy 215.833563 -362.051412) (xy 215.757274 -362.171473) (xy 215.674316 -362.287026) (xy 215.584952 -362.3977)
			(xy 215.489471 -362.503142) (xy 215.388177 -362.603012) (xy 215.281395 -362.696992) (xy 215.169467 -362.78478)
			(xy 215.052751 -362.866096) (xy 214.931623 -362.940678) (xy 214.806469 -363.008287) (xy 214.67769 -363.068708)
			(xy 214.545699 -363.121746) (xy 214.410919 -363.167232) (xy 214.273781 -363.20502) (xy 214.134726 -363.234989)
			(xy 213.994197 -363.257043) (xy 213.852646 -363.271111) (xy 213.710526 -363.277148) (xy 213.568291 -363.275135)
			(xy 213.426399 -363.265078) (xy 213.285303 -363.24701) (xy 213.145454 -363.220989) (xy 213.007302 -363.187097)
			(xy 212.871289 -363.145443) (xy 212.73785 -363.096161) (xy 212.607413 -363.039409) (xy 212.480396 -362.975368)
			(xy 212.357205 -362.904244) (xy 212.238236 -362.826264) (xy 212.123868 -362.741678) (xy 212.014469 -362.650758)
			(xy 211.91039 -362.553794) (xy 211.811962 -362.451097) (xy 211.719503 -362.342995) (xy 211.633307 -362.229836)
			(xy 211.553652 -362.111982) (xy 211.480791 -361.98981) (xy 211.41496 -361.863712) (xy 211.356367 -361.734091)
			(xy 211.305202 -361.601363) (xy 211.261628 -361.465953) (xy 211.225784 -361.328294) (xy 211.197786 -361.188828)
			(xy 211.177723 -361.048002) (xy 211.16566 -360.906266) (xy 211.161635 -360.764074) (xy 187.684417 -360.764074)
			(xy 187.675402 -360.849986) (xy 187.656207 -360.94064) (xy 187.627695 -361.028809) (xy 187.60948 -361.071414)
			(xy 187.605683 -361.081359) (xy 187.605679 -361.10262) (xy 187.60948 -361.112562) (xy 187.627719 -361.155227)
			(xy 187.656265 -361.243518) (xy 187.67546 -361.334302) (xy 187.685094 -361.426592) (xy 187.68568 -361.472988)
			(xy 187.685095 -361.519384) (xy 187.675451 -361.611672) (xy 187.656256 -361.702456) (xy 187.627718 -361.790749)
			(xy 187.60948 -361.833414) (xy 187.605683 -361.843359) (xy 187.605679 -361.86462) (xy 187.60948 -361.874562)
			(xy 187.627696 -361.917167) (xy 187.656216 -362.005334) (xy 187.67541 -362.095988) (xy 187.685071 -362.188148)
			(xy 187.68568 -362.23448) (xy 187.68568 -362.234988) (xy 187.685236 -362.276092) (xy 187.677652 -362.357949)
			(xy 187.664078 -362.430568) (xy 190.281567 -362.430568) (xy 190.285572 -362.324819) (xy 190.297562 -362.219676)
			(xy 190.317471 -362.115741) (xy 190.345182 -362.013609) (xy 190.380539 -361.913865) (xy 190.423337 -361.817081)
			(xy 190.473333 -361.723811) (xy 190.53024 -361.63459) (xy 190.593731 -361.549927) (xy 190.663443 -361.470309)
			(xy 190.738977 -361.396191) (xy 190.8199 -361.327998) (xy 190.905749 -361.26612) (xy 190.996032 -361.210913)
			(xy 191.090231 -361.162691) (xy 191.187808 -361.121731) (xy 191.288203 -361.088269) (xy 191.390841 -361.062495)
			(xy 191.495134 -361.044557) (xy 191.600485 -361.034558) (xy 191.706291 -361.032555) (xy 191.811945 -361.03856)
			(xy 191.916842 -361.052539) (xy 192.020382 -361.07441) (xy 192.121971 -361.10405) (xy 192.221028 -361.141288)
			(xy 192.316985 -361.18591) (xy 192.409292 -361.237662) (xy 192.497421 -361.296247) (xy 192.580867 -361.361329)
			(xy 192.659151 -361.432535) (xy 192.731826 -361.509458) (xy 192.798476 -361.591658) (xy 192.858718 -361.678662)
			(xy 192.912207 -361.769973) (xy 192.958638 -361.865068) (xy 192.997743 -361.963402) (xy 193.0293 -362.064413)
			(xy 193.053127 -362.16752) (xy 193.069088 -362.272134) (xy 193.077092 -362.377656) (xy 193.077592 -362.430568)
			(xy 193.077092 -362.48348) (xy 193.069088 -362.589002) (xy 193.053127 -362.693616) (xy 193.0293 -362.796723)
			(xy 192.997743 -362.897734) (xy 192.958638 -362.996068) (xy 192.912207 -363.091163) (xy 192.858718 -363.182474)
			(xy 192.798476 -363.269478) (xy 192.731826 -363.351678) (xy 192.659151 -363.428601) (xy 192.580867 -363.499807)
			(xy 192.497421 -363.564889) (xy 192.409292 -363.623474) (xy 192.316985 -363.675226) (xy 192.221028 -363.719848)
			(xy 192.121971 -363.757086) (xy 192.020382 -363.786726) (xy 191.916842 -363.808597) (xy 191.811945 -363.822576)
			(xy 191.706291 -363.828581) (xy 191.600485 -363.826578) (xy 191.495134 -363.816579) (xy 191.390841 -363.798641)
			(xy 191.288203 -363.772867) (xy 191.187808 -363.739405) (xy 191.090231 -363.698445) (xy 190.996032 -363.650223)
			(xy 190.905749 -363.595016) (xy 190.8199 -363.533138) (xy 190.738977 -363.464945) (xy 190.663443 -363.390827)
			(xy 190.593731 -363.311209) (xy 190.53024 -363.226546) (xy 190.473333 -363.137325) (xy 190.423337 -363.044055)
			(xy 190.380539 -362.947271) (xy 190.345182 -362.847527) (xy 190.317471 -362.745395) (xy 190.297562 -362.64146)
			(xy 190.285572 -362.536317) (xy 190.281567 -362.430568) (xy 187.664078 -362.430568) (xy 187.662547 -362.438757)
			(xy 187.64005 -362.517826) (xy 187.610354 -362.594483) (xy 187.573711 -362.668072) (xy 187.530434 -362.737966)
			(xy 187.480892 -362.803569) (xy 187.425509 -362.86432) (xy 187.364756 -362.919703) (xy 187.299153 -362.969243)
			(xy 187.229258 -363.012519) (xy 187.155668 -363.04916) (xy 187.079011 -363.078856) (xy 186.999941 -363.101351)
			(xy 186.919133 -363.116454) (xy 186.837276 -363.124037) (xy 186.796172 -363.124496) (xy 186.795664 -363.124496)
			(xy 186.749333 -363.123866) (xy 186.657176 -363.114202) (xy 186.566521 -363.095013) (xy 186.478352 -363.066508)
			(xy 186.435746 -363.048296) (xy 186.425804 -363.04449) (xy 186.40454 -363.04449) (xy 186.394598 -363.048296)
			(xy 186.351999 -363.066527) (xy 186.26383 -363.095042) (xy 186.173173 -363.114232) (xy 186.081013 -363.123889)
			(xy 186.03468 -363.124496) (xy 186.034172 -363.124496) (xy 185.993069 -363.12406) (xy 185.911213 -363.116473)
			(xy 185.830407 -363.101365) (xy 185.751339 -363.078866) (xy 185.674684 -363.049167) (xy 185.601097 -363.012522)
			(xy 185.531204 -362.969244) (xy 185.465603 -362.919702) (xy 185.404853 -362.864319) (xy 185.349472 -362.803566)
			(xy 185.299933 -362.737963) (xy 185.256658 -362.668068) (xy 185.220017 -362.594479) (xy 185.190322 -362.517823)
			(xy 185.167826 -362.438755) (xy 185.152722 -362.357947) (xy 185.145138 -362.276091) (xy 185.144664 -362.234988)
			(xy 166.497508 -362.234988) (xy 166.497508 -362.396278) (xy 166.497022 -362.423547) (xy 166.48926 -362.477531)
			(xy 166.473895 -362.529861) (xy 166.451238 -362.579471) (xy 166.421752 -362.625352) (xy 166.386037 -362.666569)
			(xy 166.34482 -362.702284) (xy 166.298939 -362.73177) (xy 166.249329 -362.754427) (xy 166.196999 -362.769792)
			(xy 166.143015 -362.777554) (xy 166.088477 -362.777554) (xy 166.034493 -362.769792) (xy 165.982163 -362.754427)
			(xy 165.932553 -362.73177) (xy 165.886672 -362.702284) (xy 165.845455 -362.666569) (xy 165.80974 -362.625352)
			(xy 165.780254 -362.579471) (xy 165.757597 -362.529861) (xy 165.742232 -362.477531) (xy 165.73447 -362.423547)
			(xy 165.733984 -362.396278) (xy 10.079022 -362.396278) (xy 10.05934 -362.458146) (xy 10.012689 -362.578565)
			(xy 9.958714 -362.695884) (xy 9.897619 -362.809658) (xy 9.829636 -362.919455) (xy 9.755022 -363.024858)
			(xy 9.674061 -363.125468) (xy 9.587061 -363.220903) (xy 9.49435 -363.310802) (xy 9.39628 -363.394823)
			(xy 9.293225 -363.472647) (xy 9.185574 -363.543979) (xy 9.073735 -363.608549) (xy 8.958134 -363.666111)
			(xy 8.839209 -363.716448) (xy 8.71741 -363.759368) (xy 8.5932 -363.794709) (xy 8.467051 -363.822336)
			(xy 8.339439 -363.842145) (xy 8.21085 -363.854061) (xy 8.081772 -363.858038) (xy 7.952694 -363.854061)
			(xy 7.824105 -363.842145) (xy 7.696493 -363.822336) (xy 7.570344 -363.794709) (xy 7.446134 -363.759368)
			(xy 7.324335 -363.716448) (xy 7.20541 -363.666111) (xy 7.089809 -363.608549) (xy 6.97797 -363.543979)
			(xy 6.870319 -363.472647) (xy 6.767264 -363.394823) (xy 6.669194 -363.310802) (xy 6.576483 -363.220903)
			(xy 6.489483 -363.125468) (xy 6.408522 -363.024858) (xy 6.333908 -362.919455) (xy 6.265925 -362.809658)
			(xy 6.20483 -362.695884) (xy 6.150855 -362.578565) (xy 6.104204 -362.458146) (xy 6.065055 -362.335083)
			(xy 6.033556 -362.209844) (xy 6.009827 -362.082903) (xy 5.993957 -361.954743) (xy 5.986007 -361.825848)
			(xy 2.509012 -361.825848) (xy 2.509012 -369.062565) (xy 44.335754 -369.062565) (xy 44.335754 -369.008035)
			(xy 44.343514 -368.95406) (xy 44.358876 -368.901738) (xy 44.381527 -368.852135) (xy 44.411006 -368.806259)
			(xy 44.446714 -368.765046) (xy 44.487923 -368.729334) (xy 44.533794 -368.699849) (xy 44.583395 -368.677192)
			(xy 44.635715 -368.661824) (xy 44.689689 -368.654057) (xy 44.716954 -368.653568) (xy 45.580554 -368.653568)
			(xy 45.607829 -368.653968) (xy 45.661825 -368.661726) (xy 45.714168 -368.677089) (xy 45.763791 -368.699746)
			(xy 45.809684 -368.729235) (xy 45.850912 -368.764955) (xy 45.886638 -368.80618) (xy 45.916132 -368.852069)
			(xy 45.938795 -368.901689) (xy 45.954164 -368.95403) (xy 45.961928 -369.008025) (xy 45.961928 -369.062565)
			(xy 51.142954 -369.062565) (xy 51.142954 -369.008035) (xy 51.150714 -368.95406) (xy 51.166076 -368.901738)
			(xy 51.188727 -368.852135) (xy 51.218206 -368.806259) (xy 51.253914 -368.765046) (xy 51.295123 -368.729334)
			(xy 51.340994 -368.699849) (xy 51.390595 -368.677192) (xy 51.442915 -368.661824) (xy 51.496889 -368.654057)
			(xy 51.524154 -368.653568) (xy 52.387754 -368.653568) (xy 52.415029 -368.653968) (xy 52.469025 -368.661726)
			(xy 52.521368 -368.677089) (xy 52.570991 -368.699746) (xy 52.616884 -368.729235) (xy 52.658112 -368.764955)
			(xy 52.693838 -368.80618) (xy 52.723332 -368.852069) (xy 52.745995 -368.901689) (xy 52.761364 -368.95403)
			(xy 52.769128 -369.008025) (xy 52.769128 -369.062565) (xy 57.950154 -369.062565) (xy 57.950154 -369.008035)
			(xy 57.957914 -368.95406) (xy 57.973276 -368.901738) (xy 57.995927 -368.852135) (xy 58.025406 -368.806259)
			(xy 58.061114 -368.765046) (xy 58.102323 -368.729334) (xy 58.148194 -368.699849) (xy 58.197795 -368.677192)
			(xy 58.250115 -368.661824) (xy 58.304089 -368.654057) (xy 58.331354 -368.653568) (xy 59.194954 -368.653568)
			(xy 59.222229 -368.653968) (xy 59.276225 -368.661726) (xy 59.328568 -368.677089) (xy 59.378191 -368.699746)
			(xy 59.424084 -368.729235) (xy 59.465312 -368.764955) (xy 59.501038 -368.80618) (xy 59.530532 -368.852069)
			(xy 59.553195 -368.901689) (xy 59.568564 -368.95403) (xy 59.576328 -369.008025) (xy 59.576328 -369.062565)
			(xy 64.757354 -369.062565) (xy 64.757354 -369.008035) (xy 64.765114 -368.95406) (xy 64.780476 -368.901738)
			(xy 64.803127 -368.852135) (xy 64.832606 -368.806259) (xy 64.868314 -368.765046) (xy 64.909523 -368.729334)
			(xy 64.955394 -368.699849) (xy 65.004995 -368.677192) (xy 65.057315 -368.661824) (xy 65.111289 -368.654057)
			(xy 65.138554 -368.653568) (xy 66.002154 -368.653568) (xy 66.029429 -368.653968) (xy 66.083425 -368.661726)
			(xy 66.135768 -368.677089) (xy 66.185391 -368.699746) (xy 66.231284 -368.729235) (xy 66.272512 -368.764955)
			(xy 66.308238 -368.80618) (xy 66.337732 -368.852069) (xy 66.360395 -368.901689) (xy 66.375764 -368.95403)
			(xy 66.383528 -369.008025) (xy 66.383528 -369.062565) (xy 68.160954 -369.062565) (xy 68.160954 -369.008035)
			(xy 68.168714 -368.95406) (xy 68.184076 -368.901738) (xy 68.206727 -368.852135) (xy 68.236206 -368.806259)
			(xy 68.271914 -368.765046) (xy 68.313123 -368.729334) (xy 68.358994 -368.699849) (xy 68.408595 -368.677192)
			(xy 68.460915 -368.661824) (xy 68.514889 -368.654057) (xy 68.542154 -368.653568) (xy 69.405754 -368.653568)
			(xy 69.433029 -368.653968) (xy 69.487025 -368.661726) (xy 69.539368 -368.677089) (xy 69.588991 -368.699746)
			(xy 69.634884 -368.729235) (xy 69.676112 -368.764955) (xy 69.711838 -368.80618) (xy 69.741332 -368.852069)
			(xy 69.763995 -368.901689) (xy 69.779364 -368.95403) (xy 69.787128 -369.008025) (xy 69.787128 -369.062569)
			(xy 76.863431 -369.062569) (xy 76.863431 -369.008031) (xy 76.871193 -368.954048) (xy 76.886558 -368.90172)
			(xy 76.909214 -368.85211) (xy 76.9387 -368.80623) (xy 76.974414 -368.765013) (xy 77.015632 -368.729298)
			(xy 77.061512 -368.699813) (xy 77.111121 -368.677157) (xy 77.16345 -368.661793) (xy 77.217433 -368.654031)
			(xy 77.244702 -368.653568) (xy 78.108302 -368.653568) (xy 78.135573 -368.653995) (xy 78.189561 -368.661757)
			(xy 78.241894 -368.677124) (xy 78.291508 -368.699782) (xy 78.337393 -368.72927) (xy 78.378613 -368.764988)
			(xy 78.414331 -368.806209) (xy 78.443819 -368.852093) (xy 78.466477 -368.901707) (xy 78.481843 -368.954041)
			(xy 78.489606 -369.008029) (xy 78.489606 -369.062569) (xy 83.670631 -369.062569) (xy 83.670631 -369.008031)
			(xy 83.678393 -368.954048) (xy 83.693758 -368.90172) (xy 83.716414 -368.85211) (xy 83.7459 -368.80623)
			(xy 83.781614 -368.765013) (xy 83.822832 -368.729298) (xy 83.868712 -368.699813) (xy 83.918321 -368.677157)
			(xy 83.97065 -368.661793) (xy 84.024633 -368.654031) (xy 84.051902 -368.653568) (xy 84.915502 -368.653568)
			(xy 84.942773 -368.653995) (xy 84.996761 -368.661757) (xy 85.049094 -368.677124) (xy 85.098708 -368.699782)
			(xy 85.144593 -368.72927) (xy 85.185813 -368.764988) (xy 85.221531 -368.806209) (xy 85.251019 -368.852093)
			(xy 85.273677 -368.901707) (xy 85.289043 -368.954041) (xy 85.296806 -369.008029) (xy 85.296806 -369.062569)
			(xy 90.477831 -369.062569) (xy 90.477831 -369.008031) (xy 90.485593 -368.954048) (xy 90.500958 -368.90172)
			(xy 90.523614 -368.85211) (xy 90.5531 -368.80623) (xy 90.588814 -368.765013) (xy 90.630032 -368.729298)
			(xy 90.675912 -368.699813) (xy 90.725521 -368.677157) (xy 90.77785 -368.661793) (xy 90.831833 -368.654031)
			(xy 90.859102 -368.653568) (xy 91.722702 -368.653568) (xy 91.749973 -368.653995) (xy 91.803961 -368.661757)
			(xy 91.856294 -368.677124) (xy 91.905908 -368.699782) (xy 91.951793 -368.72927) (xy 91.993013 -368.764988)
			(xy 92.028731 -368.806209) (xy 92.058219 -368.852093) (xy 92.080877 -368.901707) (xy 92.096243 -368.954041)
			(xy 92.104006 -369.008029) (xy 92.104006 -369.062569) (xy 97.285031 -369.062569) (xy 97.285031 -369.008031)
			(xy 97.292793 -368.954048) (xy 97.308158 -368.90172) (xy 97.330814 -368.85211) (xy 97.3603 -368.80623)
			(xy 97.396014 -368.765013) (xy 97.437232 -368.729298) (xy 97.483112 -368.699813) (xy 97.532721 -368.677157)
			(xy 97.58505 -368.661793) (xy 97.639033 -368.654031) (xy 97.666302 -368.653568) (xy 98.529902 -368.653568)
			(xy 98.557173 -368.653995) (xy 98.611161 -368.661757) (xy 98.663494 -368.677124) (xy 98.713108 -368.699782)
			(xy 98.758993 -368.72927) (xy 98.800213 -368.764988) (xy 98.835931 -368.806209) (xy 98.865419 -368.852093)
			(xy 98.888077 -368.901707) (xy 98.903443 -368.954041) (xy 98.911206 -369.008029) (xy 98.911206 -369.062569)
			(xy 100.688631 -369.062569) (xy 100.688631 -369.008031) (xy 100.696393 -368.954048) (xy 100.711758 -368.90172)
			(xy 100.734414 -368.85211) (xy 100.7639 -368.80623) (xy 100.799614 -368.765013) (xy 100.840832 -368.729298)
			(xy 100.886712 -368.699813) (xy 100.936321 -368.677157) (xy 100.98865 -368.661793) (xy 101.042633 -368.654031)
			(xy 101.069902 -368.653568) (xy 101.933502 -368.653568) (xy 101.960773 -368.653995) (xy 102.014761 -368.661757)
			(xy 102.067094 -368.677124) (xy 102.116708 -368.699782) (xy 102.162593 -368.72927) (xy 102.203813 -368.764988)
			(xy 102.239531 -368.806209) (xy 102.269019 -368.852093) (xy 102.291677 -368.901707) (xy 102.307043 -368.954041)
			(xy 102.314806 -369.008029) (xy 102.314806 -369.062567) (xy 111.435654 -369.062567) (xy 111.435654 -369.008033)
			(xy 111.443415 -368.954054) (xy 111.458779 -368.901729) (xy 111.481433 -368.852123) (xy 111.510917 -368.806246)
			(xy 111.546629 -368.765031) (xy 111.587842 -368.729319) (xy 111.633719 -368.699835) (xy 111.683325 -368.677181)
			(xy 111.73565 -368.661816) (xy 111.789629 -368.654055) (xy 111.816896 -368.653568) (xy 112.680496 -368.653568)
			(xy 112.707769 -368.653971) (xy 112.761761 -368.661734) (xy 112.814098 -368.677101) (xy 112.863716 -368.69976)
			(xy 112.909603 -368.72925) (xy 112.950827 -368.76497) (xy 112.986548 -368.806193) (xy 113.016038 -368.852081)
			(xy 113.038698 -368.901698) (xy 113.054066 -368.954035) (xy 113.061828 -369.008027) (xy 113.061828 -369.062567)
			(xy 118.242854 -369.062567) (xy 118.242854 -369.008033) (xy 118.250615 -368.954054) (xy 118.265979 -368.901729)
			(xy 118.288633 -368.852123) (xy 118.318117 -368.806246) (xy 118.353829 -368.765031) (xy 118.395042 -368.729319)
			(xy 118.440919 -368.699835) (xy 118.490525 -368.677181) (xy 118.54285 -368.661816) (xy 118.596829 -368.654055)
			(xy 118.624096 -368.653568) (xy 119.487696 -368.653568) (xy 119.514969 -368.653971) (xy 119.568961 -368.661734)
			(xy 119.621298 -368.677101) (xy 119.670916 -368.69976) (xy 119.716803 -368.72925) (xy 119.758027 -368.76497)
			(xy 119.793748 -368.806193) (xy 119.823238 -368.852081) (xy 119.845898 -368.901698) (xy 119.861266 -368.954035)
			(xy 119.869028 -369.008027) (xy 119.869028 -369.062567) (xy 125.050054 -369.062567) (xy 125.050054 -369.008033)
			(xy 125.057815 -368.954054) (xy 125.073179 -368.901729) (xy 125.095833 -368.852123) (xy 125.125317 -368.806246)
			(xy 125.161029 -368.765031) (xy 125.202242 -368.729319) (xy 125.248119 -368.699835) (xy 125.297725 -368.677181)
			(xy 125.35005 -368.661816) (xy 125.404029 -368.654055) (xy 125.431296 -368.653568) (xy 126.294896 -368.653568)
			(xy 126.322169 -368.653971) (xy 126.376161 -368.661734) (xy 126.428498 -368.677101) (xy 126.478116 -368.69976)
			(xy 126.524003 -368.72925) (xy 126.565227 -368.76497) (xy 126.600948 -368.806193) (xy 126.630438 -368.852081)
			(xy 126.653098 -368.901698) (xy 126.668466 -368.954035) (xy 126.676228 -369.008027) (xy 126.676228 -369.062567)
			(xy 131.857254 -369.062567) (xy 131.857254 -369.008033) (xy 131.865015 -368.954054) (xy 131.880379 -368.901729)
			(xy 131.903033 -368.852123) (xy 131.932517 -368.806246) (xy 131.968229 -368.765031) (xy 132.009442 -368.729319)
			(xy 132.055319 -368.699835) (xy 132.104925 -368.677181) (xy 132.15725 -368.661816) (xy 132.211229 -368.654055)
			(xy 132.238496 -368.653568) (xy 133.102096 -368.653568) (xy 133.129369 -368.653971) (xy 133.183361 -368.661734)
			(xy 133.235698 -368.677101) (xy 133.285316 -368.69976) (xy 133.331203 -368.72925) (xy 133.372427 -368.76497)
			(xy 133.408148 -368.806193) (xy 133.437638 -368.852081) (xy 133.460298 -368.901698) (xy 133.475666 -368.954035)
			(xy 133.483428 -369.008027) (xy 133.483428 -369.062567) (xy 135.260854 -369.062567) (xy 135.260854 -369.008033)
			(xy 135.268615 -368.954054) (xy 135.283979 -368.901729) (xy 135.306633 -368.852123) (xy 135.336117 -368.806246)
			(xy 135.371829 -368.765031) (xy 135.413042 -368.729319) (xy 135.458919 -368.699835) (xy 135.508525 -368.677181)
			(xy 135.56085 -368.661816) (xy 135.614829 -368.654055) (xy 135.642096 -368.653568) (xy 136.505696 -368.653568)
			(xy 136.532969 -368.653971) (xy 136.586961 -368.661734) (xy 136.639298 -368.677101) (xy 136.688916 -368.69976)
			(xy 136.734803 -368.72925) (xy 136.776027 -368.76497) (xy 136.811748 -368.806193) (xy 136.841238 -368.852081)
			(xy 136.863898 -368.901698) (xy 136.879266 -368.954035) (xy 136.887028 -369.008027) (xy 136.887028 -369.062573)
			(xy 136.879266 -369.116565) (xy 136.863898 -369.168902) (xy 136.841238 -369.218519) (xy 136.811748 -369.264407)
			(xy 136.776027 -369.30563) (xy 136.734803 -369.34135) (xy 136.688916 -369.37084) (xy 136.639298 -369.393499)
			(xy 136.586961 -369.408866) (xy 136.532969 -369.416629) (xy 136.505696 -369.417092) (xy 135.642096 -369.417092)
			(xy 135.614829 -369.416545) (xy 135.56085 -369.408784) (xy 135.508525 -369.393419) (xy 135.458919 -369.370765)
			(xy 135.413042 -369.341281) (xy 135.371829 -369.305569) (xy 135.336117 -369.264354) (xy 135.306633 -369.218477)
			(xy 135.283979 -369.168871) (xy 135.268615 -369.116546) (xy 135.260854 -369.062567) (xy 133.483428 -369.062567)
			(xy 133.483428 -369.062573) (xy 133.475666 -369.116565) (xy 133.460298 -369.168902) (xy 133.437638 -369.218519)
			(xy 133.408148 -369.264407) (xy 133.372427 -369.30563) (xy 133.331203 -369.34135) (xy 133.285316 -369.37084)
			(xy 133.235698 -369.393499) (xy 133.183361 -369.408866) (xy 133.129369 -369.416629) (xy 133.102096 -369.417092)
			(xy 132.238496 -369.417092) (xy 132.211229 -369.416545) (xy 132.15725 -369.408784) (xy 132.104925 -369.393419)
			(xy 132.055319 -369.370765) (xy 132.009442 -369.341281) (xy 131.968229 -369.305569) (xy 131.932517 -369.264354)
			(xy 131.903033 -369.218477) (xy 131.880379 -369.168871) (xy 131.865015 -369.116546) (xy 131.857254 -369.062567)
			(xy 126.676228 -369.062567) (xy 126.676228 -369.062573) (xy 126.668466 -369.116565) (xy 126.653098 -369.168902)
			(xy 126.630438 -369.218519) (xy 126.600948 -369.264407) (xy 126.565227 -369.30563) (xy 126.524003 -369.34135)
			(xy 126.478116 -369.37084) (xy 126.428498 -369.393499) (xy 126.376161 -369.408866) (xy 126.322169 -369.416629)
			(xy 126.294896 -369.417092) (xy 125.431296 -369.417092) (xy 125.404029 -369.416545) (xy 125.35005 -369.408784)
			(xy 125.297725 -369.393419) (xy 125.248119 -369.370765) (xy 125.202242 -369.341281) (xy 125.161029 -369.305569)
			(xy 125.125317 -369.264354) (xy 125.095833 -369.218477) (xy 125.073179 -369.168871) (xy 125.057815 -369.116546)
			(xy 125.050054 -369.062567) (xy 119.869028 -369.062567) (xy 119.869028 -369.062573) (xy 119.861266 -369.116565)
			(xy 119.845898 -369.168902) (xy 119.823238 -369.218519) (xy 119.793748 -369.264407) (xy 119.758027 -369.30563)
			(xy 119.716803 -369.34135) (xy 119.670916 -369.37084) (xy 119.621298 -369.393499) (xy 119.568961 -369.408866)
			(xy 119.514969 -369.416629) (xy 119.487696 -369.417092) (xy 118.624096 -369.417092) (xy 118.596829 -369.416545)
			(xy 118.54285 -369.408784) (xy 118.490525 -369.393419) (xy 118.440919 -369.370765) (xy 118.395042 -369.341281)
			(xy 118.353829 -369.305569) (xy 118.318117 -369.264354) (xy 118.288633 -369.218477) (xy 118.265979 -369.168871)
			(xy 118.250615 -369.116546) (xy 118.242854 -369.062567) (xy 113.061828 -369.062567) (xy 113.061828 -369.062573)
			(xy 113.054066 -369.116565) (xy 113.038698 -369.168902) (xy 113.016038 -369.218519) (xy 112.986548 -369.264407)
			(xy 112.950827 -369.30563) (xy 112.909603 -369.34135) (xy 112.863716 -369.37084) (xy 112.814098 -369.393499)
			(xy 112.761761 -369.408866) (xy 112.707769 -369.416629) (xy 112.680496 -369.417092) (xy 111.816896 -369.417092)
			(xy 111.789629 -369.416545) (xy 111.73565 -369.408784) (xy 111.683325 -369.393419) (xy 111.633719 -369.370765)
			(xy 111.587842 -369.341281) (xy 111.546629 -369.305569) (xy 111.510917 -369.264354) (xy 111.481433 -369.218477)
			(xy 111.458779 -369.168871) (xy 111.443415 -369.116546) (xy 111.435654 -369.062567) (xy 102.314806 -369.062567)
			(xy 102.314806 -369.062571) (xy 102.307043 -369.116559) (xy 102.291677 -369.168893) (xy 102.269019 -369.218507)
			(xy 102.239531 -369.264391) (xy 102.203813 -369.305612) (xy 102.162593 -369.34133) (xy 102.116708 -369.370818)
			(xy 102.067094 -369.393476) (xy 102.014761 -369.408843) (xy 101.960773 -369.416605) (xy 101.933502 -369.417092)
			(xy 101.069902 -369.417092) (xy 101.042633 -369.416569) (xy 100.98865 -369.408807) (xy 100.936321 -369.393443)
			(xy 100.886712 -369.370787) (xy 100.840832 -369.341302) (xy 100.799614 -369.305587) (xy 100.7639 -369.26437)
			(xy 100.734414 -369.21849) (xy 100.711758 -369.16888) (xy 100.696393 -369.116552) (xy 100.688631 -369.062569)
			(xy 98.911206 -369.062569) (xy 98.911206 -369.062571) (xy 98.903443 -369.116559) (xy 98.888077 -369.168893)
			(xy 98.865419 -369.218507) (xy 98.835931 -369.264391) (xy 98.800213 -369.305612) (xy 98.758993 -369.34133)
			(xy 98.713108 -369.370818) (xy 98.663494 -369.393476) (xy 98.611161 -369.408843) (xy 98.557173 -369.416605)
			(xy 98.529902 -369.417092) (xy 97.666302 -369.417092) (xy 97.639033 -369.416569) (xy 97.58505 -369.408807)
			(xy 97.532721 -369.393443) (xy 97.483112 -369.370787) (xy 97.437232 -369.341302) (xy 97.396014 -369.305587)
			(xy 97.3603 -369.26437) (xy 97.330814 -369.21849) (xy 97.308158 -369.16888) (xy 97.292793 -369.116552)
			(xy 97.285031 -369.062569) (xy 92.104006 -369.062569) (xy 92.104006 -369.062571) (xy 92.096243 -369.116559)
			(xy 92.080877 -369.168893) (xy 92.058219 -369.218507) (xy 92.028731 -369.264391) (xy 91.993013 -369.305612)
			(xy 91.951793 -369.34133) (xy 91.905908 -369.370818) (xy 91.856294 -369.393476) (xy 91.803961 -369.408843)
			(xy 91.749973 -369.416605) (xy 91.722702 -369.417092) (xy 90.859102 -369.417092) (xy 90.831833 -369.416569)
			(xy 90.77785 -369.408807) (xy 90.725521 -369.393443) (xy 90.675912 -369.370787) (xy 90.630032 -369.341302)
			(xy 90.588814 -369.305587) (xy 90.5531 -369.26437) (xy 90.523614 -369.21849) (xy 90.500958 -369.16888)
			(xy 90.485593 -369.116552) (xy 90.477831 -369.062569) (xy 85.296806 -369.062569) (xy 85.296806 -369.062571)
			(xy 85.289043 -369.116559) (xy 85.273677 -369.168893) (xy 85.251019 -369.218507) (xy 85.221531 -369.264391)
			(xy 85.185813 -369.305612) (xy 85.144593 -369.34133) (xy 85.098708 -369.370818) (xy 85.049094 -369.393476)
			(xy 84.996761 -369.408843) (xy 84.942773 -369.416605) (xy 84.915502 -369.417092) (xy 84.051902 -369.417092)
			(xy 84.024633 -369.416569) (xy 83.97065 -369.408807) (xy 83.918321 -369.393443) (xy 83.868712 -369.370787)
			(xy 83.822832 -369.341302) (xy 83.781614 -369.305587) (xy 83.7459 -369.26437) (xy 83.716414 -369.21849)
			(xy 83.693758 -369.16888) (xy 83.678393 -369.116552) (xy 83.670631 -369.062569) (xy 78.489606 -369.062569)
			(xy 78.489606 -369.062571) (xy 78.481843 -369.116559) (xy 78.466477 -369.168893) (xy 78.443819 -369.218507)
			(xy 78.414331 -369.264391) (xy 78.378613 -369.305612) (xy 78.337393 -369.34133) (xy 78.291508 -369.370818)
			(xy 78.241894 -369.393476) (xy 78.189561 -369.408843) (xy 78.135573 -369.416605) (xy 78.108302 -369.417092)
			(xy 77.244702 -369.417092) (xy 77.217433 -369.416569) (xy 77.16345 -369.408807) (xy 77.111121 -369.393443)
			(xy 77.061512 -369.370787) (xy 77.015632 -369.341302) (xy 76.974414 -369.305587) (xy 76.9387 -369.26437)
			(xy 76.909214 -369.21849) (xy 76.886558 -369.16888) (xy 76.871193 -369.116552) (xy 76.863431 -369.062569)
			(xy 69.787128 -369.062569) (xy 69.787128 -369.062575) (xy 69.779364 -369.11657) (xy 69.763995 -369.168911)
			(xy 69.741332 -369.218531) (xy 69.711838 -369.26442) (xy 69.676112 -369.305645) (xy 69.634884 -369.341365)
			(xy 69.588991 -369.370854) (xy 69.539368 -369.393511) (xy 69.487025 -369.408874) (xy 69.433029 -369.416632)
			(xy 69.405754 -369.417092) (xy 68.542154 -369.417092) (xy 68.514889 -369.416543) (xy 68.460915 -369.408776)
			(xy 68.408595 -369.393408) (xy 68.358994 -369.370751) (xy 68.313123 -369.341266) (xy 68.271914 -369.305554)
			(xy 68.236206 -369.264341) (xy 68.206727 -369.218465) (xy 68.184076 -369.168862) (xy 68.168714 -369.11654)
			(xy 68.160954 -369.062565) (xy 66.383528 -369.062565) (xy 66.383528 -369.062575) (xy 66.375764 -369.11657)
			(xy 66.360395 -369.168911) (xy 66.337732 -369.218531) (xy 66.308238 -369.26442) (xy 66.272512 -369.305645)
			(xy 66.231284 -369.341365) (xy 66.185391 -369.370854) (xy 66.135768 -369.393511) (xy 66.083425 -369.408874)
			(xy 66.029429 -369.416632) (xy 66.002154 -369.417092) (xy 65.138554 -369.417092) (xy 65.111289 -369.416543)
			(xy 65.057315 -369.408776) (xy 65.004995 -369.393408) (xy 64.955394 -369.370751) (xy 64.909523 -369.341266)
			(xy 64.868314 -369.305554) (xy 64.832606 -369.264341) (xy 64.803127 -369.218465) (xy 64.780476 -369.168862)
			(xy 64.765114 -369.11654) (xy 64.757354 -369.062565) (xy 59.576328 -369.062565) (xy 59.576328 -369.062575)
			(xy 59.568564 -369.11657) (xy 59.553195 -369.168911) (xy 59.530532 -369.218531) (xy 59.501038 -369.26442)
			(xy 59.465312 -369.305645) (xy 59.424084 -369.341365) (xy 59.378191 -369.370854) (xy 59.328568 -369.393511)
			(xy 59.276225 -369.408874) (xy 59.222229 -369.416632) (xy 59.194954 -369.417092) (xy 58.331354 -369.417092)
			(xy 58.304089 -369.416543) (xy 58.250115 -369.408776) (xy 58.197795 -369.393408) (xy 58.148194 -369.370751)
			(xy 58.102323 -369.341266) (xy 58.061114 -369.305554) (xy 58.025406 -369.264341) (xy 57.995927 -369.218465)
			(xy 57.973276 -369.168862) (xy 57.957914 -369.11654) (xy 57.950154 -369.062565) (xy 52.769128 -369.062565)
			(xy 52.769128 -369.062575) (xy 52.761364 -369.11657) (xy 52.745995 -369.168911) (xy 52.723332 -369.218531)
			(xy 52.693838 -369.26442) (xy 52.658112 -369.305645) (xy 52.616884 -369.341365) (xy 52.570991 -369.370854)
			(xy 52.521368 -369.393511) (xy 52.469025 -369.408874) (xy 52.415029 -369.416632) (xy 52.387754 -369.417092)
			(xy 51.524154 -369.417092) (xy 51.496889 -369.416543) (xy 51.442915 -369.408776) (xy 51.390595 -369.393408)
			(xy 51.340994 -369.370751) (xy 51.295123 -369.341266) (xy 51.253914 -369.305554) (xy 51.218206 -369.264341)
			(xy 51.188727 -369.218465) (xy 51.166076 -369.168862) (xy 51.150714 -369.11654) (xy 51.142954 -369.062565)
			(xy 45.961928 -369.062565) (xy 45.961928 -369.062575) (xy 45.954164 -369.11657) (xy 45.938795 -369.168911)
			(xy 45.916132 -369.218531) (xy 45.886638 -369.26442) (xy 45.850912 -369.305645) (xy 45.809684 -369.341365)
			(xy 45.763791 -369.370854) (xy 45.714168 -369.393511) (xy 45.661825 -369.408874) (xy 45.607829 -369.416632)
			(xy 45.580554 -369.417092) (xy 44.716954 -369.417092) (xy 44.689689 -369.416543) (xy 44.635715 -369.408776)
			(xy 44.583395 -369.393408) (xy 44.533794 -369.370751) (xy 44.487923 -369.341266) (xy 44.446714 -369.305554)
			(xy 44.411006 -369.264341) (xy 44.381527 -369.218465) (xy 44.358876 -369.168862) (xy 44.343514 -369.11654)
			(xy 44.335754 -369.062565) (xy 2.509012 -369.062565) (xy 2.509012 -370.915184) (xy 44.499276 -370.915184)
			(xy 44.499276 -370.22913) (xy 44.499734 -370.217038) (xy 44.507186 -370.194033) (xy 44.521374 -370.174449)
			(xy 44.540912 -370.160199) (xy 44.563894 -370.152673) (xy 44.575984 -370.152168) (xy 44.770548 -370.152168)
			(xy 44.781674 -370.152575) (xy 44.802971 -370.159039) (xy 44.812458 -370.164868) (xy 45.106082 -370.3574)
			(xy 45.115463 -370.363108) (xy 45.136477 -370.369443) (xy 45.158425 -370.369516) (xy 45.17948 -370.363319)
			(xy 45.188886 -370.357654) (xy 45.48505 -370.164868) (xy 45.494538 -370.159049) (xy 45.515837 -370.152607)
			(xy 45.52696 -370.152168) (xy 45.721524 -370.152168) (xy 45.733597 -370.152644) (xy 45.756561 -370.16011)
			(xy 45.776096 -370.174304) (xy 45.79029 -370.193839) (xy 45.797756 -370.216803) (xy 45.798232 -370.228876)
			(xy 45.798232 -370.91493) (xy 45.798223 -370.915184) (xy 51.306476 -370.915184) (xy 51.306476 -370.22913)
			(xy 51.306934 -370.217038) (xy 51.314386 -370.194033) (xy 51.328574 -370.174449) (xy 51.348112 -370.160199)
			(xy 51.371094 -370.152673) (xy 51.383184 -370.152168) (xy 51.577748 -370.152168) (xy 51.588874 -370.152575)
			(xy 51.610171 -370.159039) (xy 51.619658 -370.164868) (xy 51.913282 -370.3574) (xy 51.922663 -370.363108)
			(xy 51.943677 -370.369443) (xy 51.965625 -370.369516) (xy 51.98668 -370.363319) (xy 51.996086 -370.357654)
			(xy 52.29225 -370.164868) (xy 52.301738 -370.159049) (xy 52.323037 -370.152607) (xy 52.33416 -370.152168)
			(xy 52.528724 -370.152168) (xy 52.540797 -370.152644) (xy 52.563761 -370.16011) (xy 52.583296 -370.174304)
			(xy 52.59749 -370.193839) (xy 52.604956 -370.216803) (xy 52.605432 -370.228876) (xy 52.605432 -370.91493)
			(xy 52.605423 -370.915184) (xy 58.113676 -370.915184) (xy 58.113676 -370.22913) (xy 58.114134 -370.217038)
			(xy 58.121586 -370.194033) (xy 58.135774 -370.174449) (xy 58.155312 -370.160199) (xy 58.178294 -370.152673)
			(xy 58.190384 -370.152168) (xy 58.384948 -370.152168) (xy 58.396074 -370.152575) (xy 58.417371 -370.159039)
			(xy 58.426858 -370.164868) (xy 58.720482 -370.3574) (xy 58.729863 -370.363108) (xy 58.750877 -370.369443)
			(xy 58.772825 -370.369516) (xy 58.79388 -370.363319) (xy 58.803286 -370.357654) (xy 59.09945 -370.164868)
			(xy 59.108938 -370.159049) (xy 59.130237 -370.152607) (xy 59.14136 -370.152168) (xy 59.335924 -370.152168)
			(xy 59.347997 -370.152644) (xy 59.370961 -370.16011) (xy 59.390496 -370.174304) (xy 59.40469 -370.193839)
			(xy 59.412156 -370.216803) (xy 59.412632 -370.228876) (xy 59.412632 -370.91493) (xy 59.412623 -370.915184)
			(xy 64.920876 -370.915184) (xy 64.920876 -370.22913) (xy 64.921334 -370.217038) (xy 64.928786 -370.194033)
			(xy 64.942974 -370.174449) (xy 64.962512 -370.160199) (xy 64.985494 -370.152673) (xy 64.997584 -370.152168)
			(xy 65.192148 -370.152168) (xy 65.203274 -370.152575) (xy 65.224571 -370.159039) (xy 65.234058 -370.164868)
			(xy 65.527682 -370.3574) (xy 65.537063 -370.363108) (xy 65.558077 -370.369443) (xy 65.580025 -370.369516)
			(xy 65.60108 -370.363319) (xy 65.610486 -370.357654) (xy 65.90665 -370.164868) (xy 65.916138 -370.159049)
			(xy 65.937437 -370.152607) (xy 65.94856 -370.152168) (xy 66.143124 -370.152168) (xy 66.155197 -370.152644)
			(xy 66.178161 -370.16011) (xy 66.197696 -370.174304) (xy 66.21189 -370.193839) (xy 66.219356 -370.216803)
			(xy 66.219832 -370.228876) (xy 66.219832 -370.91493) (xy 66.219823 -370.915184) (xy 68.324476 -370.915184)
			(xy 68.324476 -370.22913) (xy 68.324934 -370.217038) (xy 68.332386 -370.194033) (xy 68.346574 -370.174449)
			(xy 68.366112 -370.160199) (xy 68.389094 -370.152673) (xy 68.401184 -370.152168) (xy 68.595748 -370.152168)
			(xy 68.606874 -370.152575) (xy 68.628171 -370.159039) (xy 68.637658 -370.164868) (xy 68.931282 -370.3574)
			(xy 68.940663 -370.363108) (xy 68.961677 -370.369443) (xy 68.983625 -370.369516) (xy 69.00468 -370.363319)
			(xy 69.014086 -370.357654) (xy 69.31025 -370.164868) (xy 69.319738 -370.159049) (xy 69.341037 -370.152607)
			(xy 69.35216 -370.152168) (xy 69.546724 -370.152168) (xy 69.558797 -370.152644) (xy 69.581761 -370.16011)
			(xy 69.601296 -370.174304) (xy 69.61549 -370.193839) (xy 69.622956 -370.216803) (xy 69.623432 -370.228876)
			(xy 69.623432 -370.91493) (xy 69.623423 -370.915184) (xy 77.027024 -370.915184) (xy 77.027024 -370.22913)
			(xy 77.027533 -370.217044) (xy 77.034979 -370.194047) (xy 77.049156 -370.174468) (xy 77.06868 -370.160215)
			(xy 77.091647 -370.15268) (xy 77.103732 -370.152168) (xy 77.298296 -370.152168) (xy 77.30942 -370.152596)
			(xy 77.330718 -370.159046) (xy 77.340206 -370.164868) (xy 77.63383 -370.3574) (xy 77.643188 -370.363149)
			(xy 77.664213 -370.369475) (xy 77.686169 -370.369536) (xy 77.707228 -370.363327) (xy 77.716634 -370.357654)
			(xy 78.012798 -370.164868) (xy 78.022297 -370.159068) (xy 78.043587 -370.152614) (xy 78.054708 -370.152168)
			(xy 78.249272 -370.152168) (xy 78.261351 -370.152636) (xy 78.284329 -370.160093) (xy 78.303877 -370.174286)
			(xy 78.318083 -370.193825) (xy 78.325556 -370.216797) (xy 78.32598 -370.228876) (xy 78.32598 -370.91493)
			(xy 78.32597 -370.915184) (xy 83.834224 -370.915184) (xy 83.834224 -370.22913) (xy 83.834733 -370.217044)
			(xy 83.842179 -370.194047) (xy 83.856356 -370.174468) (xy 83.87588 -370.160215) (xy 83.898847 -370.15268)
			(xy 83.910932 -370.152168) (xy 84.105496 -370.152168) (xy 84.11662 -370.152596) (xy 84.137918 -370.159046)
			(xy 84.147406 -370.164868) (xy 84.44103 -370.3574) (xy 84.450388 -370.363149) (xy 84.471413 -370.369475)
			(xy 84.493369 -370.369536) (xy 84.514428 -370.363327) (xy 84.523834 -370.357654) (xy 84.819998 -370.164868)
			(xy 84.829497 -370.159068) (xy 84.850787 -370.152614) (xy 84.861908 -370.152168) (xy 85.056472 -370.152168)
			(xy 85.068551 -370.152636) (xy 85.091529 -370.160093) (xy 85.111077 -370.174286) (xy 85.125283 -370.193825)
			(xy 85.132756 -370.216797) (xy 85.13318 -370.228876) (xy 85.13318 -370.91493) (xy 85.13317 -370.915184)
			(xy 90.641424 -370.915184) (xy 90.641424 -370.22913) (xy 90.641933 -370.217044) (xy 90.649379 -370.194047)
			(xy 90.663556 -370.174468) (xy 90.68308 -370.160215) (xy 90.706047 -370.15268) (xy 90.718132 -370.152168)
			(xy 90.912696 -370.152168) (xy 90.92382 -370.152596) (xy 90.945118 -370.159046) (xy 90.954606 -370.164868)
			(xy 91.24823 -370.3574) (xy 91.257588 -370.363149) (xy 91.278613 -370.369475) (xy 91.300569 -370.369536)
			(xy 91.321628 -370.363327) (xy 91.331034 -370.357654) (xy 91.627198 -370.164868) (xy 91.636697 -370.159068)
			(xy 91.657987 -370.152614) (xy 91.669108 -370.152168) (xy 91.863672 -370.152168) (xy 91.875751 -370.152636)
			(xy 91.898729 -370.160093) (xy 91.918277 -370.174286) (xy 91.932483 -370.193825) (xy 91.939956 -370.216797)
			(xy 91.94038 -370.228876) (xy 91.94038 -370.91493) (xy 91.94037 -370.915184) (xy 97.448624 -370.915184)
			(xy 97.448624 -370.22913) (xy 97.449133 -370.217044) (xy 97.456579 -370.194047) (xy 97.470756 -370.174468)
			(xy 97.49028 -370.160215) (xy 97.513247 -370.15268) (xy 97.525332 -370.152168) (xy 97.719896 -370.152168)
			(xy 97.73102 -370.152596) (xy 97.752318 -370.159046) (xy 97.761806 -370.164868) (xy 98.05543 -370.3574)
			(xy 98.064788 -370.363149) (xy 98.085813 -370.369475) (xy 98.107769 -370.369536) (xy 98.128828 -370.363327)
			(xy 98.138234 -370.357654) (xy 98.434398 -370.164868) (xy 98.443897 -370.159068) (xy 98.465187 -370.152614)
			(xy 98.476308 -370.152168) (xy 98.670872 -370.152168) (xy 98.682951 -370.152636) (xy 98.705929 -370.160093)
			(xy 98.725477 -370.174286) (xy 98.739683 -370.193825) (xy 98.747156 -370.216797) (xy 98.74758 -370.228876)
			(xy 98.74758 -370.91493) (xy 98.74757 -370.915184) (xy 100.852224 -370.915184) (xy 100.852224 -370.22913)
			(xy 100.852733 -370.217044) (xy 100.860179 -370.194047) (xy 100.874356 -370.174468) (xy 100.89388 -370.160215)
			(xy 100.916847 -370.15268) (xy 100.928932 -370.152168) (xy 101.123496 -370.152168) (xy 101.13462 -370.152596)
			(xy 101.155918 -370.159046) (xy 101.165406 -370.164868) (xy 101.45903 -370.3574) (xy 101.468388 -370.363149)
			(xy 101.489413 -370.369475) (xy 101.511369 -370.369536) (xy 101.532428 -370.363327) (xy 101.541834 -370.357654)
			(xy 101.837998 -370.164868) (xy 101.847497 -370.159068) (xy 101.868787 -370.152614) (xy 101.879908 -370.152168)
			(xy 102.074472 -370.152168) (xy 102.086551 -370.152636) (xy 102.109529 -370.160093) (xy 102.129077 -370.174286)
			(xy 102.143283 -370.193825) (xy 102.150756 -370.216797) (xy 102.15118 -370.228876) (xy 102.15118 -370.91493)
			(xy 111.598964 -370.91493) (xy 111.598964 -370.22913) (xy 111.599386 -370.217006) (xy 111.606873 -370.193944)
			(xy 111.621123 -370.174326) (xy 111.64074 -370.160075) (xy 111.663802 -370.152586) (xy 111.675926 -370.152168)
			(xy 111.87049 -370.152168) (xy 111.881614 -370.152599) (xy 111.902911 -370.159046) (xy 111.9124 -370.164868)
			(xy 112.206024 -370.3574) (xy 112.215385 -370.363144) (xy 112.236408 -370.369471) (xy 112.258363 -370.369534)
			(xy 112.279422 -370.363326) (xy 112.288828 -370.357654) (xy 112.584992 -370.164868) (xy 112.594492 -370.15907)
			(xy 112.615782 -370.152615) (xy 112.626902 -370.152168) (xy 112.821466 -370.152168) (xy 112.83359 -370.152589)
			(xy 112.856653 -370.160076) (xy 112.876271 -370.174326) (xy 112.890522 -370.193944) (xy 112.89801 -370.217006)
			(xy 112.898428 -370.22913) (xy 112.898428 -370.91493) (xy 118.406164 -370.91493) (xy 118.406164 -370.22913)
			(xy 118.406586 -370.217006) (xy 118.414073 -370.193944) (xy 118.428323 -370.174326) (xy 118.44794 -370.160075)
			(xy 118.471002 -370.152586) (xy 118.483126 -370.152168) (xy 118.67769 -370.152168) (xy 118.688814 -370.152599)
			(xy 118.710111 -370.159046) (xy 118.7196 -370.164868) (xy 119.013224 -370.3574) (xy 119.022585 -370.363144)
			(xy 119.043608 -370.369471) (xy 119.065563 -370.369534) (xy 119.086622 -370.363326) (xy 119.096028 -370.357654)
			(xy 119.392192 -370.164868) (xy 119.401692 -370.15907) (xy 119.422982 -370.152615) (xy 119.434102 -370.152168)
			(xy 119.628666 -370.152168) (xy 119.64079 -370.152589) (xy 119.663853 -370.160076) (xy 119.683471 -370.174326)
			(xy 119.697722 -370.193944) (xy 119.70521 -370.217006) (xy 119.705628 -370.22913) (xy 119.705628 -370.91493)
			(xy 125.213364 -370.91493) (xy 125.213364 -370.22913) (xy 125.213786 -370.217006) (xy 125.221273 -370.193944)
			(xy 125.235523 -370.174326) (xy 125.25514 -370.160075) (xy 125.278202 -370.152586) (xy 125.290326 -370.152168)
			(xy 125.48489 -370.152168) (xy 125.496014 -370.152599) (xy 125.517311 -370.159046) (xy 125.5268 -370.164868)
			(xy 125.820424 -370.3574) (xy 125.829785 -370.363144) (xy 125.850808 -370.369471) (xy 125.872763 -370.369534)
			(xy 125.893822 -370.363326) (xy 125.903228 -370.357654) (xy 126.199392 -370.164868) (xy 126.208892 -370.15907)
			(xy 126.230182 -370.152615) (xy 126.241302 -370.152168) (xy 126.435866 -370.152168) (xy 126.44799 -370.152589)
			(xy 126.471053 -370.160076) (xy 126.490671 -370.174326) (xy 126.504922 -370.193944) (xy 126.51241 -370.217006)
			(xy 126.512828 -370.22913) (xy 126.512828 -370.91493) (xy 132.020564 -370.91493) (xy 132.020564 -370.22913)
			(xy 132.020986 -370.217006) (xy 132.028473 -370.193944) (xy 132.042723 -370.174326) (xy 132.06234 -370.160075)
			(xy 132.085402 -370.152586) (xy 132.097526 -370.152168) (xy 132.29209 -370.152168) (xy 132.303214 -370.152599)
			(xy 132.324511 -370.159046) (xy 132.334 -370.164868) (xy 132.627624 -370.3574) (xy 132.636985 -370.363144)
			(xy 132.658008 -370.369471) (xy 132.679963 -370.369534) (xy 132.701022 -370.363326) (xy 132.710428 -370.357654)
			(xy 133.006592 -370.164868) (xy 133.016092 -370.15907) (xy 133.037382 -370.152615) (xy 133.048502 -370.152168)
			(xy 133.243066 -370.152168) (xy 133.25519 -370.152589) (xy 133.278253 -370.160076) (xy 133.297871 -370.174326)
			(xy 133.312122 -370.193944) (xy 133.31961 -370.217006) (xy 133.320028 -370.22913) (xy 133.320028 -370.91493)
			(xy 135.424164 -370.91493) (xy 135.424164 -370.22913) (xy 135.424586 -370.217006) (xy 135.432073 -370.193944)
			(xy 135.446323 -370.174326) (xy 135.46594 -370.160075) (xy 135.489002 -370.152586) (xy 135.501126 -370.152168)
			(xy 135.69569 -370.152168) (xy 135.706814 -370.152599) (xy 135.728111 -370.159046) (xy 135.7376 -370.164868)
			(xy 136.031224 -370.3574) (xy 136.040585 -370.363144) (xy 136.061608 -370.369471) (xy 136.083563 -370.369534)
			(xy 136.104622 -370.363326) (xy 136.114028 -370.357654) (xy 136.410192 -370.164868) (xy 136.419692 -370.15907)
			(xy 136.440982 -370.152615) (xy 136.452102 -370.152168) (xy 136.646666 -370.152168) (xy 136.65879 -370.152589)
			(xy 136.681853 -370.160076) (xy 136.701471 -370.174326) (xy 136.715722 -370.193944) (xy 136.719889 -370.206778)
			(xy 138.3665 -370.206778) (xy 138.3665 -369.343178) (xy 138.366986 -369.315909) (xy 138.374748 -369.261925)
			(xy 138.390113 -369.209595) (xy 138.41277 -369.159985) (xy 138.442256 -369.114104) (xy 138.477971 -369.072887)
			(xy 138.519188 -369.037172) (xy 138.565069 -369.007686) (xy 138.614679 -368.985029) (xy 138.667009 -368.969664)
			(xy 138.720993 -368.961902) (xy 138.775531 -368.961902) (xy 138.829515 -368.969664) (xy 138.881845 -368.985029)
			(xy 138.931455 -369.007686) (xy 138.977336 -369.037172) (xy 139.006648 -369.062571) (xy 143.963332 -369.062571)
			(xy 143.963332 -369.008029) (xy 143.971094 -368.954043) (xy 143.986461 -368.901711) (xy 144.009121 -368.852098)
			(xy 144.03861 -368.806216) (xy 144.074329 -368.764998) (xy 144.115551 -368.729284) (xy 144.161437 -368.699799)
			(xy 144.211052 -368.677146) (xy 144.263386 -368.661785) (xy 144.317373 -368.654028) (xy 144.344644 -368.653568)
			(xy 145.208244 -368.653568) (xy 145.235513 -368.653998) (xy 145.289497 -368.661765) (xy 145.341825 -368.677135)
			(xy 145.391433 -368.699796) (xy 145.437312 -368.729285) (xy 145.478528 -368.765003) (xy 145.514241 -368.806223)
			(xy 145.543725 -368.852105) (xy 145.56638 -368.901716) (xy 145.581744 -368.954047) (xy 145.589506 -369.00803)
			(xy 145.589506 -369.06257) (xy 145.589506 -369.062571) (xy 150.770532 -369.062571) (xy 150.770532 -369.008029)
			(xy 150.778294 -368.954043) (xy 150.793661 -368.901711) (xy 150.816321 -368.852098) (xy 150.84581 -368.806216)
			(xy 150.881529 -368.764998) (xy 150.922751 -368.729284) (xy 150.968637 -368.699799) (xy 151.018252 -368.677146)
			(xy 151.070586 -368.661785) (xy 151.124573 -368.654028) (xy 151.151844 -368.653568) (xy 152.015444 -368.653568)
			(xy 152.042713 -368.653998) (xy 152.096697 -368.661765) (xy 152.149025 -368.677135) (xy 152.198633 -368.699796)
			(xy 152.244512 -368.729285) (xy 152.285728 -368.765003) (xy 152.321441 -368.806223) (xy 152.350925 -368.852105)
			(xy 152.37358 -368.901716) (xy 152.388944 -368.954047) (xy 152.396706 -369.00803) (xy 152.396706 -369.06257)
			(xy 152.396706 -369.062571) (xy 157.577732 -369.062571) (xy 157.577732 -369.008029) (xy 157.585494 -368.954043)
			(xy 157.600861 -368.901711) (xy 157.623521 -368.852098) (xy 157.65301 -368.806216) (xy 157.688729 -368.764998)
			(xy 157.729951 -368.729284) (xy 157.775837 -368.699799) (xy 157.825452 -368.677146) (xy 157.877786 -368.661785)
			(xy 157.931773 -368.654028) (xy 157.959044 -368.653568) (xy 158.822644 -368.653568) (xy 158.849913 -368.653998)
			(xy 158.903897 -368.661765) (xy 158.956225 -368.677135) (xy 159.005833 -368.699796) (xy 159.051712 -368.729285)
			(xy 159.092928 -368.765003) (xy 159.128641 -368.806223) (xy 159.158125 -368.852105) (xy 159.18078 -368.901716)
			(xy 159.196144 -368.954047) (xy 159.203906 -369.00803) (xy 159.203906 -369.06257) (xy 159.203906 -369.062571)
			(xy 164.384932 -369.062571) (xy 164.384932 -369.008029) (xy 164.392694 -368.954043) (xy 164.408061 -368.901711)
			(xy 164.430721 -368.852098) (xy 164.46021 -368.806216) (xy 164.495929 -368.764998) (xy 164.537151 -368.729284)
			(xy 164.583037 -368.699799) (xy 164.632652 -368.677146) (xy 164.684986 -368.661785) (xy 164.738973 -368.654028)
			(xy 164.766244 -368.653568) (xy 165.629844 -368.653568) (xy 165.657113 -368.653998) (xy 165.711097 -368.661765)
			(xy 165.763425 -368.677135) (xy 165.813033 -368.699796) (xy 165.858912 -368.729285) (xy 165.900128 -368.765003)
			(xy 165.935841 -368.806223) (xy 165.965325 -368.852105) (xy 165.98798 -368.901716) (xy 166.003344 -368.954047)
			(xy 166.011106 -369.00803) (xy 166.011106 -369.06257) (xy 166.011106 -369.062571) (xy 167.788532 -369.062571)
			(xy 167.788532 -369.008029) (xy 167.796294 -368.954043) (xy 167.811661 -368.901711) (xy 167.834321 -368.852098)
			(xy 167.86381 -368.806216) (xy 167.899529 -368.764998) (xy 167.940751 -368.729284) (xy 167.986637 -368.699799)
			(xy 168.036252 -368.677146) (xy 168.088586 -368.661785) (xy 168.142573 -368.654028) (xy 168.169844 -368.653568)
			(xy 169.033444 -368.653568) (xy 169.060713 -368.653998) (xy 169.114697 -368.661765) (xy 169.167025 -368.677135)
			(xy 169.216633 -368.699796) (xy 169.262512 -368.729285) (xy 169.303728 -368.765003) (xy 169.339441 -368.806223)
			(xy 169.368925 -368.852105) (xy 169.39158 -368.901716) (xy 169.406944 -368.954047) (xy 169.414706 -369.00803)
			(xy 169.414706 -369.06257) (xy 169.406944 -369.116553) (xy 169.39158 -369.168884) (xy 169.368925 -369.218495)
			(xy 169.339441 -369.264377) (xy 169.303728 -369.305597) (xy 169.262512 -369.341315) (xy 169.216633 -369.370804)
			(xy 169.167025 -369.393465) (xy 169.114697 -369.408835) (xy 169.060713 -369.416602) (xy 169.033444 -369.417092)
			(xy 168.169844 -369.417092) (xy 168.142573 -369.416572) (xy 168.088586 -369.408815) (xy 168.036252 -369.393454)
			(xy 167.986637 -369.370801) (xy 167.940751 -369.341316) (xy 167.899529 -369.305602) (xy 167.86381 -369.264384)
			(xy 167.834321 -369.218502) (xy 167.811661 -369.168889) (xy 167.796294 -369.116557) (xy 167.788532 -369.062571)
			(xy 166.011106 -369.062571) (xy 166.003344 -369.116553) (xy 165.98798 -369.168884) (xy 165.965325 -369.218495)
			(xy 165.935841 -369.264377) (xy 165.900128 -369.305597) (xy 165.858912 -369.341315) (xy 165.813033 -369.370804)
			(xy 165.763425 -369.393465) (xy 165.711097 -369.408835) (xy 165.657113 -369.416602) (xy 165.629844 -369.417092)
			(xy 164.766244 -369.417092) (xy 164.738973 -369.416572) (xy 164.684986 -369.408815) (xy 164.632652 -369.393454)
			(xy 164.583037 -369.370801) (xy 164.537151 -369.341316) (xy 164.495929 -369.305602) (xy 164.46021 -369.264384)
			(xy 164.430721 -369.218502) (xy 164.408061 -369.168889) (xy 164.392694 -369.116557) (xy 164.384932 -369.062571)
			(xy 159.203906 -369.062571) (xy 159.196144 -369.116553) (xy 159.18078 -369.168884) (xy 159.158125 -369.218495)
			(xy 159.128641 -369.264377) (xy 159.092928 -369.305597) (xy 159.051712 -369.341315) (xy 159.005833 -369.370804)
			(xy 158.956225 -369.393465) (xy 158.903897 -369.408835) (xy 158.849913 -369.416602) (xy 158.822644 -369.417092)
			(xy 157.959044 -369.417092) (xy 157.931773 -369.416572) (xy 157.877786 -369.408815) (xy 157.825452 -369.393454)
			(xy 157.775837 -369.370801) (xy 157.729951 -369.341316) (xy 157.688729 -369.305602) (xy 157.65301 -369.264384)
			(xy 157.623521 -369.218502) (xy 157.600861 -369.168889) (xy 157.585494 -369.116557) (xy 157.577732 -369.062571)
			(xy 152.396706 -369.062571) (xy 152.388944 -369.116553) (xy 152.37358 -369.168884) (xy 152.350925 -369.218495)
			(xy 152.321441 -369.264377) (xy 152.285728 -369.305597) (xy 152.244512 -369.341315) (xy 152.198633 -369.370804)
			(xy 152.149025 -369.393465) (xy 152.096697 -369.408835) (xy 152.042713 -369.416602) (xy 152.015444 -369.417092)
			(xy 151.151844 -369.417092) (xy 151.124573 -369.416572) (xy 151.070586 -369.408815) (xy 151.018252 -369.393454)
			(xy 150.968637 -369.370801) (xy 150.922751 -369.341316) (xy 150.881529 -369.305602) (xy 150.84581 -369.264384)
			(xy 150.816321 -369.218502) (xy 150.793661 -369.168889) (xy 150.778294 -369.116557) (xy 150.770532 -369.062571)
			(xy 145.589506 -369.062571) (xy 145.581744 -369.116553) (xy 145.56638 -369.168884) (xy 145.543725 -369.218495)
			(xy 145.514241 -369.264377) (xy 145.478528 -369.305597) (xy 145.437312 -369.341315) (xy 145.391433 -369.370804)
			(xy 145.341825 -369.393465) (xy 145.289497 -369.408835) (xy 145.235513 -369.416602) (xy 145.208244 -369.417092)
			(xy 144.344644 -369.417092) (xy 144.317373 -369.416572) (xy 144.263386 -369.408815) (xy 144.211052 -369.393454)
			(xy 144.161437 -369.370801) (xy 144.115551 -369.341316) (xy 144.074329 -369.305602) (xy 144.03861 -369.264384)
			(xy 144.009121 -369.218502) (xy 143.986461 -369.168889) (xy 143.971094 -369.116557) (xy 143.963332 -369.062571)
			(xy 139.006648 -369.062571) (xy 139.018553 -369.072887) (xy 139.054268 -369.114104) (xy 139.083754 -369.159985)
			(xy 139.106411 -369.209595) (xy 139.121776 -369.261925) (xy 139.129538 -369.315909) (xy 139.130024 -369.343178)
			(xy 139.130024 -370.206778) (xy 139.129538 -370.234047) (xy 139.121776 -370.288031) (xy 139.106411 -370.340361)
			(xy 139.083754 -370.389971) (xy 139.071223 -370.40947) (xy 141.572996 -370.40947) (xy 141.572996 -369.54587)
			(xy 141.573482 -369.518619) (xy 141.581238 -369.464671) (xy 141.596593 -369.412376) (xy 141.619235 -369.362799)
			(xy 141.648701 -369.316949) (xy 141.684392 -369.275758) (xy 141.725583 -369.240067) (xy 141.771433 -369.210601)
			(xy 141.82101 -369.187959) (xy 141.873305 -369.172604) (xy 141.927253 -369.164848) (xy 141.981755 -369.164848)
			(xy 142.035703 -369.172604) (xy 142.087998 -369.187959) (xy 142.137575 -369.210601) (xy 142.183425 -369.240067)
			(xy 142.224616 -369.275758) (xy 142.260307 -369.316949) (xy 142.289773 -369.362799) (xy 142.312415 -369.412376)
			(xy 142.32777 -369.464671) (xy 142.335526 -369.518619) (xy 142.336012 -369.54587) (xy 142.336012 -369.62565)
			(xy 175.203103 -369.62565) (xy 175.203103 -369.57115) (xy 175.210859 -369.517206) (xy 175.226214 -369.464914)
			(xy 175.248854 -369.41534) (xy 175.278318 -369.369493) (xy 175.314008 -369.328305) (xy 175.355196 -369.292616)
			(xy 175.401044 -369.263152) (xy 175.450618 -369.240512) (xy 175.50291 -369.225158) (xy 175.556854 -369.217403)
			(xy 175.584104 -369.21694) (xy 176.447704 -369.21694) (xy 176.474958 -369.21733) (xy 176.528913 -369.225088)
			(xy 176.581213 -369.240446) (xy 176.630796 -369.26309) (xy 176.676652 -369.29256) (xy 176.717847 -369.328256)
			(xy 176.753543 -369.369451) (xy 176.783012 -369.415307) (xy 176.805656 -369.46489) (xy 176.821013 -369.517191)
			(xy 176.82877 -369.571146) (xy 176.82877 -369.625654) (xy 176.821013 -369.679609) (xy 176.805656 -369.73191)
			(xy 176.783012 -369.781493) (xy 176.753543 -369.827349) (xy 176.717847 -369.868544) (xy 176.676652 -369.90424)
			(xy 176.630796 -369.93371) (xy 176.581213 -369.956354) (xy 176.528913 -369.971712) (xy 176.474958 -369.97947)
			(xy 176.447704 -369.979956) (xy 175.584104 -369.979956) (xy 175.556854 -369.979397) (xy 175.50291 -369.971642)
			(xy 175.450618 -369.956288) (xy 175.401044 -369.933648) (xy 175.355196 -369.904184) (xy 175.314008 -369.868495)
			(xy 175.278318 -369.827307) (xy 175.248854 -369.78146) (xy 175.226214 -369.731886) (xy 175.210859 -369.679594)
			(xy 175.203103 -369.62565) (xy 142.336012 -369.62565) (xy 142.336012 -370.40947) (xy 142.335526 -370.436721)
			(xy 142.32777 -370.490669) (xy 142.312415 -370.542964) (xy 142.289773 -370.592541) (xy 142.260307 -370.638391)
			(xy 142.224616 -370.679582) (xy 142.183425 -370.715273) (xy 142.137575 -370.744739) (xy 142.087998 -370.767381)
			(xy 142.035703 -370.782736) (xy 141.981755 -370.790492) (xy 141.927253 -370.790492) (xy 141.873305 -370.782736)
			(xy 141.82101 -370.767381) (xy 141.771433 -370.744739) (xy 141.725583 -370.715273) (xy 141.684392 -370.679582)
			(xy 141.648701 -370.638391) (xy 141.619235 -370.592541) (xy 141.596593 -370.542964) (xy 141.581238 -370.490669)
			(xy 141.573482 -370.436721) (xy 141.572996 -370.40947) (xy 139.071223 -370.40947) (xy 139.054268 -370.435852)
			(xy 139.018553 -370.477069) (xy 138.977336 -370.512784) (xy 138.931455 -370.54227) (xy 138.881845 -370.564927)
			(xy 138.829515 -370.580292) (xy 138.775531 -370.588054) (xy 138.720993 -370.588054) (xy 138.667009 -370.580292)
			(xy 138.614679 -370.564927) (xy 138.565069 -370.54227) (xy 138.519188 -370.512784) (xy 138.477971 -370.477069)
			(xy 138.442256 -370.435852) (xy 138.41277 -370.389971) (xy 138.390113 -370.340361) (xy 138.374748 -370.288031)
			(xy 138.366986 -370.234047) (xy 138.3665 -370.206778) (xy 136.719889 -370.206778) (xy 136.72321 -370.217006)
			(xy 136.723628 -370.22913) (xy 136.723628 -370.91493) (xy 144.126712 -370.91493) (xy 144.126712 -370.22913)
			(xy 144.127185 -370.217011) (xy 144.134666 -370.193958) (xy 144.148905 -370.174345) (xy 144.168508 -370.160092)
			(xy 144.191556 -370.152594) (xy 144.203674 -370.152168) (xy 144.398238 -370.152168) (xy 144.409364 -370.152579)
			(xy 144.430661 -370.15904) (xy 144.440148 -370.164868) (xy 144.733772 -370.3574) (xy 144.743158 -370.363099)
			(xy 144.764169 -370.369436) (xy 144.786116 -370.369512) (xy 144.80717 -370.363318) (xy 144.816576 -370.357654)
			(xy 145.11274 -370.164868) (xy 145.12223 -370.159052) (xy 145.143528 -370.152608) (xy 145.15465 -370.152168)
			(xy 145.349214 -370.152168) (xy 145.36134 -370.152549) (xy 145.384405 -370.160048) (xy 145.404022 -370.174309)
			(xy 145.418272 -370.193935) (xy 145.425758 -370.217003) (xy 145.426176 -370.22913) (xy 145.426176 -370.91493)
			(xy 150.933912 -370.91493) (xy 150.933912 -370.22913) (xy 150.934385 -370.217011) (xy 150.941866 -370.193958)
			(xy 150.956105 -370.174345) (xy 150.975708 -370.160092) (xy 150.998756 -370.152594) (xy 151.010874 -370.152168)
			(xy 151.205438 -370.152168) (xy 151.216564 -370.152579) (xy 151.237861 -370.15904) (xy 151.247348 -370.164868)
			(xy 151.540972 -370.3574) (xy 151.550358 -370.363099) (xy 151.571369 -370.369436) (xy 151.593316 -370.369512)
			(xy 151.61437 -370.363318) (xy 151.623776 -370.357654) (xy 151.91994 -370.164868) (xy 151.92943 -370.159052)
			(xy 151.950728 -370.152608) (xy 151.96185 -370.152168) (xy 152.156414 -370.152168) (xy 152.16854 -370.152549)
			(xy 152.191605 -370.160048) (xy 152.211222 -370.174309) (xy 152.225472 -370.193935) (xy 152.232958 -370.217003)
			(xy 152.233376 -370.22913) (xy 152.233376 -370.91493) (xy 157.741112 -370.91493) (xy 157.741112 -370.22913)
			(xy 157.741585 -370.217011) (xy 157.749066 -370.193958) (xy 157.763305 -370.174345) (xy 157.782908 -370.160092)
			(xy 157.805956 -370.152594) (xy 157.818074 -370.152168) (xy 158.012638 -370.152168) (xy 158.023764 -370.152579)
			(xy 158.045061 -370.15904) (xy 158.054548 -370.164868) (xy 158.348172 -370.3574) (xy 158.357558 -370.363099)
			(xy 158.378569 -370.369436) (xy 158.400516 -370.369512) (xy 158.42157 -370.363318) (xy 158.430976 -370.357654)
			(xy 158.72714 -370.164868) (xy 158.73663 -370.159052) (xy 158.757928 -370.152608) (xy 158.76905 -370.152168)
			(xy 158.963614 -370.152168) (xy 158.97574 -370.152549) (xy 158.998805 -370.160048) (xy 159.018422 -370.174309)
			(xy 159.032672 -370.193935) (xy 159.040158 -370.217003) (xy 159.040576 -370.22913) (xy 159.040576 -370.91493)
			(xy 164.548312 -370.91493) (xy 164.548312 -370.22913) (xy 164.548785 -370.217011) (xy 164.556266 -370.193958)
			(xy 164.570505 -370.174345) (xy 164.590108 -370.160092) (xy 164.613156 -370.152594) (xy 164.625274 -370.152168)
			(xy 164.819838 -370.152168) (xy 164.830964 -370.152579) (xy 164.852261 -370.15904) (xy 164.861748 -370.164868)
			(xy 165.155372 -370.3574) (xy 165.164758 -370.363099) (xy 165.185769 -370.369436) (xy 165.207716 -370.369512)
			(xy 165.22877 -370.363318) (xy 165.238176 -370.357654) (xy 165.53434 -370.164868) (xy 165.54383 -370.159052)
			(xy 165.565128 -370.152608) (xy 165.57625 -370.152168) (xy 165.770814 -370.152168) (xy 165.78294 -370.152549)
			(xy 165.806005 -370.160048) (xy 165.825622 -370.174309) (xy 165.839872 -370.193935) (xy 165.847358 -370.217003)
			(xy 165.847776 -370.22913) (xy 165.847776 -370.91493) (xy 167.951912 -370.91493) (xy 167.951912 -370.22913)
			(xy 167.952385 -370.217011) (xy 167.959866 -370.193958) (xy 167.974105 -370.174345) (xy 167.993708 -370.160092)
			(xy 168.016756 -370.152594) (xy 168.028874 -370.152168) (xy 168.223438 -370.152168) (xy 168.234564 -370.152579)
			(xy 168.255861 -370.15904) (xy 168.265348 -370.164868) (xy 168.558972 -370.3574) (xy 168.568358 -370.363099)
			(xy 168.589369 -370.369436) (xy 168.611316 -370.369512) (xy 168.63237 -370.363318) (xy 168.641776 -370.357654)
			(xy 168.93794 -370.164868) (xy 168.94743 -370.159052) (xy 168.968728 -370.152608) (xy 168.97985 -370.152168)
			(xy 169.174414 -370.152168) (xy 169.18654 -370.152549) (xy 169.209605 -370.160048) (xy 169.229222 -370.174309)
			(xy 169.243472 -370.193935) (xy 169.250958 -370.217003) (xy 169.251376 -370.22913) (xy 169.251376 -370.91493)
			(xy 169.250914 -370.927045) (xy 169.24342 -370.950087) (xy 169.229175 -370.969687) (xy 169.209572 -370.983928)
			(xy 169.186529 -370.991417) (xy 169.174414 -370.991892) (xy 168.97985 -370.991892) (xy 168.968725 -370.991476)
			(xy 168.947428 -370.985018) (xy 168.93794 -370.979192) (xy 168.643046 -370.78666) (xy 168.633659 -370.780957)
			(xy 168.612621 -370.774684) (xy 168.590667 -370.774684) (xy 168.569629 -370.780957) (xy 168.560242 -370.78666)
			(xy 168.266618 -370.979192) (xy 168.257114 -370.984983) (xy 168.235827 -370.991443) (xy 168.224708 -370.991892)
			(xy 168.028874 -370.991892) (xy 168.016761 -370.991411) (xy 167.993722 -370.98392) (xy 167.974123 -370.96968)
			(xy 167.959882 -370.950082) (xy 167.95239 -370.927043) (xy 167.951912 -370.91493) (xy 165.847776 -370.91493)
			(xy 165.847314 -370.927045) (xy 165.83982 -370.950087) (xy 165.825575 -370.969687) (xy 165.805972 -370.983928)
			(xy 165.782929 -370.991417) (xy 165.770814 -370.991892) (xy 165.57625 -370.991892) (xy 165.565125 -370.991476)
			(xy 165.543828 -370.985018) (xy 165.53434 -370.979192) (xy 165.239446 -370.78666) (xy 165.230059 -370.780957)
			(xy 165.209021 -370.774684) (xy 165.187067 -370.774684) (xy 165.166029 -370.780957) (xy 165.156642 -370.78666)
			(xy 164.863018 -370.979192) (xy 164.853514 -370.984983) (xy 164.832227 -370.991443) (xy 164.821108 -370.991892)
			(xy 164.625274 -370.991892) (xy 164.613161 -370.991411) (xy 164.590122 -370.98392) (xy 164.570523 -370.96968)
			(xy 164.556282 -370.950082) (xy 164.54879 -370.927043) (xy 164.548312 -370.91493) (xy 159.040576 -370.91493)
			(xy 159.040114 -370.927045) (xy 159.03262 -370.950087) (xy 159.018375 -370.969687) (xy 158.998772 -370.983928)
			(xy 158.975729 -370.991417) (xy 158.963614 -370.991892) (xy 158.76905 -370.991892) (xy 158.757925 -370.991476)
			(xy 158.736628 -370.985018) (xy 158.72714 -370.979192) (xy 158.432246 -370.78666) (xy 158.422859 -370.780957)
			(xy 158.401821 -370.774684) (xy 158.379867 -370.774684) (xy 158.358829 -370.780957) (xy 158.349442 -370.78666)
			(xy 158.055818 -370.979192) (xy 158.046314 -370.984983) (xy 158.025027 -370.991443) (xy 158.013908 -370.991892)
			(xy 157.818074 -370.991892) (xy 157.805961 -370.991411) (xy 157.782922 -370.98392) (xy 157.763323 -370.96968)
			(xy 157.749082 -370.950082) (xy 157.74159 -370.927043) (xy 157.741112 -370.91493) (xy 152.233376 -370.91493)
			(xy 152.232914 -370.927045) (xy 152.22542 -370.950087) (xy 152.211175 -370.969687) (xy 152.191572 -370.983928)
			(xy 152.168529 -370.991417) (xy 152.156414 -370.991892) (xy 151.96185 -370.991892) (xy 151.950725 -370.991476)
			(xy 151.929428 -370.985018) (xy 151.91994 -370.979192) (xy 151.625046 -370.78666) (xy 151.615659 -370.780957)
			(xy 151.594621 -370.774684) (xy 151.572667 -370.774684) (xy 151.551629 -370.780957) (xy 151.542242 -370.78666)
			(xy 151.248618 -370.979192) (xy 151.239114 -370.984983) (xy 151.217827 -370.991443) (xy 151.206708 -370.991892)
			(xy 151.010874 -370.991892) (xy 150.998761 -370.991411) (xy 150.975722 -370.98392) (xy 150.956123 -370.96968)
			(xy 150.941882 -370.950082) (xy 150.93439 -370.927043) (xy 150.933912 -370.91493) (xy 145.426176 -370.91493)
			(xy 145.425714 -370.927045) (xy 145.41822 -370.950087) (xy 145.403975 -370.969687) (xy 145.384372 -370.983928)
			(xy 145.361329 -370.991417) (xy 145.349214 -370.991892) (xy 145.15465 -370.991892) (xy 145.143525 -370.991476)
			(xy 145.122228 -370.985018) (xy 145.11274 -370.979192) (xy 144.817846 -370.78666) (xy 144.808459 -370.780957)
			(xy 144.787421 -370.774684) (xy 144.765467 -370.774684) (xy 144.744429 -370.780957) (xy 144.735042 -370.78666)
			(xy 144.441418 -370.979192) (xy 144.431914 -370.984983) (xy 144.410627 -370.991443) (xy 144.399508 -370.991892)
			(xy 144.203674 -370.991892) (xy 144.191561 -370.991411) (xy 144.168522 -370.98392) (xy 144.148923 -370.96968)
			(xy 144.134682 -370.950082) (xy 144.12719 -370.927043) (xy 144.126712 -370.91493) (xy 136.723628 -370.91493)
			(xy 136.723265 -370.927058) (xy 136.715761 -370.950123) (xy 136.701495 -370.969741) (xy 136.681866 -370.98399)
			(xy 136.658794 -370.991475) (xy 136.646666 -370.991892) (xy 136.452102 -370.991892) (xy 136.440978 -370.991456)
			(xy 136.419682 -370.985011) (xy 136.410192 -370.979192) (xy 136.115298 -370.78666) (xy 136.105911 -370.780957)
			(xy 136.084873 -370.774684) (xy 136.062919 -370.774684) (xy 136.041881 -370.780957) (xy 136.032494 -370.78666)
			(xy 135.73887 -370.979192) (xy 135.729375 -370.985) (xy 135.708082 -370.991449) (xy 135.69696 -370.991892)
			(xy 135.501126 -370.991892) (xy 135.489016 -370.991367) (xy 135.465978 -370.98389) (xy 135.446379 -370.969661)
			(xy 135.432135 -370.950072) (xy 135.424642 -370.92704) (xy 135.424164 -370.91493) (xy 133.320028 -370.91493)
			(xy 133.319665 -370.927058) (xy 133.312161 -370.950123) (xy 133.297895 -370.969741) (xy 133.278266 -370.98399)
			(xy 133.255194 -370.991475) (xy 133.243066 -370.991892) (xy 133.048502 -370.991892) (xy 133.037378 -370.991456)
			(xy 133.016082 -370.985011) (xy 133.006592 -370.979192) (xy 132.711698 -370.78666) (xy 132.702311 -370.780957)
			(xy 132.681273 -370.774684) (xy 132.659319 -370.774684) (xy 132.638281 -370.780957) (xy 132.628894 -370.78666)
			(xy 132.33527 -370.979192) (xy 132.325775 -370.985) (xy 132.304482 -370.991449) (xy 132.29336 -370.991892)
			(xy 132.097526 -370.991892) (xy 132.085416 -370.991367) (xy 132.062378 -370.98389) (xy 132.042779 -370.969661)
			(xy 132.028535 -370.950072) (xy 132.021042 -370.92704) (xy 132.020564 -370.91493) (xy 126.512828 -370.91493)
			(xy 126.512465 -370.927058) (xy 126.504961 -370.950123) (xy 126.490695 -370.969741) (xy 126.471066 -370.98399)
			(xy 126.447994 -370.991475) (xy 126.435866 -370.991892) (xy 126.241302 -370.991892) (xy 126.230178 -370.991456)
			(xy 126.208882 -370.985011) (xy 126.199392 -370.979192) (xy 125.904498 -370.78666) (xy 125.895111 -370.780957)
			(xy 125.874073 -370.774684) (xy 125.852119 -370.774684) (xy 125.831081 -370.780957) (xy 125.821694 -370.78666)
			(xy 125.52807 -370.979192) (xy 125.518575 -370.985) (xy 125.497282 -370.991449) (xy 125.48616 -370.991892)
			(xy 125.290326 -370.991892) (xy 125.278216 -370.991367) (xy 125.255178 -370.98389) (xy 125.235579 -370.969661)
			(xy 125.221335 -370.950072) (xy 125.213842 -370.92704) (xy 125.213364 -370.91493) (xy 119.705628 -370.91493)
			(xy 119.705265 -370.927058) (xy 119.697761 -370.950123) (xy 119.683495 -370.969741) (xy 119.663866 -370.98399)
			(xy 119.640794 -370.991475) (xy 119.628666 -370.991892) (xy 119.434102 -370.991892) (xy 119.422978 -370.991456)
			(xy 119.401682 -370.985011) (xy 119.392192 -370.979192) (xy 119.097298 -370.78666) (xy 119.087911 -370.780957)
			(xy 119.066873 -370.774684) (xy 119.044919 -370.774684) (xy 119.023881 -370.780957) (xy 119.014494 -370.78666)
			(xy 118.72087 -370.979192) (xy 118.711375 -370.985) (xy 118.690082 -370.991449) (xy 118.67896 -370.991892)
			(xy 118.483126 -370.991892) (xy 118.471016 -370.991367) (xy 118.447978 -370.98389) (xy 118.428379 -370.969661)
			(xy 118.414135 -370.950072) (xy 118.406642 -370.92704) (xy 118.406164 -370.91493) (xy 112.898428 -370.91493)
			(xy 112.898065 -370.927058) (xy 112.890561 -370.950123) (xy 112.876295 -370.969741) (xy 112.856666 -370.98399)
			(xy 112.833594 -370.991475) (xy 112.821466 -370.991892) (xy 112.626902 -370.991892) (xy 112.615778 -370.991456)
			(xy 112.594482 -370.985011) (xy 112.584992 -370.979192) (xy 112.290098 -370.78666) (xy 112.280711 -370.780957)
			(xy 112.259673 -370.774684) (xy 112.237719 -370.774684) (xy 112.216681 -370.780957) (xy 112.207294 -370.78666)
			(xy 111.91367 -370.979192) (xy 111.904175 -370.985) (xy 111.882882 -370.991449) (xy 111.87176 -370.991892)
			(xy 111.675926 -370.991892) (xy 111.663816 -370.991367) (xy 111.640778 -370.98389) (xy 111.621179 -370.969661)
			(xy 111.606935 -370.950072) (xy 111.599442 -370.92704) (xy 111.598964 -370.91493) (xy 102.15118 -370.91493)
			(xy 102.150719 -370.927019) (xy 102.143256 -370.950017) (xy 102.129067 -370.969595) (xy 102.109534 -370.983845)
			(xy 102.08656 -370.99138) (xy 102.074472 -370.991892) (xy 101.879908 -370.991892) (xy 101.868785 -370.991453)
			(xy 101.847488 -370.98501) (xy 101.837998 -370.979192) (xy 101.543104 -370.78666) (xy 101.533717 -370.780957)
			(xy 101.512679 -370.774684) (xy 101.490725 -370.774684) (xy 101.469687 -370.780957) (xy 101.4603 -370.78666)
			(xy 101.166676 -370.979192) (xy 101.15718 -370.984998) (xy 101.135887 -370.991449) (xy 101.124766 -370.991892)
			(xy 100.928932 -370.991892) (xy 100.916849 -370.99146) (xy 100.893865 -370.983999) (xy 100.874313 -370.969799)
			(xy 100.860108 -370.950249) (xy 100.852643 -370.927267) (xy 100.852224 -370.915184) (xy 98.74757 -370.915184)
			(xy 98.747119 -370.927019) (xy 98.739656 -370.950017) (xy 98.725467 -370.969595) (xy 98.705934 -370.983845)
			(xy 98.68296 -370.99138) (xy 98.670872 -370.991892) (xy 98.476308 -370.991892) (xy 98.465185 -370.991453)
			(xy 98.443888 -370.98501) (xy 98.434398 -370.979192) (xy 98.139504 -370.78666) (xy 98.130117 -370.780957)
			(xy 98.109079 -370.774684) (xy 98.087125 -370.774684) (xy 98.066087 -370.780957) (xy 98.0567 -370.78666)
			(xy 97.763076 -370.979192) (xy 97.75358 -370.984998) (xy 97.732287 -370.991449) (xy 97.721166 -370.991892)
			(xy 97.525332 -370.991892) (xy 97.513249 -370.99146) (xy 97.490265 -370.983999) (xy 97.470713 -370.969799)
			(xy 97.456508 -370.950249) (xy 97.449043 -370.927267) (xy 97.448624 -370.915184) (xy 91.94037 -370.915184)
			(xy 91.939919 -370.927019) (xy 91.932456 -370.950017) (xy 91.918267 -370.969595) (xy 91.898734 -370.983845)
			(xy 91.87576 -370.99138) (xy 91.863672 -370.991892) (xy 91.669108 -370.991892) (xy 91.657985 -370.991453)
			(xy 91.636688 -370.98501) (xy 91.627198 -370.979192) (xy 91.332304 -370.78666) (xy 91.322917 -370.780957)
			(xy 91.301879 -370.774684) (xy 91.279925 -370.774684) (xy 91.258887 -370.780957) (xy 91.2495 -370.78666)
			(xy 90.955876 -370.979192) (xy 90.94638 -370.984998) (xy 90.925087 -370.991449) (xy 90.913966 -370.991892)
			(xy 90.718132 -370.991892) (xy 90.706049 -370.99146) (xy 90.683065 -370.983999) (xy 90.663513 -370.969799)
			(xy 90.649308 -370.950249) (xy 90.641843 -370.927267) (xy 90.641424 -370.915184) (xy 85.13317 -370.915184)
			(xy 85.132719 -370.927019) (xy 85.125256 -370.950017) (xy 85.111067 -370.969595) (xy 85.091534 -370.983845)
			(xy 85.06856 -370.99138) (xy 85.056472 -370.991892) (xy 84.861908 -370.991892) (xy 84.850785 -370.991453)
			(xy 84.829488 -370.98501) (xy 84.819998 -370.979192) (xy 84.525104 -370.78666) (xy 84.515717 -370.780957)
			(xy 84.494679 -370.774684) (xy 84.472725 -370.774684) (xy 84.451687 -370.780957) (xy 84.4423 -370.78666)
			(xy 84.148676 -370.979192) (xy 84.13918 -370.984998) (xy 84.117887 -370.991449) (xy 84.106766 -370.991892)
			(xy 83.910932 -370.991892) (xy 83.898849 -370.99146) (xy 83.875865 -370.983999) (xy 83.856313 -370.969799)
			(xy 83.842108 -370.950249) (xy 83.834643 -370.927267) (xy 83.834224 -370.915184) (xy 78.32597 -370.915184)
			(xy 78.325519 -370.927019) (xy 78.318056 -370.950017) (xy 78.303867 -370.969595) (xy 78.284334 -370.983845)
			(xy 78.26136 -370.99138) (xy 78.249272 -370.991892) (xy 78.054708 -370.991892) (xy 78.043585 -370.991453)
			(xy 78.022288 -370.98501) (xy 78.012798 -370.979192) (xy 77.717904 -370.78666) (xy 77.708517 -370.780957)
			(xy 77.687479 -370.774684) (xy 77.665525 -370.774684) (xy 77.644487 -370.780957) (xy 77.6351 -370.78666)
			(xy 77.341476 -370.979192) (xy 77.33198 -370.984998) (xy 77.310687 -370.991449) (xy 77.299566 -370.991892)
			(xy 77.103732 -370.991892) (xy 77.091649 -370.99146) (xy 77.068665 -370.983999) (xy 77.049113 -370.969799)
			(xy 77.034908 -370.950249) (xy 77.027443 -370.927267) (xy 77.027024 -370.915184) (xy 69.623423 -370.915184)
			(xy 69.623018 -370.927024) (xy 69.615549 -370.95003) (xy 69.60135 -370.969612) (xy 69.581804 -370.983861)
			(xy 69.558817 -370.991387) (xy 69.546724 -370.991892) (xy 69.35216 -370.991892) (xy 69.341035 -370.991472)
			(xy 69.319738 -370.985016) (xy 69.31025 -370.979192) (xy 69.015356 -370.78666) (xy 69.005969 -370.780957)
			(xy 68.984931 -370.774684) (xy 68.962977 -370.774684) (xy 68.941939 -370.780957) (xy 68.932552 -370.78666)
			(xy 68.638928 -370.979192) (xy 68.629422 -370.984979) (xy 68.608137 -370.991441) (xy 68.597018 -370.991892)
			(xy 68.401184 -370.991892) (xy 68.389107 -370.991449) (xy 68.366137 -370.98398) (xy 68.346599 -370.969779)
			(xy 68.332405 -370.950235) (xy 68.324946 -370.927261) (xy 68.324476 -370.915184) (xy 66.219823 -370.915184)
			(xy 66.219418 -370.927024) (xy 66.211949 -370.95003) (xy 66.19775 -370.969612) (xy 66.178204 -370.983861)
			(xy 66.155217 -370.991387) (xy 66.143124 -370.991892) (xy 65.94856 -370.991892) (xy 65.937435 -370.991472)
			(xy 65.916138 -370.985016) (xy 65.90665 -370.979192) (xy 65.611756 -370.78666) (xy 65.602369 -370.780957)
			(xy 65.581331 -370.774684) (xy 65.559377 -370.774684) (xy 65.538339 -370.780957) (xy 65.528952 -370.78666)
			(xy 65.235328 -370.979192) (xy 65.225822 -370.984979) (xy 65.204537 -370.991441) (xy 65.193418 -370.991892)
			(xy 64.997584 -370.991892) (xy 64.985507 -370.991449) (xy 64.962537 -370.98398) (xy 64.942999 -370.969779)
			(xy 64.928805 -370.950235) (xy 64.921346 -370.927261) (xy 64.920876 -370.915184) (xy 59.412623 -370.915184)
			(xy 59.412218 -370.927024) (xy 59.404749 -370.95003) (xy 59.39055 -370.969612) (xy 59.371004 -370.983861)
			(xy 59.348017 -370.991387) (xy 59.335924 -370.991892) (xy 59.14136 -370.991892) (xy 59.130235 -370.991472)
			(xy 59.108938 -370.985016) (xy 59.09945 -370.979192) (xy 58.804556 -370.78666) (xy 58.795169 -370.780957)
			(xy 58.774131 -370.774684) (xy 58.752177 -370.774684) (xy 58.731139 -370.780957) (xy 58.721752 -370.78666)
			(xy 58.428128 -370.979192) (xy 58.418622 -370.984979) (xy 58.397337 -370.991441) (xy 58.386218 -370.991892)
			(xy 58.190384 -370.991892) (xy 58.178307 -370.991449) (xy 58.155337 -370.98398) (xy 58.135799 -370.969779)
			(xy 58.121605 -370.950235) (xy 58.114146 -370.927261) (xy 58.113676 -370.915184) (xy 52.605423 -370.915184)
			(xy 52.605018 -370.927024) (xy 52.597549 -370.95003) (xy 52.58335 -370.969612) (xy 52.563804 -370.983861)
			(xy 52.540817 -370.991387) (xy 52.528724 -370.991892) (xy 52.33416 -370.991892) (xy 52.323035 -370.991472)
			(xy 52.301738 -370.985016) (xy 52.29225 -370.979192) (xy 51.997356 -370.78666) (xy 51.987969 -370.780957)
			(xy 51.966931 -370.774684) (xy 51.944977 -370.774684) (xy 51.923939 -370.780957) (xy 51.914552 -370.78666)
			(xy 51.620928 -370.979192) (xy 51.611422 -370.984979) (xy 51.590137 -370.991441) (xy 51.579018 -370.991892)
			(xy 51.383184 -370.991892) (xy 51.371107 -370.991449) (xy 51.348137 -370.98398) (xy 51.328599 -370.969779)
			(xy 51.314405 -370.950235) (xy 51.306946 -370.927261) (xy 51.306476 -370.915184) (xy 45.798223 -370.915184)
			(xy 45.797818 -370.927024) (xy 45.790349 -370.95003) (xy 45.77615 -370.969612) (xy 45.756604 -370.983861)
			(xy 45.733617 -370.991387) (xy 45.721524 -370.991892) (xy 45.52696 -370.991892) (xy 45.515835 -370.991472)
			(xy 45.494538 -370.985016) (xy 45.48505 -370.979192) (xy 45.190156 -370.78666) (xy 45.180769 -370.780957)
			(xy 45.159731 -370.774684) (xy 45.137777 -370.774684) (xy 45.116739 -370.780957) (xy 45.107352 -370.78666)
			(xy 44.813728 -370.979192) (xy 44.804222 -370.984979) (xy 44.782937 -370.991441) (xy 44.771818 -370.991892)
			(xy 44.575984 -370.991892) (xy 44.563907 -370.991449) (xy 44.540937 -370.98398) (xy 44.521399 -370.969779)
			(xy 44.507205 -370.950235) (xy 44.499746 -370.927261) (xy 44.499276 -370.915184) (xy 2.509012 -370.915184)
			(xy 2.509012 -371.526365) (xy 42.633954 -371.526365) (xy 42.633954 -371.471835) (xy 42.641714 -371.41786)
			(xy 42.657076 -371.365538) (xy 42.679727 -371.315935) (xy 42.709206 -371.270059) (xy 42.744914 -371.228846)
			(xy 42.786123 -371.193134) (xy 42.831994 -371.163649) (xy 42.881595 -371.140992) (xy 42.933915 -371.125624)
			(xy 42.987889 -371.117857) (xy 43.015154 -371.117368) (xy 43.878754 -371.117368) (xy 43.906029 -371.117768)
			(xy 43.960025 -371.125526) (xy 44.012368 -371.140889) (xy 44.061991 -371.163546) (xy 44.107884 -371.193035)
			(xy 44.149112 -371.228755) (xy 44.184838 -371.26998) (xy 44.214332 -371.315869) (xy 44.236995 -371.365489)
			(xy 44.252364 -371.41783) (xy 44.260128 -371.471825) (xy 44.260128 -371.526365) (xy 49.441154 -371.526365)
			(xy 49.441154 -371.471835) (xy 49.448914 -371.41786) (xy 49.464276 -371.365538) (xy 49.486927 -371.315935)
			(xy 49.516406 -371.270059) (xy 49.552114 -371.228846) (xy 49.593323 -371.193134) (xy 49.639194 -371.163649)
			(xy 49.688795 -371.140992) (xy 49.741115 -371.125624) (xy 49.795089 -371.117857) (xy 49.822354 -371.117368)
			(xy 50.685954 -371.117368) (xy 50.713229 -371.117768) (xy 50.767225 -371.125526) (xy 50.819568 -371.140889)
			(xy 50.869191 -371.163546) (xy 50.915084 -371.193035) (xy 50.956312 -371.228755) (xy 50.992038 -371.26998)
			(xy 51.021532 -371.315869) (xy 51.044195 -371.365489) (xy 51.059564 -371.41783) (xy 51.067328 -371.471825)
			(xy 51.067328 -371.526365) (xy 56.248354 -371.526365) (xy 56.248354 -371.471835) (xy 56.256114 -371.41786)
			(xy 56.271476 -371.365538) (xy 56.294127 -371.315935) (xy 56.323606 -371.270059) (xy 56.359314 -371.228846)
			(xy 56.400523 -371.193134) (xy 56.446394 -371.163649) (xy 56.495995 -371.140992) (xy 56.548315 -371.125624)
			(xy 56.602289 -371.117857) (xy 56.629554 -371.117368) (xy 57.493154 -371.117368) (xy 57.520429 -371.117768)
			(xy 57.574425 -371.125526) (xy 57.626768 -371.140889) (xy 57.676391 -371.163546) (xy 57.722284 -371.193035)
			(xy 57.763512 -371.228755) (xy 57.799238 -371.26998) (xy 57.828732 -371.315869) (xy 57.851395 -371.365489)
			(xy 57.866764 -371.41783) (xy 57.874528 -371.471825) (xy 57.874528 -371.526365) (xy 63.055554 -371.526365)
			(xy 63.055554 -371.471835) (xy 63.063314 -371.41786) (xy 63.078676 -371.365538) (xy 63.101327 -371.315935)
			(xy 63.130806 -371.270059) (xy 63.166514 -371.228846) (xy 63.207723 -371.193134) (xy 63.253594 -371.163649)
			(xy 63.303195 -371.140992) (xy 63.355515 -371.125624) (xy 63.409489 -371.117857) (xy 63.436754 -371.117368)
			(xy 64.300354 -371.117368) (xy 64.327629 -371.117768) (xy 64.381625 -371.125526) (xy 64.433968 -371.140889)
			(xy 64.483591 -371.163546) (xy 64.529484 -371.193035) (xy 64.570712 -371.228755) (xy 64.606438 -371.26998)
			(xy 64.635932 -371.315869) (xy 64.658595 -371.365489) (xy 64.673964 -371.41783) (xy 64.681728 -371.471825)
			(xy 64.681728 -371.526369) (xy 75.161631 -371.526369) (xy 75.161631 -371.471831) (xy 75.169393 -371.417848)
			(xy 75.184758 -371.36552) (xy 75.207414 -371.31591) (xy 75.2369 -371.27003) (xy 75.272614 -371.228813)
			(xy 75.313832 -371.193098) (xy 75.359712 -371.163613) (xy 75.409321 -371.140957) (xy 75.46165 -371.125593)
			(xy 75.515633 -371.117831) (xy 75.542902 -371.117368) (xy 76.406502 -371.117368) (xy 76.433773 -371.117795)
			(xy 76.487761 -371.125557) (xy 76.540094 -371.140924) (xy 76.589708 -371.163582) (xy 76.635593 -371.19307)
			(xy 76.676813 -371.228788) (xy 76.712531 -371.270009) (xy 76.742019 -371.315893) (xy 76.764677 -371.365507)
			(xy 76.780043 -371.417841) (xy 76.787806 -371.471829) (xy 76.787806 -371.526369) (xy 81.968831 -371.526369)
			(xy 81.968831 -371.471831) (xy 81.976593 -371.417848) (xy 81.991958 -371.36552) (xy 82.014614 -371.31591)
			(xy 82.0441 -371.27003) (xy 82.079814 -371.228813) (xy 82.121032 -371.193098) (xy 82.166912 -371.163613)
			(xy 82.216521 -371.140957) (xy 82.26885 -371.125593) (xy 82.322833 -371.117831) (xy 82.350102 -371.117368)
			(xy 83.213702 -371.117368) (xy 83.240973 -371.117795) (xy 83.294961 -371.125557) (xy 83.347294 -371.140924)
			(xy 83.396908 -371.163582) (xy 83.442793 -371.19307) (xy 83.484013 -371.228788) (xy 83.519731 -371.270009)
			(xy 83.549219 -371.315893) (xy 83.571877 -371.365507) (xy 83.587243 -371.417841) (xy 83.595006 -371.471829)
			(xy 83.595006 -371.526369) (xy 88.776031 -371.526369) (xy 88.776031 -371.471831) (xy 88.783793 -371.417848)
			(xy 88.799158 -371.36552) (xy 88.821814 -371.31591) (xy 88.8513 -371.27003) (xy 88.887014 -371.228813)
			(xy 88.928232 -371.193098) (xy 88.974112 -371.163613) (xy 89.023721 -371.140957) (xy 89.07605 -371.125593)
			(xy 89.130033 -371.117831) (xy 89.157302 -371.117368) (xy 90.020902 -371.117368) (xy 90.048173 -371.117795)
			(xy 90.102161 -371.125557) (xy 90.154494 -371.140924) (xy 90.204108 -371.163582) (xy 90.249993 -371.19307)
			(xy 90.291213 -371.228788) (xy 90.326931 -371.270009) (xy 90.356419 -371.315893) (xy 90.379077 -371.365507)
			(xy 90.394443 -371.417841) (xy 90.402206 -371.471829) (xy 90.402206 -371.526369) (xy 95.583231 -371.526369)
			(xy 95.583231 -371.471831) (xy 95.590993 -371.417848) (xy 95.606358 -371.36552) (xy 95.629014 -371.31591)
			(xy 95.6585 -371.27003) (xy 95.694214 -371.228813) (xy 95.735432 -371.193098) (xy 95.781312 -371.163613)
			(xy 95.830921 -371.140957) (xy 95.88325 -371.125593) (xy 95.937233 -371.117831) (xy 95.964502 -371.117368)
			(xy 96.828102 -371.117368) (xy 96.855373 -371.117795) (xy 96.909361 -371.125557) (xy 96.961694 -371.140924)
			(xy 97.011308 -371.163582) (xy 97.057193 -371.19307) (xy 97.098413 -371.228788) (xy 97.134131 -371.270009)
			(xy 97.163619 -371.315893) (xy 97.186277 -371.365507) (xy 97.201643 -371.417841) (xy 97.209406 -371.471829)
			(xy 97.209406 -371.526367) (xy 109.733854 -371.526367) (xy 109.733854 -371.471833) (xy 109.741615 -371.417854)
			(xy 109.756979 -371.365529) (xy 109.779633 -371.315923) (xy 109.809117 -371.270046) (xy 109.844829 -371.228831)
			(xy 109.886042 -371.193119) (xy 109.931919 -371.163635) (xy 109.981525 -371.140981) (xy 110.03385 -371.125616)
			(xy 110.087829 -371.117855) (xy 110.115096 -371.117368) (xy 110.978696 -371.117368) (xy 111.005969 -371.117771)
			(xy 111.059961 -371.125534) (xy 111.112298 -371.140901) (xy 111.161916 -371.16356) (xy 111.207803 -371.19305)
			(xy 111.249027 -371.22877) (xy 111.284748 -371.269993) (xy 111.314238 -371.315881) (xy 111.336898 -371.365498)
			(xy 111.352266 -371.417835) (xy 111.360028 -371.471827) (xy 111.360028 -371.526367) (xy 116.541054 -371.526367)
			(xy 116.541054 -371.471833) (xy 116.548815 -371.417854) (xy 116.564179 -371.365529) (xy 116.586833 -371.315923)
			(xy 116.616317 -371.270046) (xy 116.652029 -371.228831) (xy 116.693242 -371.193119) (xy 116.739119 -371.163635)
			(xy 116.788725 -371.140981) (xy 116.84105 -371.125616) (xy 116.895029 -371.117855) (xy 116.922296 -371.117368)
			(xy 117.785896 -371.117368) (xy 117.813169 -371.117771) (xy 117.867161 -371.125534) (xy 117.919498 -371.140901)
			(xy 117.969116 -371.16356) (xy 118.015003 -371.19305) (xy 118.056227 -371.22877) (xy 118.091948 -371.269993)
			(xy 118.121438 -371.315881) (xy 118.144098 -371.365498) (xy 118.159466 -371.417835) (xy 118.167228 -371.471827)
			(xy 118.167228 -371.526367) (xy 123.348254 -371.526367) (xy 123.348254 -371.471833) (xy 123.356015 -371.417854)
			(xy 123.371379 -371.365529) (xy 123.394033 -371.315923) (xy 123.423517 -371.270046) (xy 123.459229 -371.228831)
			(xy 123.500442 -371.193119) (xy 123.546319 -371.163635) (xy 123.595925 -371.140981) (xy 123.64825 -371.125616)
			(xy 123.702229 -371.117855) (xy 123.729496 -371.117368) (xy 124.593096 -371.117368) (xy 124.620369 -371.117771)
			(xy 124.674361 -371.125534) (xy 124.726698 -371.140901) (xy 124.776316 -371.16356) (xy 124.822203 -371.19305)
			(xy 124.863427 -371.22877) (xy 124.899148 -371.269993) (xy 124.928638 -371.315881) (xy 124.951298 -371.365498)
			(xy 124.966666 -371.417835) (xy 124.974428 -371.471827) (xy 124.974428 -371.526367) (xy 130.155454 -371.526367)
			(xy 130.155454 -371.471833) (xy 130.163215 -371.417854) (xy 130.178579 -371.365529) (xy 130.201233 -371.315923)
			(xy 130.230717 -371.270046) (xy 130.266429 -371.228831) (xy 130.307642 -371.193119) (xy 130.353519 -371.163635)
			(xy 130.403125 -371.140981) (xy 130.45545 -371.125616) (xy 130.509429 -371.117855) (xy 130.536696 -371.117368)
			(xy 131.400296 -371.117368) (xy 131.427569 -371.117771) (xy 131.481561 -371.125534) (xy 131.533898 -371.140901)
			(xy 131.583516 -371.16356) (xy 131.629403 -371.19305) (xy 131.670627 -371.22877) (xy 131.706348 -371.269993)
			(xy 131.735838 -371.315881) (xy 131.758498 -371.365498) (xy 131.773866 -371.417835) (xy 131.781628 -371.471827)
			(xy 131.781628 -371.526371) (xy 142.261532 -371.526371) (xy 142.261532 -371.471829) (xy 142.269294 -371.417843)
			(xy 142.284661 -371.365511) (xy 142.307321 -371.315898) (xy 142.33681 -371.270016) (xy 142.372529 -371.228798)
			(xy 142.413751 -371.193084) (xy 142.459637 -371.163599) (xy 142.509252 -371.140946) (xy 142.561586 -371.125585)
			(xy 142.615573 -371.117828) (xy 142.642844 -371.117368) (xy 143.506444 -371.117368) (xy 143.533713 -371.117798)
			(xy 143.587697 -371.125565) (xy 143.640025 -371.140935) (xy 143.689633 -371.163596) (xy 143.735512 -371.193085)
			(xy 143.776728 -371.228803) (xy 143.812441 -371.270023) (xy 143.841925 -371.315905) (xy 143.86458 -371.365516)
			(xy 143.879944 -371.417847) (xy 143.887706 -371.47183) (xy 143.887706 -371.52637) (xy 143.887706 -371.526371)
			(xy 149.068732 -371.526371) (xy 149.068732 -371.471829) (xy 149.076494 -371.417843) (xy 149.091861 -371.365511)
			(xy 149.114521 -371.315898) (xy 149.14401 -371.270016) (xy 149.179729 -371.228798) (xy 149.220951 -371.193084)
			(xy 149.266837 -371.163599) (xy 149.316452 -371.140946) (xy 149.368786 -371.125585) (xy 149.422773 -371.117828)
			(xy 149.450044 -371.117368) (xy 150.313644 -371.117368) (xy 150.340913 -371.117798) (xy 150.394897 -371.125565)
			(xy 150.447225 -371.140935) (xy 150.496833 -371.163596) (xy 150.542712 -371.193085) (xy 150.583928 -371.228803)
			(xy 150.619641 -371.270023) (xy 150.649125 -371.315905) (xy 150.67178 -371.365516) (xy 150.687144 -371.417847)
			(xy 150.694906 -371.47183) (xy 150.694906 -371.52637) (xy 150.694906 -371.526371) (xy 155.875932 -371.526371)
			(xy 155.875932 -371.471829) (xy 155.883694 -371.417843) (xy 155.899061 -371.365511) (xy 155.921721 -371.315898)
			(xy 155.95121 -371.270016) (xy 155.986929 -371.228798) (xy 156.028151 -371.193084) (xy 156.074037 -371.163599)
			(xy 156.123652 -371.140946) (xy 156.175986 -371.125585) (xy 156.229973 -371.117828) (xy 156.257244 -371.117368)
			(xy 157.120844 -371.117368) (xy 157.148113 -371.117798) (xy 157.202097 -371.125565) (xy 157.254425 -371.140935)
			(xy 157.304033 -371.163596) (xy 157.349912 -371.193085) (xy 157.391128 -371.228803) (xy 157.426841 -371.270023)
			(xy 157.456325 -371.315905) (xy 157.47898 -371.365516) (xy 157.494344 -371.417847) (xy 157.502106 -371.47183)
			(xy 157.502106 -371.52637) (xy 157.502106 -371.526371) (xy 162.683132 -371.526371) (xy 162.683132 -371.471829)
			(xy 162.690894 -371.417843) (xy 162.706261 -371.365511) (xy 162.728921 -371.315898) (xy 162.75841 -371.270016)
			(xy 162.794129 -371.228798) (xy 162.835351 -371.193084) (xy 162.881237 -371.163599) (xy 162.930852 -371.140946)
			(xy 162.983186 -371.125585) (xy 163.037173 -371.117828) (xy 163.064444 -371.117368) (xy 163.928044 -371.117368)
			(xy 163.955313 -371.117798) (xy 164.009297 -371.125565) (xy 164.061625 -371.140935) (xy 164.111233 -371.163596)
			(xy 164.157112 -371.193085) (xy 164.198328 -371.228803) (xy 164.234041 -371.270023) (xy 164.263525 -371.315905)
			(xy 164.28618 -371.365516) (xy 164.301544 -371.417847) (xy 164.309306 -371.47183) (xy 164.309306 -371.52637)
			(xy 164.301544 -371.580353) (xy 164.28618 -371.632684) (xy 164.263525 -371.682295) (xy 164.234041 -371.728177)
			(xy 164.198328 -371.769397) (xy 164.157112 -371.805115) (xy 164.111233 -371.834604) (xy 164.061625 -371.857265)
			(xy 164.009297 -371.872635) (xy 163.955313 -371.880402) (xy 163.928044 -371.880892) (xy 163.064444 -371.880892)
			(xy 163.037173 -371.880372) (xy 162.983186 -371.872615) (xy 162.930852 -371.857254) (xy 162.881237 -371.834601)
			(xy 162.835351 -371.805116) (xy 162.794129 -371.769402) (xy 162.75841 -371.728184) (xy 162.728921 -371.682302)
			(xy 162.706261 -371.632689) (xy 162.690894 -371.580357) (xy 162.683132 -371.526371) (xy 157.502106 -371.526371)
			(xy 157.494344 -371.580353) (xy 157.47898 -371.632684) (xy 157.456325 -371.682295) (xy 157.426841 -371.728177)
			(xy 157.391128 -371.769397) (xy 157.349912 -371.805115) (xy 157.304033 -371.834604) (xy 157.254425 -371.857265)
			(xy 157.202097 -371.872635) (xy 157.148113 -371.880402) (xy 157.120844 -371.880892) (xy 156.257244 -371.880892)
			(xy 156.229973 -371.880372) (xy 156.175986 -371.872615) (xy 156.123652 -371.857254) (xy 156.074037 -371.834601)
			(xy 156.028151 -371.805116) (xy 155.986929 -371.769402) (xy 155.95121 -371.728184) (xy 155.921721 -371.682302)
			(xy 155.899061 -371.632689) (xy 155.883694 -371.580357) (xy 155.875932 -371.526371) (xy 150.694906 -371.526371)
			(xy 150.687144 -371.580353) (xy 150.67178 -371.632684) (xy 150.649125 -371.682295) (xy 150.619641 -371.728177)
			(xy 150.583928 -371.769397) (xy 150.542712 -371.805115) (xy 150.496833 -371.834604) (xy 150.447225 -371.857265)
			(xy 150.394897 -371.872635) (xy 150.340913 -371.880402) (xy 150.313644 -371.880892) (xy 149.450044 -371.880892)
			(xy 149.422773 -371.880372) (xy 149.368786 -371.872615) (xy 149.316452 -371.857254) (xy 149.266837 -371.834601)
			(xy 149.220951 -371.805116) (xy 149.179729 -371.769402) (xy 149.14401 -371.728184) (xy 149.114521 -371.682302)
			(xy 149.091861 -371.632689) (xy 149.076494 -371.580357) (xy 149.068732 -371.526371) (xy 143.887706 -371.526371)
			(xy 143.879944 -371.580353) (xy 143.86458 -371.632684) (xy 143.841925 -371.682295) (xy 143.812441 -371.728177)
			(xy 143.776728 -371.769397) (xy 143.735512 -371.805115) (xy 143.689633 -371.834604) (xy 143.640025 -371.857265)
			(xy 143.587697 -371.872635) (xy 143.533713 -371.880402) (xy 143.506444 -371.880892) (xy 142.642844 -371.880892)
			(xy 142.615573 -371.880372) (xy 142.561586 -371.872615) (xy 142.509252 -371.857254) (xy 142.459637 -371.834601)
			(xy 142.413751 -371.805116) (xy 142.372529 -371.769402) (xy 142.33681 -371.728184) (xy 142.307321 -371.682302)
			(xy 142.284661 -371.632689) (xy 142.269294 -371.580357) (xy 142.261532 -371.526371) (xy 131.781628 -371.526371)
			(xy 131.781628 -371.526373) (xy 131.773866 -371.580365) (xy 131.758498 -371.632702) (xy 131.735838 -371.682319)
			(xy 131.706348 -371.728207) (xy 131.670627 -371.76943) (xy 131.629403 -371.80515) (xy 131.583516 -371.83464)
			(xy 131.533898 -371.857299) (xy 131.481561 -371.872666) (xy 131.427569 -371.880429) (xy 131.400296 -371.880892)
			(xy 130.536696 -371.880892) (xy 130.509429 -371.880345) (xy 130.45545 -371.872584) (xy 130.403125 -371.857219)
			(xy 130.353519 -371.834565) (xy 130.307642 -371.805081) (xy 130.266429 -371.769369) (xy 130.230717 -371.728154)
			(xy 130.201233 -371.682277) (xy 130.178579 -371.632671) (xy 130.163215 -371.580346) (xy 130.155454 -371.526367)
			(xy 124.974428 -371.526367) (xy 124.974428 -371.526373) (xy 124.966666 -371.580365) (xy 124.951298 -371.632702)
			(xy 124.928638 -371.682319) (xy 124.899148 -371.728207) (xy 124.863427 -371.76943) (xy 124.822203 -371.80515)
			(xy 124.776316 -371.83464) (xy 124.726698 -371.857299) (xy 124.674361 -371.872666) (xy 124.620369 -371.880429)
			(xy 124.593096 -371.880892) (xy 123.729496 -371.880892) (xy 123.702229 -371.880345) (xy 123.64825 -371.872584)
			(xy 123.595925 -371.857219) (xy 123.546319 -371.834565) (xy 123.500442 -371.805081) (xy 123.459229 -371.769369)
			(xy 123.423517 -371.728154) (xy 123.394033 -371.682277) (xy 123.371379 -371.632671) (xy 123.356015 -371.580346)
			(xy 123.348254 -371.526367) (xy 118.167228 -371.526367) (xy 118.167228 -371.526373) (xy 118.159466 -371.580365)
			(xy 118.144098 -371.632702) (xy 118.121438 -371.682319) (xy 118.091948 -371.728207) (xy 118.056227 -371.76943)
			(xy 118.015003 -371.80515) (xy 117.969116 -371.83464) (xy 117.919498 -371.857299) (xy 117.867161 -371.872666)
			(xy 117.813169 -371.880429) (xy 117.785896 -371.880892) (xy 116.922296 -371.880892) (xy 116.895029 -371.880345)
			(xy 116.84105 -371.872584) (xy 116.788725 -371.857219) (xy 116.739119 -371.834565) (xy 116.693242 -371.805081)
			(xy 116.652029 -371.769369) (xy 116.616317 -371.728154) (xy 116.586833 -371.682277) (xy 116.564179 -371.632671)
			(xy 116.548815 -371.580346) (xy 116.541054 -371.526367) (xy 111.360028 -371.526367) (xy 111.360028 -371.526373)
			(xy 111.352266 -371.580365) (xy 111.336898 -371.632702) (xy 111.314238 -371.682319) (xy 111.284748 -371.728207)
			(xy 111.249027 -371.76943) (xy 111.207803 -371.80515) (xy 111.161916 -371.83464) (xy 111.112298 -371.857299)
			(xy 111.059961 -371.872666) (xy 111.005969 -371.880429) (xy 110.978696 -371.880892) (xy 110.115096 -371.880892)
			(xy 110.087829 -371.880345) (xy 110.03385 -371.872584) (xy 109.981525 -371.857219) (xy 109.931919 -371.834565)
			(xy 109.886042 -371.805081) (xy 109.844829 -371.769369) (xy 109.809117 -371.728154) (xy 109.779633 -371.682277)
			(xy 109.756979 -371.632671) (xy 109.741615 -371.580346) (xy 109.733854 -371.526367) (xy 97.209406 -371.526367)
			(xy 97.209406 -371.526371) (xy 97.201643 -371.580359) (xy 97.186277 -371.632693) (xy 97.163619 -371.682307)
			(xy 97.134131 -371.728191) (xy 97.098413 -371.769412) (xy 97.057193 -371.80513) (xy 97.011308 -371.834618)
			(xy 96.961694 -371.857276) (xy 96.909361 -371.872643) (xy 96.855373 -371.880405) (xy 96.828102 -371.880892)
			(xy 95.964502 -371.880892) (xy 95.937233 -371.880369) (xy 95.88325 -371.872607) (xy 95.830921 -371.857243)
			(xy 95.781312 -371.834587) (xy 95.735432 -371.805102) (xy 95.694214 -371.769387) (xy 95.6585 -371.72817)
			(xy 95.629014 -371.68229) (xy 95.606358 -371.63268) (xy 95.590993 -371.580352) (xy 95.583231 -371.526369)
			(xy 90.402206 -371.526369) (xy 90.402206 -371.526371) (xy 90.394443 -371.580359) (xy 90.379077 -371.632693)
			(xy 90.356419 -371.682307) (xy 90.326931 -371.728191) (xy 90.291213 -371.769412) (xy 90.249993 -371.80513)
			(xy 90.204108 -371.834618) (xy 90.154494 -371.857276) (xy 90.102161 -371.872643) (xy 90.048173 -371.880405)
			(xy 90.020902 -371.880892) (xy 89.157302 -371.880892) (xy 89.130033 -371.880369) (xy 89.07605 -371.872607)
			(xy 89.023721 -371.857243) (xy 88.974112 -371.834587) (xy 88.928232 -371.805102) (xy 88.887014 -371.769387)
			(xy 88.8513 -371.72817) (xy 88.821814 -371.68229) (xy 88.799158 -371.63268) (xy 88.783793 -371.580352)
			(xy 88.776031 -371.526369) (xy 83.595006 -371.526369) (xy 83.595006 -371.526371) (xy 83.587243 -371.580359)
			(xy 83.571877 -371.632693) (xy 83.549219 -371.682307) (xy 83.519731 -371.728191) (xy 83.484013 -371.769412)
			(xy 83.442793 -371.80513) (xy 83.396908 -371.834618) (xy 83.347294 -371.857276) (xy 83.294961 -371.872643)
			(xy 83.240973 -371.880405) (xy 83.213702 -371.880892) (xy 82.350102 -371.880892) (xy 82.322833 -371.880369)
			(xy 82.26885 -371.872607) (xy 82.216521 -371.857243) (xy 82.166912 -371.834587) (xy 82.121032 -371.805102)
			(xy 82.079814 -371.769387) (xy 82.0441 -371.72817) (xy 82.014614 -371.68229) (xy 81.991958 -371.63268)
			(xy 81.976593 -371.580352) (xy 81.968831 -371.526369) (xy 76.787806 -371.526369) (xy 76.787806 -371.526371)
			(xy 76.780043 -371.580359) (xy 76.764677 -371.632693) (xy 76.742019 -371.682307) (xy 76.712531 -371.728191)
			(xy 76.676813 -371.769412) (xy 76.635593 -371.80513) (xy 76.589708 -371.834618) (xy 76.540094 -371.857276)
			(xy 76.487761 -371.872643) (xy 76.433773 -371.880405) (xy 76.406502 -371.880892) (xy 75.542902 -371.880892)
			(xy 75.515633 -371.880369) (xy 75.46165 -371.872607) (xy 75.409321 -371.857243) (xy 75.359712 -371.834587)
			(xy 75.313832 -371.805102) (xy 75.272614 -371.769387) (xy 75.2369 -371.72817) (xy 75.207414 -371.68229)
			(xy 75.184758 -371.63268) (xy 75.169393 -371.580352) (xy 75.161631 -371.526369) (xy 64.681728 -371.526369)
			(xy 64.681728 -371.526375) (xy 64.673964 -371.58037) (xy 64.658595 -371.632711) (xy 64.635932 -371.682331)
			(xy 64.606438 -371.72822) (xy 64.570712 -371.769445) (xy 64.529484 -371.805165) (xy 64.483591 -371.834654)
			(xy 64.433968 -371.857311) (xy 64.381625 -371.872674) (xy 64.327629 -371.880432) (xy 64.300354 -371.880892)
			(xy 63.436754 -371.880892) (xy 63.409489 -371.880343) (xy 63.355515 -371.872576) (xy 63.303195 -371.857208)
			(xy 63.253594 -371.834551) (xy 63.207723 -371.805066) (xy 63.166514 -371.769354) (xy 63.130806 -371.728141)
			(xy 63.101327 -371.682265) (xy 63.078676 -371.632662) (xy 63.063314 -371.58034) (xy 63.055554 -371.526365)
			(xy 57.874528 -371.526365) (xy 57.874528 -371.526375) (xy 57.866764 -371.58037) (xy 57.851395 -371.632711)
			(xy 57.828732 -371.682331) (xy 57.799238 -371.72822) (xy 57.763512 -371.769445) (xy 57.722284 -371.805165)
			(xy 57.676391 -371.834654) (xy 57.626768 -371.857311) (xy 57.574425 -371.872674) (xy 57.520429 -371.880432)
			(xy 57.493154 -371.880892) (xy 56.629554 -371.880892) (xy 56.602289 -371.880343) (xy 56.548315 -371.872576)
			(xy 56.495995 -371.857208) (xy 56.446394 -371.834551) (xy 56.400523 -371.805066) (xy 56.359314 -371.769354)
			(xy 56.323606 -371.728141) (xy 56.294127 -371.682265) (xy 56.271476 -371.632662) (xy 56.256114 -371.58034)
			(xy 56.248354 -371.526365) (xy 51.067328 -371.526365) (xy 51.067328 -371.526375) (xy 51.059564 -371.58037)
			(xy 51.044195 -371.632711) (xy 51.021532 -371.682331) (xy 50.992038 -371.72822) (xy 50.956312 -371.769445)
			(xy 50.915084 -371.805165) (xy 50.869191 -371.834654) (xy 50.819568 -371.857311) (xy 50.767225 -371.872674)
			(xy 50.713229 -371.880432) (xy 50.685954 -371.880892) (xy 49.822354 -371.880892) (xy 49.795089 -371.880343)
			(xy 49.741115 -371.872576) (xy 49.688795 -371.857208) (xy 49.639194 -371.834551) (xy 49.593323 -371.805066)
			(xy 49.552114 -371.769354) (xy 49.516406 -371.728141) (xy 49.486927 -371.682265) (xy 49.464276 -371.632662)
			(xy 49.448914 -371.58034) (xy 49.441154 -371.526365) (xy 44.260128 -371.526365) (xy 44.260128 -371.526375)
			(xy 44.252364 -371.58037) (xy 44.236995 -371.632711) (xy 44.214332 -371.682331) (xy 44.184838 -371.72822)
			(xy 44.149112 -371.769445) (xy 44.107884 -371.805165) (xy 44.061991 -371.834654) (xy 44.012368 -371.857311)
			(xy 43.960025 -371.872674) (xy 43.906029 -371.880432) (xy 43.878754 -371.880892) (xy 43.015154 -371.880892)
			(xy 42.987889 -371.880343) (xy 42.933915 -371.872576) (xy 42.881595 -371.857208) (xy 42.831994 -371.834551)
			(xy 42.786123 -371.805066) (xy 42.744914 -371.769354) (xy 42.709206 -371.728141) (xy 42.679727 -371.682265)
			(xy 42.657076 -371.632662) (xy 42.641714 -371.58034) (xy 42.633954 -371.526365) (xy 2.509012 -371.526365)
			(xy 2.509012 -376.489976) (xy 31.068784 -376.489976) (xy 31.072756 -376.311733) (xy 31.084664 -376.133844)
			(xy 31.104485 -375.956662) (xy 31.132179 -375.780538) (xy 31.167691 -375.605823) (xy 31.210951 -375.432864)
			(xy 31.261873 -375.262003) (xy 31.320356 -375.093581) (xy 31.386283 -374.927931) (xy 31.459524 -374.765382)
			(xy 31.539934 -374.606257) (xy 31.627352 -374.450872) (xy 31.721605 -374.299536) (xy 31.822506 -374.152548)
			(xy 31.929855 -374.010201) (xy 32.043438 -373.872778) (xy 32.163031 -373.740551) (xy 32.288395 -373.613782)
			(xy 32.419282 -373.492724) (xy 32.555431 -373.377617) (xy 32.696573 -373.268689) (xy 32.842428 -373.166157)
			(xy 32.992705 -373.070223) (xy 33.147106 -372.98108) (xy 33.305325 -372.898903) (xy 33.467048 -372.823855)
			(xy 33.631953 -372.756087) (xy 33.799714 -372.695731) (xy 33.969997 -372.642909) (xy 34.142464 -372.597725)
			(xy 34.316772 -372.560268) (xy 34.492576 -372.530614) (xy 34.669526 -372.508821) (xy 34.847272 -372.494931)
			(xy 35.025459 -372.488974) (xy 35.203736 -372.49096) (xy 35.381747 -372.500886) (xy 35.559139 -372.518732)
			(xy 35.735559 -372.544462) (xy 35.910659 -372.578026) (xy 36.08409 -372.619356) (xy 36.255507 -372.668372)
			(xy 36.42457 -372.724974) (xy 36.590945 -372.789052) (xy 36.754299 -372.860478) (xy 36.91431 -372.93911)
			(xy 37.070659 -373.024791) (xy 37.223036 -373.117353) (xy 37.371139 -373.21661) (xy 37.514673 -373.322367)
			(xy 37.584749 -373.378984) (xy 42.797476 -373.378984) (xy 42.797476 -372.69293) (xy 42.797934 -372.680838)
			(xy 42.805386 -372.657833) (xy 42.819574 -372.638249) (xy 42.839112 -372.623999) (xy 42.862094 -372.616473)
			(xy 42.874184 -372.615968) (xy 43.068748 -372.615968) (xy 43.079874 -372.616375) (xy 43.101171 -372.622839)
			(xy 43.110658 -372.628668) (xy 43.404282 -372.8212) (xy 43.413663 -372.826908) (xy 43.434677 -372.833243)
			(xy 43.456625 -372.833316) (xy 43.47768 -372.827119) (xy 43.487086 -372.821454) (xy 43.78325 -372.628668)
			(xy 43.792738 -372.622849) (xy 43.814037 -372.616407) (xy 43.82516 -372.615968) (xy 44.019724 -372.615968)
			(xy 44.031797 -372.616444) (xy 44.054761 -372.62391) (xy 44.074296 -372.638104) (xy 44.08849 -372.657639)
			(xy 44.095956 -372.680603) (xy 44.096432 -372.692676) (xy 44.096432 -373.37873) (xy 44.096423 -373.378984)
			(xy 49.604676 -373.378984) (xy 49.604676 -372.69293) (xy 49.605134 -372.680838) (xy 49.612586 -372.657833)
			(xy 49.626774 -372.638249) (xy 49.646312 -372.623999) (xy 49.669294 -372.616473) (xy 49.681384 -372.615968)
			(xy 49.875948 -372.615968) (xy 49.887074 -372.616375) (xy 49.908371 -372.622839) (xy 49.917858 -372.628668)
			(xy 50.211482 -372.8212) (xy 50.220863 -372.826908) (xy 50.241877 -372.833243) (xy 50.263825 -372.833316)
			(xy 50.28488 -372.827119) (xy 50.294286 -372.821454) (xy 50.59045 -372.628668) (xy 50.599938 -372.622849)
			(xy 50.621237 -372.616407) (xy 50.63236 -372.615968) (xy 50.826924 -372.615968) (xy 50.838997 -372.616444)
			(xy 50.861961 -372.62391) (xy 50.881496 -372.638104) (xy 50.89569 -372.657639) (xy 50.903156 -372.680603)
			(xy 50.903632 -372.692676) (xy 50.903632 -373.37873) (xy 50.903623 -373.378984) (xy 56.411876 -373.378984)
			(xy 56.411876 -372.69293) (xy 56.412334 -372.680838) (xy 56.419786 -372.657833) (xy 56.433974 -372.638249)
			(xy 56.453512 -372.623999) (xy 56.476494 -372.616473) (xy 56.488584 -372.615968) (xy 56.683148 -372.615968)
			(xy 56.694274 -372.616375) (xy 56.715571 -372.622839) (xy 56.725058 -372.628668) (xy 57.018682 -372.8212)
			(xy 57.028063 -372.826908) (xy 57.049077 -372.833243) (xy 57.071025 -372.833316) (xy 57.09208 -372.827119)
			(xy 57.101486 -372.821454) (xy 57.39765 -372.628668) (xy 57.407138 -372.622849) (xy 57.428437 -372.616407)
			(xy 57.43956 -372.615968) (xy 57.634124 -372.615968) (xy 57.646197 -372.616444) (xy 57.669161 -372.62391)
			(xy 57.688696 -372.638104) (xy 57.70289 -372.657639) (xy 57.710356 -372.680603) (xy 57.710832 -372.692676)
			(xy 57.710832 -373.37873) (xy 57.710823 -373.378984) (xy 63.219076 -373.378984) (xy 63.219076 -372.69293)
			(xy 63.219534 -372.680838) (xy 63.226986 -372.657833) (xy 63.241174 -372.638249) (xy 63.260712 -372.623999)
			(xy 63.283694 -372.616473) (xy 63.295784 -372.615968) (xy 63.490348 -372.615968) (xy 63.501474 -372.616375)
			(xy 63.522771 -372.622839) (xy 63.532258 -372.628668) (xy 63.825882 -372.8212) (xy 63.835263 -372.826908)
			(xy 63.856277 -372.833243) (xy 63.878225 -372.833316) (xy 63.89928 -372.827119) (xy 63.908686 -372.821454)
			(xy 64.20485 -372.628668) (xy 64.214338 -372.622849) (xy 64.235637 -372.616407) (xy 64.24676 -372.615968)
			(xy 64.441324 -372.615968) (xy 64.453397 -372.616444) (xy 64.476361 -372.62391) (xy 64.495896 -372.638104)
			(xy 64.51009 -372.657639) (xy 64.517556 -372.680603) (xy 64.518032 -372.692676) (xy 64.518032 -373.37873)
			(xy 64.518023 -373.378984) (xy 75.325224 -373.378984) (xy 75.325224 -372.69293) (xy 75.325733 -372.680844)
			(xy 75.333179 -372.657847) (xy 75.347356 -372.638268) (xy 75.36688 -372.624015) (xy 75.389847 -372.61648)
			(xy 75.401932 -372.615968) (xy 75.596496 -372.615968) (xy 75.60762 -372.616396) (xy 75.628918 -372.622846)
			(xy 75.638406 -372.628668) (xy 75.93203 -372.8212) (xy 75.941388 -372.826949) (xy 75.962413 -372.833275)
			(xy 75.984369 -372.833336) (xy 76.005428 -372.827127) (xy 76.014834 -372.821454) (xy 76.310998 -372.628668)
			(xy 76.320497 -372.622868) (xy 76.341787 -372.616414) (xy 76.352908 -372.615968) (xy 76.547472 -372.615968)
			(xy 76.559551 -372.616436) (xy 76.582529 -372.623893) (xy 76.602077 -372.638086) (xy 76.616283 -372.657625)
			(xy 76.623756 -372.680597) (xy 76.62418 -372.692676) (xy 76.62418 -373.37873) (xy 76.62417 -373.378984)
			(xy 82.132424 -373.378984) (xy 82.132424 -372.69293) (xy 82.132933 -372.680844) (xy 82.140379 -372.657847)
			(xy 82.154556 -372.638268) (xy 82.17408 -372.624015) (xy 82.197047 -372.61648) (xy 82.209132 -372.615968)
			(xy 82.403696 -372.615968) (xy 82.41482 -372.616396) (xy 82.436118 -372.622846) (xy 82.445606 -372.628668)
			(xy 82.73923 -372.8212) (xy 82.748588 -372.826949) (xy 82.769613 -372.833275) (xy 82.791569 -372.833336)
			(xy 82.812628 -372.827127) (xy 82.822034 -372.821454) (xy 83.118198 -372.628668) (xy 83.127697 -372.622868)
			(xy 83.148987 -372.616414) (xy 83.160108 -372.615968) (xy 83.354672 -372.615968) (xy 83.366751 -372.616436)
			(xy 83.389729 -372.623893) (xy 83.409277 -372.638086) (xy 83.423483 -372.657625) (xy 83.430956 -372.680597)
			(xy 83.43138 -372.692676) (xy 83.43138 -373.37873) (xy 83.43137 -373.378984) (xy 88.939624 -373.378984)
			(xy 88.939624 -372.69293) (xy 88.940133 -372.680844) (xy 88.947579 -372.657847) (xy 88.961756 -372.638268)
			(xy 88.98128 -372.624015) (xy 89.004247 -372.61648) (xy 89.016332 -372.615968) (xy 89.210896 -372.615968)
			(xy 89.22202 -372.616396) (xy 89.243318 -372.622846) (xy 89.252806 -372.628668) (xy 89.54643 -372.8212)
			(xy 89.555788 -372.826949) (xy 89.576813 -372.833275) (xy 89.598769 -372.833336) (xy 89.619828 -372.827127)
			(xy 89.629234 -372.821454) (xy 89.925398 -372.628668) (xy 89.934897 -372.622868) (xy 89.956187 -372.616414)
			(xy 89.967308 -372.615968) (xy 90.161872 -372.615968) (xy 90.173951 -372.616436) (xy 90.196929 -372.623893)
			(xy 90.216477 -372.638086) (xy 90.230683 -372.657625) (xy 90.238156 -372.680597) (xy 90.23858 -372.692676)
			(xy 90.23858 -373.37873) (xy 90.23857 -373.378984) (xy 95.746824 -373.378984) (xy 95.746824 -372.69293)
			(xy 95.747333 -372.680844) (xy 95.754779 -372.657847) (xy 95.768956 -372.638268) (xy 95.78848 -372.624015)
			(xy 95.811447 -372.61648) (xy 95.823532 -372.615968) (xy 96.018096 -372.615968) (xy 96.02922 -372.616396)
			(xy 96.050518 -372.622846) (xy 96.060006 -372.628668) (xy 96.35363 -372.8212) (xy 96.362988 -372.826949)
			(xy 96.384013 -372.833275) (xy 96.405969 -372.833336) (xy 96.427028 -372.827127) (xy 96.436434 -372.821454)
			(xy 96.732598 -372.628668) (xy 96.742097 -372.622868) (xy 96.763387 -372.616414) (xy 96.774508 -372.615968)
			(xy 96.969072 -372.615968) (xy 96.981151 -372.616436) (xy 97.004129 -372.623893) (xy 97.023677 -372.638086)
			(xy 97.037883 -372.657625) (xy 97.045356 -372.680597) (xy 97.04578 -372.692676) (xy 97.04578 -373.37873)
			(xy 109.897164 -373.37873) (xy 109.897164 -372.69293) (xy 109.897586 -372.680806) (xy 109.905073 -372.657744)
			(xy 109.919323 -372.638126) (xy 109.93894 -372.623875) (xy 109.962002 -372.616386) (xy 109.974126 -372.615968)
			(xy 110.16869 -372.615968) (xy 110.179814 -372.616399) (xy 110.201111 -372.622846) (xy 110.2106 -372.628668)
			(xy 110.504224 -372.8212) (xy 110.513585 -372.826944) (xy 110.534608 -372.833271) (xy 110.556563 -372.833334)
			(xy 110.577622 -372.827126) (xy 110.587028 -372.821454) (xy 110.883192 -372.628668) (xy 110.892692 -372.62287)
			(xy 110.913982 -372.616415) (xy 110.925102 -372.615968) (xy 111.119666 -372.615968) (xy 111.13179 -372.616389)
			(xy 111.154853 -372.623876) (xy 111.174471 -372.638126) (xy 111.188722 -372.657744) (xy 111.19621 -372.680806)
			(xy 111.196628 -372.69293) (xy 111.196628 -373.37873) (xy 116.704364 -373.37873) (xy 116.704364 -372.69293)
			(xy 116.704786 -372.680806) (xy 116.712273 -372.657744) (xy 116.726523 -372.638126) (xy 116.74614 -372.623875)
			(xy 116.769202 -372.616386) (xy 116.781326 -372.615968) (xy 116.97589 -372.615968) (xy 116.987014 -372.616399)
			(xy 117.008311 -372.622846) (xy 117.0178 -372.628668) (xy 117.311424 -372.8212) (xy 117.320785 -372.826944)
			(xy 117.341808 -372.833271) (xy 117.363763 -372.833334) (xy 117.384822 -372.827126) (xy 117.394228 -372.821454)
			(xy 117.690392 -372.628668) (xy 117.699892 -372.62287) (xy 117.721182 -372.616415) (xy 117.732302 -372.615968)
			(xy 117.926866 -372.615968) (xy 117.93899 -372.616389) (xy 117.962053 -372.623876) (xy 117.981671 -372.638126)
			(xy 117.995922 -372.657744) (xy 118.00341 -372.680806) (xy 118.003828 -372.69293) (xy 118.003828 -373.37873)
			(xy 123.511564 -373.37873) (xy 123.511564 -372.69293) (xy 123.511986 -372.680806) (xy 123.519473 -372.657744)
			(xy 123.533723 -372.638126) (xy 123.55334 -372.623875) (xy 123.576402 -372.616386) (xy 123.588526 -372.615968)
			(xy 123.78309 -372.615968) (xy 123.794214 -372.616399) (xy 123.815511 -372.622846) (xy 123.825 -372.628668)
			(xy 124.118624 -372.8212) (xy 124.127985 -372.826944) (xy 124.149008 -372.833271) (xy 124.170963 -372.833334)
			(xy 124.192022 -372.827126) (xy 124.201428 -372.821454) (xy 124.497592 -372.628668) (xy 124.507092 -372.62287)
			(xy 124.528382 -372.616415) (xy 124.539502 -372.615968) (xy 124.734066 -372.615968) (xy 124.74619 -372.616389)
			(xy 124.769253 -372.623876) (xy 124.788871 -372.638126) (xy 124.803122 -372.657744) (xy 124.81061 -372.680806)
			(xy 124.811028 -372.69293) (xy 124.811028 -373.37873) (xy 130.318764 -373.37873) (xy 130.318764 -372.69293)
			(xy 130.319186 -372.680806) (xy 130.326673 -372.657744) (xy 130.340923 -372.638126) (xy 130.36054 -372.623875)
			(xy 130.383602 -372.616386) (xy 130.395726 -372.615968) (xy 130.59029 -372.615968) (xy 130.601414 -372.616399)
			(xy 130.622711 -372.622846) (xy 130.6322 -372.628668) (xy 130.925824 -372.8212) (xy 130.935185 -372.826944)
			(xy 130.956208 -372.833271) (xy 130.978163 -372.833334) (xy 130.999222 -372.827126) (xy 131.008628 -372.821454)
			(xy 131.304792 -372.628668) (xy 131.314292 -372.62287) (xy 131.335582 -372.616415) (xy 131.346702 -372.615968)
			(xy 131.541266 -372.615968) (xy 131.55339 -372.616389) (xy 131.576453 -372.623876) (xy 131.596071 -372.638126)
			(xy 131.610322 -372.657744) (xy 131.61781 -372.680806) (xy 131.618228 -372.69293) (xy 131.618228 -373.37873)
			(xy 142.424912 -373.37873) (xy 142.424912 -372.69293) (xy 142.425385 -372.680811) (xy 142.432866 -372.657758)
			(xy 142.447105 -372.638145) (xy 142.466708 -372.623892) (xy 142.489756 -372.616394) (xy 142.501874 -372.615968)
			(xy 142.696438 -372.615968) (xy 142.707564 -372.616379) (xy 142.728861 -372.62284) (xy 142.738348 -372.628668)
			(xy 143.031972 -372.8212) (xy 143.041358 -372.826899) (xy 143.062369 -372.833236) (xy 143.084316 -372.833312)
			(xy 143.10537 -372.827118) (xy 143.114776 -372.821454) (xy 143.41094 -372.628668) (xy 143.42043 -372.622852)
			(xy 143.441728 -372.616408) (xy 143.45285 -372.615968) (xy 143.647414 -372.615968) (xy 143.65954 -372.616349)
			(xy 143.682605 -372.623848) (xy 143.702222 -372.638109) (xy 143.716472 -372.657735) (xy 143.723958 -372.680803)
			(xy 143.724376 -372.69293) (xy 143.724376 -373.37873) (xy 149.232112 -373.37873) (xy 149.232112 -372.69293)
			(xy 149.232585 -372.680811) (xy 149.240066 -372.657758) (xy 149.254305 -372.638145) (xy 149.273908 -372.623892)
			(xy 149.296956 -372.616394) (xy 149.309074 -372.615968) (xy 149.503638 -372.615968) (xy 149.514764 -372.616379)
			(xy 149.536061 -372.62284) (xy 149.545548 -372.628668) (xy 149.839172 -372.8212) (xy 149.848558 -372.826899)
			(xy 149.869569 -372.833236) (xy 149.891516 -372.833312) (xy 149.91257 -372.827118) (xy 149.921976 -372.821454)
			(xy 150.21814 -372.628668) (xy 150.22763 -372.622852) (xy 150.248928 -372.616408) (xy 150.26005 -372.615968)
			(xy 150.454614 -372.615968) (xy 150.46674 -372.616349) (xy 150.489805 -372.623848) (xy 150.509422 -372.638109)
			(xy 150.523672 -372.657735) (xy 150.531158 -372.680803) (xy 150.531576 -372.69293) (xy 150.531576 -373.37873)
			(xy 156.039312 -373.37873) (xy 156.039312 -372.69293) (xy 156.039785 -372.680811) (xy 156.047266 -372.657758)
			(xy 156.061505 -372.638145) (xy 156.081108 -372.623892) (xy 156.104156 -372.616394) (xy 156.116274 -372.615968)
			(xy 156.310838 -372.615968) (xy 156.321964 -372.616379) (xy 156.343261 -372.62284) (xy 156.352748 -372.628668)
			(xy 156.646372 -372.8212) (xy 156.655758 -372.826899) (xy 156.676769 -372.833236) (xy 156.698716 -372.833312)
			(xy 156.71977 -372.827118) (xy 156.729176 -372.821454) (xy 157.02534 -372.628668) (xy 157.03483 -372.622852)
			(xy 157.056128 -372.616408) (xy 157.06725 -372.615968) (xy 157.261814 -372.615968) (xy 157.27394 -372.616349)
			(xy 157.297005 -372.623848) (xy 157.316622 -372.638109) (xy 157.330872 -372.657735) (xy 157.338358 -372.680803)
			(xy 157.338776 -372.69293) (xy 157.338776 -373.37873) (xy 162.846512 -373.37873) (xy 162.846512 -372.69293)
			(xy 162.846985 -372.680811) (xy 162.854466 -372.657758) (xy 162.868705 -372.638145) (xy 162.888308 -372.623892)
			(xy 162.911356 -372.616394) (xy 162.923474 -372.615968) (xy 163.118038 -372.615968) (xy 163.129164 -372.616379)
			(xy 163.150461 -372.62284) (xy 163.159948 -372.628668) (xy 163.453572 -372.8212) (xy 163.462958 -372.826899)
			(xy 163.483969 -372.833236) (xy 163.505916 -372.833312) (xy 163.52697 -372.827118) (xy 163.536376 -372.821454)
			(xy 163.83254 -372.628668) (xy 163.84203 -372.622852) (xy 163.863328 -372.616408) (xy 163.87445 -372.615968)
			(xy 164.069014 -372.615968) (xy 164.08114 -372.616349) (xy 164.104205 -372.623848) (xy 164.123822 -372.638109)
			(xy 164.138072 -372.657735) (xy 164.145558 -372.680803) (xy 164.145976 -372.69293) (xy 164.145976 -373.37873)
			(xy 164.145514 -373.390845) (xy 164.13802 -373.413887) (xy 164.123775 -373.433487) (xy 164.104172 -373.447728)
			(xy 164.081129 -373.455217) (xy 164.069014 -373.455692) (xy 163.87445 -373.455692) (xy 163.863325 -373.455276)
			(xy 163.842028 -373.448818) (xy 163.83254 -373.442992) (xy 163.537646 -373.25046) (xy 163.528259 -373.244757)
			(xy 163.507221 -373.238484) (xy 163.485267 -373.238484) (xy 163.464229 -373.244757) (xy 163.454842 -373.25046)
			(xy 163.161218 -373.442992) (xy 163.151714 -373.448783) (xy 163.130427 -373.455243) (xy 163.119308 -373.455692)
			(xy 162.923474 -373.455692) (xy 162.911361 -373.455211) (xy 162.888322 -373.44772) (xy 162.868723 -373.43348)
			(xy 162.854482 -373.413882) (xy 162.84699 -373.390843) (xy 162.846512 -373.37873) (xy 157.338776 -373.37873)
			(xy 157.338314 -373.390845) (xy 157.33082 -373.413887) (xy 157.316575 -373.433487) (xy 157.296972 -373.447728)
			(xy 157.273929 -373.455217) (xy 157.261814 -373.455692) (xy 157.06725 -373.455692) (xy 157.056125 -373.455276)
			(xy 157.034828 -373.448818) (xy 157.02534 -373.442992) (xy 156.730446 -373.25046) (xy 156.721059 -373.244757)
			(xy 156.700021 -373.238484) (xy 156.678067 -373.238484) (xy 156.657029 -373.244757) (xy 156.647642 -373.25046)
			(xy 156.354018 -373.442992) (xy 156.344514 -373.448783) (xy 156.323227 -373.455243) (xy 156.312108 -373.455692)
			(xy 156.116274 -373.455692) (xy 156.104161 -373.455211) (xy 156.081122 -373.44772) (xy 156.061523 -373.43348)
			(xy 156.047282 -373.413882) (xy 156.03979 -373.390843) (xy 156.039312 -373.37873) (xy 150.531576 -373.37873)
			(xy 150.531114 -373.390845) (xy 150.52362 -373.413887) (xy 150.509375 -373.433487) (xy 150.489772 -373.447728)
			(xy 150.466729 -373.455217) (xy 150.454614 -373.455692) (xy 150.26005 -373.455692) (xy 150.248925 -373.455276)
			(xy 150.227628 -373.448818) (xy 150.21814 -373.442992) (xy 149.923246 -373.25046) (xy 149.913859 -373.244757)
			(xy 149.892821 -373.238484) (xy 149.870867 -373.238484) (xy 149.849829 -373.244757) (xy 149.840442 -373.25046)
			(xy 149.546818 -373.442992) (xy 149.537314 -373.448783) (xy 149.516027 -373.455243) (xy 149.504908 -373.455692)
			(xy 149.309074 -373.455692) (xy 149.296961 -373.455211) (xy 149.273922 -373.44772) (xy 149.254323 -373.43348)
			(xy 149.240082 -373.413882) (xy 149.23259 -373.390843) (xy 149.232112 -373.37873) (xy 143.724376 -373.37873)
			(xy 143.723914 -373.390845) (xy 143.71642 -373.413887) (xy 143.702175 -373.433487) (xy 143.682572 -373.447728)
			(xy 143.659529 -373.455217) (xy 143.647414 -373.455692) (xy 143.45285 -373.455692) (xy 143.441725 -373.455276)
			(xy 143.420428 -373.448818) (xy 143.41094 -373.442992) (xy 143.116046 -373.25046) (xy 143.106659 -373.244757)
			(xy 143.085621 -373.238484) (xy 143.063667 -373.238484) (xy 143.042629 -373.244757) (xy 143.033242 -373.25046)
			(xy 142.739618 -373.442992) (xy 142.730114 -373.448783) (xy 142.708827 -373.455243) (xy 142.697708 -373.455692)
			(xy 142.501874 -373.455692) (xy 142.489761 -373.455211) (xy 142.466722 -373.44772) (xy 142.447123 -373.43348)
			(xy 142.432882 -373.413882) (xy 142.42539 -373.390843) (xy 142.424912 -373.37873) (xy 131.618228 -373.37873)
			(xy 131.617865 -373.390858) (xy 131.610361 -373.413923) (xy 131.596095 -373.433541) (xy 131.576466 -373.44779)
			(xy 131.553394 -373.455275) (xy 131.541266 -373.455692) (xy 131.346702 -373.455692) (xy 131.335578 -373.455256)
			(xy 131.314282 -373.448811) (xy 131.304792 -373.442992) (xy 131.009898 -373.25046) (xy 131.000511 -373.244757)
			(xy 130.979473 -373.238484) (xy 130.957519 -373.238484) (xy 130.936481 -373.244757) (xy 130.927094 -373.25046)
			(xy 130.63347 -373.442992) (xy 130.623975 -373.4488) (xy 130.602682 -373.455249) (xy 130.59156 -373.455692)
			(xy 130.395726 -373.455692) (xy 130.383616 -373.455167) (xy 130.360578 -373.44769) (xy 130.340979 -373.433461)
			(xy 130.326735 -373.413872) (xy 130.319242 -373.39084) (xy 130.318764 -373.37873) (xy 124.811028 -373.37873)
			(xy 124.810665 -373.390858) (xy 124.803161 -373.413923) (xy 124.788895 -373.433541) (xy 124.769266 -373.44779)
			(xy 124.746194 -373.455275) (xy 124.734066 -373.455692) (xy 124.539502 -373.455692) (xy 124.528378 -373.455256)
			(xy 124.507082 -373.448811) (xy 124.497592 -373.442992) (xy 124.202698 -373.25046) (xy 124.193311 -373.244757)
			(xy 124.172273 -373.238484) (xy 124.150319 -373.238484) (xy 124.129281 -373.244757) (xy 124.119894 -373.25046)
			(xy 123.82627 -373.442992) (xy 123.816775 -373.4488) (xy 123.795482 -373.455249) (xy 123.78436 -373.455692)
			(xy 123.588526 -373.455692) (xy 123.576416 -373.455167) (xy 123.553378 -373.44769) (xy 123.533779 -373.433461)
			(xy 123.519535 -373.413872) (xy 123.512042 -373.39084) (xy 123.511564 -373.37873) (xy 118.003828 -373.37873)
			(xy 118.003465 -373.390858) (xy 117.995961 -373.413923) (xy 117.981695 -373.433541) (xy 117.962066 -373.44779)
			(xy 117.938994 -373.455275) (xy 117.926866 -373.455692) (xy 117.732302 -373.455692) (xy 117.721178 -373.455256)
			(xy 117.699882 -373.448811) (xy 117.690392 -373.442992) (xy 117.395498 -373.25046) (xy 117.386111 -373.244757)
			(xy 117.365073 -373.238484) (xy 117.343119 -373.238484) (xy 117.322081 -373.244757) (xy 117.312694 -373.25046)
			(xy 117.01907 -373.442992) (xy 117.009575 -373.4488) (xy 116.988282 -373.455249) (xy 116.97716 -373.455692)
			(xy 116.781326 -373.455692) (xy 116.769216 -373.455167) (xy 116.746178 -373.44769) (xy 116.726579 -373.433461)
			(xy 116.712335 -373.413872) (xy 116.704842 -373.39084) (xy 116.704364 -373.37873) (xy 111.196628 -373.37873)
			(xy 111.196265 -373.390858) (xy 111.188761 -373.413923) (xy 111.174495 -373.433541) (xy 111.154866 -373.44779)
			(xy 111.131794 -373.455275) (xy 111.119666 -373.455692) (xy 110.925102 -373.455692) (xy 110.913978 -373.455256)
			(xy 110.892682 -373.448811) (xy 110.883192 -373.442992) (xy 110.588298 -373.25046) (xy 110.578911 -373.244757)
			(xy 110.557873 -373.238484) (xy 110.535919 -373.238484) (xy 110.514881 -373.244757) (xy 110.505494 -373.25046)
			(xy 110.21187 -373.442992) (xy 110.202375 -373.4488) (xy 110.181082 -373.455249) (xy 110.16996 -373.455692)
			(xy 109.974126 -373.455692) (xy 109.962016 -373.455167) (xy 109.938978 -373.44769) (xy 109.919379 -373.433461)
			(xy 109.905135 -373.413872) (xy 109.897642 -373.39084) (xy 109.897164 -373.37873) (xy 97.04578 -373.37873)
			(xy 97.045319 -373.390819) (xy 97.037856 -373.413817) (xy 97.023667 -373.433395) (xy 97.004134 -373.447645)
			(xy 96.98116 -373.45518) (xy 96.969072 -373.455692) (xy 96.774508 -373.455692) (xy 96.763385 -373.455253)
			(xy 96.742088 -373.44881) (xy 96.732598 -373.442992) (xy 96.437704 -373.25046) (xy 96.428317 -373.244757)
			(xy 96.407279 -373.238484) (xy 96.385325 -373.238484) (xy 96.364287 -373.244757) (xy 96.3549 -373.25046)
			(xy 96.061276 -373.442992) (xy 96.05178 -373.448798) (xy 96.030487 -373.455249) (xy 96.019366 -373.455692)
			(xy 95.823532 -373.455692) (xy 95.811449 -373.45526) (xy 95.788465 -373.447799) (xy 95.768913 -373.433599)
			(xy 95.754708 -373.414049) (xy 95.747243 -373.391067) (xy 95.746824 -373.378984) (xy 90.23857 -373.378984)
			(xy 90.238119 -373.390819) (xy 90.230656 -373.413817) (xy 90.216467 -373.433395) (xy 90.196934 -373.447645)
			(xy 90.17396 -373.45518) (xy 90.161872 -373.455692) (xy 89.967308 -373.455692) (xy 89.956185 -373.455253)
			(xy 89.934888 -373.44881) (xy 89.925398 -373.442992) (xy 89.630504 -373.25046) (xy 89.621117 -373.244757)
			(xy 89.600079 -373.238484) (xy 89.578125 -373.238484) (xy 89.557087 -373.244757) (xy 89.5477 -373.25046)
			(xy 89.254076 -373.442992) (xy 89.24458 -373.448798) (xy 89.223287 -373.455249) (xy 89.212166 -373.455692)
			(xy 89.016332 -373.455692) (xy 89.004249 -373.45526) (xy 88.981265 -373.447799) (xy 88.961713 -373.433599)
			(xy 88.947508 -373.414049) (xy 88.940043 -373.391067) (xy 88.939624 -373.378984) (xy 83.43137 -373.378984)
			(xy 83.430919 -373.390819) (xy 83.423456 -373.413817) (xy 83.409267 -373.433395) (xy 83.389734 -373.447645)
			(xy 83.36676 -373.45518) (xy 83.354672 -373.455692) (xy 83.160108 -373.455692) (xy 83.148985 -373.455253)
			(xy 83.127688 -373.44881) (xy 83.118198 -373.442992) (xy 82.823304 -373.25046) (xy 82.813917 -373.244757)
			(xy 82.792879 -373.238484) (xy 82.770925 -373.238484) (xy 82.749887 -373.244757) (xy 82.7405 -373.25046)
			(xy 82.446876 -373.442992) (xy 82.43738 -373.448798) (xy 82.416087 -373.455249) (xy 82.404966 -373.455692)
			(xy 82.209132 -373.455692) (xy 82.197049 -373.45526) (xy 82.174065 -373.447799) (xy 82.154513 -373.433599)
			(xy 82.140308 -373.414049) (xy 82.132843 -373.391067) (xy 82.132424 -373.378984) (xy 76.62417 -373.378984)
			(xy 76.623719 -373.390819) (xy 76.616256 -373.413817) (xy 76.602067 -373.433395) (xy 76.582534 -373.447645)
			(xy 76.55956 -373.45518) (xy 76.547472 -373.455692) (xy 76.352908 -373.455692) (xy 76.341785 -373.455253)
			(xy 76.320488 -373.44881) (xy 76.310998 -373.442992) (xy 76.016104 -373.25046) (xy 76.006717 -373.244757)
			(xy 75.985679 -373.238484) (xy 75.963725 -373.238484) (xy 75.942687 -373.244757) (xy 75.9333 -373.25046)
			(xy 75.639676 -373.442992) (xy 75.63018 -373.448798) (xy 75.608887 -373.455249) (xy 75.597766 -373.455692)
			(xy 75.401932 -373.455692) (xy 75.389849 -373.45526) (xy 75.366865 -373.447799) (xy 75.347313 -373.433599)
			(xy 75.333108 -373.414049) (xy 75.325643 -373.391067) (xy 75.325224 -373.378984) (xy 64.518023 -373.378984)
			(xy 64.517618 -373.390824) (xy 64.510149 -373.41383) (xy 64.49595 -373.433412) (xy 64.476404 -373.447661)
			(xy 64.453417 -373.455187) (xy 64.441324 -373.455692) (xy 64.24676 -373.455692) (xy 64.235635 -373.455272)
			(xy 64.214338 -373.448816) (xy 64.20485 -373.442992) (xy 63.909956 -373.25046) (xy 63.900569 -373.244757)
			(xy 63.879531 -373.238484) (xy 63.857577 -373.238484) (xy 63.836539 -373.244757) (xy 63.827152 -373.25046)
			(xy 63.533528 -373.442992) (xy 63.524022 -373.448779) (xy 63.502737 -373.455241) (xy 63.491618 -373.455692)
			(xy 63.295784 -373.455692) (xy 63.283707 -373.455249) (xy 63.260737 -373.44778) (xy 63.241199 -373.433579)
			(xy 63.227005 -373.414035) (xy 63.219546 -373.391061) (xy 63.219076 -373.378984) (xy 57.710823 -373.378984)
			(xy 57.710418 -373.390824) (xy 57.702949 -373.41383) (xy 57.68875 -373.433412) (xy 57.669204 -373.447661)
			(xy 57.646217 -373.455187) (xy 57.634124 -373.455692) (xy 57.43956 -373.455692) (xy 57.428435 -373.455272)
			(xy 57.407138 -373.448816) (xy 57.39765 -373.442992) (xy 57.102756 -373.25046) (xy 57.093369 -373.244757)
			(xy 57.072331 -373.238484) (xy 57.050377 -373.238484) (xy 57.029339 -373.244757) (xy 57.019952 -373.25046)
			(xy 56.726328 -373.442992) (xy 56.716822 -373.448779) (xy 56.695537 -373.455241) (xy 56.684418 -373.455692)
			(xy 56.488584 -373.455692) (xy 56.476507 -373.455249) (xy 56.453537 -373.44778) (xy 56.433999 -373.433579)
			(xy 56.419805 -373.414035) (xy 56.412346 -373.391061) (xy 56.411876 -373.378984) (xy 50.903623 -373.378984)
			(xy 50.903218 -373.390824) (xy 50.895749 -373.41383) (xy 50.88155 -373.433412) (xy 50.862004 -373.447661)
			(xy 50.839017 -373.455187) (xy 50.826924 -373.455692) (xy 50.63236 -373.455692) (xy 50.621235 -373.455272)
			(xy 50.599938 -373.448816) (xy 50.59045 -373.442992) (xy 50.295556 -373.25046) (xy 50.286169 -373.244757)
			(xy 50.265131 -373.238484) (xy 50.243177 -373.238484) (xy 50.222139 -373.244757) (xy 50.212752 -373.25046)
			(xy 49.919128 -373.442992) (xy 49.909622 -373.448779) (xy 49.888337 -373.455241) (xy 49.877218 -373.455692)
			(xy 49.681384 -373.455692) (xy 49.669307 -373.455249) (xy 49.646337 -373.44778) (xy 49.626799 -373.433579)
			(xy 49.612605 -373.414035) (xy 49.605146 -373.391061) (xy 49.604676 -373.378984) (xy 44.096423 -373.378984)
			(xy 44.096018 -373.390824) (xy 44.088549 -373.41383) (xy 44.07435 -373.433412) (xy 44.054804 -373.447661)
			(xy 44.031817 -373.455187) (xy 44.019724 -373.455692) (xy 43.82516 -373.455692) (xy 43.814035 -373.455272)
			(xy 43.792738 -373.448816) (xy 43.78325 -373.442992) (xy 43.488356 -373.25046) (xy 43.478969 -373.244757)
			(xy 43.457931 -373.238484) (xy 43.435977 -373.238484) (xy 43.414939 -373.244757) (xy 43.405552 -373.25046)
			(xy 43.111928 -373.442992) (xy 43.102422 -373.448779) (xy 43.081137 -373.455241) (xy 43.070018 -373.455692)
			(xy 42.874184 -373.455692) (xy 42.862107 -373.455249) (xy 42.839137 -373.44778) (xy 42.819599 -373.433579)
			(xy 42.805405 -373.414035) (xy 42.797946 -373.391061) (xy 42.797476 -373.378984) (xy 37.584749 -373.378984)
			(xy 37.653353 -373.434412) (xy 37.786904 -373.552524) (xy 37.915061 -373.676468) (xy 38.03757 -373.805998)
			(xy 38.154187 -373.940857) (xy 38.193125 -373.990165) (xy 47.739354 -373.990165) (xy 47.739354 -373.935635)
			(xy 47.747114 -373.88166) (xy 47.762476 -373.829338) (xy 47.785127 -373.779735) (xy 47.814606 -373.733859)
			(xy 47.850314 -373.692646) (xy 47.891523 -373.656934) (xy 47.937394 -373.627449) (xy 47.986995 -373.604792)
			(xy 48.039315 -373.589424) (xy 48.093289 -373.581657) (xy 48.120554 -373.581168) (xy 48.984154 -373.581168)
			(xy 49.011429 -373.581568) (xy 49.065425 -373.589326) (xy 49.117768 -373.604689) (xy 49.167391 -373.627346)
			(xy 49.213284 -373.656835) (xy 49.254512 -373.692555) (xy 49.290238 -373.73378) (xy 49.319732 -373.779669)
			(xy 49.342395 -373.829289) (xy 49.357764 -373.88163) (xy 49.365528 -373.935625) (xy 49.365528 -373.990165)
			(xy 54.546554 -373.990165) (xy 54.546554 -373.935635) (xy 54.554314 -373.88166) (xy 54.569676 -373.829338)
			(xy 54.592327 -373.779735) (xy 54.621806 -373.733859) (xy 54.657514 -373.692646) (xy 54.698723 -373.656934)
			(xy 54.744594 -373.627449) (xy 54.794195 -373.604792) (xy 54.846515 -373.589424) (xy 54.900489 -373.581657)
			(xy 54.927754 -373.581168) (xy 55.791354 -373.581168) (xy 55.818629 -373.581568) (xy 55.872625 -373.589326)
			(xy 55.924968 -373.604689) (xy 55.974591 -373.627346) (xy 56.020484 -373.656835) (xy 56.061712 -373.692555)
			(xy 56.097438 -373.73378) (xy 56.126932 -373.779669) (xy 56.149595 -373.829289) (xy 56.164964 -373.88163)
			(xy 56.172728 -373.935625) (xy 56.172728 -373.990165) (xy 61.353754 -373.990165) (xy 61.353754 -373.935635)
			(xy 61.361514 -373.88166) (xy 61.376876 -373.829338) (xy 61.399527 -373.779735) (xy 61.429006 -373.733859)
			(xy 61.464714 -373.692646) (xy 61.505923 -373.656934) (xy 61.551794 -373.627449) (xy 61.601395 -373.604792)
			(xy 61.653715 -373.589424) (xy 61.707689 -373.581657) (xy 61.734954 -373.581168) (xy 62.598554 -373.581168)
			(xy 62.625829 -373.581568) (xy 62.679825 -373.589326) (xy 62.732168 -373.604689) (xy 62.781791 -373.627346)
			(xy 62.827684 -373.656835) (xy 62.868912 -373.692555) (xy 62.904638 -373.73378) (xy 62.934132 -373.779669)
			(xy 62.956795 -373.829289) (xy 62.972164 -373.88163) (xy 62.979928 -373.935625) (xy 62.979928 -373.990169)
			(xy 80.267031 -373.990169) (xy 80.267031 -373.935631) (xy 80.274793 -373.881648) (xy 80.290158 -373.82932)
			(xy 80.312814 -373.77971) (xy 80.3423 -373.73383) (xy 80.378014 -373.692613) (xy 80.419232 -373.656898)
			(xy 80.465112 -373.627413) (xy 80.514721 -373.604757) (xy 80.56705 -373.589393) (xy 80.621033 -373.581631)
			(xy 80.648302 -373.581168) (xy 81.511902 -373.581168) (xy 81.539173 -373.581595) (xy 81.593161 -373.589357)
			(xy 81.645494 -373.604724) (xy 81.695108 -373.627382) (xy 81.740993 -373.65687) (xy 81.782213 -373.692588)
			(xy 81.817931 -373.733809) (xy 81.847419 -373.779693) (xy 81.870077 -373.829307) (xy 81.885443 -373.881641)
			(xy 81.893206 -373.935629) (xy 81.893206 -373.990169) (xy 87.074231 -373.990169) (xy 87.074231 -373.935631)
			(xy 87.081993 -373.881648) (xy 87.097358 -373.82932) (xy 87.120014 -373.77971) (xy 87.1495 -373.73383)
			(xy 87.185214 -373.692613) (xy 87.226432 -373.656898) (xy 87.272312 -373.627413) (xy 87.321921 -373.604757)
			(xy 87.37425 -373.589393) (xy 87.428233 -373.581631) (xy 87.455502 -373.581168) (xy 88.319102 -373.581168)
			(xy 88.346373 -373.581595) (xy 88.400361 -373.589357) (xy 88.452694 -373.604724) (xy 88.502308 -373.627382)
			(xy 88.548193 -373.65687) (xy 88.589413 -373.692588) (xy 88.625131 -373.733809) (xy 88.654619 -373.779693)
			(xy 88.677277 -373.829307) (xy 88.692643 -373.881641) (xy 88.700406 -373.935629) (xy 88.700406 -373.990169)
			(xy 93.881431 -373.990169) (xy 93.881431 -373.935631) (xy 93.889193 -373.881648) (xy 93.904558 -373.82932)
			(xy 93.927214 -373.77971) (xy 93.9567 -373.73383) (xy 93.992414 -373.692613) (xy 94.033632 -373.656898)
			(xy 94.079512 -373.627413) (xy 94.129121 -373.604757) (xy 94.18145 -373.589393) (xy 94.235433 -373.581631)
			(xy 94.262702 -373.581168) (xy 95.126302 -373.581168) (xy 95.153573 -373.581595) (xy 95.207561 -373.589357)
			(xy 95.259894 -373.604724) (xy 95.309508 -373.627382) (xy 95.355393 -373.65687) (xy 95.396613 -373.692588)
			(xy 95.432331 -373.733809) (xy 95.461819 -373.779693) (xy 95.484477 -373.829307) (xy 95.499843 -373.881641)
			(xy 95.507606 -373.935629) (xy 95.507606 -373.990167) (xy 114.839254 -373.990167) (xy 114.839254 -373.935633)
			(xy 114.847015 -373.881654) (xy 114.862379 -373.829329) (xy 114.885033 -373.779723) (xy 114.914517 -373.733846)
			(xy 114.950229 -373.692631) (xy 114.991442 -373.656919) (xy 115.037319 -373.627435) (xy 115.086925 -373.604781)
			(xy 115.13925 -373.589416) (xy 115.193229 -373.581655) (xy 115.220496 -373.581168) (xy 116.084096 -373.581168)
			(xy 116.111369 -373.581571) (xy 116.165361 -373.589334) (xy 116.217698 -373.604701) (xy 116.267316 -373.62736)
			(xy 116.313203 -373.65685) (xy 116.354427 -373.69257) (xy 116.390148 -373.733793) (xy 116.419638 -373.779681)
			(xy 116.442298 -373.829298) (xy 116.457666 -373.881635) (xy 116.465428 -373.935627) (xy 116.465428 -373.990167)
			(xy 121.646454 -373.990167) (xy 121.646454 -373.935633) (xy 121.654215 -373.881654) (xy 121.669579 -373.829329)
			(xy 121.692233 -373.779723) (xy 121.721717 -373.733846) (xy 121.757429 -373.692631) (xy 121.798642 -373.656919)
			(xy 121.844519 -373.627435) (xy 121.894125 -373.604781) (xy 121.94645 -373.589416) (xy 122.000429 -373.581655)
			(xy 122.027696 -373.581168) (xy 122.891296 -373.581168) (xy 122.918569 -373.581571) (xy 122.972561 -373.589334)
			(xy 123.024898 -373.604701) (xy 123.074516 -373.62736) (xy 123.120403 -373.65685) (xy 123.161627 -373.69257)
			(xy 123.197348 -373.733793) (xy 123.226838 -373.779681) (xy 123.249498 -373.829298) (xy 123.264866 -373.881635)
			(xy 123.272628 -373.935627) (xy 123.272628 -373.990167) (xy 128.453654 -373.990167) (xy 128.453654 -373.935633)
			(xy 128.461415 -373.881654) (xy 128.476779 -373.829329) (xy 128.499433 -373.779723) (xy 128.528917 -373.733846)
			(xy 128.564629 -373.692631) (xy 128.605842 -373.656919) (xy 128.651719 -373.627435) (xy 128.701325 -373.604781)
			(xy 128.75365 -373.589416) (xy 128.807629 -373.581655) (xy 128.834896 -373.581168) (xy 129.698496 -373.581168)
			(xy 129.725769 -373.581571) (xy 129.779761 -373.589334) (xy 129.832098 -373.604701) (xy 129.881716 -373.62736)
			(xy 129.927603 -373.65685) (xy 129.968827 -373.69257) (xy 130.004548 -373.733793) (xy 130.034038 -373.779681)
			(xy 130.056698 -373.829298) (xy 130.072066 -373.881635) (xy 130.079828 -373.935627) (xy 130.079828 -373.990171)
			(xy 147.366932 -373.990171) (xy 147.366932 -373.935629) (xy 147.374694 -373.881643) (xy 147.390061 -373.829311)
			(xy 147.412721 -373.779698) (xy 147.44221 -373.733816) (xy 147.477929 -373.692598) (xy 147.519151 -373.656884)
			(xy 147.565037 -373.627399) (xy 147.614652 -373.604746) (xy 147.666986 -373.589385) (xy 147.720973 -373.581628)
			(xy 147.748244 -373.581168) (xy 148.611844 -373.581168) (xy 148.639113 -373.581598) (xy 148.693097 -373.589365)
			(xy 148.745425 -373.604735) (xy 148.795033 -373.627396) (xy 148.840912 -373.656885) (xy 148.882128 -373.692603)
			(xy 148.917841 -373.733823) (xy 148.947325 -373.779705) (xy 148.96998 -373.829316) (xy 148.985344 -373.881647)
			(xy 148.993106 -373.93563) (xy 148.993106 -373.99017) (xy 148.993106 -373.990171) (xy 154.174132 -373.990171)
			(xy 154.174132 -373.935629) (xy 154.181894 -373.881643) (xy 154.197261 -373.829311) (xy 154.219921 -373.779698)
			(xy 154.24941 -373.733816) (xy 154.285129 -373.692598) (xy 154.326351 -373.656884) (xy 154.372237 -373.627399)
			(xy 154.421852 -373.604746) (xy 154.474186 -373.589385) (xy 154.528173 -373.581628) (xy 154.555444 -373.581168)
			(xy 155.419044 -373.581168) (xy 155.446313 -373.581598) (xy 155.500297 -373.589365) (xy 155.552625 -373.604735)
			(xy 155.602233 -373.627396) (xy 155.648112 -373.656885) (xy 155.689328 -373.692603) (xy 155.725041 -373.733823)
			(xy 155.754525 -373.779705) (xy 155.77718 -373.829316) (xy 155.792544 -373.881647) (xy 155.800306 -373.93563)
			(xy 155.800306 -373.99017) (xy 155.800306 -373.990171) (xy 160.981332 -373.990171) (xy 160.981332 -373.935629)
			(xy 160.989094 -373.881643) (xy 161.004461 -373.829311) (xy 161.027121 -373.779698) (xy 161.05661 -373.733816)
			(xy 161.092329 -373.692598) (xy 161.133551 -373.656884) (xy 161.179437 -373.627399) (xy 161.229052 -373.604746)
			(xy 161.281386 -373.589385) (xy 161.335373 -373.581628) (xy 161.362644 -373.581168) (xy 162.226244 -373.581168)
			(xy 162.253513 -373.581598) (xy 162.307497 -373.589365) (xy 162.359825 -373.604735) (xy 162.409433 -373.627396)
			(xy 162.455312 -373.656885) (xy 162.496528 -373.692603) (xy 162.532241 -373.733823) (xy 162.561725 -373.779705)
			(xy 162.58438 -373.829316) (xy 162.599744 -373.881647) (xy 162.607506 -373.93563) (xy 162.607506 -373.99017)
			(xy 162.599744 -374.044153) (xy 162.58438 -374.096484) (xy 162.561725 -374.146095) (xy 162.532241 -374.191977)
			(xy 162.496528 -374.233197) (xy 162.455312 -374.268915) (xy 162.409433 -374.298404) (xy 162.359825 -374.321065)
			(xy 162.307497 -374.336435) (xy 162.253513 -374.344202) (xy 162.226244 -374.344692) (xy 161.362644 -374.344692)
			(xy 161.335373 -374.344172) (xy 161.281386 -374.336415) (xy 161.229052 -374.321054) (xy 161.179437 -374.298401)
			(xy 161.133551 -374.268916) (xy 161.092329 -374.233202) (xy 161.05661 -374.191984) (xy 161.027121 -374.146102)
			(xy 161.004461 -374.096489) (xy 160.989094 -374.044157) (xy 160.981332 -373.990171) (xy 155.800306 -373.990171)
			(xy 155.792544 -374.044153) (xy 155.77718 -374.096484) (xy 155.754525 -374.146095) (xy 155.725041 -374.191977)
			(xy 155.689328 -374.233197) (xy 155.648112 -374.268915) (xy 155.602233 -374.298404) (xy 155.552625 -374.321065)
			(xy 155.500297 -374.336435) (xy 155.446313 -374.344202) (xy 155.419044 -374.344692) (xy 154.555444 -374.344692)
			(xy 154.528173 -374.344172) (xy 154.474186 -374.336415) (xy 154.421852 -374.321054) (xy 154.372237 -374.298401)
			(xy 154.326351 -374.268916) (xy 154.285129 -374.233202) (xy 154.24941 -374.191984) (xy 154.219921 -374.146102)
			(xy 154.197261 -374.096489) (xy 154.181894 -374.044157) (xy 154.174132 -373.990171) (xy 148.993106 -373.990171)
			(xy 148.985344 -374.044153) (xy 148.96998 -374.096484) (xy 148.947325 -374.146095) (xy 148.917841 -374.191977)
			(xy 148.882128 -374.233197) (xy 148.840912 -374.268915) (xy 148.795033 -374.298404) (xy 148.745425 -374.321065)
			(xy 148.693097 -374.336435) (xy 148.639113 -374.344202) (xy 148.611844 -374.344692) (xy 147.748244 -374.344692)
			(xy 147.720973 -374.344172) (xy 147.666986 -374.336415) (xy 147.614652 -374.321054) (xy 147.565037 -374.298401)
			(xy 147.519151 -374.268916) (xy 147.477929 -374.233202) (xy 147.44221 -374.191984) (xy 147.412721 -374.146102)
			(xy 147.390061 -374.096489) (xy 147.374694 -374.044157) (xy 147.366932 -373.990171) (xy 130.079828 -373.990171)
			(xy 130.079828 -373.990173) (xy 130.072066 -374.044165) (xy 130.056698 -374.096502) (xy 130.034038 -374.146119)
			(xy 130.004548 -374.192007) (xy 129.968827 -374.23323) (xy 129.927603 -374.26895) (xy 129.881716 -374.29844)
			(xy 129.832098 -374.321099) (xy 129.779761 -374.336466) (xy 129.725769 -374.344229) (xy 129.698496 -374.344692)
			(xy 128.834896 -374.344692) (xy 128.807629 -374.344145) (xy 128.75365 -374.336384) (xy 128.701325 -374.321019)
			(xy 128.651719 -374.298365) (xy 128.605842 -374.268881) (xy 128.564629 -374.233169) (xy 128.528917 -374.191954)
			(xy 128.499433 -374.146077) (xy 128.476779 -374.096471) (xy 128.461415 -374.044146) (xy 128.453654 -373.990167)
			(xy 123.272628 -373.990167) (xy 123.272628 -373.990173) (xy 123.264866 -374.044165) (xy 123.249498 -374.096502)
			(xy 123.226838 -374.146119) (xy 123.197348 -374.192007) (xy 123.161627 -374.23323) (xy 123.120403 -374.26895)
			(xy 123.074516 -374.29844) (xy 123.024898 -374.321099) (xy 122.972561 -374.336466) (xy 122.918569 -374.344229)
			(xy 122.891296 -374.344692) (xy 122.027696 -374.344692) (xy 122.000429 -374.344145) (xy 121.94645 -374.336384)
			(xy 121.894125 -374.321019) (xy 121.844519 -374.298365) (xy 121.798642 -374.268881) (xy 121.757429 -374.233169)
			(xy 121.721717 -374.191954) (xy 121.692233 -374.146077) (xy 121.669579 -374.096471) (xy 121.654215 -374.044146)
			(xy 121.646454 -373.990167) (xy 116.465428 -373.990167) (xy 116.465428 -373.990173) (xy 116.457666 -374.044165)
			(xy 116.442298 -374.096502) (xy 116.419638 -374.146119) (xy 116.390148 -374.192007) (xy 116.354427 -374.23323)
			(xy 116.313203 -374.26895) (xy 116.267316 -374.29844) (xy 116.217698 -374.321099) (xy 116.165361 -374.336466)
			(xy 116.111369 -374.344229) (xy 116.084096 -374.344692) (xy 115.220496 -374.344692) (xy 115.193229 -374.344145)
			(xy 115.13925 -374.336384) (xy 115.086925 -374.321019) (xy 115.037319 -374.298365) (xy 114.991442 -374.268881)
			(xy 114.950229 -374.233169) (xy 114.914517 -374.191954) (xy 114.885033 -374.146077) (xy 114.862379 -374.096471)
			(xy 114.847015 -374.044146) (xy 114.839254 -373.990167) (xy 95.507606 -373.990167) (xy 95.507606 -373.990171)
			(xy 95.499843 -374.044159) (xy 95.484477 -374.096493) (xy 95.461819 -374.146107) (xy 95.432331 -374.191991)
			(xy 95.396613 -374.233212) (xy 95.355393 -374.26893) (xy 95.309508 -374.298418) (xy 95.259894 -374.321076)
			(xy 95.207561 -374.336443) (xy 95.153573 -374.344205) (xy 95.126302 -374.344692) (xy 94.262702 -374.344692)
			(xy 94.235433 -374.344169) (xy 94.18145 -374.336407) (xy 94.129121 -374.321043) (xy 94.079512 -374.298387)
			(xy 94.033632 -374.268902) (xy 93.992414 -374.233187) (xy 93.9567 -374.19197) (xy 93.927214 -374.14609)
			(xy 93.904558 -374.09648) (xy 93.889193 -374.044152) (xy 93.881431 -373.990169) (xy 88.700406 -373.990169)
			(xy 88.700406 -373.990171) (xy 88.692643 -374.044159) (xy 88.677277 -374.096493) (xy 88.654619 -374.146107)
			(xy 88.625131 -374.191991) (xy 88.589413 -374.233212) (xy 88.548193 -374.26893) (xy 88.502308 -374.298418)
			(xy 88.452694 -374.321076) (xy 88.400361 -374.336443) (xy 88.346373 -374.344205) (xy 88.319102 -374.344692)
			(xy 87.455502 -374.344692) (xy 87.428233 -374.344169) (xy 87.37425 -374.336407) (xy 87.321921 -374.321043)
			(xy 87.272312 -374.298387) (xy 87.226432 -374.268902) (xy 87.185214 -374.233187) (xy 87.1495 -374.19197)
			(xy 87.120014 -374.14609) (xy 87.097358 -374.09648) (xy 87.081993 -374.044152) (xy 87.074231 -373.990169)
			(xy 81.893206 -373.990169) (xy 81.893206 -373.990171) (xy 81.885443 -374.044159) (xy 81.870077 -374.096493)
			(xy 81.847419 -374.146107) (xy 81.817931 -374.191991) (xy 81.782213 -374.233212) (xy 81.740993 -374.26893)
			(xy 81.695108 -374.298418) (xy 81.645494 -374.321076) (xy 81.593161 -374.336443) (xy 81.539173 -374.344205)
			(xy 81.511902 -374.344692) (xy 80.648302 -374.344692) (xy 80.621033 -374.344169) (xy 80.56705 -374.336407)
			(xy 80.514721 -374.321043) (xy 80.465112 -374.298387) (xy 80.419232 -374.268902) (xy 80.378014 -374.233187)
			(xy 80.3423 -374.19197) (xy 80.312814 -374.14609) (xy 80.290158 -374.09648) (xy 80.274793 -374.044152)
			(xy 80.267031 -373.990169) (xy 62.979928 -373.990169) (xy 62.979928 -373.990175) (xy 62.972164 -374.04417)
			(xy 62.956795 -374.096511) (xy 62.934132 -374.146131) (xy 62.904638 -374.19202) (xy 62.868912 -374.233245)
			(xy 62.827684 -374.268965) (xy 62.781791 -374.298454) (xy 62.732168 -374.321111) (xy 62.679825 -374.336474)
			(xy 62.625829 -374.344232) (xy 62.598554 -374.344692) (xy 61.734954 -374.344692) (xy 61.707689 -374.344143)
			(xy 61.653715 -374.336376) (xy 61.601395 -374.321008) (xy 61.551794 -374.298351) (xy 61.505923 -374.268866)
			(xy 61.464714 -374.233154) (xy 61.429006 -374.191941) (xy 61.399527 -374.146065) (xy 61.376876 -374.096462)
			(xy 61.361514 -374.04414) (xy 61.353754 -373.990165) (xy 56.172728 -373.990165) (xy 56.172728 -373.990175)
			(xy 56.164964 -374.04417) (xy 56.149595 -374.096511) (xy 56.126932 -374.146131) (xy 56.097438 -374.19202)
			(xy 56.061712 -374.233245) (xy 56.020484 -374.268965) (xy 55.974591 -374.298454) (xy 55.924968 -374.321111)
			(xy 55.872625 -374.336474) (xy 55.818629 -374.344232) (xy 55.791354 -374.344692) (xy 54.927754 -374.344692)
			(xy 54.900489 -374.344143) (xy 54.846515 -374.336376) (xy 54.794195 -374.321008) (xy 54.744594 -374.298351)
			(xy 54.698723 -374.268866) (xy 54.657514 -374.233154) (xy 54.621806 -374.191941) (xy 54.592327 -374.146065)
			(xy 54.569676 -374.096462) (xy 54.554314 -374.04414) (xy 54.546554 -373.990165) (xy 49.365528 -373.990165)
			(xy 49.365528 -373.990175) (xy 49.357764 -374.04417) (xy 49.342395 -374.096511) (xy 49.319732 -374.146131)
			(xy 49.290238 -374.19202) (xy 49.254512 -374.233245) (xy 49.213284 -374.268965) (xy 49.167391 -374.298454)
			(xy 49.117768 -374.321111) (xy 49.065425 -374.336474) (xy 49.011429 -374.344232) (xy 48.984154 -374.344692)
			(xy 48.120554 -374.344692) (xy 48.093289 -374.344143) (xy 48.039315 -374.336376) (xy 47.986995 -374.321008)
			(xy 47.937394 -374.298351) (xy 47.891523 -374.268866) (xy 47.850314 -374.233154) (xy 47.814606 -374.191941)
			(xy 47.785127 -374.146065) (xy 47.762476 -374.096462) (xy 47.747114 -374.04414) (xy 47.739354 -373.990165)
			(xy 38.193125 -373.990165) (xy 38.26468 -374.080777) (xy 38.368831 -374.22548) (xy 38.466433 -374.374679)
			(xy 38.557291 -374.528078) (xy 38.641225 -374.685372) (xy 38.71807 -374.846248) (xy 38.787671 -375.010389)
			(xy 38.849892 -375.177466) (xy 38.904608 -375.34715) (xy 38.95171 -375.519103) (xy 38.991106 -375.692983)
			(xy 39.022717 -375.868446) (xy 39.046481 -376.045142) (xy 39.062349 -376.222722) (xy 39.070291 -376.400832)
			(xy 39.070788 -376.489976) (xy 39.070291 -376.57912) (xy 39.062349 -376.75723) (xy 39.05568 -376.83186)
			(xy 41.04894 -376.83186) (xy 41.04894 -375.96826) (xy 41.049426 -375.940991) (xy 41.057188 -375.887007)
			(xy 41.072553 -375.834677) (xy 41.09521 -375.785067) (xy 41.124696 -375.739186) (xy 41.160411 -375.697969)
			(xy 41.201628 -375.662254) (xy 41.247509 -375.632768) (xy 41.297119 -375.610111) (xy 41.349449 -375.594746)
			(xy 41.403433 -375.586984) (xy 41.457971 -375.586984) (xy 41.511955 -375.594746) (xy 41.564285 -375.610111)
			(xy 41.613895 -375.632768) (xy 41.659776 -375.662254) (xy 41.700993 -375.697969) (xy 41.736708 -375.739186)
			(xy 41.766194 -375.785067) (xy 41.788851 -375.834677) (xy 41.804216 -375.887007) (xy 41.811978 -375.940991)
			(xy 41.812464 -375.96826) (xy 41.812464 -376.83186) (xy 41.811978 -376.859129) (xy 41.804216 -376.913113)
			(xy 41.788851 -376.965443) (xy 41.785477 -376.97283) (xy 42.54754 -376.97283) (xy 42.54754 -376.778266)
			(xy 42.547957 -376.767141) (xy 42.554414 -376.745844) (xy 42.56024 -376.736356) (xy 42.752772 -376.441462)
			(xy 42.758507 -376.432093) (xy 42.764771 -376.411046) (xy 42.764761 -376.389087) (xy 42.758479 -376.368045)
			(xy 42.752772 -376.358658) (xy 42.56024 -376.065034) (xy 42.554421 -376.055545) (xy 42.547978 -376.034247)
			(xy 42.54754 -376.023124) (xy 42.54754 -375.82729) (xy 42.548004 -375.815175) (xy 42.555494 -375.792131)
			(xy 42.569738 -375.772529) (xy 42.589342 -375.758288) (xy 42.612387 -375.750802) (xy 42.624502 -375.750328)
			(xy 43.310302 -375.750328) (xy 43.322416 -375.75081) (xy 43.345457 -375.758297) (xy 43.365058 -375.772536)
			(xy 43.3793 -375.792136) (xy 43.386789 -375.815176) (xy 43.387264 -375.82729) (xy 43.387264 -375.842784)
			(xy 47.902876 -375.842784) (xy 47.902876 -375.15673) (xy 47.903334 -375.144638) (xy 47.910786 -375.121633)
			(xy 47.924974 -375.102049) (xy 47.944512 -375.087799) (xy 47.967494 -375.080273) (xy 47.979584 -375.079768)
			(xy 48.174148 -375.079768) (xy 48.185274 -375.080175) (xy 48.206571 -375.086639) (xy 48.216058 -375.092468)
			(xy 48.509682 -375.285) (xy 48.519063 -375.290708) (xy 48.540077 -375.297043) (xy 48.562025 -375.297116)
			(xy 48.58308 -375.290919) (xy 48.592486 -375.285254) (xy 48.88865 -375.092468) (xy 48.898138 -375.086649)
			(xy 48.919437 -375.080207) (xy 48.93056 -375.079768) (xy 49.125124 -375.079768) (xy 49.137197 -375.080244)
			(xy 49.160161 -375.08771) (xy 49.179696 -375.101904) (xy 49.19389 -375.121439) (xy 49.201356 -375.144403)
			(xy 49.201832 -375.156476) (xy 49.201832 -375.84253) (xy 49.201823 -375.842784) (xy 54.710076 -375.842784)
			(xy 54.710076 -375.15673) (xy 54.710534 -375.144638) (xy 54.717986 -375.121633) (xy 54.732174 -375.102049)
			(xy 54.751712 -375.087799) (xy 54.774694 -375.080273) (xy 54.786784 -375.079768) (xy 54.981348 -375.079768)
			(xy 54.992474 -375.080175) (xy 55.013771 -375.086639) (xy 55.023258 -375.092468) (xy 55.316882 -375.285)
			(xy 55.326263 -375.290708) (xy 55.347277 -375.297043) (xy 55.369225 -375.297116) (xy 55.39028 -375.290919)
			(xy 55.399686 -375.285254) (xy 55.69585 -375.092468) (xy 55.705338 -375.086649) (xy 55.726637 -375.080207)
			(xy 55.73776 -375.079768) (xy 55.932324 -375.079768) (xy 55.944397 -375.080244) (xy 55.967361 -375.08771)
			(xy 55.986896 -375.101904) (xy 56.00109 -375.121439) (xy 56.008556 -375.144403) (xy 56.009032 -375.156476)
			(xy 56.009032 -375.84253) (xy 56.009023 -375.842784) (xy 61.517276 -375.842784) (xy 61.517276 -375.15673)
			(xy 61.517734 -375.144638) (xy 61.525186 -375.121633) (xy 61.539374 -375.102049) (xy 61.558912 -375.087799)
			(xy 61.581894 -375.080273) (xy 61.593984 -375.079768) (xy 61.788548 -375.079768) (xy 61.799674 -375.080175)
			(xy 61.820971 -375.086639) (xy 61.830458 -375.092468) (xy 62.124082 -375.285) (xy 62.133463 -375.290708)
			(xy 62.154477 -375.297043) (xy 62.176425 -375.297116) (xy 62.19748 -375.290919) (xy 62.206886 -375.285254)
			(xy 62.50305 -375.092468) (xy 62.512538 -375.086649) (xy 62.533837 -375.080207) (xy 62.54496 -375.079768)
			(xy 62.739524 -375.079768) (xy 62.751597 -375.080244) (xy 62.774561 -375.08771) (xy 62.794096 -375.101904)
			(xy 62.80829 -375.121439) (xy 62.815756 -375.144403) (xy 62.816232 -375.156476) (xy 62.816232 -375.84253)
			(xy 62.815818 -375.854624) (xy 62.808349 -375.87763) (xy 62.79415 -375.897212) (xy 62.774604 -375.911461)
			(xy 62.751617 -375.918987) (xy 62.739524 -375.919492) (xy 62.54496 -375.919492) (xy 62.533835 -375.919072)
			(xy 62.512538 -375.912616) (xy 62.50305 -375.906792) (xy 62.208156 -375.71426) (xy 62.198769 -375.708557)
			(xy 62.177731 -375.702284) (xy 62.155777 -375.702284) (xy 62.134739 -375.708557) (xy 62.125352 -375.71426)
			(xy 61.831728 -375.906792) (xy 61.822222 -375.912579) (xy 61.800937 -375.919041) (xy 61.789818 -375.919492)
			(xy 61.593984 -375.919492) (xy 61.581907 -375.919049) (xy 61.558937 -375.91158) (xy 61.539399 -375.897379)
			(xy 61.525205 -375.877835) (xy 61.517746 -375.854861) (xy 61.517276 -375.842784) (xy 56.009023 -375.842784)
			(xy 56.008618 -375.854624) (xy 56.001149 -375.87763) (xy 55.98695 -375.897212) (xy 55.967404 -375.911461)
			(xy 55.944417 -375.918987) (xy 55.932324 -375.919492) (xy 55.73776 -375.919492) (xy 55.726635 -375.919072)
			(xy 55.705338 -375.912616) (xy 55.69585 -375.906792) (xy 55.400956 -375.71426) (xy 55.391569 -375.708557)
			(xy 55.370531 -375.702284) (xy 55.348577 -375.702284) (xy 55.327539 -375.708557) (xy 55.318152 -375.71426)
			(xy 55.024528 -375.906792) (xy 55.015022 -375.912579) (xy 54.993737 -375.919041) (xy 54.982618 -375.919492)
			(xy 54.786784 -375.919492) (xy 54.774707 -375.919049) (xy 54.751737 -375.91158) (xy 54.732199 -375.897379)
			(xy 54.718005 -375.877835) (xy 54.710546 -375.854861) (xy 54.710076 -375.842784) (xy 49.201823 -375.842784)
			(xy 49.201418 -375.854624) (xy 49.193949 -375.87763) (xy 49.17975 -375.897212) (xy 49.160204 -375.911461)
			(xy 49.137217 -375.918987) (xy 49.125124 -375.919492) (xy 48.93056 -375.919492) (xy 48.919435 -375.919072)
			(xy 48.898138 -375.912616) (xy 48.88865 -375.906792) (xy 48.593756 -375.71426) (xy 48.584369 -375.708557)
			(xy 48.563331 -375.702284) (xy 48.541377 -375.702284) (xy 48.520339 -375.708557) (xy 48.510952 -375.71426)
			(xy 48.217328 -375.906792) (xy 48.207822 -375.912579) (xy 48.186537 -375.919041) (xy 48.175418 -375.919492)
			(xy 47.979584 -375.919492) (xy 47.967507 -375.919049) (xy 47.944537 -375.91158) (xy 47.924999 -375.897379)
			(xy 47.910805 -375.877835) (xy 47.903346 -375.854861) (xy 47.902876 -375.842784) (xy 43.387264 -375.842784)
			(xy 43.387264 -376.021854) (xy 43.386854 -376.03298) (xy 43.380392 -376.054277) (xy 43.374564 -376.063764)
			(xy 43.182032 -376.357388) (xy 43.176317 -376.366766) (xy 43.16998 -376.387781) (xy 43.169909 -376.409731)
			(xy 43.17611 -376.430787) (xy 43.181778 -376.440192) (xy 43.374564 -376.736356) (xy 43.38038 -376.745847)
			(xy 43.386825 -376.767143) (xy 43.387264 -376.778266) (xy 43.387264 -376.97283) (xy 43.386814 -376.984946)
			(xy 43.379319 -377.00799) (xy 43.365071 -377.027591) (xy 43.345465 -377.041832) (xy 43.322418 -377.049318)
			(xy 43.310302 -377.049792) (xy 42.624502 -377.049792) (xy 42.612391 -377.049287) (xy 42.589353 -377.041804)
			(xy 42.569753 -377.027569) (xy 42.555511 -377.007976) (xy 42.548018 -376.984941) (xy 42.54754 -376.97283)
			(xy 41.785477 -376.97283) (xy 41.766194 -377.015053) (xy 41.736708 -377.060934) (xy 41.704765 -377.097798)
			(xy 69.321172 -377.097798) (xy 69.321172 -376.903234) (xy 69.321571 -376.892107) (xy 69.32804 -376.87081)
			(xy 69.333872 -376.861324) (xy 69.526404 -376.56643) (xy 69.532085 -376.557031) (xy 69.538368 -376.535999)
			(xy 69.538375 -376.514048) (xy 69.532105 -376.493012) (xy 69.526404 -376.483626) (xy 69.333872 -376.190002)
			(xy 69.328072 -376.180503) (xy 69.321618 -376.159213) (xy 69.321172 -376.148092) (xy 69.321172 -375.952258)
			(xy 69.321576 -375.940138) (xy 69.329079 -375.917087) (xy 69.343338 -375.897483) (xy 69.362956 -375.883245)
			(xy 69.386013 -375.875764) (xy 69.398134 -375.875296) (xy 70.083934 -375.875296) (xy 70.096046 -375.875782)
			(xy 70.119083 -375.883273) (xy 70.138681 -375.897513) (xy 70.152923 -375.917109) (xy 70.160417 -375.940146)
			(xy 70.160896 -375.952258) (xy 70.160896 -376.146822) (xy 70.160469 -376.157946) (xy 70.154018 -376.179243)
			(xy 70.148196 -376.188732) (xy 69.955664 -376.482356) (xy 69.94998 -376.49175) (xy 69.943643 -376.512758)
			(xy 69.943564 -376.534701) (xy 69.94975 -376.555754) (xy 69.95541 -376.56516) (xy 70.148196 -376.861324)
			(xy 70.154002 -376.87082) (xy 70.160453 -376.892113) (xy 70.160896 -376.903234) (xy 70.160896 -376.956828)
			(xy 70.895972 -376.956828) (xy 70.895972 -376.093228) (xy 70.896458 -376.065959) (xy 70.90422 -376.011975)
			(xy 70.919585 -375.959645) (xy 70.942242 -375.910035) (xy 70.971728 -375.864154) (xy 71.007443 -375.822937)
			(xy 71.04866 -375.787222) (xy 71.094541 -375.757736) (xy 71.144151 -375.735079) (xy 71.196481 -375.719714)
			(xy 71.250465 -375.711952) (xy 71.305003 -375.711952) (xy 71.358987 -375.719714) (xy 71.411317 -375.735079)
			(xy 71.460927 -375.757736) (xy 71.506808 -375.787222) (xy 71.548025 -375.822937) (xy 71.58374 -375.864154)
			(xy 71.613226 -375.910035) (xy 71.635883 -375.959645) (xy 71.651248 -376.011975) (xy 71.65901 -376.065959)
			(xy 71.659496 -376.093228) (xy 71.659496 -376.83186) (xy 73.576688 -376.83186) (xy 73.576688 -375.96826)
			(xy 73.577174 -375.940991) (xy 73.584936 -375.887007) (xy 73.600301 -375.834677) (xy 73.622958 -375.785067)
			(xy 73.652444 -375.739186) (xy 73.688159 -375.697969) (xy 73.729376 -375.662254) (xy 73.775257 -375.632768)
			(xy 73.824867 -375.610111) (xy 73.877197 -375.594746) (xy 73.931181 -375.586984) (xy 73.985719 -375.586984)
			(xy 74.039703 -375.594746) (xy 74.092033 -375.610111) (xy 74.141643 -375.632768) (xy 74.187524 -375.662254)
			(xy 74.228741 -375.697969) (xy 74.264456 -375.739186) (xy 74.293942 -375.785067) (xy 74.316599 -375.834677)
			(xy 74.331964 -375.887007) (xy 74.339726 -375.940991) (xy 74.340212 -375.96826) (xy 74.340212 -376.83186)
			(xy 74.339726 -376.859129) (xy 74.331964 -376.913113) (xy 74.316599 -376.965443) (xy 74.313225 -376.97283)
			(xy 75.075288 -376.97283) (xy 75.075288 -376.778266) (xy 75.075713 -376.767141) (xy 75.082166 -376.745845)
			(xy 75.087988 -376.736356) (xy 75.28052 -376.441462) (xy 75.286259 -376.432095) (xy 75.292527 -376.411047)
			(xy 75.292517 -376.389086) (xy 75.28623 -376.368044) (xy 75.28052 -376.358658) (xy 75.087988 -376.065034)
			(xy 75.082165 -376.055548) (xy 75.075725 -376.034247) (xy 75.075288 -376.023124) (xy 75.075288 -375.82729)
			(xy 75.075803 -375.81518) (xy 75.083287 -375.792145) (xy 75.097519 -375.772548) (xy 75.117109 -375.758305)
			(xy 75.14014 -375.750809) (xy 75.15225 -375.750328) (xy 75.83805 -375.750328) (xy 75.850166 -375.750769)
			(xy 75.873209 -375.758269) (xy 75.892809 -375.772519) (xy 75.90705 -375.792127) (xy 75.914537 -375.815174)
			(xy 75.915012 -375.82729) (xy 75.915012 -375.842784) (xy 80.430624 -375.842784) (xy 80.430624 -375.15673)
			(xy 80.431133 -375.144644) (xy 80.438579 -375.121647) (xy 80.452756 -375.102068) (xy 80.47228 -375.087815)
			(xy 80.495247 -375.08028) (xy 80.507332 -375.079768) (xy 80.701896 -375.079768) (xy 80.71302 -375.080196)
			(xy 80.734318 -375.086646) (xy 80.743806 -375.092468) (xy 81.03743 -375.285) (xy 81.046788 -375.290749)
			(xy 81.067813 -375.297075) (xy 81.089769 -375.297136) (xy 81.110828 -375.290927) (xy 81.120234 -375.285254)
			(xy 81.416398 -375.092468) (xy 81.425897 -375.086668) (xy 81.447187 -375.080214) (xy 81.458308 -375.079768)
			(xy 81.652872 -375.079768) (xy 81.664951 -375.080236) (xy 81.687929 -375.087693) (xy 81.707477 -375.101886)
			(xy 81.721683 -375.121425) (xy 81.729156 -375.144397) (xy 81.72958 -375.156476) (xy 81.72958 -375.84253)
			(xy 81.72957 -375.842784) (xy 87.237824 -375.842784) (xy 87.237824 -375.15673) (xy 87.238333 -375.144644)
			(xy 87.245779 -375.121647) (xy 87.259956 -375.102068) (xy 87.27948 -375.087815) (xy 87.302447 -375.08028)
			(xy 87.314532 -375.079768) (xy 87.509096 -375.079768) (xy 87.52022 -375.080196) (xy 87.541518 -375.086646)
			(xy 87.551006 -375.092468) (xy 87.84463 -375.285) (xy 87.853988 -375.290749) (xy 87.875013 -375.297075)
			(xy 87.896969 -375.297136) (xy 87.918028 -375.290927) (xy 87.927434 -375.285254) (xy 88.223598 -375.092468)
			(xy 88.233097 -375.086668) (xy 88.254387 -375.080214) (xy 88.265508 -375.079768) (xy 88.460072 -375.079768)
			(xy 88.472151 -375.080236) (xy 88.495129 -375.087693) (xy 88.514677 -375.101886) (xy 88.528883 -375.121425)
			(xy 88.536356 -375.144397) (xy 88.53678 -375.156476) (xy 88.53678 -375.84253) (xy 88.53677 -375.842784)
			(xy 94.045024 -375.842784) (xy 94.045024 -375.15673) (xy 94.045533 -375.144644) (xy 94.052979 -375.121647)
			(xy 94.067156 -375.102068) (xy 94.08668 -375.087815) (xy 94.109647 -375.08028) (xy 94.121732 -375.079768)
			(xy 94.316296 -375.079768) (xy 94.32742 -375.080196) (xy 94.348718 -375.086646) (xy 94.358206 -375.092468)
			(xy 94.65183 -375.285) (xy 94.661188 -375.290749) (xy 94.682213 -375.297075) (xy 94.704169 -375.297136)
			(xy 94.725228 -375.290927) (xy 94.734634 -375.285254) (xy 95.030798 -375.092468) (xy 95.040297 -375.086668)
			(xy 95.061587 -375.080214) (xy 95.072708 -375.079768) (xy 95.267272 -375.079768) (xy 95.279351 -375.080236)
			(xy 95.302329 -375.087693) (xy 95.321877 -375.101886) (xy 95.336083 -375.121425) (xy 95.343556 -375.144397)
			(xy 95.34398 -375.156476) (xy 95.34398 -375.84253) (xy 95.343519 -375.854619) (xy 95.336056 -375.877617)
			(xy 95.321867 -375.897195) (xy 95.302334 -375.911445) (xy 95.27936 -375.91898) (xy 95.267272 -375.919492)
			(xy 95.072708 -375.919492) (xy 95.061585 -375.919053) (xy 95.040288 -375.91261) (xy 95.030798 -375.906792)
			(xy 94.735904 -375.71426) (xy 94.726517 -375.708557) (xy 94.705479 -375.702284) (xy 94.683525 -375.702284)
			(xy 94.662487 -375.708557) (xy 94.6531 -375.71426) (xy 94.359476 -375.906792) (xy 94.34998 -375.912598)
			(xy 94.328687 -375.919049) (xy 94.317566 -375.919492) (xy 94.121732 -375.919492) (xy 94.109649 -375.91906)
			(xy 94.086665 -375.911599) (xy 94.067113 -375.897399) (xy 94.052908 -375.877849) (xy 94.045443 -375.854867)
			(xy 94.045024 -375.842784) (xy 88.53677 -375.842784) (xy 88.536319 -375.854619) (xy 88.528856 -375.877617)
			(xy 88.514667 -375.897195) (xy 88.495134 -375.911445) (xy 88.47216 -375.91898) (xy 88.460072 -375.919492)
			(xy 88.265508 -375.919492) (xy 88.254385 -375.919053) (xy 88.233088 -375.91261) (xy 88.223598 -375.906792)
			(xy 87.928704 -375.71426) (xy 87.919317 -375.708557) (xy 87.898279 -375.702284) (xy 87.876325 -375.702284)
			(xy 87.855287 -375.708557) (xy 87.8459 -375.71426) (xy 87.552276 -375.906792) (xy 87.54278 -375.912598)
			(xy 87.521487 -375.919049) (xy 87.510366 -375.919492) (xy 87.314532 -375.919492) (xy 87.302449 -375.91906)
			(xy 87.279465 -375.911599) (xy 87.259913 -375.897399) (xy 87.245708 -375.877849) (xy 87.238243 -375.854867)
			(xy 87.237824 -375.842784) (xy 81.72957 -375.842784) (xy 81.729119 -375.854619) (xy 81.721656 -375.877617)
			(xy 81.707467 -375.897195) (xy 81.687934 -375.911445) (xy 81.66496 -375.91898) (xy 81.652872 -375.919492)
			(xy 81.458308 -375.919492) (xy 81.447185 -375.919053) (xy 81.425888 -375.91261) (xy 81.416398 -375.906792)
			(xy 81.121504 -375.71426) (xy 81.112117 -375.708557) (xy 81.091079 -375.702284) (xy 81.069125 -375.702284)
			(xy 81.048087 -375.708557) (xy 81.0387 -375.71426) (xy 80.745076 -375.906792) (xy 80.73558 -375.912598)
			(xy 80.714287 -375.919049) (xy 80.703166 -375.919492) (xy 80.507332 -375.919492) (xy 80.495249 -375.91906)
			(xy 80.472265 -375.911599) (xy 80.452713 -375.897399) (xy 80.438508 -375.877849) (xy 80.431043 -375.854867)
			(xy 80.430624 -375.842784) (xy 75.915012 -375.842784) (xy 75.915012 -376.021854) (xy 75.914595 -376.032979)
			(xy 75.908137 -376.054276) (xy 75.902312 -376.063764) (xy 75.70978 -376.357388) (xy 75.704068 -376.366767)
			(xy 75.697735 -376.387782) (xy 75.697664 -376.40973) (xy 75.703861 -376.430786) (xy 75.709526 -376.440192)
			(xy 75.902312 -376.736356) (xy 75.908131 -376.745844) (xy 75.914573 -376.767143) (xy 75.915012 -376.778266)
			(xy 75.915012 -376.97283) (xy 75.914515 -376.984941) (xy 75.907025 -377.007977) (xy 75.892788 -377.027574)
			(xy 75.873195 -377.041816) (xy 75.850161 -377.049312) (xy 75.83805 -377.049792) (xy 75.15225 -377.049792)
			(xy 75.140136 -377.049331) (xy 75.117096 -377.041834) (xy 75.097498 -377.027588) (xy 75.083257 -377.007986)
			(xy 75.075766 -376.984944) (xy 75.075288 -376.97283) (xy 74.313225 -376.97283) (xy 74.293942 -377.015053)
			(xy 74.264456 -377.060934) (xy 74.232513 -377.097798) (xy 101.84892 -377.097798) (xy 101.84892 -376.903234)
			(xy 101.849327 -376.892108) (xy 101.855792 -376.870811) (xy 101.86162 -376.861324) (xy 102.054152 -376.56643)
			(xy 102.059831 -376.55703) (xy 102.066109 -376.535998) (xy 102.066116 -376.514049) (xy 102.05985 -376.493013)
			(xy 102.054152 -376.483626) (xy 101.86162 -376.190002) (xy 101.855824 -376.180501) (xy 101.849367 -376.159212)
			(xy 101.84892 -376.148092) (xy 101.84892 -375.952258) (xy 101.849376 -375.940143) (xy 101.856872 -375.917101)
			(xy 101.871119 -375.897502) (xy 101.890723 -375.883261) (xy 101.913767 -375.875772) (xy 101.925882 -375.875296)
			(xy 102.611682 -375.875296) (xy 102.623791 -375.875826) (xy 102.646827 -375.883304) (xy 102.666425 -375.897532)
			(xy 102.680669 -375.917119) (xy 102.688164 -375.940149) (xy 102.688644 -375.952258) (xy 102.688644 -376.146822)
			(xy 102.688225 -376.157947) (xy 102.681769 -376.179244) (xy 102.675944 -376.188732) (xy 102.483412 -376.482356)
			(xy 102.477726 -376.491749) (xy 102.471384 -376.512757) (xy 102.471305 -376.534701) (xy 102.477495 -376.555755)
			(xy 102.483158 -376.56516) (xy 102.675944 -376.861324) (xy 102.681746 -376.870822) (xy 102.6882 -376.892113)
			(xy 102.688644 -376.903234) (xy 102.688644 -376.956828) (xy 103.42372 -376.956828) (xy 103.42372 -376.093228)
			(xy 103.424206 -376.065959) (xy 103.431968 -376.011975) (xy 103.447333 -375.959645) (xy 103.46999 -375.910035)
			(xy 103.499476 -375.864154) (xy 103.535191 -375.822937) (xy 103.576408 -375.787222) (xy 103.622289 -375.757736)
			(xy 103.671899 -375.735079) (xy 103.724229 -375.719714) (xy 103.778213 -375.711952) (xy 103.832751 -375.711952)
			(xy 103.886735 -375.719714) (xy 103.939065 -375.735079) (xy 103.988675 -375.757736) (xy 104.034556 -375.787222)
			(xy 104.075773 -375.822937) (xy 104.111488 -375.864154) (xy 104.140974 -375.910035) (xy 104.163631 -375.959645)
			(xy 104.178996 -376.011975) (xy 104.186758 -376.065959) (xy 104.187244 -376.093228) (xy 104.187244 -376.83186)
			(xy 108.149136 -376.83186) (xy 108.149136 -375.96826) (xy 108.149622 -375.941009) (xy 108.157378 -375.887061)
			(xy 108.172733 -375.834766) (xy 108.195375 -375.785189) (xy 108.224841 -375.739339) (xy 108.260532 -375.698148)
			(xy 108.301723 -375.662457) (xy 108.347573 -375.632991) (xy 108.39715 -375.610349) (xy 108.449445 -375.594994)
			(xy 108.503393 -375.587238) (xy 108.557895 -375.587238) (xy 108.611843 -375.594994) (xy 108.664138 -375.610349)
			(xy 108.713715 -375.632991) (xy 108.759565 -375.662457) (xy 108.800756 -375.698148) (xy 108.836447 -375.739339)
			(xy 108.865913 -375.785189) (xy 108.888555 -375.834766) (xy 108.90391 -375.887061) (xy 108.911666 -375.941009)
			(xy 108.912152 -375.96826) (xy 108.912152 -376.83186) (xy 108.911666 -376.859111) (xy 108.90391 -376.913059)
			(xy 108.888555 -376.965354) (xy 108.885025 -376.973084) (xy 109.647736 -376.973084) (xy 109.647736 -376.778266)
			(xy 109.648099 -376.767158) (xy 109.654424 -376.745862) (xy 109.660182 -376.736356) (xy 109.852714 -376.441462)
			(xy 109.858453 -376.432095) (xy 109.864722 -376.411047) (xy 109.864712 -376.389086) (xy 109.858425 -376.368044)
			(xy 109.852714 -376.358658) (xy 109.660182 -376.065034) (xy 109.654432 -376.055525) (xy 109.648108 -376.034231)
			(xy 109.647736 -376.023124) (xy 109.647736 -375.82729) (xy 109.648199 -375.8152) (xy 109.655658 -375.7922)
			(xy 109.669846 -375.772621) (xy 109.68938 -375.758371) (xy 109.712356 -375.750838) (xy 109.724444 -375.750328)
			(xy 110.410244 -375.750328) (xy 110.422324 -375.750727) (xy 110.445299 -375.758206) (xy 110.464839 -375.772418)
			(xy 110.47903 -375.791973) (xy 110.486485 -375.814955) (xy 110.486952 -375.827036) (xy 110.486952 -375.84253)
			(xy 115.002564 -375.84253) (xy 115.002564 -375.15673) (xy 115.002986 -375.144606) (xy 115.010473 -375.121544)
			(xy 115.024723 -375.101926) (xy 115.04434 -375.087675) (xy 115.067402 -375.080186) (xy 115.079526 -375.079768)
			(xy 115.27409 -375.079768) (xy 115.285214 -375.080199) (xy 115.306511 -375.086646) (xy 115.316 -375.092468)
			(xy 115.609624 -375.285) (xy 115.618985 -375.290744) (xy 115.640008 -375.297071) (xy 115.661963 -375.297134)
			(xy 115.683022 -375.290926) (xy 115.692428 -375.285254) (xy 115.988592 -375.092468) (xy 115.998092 -375.08667)
			(xy 116.019382 -375.080215) (xy 116.030502 -375.079768) (xy 116.225066 -375.079768) (xy 116.23719 -375.080189)
			(xy 116.260253 -375.087676) (xy 116.279871 -375.101926) (xy 116.294122 -375.121544) (xy 116.30161 -375.144606)
			(xy 116.302028 -375.15673) (xy 116.302028 -375.84253) (xy 121.809764 -375.84253) (xy 121.809764 -375.15673)
			(xy 121.810186 -375.144606) (xy 121.817673 -375.121544) (xy 121.831923 -375.101926) (xy 121.85154 -375.087675)
			(xy 121.874602 -375.080186) (xy 121.886726 -375.079768) (xy 122.08129 -375.079768) (xy 122.092414 -375.080199)
			(xy 122.113711 -375.086646) (xy 122.1232 -375.092468) (xy 122.416824 -375.285) (xy 122.426185 -375.290744)
			(xy 122.447208 -375.297071) (xy 122.469163 -375.297134) (xy 122.490222 -375.290926) (xy 122.499628 -375.285254)
			(xy 122.795792 -375.092468) (xy 122.805292 -375.08667) (xy 122.826582 -375.080215) (xy 122.837702 -375.079768)
			(xy 123.032266 -375.079768) (xy 123.04439 -375.080189) (xy 123.067453 -375.087676) (xy 123.087071 -375.101926)
			(xy 123.101322 -375.121544) (xy 123.10881 -375.144606) (xy 123.109228 -375.15673) (xy 123.109228 -375.84253)
			(xy 128.616964 -375.84253) (xy 128.616964 -375.15673) (xy 128.617386 -375.144606) (xy 128.624873 -375.121544)
			(xy 128.639123 -375.101926) (xy 128.65874 -375.087675) (xy 128.681802 -375.080186) (xy 128.693926 -375.079768)
			(xy 128.88849 -375.079768) (xy 128.899614 -375.080199) (xy 128.920911 -375.086646) (xy 128.9304 -375.092468)
			(xy 129.224024 -375.285) (xy 129.233385 -375.290744) (xy 129.254408 -375.297071) (xy 129.276363 -375.297134)
			(xy 129.297422 -375.290926) (xy 129.306828 -375.285254) (xy 129.602992 -375.092468) (xy 129.612492 -375.08667)
			(xy 129.633782 -375.080215) (xy 129.644902 -375.079768) (xy 129.839466 -375.079768) (xy 129.85159 -375.080189)
			(xy 129.874653 -375.087676) (xy 129.894271 -375.101926) (xy 129.908522 -375.121544) (xy 129.91601 -375.144606)
			(xy 129.916428 -375.15673) (xy 129.916428 -375.84253) (xy 129.916065 -375.854658) (xy 129.908561 -375.877723)
			(xy 129.894295 -375.897341) (xy 129.874666 -375.91159) (xy 129.851594 -375.919075) (xy 129.839466 -375.919492)
			(xy 129.644902 -375.919492) (xy 129.633778 -375.919056) (xy 129.612482 -375.912611) (xy 129.602992 -375.906792)
			(xy 129.308098 -375.71426) (xy 129.298711 -375.708557) (xy 129.277673 -375.702284) (xy 129.255719 -375.702284)
			(xy 129.234681 -375.708557) (xy 129.225294 -375.71426) (xy 128.93167 -375.906792) (xy 128.922175 -375.9126)
			(xy 128.900882 -375.919049) (xy 128.88976 -375.919492) (xy 128.693926 -375.919492) (xy 128.681816 -375.918967)
			(xy 128.658778 -375.91149) (xy 128.639179 -375.897261) (xy 128.624935 -375.877672) (xy 128.617442 -375.85464)
			(xy 128.616964 -375.84253) (xy 123.109228 -375.84253) (xy 123.108865 -375.854658) (xy 123.101361 -375.877723)
			(xy 123.087095 -375.897341) (xy 123.067466 -375.91159) (xy 123.044394 -375.919075) (xy 123.032266 -375.919492)
			(xy 122.837702 -375.919492) (xy 122.826578 -375.919056) (xy 122.805282 -375.912611) (xy 122.795792 -375.906792)
			(xy 122.500898 -375.71426) (xy 122.491511 -375.708557) (xy 122.470473 -375.702284) (xy 122.448519 -375.702284)
			(xy 122.427481 -375.708557) (xy 122.418094 -375.71426) (xy 122.12447 -375.906792) (xy 122.114975 -375.9126)
			(xy 122.093682 -375.919049) (xy 122.08256 -375.919492) (xy 121.886726 -375.919492) (xy 121.874616 -375.918967)
			(xy 121.851578 -375.91149) (xy 121.831979 -375.897261) (xy 121.817735 -375.877672) (xy 121.810242 -375.85464)
			(xy 121.809764 -375.84253) (xy 116.302028 -375.84253) (xy 116.301665 -375.854658) (xy 116.294161 -375.877723)
			(xy 116.279895 -375.897341) (xy 116.260266 -375.91159) (xy 116.237194 -375.919075) (xy 116.225066 -375.919492)
			(xy 116.030502 -375.919492) (xy 116.019378 -375.919056) (xy 115.998082 -375.912611) (xy 115.988592 -375.906792)
			(xy 115.693698 -375.71426) (xy 115.684311 -375.708557) (xy 115.663273 -375.702284) (xy 115.641319 -375.702284)
			(xy 115.620281 -375.708557) (xy 115.610894 -375.71426) (xy 115.31727 -375.906792) (xy 115.307775 -375.9126)
			(xy 115.286482 -375.919049) (xy 115.27536 -375.919492) (xy 115.079526 -375.919492) (xy 115.067416 -375.918967)
			(xy 115.044378 -375.91149) (xy 115.024779 -375.897261) (xy 115.010535 -375.877672) (xy 115.003042 -375.85464)
			(xy 115.002564 -375.84253) (xy 110.486952 -375.84253) (xy 110.486952 -376.021854) (xy 110.486577 -376.032959)
			(xy 110.48025 -376.054251) (xy 110.474506 -376.063764) (xy 110.281974 -376.357388) (xy 110.276262 -376.366767)
			(xy 110.26993 -376.387782) (xy 110.269859 -376.40973) (xy 110.276055 -376.430786) (xy 110.28172 -376.440192)
			(xy 110.474506 -376.736356) (xy 110.480252 -376.745868) (xy 110.486579 -376.76716) (xy 110.486952 -376.778266)
			(xy 110.486952 -376.97283) (xy 110.486518 -376.984922) (xy 110.479052 -377.007925) (xy 110.464857 -377.027505)
			(xy 110.445317 -377.041754) (xy 110.422335 -377.049284) (xy 110.410244 -377.049792) (xy 109.724444 -377.049792)
			(xy 109.712362 -377.04935) (xy 109.689378 -377.041892) (xy 109.669826 -377.027694) (xy 109.655621 -377.008147)
			(xy 109.648155 -376.985166) (xy 109.647736 -376.973084) (xy 108.885025 -376.973084) (xy 108.865913 -377.014931)
			(xy 108.836447 -377.060781) (xy 108.804153 -377.098052) (xy 136.421368 -377.098052) (xy 136.421368 -376.903234)
			(xy 136.421714 -376.892124) (xy 136.42805 -376.870828) (xy 136.433814 -376.861324) (xy 136.626346 -376.56643)
			(xy 136.632025 -376.55703) (xy 136.638304 -376.535998) (xy 136.638311 -376.514049) (xy 136.632045 -376.493012)
			(xy 136.626346 -376.483626) (xy 136.433814 -376.190002) (xy 136.428054 -376.180498) (xy 136.421735 -376.1592)
			(xy 136.421368 -376.148092) (xy 136.421368 -375.952258) (xy 136.421772 -375.940163) (xy 136.429244 -375.917157)
			(xy 136.443446 -375.897575) (xy 136.462994 -375.883327) (xy 136.485983 -375.875801) (xy 136.498076 -375.875296)
			(xy 137.183876 -375.875296) (xy 137.195958 -375.875733) (xy 137.21894 -375.883195) (xy 137.238491 -375.897394)
			(xy 137.252696 -375.916942) (xy 137.260164 -375.939922) (xy 137.260584 -375.952004) (xy 137.260584 -376.146822)
			(xy 137.260191 -376.157926) (xy 137.253875 -376.179218) (xy 137.248138 -376.188732) (xy 137.055606 -376.482356)
			(xy 137.04992 -376.491749) (xy 137.043579 -376.512757) (xy 137.0435 -376.534701) (xy 137.04969 -376.555755)
			(xy 137.055352 -376.56516) (xy 137.248138 -376.861324) (xy 137.253875 -376.870841) (xy 137.260207 -376.892129)
			(xy 137.260584 -376.903234) (xy 137.260584 -376.956828) (xy 137.996168 -376.956828) (xy 137.996168 -376.093228)
			(xy 137.996654 -376.065977) (xy 138.00441 -376.012029) (xy 138.019765 -375.959734) (xy 138.042407 -375.910157)
			(xy 138.071873 -375.864307) (xy 138.107564 -375.823116) (xy 138.148755 -375.787425) (xy 138.194605 -375.757959)
			(xy 138.244182 -375.735317) (xy 138.296477 -375.719962) (xy 138.350425 -375.712206) (xy 138.404927 -375.712206)
			(xy 138.458875 -375.719962) (xy 138.51117 -375.735317) (xy 138.560747 -375.757959) (xy 138.606597 -375.787425)
			(xy 138.647788 -375.823116) (xy 138.683479 -375.864307) (xy 138.712945 -375.910157) (xy 138.735587 -375.959734)
			(xy 138.750942 -376.012029) (xy 138.758698 -376.065977) (xy 138.759184 -376.093228) (xy 138.759184 -376.83186)
			(xy 140.676884 -376.83186) (xy 140.676884 -375.96826) (xy 140.67737 -375.941009) (xy 140.685126 -375.887061)
			(xy 140.700481 -375.834766) (xy 140.723123 -375.785189) (xy 140.752589 -375.739339) (xy 140.78828 -375.698148)
			(xy 140.829471 -375.662457) (xy 140.875321 -375.632991) (xy 140.924898 -375.610349) (xy 140.977193 -375.594994)
			(xy 141.031141 -375.587238) (xy 141.085643 -375.587238) (xy 141.139591 -375.594994) (xy 141.191886 -375.610349)
			(xy 141.241463 -375.632991) (xy 141.287313 -375.662457) (xy 141.328504 -375.698148) (xy 141.364195 -375.739339)
			(xy 141.393661 -375.785189) (xy 141.416303 -375.834766) (xy 141.431658 -375.887061) (xy 141.439414 -375.941009)
			(xy 141.4399 -375.96826) (xy 141.4399 -376.83186) (xy 141.439414 -376.859111) (xy 141.431658 -376.913059)
			(xy 141.416303 -376.965354) (xy 141.412773 -376.973084) (xy 142.175484 -376.973084) (xy 142.175484 -376.778266)
			(xy 142.175855 -376.767159) (xy 142.182175 -376.745863) (xy 142.18793 -376.736356) (xy 142.380462 -376.441462)
			(xy 142.386198 -376.432094) (xy 142.392463 -376.411047) (xy 142.392453 -376.389087) (xy 142.386169 -376.368045)
			(xy 142.380462 -376.358658) (xy 142.18793 -376.065034) (xy 142.182183 -376.055523) (xy 142.175856 -376.03423)
			(xy 142.175484 -376.023124) (xy 142.175484 -375.82729) (xy 142.1759 -375.815196) (xy 142.183365 -375.792187)
			(xy 142.197563 -375.772604) (xy 142.21711 -375.758355) (xy 142.240099 -375.750831) (xy 142.252192 -375.750328)
			(xy 142.937992 -375.750328) (xy 142.950078 -375.75072) (xy 142.973067 -375.758189) (xy 142.99262 -375.7724)
			(xy 143.006823 -375.791959) (xy 143.014285 -375.81495) (xy 143.0147 -375.827036) (xy 143.0147 -375.84253)
			(xy 147.530312 -375.84253) (xy 147.530312 -375.15673) (xy 147.530785 -375.144611) (xy 147.538266 -375.121558)
			(xy 147.552505 -375.101945) (xy 147.572108 -375.087692) (xy 147.595156 -375.080194) (xy 147.607274 -375.079768)
			(xy 147.801838 -375.079768) (xy 147.812964 -375.080179) (xy 147.834261 -375.08664) (xy 147.843748 -375.092468)
			(xy 148.137372 -375.285) (xy 148.146758 -375.290699) (xy 148.167769 -375.297036) (xy 148.189716 -375.297112)
			(xy 148.21077 -375.290918) (xy 148.220176 -375.285254) (xy 148.51634 -375.092468) (xy 148.52583 -375.086652)
			(xy 148.547128 -375.080208) (xy 148.55825 -375.079768) (xy 148.752814 -375.079768) (xy 148.76494 -375.080149)
			(xy 148.788005 -375.087648) (xy 148.807622 -375.101909) (xy 148.821872 -375.121535) (xy 148.829358 -375.144603)
			(xy 148.829776 -375.15673) (xy 148.829776 -375.84253) (xy 154.337512 -375.84253) (xy 154.337512 -375.15673)
			(xy 154.337985 -375.144611) (xy 154.345466 -375.121558) (xy 154.359705 -375.101945) (xy 154.379308 -375.087692)
			(xy 154.402356 -375.080194) (xy 154.414474 -375.079768) (xy 154.609038 -375.079768) (xy 154.620164 -375.080179)
			(xy 154.641461 -375.08664) (xy 154.650948 -375.092468) (xy 154.944572 -375.285) (xy 154.953958 -375.290699)
			(xy 154.974969 -375.297036) (xy 154.996916 -375.297112) (xy 155.01797 -375.290918) (xy 155.027376 -375.285254)
			(xy 155.32354 -375.092468) (xy 155.33303 -375.086652) (xy 155.354328 -375.080208) (xy 155.36545 -375.079768)
			(xy 155.560014 -375.079768) (xy 155.57214 -375.080149) (xy 155.595205 -375.087648) (xy 155.614822 -375.101909)
			(xy 155.629072 -375.121535) (xy 155.636558 -375.144603) (xy 155.636976 -375.15673) (xy 155.636976 -375.84253)
			(xy 161.144712 -375.84253) (xy 161.144712 -375.15673) (xy 161.145185 -375.144611) (xy 161.152666 -375.121558)
			(xy 161.166905 -375.101945) (xy 161.186508 -375.087692) (xy 161.209556 -375.080194) (xy 161.221674 -375.079768)
			(xy 161.416238 -375.079768) (xy 161.427364 -375.080179) (xy 161.448661 -375.08664) (xy 161.458148 -375.092468)
			(xy 161.751772 -375.285) (xy 161.761158 -375.290699) (xy 161.782169 -375.297036) (xy 161.804116 -375.297112)
			(xy 161.82517 -375.290918) (xy 161.834576 -375.285254) (xy 162.13074 -375.092468) (xy 162.14023 -375.086652)
			(xy 162.161528 -375.080208) (xy 162.17265 -375.079768) (xy 162.367214 -375.079768) (xy 162.37934 -375.080149)
			(xy 162.402405 -375.087648) (xy 162.422022 -375.101909) (xy 162.436272 -375.121535) (xy 162.443758 -375.144603)
			(xy 162.444176 -375.15673) (xy 162.444176 -375.84253) (xy 162.443714 -375.854645) (xy 162.43622 -375.877687)
			(xy 162.421975 -375.897287) (xy 162.402372 -375.911528) (xy 162.379329 -375.919017) (xy 162.367214 -375.919492)
			(xy 162.17265 -375.919492) (xy 162.161525 -375.919076) (xy 162.140228 -375.912618) (xy 162.13074 -375.906792)
			(xy 161.835846 -375.71426) (xy 161.826459 -375.708557) (xy 161.805421 -375.702284) (xy 161.783467 -375.702284)
			(xy 161.762429 -375.708557) (xy 161.753042 -375.71426) (xy 161.459418 -375.906792) (xy 161.449914 -375.912583)
			(xy 161.428627 -375.919043) (xy 161.417508 -375.919492) (xy 161.221674 -375.919492) (xy 161.209561 -375.919011)
			(xy 161.186522 -375.91152) (xy 161.166923 -375.89728) (xy 161.152682 -375.877682) (xy 161.14519 -375.854643)
			(xy 161.144712 -375.84253) (xy 155.636976 -375.84253) (xy 155.636514 -375.854645) (xy 155.62902 -375.877687)
			(xy 155.614775 -375.897287) (xy 155.595172 -375.911528) (xy 155.572129 -375.919017) (xy 155.560014 -375.919492)
			(xy 155.36545 -375.919492) (xy 155.354325 -375.919076) (xy 155.333028 -375.912618) (xy 155.32354 -375.906792)
			(xy 155.028646 -375.71426) (xy 155.019259 -375.708557) (xy 154.998221 -375.702284) (xy 154.976267 -375.702284)
			(xy 154.955229 -375.708557) (xy 154.945842 -375.71426) (xy 154.652218 -375.906792) (xy 154.642714 -375.912583)
			(xy 154.621427 -375.919043) (xy 154.610308 -375.919492) (xy 154.414474 -375.919492) (xy 154.402361 -375.919011)
			(xy 154.379322 -375.91152) (xy 154.359723 -375.89728) (xy 154.345482 -375.877682) (xy 154.33799 -375.854643)
			(xy 154.337512 -375.84253) (xy 148.829776 -375.84253) (xy 148.829314 -375.854645) (xy 148.82182 -375.877687)
			(xy 148.807575 -375.897287) (xy 148.787972 -375.911528) (xy 148.764929 -375.919017) (xy 148.752814 -375.919492)
			(xy 148.55825 -375.919492) (xy 148.547125 -375.919076) (xy 148.525828 -375.912618) (xy 148.51634 -375.906792)
			(xy 148.221446 -375.71426) (xy 148.212059 -375.708557) (xy 148.191021 -375.702284) (xy 148.169067 -375.702284)
			(xy 148.148029 -375.708557) (xy 148.138642 -375.71426) (xy 147.845018 -375.906792) (xy 147.835514 -375.912583)
			(xy 147.814227 -375.919043) (xy 147.803108 -375.919492) (xy 147.607274 -375.919492) (xy 147.595161 -375.919011)
			(xy 147.572122 -375.91152) (xy 147.552523 -375.89728) (xy 147.538282 -375.877682) (xy 147.53079 -375.854643)
			(xy 147.530312 -375.84253) (xy 143.0147 -375.84253) (xy 143.0147 -376.021854) (xy 143.014318 -376.032959)
			(xy 143.007994 -376.05425) (xy 143.002254 -376.063764) (xy 142.809722 -376.357388) (xy 142.804008 -376.366766)
			(xy 142.797672 -376.387781) (xy 142.7976 -376.409731) (xy 142.8038 -376.430787) (xy 142.809468 -376.440192)
			(xy 143.002254 -376.736356) (xy 143.008004 -376.745865) (xy 143.014328 -376.76716) (xy 143.0147 -376.778266)
			(xy 143.0147 -376.97283) (xy 143.014219 -376.984917) (xy 143.006759 -377.007912) (xy 142.992574 -377.027488)
			(xy 142.973047 -377.041739) (xy 142.950078 -377.049277) (xy 142.937992 -377.049792) (xy 142.252192 -377.049792)
			(xy 142.240107 -377.049394) (xy 142.217121 -377.041922) (xy 142.19757 -377.027713) (xy 142.183367 -377.008157)
			(xy 142.175902 -376.985169) (xy 142.175484 -376.973084) (xy 141.412773 -376.973084) (xy 141.393661 -377.014931)
			(xy 141.364195 -377.060781) (xy 141.331901 -377.098052) (xy 168.949116 -377.098052) (xy 168.949116 -376.903234)
			(xy 168.94947 -376.892125) (xy 168.955801 -376.870829) (xy 168.961562 -376.861324) (xy 169.154094 -376.56643)
			(xy 169.15977 -376.557029) (xy 169.166045 -376.535997) (xy 169.166051 -376.514049) (xy 169.15979 -376.493014)
			(xy 169.154094 -376.483626) (xy 168.961562 -376.190002) (xy 168.955798 -376.1805) (xy 168.949483 -376.1592)
			(xy 168.949116 -376.148092) (xy 168.949116 -375.952258) (xy 168.949571 -375.940169) (xy 168.957036 -375.917171)
			(xy 168.971227 -375.897593) (xy 168.990761 -375.883343) (xy 169.013736 -375.875808) (xy 169.025824 -375.875296)
			(xy 169.711624 -375.875296) (xy 169.7237 -375.875744) (xy 169.746669 -375.883214) (xy 169.766206 -375.897414)
			(xy 169.780399 -375.916956) (xy 169.78786 -375.939928) (xy 169.788332 -375.952004) (xy 169.788332 -376.146822)
			(xy 169.787947 -376.157927) (xy 169.781626 -376.179219) (xy 169.775886 -376.188732) (xy 169.583354 -376.482356)
			(xy 169.577665 -376.491748) (xy 169.57132 -376.512757) (xy 169.571241 -376.534702) (xy 169.577435 -376.555756)
			(xy 169.5831 -376.56516) (xy 169.775886 -376.861324) (xy 169.781618 -376.870843) (xy 169.787954 -376.89213)
			(xy 169.788332 -376.903234) (xy 169.788332 -376.956828) (xy 170.523916 -376.956828) (xy 170.523916 -376.093228)
			(xy 170.524402 -376.065977) (xy 170.532158 -376.012029) (xy 170.547513 -375.959734) (xy 170.570155 -375.910157)
			(xy 170.599621 -375.864307) (xy 170.635312 -375.823116) (xy 170.676503 -375.787425) (xy 170.722353 -375.757959)
			(xy 170.77193 -375.735317) (xy 170.824225 -375.719962) (xy 170.878173 -375.712206) (xy 170.932675 -375.712206)
			(xy 170.986623 -375.719962) (xy 171.038918 -375.735317) (xy 171.088495 -375.757959) (xy 171.134345 -375.787425)
			(xy 171.175536 -375.823116) (xy 171.211227 -375.864307) (xy 171.240693 -375.910157) (xy 171.263335 -375.959734)
			(xy 171.27869 -376.012029) (xy 171.286446 -376.065977) (xy 171.286932 -376.093228) (xy 171.286932 -376.489976)
			(xy 173.498776 -376.489976) (xy 173.502748 -376.311733) (xy 173.514656 -376.133844) (xy 173.534477 -375.956662)
			(xy 173.562171 -375.780538) (xy 173.597683 -375.605823) (xy 173.640943 -375.432864) (xy 173.691865 -375.262003)
			(xy 173.750348 -375.093581) (xy 173.816275 -374.927931) (xy 173.889516 -374.765382) (xy 173.969926 -374.606257)
			(xy 174.057344 -374.450872) (xy 174.151597 -374.299536) (xy 174.252498 -374.152548) (xy 174.359847 -374.010201)
			(xy 174.47343 -373.872778) (xy 174.593023 -373.740551) (xy 174.718387 -373.613782) (xy 174.849274 -373.492724)
			(xy 174.985423 -373.377617) (xy 175.126565 -373.268689) (xy 175.27242 -373.166157) (xy 175.422697 -373.070223)
			(xy 175.577098 -372.98108) (xy 175.735317 -372.898903) (xy 175.89704 -372.823855) (xy 176.061945 -372.756087)
			(xy 176.229706 -372.695731) (xy 176.399989 -372.642909) (xy 176.572456 -372.597725) (xy 176.746764 -372.560268)
			(xy 176.922568 -372.530614) (xy 177.099518 -372.508821) (xy 177.277264 -372.494931) (xy 177.455451 -372.488974)
			(xy 177.633728 -372.49096) (xy 177.811739 -372.500886) (xy 177.989131 -372.518732) (xy 178.165551 -372.544462)
			(xy 178.340651 -372.578026) (xy 178.514082 -372.619356) (xy 178.685499 -372.668372) (xy 178.854562 -372.724974)
			(xy 179.020937 -372.789052) (xy 179.184291 -372.860478) (xy 179.344302 -372.93911) (xy 179.500651 -373.024791)
			(xy 179.653028 -373.117353) (xy 179.801131 -373.21661) (xy 179.944665 -373.322367) (xy 180.083345 -373.434412)
			(xy 180.216896 -373.552524) (xy 180.345053 -373.676468) (xy 180.467562 -373.805998) (xy 180.584179 -373.940857)
			(xy 180.596796 -373.956834) (xy 282.853384 -373.956834) (xy 282.853384 -373.093234) (xy 282.85387 -373.065983)
			(xy 282.861626 -373.012035) (xy 282.876981 -372.95974) (xy 282.899623 -372.910163) (xy 282.929089 -372.864313)
			(xy 282.96478 -372.823122) (xy 283.005971 -372.787431) (xy 283.051821 -372.757965) (xy 283.101398 -372.735323)
			(xy 283.153693 -372.719968) (xy 283.207641 -372.712212) (xy 283.262143 -372.712212) (xy 283.316091 -372.719968)
			(xy 283.368386 -372.735323) (xy 283.417963 -372.757965) (xy 283.463813 -372.787431) (xy 283.505004 -372.823122)
			(xy 283.540695 -372.864313) (xy 283.570161 -372.910163) (xy 283.592803 -372.95974) (xy 283.608158 -373.012035)
			(xy 283.615914 -373.065983) (xy 283.6164 -373.093234) (xy 283.6164 -373.956834) (xy 283.615914 -373.984085)
			(xy 283.608158 -374.038033) (xy 283.592803 -374.090328) (xy 283.570161 -374.139905) (xy 283.540695 -374.185755)
			(xy 283.505004 -374.226946) (xy 283.463813 -374.262637) (xy 283.417963 -374.292103) (xy 283.368386 -374.314745)
			(xy 283.316091 -374.3301) (xy 283.262143 -374.337856) (xy 283.207641 -374.337856) (xy 283.153693 -374.3301)
			(xy 283.101398 -374.314745) (xy 283.051821 -374.292103) (xy 283.005971 -374.262637) (xy 282.96478 -374.226946)
			(xy 282.929089 -374.185755) (xy 282.899623 -374.139905) (xy 282.876981 -374.090328) (xy 282.861626 -374.038033)
			(xy 282.85387 -373.984085) (xy 282.853384 -373.956834) (xy 180.596796 -373.956834) (xy 180.694672 -374.080777)
			(xy 180.798823 -374.22548) (xy 180.896425 -374.374679) (xy 180.987283 -374.528078) (xy 181.071217 -374.685372)
			(xy 181.148062 -374.846248) (xy 181.217663 -375.010389) (xy 181.279884 -375.177466) (xy 181.3346 -375.34715)
			(xy 181.381702 -375.519103) (xy 181.421098 -375.692983) (xy 181.452709 -375.868446) (xy 181.476473 -376.045142)
			(xy 181.492341 -376.222722) (xy 181.500283 -376.400832) (xy 181.50078 -376.489976) (xy 181.500283 -376.57912)
			(xy 181.492341 -376.75723) (xy 181.476473 -376.93481) (xy 181.452709 -377.111506) (xy 181.421098 -377.286969)
			(xy 181.381702 -377.460849) (xy 181.3346 -377.632802) (xy 181.319901 -377.678385) (xy 193.900548 -377.678385)
			(xy 193.900548 -377.593663) (xy 193.908601 -377.509326) (xy 193.924635 -377.426136) (xy 193.948503 -377.344846)
			(xy 193.979991 -377.266194) (xy 194.018813 -377.190891) (xy 194.064616 -377.119619) (xy 194.116987 -377.053023)
			(xy 194.175452 -376.991708) (xy 194.23948 -376.936227) (xy 194.308492 -376.887084) (xy 194.381862 -376.844724)
			(xy 194.458927 -376.809529) (xy 194.538989 -376.78182) (xy 194.621322 -376.761846) (xy 194.705181 -376.749789)
			(xy 194.789806 -376.745758) (xy 194.874431 -376.749789) (xy 194.95829 -376.761846) (xy 195.040623 -376.78182)
			(xy 195.120685 -376.809529) (xy 195.19775 -376.844724) (xy 195.27112 -376.887084) (xy 195.340132 -376.936227)
			(xy 195.40416 -376.991708) (xy 195.462625 -377.053023) (xy 195.514996 -377.119619) (xy 195.560799 -377.190891)
			(xy 195.599621 -377.266194) (xy 195.631109 -377.344846) (xy 195.654977 -377.426136) (xy 195.671011 -377.509326)
			(xy 195.679064 -377.593663) (xy 195.679568 -377.636024) (xy 195.679064 -377.678385) (xy 195.671011 -377.762722)
			(xy 195.654977 -377.845912) (xy 195.631109 -377.927202) (xy 195.599621 -378.005854) (xy 195.560799 -378.081157)
			(xy 195.514996 -378.152429) (xy 195.47531 -378.202895) (xy 199.443082 -378.202895) (xy 199.443082 -378.118173)
			(xy 199.451135 -378.033836) (xy 199.467169 -377.950646) (xy 199.491037 -377.869356) (xy 199.522525 -377.790704)
			(xy 199.561347 -377.715401) (xy 199.60715 -377.644129) (xy 199.659521 -377.577533) (xy 199.717986 -377.516218)
			(xy 199.782014 -377.460737) (xy 199.851026 -377.411594) (xy 199.924396 -377.369234) (xy 200.001461 -377.334039)
			(xy 200.081523 -377.30633) (xy 200.163856 -377.286356) (xy 200.247715 -377.274299) (xy 200.33234 -377.270268)
			(xy 200.416965 -377.274299) (xy 200.500824 -377.286356) (xy 200.583157 -377.30633) (xy 200.663219 -377.334039)
			(xy 200.740284 -377.369234) (xy 200.813654 -377.411594) (xy 200.859958 -377.444567) (xy 300.335454 -377.444567)
			(xy 300.335454 -377.390033) (xy 300.343215 -377.336054) (xy 300.358579 -377.283729) (xy 300.381233 -377.234123)
			(xy 300.410717 -377.188246) (xy 300.446429 -377.147031) (xy 300.487642 -377.111319) (xy 300.533519 -377.081835)
			(xy 300.583125 -377.059181) (xy 300.63545 -377.043816) (xy 300.689429 -377.036055) (xy 300.716696 -377.035568)
			(xy 301.580296 -377.035568) (xy 301.607569 -377.035971) (xy 301.661561 -377.043734) (xy 301.713898 -377.059101)
			(xy 301.763516 -377.08176) (xy 301.809403 -377.11125) (xy 301.850627 -377.14697) (xy 301.886348 -377.188193)
			(xy 301.915838 -377.234081) (xy 301.938498 -377.283698) (xy 301.953866 -377.336035) (xy 301.961628 -377.390027)
			(xy 301.961628 -377.444567) (xy 307.142654 -377.444567) (xy 307.142654 -377.390033) (xy 307.150415 -377.336054)
			(xy 307.165779 -377.283729) (xy 307.188433 -377.234123) (xy 307.217917 -377.188246) (xy 307.253629 -377.147031)
			(xy 307.294842 -377.111319) (xy 307.340719 -377.081835) (xy 307.390325 -377.059181) (xy 307.44265 -377.043816)
			(xy 307.496629 -377.036055) (xy 307.523896 -377.035568) (xy 308.387496 -377.035568) (xy 308.414769 -377.035971)
			(xy 308.468761 -377.043734) (xy 308.521098 -377.059101) (xy 308.570716 -377.08176) (xy 308.616603 -377.11125)
			(xy 308.657827 -377.14697) (xy 308.693548 -377.188193) (xy 308.723038 -377.234081) (xy 308.745698 -377.283698)
			(xy 308.761066 -377.336035) (xy 308.768828 -377.390027) (xy 308.768828 -377.444567) (xy 313.949854 -377.444567)
			(xy 313.949854 -377.390033) (xy 313.957615 -377.336054) (xy 313.972979 -377.283729) (xy 313.995633 -377.234123)
			(xy 314.025117 -377.188246) (xy 314.060829 -377.147031) (xy 314.102042 -377.111319) (xy 314.147919 -377.081835)
			(xy 314.197525 -377.059181) (xy 314.24985 -377.043816) (xy 314.303829 -377.036055) (xy 314.331096 -377.035568)
			(xy 315.194696 -377.035568) (xy 315.221969 -377.035971) (xy 315.275961 -377.043734) (xy 315.328298 -377.059101)
			(xy 315.377916 -377.08176) (xy 315.423803 -377.11125) (xy 315.465027 -377.14697) (xy 315.500748 -377.188193)
			(xy 315.530238 -377.234081) (xy 315.552898 -377.283698) (xy 315.568266 -377.336035) (xy 315.576028 -377.390027)
			(xy 315.576028 -377.444567) (xy 320.757054 -377.444567) (xy 320.757054 -377.390033) (xy 320.764815 -377.336054)
			(xy 320.780179 -377.283729) (xy 320.802833 -377.234123) (xy 320.832317 -377.188246) (xy 320.868029 -377.147031)
			(xy 320.909242 -377.111319) (xy 320.955119 -377.081835) (xy 321.004725 -377.059181) (xy 321.05705 -377.043816)
			(xy 321.111029 -377.036055) (xy 321.138296 -377.035568) (xy 322.001896 -377.035568) (xy 322.029169 -377.035971)
			(xy 322.083161 -377.043734) (xy 322.135498 -377.059101) (xy 322.185116 -377.08176) (xy 322.231003 -377.11125)
			(xy 322.272227 -377.14697) (xy 322.307948 -377.188193) (xy 322.337438 -377.234081) (xy 322.360098 -377.283698)
			(xy 322.375466 -377.336035) (xy 322.383228 -377.390027) (xy 322.383228 -377.444567) (xy 324.160654 -377.444567)
			(xy 324.160654 -377.390033) (xy 324.168415 -377.336054) (xy 324.183779 -377.283729) (xy 324.206433 -377.234123)
			(xy 324.235917 -377.188246) (xy 324.271629 -377.147031) (xy 324.312842 -377.111319) (xy 324.358719 -377.081835)
			(xy 324.408325 -377.059181) (xy 324.46065 -377.043816) (xy 324.514629 -377.036055) (xy 324.541896 -377.035568)
			(xy 325.405496 -377.035568) (xy 325.432769 -377.035971) (xy 325.486761 -377.043734) (xy 325.539098 -377.059101)
			(xy 325.588716 -377.08176) (xy 325.634603 -377.11125) (xy 325.675827 -377.14697) (xy 325.711548 -377.188193)
			(xy 325.741038 -377.234081) (xy 325.763698 -377.283698) (xy 325.779066 -377.336035) (xy 325.786828 -377.390027)
			(xy 325.786828 -377.444571) (xy 332.863132 -377.444571) (xy 332.863132 -377.390029) (xy 332.870894 -377.336043)
			(xy 332.886261 -377.283711) (xy 332.908921 -377.234098) (xy 332.93841 -377.188216) (xy 332.974129 -377.146998)
			(xy 333.015351 -377.111284) (xy 333.061237 -377.081799) (xy 333.110852 -377.059146) (xy 333.163186 -377.043785)
			(xy 333.217173 -377.036028) (xy 333.244444 -377.035568) (xy 334.108044 -377.035568) (xy 334.135313 -377.035998)
			(xy 334.189297 -377.043765) (xy 334.241625 -377.059135) (xy 334.291233 -377.081796) (xy 334.337112 -377.111285)
			(xy 334.378328 -377.147003) (xy 334.414041 -377.188223) (xy 334.443525 -377.234105) (xy 334.46618 -377.283716)
			(xy 334.481544 -377.336047) (xy 334.489306 -377.39003) (xy 334.489306 -377.44457) (xy 334.489306 -377.444571)
			(xy 339.670332 -377.444571) (xy 339.670332 -377.390029) (xy 339.678094 -377.336043) (xy 339.693461 -377.283711)
			(xy 339.716121 -377.234098) (xy 339.74561 -377.188216) (xy 339.781329 -377.146998) (xy 339.822551 -377.111284)
			(xy 339.868437 -377.081799) (xy 339.918052 -377.059146) (xy 339.970386 -377.043785) (xy 340.024373 -377.036028)
			(xy 340.051644 -377.035568) (xy 340.915244 -377.035568) (xy 340.942513 -377.035998) (xy 340.996497 -377.043765)
			(xy 341.048825 -377.059135) (xy 341.098433 -377.081796) (xy 341.144312 -377.111285) (xy 341.185528 -377.147003)
			(xy 341.221241 -377.188223) (xy 341.250725 -377.234105) (xy 341.27338 -377.283716) (xy 341.288744 -377.336047)
			(xy 341.296506 -377.39003) (xy 341.296506 -377.44457) (xy 341.296506 -377.444571) (xy 346.477532 -377.444571)
			(xy 346.477532 -377.390029) (xy 346.485294 -377.336043) (xy 346.500661 -377.283711) (xy 346.523321 -377.234098)
			(xy 346.55281 -377.188216) (xy 346.588529 -377.146998) (xy 346.629751 -377.111284) (xy 346.675637 -377.081799)
			(xy 346.725252 -377.059146) (xy 346.777586 -377.043785) (xy 346.831573 -377.036028) (xy 346.858844 -377.035568)
			(xy 347.722444 -377.035568) (xy 347.749713 -377.035998) (xy 347.803697 -377.043765) (xy 347.856025 -377.059135)
			(xy 347.905633 -377.081796) (xy 347.951512 -377.111285) (xy 347.992728 -377.147003) (xy 348.028441 -377.188223)
			(xy 348.057925 -377.234105) (xy 348.08058 -377.283716) (xy 348.095944 -377.336047) (xy 348.103706 -377.39003)
			(xy 348.103706 -377.44457) (xy 348.103706 -377.444571) (xy 353.284732 -377.444571) (xy 353.284732 -377.390029)
			(xy 353.292494 -377.336043) (xy 353.307861 -377.283711) (xy 353.330521 -377.234098) (xy 353.36001 -377.188216)
			(xy 353.395729 -377.146998) (xy 353.436951 -377.111284) (xy 353.482837 -377.081799) (xy 353.532452 -377.059146)
			(xy 353.584786 -377.043785) (xy 353.638773 -377.036028) (xy 353.666044 -377.035568) (xy 354.529644 -377.035568)
			(xy 354.556913 -377.035998) (xy 354.610897 -377.043765) (xy 354.663225 -377.059135) (xy 354.712833 -377.081796)
			(xy 354.758712 -377.111285) (xy 354.799928 -377.147003) (xy 354.835641 -377.188223) (xy 354.865125 -377.234105)
			(xy 354.88778 -377.283716) (xy 354.903144 -377.336047) (xy 354.910906 -377.39003) (xy 354.910906 -377.44457)
			(xy 354.910906 -377.444571) (xy 356.688332 -377.444571) (xy 356.688332 -377.390029) (xy 356.696094 -377.336043)
			(xy 356.711461 -377.283711) (xy 356.734121 -377.234098) (xy 356.76361 -377.188216) (xy 356.799329 -377.146998)
			(xy 356.840551 -377.111284) (xy 356.886437 -377.081799) (xy 356.936052 -377.059146) (xy 356.988386 -377.043785)
			(xy 357.042373 -377.036028) (xy 357.069644 -377.035568) (xy 357.933244 -377.035568) (xy 357.960513 -377.035998)
			(xy 358.014497 -377.043765) (xy 358.066825 -377.059135) (xy 358.116433 -377.081796) (xy 358.162312 -377.111285)
			(xy 358.203528 -377.147003) (xy 358.239241 -377.188223) (xy 358.268725 -377.234105) (xy 358.29138 -377.283716)
			(xy 358.306744 -377.336047) (xy 358.314506 -377.39003) (xy 358.314506 -377.444567) (xy 367.435654 -377.444567)
			(xy 367.435654 -377.390033) (xy 367.443415 -377.336054) (xy 367.458779 -377.28373) (xy 367.481433 -377.234124)
			(xy 367.510916 -377.188247) (xy 367.546627 -377.147033) (xy 367.587841 -377.11132) (xy 367.633717 -377.081837)
			(xy 367.683322 -377.059182) (xy 367.735647 -377.043817) (xy 367.789625 -377.036055) (xy 367.816892 -377.035568)
			(xy 368.680492 -377.035568) (xy 368.707766 -377.035971) (xy 368.761757 -377.043733) (xy 368.814095 -377.0591)
			(xy 368.863713 -377.081759) (xy 368.909602 -377.111248) (xy 368.950826 -377.146968) (xy 368.986547 -377.188192)
			(xy 369.016038 -377.23408) (xy 369.038698 -377.283697) (xy 369.054065 -377.336035) (xy 369.061828 -377.390026)
			(xy 369.061828 -377.444567) (xy 374.242854 -377.444567) (xy 374.242854 -377.390033) (xy 374.250615 -377.336054)
			(xy 374.265979 -377.28373) (xy 374.288633 -377.234124) (xy 374.318116 -377.188247) (xy 374.353827 -377.147033)
			(xy 374.395041 -377.11132) (xy 374.440917 -377.081837) (xy 374.490522 -377.059182) (xy 374.542847 -377.043817)
			(xy 374.596825 -377.036055) (xy 374.624092 -377.035568) (xy 375.487692 -377.035568) (xy 375.514966 -377.035971)
			(xy 375.568957 -377.043733) (xy 375.621295 -377.0591) (xy 375.670913 -377.081759) (xy 375.716802 -377.111248)
			(xy 375.758026 -377.146968) (xy 375.793747 -377.188192) (xy 375.823238 -377.23408) (xy 375.845898 -377.283697)
			(xy 375.861265 -377.336035) (xy 375.869028 -377.390026) (xy 375.869028 -377.444567) (xy 381.050054 -377.444567)
			(xy 381.050054 -377.390033) (xy 381.057815 -377.336054) (xy 381.073179 -377.28373) (xy 381.095833 -377.234124)
			(xy 381.125316 -377.188247) (xy 381.161027 -377.147033) (xy 381.202241 -377.11132) (xy 381.248117 -377.081837)
			(xy 381.297722 -377.059182) (xy 381.350047 -377.043817) (xy 381.404025 -377.036055) (xy 381.431292 -377.035568)
			(xy 382.294892 -377.035568) (xy 382.322166 -377.035971) (xy 382.376157 -377.043733) (xy 382.428495 -377.0591)
			(xy 382.478113 -377.081759) (xy 382.524002 -377.111248) (xy 382.565226 -377.146968) (xy 382.600947 -377.188192)
			(xy 382.630438 -377.23408) (xy 382.653098 -377.283697) (xy 382.668465 -377.336035) (xy 382.676228 -377.390026)
			(xy 382.676228 -377.444567) (xy 387.857254 -377.444567) (xy 387.857254 -377.390033) (xy 387.865015 -377.336054)
			(xy 387.880379 -377.28373) (xy 387.903033 -377.234124) (xy 387.932516 -377.188247) (xy 387.968227 -377.147033)
			(xy 388.009441 -377.11132) (xy 388.055317 -377.081837) (xy 388.104922 -377.059182) (xy 388.157247 -377.043817)
			(xy 388.211225 -377.036055) (xy 388.238492 -377.035568) (xy 389.102092 -377.035568) (xy 389.129366 -377.035971)
			(xy 389.183357 -377.043733) (xy 389.235695 -377.0591) (xy 389.285313 -377.081759) (xy 389.331202 -377.111248)
			(xy 389.372426 -377.146968) (xy 389.408147 -377.188192) (xy 389.437638 -377.23408) (xy 389.460298 -377.283697)
			(xy 389.475665 -377.336035) (xy 389.483428 -377.390026) (xy 389.483428 -377.444567) (xy 391.260854 -377.444567)
			(xy 391.260854 -377.390033) (xy 391.268615 -377.336054) (xy 391.283979 -377.28373) (xy 391.306633 -377.234124)
			(xy 391.336116 -377.188247) (xy 391.371827 -377.147033) (xy 391.413041 -377.11132) (xy 391.458917 -377.081837)
			(xy 391.508522 -377.059182) (xy 391.560847 -377.043817) (xy 391.614825 -377.036055) (xy 391.642092 -377.035568)
			(xy 392.505692 -377.035568) (xy 392.532966 -377.035971) (xy 392.586957 -377.043733) (xy 392.639295 -377.0591)
			(xy 392.688913 -377.081759) (xy 392.734802 -377.111248) (xy 392.776026 -377.146968) (xy 392.811747 -377.188192)
			(xy 392.841238 -377.23408) (xy 392.863898 -377.283697) (xy 392.879265 -377.336035) (xy 392.887028 -377.390026)
			(xy 392.887028 -377.444571) (xy 399.963332 -377.444571) (xy 399.963332 -377.390029) (xy 399.971094 -377.336043)
			(xy 399.986461 -377.283711) (xy 400.00912 -377.234099) (xy 400.038609 -377.188217) (xy 400.074328 -377.147)
			(xy 400.11555 -377.111285) (xy 400.161435 -377.081801) (xy 400.211049 -377.059147) (xy 400.263382 -377.043786)
			(xy 400.317369 -377.036029) (xy 400.34464 -377.035568) (xy 401.20824 -377.035568) (xy 401.23551 -377.035997)
			(xy 401.289493 -377.043764) (xy 401.341822 -377.059134) (xy 401.391431 -377.081794) (xy 401.437311 -377.111284)
			(xy 401.478527 -377.147002) (xy 401.51424 -377.188222) (xy 401.543725 -377.234104) (xy 401.56638 -377.283716)
			(xy 401.581744 -377.336046) (xy 401.589506 -377.39003) (xy 401.589506 -377.44457) (xy 401.589506 -377.444571)
			(xy 406.770532 -377.444571) (xy 406.770532 -377.390029) (xy 406.778294 -377.336043) (xy 406.793661 -377.283711)
			(xy 406.81632 -377.234099) (xy 406.845809 -377.188217) (xy 406.881528 -377.147) (xy 406.92275 -377.111285)
			(xy 406.968635 -377.081801) (xy 407.018249 -377.059147) (xy 407.070582 -377.043786) (xy 407.124569 -377.036029)
			(xy 407.15184 -377.035568) (xy 408.01544 -377.035568) (xy 408.04271 -377.035997) (xy 408.096693 -377.043764)
			(xy 408.149022 -377.059134) (xy 408.198631 -377.081794) (xy 408.244511 -377.111284) (xy 408.285727 -377.147002)
			(xy 408.32144 -377.188222) (xy 408.350925 -377.234104) (xy 408.37358 -377.283716) (xy 408.388944 -377.336046)
			(xy 408.396706 -377.39003) (xy 408.396706 -377.44457) (xy 408.396706 -377.444571) (xy 413.577732 -377.444571)
			(xy 413.577732 -377.390029) (xy 413.585494 -377.336043) (xy 413.600861 -377.283711) (xy 413.62352 -377.234099)
			(xy 413.653009 -377.188217) (xy 413.688728 -377.147) (xy 413.72995 -377.111285) (xy 413.775835 -377.081801)
			(xy 413.825449 -377.059147) (xy 413.877782 -377.043786) (xy 413.931769 -377.036029) (xy 413.95904 -377.035568)
			(xy 414.82264 -377.035568) (xy 414.84991 -377.035997) (xy 414.903893 -377.043764) (xy 414.956222 -377.059134)
			(xy 415.005831 -377.081794) (xy 415.051711 -377.111284) (xy 415.092927 -377.147002) (xy 415.12864 -377.188222)
			(xy 415.158125 -377.234104) (xy 415.18078 -377.283716) (xy 415.196144 -377.336046) (xy 415.203906 -377.39003)
			(xy 415.203906 -377.44457) (xy 415.203906 -377.444571) (xy 420.384932 -377.444571) (xy 420.384932 -377.390029)
			(xy 420.392694 -377.336043) (xy 420.408061 -377.283711) (xy 420.43072 -377.234099) (xy 420.460209 -377.188217)
			(xy 420.495928 -377.147) (xy 420.53715 -377.111285) (xy 420.583035 -377.081801) (xy 420.632649 -377.059147)
			(xy 420.684982 -377.043786) (xy 420.738969 -377.036029) (xy 420.76624 -377.035568) (xy 421.62984 -377.035568)
			(xy 421.65711 -377.035997) (xy 421.711093 -377.043764) (xy 421.763422 -377.059134) (xy 421.813031 -377.081794)
			(xy 421.858911 -377.111284) (xy 421.900127 -377.147002) (xy 421.93584 -377.188222) (xy 421.965325 -377.234104)
			(xy 421.98798 -377.283716) (xy 422.003344 -377.336046) (xy 422.011106 -377.39003) (xy 422.011106 -377.44457)
			(xy 422.011106 -377.444571) (xy 423.788532 -377.444571) (xy 423.788532 -377.390029) (xy 423.796294 -377.336043)
			(xy 423.811661 -377.283711) (xy 423.83432 -377.234099) (xy 423.863809 -377.188217) (xy 423.899528 -377.147)
			(xy 423.94075 -377.111285) (xy 423.986635 -377.081801) (xy 424.036249 -377.059147) (xy 424.088582 -377.043786)
			(xy 424.142569 -377.036029) (xy 424.16984 -377.035568) (xy 425.03344 -377.035568) (xy 425.06071 -377.035997)
			(xy 425.114693 -377.043764) (xy 425.167022 -377.059134) (xy 425.216631 -377.081794) (xy 425.262511 -377.111284)
			(xy 425.303727 -377.147002) (xy 425.33944 -377.188222) (xy 425.368925 -377.234104) (xy 425.39158 -377.283716)
			(xy 425.406944 -377.336046) (xy 425.414706 -377.39003) (xy 425.414706 -377.44457) (xy 425.406944 -377.498554)
			(xy 425.39158 -377.550884) (xy 425.368925 -377.600496) (xy 425.33944 -377.646378) (xy 425.303727 -377.687598)
			(xy 425.262511 -377.723316) (xy 425.216631 -377.752806) (xy 425.167022 -377.775466) (xy 425.114693 -377.790836)
			(xy 425.06071 -377.798603) (xy 425.03344 -377.799092) (xy 424.16984 -377.799092) (xy 424.142569 -377.798571)
			(xy 424.088582 -377.790814) (xy 424.036249 -377.775453) (xy 423.986635 -377.752799) (xy 423.94075 -377.723315)
			(xy 423.899528 -377.6876) (xy 423.863809 -377.646383) (xy 423.83432 -377.600501) (xy 423.811661 -377.550889)
			(xy 423.796294 -377.498557) (xy 423.788532 -377.444571) (xy 422.011106 -377.444571) (xy 422.003344 -377.498554)
			(xy 421.98798 -377.550884) (xy 421.965325 -377.600496) (xy 421.93584 -377.646378) (xy 421.900127 -377.687598)
			(xy 421.858911 -377.723316) (xy 421.813031 -377.752806) (xy 421.763422 -377.775466) (xy 421.711093 -377.790836)
			(xy 421.65711 -377.798603) (xy 421.62984 -377.799092) (xy 420.76624 -377.799092) (xy 420.738969 -377.798571)
			(xy 420.684982 -377.790814) (xy 420.632649 -377.775453) (xy 420.583035 -377.752799) (xy 420.53715 -377.723315)
			(xy 420.495928 -377.6876) (xy 420.460209 -377.646383) (xy 420.43072 -377.600501) (xy 420.408061 -377.550889)
			(xy 420.392694 -377.498557) (xy 420.384932 -377.444571) (xy 415.203906 -377.444571) (xy 415.196144 -377.498554)
			(xy 415.18078 -377.550884) (xy 415.158125 -377.600496) (xy 415.12864 -377.646378) (xy 415.092927 -377.687598)
			(xy 415.051711 -377.723316) (xy 415.005831 -377.752806) (xy 414.956222 -377.775466) (xy 414.903893 -377.790836)
			(xy 414.84991 -377.798603) (xy 414.82264 -377.799092) (xy 413.95904 -377.799092) (xy 413.931769 -377.798571)
			(xy 413.877782 -377.790814) (xy 413.825449 -377.775453) (xy 413.775835 -377.752799) (xy 413.72995 -377.723315)
			(xy 413.688728 -377.6876) (xy 413.653009 -377.646383) (xy 413.62352 -377.600501) (xy 413.600861 -377.550889)
			(xy 413.585494 -377.498557) (xy 413.577732 -377.444571) (xy 408.396706 -377.444571) (xy 408.388944 -377.498554)
			(xy 408.37358 -377.550884) (xy 408.350925 -377.600496) (xy 408.32144 -377.646378) (xy 408.285727 -377.687598)
			(xy 408.244511 -377.723316) (xy 408.198631 -377.752806) (xy 408.149022 -377.775466) (xy 408.096693 -377.790836)
			(xy 408.04271 -377.798603) (xy 408.01544 -377.799092) (xy 407.15184 -377.799092) (xy 407.124569 -377.798571)
			(xy 407.070582 -377.790814) (xy 407.018249 -377.775453) (xy 406.968635 -377.752799) (xy 406.92275 -377.723315)
			(xy 406.881528 -377.6876) (xy 406.845809 -377.646383) (xy 406.81632 -377.600501) (xy 406.793661 -377.550889)
			(xy 406.778294 -377.498557) (xy 406.770532 -377.444571) (xy 401.589506 -377.444571) (xy 401.581744 -377.498554)
			(xy 401.56638 -377.550884) (xy 401.543725 -377.600496) (xy 401.51424 -377.646378) (xy 401.478527 -377.687598)
			(xy 401.437311 -377.723316) (xy 401.391431 -377.752806) (xy 401.341822 -377.775466) (xy 401.289493 -377.790836)
			(xy 401.23551 -377.798603) (xy 401.20824 -377.799092) (xy 400.34464 -377.799092) (xy 400.317369 -377.798571)
			(xy 400.263382 -377.790814) (xy 400.211049 -377.775453) (xy 400.161435 -377.752799) (xy 400.11555 -377.723315)
			(xy 400.074328 -377.6876) (xy 400.038609 -377.646383) (xy 400.00912 -377.600501) (xy 399.986461 -377.550889)
			(xy 399.971094 -377.498557) (xy 399.963332 -377.444571) (xy 392.887028 -377.444571) (xy 392.887028 -377.444574)
			(xy 392.879265 -377.498565) (xy 392.863898 -377.550903) (xy 392.841238 -377.60052) (xy 392.811747 -377.646408)
			(xy 392.776026 -377.687632) (xy 392.734802 -377.723352) (xy 392.688913 -377.752841) (xy 392.639295 -377.7755)
			(xy 392.586957 -377.790867) (xy 392.532966 -377.798629) (xy 392.505692 -377.799092) (xy 391.642092 -377.799092)
			(xy 391.614825 -377.798545) (xy 391.560847 -377.790783) (xy 391.508522 -377.775418) (xy 391.458917 -377.752763)
			(xy 391.413041 -377.72328) (xy 391.371827 -377.687567) (xy 391.336116 -377.646353) (xy 391.306633 -377.600476)
			(xy 391.283979 -377.55087) (xy 391.268615 -377.498546) (xy 391.260854 -377.444567) (xy 389.483428 -377.444567)
			(xy 389.483428 -377.444574) (xy 389.475665 -377.498565) (xy 389.460298 -377.550903) (xy 389.437638 -377.60052)
			(xy 389.408147 -377.646408) (xy 389.372426 -377.687632) (xy 389.331202 -377.723352) (xy 389.285313 -377.752841)
			(xy 389.235695 -377.7755) (xy 389.183357 -377.790867) (xy 389.129366 -377.798629) (xy 389.102092 -377.799092)
			(xy 388.238492 -377.799092) (xy 388.211225 -377.798545) (xy 388.157247 -377.790783) (xy 388.104922 -377.775418)
			(xy 388.055317 -377.752763) (xy 388.009441 -377.72328) (xy 387.968227 -377.687567) (xy 387.932516 -377.646353)
			(xy 387.903033 -377.600476) (xy 387.880379 -377.55087) (xy 387.865015 -377.498546) (xy 387.857254 -377.444567)
			(xy 382.676228 -377.444567) (xy 382.676228 -377.444574) (xy 382.668465 -377.498565) (xy 382.653098 -377.550903)
			(xy 382.630438 -377.60052) (xy 382.600947 -377.646408) (xy 382.565226 -377.687632) (xy 382.524002 -377.723352)
			(xy 382.478113 -377.752841) (xy 382.428495 -377.7755) (xy 382.376157 -377.790867) (xy 382.322166 -377.798629)
			(xy 382.294892 -377.799092) (xy 381.431292 -377.799092) (xy 381.404025 -377.798545) (xy 381.350047 -377.790783)
			(xy 381.297722 -377.775418) (xy 381.248117 -377.752763) (xy 381.202241 -377.72328) (xy 381.161027 -377.687567)
			(xy 381.125316 -377.646353) (xy 381.095833 -377.600476) (xy 381.073179 -377.55087) (xy 381.057815 -377.498546)
			(xy 381.050054 -377.444567) (xy 375.869028 -377.444567) (xy 375.869028 -377.444574) (xy 375.861265 -377.498565)
			(xy 375.845898 -377.550903) (xy 375.823238 -377.60052) (xy 375.793747 -377.646408) (xy 375.758026 -377.687632)
			(xy 375.716802 -377.723352) (xy 375.670913 -377.752841) (xy 375.621295 -377.7755) (xy 375.568957 -377.790867)
			(xy 375.514966 -377.798629) (xy 375.487692 -377.799092) (xy 374.624092 -377.799092) (xy 374.596825 -377.798545)
			(xy 374.542847 -377.790783) (xy 374.490522 -377.775418) (xy 374.440917 -377.752763) (xy 374.395041 -377.72328)
			(xy 374.353827 -377.687567) (xy 374.318116 -377.646353) (xy 374.288633 -377.600476) (xy 374.265979 -377.55087)
			(xy 374.250615 -377.498546) (xy 374.242854 -377.444567) (xy 369.061828 -377.444567) (xy 369.061828 -377.444574)
			(xy 369.054065 -377.498565) (xy 369.038698 -377.550903) (xy 369.016038 -377.60052) (xy 368.986547 -377.646408)
			(xy 368.950826 -377.687632) (xy 368.909602 -377.723352) (xy 368.863713 -377.752841) (xy 368.814095 -377.7755)
			(xy 368.761757 -377.790867) (xy 368.707766 -377.798629) (xy 368.680492 -377.799092) (xy 367.816892 -377.799092)
			(xy 367.789625 -377.798545) (xy 367.735647 -377.790783) (xy 367.683322 -377.775418) (xy 367.633717 -377.752763)
			(xy 367.587841 -377.72328) (xy 367.546627 -377.687567) (xy 367.510916 -377.646353) (xy 367.481433 -377.600476)
			(xy 367.458779 -377.55087) (xy 367.443415 -377.498546) (xy 367.435654 -377.444567) (xy 358.314506 -377.444567)
			(xy 358.314506 -377.44457) (xy 358.306744 -377.498553) (xy 358.29138 -377.550884) (xy 358.268725 -377.600495)
			(xy 358.239241 -377.646377) (xy 358.203528 -377.687597) (xy 358.162312 -377.723315) (xy 358.116433 -377.752804)
			(xy 358.066825 -377.775465) (xy 358.014497 -377.790835) (xy 357.960513 -377.798602) (xy 357.933244 -377.799092)
			(xy 357.069644 -377.799092) (xy 357.042373 -377.798572) (xy 356.988386 -377.790815) (xy 356.936052 -377.775454)
			(xy 356.886437 -377.752801) (xy 356.840551 -377.723316) (xy 356.799329 -377.687602) (xy 356.76361 -377.646384)
			(xy 356.734121 -377.600502) (xy 356.711461 -377.550889) (xy 356.696094 -377.498557) (xy 356.688332 -377.444571)
			(xy 354.910906 -377.444571) (xy 354.903144 -377.498553) (xy 354.88778 -377.550884) (xy 354.865125 -377.600495)
			(xy 354.835641 -377.646377) (xy 354.799928 -377.687597) (xy 354.758712 -377.723315) (xy 354.712833 -377.752804)
			(xy 354.663225 -377.775465) (xy 354.610897 -377.790835) (xy 354.556913 -377.798602) (xy 354.529644 -377.799092)
			(xy 353.666044 -377.799092) (xy 353.638773 -377.798572) (xy 353.584786 -377.790815) (xy 353.532452 -377.775454)
			(xy 353.482837 -377.752801) (xy 353.436951 -377.723316) (xy 353.395729 -377.687602) (xy 353.36001 -377.646384)
			(xy 353.330521 -377.600502) (xy 353.307861 -377.550889) (xy 353.292494 -377.498557) (xy 353.284732 -377.444571)
			(xy 348.103706 -377.444571) (xy 348.095944 -377.498553) (xy 348.08058 -377.550884) (xy 348.057925 -377.600495)
			(xy 348.028441 -377.646377) (xy 347.992728 -377.687597) (xy 347.951512 -377.723315) (xy 347.905633 -377.752804)
			(xy 347.856025 -377.775465) (xy 347.803697 -377.790835) (xy 347.749713 -377.798602) (xy 347.722444 -377.799092)
			(xy 346.858844 -377.799092) (xy 346.831573 -377.798572) (xy 346.777586 -377.790815) (xy 346.725252 -377.775454)
			(xy 346.675637 -377.752801) (xy 346.629751 -377.723316) (xy 346.588529 -377.687602) (xy 346.55281 -377.646384)
			(xy 346.523321 -377.600502) (xy 346.500661 -377.550889) (xy 346.485294 -377.498557) (xy 346.477532 -377.444571)
			(xy 341.296506 -377.444571) (xy 341.288744 -377.498553) (xy 341.27338 -377.550884) (xy 341.250725 -377.600495)
			(xy 341.221241 -377.646377) (xy 341.185528 -377.687597) (xy 341.144312 -377.723315) (xy 341.098433 -377.752804)
			(xy 341.048825 -377.775465) (xy 340.996497 -377.790835) (xy 340.942513 -377.798602) (xy 340.915244 -377.799092)
			(xy 340.051644 -377.799092) (xy 340.024373 -377.798572) (xy 339.970386 -377.790815) (xy 339.918052 -377.775454)
			(xy 339.868437 -377.752801) (xy 339.822551 -377.723316) (xy 339.781329 -377.687602) (xy 339.74561 -377.646384)
			(xy 339.716121 -377.600502) (xy 339.693461 -377.550889) (xy 339.678094 -377.498557) (xy 339.670332 -377.444571)
			(xy 334.489306 -377.444571) (xy 334.481544 -377.498553) (xy 334.46618 -377.550884) (xy 334.443525 -377.600495)
			(xy 334.414041 -377.646377) (xy 334.378328 -377.687597) (xy 334.337112 -377.723315) (xy 334.291233 -377.752804)
			(xy 334.241625 -377.775465) (xy 334.189297 -377.790835) (xy 334.135313 -377.798602) (xy 334.108044 -377.799092)
			(xy 333.244444 -377.799092) (xy 333.217173 -377.798572) (xy 333.163186 -377.790815) (xy 333.110852 -377.775454)
			(xy 333.061237 -377.752801) (xy 333.015351 -377.723316) (xy 332.974129 -377.687602) (xy 332.93841 -377.646384)
			(xy 332.908921 -377.600502) (xy 332.886261 -377.550889) (xy 332.870894 -377.498557) (xy 332.863132 -377.444571)
			(xy 325.786828 -377.444571) (xy 325.786828 -377.444573) (xy 325.779066 -377.498565) (xy 325.763698 -377.550902)
			(xy 325.741038 -377.600519) (xy 325.711548 -377.646407) (xy 325.675827 -377.68763) (xy 325.634603 -377.72335)
			(xy 325.588716 -377.75284) (xy 325.539098 -377.775499) (xy 325.486761 -377.790866) (xy 325.432769 -377.798629)
			(xy 325.405496 -377.799092) (xy 324.541896 -377.799092) (xy 324.514629 -377.798545) (xy 324.46065 -377.790784)
			(xy 324.408325 -377.775419) (xy 324.358719 -377.752765) (xy 324.312842 -377.723281) (xy 324.271629 -377.687569)
			(xy 324.235917 -377.646354) (xy 324.206433 -377.600477) (xy 324.183779 -377.550871) (xy 324.168415 -377.498546)
			(xy 324.160654 -377.444567) (xy 322.383228 -377.444567) (xy 322.383228 -377.444573) (xy 322.375466 -377.498565)
			(xy 322.360098 -377.550902) (xy 322.337438 -377.600519) (xy 322.307948 -377.646407) (xy 322.272227 -377.68763)
			(xy 322.231003 -377.72335) (xy 322.185116 -377.75284) (xy 322.135498 -377.775499) (xy 322.083161 -377.790866)
			(xy 322.029169 -377.798629) (xy 322.001896 -377.799092) (xy 321.138296 -377.799092) (xy 321.111029 -377.798545)
			(xy 321.05705 -377.790784) (xy 321.004725 -377.775419) (xy 320.955119 -377.752765) (xy 320.909242 -377.723281)
			(xy 320.868029 -377.687569) (xy 320.832317 -377.646354) (xy 320.802833 -377.600477) (xy 320.780179 -377.550871)
			(xy 320.764815 -377.498546) (xy 320.757054 -377.444567) (xy 315.576028 -377.444567) (xy 315.576028 -377.444573)
			(xy 315.568266 -377.498565) (xy 315.552898 -377.550902) (xy 315.530238 -377.600519) (xy 315.500748 -377.646407)
			(xy 315.465027 -377.68763) (xy 315.423803 -377.72335) (xy 315.377916 -377.75284) (xy 315.328298 -377.775499)
			(xy 315.275961 -377.790866) (xy 315.221969 -377.798629) (xy 315.194696 -377.799092) (xy 314.331096 -377.799092)
			(xy 314.303829 -377.798545) (xy 314.24985 -377.790784) (xy 314.197525 -377.775419) (xy 314.147919 -377.752765)
			(xy 314.102042 -377.723281) (xy 314.060829 -377.687569) (xy 314.025117 -377.646354) (xy 313.995633 -377.600477)
			(xy 313.972979 -377.550871) (xy 313.957615 -377.498546) (xy 313.949854 -377.444567) (xy 308.768828 -377.444567)
			(xy 308.768828 -377.444573) (xy 308.761066 -377.498565) (xy 308.745698 -377.550902) (xy 308.723038 -377.600519)
			(xy 308.693548 -377.646407) (xy 308.657827 -377.68763) (xy 308.616603 -377.72335) (xy 308.570716 -377.75284)
			(xy 308.521098 -377.775499) (xy 308.468761 -377.790866) (xy 308.414769 -377.798629) (xy 308.387496 -377.799092)
			(xy 307.523896 -377.799092) (xy 307.496629 -377.798545) (xy 307.44265 -377.790784) (xy 307.390325 -377.775419)
			(xy 307.340719 -377.752765) (xy 307.294842 -377.723281) (xy 307.253629 -377.687569) (xy 307.217917 -377.646354)
			(xy 307.188433 -377.600477) (xy 307.165779 -377.550871) (xy 307.150415 -377.498546) (xy 307.142654 -377.444567)
			(xy 301.961628 -377.444567) (xy 301.961628 -377.444573) (xy 301.953866 -377.498565) (xy 301.938498 -377.550902)
			(xy 301.915838 -377.600519) (xy 301.886348 -377.646407) (xy 301.850627 -377.68763) (xy 301.809403 -377.72335)
			(xy 301.763516 -377.75284) (xy 301.713898 -377.775499) (xy 301.661561 -377.790866) (xy 301.607569 -377.798629)
			(xy 301.580296 -377.799092) (xy 300.716696 -377.799092) (xy 300.689429 -377.798545) (xy 300.63545 -377.790784)
			(xy 300.583125 -377.775419) (xy 300.533519 -377.752765) (xy 300.487642 -377.723281) (xy 300.446429 -377.687569)
			(xy 300.410717 -377.646354) (xy 300.381233 -377.600477) (xy 300.358579 -377.550871) (xy 300.343215 -377.498546)
			(xy 300.335454 -377.444567) (xy 200.859958 -377.444567) (xy 200.882666 -377.460737) (xy 200.946694 -377.516218)
			(xy 201.005159 -377.577533) (xy 201.05753 -377.644129) (xy 201.103333 -377.715401) (xy 201.142155 -377.790704)
			(xy 201.173643 -377.869356) (xy 201.197511 -377.950646) (xy 201.213545 -378.033836) (xy 201.221598 -378.118173)
			(xy 201.222102 -378.160534) (xy 201.221598 -378.202895) (xy 201.213545 -378.287232) (xy 201.197511 -378.370422)
			(xy 201.173643 -378.451712) (xy 201.142155 -378.530364) (xy 201.103333 -378.605667) (xy 201.05753 -378.676939)
			(xy 201.005159 -378.743535) (xy 200.946694 -378.80485) (xy 200.882666 -378.860331) (xy 200.813654 -378.909474)
			(xy 200.740284 -378.951834) (xy 200.663219 -378.987029) (xy 200.583157 -379.014738) (xy 200.500824 -379.034712)
			(xy 200.416965 -379.046769) (xy 200.33234 -379.050801) (xy 200.247715 -379.046769) (xy 200.163856 -379.034712)
			(xy 200.081523 -379.014738) (xy 200.001461 -378.987029) (xy 199.924396 -378.951834) (xy 199.851026 -378.909474)
			(xy 199.782014 -378.860331) (xy 199.717986 -378.80485) (xy 199.659521 -378.743535) (xy 199.60715 -378.676939)
			(xy 199.561347 -378.605667) (xy 199.522525 -378.530364) (xy 199.491037 -378.451712) (xy 199.467169 -378.370422)
			(xy 199.451135 -378.287232) (xy 199.443082 -378.202895) (xy 195.47531 -378.202895) (xy 195.462625 -378.219025)
			(xy 195.40416 -378.28034) (xy 195.340132 -378.335821) (xy 195.27112 -378.384964) (xy 195.19775 -378.427324)
			(xy 195.120685 -378.462519) (xy 195.040623 -378.490228) (xy 194.95829 -378.510202) (xy 194.874431 -378.522259)
			(xy 194.789806 -378.526291) (xy 194.705181 -378.522259) (xy 194.621322 -378.510202) (xy 194.538989 -378.490228)
			(xy 194.458927 -378.462519) (xy 194.381862 -378.427324) (xy 194.308492 -378.384964) (xy 194.23948 -378.335821)
			(xy 194.175452 -378.28034) (xy 194.116987 -378.219025) (xy 194.064616 -378.152429) (xy 194.018813 -378.081157)
			(xy 193.979991 -378.005854) (xy 193.948503 -377.927202) (xy 193.924635 -377.845912) (xy 193.908601 -377.762722)
			(xy 193.900548 -377.678385) (xy 181.319901 -377.678385) (xy 181.279884 -377.802486) (xy 181.217663 -377.969563)
			(xy 181.148062 -378.133704) (xy 181.071217 -378.29458) (xy 180.987283 -378.451874) (xy 180.896425 -378.605273)
			(xy 180.798823 -378.754472) (xy 180.694672 -378.899175) (xy 180.584179 -379.039095) (xy 180.467562 -379.173954)
			(xy 180.351012 -379.297184) (xy 300.499272 -379.297184) (xy 300.499272 -378.61113) (xy 300.499734 -378.599039)
			(xy 300.507186 -378.576034) (xy 300.521373 -378.556451) (xy 300.54091 -378.5422) (xy 300.56389 -378.534673)
			(xy 300.57598 -378.534168) (xy 300.770544 -378.534168) (xy 300.78167 -378.534577) (xy 300.802967 -378.541039)
			(xy 300.812454 -378.546868) (xy 301.106078 -378.7394) (xy 301.115461 -378.745104) (xy 301.136474 -378.75144)
			(xy 301.158421 -378.751514) (xy 301.179476 -378.745319) (xy 301.188882 -378.739654) (xy 301.485046 -378.546868)
			(xy 301.494535 -378.54105) (xy 301.515833 -378.534608) (xy 301.526956 -378.534168) (xy 301.72152 -378.534168)
			(xy 301.733593 -378.534647) (xy 301.756557 -378.542112) (xy 301.776091 -378.556306) (xy 301.790286 -378.57584)
			(xy 301.797752 -378.598803) (xy 301.798228 -378.610876) (xy 301.798228 -379.29693) (xy 301.798219 -379.297184)
			(xy 307.306472 -379.297184) (xy 307.306472 -378.61113) (xy 307.306934 -378.599039) (xy 307.314386 -378.576034)
			(xy 307.328573 -378.556451) (xy 307.34811 -378.5422) (xy 307.37109 -378.534673) (xy 307.38318 -378.534168)
			(xy 307.577744 -378.534168) (xy 307.58887 -378.534577) (xy 307.610167 -378.541039) (xy 307.619654 -378.546868)
			(xy 307.913278 -378.7394) (xy 307.922661 -378.745104) (xy 307.943674 -378.75144) (xy 307.965621 -378.751514)
			(xy 307.986676 -378.745319) (xy 307.996082 -378.739654) (xy 308.292246 -378.546868) (xy 308.301735 -378.54105)
			(xy 308.323033 -378.534608) (xy 308.334156 -378.534168) (xy 308.52872 -378.534168) (xy 308.540793 -378.534647)
			(xy 308.563757 -378.542112) (xy 308.583291 -378.556306) (xy 308.597486 -378.57584) (xy 308.604952 -378.598803)
			(xy 308.605428 -378.610876) (xy 308.605428 -379.29693) (xy 308.605419 -379.297184) (xy 314.113672 -379.297184)
			(xy 314.113672 -378.61113) (xy 314.114134 -378.599039) (xy 314.121586 -378.576034) (xy 314.135773 -378.556451)
			(xy 314.15531 -378.5422) (xy 314.17829 -378.534673) (xy 314.19038 -378.534168) (xy 314.384944 -378.534168)
			(xy 314.39607 -378.534577) (xy 314.417367 -378.541039) (xy 314.426854 -378.546868) (xy 314.720478 -378.7394)
			(xy 314.729861 -378.745104) (xy 314.750874 -378.75144) (xy 314.772821 -378.751514) (xy 314.793876 -378.745319)
			(xy 314.803282 -378.739654) (xy 315.099446 -378.546868) (xy 315.108935 -378.54105) (xy 315.130233 -378.534608)
			(xy 315.141356 -378.534168) (xy 315.33592 -378.534168) (xy 315.347993 -378.534647) (xy 315.370957 -378.542112)
			(xy 315.390491 -378.556306) (xy 315.404686 -378.57584) (xy 315.412152 -378.598803) (xy 315.412628 -378.610876)
			(xy 315.412628 -379.29693) (xy 315.412619 -379.297184) (xy 320.920872 -379.297184) (xy 320.920872 -378.61113)
			(xy 320.921334 -378.599039) (xy 320.928786 -378.576034) (xy 320.942973 -378.556451) (xy 320.96251 -378.5422)
			(xy 320.98549 -378.534673) (xy 320.99758 -378.534168) (xy 321.192144 -378.534168) (xy 321.20327 -378.534577)
			(xy 321.224567 -378.541039) (xy 321.234054 -378.546868) (xy 321.527678 -378.7394) (xy 321.537061 -378.745104)
			(xy 321.558074 -378.75144) (xy 321.580021 -378.751514) (xy 321.601076 -378.745319) (xy 321.610482 -378.739654)
			(xy 321.906646 -378.546868) (xy 321.916135 -378.54105) (xy 321.937433 -378.534608) (xy 321.948556 -378.534168)
			(xy 322.14312 -378.534168) (xy 322.155193 -378.534647) (xy 322.178157 -378.542112) (xy 322.197691 -378.556306)
			(xy 322.211886 -378.57584) (xy 322.219352 -378.598803) (xy 322.219828 -378.610876) (xy 322.219828 -379.29693)
			(xy 322.219819 -379.297184) (xy 324.324472 -379.297184) (xy 324.324472 -378.61113) (xy 324.324934 -378.599039)
			(xy 324.332386 -378.576034) (xy 324.346573 -378.556451) (xy 324.36611 -378.5422) (xy 324.38909 -378.534673)
			(xy 324.40118 -378.534168) (xy 324.595744 -378.534168) (xy 324.60687 -378.534577) (xy 324.628167 -378.541039)
			(xy 324.637654 -378.546868) (xy 324.931278 -378.7394) (xy 324.940661 -378.745104) (xy 324.961674 -378.75144)
			(xy 324.983621 -378.751514) (xy 325.004676 -378.745319) (xy 325.014082 -378.739654) (xy 325.310246 -378.546868)
			(xy 325.319735 -378.54105) (xy 325.341033 -378.534608) (xy 325.352156 -378.534168) (xy 325.54672 -378.534168)
			(xy 325.558793 -378.534647) (xy 325.581757 -378.542112) (xy 325.601291 -378.556306) (xy 325.615486 -378.57584)
			(xy 325.622952 -378.598803) (xy 325.623428 -378.610876) (xy 325.623428 -379.29693) (xy 325.623419 -379.297184)
			(xy 333.02702 -379.297184) (xy 333.02702 -378.61113) (xy 333.027533 -378.599044) (xy 333.034979 -378.576048)
			(xy 333.049154 -378.556469) (xy 333.068677 -378.542217) (xy 333.091644 -378.53468) (xy 333.103728 -378.534168)
			(xy 333.298292 -378.534168) (xy 333.309416 -378.534598) (xy 333.330713 -378.541046) (xy 333.340202 -378.546868)
			(xy 333.633826 -378.7394) (xy 333.643186 -378.745146) (xy 333.66421 -378.751473) (xy 333.686165 -378.751535)
			(xy 333.707224 -378.745326) (xy 333.71663 -378.739654) (xy 334.012794 -378.546868) (xy 334.022294 -378.541069)
			(xy 334.043584 -378.534615) (xy 334.054704 -378.534168) (xy 334.249268 -378.534168) (xy 334.261347 -378.53464)
			(xy 334.284324 -378.542095) (xy 334.303873 -378.556287) (xy 334.318079 -378.575826) (xy 334.325552 -378.598798)
			(xy 334.325976 -378.610876) (xy 334.325976 -379.29693) (xy 334.325966 -379.297184) (xy 339.83422 -379.297184)
			(xy 339.83422 -378.61113) (xy 339.834733 -378.599044) (xy 339.842179 -378.576048) (xy 339.856354 -378.556469)
			(xy 339.875877 -378.542217) (xy 339.898844 -378.53468) (xy 339.910928 -378.534168) (xy 340.105492 -378.534168)
			(xy 340.116616 -378.534598) (xy 340.137913 -378.541046) (xy 340.147402 -378.546868) (xy 340.441026 -378.7394)
			(xy 340.450386 -378.745146) (xy 340.47141 -378.751473) (xy 340.493365 -378.751535) (xy 340.514424 -378.745326)
			(xy 340.52383 -378.739654) (xy 340.819994 -378.546868) (xy 340.829494 -378.541069) (xy 340.850784 -378.534615)
			(xy 340.861904 -378.534168) (xy 341.056468 -378.534168) (xy 341.068547 -378.53464) (xy 341.091524 -378.542095)
			(xy 341.111073 -378.556287) (xy 341.125279 -378.575826) (xy 341.132752 -378.598798) (xy 341.133176 -378.610876)
			(xy 341.133176 -379.29693) (xy 341.133166 -379.297184) (xy 346.64142 -379.297184) (xy 346.64142 -378.61113)
			(xy 346.641933 -378.599044) (xy 346.649379 -378.576048) (xy 346.663554 -378.556469) (xy 346.683077 -378.542217)
			(xy 346.706044 -378.53468) (xy 346.718128 -378.534168) (xy 346.912692 -378.534168) (xy 346.923816 -378.534598)
			(xy 346.945113 -378.541046) (xy 346.954602 -378.546868) (xy 347.248226 -378.7394) (xy 347.257586 -378.745146)
			(xy 347.27861 -378.751473) (xy 347.300565 -378.751535) (xy 347.321624 -378.745326) (xy 347.33103 -378.739654)
			(xy 347.627194 -378.546868) (xy 347.636694 -378.541069) (xy 347.657984 -378.534615) (xy 347.669104 -378.534168)
			(xy 347.863668 -378.534168) (xy 347.875747 -378.53464) (xy 347.898724 -378.542095) (xy 347.918273 -378.556287)
			(xy 347.932479 -378.575826) (xy 347.939952 -378.598798) (xy 347.940376 -378.610876) (xy 347.940376 -379.29693)
			(xy 347.940366 -379.297184) (xy 353.44862 -379.297184) (xy 353.44862 -378.61113) (xy 353.449133 -378.599044)
			(xy 353.456579 -378.576048) (xy 353.470754 -378.556469) (xy 353.490277 -378.542217) (xy 353.513244 -378.53468)
			(xy 353.525328 -378.534168) (xy 353.719892 -378.534168) (xy 353.731016 -378.534598) (xy 353.752313 -378.541046)
			(xy 353.761802 -378.546868) (xy 354.055426 -378.7394) (xy 354.064786 -378.745146) (xy 354.08581 -378.751473)
			(xy 354.107765 -378.751535) (xy 354.128824 -378.745326) (xy 354.13823 -378.739654) (xy 354.434394 -378.546868)
			(xy 354.443894 -378.541069) (xy 354.465184 -378.534615) (xy 354.476304 -378.534168) (xy 354.670868 -378.534168)
			(xy 354.682947 -378.53464) (xy 354.705924 -378.542095) (xy 354.725473 -378.556287) (xy 354.739679 -378.575826)
			(xy 354.747152 -378.598798) (xy 354.747576 -378.610876) (xy 354.747576 -379.29693) (xy 354.747566 -379.297184)
			(xy 356.85222 -379.297184) (xy 356.85222 -378.61113) (xy 356.852733 -378.599044) (xy 356.860179 -378.576048)
			(xy 356.874354 -378.556469) (xy 356.893877 -378.542217) (xy 356.916844 -378.53468) (xy 356.928928 -378.534168)
			(xy 357.123492 -378.534168) (xy 357.134616 -378.534598) (xy 357.155913 -378.541046) (xy 357.165402 -378.546868)
			(xy 357.459026 -378.7394) (xy 357.468386 -378.745146) (xy 357.48941 -378.751473) (xy 357.511365 -378.751535)
			(xy 357.532424 -378.745326) (xy 357.54183 -378.739654) (xy 357.837994 -378.546868) (xy 357.847494 -378.541069)
			(xy 357.868784 -378.534615) (xy 357.879904 -378.534168) (xy 358.074468 -378.534168) (xy 358.086547 -378.53464)
			(xy 358.109524 -378.542095) (xy 358.129073 -378.556287) (xy 358.143279 -378.575826) (xy 358.150752 -378.598798)
			(xy 358.151176 -378.610876) (xy 358.151176 -379.29693) (xy 367.59896 -379.29693) (xy 367.59896 -378.61113)
			(xy 367.599386 -378.599007) (xy 367.606872 -378.575945) (xy 367.621122 -378.556328) (xy 367.640738 -378.542076)
			(xy 367.663799 -378.534587) (xy 367.675922 -378.534168) (xy 367.870486 -378.534168) (xy 367.88161 -378.534601)
			(xy 367.902907 -378.541047) (xy 367.912396 -378.546868) (xy 368.20602 -378.7394) (xy 368.215383 -378.74514)
			(xy 368.236405 -378.751469) (xy 368.25836 -378.751532) (xy 368.279418 -378.745325) (xy 368.288824 -378.739654)
			(xy 368.584988 -378.546868) (xy 368.594489 -378.541071) (xy 368.615778 -378.534615) (xy 368.626898 -378.534168)
			(xy 368.821462 -378.534168) (xy 368.833586 -378.534593) (xy 368.856649 -378.542078) (xy 368.876267 -378.556327)
			(xy 368.890518 -378.575944) (xy 368.898006 -378.599006) (xy 368.898424 -378.61113) (xy 368.898424 -379.29693)
			(xy 374.40616 -379.29693) (xy 374.40616 -378.61113) (xy 374.406586 -378.599007) (xy 374.414072 -378.575945)
			(xy 374.428322 -378.556328) (xy 374.447938 -378.542076) (xy 374.470999 -378.534587) (xy 374.483122 -378.534168)
			(xy 374.677686 -378.534168) (xy 374.68881 -378.534601) (xy 374.710107 -378.541047) (xy 374.719596 -378.546868)
			(xy 375.01322 -378.7394) (xy 375.022583 -378.74514) (xy 375.043605 -378.751469) (xy 375.06556 -378.751532)
			(xy 375.086618 -378.745325) (xy 375.096024 -378.739654) (xy 375.392188 -378.546868) (xy 375.401689 -378.541071)
			(xy 375.422978 -378.534615) (xy 375.434098 -378.534168) (xy 375.628662 -378.534168) (xy 375.640786 -378.534593)
			(xy 375.663849 -378.542078) (xy 375.683467 -378.556327) (xy 375.697718 -378.575944) (xy 375.705206 -378.599006)
			(xy 375.705624 -378.61113) (xy 375.705624 -379.29693) (xy 381.21336 -379.29693) (xy 381.21336 -378.61113)
			(xy 381.213786 -378.599007) (xy 381.221272 -378.575945) (xy 381.235522 -378.556328) (xy 381.255138 -378.542076)
			(xy 381.278199 -378.534587) (xy 381.290322 -378.534168) (xy 381.484886 -378.534168) (xy 381.49601 -378.534601)
			(xy 381.517307 -378.541047) (xy 381.526796 -378.546868) (xy 381.82042 -378.7394) (xy 381.829783 -378.74514)
			(xy 381.850805 -378.751469) (xy 381.87276 -378.751532) (xy 381.893818 -378.745325) (xy 381.903224 -378.739654)
			(xy 382.199388 -378.546868) (xy 382.208889 -378.541071) (xy 382.230178 -378.534615) (xy 382.241298 -378.534168)
			(xy 382.435862 -378.534168) (xy 382.447986 -378.534593) (xy 382.471049 -378.542078) (xy 382.490667 -378.556327)
			(xy 382.504918 -378.575944) (xy 382.512406 -378.599006) (xy 382.512824 -378.61113) (xy 382.512824 -379.29693)
			(xy 388.02056 -379.29693) (xy 388.02056 -378.61113) (xy 388.020986 -378.599007) (xy 388.028472 -378.575945)
			(xy 388.042722 -378.556328) (xy 388.062338 -378.542076) (xy 388.085399 -378.534587) (xy 388.097522 -378.534168)
			(xy 388.292086 -378.534168) (xy 388.30321 -378.534601) (xy 388.324507 -378.541047) (xy 388.333996 -378.546868)
			(xy 388.62762 -378.7394) (xy 388.636983 -378.74514) (xy 388.658005 -378.751469) (xy 388.67996 -378.751532)
			(xy 388.701018 -378.745325) (xy 388.710424 -378.739654) (xy 389.006588 -378.546868) (xy 389.016089 -378.541071)
			(xy 389.037378 -378.534615) (xy 389.048498 -378.534168) (xy 389.243062 -378.534168) (xy 389.255186 -378.534593)
			(xy 389.278249 -378.542078) (xy 389.297867 -378.556327) (xy 389.312118 -378.575944) (xy 389.319606 -378.599006)
			(xy 389.320024 -378.61113) (xy 389.320024 -379.29693) (xy 391.42416 -379.29693) (xy 391.42416 -378.61113)
			(xy 391.424586 -378.599007) (xy 391.432072 -378.575945) (xy 391.446322 -378.556328) (xy 391.465938 -378.542076)
			(xy 391.488999 -378.534587) (xy 391.501122 -378.534168) (xy 391.695686 -378.534168) (xy 391.70681 -378.534601)
			(xy 391.728107 -378.541047) (xy 391.737596 -378.546868) (xy 392.03122 -378.7394) (xy 392.040583 -378.74514)
			(xy 392.061605 -378.751469) (xy 392.08356 -378.751532) (xy 392.104618 -378.745325) (xy 392.114024 -378.739654)
			(xy 392.410188 -378.546868) (xy 392.419689 -378.541071) (xy 392.440978 -378.534615) (xy 392.452098 -378.534168)
			(xy 392.646662 -378.534168) (xy 392.658786 -378.534593) (xy 392.681849 -378.542078) (xy 392.701467 -378.556327)
			(xy 392.715718 -378.575944) (xy 392.723206 -378.599006) (xy 392.723624 -378.61113) (xy 392.723624 -379.29693)
			(xy 400.126708 -379.29693) (xy 400.126708 -378.61113) (xy 400.127237 -378.59902) (xy 400.134712 -378.575983)
			(xy 400.14894 -378.556383) (xy 400.168529 -378.54214) (xy 400.19156 -378.534646) (xy 400.20367 -378.534168)
			(xy 400.398234 -378.534168) (xy 400.40936 -378.534581) (xy 400.430657 -378.54104) (xy 400.440144 -378.546868)
			(xy 400.733768 -378.7394) (xy 400.743156 -378.745096) (xy 400.764166 -378.751434) (xy 400.786112 -378.75151)
			(xy 400.807166 -378.745317) (xy 400.816572 -378.739654) (xy 401.112736 -378.546868) (xy 401.122227 -378.541054)
			(xy 401.143524 -378.534609) (xy 401.154646 -378.534168) (xy 401.34921 -378.534168) (xy 401.361336 -378.534552)
			(xy 401.3844 -378.542051) (xy 401.404018 -378.556311) (xy 401.418268 -378.575935) (xy 401.425754 -378.599004)
			(xy 401.426172 -378.61113) (xy 401.426172 -379.29693) (xy 406.933908 -379.29693) (xy 406.933908 -378.61113)
			(xy 406.934437 -378.59902) (xy 406.941912 -378.575983) (xy 406.95614 -378.556383) (xy 406.975729 -378.54214)
			(xy 406.99876 -378.534646) (xy 407.01087 -378.534168) (xy 407.205434 -378.534168) (xy 407.21656 -378.534581)
			(xy 407.237857 -378.54104) (xy 407.247344 -378.546868) (xy 407.540968 -378.7394) (xy 407.550356 -378.745096)
			(xy 407.571366 -378.751434) (xy 407.593312 -378.75151) (xy 407.614366 -378.745317) (xy 407.623772 -378.739654)
			(xy 407.919936 -378.546868) (xy 407.929427 -378.541054) (xy 407.950724 -378.534609) (xy 407.961846 -378.534168)
			(xy 408.15641 -378.534168) (xy 408.168536 -378.534552) (xy 408.1916 -378.542051) (xy 408.211218 -378.556311)
			(xy 408.225468 -378.575935) (xy 408.232954 -378.599004) (xy 408.233372 -378.61113) (xy 408.233372 -379.29693)
			(xy 413.741108 -379.29693) (xy 413.741108 -378.61113) (xy 413.741637 -378.59902) (xy 413.749112 -378.575983)
			(xy 413.76334 -378.556383) (xy 413.782929 -378.54214) (xy 413.80596 -378.534646) (xy 413.81807 -378.534168)
			(xy 414.012634 -378.534168) (xy 414.02376 -378.534581) (xy 414.045057 -378.54104) (xy 414.054544 -378.546868)
			(xy 414.348168 -378.7394) (xy 414.357556 -378.745096) (xy 414.378566 -378.751434) (xy 414.400512 -378.75151)
			(xy 414.421566 -378.745317) (xy 414.430972 -378.739654) (xy 414.727136 -378.546868) (xy 414.736627 -378.541054)
			(xy 414.757924 -378.534609) (xy 414.769046 -378.534168) (xy 414.96361 -378.534168) (xy 414.975736 -378.534552)
			(xy 414.9988 -378.542051) (xy 415.018418 -378.556311) (xy 415.032668 -378.575935) (xy 415.040154 -378.599004)
			(xy 415.040572 -378.61113) (xy 415.040572 -379.29693) (xy 420.548308 -379.29693) (xy 420.548308 -378.61113)
			(xy 420.548837 -378.59902) (xy 420.556312 -378.575983) (xy 420.57054 -378.556383) (xy 420.590129 -378.54214)
			(xy 420.61316 -378.534646) (xy 420.62527 -378.534168) (xy 420.819834 -378.534168) (xy 420.83096 -378.534581)
			(xy 420.852257 -378.54104) (xy 420.861744 -378.546868) (xy 421.155368 -378.7394) (xy 421.164756 -378.745096)
			(xy 421.185766 -378.751434) (xy 421.207712 -378.75151) (xy 421.228766 -378.745317) (xy 421.238172 -378.739654)
			(xy 421.534336 -378.546868) (xy 421.543827 -378.541054) (xy 421.565124 -378.534609) (xy 421.576246 -378.534168)
			(xy 421.77081 -378.534168) (xy 421.782936 -378.534552) (xy 421.806 -378.542051) (xy 421.825618 -378.556311)
			(xy 421.839868 -378.575935) (xy 421.847354 -378.599004) (xy 421.847772 -378.61113) (xy 421.847772 -379.29693)
			(xy 423.951908 -379.29693) (xy 423.951908 -378.61113) (xy 423.952437 -378.59902) (xy 423.959912 -378.575983)
			(xy 423.97414 -378.556383) (xy 423.993729 -378.54214) (xy 424.01676 -378.534646) (xy 424.02887 -378.534168)
			(xy 424.223434 -378.534168) (xy 424.23456 -378.534581) (xy 424.255857 -378.54104) (xy 424.265344 -378.546868)
			(xy 424.558968 -378.7394) (xy 424.568356 -378.745096) (xy 424.589366 -378.751434) (xy 424.611312 -378.75151)
			(xy 424.632366 -378.745317) (xy 424.641772 -378.739654) (xy 424.937936 -378.546868) (xy 424.947427 -378.541054)
			(xy 424.968724 -378.534609) (xy 424.979846 -378.534168) (xy 425.17441 -378.534168) (xy 425.186536 -378.534552)
			(xy 425.2096 -378.542051) (xy 425.229218 -378.556311) (xy 425.243468 -378.575935) (xy 425.250954 -378.599004)
			(xy 425.251372 -378.61113) (xy 425.251372 -379.29693) (xy 425.250914 -379.309045) (xy 425.24342 -379.332088)
			(xy 425.229174 -379.351688) (xy 425.20957 -379.365929) (xy 425.186525 -379.373417) (xy 425.17441 -379.373892)
			(xy 424.979846 -379.373892) (xy 424.96872 -379.373478) (xy 424.947424 -379.367018) (xy 424.937936 -379.361192)
			(xy 424.643042 -379.16866) (xy 424.633655 -379.162957) (xy 424.612617 -379.156684) (xy 424.590663 -379.156684)
			(xy 424.569625 -379.162957) (xy 424.560238 -379.16866) (xy 424.266614 -379.361192) (xy 424.257111 -379.366984)
			(xy 424.235824 -379.373443) (xy 424.224704 -379.373892) (xy 424.02887 -379.373892) (xy 424.016757 -379.373414)
			(xy 423.993718 -379.365923) (xy 423.974119 -379.351681) (xy 423.959877 -379.332082) (xy 423.952386 -379.309043)
			(xy 423.951908 -379.29693) (xy 421.847772 -379.29693) (xy 421.847314 -379.309045) (xy 421.83982 -379.332088)
			(xy 421.825574 -379.351688) (xy 421.80597 -379.365929) (xy 421.782925 -379.373417) (xy 421.77081 -379.373892)
			(xy 421.576246 -379.373892) (xy 421.56512 -379.373478) (xy 421.543824 -379.367018) (xy 421.534336 -379.361192)
			(xy 421.239442 -379.16866) (xy 421.230055 -379.162957) (xy 421.209017 -379.156684) (xy 421.187063 -379.156684)
			(xy 421.166025 -379.162957) (xy 421.156638 -379.16866) (xy 420.863014 -379.361192) (xy 420.853511 -379.366984)
			(xy 420.832224 -379.373443) (xy 420.821104 -379.373892) (xy 420.62527 -379.373892) (xy 420.613157 -379.373414)
			(xy 420.590118 -379.365923) (xy 420.570519 -379.351681) (xy 420.556277 -379.332082) (xy 420.548786 -379.309043)
			(xy 420.548308 -379.29693) (xy 415.040572 -379.29693) (xy 415.040114 -379.309045) (xy 415.03262 -379.332088)
			(xy 415.018374 -379.351688) (xy 414.99877 -379.365929) (xy 414.975725 -379.373417) (xy 414.96361 -379.373892)
			(xy 414.769046 -379.373892) (xy 414.75792 -379.373478) (xy 414.736624 -379.367018) (xy 414.727136 -379.361192)
			(xy 414.432242 -379.16866) (xy 414.422855 -379.162957) (xy 414.401817 -379.156684) (xy 414.379863 -379.156684)
			(xy 414.358825 -379.162957) (xy 414.349438 -379.16866) (xy 414.055814 -379.361192) (xy 414.046311 -379.366984)
			(xy 414.025024 -379.373443) (xy 414.013904 -379.373892) (xy 413.81807 -379.373892) (xy 413.805957 -379.373414)
			(xy 413.782918 -379.365923) (xy 413.763319 -379.351681) (xy 413.749077 -379.332082) (xy 413.741586 -379.309043)
			(xy 413.741108 -379.29693) (xy 408.233372 -379.29693) (xy 408.232914 -379.309045) (xy 408.22542 -379.332088)
			(xy 408.211174 -379.351688) (xy 408.19157 -379.365929) (xy 408.168525 -379.373417) (xy 408.15641 -379.373892)
			(xy 407.961846 -379.373892) (xy 407.95072 -379.373478) (xy 407.929424 -379.367018) (xy 407.919936 -379.361192)
			(xy 407.625042 -379.16866) (xy 407.615655 -379.162957) (xy 407.594617 -379.156684) (xy 407.572663 -379.156684)
			(xy 407.551625 -379.162957) (xy 407.542238 -379.16866) (xy 407.248614 -379.361192) (xy 407.239111 -379.366984)
			(xy 407.217824 -379.373443) (xy 407.206704 -379.373892) (xy 407.01087 -379.373892) (xy 406.998757 -379.373414)
			(xy 406.975718 -379.365923) (xy 406.956119 -379.351681) (xy 406.941877 -379.332082) (xy 406.934386 -379.309043)
			(xy 406.933908 -379.29693) (xy 401.426172 -379.29693) (xy 401.425714 -379.309045) (xy 401.41822 -379.332088)
			(xy 401.403974 -379.351688) (xy 401.38437 -379.365929) (xy 401.361325 -379.373417) (xy 401.34921 -379.373892)
			(xy 401.154646 -379.373892) (xy 401.14352 -379.373478) (xy 401.122224 -379.367018) (xy 401.112736 -379.361192)
			(xy 400.817842 -379.16866) (xy 400.808455 -379.162957) (xy 400.787417 -379.156684) (xy 400.765463 -379.156684)
			(xy 400.744425 -379.162957) (xy 400.735038 -379.16866) (xy 400.441414 -379.361192) (xy 400.431911 -379.366984)
			(xy 400.410624 -379.373443) (xy 400.399504 -379.373892) (xy 400.20367 -379.373892) (xy 400.191557 -379.373414)
			(xy 400.168518 -379.365923) (xy 400.148919 -379.351681) (xy 400.134677 -379.332082) (xy 400.127186 -379.309043)
			(xy 400.126708 -379.29693) (xy 392.723624 -379.29693) (xy 392.723265 -379.309058) (xy 392.71576 -379.332124)
			(xy 392.701494 -379.351742) (xy 392.681863 -379.365991) (xy 392.658791 -379.373476) (xy 392.646662 -379.373892)
			(xy 392.452098 -379.373892) (xy 392.440974 -379.373457) (xy 392.419677 -379.367012) (xy 392.410188 -379.361192)
			(xy 392.115294 -379.16866) (xy 392.105907 -379.162957) (xy 392.084869 -379.156684) (xy 392.062915 -379.156684)
			(xy 392.041877 -379.162957) (xy 392.03249 -379.16866) (xy 391.738866 -379.361192) (xy 391.729372 -379.367002)
			(xy 391.708078 -379.37345) (xy 391.696956 -379.373892) (xy 391.501122 -379.373892) (xy 391.489012 -379.37337)
			(xy 391.465974 -379.365892) (xy 391.446375 -379.351662) (xy 391.432131 -379.332072) (xy 391.424638 -379.30904)
			(xy 391.42416 -379.29693) (xy 389.320024 -379.29693) (xy 389.319665 -379.309058) (xy 389.31216 -379.332124)
			(xy 389.297894 -379.351742) (xy 389.278263 -379.365991) (xy 389.255191 -379.373476) (xy 389.243062 -379.373892)
			(xy 389.048498 -379.373892) (xy 389.037374 -379.373457) (xy 389.016077 -379.367012) (xy 389.006588 -379.361192)
			(xy 388.711694 -379.16866) (xy 388.702307 -379.162957) (xy 388.681269 -379.156684) (xy 388.659315 -379.156684)
			(xy 388.638277 -379.162957) (xy 388.62889 -379.16866) (xy 388.335266 -379.361192) (xy 388.325772 -379.367002)
			(xy 388.304478 -379.37345) (xy 388.293356 -379.373892) (xy 388.097522 -379.373892) (xy 388.085412 -379.37337)
			(xy 388.062374 -379.365892) (xy 388.042775 -379.351662) (xy 388.028531 -379.332072) (xy 388.021038 -379.30904)
			(xy 388.02056 -379.29693) (xy 382.512824 -379.29693) (xy 382.512465 -379.309058) (xy 382.50496 -379.332124)
			(xy 382.490694 -379.351742) (xy 382.471063 -379.365991) (xy 382.447991 -379.373476) (xy 382.435862 -379.373892)
			(xy 382.241298 -379.373892) (xy 382.230174 -379.373457) (xy 382.208877 -379.367012) (xy 382.199388 -379.361192)
			(xy 381.904494 -379.16866) (xy 381.895107 -379.162957) (xy 381.874069 -379.156684) (xy 381.852115 -379.156684)
			(xy 381.831077 -379.162957) (xy 381.82169 -379.16866) (xy 381.528066 -379.361192) (xy 381.518572 -379.367002)
			(xy 381.497278 -379.37345) (xy 381.486156 -379.373892) (xy 381.290322 -379.373892) (xy 381.278212 -379.37337)
			(xy 381.255174 -379.365892) (xy 381.235575 -379.351662) (xy 381.221331 -379.332072) (xy 381.213838 -379.30904)
			(xy 381.21336 -379.29693) (xy 375.705624 -379.29693) (xy 375.705265 -379.309058) (xy 375.69776 -379.332124)
			(xy 375.683494 -379.351742) (xy 375.663863 -379.365991) (xy 375.640791 -379.373476) (xy 375.628662 -379.373892)
			(xy 375.434098 -379.373892) (xy 375.422974 -379.373457) (xy 375.401677 -379.367012) (xy 375.392188 -379.361192)
			(xy 375.097294 -379.16866) (xy 375.087907 -379.162957) (xy 375.066869 -379.156684) (xy 375.044915 -379.156684)
			(xy 375.023877 -379.162957) (xy 375.01449 -379.16866) (xy 374.720866 -379.361192) (xy 374.711372 -379.367002)
			(xy 374.690078 -379.37345) (xy 374.678956 -379.373892) (xy 374.483122 -379.373892) (xy 374.471012 -379.37337)
			(xy 374.447974 -379.365892) (xy 374.428375 -379.351662) (xy 374.414131 -379.332072) (xy 374.406638 -379.30904)
			(xy 374.40616 -379.29693) (xy 368.898424 -379.29693) (xy 368.898065 -379.309058) (xy 368.89056 -379.332124)
			(xy 368.876294 -379.351742) (xy 368.856663 -379.365991) (xy 368.833591 -379.373476) (xy 368.821462 -379.373892)
			(xy 368.626898 -379.373892) (xy 368.615774 -379.373457) (xy 368.594477 -379.367012) (xy 368.584988 -379.361192)
			(xy 368.290094 -379.16866) (xy 368.280707 -379.162957) (xy 368.259669 -379.156684) (xy 368.237715 -379.156684)
			(xy 368.216677 -379.162957) (xy 368.20729 -379.16866) (xy 367.913666 -379.361192) (xy 367.904172 -379.367002)
			(xy 367.882878 -379.37345) (xy 367.871756 -379.373892) (xy 367.675922 -379.373892) (xy 367.663812 -379.37337)
			(xy 367.640774 -379.365892) (xy 367.621175 -379.351662) (xy 367.606931 -379.332072) (xy 367.599438 -379.30904)
			(xy 367.59896 -379.29693) (xy 358.151176 -379.29693) (xy 358.150719 -379.30902) (xy 358.143256 -379.332019)
			(xy 358.129066 -379.351597) (xy 358.109532 -379.365847) (xy 358.086556 -379.373381) (xy 358.074468 -379.373892)
			(xy 357.879904 -379.373892) (xy 357.86878 -379.373455) (xy 357.847484 -379.367011) (xy 357.837994 -379.361192)
			(xy 357.5431 -379.16866) (xy 357.533713 -379.162957) (xy 357.512675 -379.156684) (xy 357.490721 -379.156684)
			(xy 357.469683 -379.162957) (xy 357.460296 -379.16866) (xy 357.166672 -379.361192) (xy 357.157177 -379.367)
			(xy 357.135884 -379.373449) (xy 357.124762 -379.373892) (xy 356.928928 -379.373892) (xy 356.916845 -379.373463)
			(xy 356.893861 -379.366001) (xy 356.874309 -379.3518) (xy 356.860104 -379.33225) (xy 356.852639 -379.309267)
			(xy 356.85222 -379.297184) (xy 354.747566 -379.297184) (xy 354.747119 -379.30902) (xy 354.739656 -379.332019)
			(xy 354.725466 -379.351597) (xy 354.705932 -379.365847) (xy 354.682956 -379.373381) (xy 354.670868 -379.373892)
			(xy 354.476304 -379.373892) (xy 354.46518 -379.373455) (xy 354.443884 -379.367011) (xy 354.434394 -379.361192)
			(xy 354.1395 -379.16866) (xy 354.130113 -379.162957) (xy 354.109075 -379.156684) (xy 354.087121 -379.156684)
			(xy 354.066083 -379.162957) (xy 354.056696 -379.16866) (xy 353.763072 -379.361192) (xy 353.753577 -379.367)
			(xy 353.732284 -379.373449) (xy 353.721162 -379.373892) (xy 353.525328 -379.373892) (xy 353.513245 -379.373463)
			(xy 353.490261 -379.366001) (xy 353.470709 -379.3518) (xy 353.456504 -379.33225) (xy 353.449039 -379.309267)
			(xy 353.44862 -379.297184) (xy 347.940366 -379.297184) (xy 347.939919 -379.30902) (xy 347.932456 -379.332019)
			(xy 347.918266 -379.351597) (xy 347.898732 -379.365847) (xy 347.875756 -379.373381) (xy 347.863668 -379.373892)
			(xy 347.669104 -379.373892) (xy 347.65798 -379.373455) (xy 347.636684 -379.367011) (xy 347.627194 -379.361192)
			(xy 347.3323 -379.16866) (xy 347.322913 -379.162957) (xy 347.301875 -379.156684) (xy 347.279921 -379.156684)
			(xy 347.258883 -379.162957) (xy 347.249496 -379.16866) (xy 346.955872 -379.361192) (xy 346.946377 -379.367)
			(xy 346.925084 -379.373449) (xy 346.913962 -379.373892) (xy 346.718128 -379.373892) (xy 346.706045 -379.373463)
			(xy 346.683061 -379.366001) (xy 346.663509 -379.3518) (xy 346.649304 -379.33225) (xy 346.641839 -379.309267)
			(xy 346.64142 -379.297184) (xy 341.133166 -379.297184) (xy 341.132719 -379.30902) (xy 341.125256 -379.332019)
			(xy 341.111066 -379.351597) (xy 341.091532 -379.365847) (xy 341.068556 -379.373381) (xy 341.056468 -379.373892)
			(xy 340.861904 -379.373892) (xy 340.85078 -379.373455) (xy 340.829484 -379.367011) (xy 340.819994 -379.361192)
			(xy 340.5251 -379.16866) (xy 340.515713 -379.162957) (xy 340.494675 -379.156684) (xy 340.472721 -379.156684)
			(xy 340.451683 -379.162957) (xy 340.442296 -379.16866) (xy 340.148672 -379.361192) (xy 340.139177 -379.367)
			(xy 340.117884 -379.373449) (xy 340.106762 -379.373892) (xy 339.910928 -379.373892) (xy 339.898845 -379.373463)
			(xy 339.875861 -379.366001) (xy 339.856309 -379.3518) (xy 339.842104 -379.33225) (xy 339.834639 -379.309267)
			(xy 339.83422 -379.297184) (xy 334.325966 -379.297184) (xy 334.325519 -379.30902) (xy 334.318056 -379.332019)
			(xy 334.303866 -379.351597) (xy 334.284332 -379.365847) (xy 334.261356 -379.373381) (xy 334.249268 -379.373892)
			(xy 334.054704 -379.373892) (xy 334.04358 -379.373455) (xy 334.022284 -379.367011) (xy 334.012794 -379.361192)
			(xy 333.7179 -379.16866) (xy 333.708513 -379.162957) (xy 333.687475 -379.156684) (xy 333.665521 -379.156684)
			(xy 333.644483 -379.162957) (xy 333.635096 -379.16866) (xy 333.341472 -379.361192) (xy 333.331977 -379.367)
			(xy 333.310684 -379.373449) (xy 333.299562 -379.373892) (xy 333.103728 -379.373892) (xy 333.091645 -379.373463)
			(xy 333.068661 -379.366001) (xy 333.049109 -379.3518) (xy 333.034904 -379.33225) (xy 333.027439 -379.309267)
			(xy 333.02702 -379.297184) (xy 325.623419 -379.297184) (xy 325.623018 -379.309024) (xy 325.615549 -379.332031)
			(xy 325.601349 -379.351614) (xy 325.581802 -379.365862) (xy 325.558813 -379.373388) (xy 325.54672 -379.373892)
			(xy 325.352156 -379.373892) (xy 325.341031 -379.373474) (xy 325.319734 -379.367017) (xy 325.310246 -379.361192)
			(xy 325.015352 -379.16866) (xy 325.005965 -379.162957) (xy 324.984927 -379.156684) (xy 324.962973 -379.156684)
			(xy 324.941935 -379.162957) (xy 324.932548 -379.16866) (xy 324.638924 -379.361192) (xy 324.629419 -379.36698)
			(xy 324.608133 -379.373442) (xy 324.597014 -379.373892) (xy 324.40118 -379.373892) (xy 324.389103 -379.373452)
			(xy 324.366132 -379.365982) (xy 324.346594 -379.35178) (xy 324.332401 -379.332235) (xy 324.324942 -379.309261)
			(xy 324.324472 -379.297184) (xy 322.219819 -379.297184) (xy 322.219418 -379.309024) (xy 322.211949 -379.332031)
			(xy 322.197749 -379.351614) (xy 322.178202 -379.365862) (xy 322.155213 -379.373388) (xy 322.14312 -379.373892)
			(xy 321.948556 -379.373892) (xy 321.937431 -379.373474) (xy 321.916134 -379.367017) (xy 321.906646 -379.361192)
			(xy 321.611752 -379.16866) (xy 321.602365 -379.162957) (xy 321.581327 -379.156684) (xy 321.559373 -379.156684)
			(xy 321.538335 -379.162957) (xy 321.528948 -379.16866) (xy 321.235324 -379.361192) (xy 321.225819 -379.36698)
			(xy 321.204533 -379.373442) (xy 321.193414 -379.373892) (xy 320.99758 -379.373892) (xy 320.985503 -379.373452)
			(xy 320.962532 -379.365982) (xy 320.942994 -379.35178) (xy 320.928801 -379.332235) (xy 320.921342 -379.309261)
			(xy 320.920872 -379.297184) (xy 315.412619 -379.297184) (xy 315.412218 -379.309024) (xy 315.404749 -379.332031)
			(xy 315.390549 -379.351614) (xy 315.371002 -379.365862) (xy 315.348013 -379.373388) (xy 315.33592 -379.373892)
			(xy 315.141356 -379.373892) (xy 315.130231 -379.373474) (xy 315.108934 -379.367017) (xy 315.099446 -379.361192)
			(xy 314.804552 -379.16866) (xy 314.795165 -379.162957) (xy 314.774127 -379.156684) (xy 314.752173 -379.156684)
			(xy 314.731135 -379.162957) (xy 314.721748 -379.16866) (xy 314.428124 -379.361192) (xy 314.418619 -379.36698)
			(xy 314.397333 -379.373442) (xy 314.386214 -379.373892) (xy 314.19038 -379.373892) (xy 314.178303 -379.373452)
			(xy 314.155332 -379.365982) (xy 314.135794 -379.35178) (xy 314.121601 -379.332235) (xy 314.114142 -379.309261)
			(xy 314.113672 -379.297184) (xy 308.605419 -379.297184) (xy 308.605018 -379.309024) (xy 308.597549 -379.332031)
			(xy 308.583349 -379.351614) (xy 308.563802 -379.365862) (xy 308.540813 -379.373388) (xy 308.52872 -379.373892)
			(xy 308.334156 -379.373892) (xy 308.323031 -379.373474) (xy 308.301734 -379.367017) (xy 308.292246 -379.361192)
			(xy 307.997352 -379.16866) (xy 307.987965 -379.162957) (xy 307.966927 -379.156684) (xy 307.944973 -379.156684)
			(xy 307.923935 -379.162957) (xy 307.914548 -379.16866) (xy 307.620924 -379.361192) (xy 307.611419 -379.36698)
			(xy 307.590133 -379.373442) (xy 307.579014 -379.373892) (xy 307.38318 -379.373892) (xy 307.371103 -379.373452)
			(xy 307.348132 -379.365982) (xy 307.328594 -379.35178) (xy 307.314401 -379.332235) (xy 307.306942 -379.309261)
			(xy 307.306472 -379.297184) (xy 301.798219 -379.297184) (xy 301.797818 -379.309024) (xy 301.790349 -379.332031)
			(xy 301.776149 -379.351614) (xy 301.756602 -379.365862) (xy 301.733613 -379.373388) (xy 301.72152 -379.373892)
			(xy 301.526956 -379.373892) (xy 301.515831 -379.373474) (xy 301.494534 -379.367017) (xy 301.485046 -379.361192)
			(xy 301.190152 -379.16866) (xy 301.180765 -379.162957) (xy 301.159727 -379.156684) (xy 301.137773 -379.156684)
			(xy 301.116735 -379.162957) (xy 301.107348 -379.16866) (xy 300.813724 -379.361192) (xy 300.804219 -379.36698)
			(xy 300.782933 -379.373442) (xy 300.771814 -379.373892) (xy 300.57598 -379.373892) (xy 300.563903 -379.373452)
			(xy 300.540932 -379.365982) (xy 300.521394 -379.35178) (xy 300.507201 -379.332235) (xy 300.499742 -379.309261)
			(xy 300.499272 -379.297184) (xy 180.351012 -379.297184) (xy 180.345053 -379.303484) (xy 180.216896 -379.427428)
			(xy 180.083345 -379.54554) (xy 179.944665 -379.657585) (xy 179.801131 -379.763342) (xy 179.653028 -379.862599)
			(xy 179.577684 -379.908367) (xy 298.633654 -379.908367) (xy 298.633654 -379.853833) (xy 298.641415 -379.799854)
			(xy 298.656779 -379.747529) (xy 298.679433 -379.697923) (xy 298.708917 -379.652046) (xy 298.744629 -379.610831)
			(xy 298.785842 -379.575119) (xy 298.831719 -379.545635) (xy 298.881325 -379.522981) (xy 298.93365 -379.507616)
			(xy 298.987629 -379.499855) (xy 299.014896 -379.499368) (xy 299.878496 -379.499368) (xy 299.905769 -379.499771)
			(xy 299.959761 -379.507534) (xy 300.012098 -379.522901) (xy 300.061716 -379.54556) (xy 300.107603 -379.57505)
			(xy 300.148827 -379.61077) (xy 300.184548 -379.651993) (xy 300.214038 -379.697881) (xy 300.236698 -379.747498)
			(xy 300.252066 -379.799835) (xy 300.259828 -379.853827) (xy 300.259828 -379.908367) (xy 305.440854 -379.908367)
			(xy 305.440854 -379.853833) (xy 305.448615 -379.799854) (xy 305.463979 -379.747529) (xy 305.486633 -379.697923)
			(xy 305.516117 -379.652046) (xy 305.551829 -379.610831) (xy 305.593042 -379.575119) (xy 305.638919 -379.545635)
			(xy 305.688525 -379.522981) (xy 305.74085 -379.507616) (xy 305.794829 -379.499855) (xy 305.822096 -379.499368)
			(xy 306.685696 -379.499368) (xy 306.712969 -379.499771) (xy 306.766961 -379.507534) (xy 306.819298 -379.522901)
			(xy 306.868916 -379.54556) (xy 306.914803 -379.57505) (xy 306.956027 -379.61077) (xy 306.991748 -379.651993)
			(xy 307.021238 -379.697881) (xy 307.043898 -379.747498) (xy 307.059266 -379.799835) (xy 307.067028 -379.853827)
			(xy 307.067028 -379.908367) (xy 312.248054 -379.908367) (xy 312.248054 -379.853833) (xy 312.255815 -379.799854)
			(xy 312.271179 -379.747529) (xy 312.293833 -379.697923) (xy 312.323317 -379.652046) (xy 312.359029 -379.610831)
			(xy 312.400242 -379.575119) (xy 312.446119 -379.545635) (xy 312.495725 -379.522981) (xy 312.54805 -379.507616)
			(xy 312.602029 -379.499855) (xy 312.629296 -379.499368) (xy 313.492896 -379.499368) (xy 313.520169 -379.499771)
			(xy 313.574161 -379.507534) (xy 313.626498 -379.522901) (xy 313.676116 -379.54556) (xy 313.722003 -379.57505)
			(xy 313.763227 -379.61077) (xy 313.798948 -379.651993) (xy 313.828438 -379.697881) (xy 313.851098 -379.747498)
			(xy 313.866466 -379.799835) (xy 313.874228 -379.853827) (xy 313.874228 -379.908367) (xy 319.055254 -379.908367)
			(xy 319.055254 -379.853833) (xy 319.063015 -379.799854) (xy 319.078379 -379.747529) (xy 319.101033 -379.697923)
			(xy 319.130517 -379.652046) (xy 319.166229 -379.610831) (xy 319.207442 -379.575119) (xy 319.253319 -379.545635)
			(xy 319.302925 -379.522981) (xy 319.35525 -379.507616) (xy 319.409229 -379.499855) (xy 319.436496 -379.499368)
			(xy 320.300096 -379.499368) (xy 320.327369 -379.499771) (xy 320.381361 -379.507534) (xy 320.433698 -379.522901)
			(xy 320.483316 -379.54556) (xy 320.529203 -379.57505) (xy 320.570427 -379.61077) (xy 320.606148 -379.651993)
			(xy 320.635638 -379.697881) (xy 320.658298 -379.747498) (xy 320.673666 -379.799835) (xy 320.681428 -379.853827)
			(xy 320.681428 -379.908371) (xy 331.161332 -379.908371) (xy 331.161332 -379.853829) (xy 331.169094 -379.799843)
			(xy 331.184461 -379.747511) (xy 331.207121 -379.697898) (xy 331.23661 -379.652016) (xy 331.272329 -379.610798)
			(xy 331.313551 -379.575084) (xy 331.359437 -379.545599) (xy 331.409052 -379.522946) (xy 331.461386 -379.507585)
			(xy 331.515373 -379.499828) (xy 331.542644 -379.499368) (xy 332.406244 -379.499368) (xy 332.433513 -379.499798)
			(xy 332.487497 -379.507565) (xy 332.539825 -379.522935) (xy 332.589433 -379.545596) (xy 332.635312 -379.575085)
			(xy 332.676528 -379.610803) (xy 332.712241 -379.652023) (xy 332.741725 -379.697905) (xy 332.76438 -379.747516)
			(xy 332.779744 -379.799847) (xy 332.787506 -379.85383) (xy 332.787506 -379.90837) (xy 332.787506 -379.908371)
			(xy 337.968532 -379.908371) (xy 337.968532 -379.853829) (xy 337.976294 -379.799843) (xy 337.991661 -379.747511)
			(xy 338.014321 -379.697898) (xy 338.04381 -379.652016) (xy 338.079529 -379.610798) (xy 338.120751 -379.575084)
			(xy 338.166637 -379.545599) (xy 338.216252 -379.522946) (xy 338.268586 -379.507585) (xy 338.322573 -379.499828)
			(xy 338.349844 -379.499368) (xy 339.213444 -379.499368) (xy 339.240713 -379.499798) (xy 339.294697 -379.507565)
			(xy 339.347025 -379.522935) (xy 339.396633 -379.545596) (xy 339.442512 -379.575085) (xy 339.483728 -379.610803)
			(xy 339.519441 -379.652023) (xy 339.548925 -379.697905) (xy 339.57158 -379.747516) (xy 339.586944 -379.799847)
			(xy 339.594706 -379.85383) (xy 339.594706 -379.90837) (xy 339.594706 -379.908371) (xy 344.775732 -379.908371)
			(xy 344.775732 -379.853829) (xy 344.783494 -379.799843) (xy 344.798861 -379.747511) (xy 344.821521 -379.697898)
			(xy 344.85101 -379.652016) (xy 344.886729 -379.610798) (xy 344.927951 -379.575084) (xy 344.973837 -379.545599)
			(xy 345.023452 -379.522946) (xy 345.075786 -379.507585) (xy 345.129773 -379.499828) (xy 345.157044 -379.499368)
			(xy 346.020644 -379.499368) (xy 346.047913 -379.499798) (xy 346.101897 -379.507565) (xy 346.154225 -379.522935)
			(xy 346.203833 -379.545596) (xy 346.249712 -379.575085) (xy 346.290928 -379.610803) (xy 346.326641 -379.652023)
			(xy 346.356125 -379.697905) (xy 346.37878 -379.747516) (xy 346.394144 -379.799847) (xy 346.401906 -379.85383)
			(xy 346.401906 -379.90837) (xy 346.401906 -379.908371) (xy 351.582932 -379.908371) (xy 351.582932 -379.853829)
			(xy 351.590694 -379.799843) (xy 351.606061 -379.747511) (xy 351.628721 -379.697898) (xy 351.65821 -379.652016)
			(xy 351.693929 -379.610798) (xy 351.735151 -379.575084) (xy 351.781037 -379.545599) (xy 351.830652 -379.522946)
			(xy 351.882986 -379.507585) (xy 351.936973 -379.499828) (xy 351.964244 -379.499368) (xy 352.827844 -379.499368)
			(xy 352.855113 -379.499798) (xy 352.909097 -379.507565) (xy 352.961425 -379.522935) (xy 353.011033 -379.545596)
			(xy 353.056912 -379.575085) (xy 353.098128 -379.610803) (xy 353.133841 -379.652023) (xy 353.163325 -379.697905)
			(xy 353.18598 -379.747516) (xy 353.201344 -379.799847) (xy 353.209106 -379.85383) (xy 353.209106 -379.908367)
			(xy 365.733854 -379.908367) (xy 365.733854 -379.853833) (xy 365.741615 -379.799854) (xy 365.756979 -379.74753)
			(xy 365.779633 -379.697924) (xy 365.809116 -379.652047) (xy 365.844827 -379.610833) (xy 365.886041 -379.57512)
			(xy 365.931917 -379.545637) (xy 365.981522 -379.522982) (xy 366.033847 -379.507617) (xy 366.087825 -379.499855)
			(xy 366.115092 -379.499368) (xy 366.978692 -379.499368) (xy 367.005966 -379.499771) (xy 367.059957 -379.507533)
			(xy 367.112295 -379.5229) (xy 367.161913 -379.545559) (xy 367.207802 -379.575048) (xy 367.249026 -379.610768)
			(xy 367.284747 -379.651992) (xy 367.314238 -379.69788) (xy 367.336898 -379.747497) (xy 367.352265 -379.799835)
			(xy 367.360028 -379.853826) (xy 367.360028 -379.908367) (xy 372.541054 -379.908367) (xy 372.541054 -379.853833)
			(xy 372.548815 -379.799854) (xy 372.564179 -379.74753) (xy 372.586833 -379.697924) (xy 372.616316 -379.652047)
			(xy 372.652027 -379.610833) (xy 372.693241 -379.57512) (xy 372.739117 -379.545637) (xy 372.788722 -379.522982)
			(xy 372.841047 -379.507617) (xy 372.895025 -379.499855) (xy 372.922292 -379.499368) (xy 373.785892 -379.499368)
			(xy 373.813166 -379.499771) (xy 373.867157 -379.507533) (xy 373.919495 -379.5229) (xy 373.969113 -379.545559)
			(xy 374.015002 -379.575048) (xy 374.056226 -379.610768) (xy 374.091947 -379.651992) (xy 374.121438 -379.69788)
			(xy 374.144098 -379.747497) (xy 374.159465 -379.799835) (xy 374.167228 -379.853826) (xy 374.167228 -379.908367)
			(xy 379.348254 -379.908367) (xy 379.348254 -379.853833) (xy 379.356015 -379.799854) (xy 379.371379 -379.74753)
			(xy 379.394033 -379.697924) (xy 379.423516 -379.652047) (xy 379.459227 -379.610833) (xy 379.500441 -379.57512)
			(xy 379.546317 -379.545637) (xy 379.595922 -379.522982) (xy 379.648247 -379.507617) (xy 379.702225 -379.499855)
			(xy 379.729492 -379.499368) (xy 380.593092 -379.499368) (xy 380.620366 -379.499771) (xy 380.674357 -379.507533)
			(xy 380.726695 -379.5229) (xy 380.776313 -379.545559) (xy 380.822202 -379.575048) (xy 380.863426 -379.610768)
			(xy 380.899147 -379.651992) (xy 380.928638 -379.69788) (xy 380.951298 -379.747497) (xy 380.966665 -379.799835)
			(xy 380.974428 -379.853826) (xy 380.974428 -379.908367) (xy 386.155454 -379.908367) (xy 386.155454 -379.853833)
			(xy 386.163215 -379.799854) (xy 386.178579 -379.74753) (xy 386.201233 -379.697924) (xy 386.230716 -379.652047)
			(xy 386.266427 -379.610833) (xy 386.307641 -379.57512) (xy 386.353517 -379.545637) (xy 386.403122 -379.522982)
			(xy 386.455447 -379.507617) (xy 386.509425 -379.499855) (xy 386.536692 -379.499368) (xy 387.400292 -379.499368)
			(xy 387.427566 -379.499771) (xy 387.481557 -379.507533) (xy 387.533895 -379.5229) (xy 387.583513 -379.545559)
			(xy 387.629402 -379.575048) (xy 387.670626 -379.610768) (xy 387.706347 -379.651992) (xy 387.735838 -379.69788)
			(xy 387.758498 -379.747497) (xy 387.773865 -379.799835) (xy 387.781628 -379.853826) (xy 387.781628 -379.908371)
			(xy 398.261532 -379.908371) (xy 398.261532 -379.853829) (xy 398.269294 -379.799843) (xy 398.284661 -379.747511)
			(xy 398.30732 -379.697899) (xy 398.336809 -379.652017) (xy 398.372528 -379.6108) (xy 398.41375 -379.575085)
			(xy 398.459635 -379.545601) (xy 398.509249 -379.522947) (xy 398.561582 -379.507586) (xy 398.615569 -379.499829)
			(xy 398.64284 -379.499368) (xy 399.50644 -379.499368) (xy 399.53371 -379.499797) (xy 399.587693 -379.507564)
			(xy 399.640022 -379.522934) (xy 399.689631 -379.545594) (xy 399.735511 -379.575084) (xy 399.776727 -379.610802)
			(xy 399.81244 -379.652022) (xy 399.841925 -379.697904) (xy 399.86458 -379.747516) (xy 399.879944 -379.799846)
			(xy 399.887706 -379.85383) (xy 399.887706 -379.90837) (xy 399.887706 -379.908371) (xy 405.068732 -379.908371)
			(xy 405.068732 -379.853829) (xy 405.076494 -379.799843) (xy 405.091861 -379.747511) (xy 405.11452 -379.697899)
			(xy 405.144009 -379.652017) (xy 405.179728 -379.6108) (xy 405.22095 -379.575085) (xy 405.266835 -379.545601)
			(xy 405.316449 -379.522947) (xy 405.368782 -379.507586) (xy 405.422769 -379.499829) (xy 405.45004 -379.499368)
			(xy 406.31364 -379.499368) (xy 406.34091 -379.499797) (xy 406.394893 -379.507564) (xy 406.447222 -379.522934)
			(xy 406.496831 -379.545594) (xy 406.542711 -379.575084) (xy 406.583927 -379.610802) (xy 406.61964 -379.652022)
			(xy 406.649125 -379.697904) (xy 406.67178 -379.747516) (xy 406.687144 -379.799846) (xy 406.694906 -379.85383)
			(xy 406.694906 -379.90837) (xy 406.694906 -379.908371) (xy 411.875932 -379.908371) (xy 411.875932 -379.853829)
			(xy 411.883694 -379.799843) (xy 411.899061 -379.747511) (xy 411.92172 -379.697899) (xy 411.951209 -379.652017)
			(xy 411.986928 -379.6108) (xy 412.02815 -379.575085) (xy 412.074035 -379.545601) (xy 412.123649 -379.522947)
			(xy 412.175982 -379.507586) (xy 412.229969 -379.499829) (xy 412.25724 -379.499368) (xy 413.12084 -379.499368)
			(xy 413.14811 -379.499797) (xy 413.202093 -379.507564) (xy 413.254422 -379.522934) (xy 413.304031 -379.545594)
			(xy 413.349911 -379.575084) (xy 413.391127 -379.610802) (xy 413.42684 -379.652022) (xy 413.456325 -379.697904)
			(xy 413.47898 -379.747516) (xy 413.494344 -379.799846) (xy 413.502106 -379.85383) (xy 413.502106 -379.90837)
			(xy 413.502106 -379.908371) (xy 418.683132 -379.908371) (xy 418.683132 -379.853829) (xy 418.690894 -379.799843)
			(xy 418.706261 -379.747511) (xy 418.72892 -379.697899) (xy 418.758409 -379.652017) (xy 418.794128 -379.6108)
			(xy 418.83535 -379.575085) (xy 418.881235 -379.545601) (xy 418.930849 -379.522947) (xy 418.983182 -379.507586)
			(xy 419.037169 -379.499829) (xy 419.06444 -379.499368) (xy 419.92804 -379.499368) (xy 419.95531 -379.499797)
			(xy 420.009293 -379.507564) (xy 420.061622 -379.522934) (xy 420.111231 -379.545594) (xy 420.157111 -379.575084)
			(xy 420.198327 -379.610802) (xy 420.23404 -379.652022) (xy 420.263525 -379.697904) (xy 420.28618 -379.747516)
			(xy 420.301544 -379.799846) (xy 420.309306 -379.85383) (xy 420.309306 -379.90837) (xy 420.301544 -379.962354)
			(xy 420.28618 -380.014684) (xy 420.263525 -380.064296) (xy 420.23404 -380.110178) (xy 420.198327 -380.151398)
			(xy 420.157111 -380.187116) (xy 420.111231 -380.216606) (xy 420.061622 -380.239266) (xy 420.009293 -380.254636)
			(xy 419.95531 -380.262403) (xy 419.92804 -380.262892) (xy 419.06444 -380.262892) (xy 419.037169 -380.262371)
			(xy 418.983182 -380.254614) (xy 418.930849 -380.239253) (xy 418.881235 -380.216599) (xy 418.83535 -380.187115)
			(xy 418.794128 -380.1514) (xy 418.758409 -380.110183) (xy 418.72892 -380.064301) (xy 418.706261 -380.014689)
			(xy 418.690894 -379.962357) (xy 418.683132 -379.908371) (xy 413.502106 -379.908371) (xy 413.494344 -379.962354)
			(xy 413.47898 -380.014684) (xy 413.456325 -380.064296) (xy 413.42684 -380.110178) (xy 413.391127 -380.151398)
			(xy 413.349911 -380.187116) (xy 413.304031 -380.216606) (xy 413.254422 -380.239266) (xy 413.202093 -380.254636)
			(xy 413.14811 -380.262403) (xy 413.12084 -380.262892) (xy 412.25724 -380.262892) (xy 412.229969 -380.262371)
			(xy 412.175982 -380.254614) (xy 412.123649 -380.239253) (xy 412.074035 -380.216599) (xy 412.02815 -380.187115)
			(xy 411.986928 -380.1514) (xy 411.951209 -380.110183) (xy 411.92172 -380.064301) (xy 411.899061 -380.014689)
			(xy 411.883694 -379.962357) (xy 411.875932 -379.908371) (xy 406.694906 -379.908371) (xy 406.687144 -379.962354)
			(xy 406.67178 -380.014684) (xy 406.649125 -380.064296) (xy 406.61964 -380.110178) (xy 406.583927 -380.151398)
			(xy 406.542711 -380.187116) (xy 406.496831 -380.216606) (xy 406.447222 -380.239266) (xy 406.394893 -380.254636)
			(xy 406.34091 -380.262403) (xy 406.31364 -380.262892) (xy 405.45004 -380.262892) (xy 405.422769 -380.262371)
			(xy 405.368782 -380.254614) (xy 405.316449 -380.239253) (xy 405.266835 -380.216599) (xy 405.22095 -380.187115)
			(xy 405.179728 -380.1514) (xy 405.144009 -380.110183) (xy 405.11452 -380.064301) (xy 405.091861 -380.014689)
			(xy 405.076494 -379.962357) (xy 405.068732 -379.908371) (xy 399.887706 -379.908371) (xy 399.879944 -379.962354)
			(xy 399.86458 -380.014684) (xy 399.841925 -380.064296) (xy 399.81244 -380.110178) (xy 399.776727 -380.151398)
			(xy 399.735511 -380.187116) (xy 399.689631 -380.216606) (xy 399.640022 -380.239266) (xy 399.587693 -380.254636)
			(xy 399.53371 -380.262403) (xy 399.50644 -380.262892) (xy 398.64284 -380.262892) (xy 398.615569 -380.262371)
			(xy 398.561582 -380.254614) (xy 398.509249 -380.239253) (xy 398.459635 -380.216599) (xy 398.41375 -380.187115)
			(xy 398.372528 -380.1514) (xy 398.336809 -380.110183) (xy 398.30732 -380.064301) (xy 398.284661 -380.014689)
			(xy 398.269294 -379.962357) (xy 398.261532 -379.908371) (xy 387.781628 -379.908371) (xy 387.781628 -379.908374)
			(xy 387.773865 -379.962365) (xy 387.758498 -380.014703) (xy 387.735838 -380.06432) (xy 387.706347 -380.110208)
			(xy 387.670626 -380.151432) (xy 387.629402 -380.187152) (xy 387.583513 -380.216641) (xy 387.533895 -380.2393)
			(xy 387.481557 -380.254667) (xy 387.427566 -380.262429) (xy 387.400292 -380.262892) (xy 386.536692 -380.262892)
			(xy 386.509425 -380.262345) (xy 386.455447 -380.254583) (xy 386.403122 -380.239218) (xy 386.353517 -380.216563)
			(xy 386.307641 -380.18708) (xy 386.266427 -380.151367) (xy 386.230716 -380.110153) (xy 386.201233 -380.064276)
			(xy 386.178579 -380.01467) (xy 386.163215 -379.962346) (xy 386.155454 -379.908367) (xy 380.974428 -379.908367)
			(xy 380.974428 -379.908374) (xy 380.966665 -379.962365) (xy 380.951298 -380.014703) (xy 380.928638 -380.06432)
			(xy 380.899147 -380.110208) (xy 380.863426 -380.151432) (xy 380.822202 -380.187152) (xy 380.776313 -380.216641)
			(xy 380.726695 -380.2393) (xy 380.674357 -380.254667) (xy 380.620366 -380.262429) (xy 380.593092 -380.262892)
			(xy 379.729492 -380.262892) (xy 379.702225 -380.262345) (xy 379.648247 -380.254583) (xy 379.595922 -380.239218)
			(xy 379.546317 -380.216563) (xy 379.500441 -380.18708) (xy 379.459227 -380.151367) (xy 379.423516 -380.110153)
			(xy 379.394033 -380.064276) (xy 379.371379 -380.01467) (xy 379.356015 -379.962346) (xy 379.348254 -379.908367)
			(xy 374.167228 -379.908367) (xy 374.167228 -379.908374) (xy 374.159465 -379.962365) (xy 374.144098 -380.014703)
			(xy 374.121438 -380.06432) (xy 374.091947 -380.110208) (xy 374.056226 -380.151432) (xy 374.015002 -380.187152)
			(xy 373.969113 -380.216641) (xy 373.919495 -380.2393) (xy 373.867157 -380.254667) (xy 373.813166 -380.262429)
			(xy 373.785892 -380.262892) (xy 372.922292 -380.262892) (xy 372.895025 -380.262345) (xy 372.841047 -380.254583)
			(xy 372.788722 -380.239218) (xy 372.739117 -380.216563) (xy 372.693241 -380.18708) (xy 372.652027 -380.151367)
			(xy 372.616316 -380.110153) (xy 372.586833 -380.064276) (xy 372.564179 -380.01467) (xy 372.548815 -379.962346)
			(xy 372.541054 -379.908367) (xy 367.360028 -379.908367) (xy 367.360028 -379.908374) (xy 367.352265 -379.962365)
			(xy 367.336898 -380.014703) (xy 367.314238 -380.06432) (xy 367.284747 -380.110208) (xy 367.249026 -380.151432)
			(xy 367.207802 -380.187152) (xy 367.161913 -380.216641) (xy 367.112295 -380.2393) (xy 367.059957 -380.254667)
			(xy 367.005966 -380.262429) (xy 366.978692 -380.262892) (xy 366.115092 -380.262892) (xy 366.087825 -380.262345)
			(xy 366.033847 -380.254583) (xy 365.981522 -380.239218) (xy 365.931917 -380.216563) (xy 365.886041 -380.18708)
			(xy 365.844827 -380.151367) (xy 365.809116 -380.110153) (xy 365.779633 -380.064276) (xy 365.756979 -380.01467)
			(xy 365.741615 -379.962346) (xy 365.733854 -379.908367) (xy 353.209106 -379.908367) (xy 353.209106 -379.90837)
			(xy 353.201344 -379.962353) (xy 353.18598 -380.014684) (xy 353.163325 -380.064295) (xy 353.133841 -380.110177)
			(xy 353.098128 -380.151397) (xy 353.056912 -380.187115) (xy 353.011033 -380.216604) (xy 352.961425 -380.239265)
			(xy 352.909097 -380.254635) (xy 352.855113 -380.262402) (xy 352.827844 -380.262892) (xy 351.964244 -380.262892)
			(xy 351.936973 -380.262372) (xy 351.882986 -380.254615) (xy 351.830652 -380.239254) (xy 351.781037 -380.216601)
			(xy 351.735151 -380.187116) (xy 351.693929 -380.151402) (xy 351.65821 -380.110184) (xy 351.628721 -380.064302)
			(xy 351.606061 -380.014689) (xy 351.590694 -379.962357) (xy 351.582932 -379.908371) (xy 346.401906 -379.908371)
			(xy 346.394144 -379.962353) (xy 346.37878 -380.014684) (xy 346.356125 -380.064295) (xy 346.326641 -380.110177)
			(xy 346.290928 -380.151397) (xy 346.249712 -380.187115) (xy 346.203833 -380.216604) (xy 346.154225 -380.239265)
			(xy 346.101897 -380.254635) (xy 346.047913 -380.262402) (xy 346.020644 -380.262892) (xy 345.157044 -380.262892)
			(xy 345.129773 -380.262372) (xy 345.075786 -380.254615) (xy 345.023452 -380.239254) (xy 344.973837 -380.216601)
			(xy 344.927951 -380.187116) (xy 344.886729 -380.151402) (xy 344.85101 -380.110184) (xy 344.821521 -380.064302)
			(xy 344.798861 -380.014689) (xy 344.783494 -379.962357) (xy 344.775732 -379.908371) (xy 339.594706 -379.908371)
			(xy 339.586944 -379.962353) (xy 339.57158 -380.014684) (xy 339.548925 -380.064295) (xy 339.519441 -380.110177)
			(xy 339.483728 -380.151397) (xy 339.442512 -380.187115) (xy 339.396633 -380.216604) (xy 339.347025 -380.239265)
			(xy 339.294697 -380.254635) (xy 339.240713 -380.262402) (xy 339.213444 -380.262892) (xy 338.349844 -380.262892)
			(xy 338.322573 -380.262372) (xy 338.268586 -380.254615) (xy 338.216252 -380.239254) (xy 338.166637 -380.216601)
			(xy 338.120751 -380.187116) (xy 338.079529 -380.151402) (xy 338.04381 -380.110184) (xy 338.014321 -380.064302)
			(xy 337.991661 -380.014689) (xy 337.976294 -379.962357) (xy 337.968532 -379.908371) (xy 332.787506 -379.908371)
			(xy 332.779744 -379.962353) (xy 332.76438 -380.014684) (xy 332.741725 -380.064295) (xy 332.712241 -380.110177)
			(xy 332.676528 -380.151397) (xy 332.635312 -380.187115) (xy 332.589433 -380.216604) (xy 332.539825 -380.239265)
			(xy 332.487497 -380.254635) (xy 332.433513 -380.262402) (xy 332.406244 -380.262892) (xy 331.542644 -380.262892)
			(xy 331.515373 -380.262372) (xy 331.461386 -380.254615) (xy 331.409052 -380.239254) (xy 331.359437 -380.216601)
			(xy 331.313551 -380.187116) (xy 331.272329 -380.151402) (xy 331.23661 -380.110184) (xy 331.207121 -380.064302)
			(xy 331.184461 -380.014689) (xy 331.169094 -379.962357) (xy 331.161332 -379.908371) (xy 320.681428 -379.908371)
			(xy 320.681428 -379.908373) (xy 320.673666 -379.962365) (xy 320.658298 -380.014702) (xy 320.635638 -380.064319)
			(xy 320.606148 -380.110207) (xy 320.570427 -380.15143) (xy 320.529203 -380.18715) (xy 320.483316 -380.21664)
			(xy 320.433698 -380.239299) (xy 320.381361 -380.254666) (xy 320.327369 -380.262429) (xy 320.300096 -380.262892)
			(xy 319.436496 -380.262892) (xy 319.409229 -380.262345) (xy 319.35525 -380.254584) (xy 319.302925 -380.239219)
			(xy 319.253319 -380.216565) (xy 319.207442 -380.187081) (xy 319.166229 -380.151369) (xy 319.130517 -380.110154)
			(xy 319.101033 -380.064277) (xy 319.078379 -380.014671) (xy 319.063015 -379.962346) (xy 319.055254 -379.908367)
			(xy 313.874228 -379.908367) (xy 313.874228 -379.908373) (xy 313.866466 -379.962365) (xy 313.851098 -380.014702)
			(xy 313.828438 -380.064319) (xy 313.798948 -380.110207) (xy 313.763227 -380.15143) (xy 313.722003 -380.18715)
			(xy 313.676116 -380.21664) (xy 313.626498 -380.239299) (xy 313.574161 -380.254666) (xy 313.520169 -380.262429)
			(xy 313.492896 -380.262892) (xy 312.629296 -380.262892) (xy 312.602029 -380.262345) (xy 312.54805 -380.254584)
			(xy 312.495725 -380.239219) (xy 312.446119 -380.216565) (xy 312.400242 -380.187081) (xy 312.359029 -380.151369)
			(xy 312.323317 -380.110154) (xy 312.293833 -380.064277) (xy 312.271179 -380.014671) (xy 312.255815 -379.962346)
			(xy 312.248054 -379.908367) (xy 307.067028 -379.908367) (xy 307.067028 -379.908373) (xy 307.059266 -379.962365)
			(xy 307.043898 -380.014702) (xy 307.021238 -380.064319) (xy 306.991748 -380.110207) (xy 306.956027 -380.15143)
			(xy 306.914803 -380.18715) (xy 306.868916 -380.21664) (xy 306.819298 -380.239299) (xy 306.766961 -380.254666)
			(xy 306.712969 -380.262429) (xy 306.685696 -380.262892) (xy 305.822096 -380.262892) (xy 305.794829 -380.262345)
			(xy 305.74085 -380.254584) (xy 305.688525 -380.239219) (xy 305.638919 -380.216565) (xy 305.593042 -380.187081)
			(xy 305.551829 -380.151369) (xy 305.516117 -380.110154) (xy 305.486633 -380.064277) (xy 305.463979 -380.014671)
			(xy 305.448615 -379.962346) (xy 305.440854 -379.908367) (xy 300.259828 -379.908367) (xy 300.259828 -379.908373)
			(xy 300.252066 -379.962365) (xy 300.236698 -380.014702) (xy 300.214038 -380.064319) (xy 300.184548 -380.110207)
			(xy 300.148827 -380.15143) (xy 300.107603 -380.18715) (xy 300.061716 -380.21664) (xy 300.012098 -380.239299)
			(xy 299.959761 -380.254666) (xy 299.905769 -380.262429) (xy 299.878496 -380.262892) (xy 299.014896 -380.262892)
			(xy 298.987629 -380.262345) (xy 298.93365 -380.254584) (xy 298.881325 -380.239219) (xy 298.831719 -380.216565)
			(xy 298.785842 -380.187081) (xy 298.744629 -380.151369) (xy 298.708917 -380.110154) (xy 298.679433 -380.064277)
			(xy 298.656779 -380.014671) (xy 298.641415 -379.962346) (xy 298.633654 -379.908367) (xy 179.577684 -379.908367)
			(xy 179.500651 -379.955161) (xy 179.344302 -380.040842) (xy 179.184291 -380.119474) (xy 179.020937 -380.1909)
			(xy 178.854562 -380.254978) (xy 178.685499 -380.31158) (xy 178.514082 -380.360596) (xy 178.340651 -380.401926)
			(xy 178.165551 -380.43549) (xy 177.989131 -380.46122) (xy 177.811739 -380.479066) (xy 177.633728 -380.488992)
			(xy 177.455451 -380.490978) (xy 177.277264 -380.485021) (xy 177.099518 -380.471131) (xy 176.922568 -380.449338)
			(xy 176.746764 -380.419684) (xy 176.572456 -380.382227) (xy 176.399989 -380.337043) (xy 176.229706 -380.284221)
			(xy 176.061945 -380.223865) (xy 175.89704 -380.156097) (xy 175.735317 -380.081049) (xy 175.577098 -379.998872)
			(xy 175.422697 -379.909729) (xy 175.27242 -379.813795) (xy 175.126565 -379.711263) (xy 174.985423 -379.602335)
			(xy 174.849274 -379.487228) (xy 174.718387 -379.36617) (xy 174.593023 -379.239401) (xy 174.47343 -379.107174)
			(xy 174.359847 -378.969751) (xy 174.252498 -378.827404) (xy 174.151597 -378.680416) (xy 174.057344 -378.52908)
			(xy 173.969926 -378.373695) (xy 173.889516 -378.21457) (xy 173.816275 -378.052021) (xy 173.750348 -377.886371)
			(xy 173.691865 -377.717949) (xy 173.640943 -377.547088) (xy 173.597683 -377.374129) (xy 173.562171 -377.199414)
			(xy 173.534477 -377.02329) (xy 173.514656 -376.846108) (xy 173.502748 -376.668219) (xy 173.498776 -376.489976)
			(xy 171.286932 -376.489976) (xy 171.286932 -376.956828) (xy 171.286446 -376.984079) (xy 171.27869 -377.038027)
			(xy 171.263335 -377.090322) (xy 171.240693 -377.139899) (xy 171.211227 -377.185749) (xy 171.175536 -377.22694)
			(xy 171.134345 -377.262631) (xy 171.088495 -377.292097) (xy 171.038918 -377.314739) (xy 170.986623 -377.330094)
			(xy 170.932675 -377.33785) (xy 170.878173 -377.33785) (xy 170.824225 -377.330094) (xy 170.77193 -377.314739)
			(xy 170.722353 -377.292097) (xy 170.676503 -377.262631) (xy 170.635312 -377.22694) (xy 170.599621 -377.185749)
			(xy 170.570155 -377.139899) (xy 170.547513 -377.090322) (xy 170.532158 -377.038027) (xy 170.524402 -376.984079)
			(xy 170.523916 -376.956828) (xy 169.788332 -376.956828) (xy 169.788332 -377.097798) (xy 169.78789 -377.10989)
			(xy 169.780431 -377.132895) (xy 169.766239 -377.152478) (xy 169.746698 -377.166727) (xy 169.723715 -377.174254)
			(xy 169.711624 -377.17476) (xy 169.025824 -377.17476) (xy 169.013738 -377.174366) (xy 168.990748 -377.166899)
			(xy 168.971193 -377.15269) (xy 168.95699 -377.133131) (xy 168.94953 -377.110138) (xy 168.949116 -377.098052)
			(xy 141.331901 -377.098052) (xy 141.328504 -377.101972) (xy 141.287313 -377.137663) (xy 141.241463 -377.167129)
			(xy 141.191886 -377.189771) (xy 141.139591 -377.205126) (xy 141.085643 -377.212882) (xy 141.031141 -377.212882)
			(xy 140.977193 -377.205126) (xy 140.924898 -377.189771) (xy 140.875321 -377.167129) (xy 140.829471 -377.137663)
			(xy 140.78828 -377.101972) (xy 140.752589 -377.060781) (xy 140.723123 -377.014931) (xy 140.700481 -376.965354)
			(xy 140.685126 -376.913059) (xy 140.67737 -376.859111) (xy 140.676884 -376.83186) (xy 138.759184 -376.83186)
			(xy 138.759184 -376.956828) (xy 138.758698 -376.984079) (xy 138.750942 -377.038027) (xy 138.735587 -377.090322)
			(xy 138.712945 -377.139899) (xy 138.683479 -377.185749) (xy 138.647788 -377.22694) (xy 138.606597 -377.262631)
			(xy 138.560747 -377.292097) (xy 138.51117 -377.314739) (xy 138.458875 -377.330094) (xy 138.404927 -377.33785)
			(xy 138.350425 -377.33785) (xy 138.296477 -377.330094) (xy 138.244182 -377.314739) (xy 138.194605 -377.292097)
			(xy 138.148755 -377.262631) (xy 138.107564 -377.22694) (xy 138.071873 -377.185749) (xy 138.042407 -377.139899)
			(xy 138.019765 -377.090322) (xy 138.00441 -377.038027) (xy 137.996654 -376.984079) (xy 137.996168 -376.956828)
			(xy 137.260584 -376.956828) (xy 137.260584 -377.097798) (xy 137.260091 -377.109885) (xy 137.252638 -377.132882)
			(xy 137.238457 -377.152459) (xy 137.218931 -377.166711) (xy 137.195961 -377.174247) (xy 137.183876 -377.17476)
			(xy 136.498076 -377.17476) (xy 136.485987 -377.174407) (xy 136.462996 -377.166927) (xy 136.443442 -377.152707)
			(xy 136.42924 -377.13314) (xy 136.421782 -377.110141) (xy 136.421368 -377.098052) (xy 108.804153 -377.098052)
			(xy 108.800756 -377.101972) (xy 108.759565 -377.137663) (xy 108.713715 -377.167129) (xy 108.664138 -377.189771)
			(xy 108.611843 -377.205126) (xy 108.557895 -377.212882) (xy 108.503393 -377.212882) (xy 108.449445 -377.205126)
			(xy 108.39715 -377.189771) (xy 108.347573 -377.167129) (xy 108.301723 -377.137663) (xy 108.260532 -377.101972)
			(xy 108.224841 -377.060781) (xy 108.195375 -377.014931) (xy 108.172733 -376.965354) (xy 108.157378 -376.913059)
			(xy 108.149622 -376.859111) (xy 108.149136 -376.83186) (xy 104.187244 -376.83186) (xy 104.187244 -376.956828)
			(xy 104.186758 -376.984097) (xy 104.178996 -377.038081) (xy 104.163631 -377.090411) (xy 104.140974 -377.140021)
			(xy 104.111488 -377.185902) (xy 104.075773 -377.227119) (xy 104.034556 -377.262834) (xy 103.988675 -377.29232)
			(xy 103.939065 -377.314977) (xy 103.886735 -377.330342) (xy 103.832751 -377.338104) (xy 103.778213 -377.338104)
			(xy 103.724229 -377.330342) (xy 103.671899 -377.314977) (xy 103.622289 -377.29232) (xy 103.576408 -377.262834)
			(xy 103.535191 -377.227119) (xy 103.499476 -377.185902) (xy 103.46999 -377.140021) (xy 103.447333 -377.090411)
			(xy 103.431968 -377.038081) (xy 103.424206 -376.984097) (xy 103.42372 -376.956828) (xy 102.688644 -376.956828)
			(xy 102.688644 -377.097798) (xy 102.688238 -377.109922) (xy 102.680744 -377.132984) (xy 102.666489 -377.152601)
			(xy 102.64687 -377.166851) (xy 102.623807 -377.17434) (xy 102.611682 -377.17476) (xy 101.925882 -377.17476)
			(xy 101.913766 -377.174304) (xy 101.890722 -377.166811) (xy 101.87112 -377.152565) (xy 101.85688 -377.13296)
			(xy 101.849393 -377.109914) (xy 101.84892 -377.097798) (xy 74.232513 -377.097798) (xy 74.228741 -377.102151)
			(xy 74.187524 -377.137866) (xy 74.141643 -377.167352) (xy 74.092033 -377.190009) (xy 74.039703 -377.205374)
			(xy 73.985719 -377.213136) (xy 73.931181 -377.213136) (xy 73.877197 -377.205374) (xy 73.824867 -377.190009)
			(xy 73.775257 -377.167352) (xy 73.729376 -377.137866) (xy 73.688159 -377.102151) (xy 73.652444 -377.060934)
			(xy 73.622958 -377.015053) (xy 73.600301 -376.965443) (xy 73.584936 -376.913113) (xy 73.577174 -376.859129)
			(xy 73.576688 -376.83186) (xy 71.659496 -376.83186) (xy 71.659496 -376.956828) (xy 71.65901 -376.984097)
			(xy 71.651248 -377.038081) (xy 71.635883 -377.090411) (xy 71.613226 -377.140021) (xy 71.58374 -377.185902)
			(xy 71.548025 -377.227119) (xy 71.506808 -377.262834) (xy 71.460927 -377.29232) (xy 71.411317 -377.314977)
			(xy 71.358987 -377.330342) (xy 71.305003 -377.338104) (xy 71.250465 -377.338104) (xy 71.196481 -377.330342)
			(xy 71.144151 -377.314977) (xy 71.094541 -377.29232) (xy 71.04866 -377.262834) (xy 71.007443 -377.227119)
			(xy 70.971728 -377.185902) (xy 70.942242 -377.140021) (xy 70.919585 -377.090411) (xy 70.90422 -377.038081)
			(xy 70.896458 -376.984097) (xy 70.895972 -376.956828) (xy 70.160896 -376.956828) (xy 70.160896 -377.097798)
			(xy 70.160387 -377.109909) (xy 70.152904 -377.132946) (xy 70.138671 -377.152545) (xy 70.119079 -377.166788)
			(xy 70.096045 -377.174281) (xy 70.083934 -377.17476) (xy 69.398134 -377.17476) (xy 69.386013 -377.174311)
			(xy 69.362955 -377.166828) (xy 69.343339 -377.152584) (xy 69.329087 -377.132974) (xy 69.321594 -377.109919)
			(xy 69.321172 -377.097798) (xy 41.704765 -377.097798) (xy 41.700993 -377.102151) (xy 41.659776 -377.137866)
			(xy 41.613895 -377.167352) (xy 41.564285 -377.190009) (xy 41.511955 -377.205374) (xy 41.457971 -377.213136)
			(xy 41.403433 -377.213136) (xy 41.349449 -377.205374) (xy 41.297119 -377.190009) (xy 41.247509 -377.167352)
			(xy 41.201628 -377.137866) (xy 41.160411 -377.102151) (xy 41.124696 -377.060934) (xy 41.09521 -377.015053)
			(xy 41.072553 -376.965443) (xy 41.057188 -376.913113) (xy 41.049426 -376.859129) (xy 41.04894 -376.83186)
			(xy 39.05568 -376.83186) (xy 39.046481 -376.93481) (xy 39.022717 -377.111506) (xy 38.991106 -377.286969)
			(xy 38.95171 -377.460849) (xy 38.904608 -377.632802) (xy 38.849892 -377.802486) (xy 38.787671 -377.969563)
			(xy 38.71807 -378.133704) (xy 38.641225 -378.29458) (xy 38.557291 -378.451874) (xy 38.466433 -378.605273)
			(xy 38.368831 -378.754472) (xy 38.26468 -378.899175) (xy 38.154187 -379.039095) (xy 38.03757 -379.173954)
			(xy 37.915061 -379.303484) (xy 37.786904 -379.427428) (xy 37.653353 -379.54554) (xy 37.514673 -379.657585)
			(xy 37.371139 -379.763342) (xy 37.223036 -379.862599) (xy 37.070659 -379.955161) (xy 36.91431 -380.040842)
			(xy 36.754299 -380.119474) (xy 36.590945 -380.1909) (xy 36.42457 -380.254978) (xy 36.255507 -380.31158)
			(xy 36.08409 -380.360596) (xy 35.910659 -380.401926) (xy 35.735559 -380.43549) (xy 35.559139 -380.46122)
			(xy 35.381747 -380.479066) (xy 35.203736 -380.488992) (xy 35.025459 -380.490978) (xy 34.847272 -380.485021)
			(xy 34.669526 -380.471131) (xy 34.492576 -380.449338) (xy 34.316772 -380.419684) (xy 34.142464 -380.382227)
			(xy 33.969997 -380.337043) (xy 33.799714 -380.284221) (xy 33.631953 -380.223865) (xy 33.467048 -380.156097)
			(xy 33.305325 -380.081049) (xy 33.147106 -379.998872) (xy 32.992705 -379.909729) (xy 32.842428 -379.813795)
			(xy 32.696573 -379.711263) (xy 32.555431 -379.602335) (xy 32.419282 -379.487228) (xy 32.288395 -379.36617)
			(xy 32.163031 -379.239401) (xy 32.043438 -379.107174) (xy 31.929855 -378.969751) (xy 31.822506 -378.827404)
			(xy 31.721605 -378.680416) (xy 31.627352 -378.52908) (xy 31.539934 -378.373695) (xy 31.459524 -378.21457)
			(xy 31.386283 -378.052021) (xy 31.320356 -377.886371) (xy 31.261873 -377.717949) (xy 31.210951 -377.547088)
			(xy 31.167691 -377.374129) (xy 31.132179 -377.199414) (xy 31.104485 -377.02329) (xy 31.084664 -376.846108)
			(xy 31.072756 -376.668219) (xy 31.068784 -376.489976) (xy 2.509012 -376.489976) (xy 2.509012 -380.501398)
			(xy 69.321172 -380.501398) (xy 69.321172 -380.306834) (xy 69.321571 -380.295707) (xy 69.32804 -380.27441)
			(xy 69.333872 -380.264924) (xy 69.526404 -379.97003) (xy 69.532085 -379.960631) (xy 69.538368 -379.939599)
			(xy 69.538375 -379.917648) (xy 69.532105 -379.896612) (xy 69.526404 -379.887226) (xy 69.333872 -379.593602)
			(xy 69.328072 -379.584103) (xy 69.321618 -379.562813) (xy 69.321172 -379.551692) (xy 69.321172 -379.355858)
			(xy 69.321576 -379.343738) (xy 69.329079 -379.320687) (xy 69.343338 -379.301083) (xy 69.362956 -379.286845)
			(xy 69.386013 -379.279364) (xy 69.398134 -379.278896) (xy 70.083934 -379.278896) (xy 70.096046 -379.279382)
			(xy 70.119083 -379.286873) (xy 70.138681 -379.301113) (xy 70.152923 -379.320709) (xy 70.160417 -379.343746)
			(xy 70.160896 -379.355858) (xy 70.160896 -379.550422) (xy 70.160469 -379.561546) (xy 70.154018 -379.582843)
			(xy 70.148196 -379.592332) (xy 69.955664 -379.885956) (xy 69.94998 -379.89535) (xy 69.943643 -379.916358)
			(xy 69.943564 -379.938301) (xy 69.94975 -379.959354) (xy 69.95541 -379.96876) (xy 70.148196 -380.264924)
			(xy 70.154002 -380.27442) (xy 70.160453 -380.295713) (xy 70.160896 -380.306834) (xy 70.160896 -380.360428)
			(xy 70.895972 -380.360428) (xy 70.895972 -379.496828) (xy 70.896458 -379.469559) (xy 70.90422 -379.415575)
			(xy 70.919585 -379.363245) (xy 70.942242 -379.313635) (xy 70.971728 -379.267754) (xy 71.007443 -379.226537)
			(xy 71.04866 -379.190822) (xy 71.094541 -379.161336) (xy 71.144151 -379.138679) (xy 71.196481 -379.123314)
			(xy 71.250465 -379.115552) (xy 71.305003 -379.115552) (xy 71.358987 -379.123314) (xy 71.411317 -379.138679)
			(xy 71.460927 -379.161336) (xy 71.506808 -379.190822) (xy 71.548025 -379.226537) (xy 71.58374 -379.267754)
			(xy 71.613226 -379.313635) (xy 71.635883 -379.363245) (xy 71.651248 -379.415575) (xy 71.65901 -379.469559)
			(xy 71.659496 -379.496828) (xy 71.659496 -380.360428) (xy 71.65901 -380.387697) (xy 71.651248 -380.441681)
			(xy 71.635883 -380.494011) (xy 71.632509 -380.501398) (xy 101.84892 -380.501398) (xy 101.84892 -380.306834)
			(xy 101.849327 -380.295708) (xy 101.855792 -380.274411) (xy 101.86162 -380.264924) (xy 102.054152 -379.97003)
			(xy 102.059831 -379.96063) (xy 102.066109 -379.939598) (xy 102.066116 -379.917649) (xy 102.05985 -379.896613)
			(xy 102.054152 -379.887226) (xy 101.86162 -379.593602) (xy 101.855824 -379.584101) (xy 101.849367 -379.562812)
			(xy 101.84892 -379.551692) (xy 101.84892 -379.355858) (xy 101.849376 -379.343743) (xy 101.856872 -379.320701)
			(xy 101.871119 -379.301102) (xy 101.890723 -379.286861) (xy 101.913767 -379.279372) (xy 101.925882 -379.278896)
			(xy 102.611682 -379.278896) (xy 102.623791 -379.279426) (xy 102.646827 -379.286904) (xy 102.666425 -379.301132)
			(xy 102.680669 -379.320719) (xy 102.688164 -379.343749) (xy 102.688644 -379.355858) (xy 102.688644 -379.550422)
			(xy 102.688225 -379.561547) (xy 102.681769 -379.582844) (xy 102.675944 -379.592332) (xy 102.483412 -379.885956)
			(xy 102.477726 -379.895349) (xy 102.471384 -379.916357) (xy 102.471305 -379.938301) (xy 102.477495 -379.959355)
			(xy 102.483158 -379.96876) (xy 102.675944 -380.264924) (xy 102.681746 -380.274422) (xy 102.6882 -380.295713)
			(xy 102.688644 -380.306834) (xy 102.688644 -380.360428) (xy 103.42372 -380.360428) (xy 103.42372 -379.496828)
			(xy 103.424206 -379.469559) (xy 103.431968 -379.415575) (xy 103.447333 -379.363245) (xy 103.46999 -379.313635)
			(xy 103.499476 -379.267754) (xy 103.535191 -379.226537) (xy 103.576408 -379.190822) (xy 103.622289 -379.161336)
			(xy 103.671899 -379.138679) (xy 103.724229 -379.123314) (xy 103.778213 -379.115552) (xy 103.832751 -379.115552)
			(xy 103.886735 -379.123314) (xy 103.939065 -379.138679) (xy 103.988675 -379.161336) (xy 104.034556 -379.190822)
			(xy 104.075773 -379.226537) (xy 104.111488 -379.267754) (xy 104.140974 -379.313635) (xy 104.163631 -379.363245)
			(xy 104.178996 -379.415575) (xy 104.186758 -379.469559) (xy 104.187244 -379.496828) (xy 104.187244 -380.360428)
			(xy 104.186758 -380.387697) (xy 104.178996 -380.441681) (xy 104.163631 -380.494011) (xy 104.160141 -380.501652)
			(xy 136.421368 -380.501652) (xy 136.421368 -380.306834) (xy 136.421714 -380.295724) (xy 136.42805 -380.274428)
			(xy 136.433814 -380.264924) (xy 136.626346 -379.97003) (xy 136.632025 -379.96063) (xy 136.638304 -379.939598)
			(xy 136.638311 -379.917649) (xy 136.632045 -379.896612) (xy 136.626346 -379.887226) (xy 136.433814 -379.593602)
			(xy 136.428054 -379.584098) (xy 136.421735 -379.5628) (xy 136.421368 -379.551692) (xy 136.421368 -379.355858)
			(xy 136.421772 -379.343763) (xy 136.429244 -379.320757) (xy 136.443446 -379.301175) (xy 136.462994 -379.286927)
			(xy 136.485983 -379.279401) (xy 136.498076 -379.278896) (xy 137.183876 -379.278896) (xy 137.195958 -379.279333)
			(xy 137.21894 -379.286795) (xy 137.238491 -379.300994) (xy 137.252696 -379.320542) (xy 137.260164 -379.343522)
			(xy 137.260584 -379.355604) (xy 137.260584 -379.550422) (xy 137.260191 -379.561526) (xy 137.253875 -379.582818)
			(xy 137.248138 -379.592332) (xy 137.055606 -379.885956) (xy 137.04992 -379.895349) (xy 137.043579 -379.916357)
			(xy 137.0435 -379.938301) (xy 137.04969 -379.959355) (xy 137.055352 -379.96876) (xy 137.248138 -380.264924)
			(xy 137.253875 -380.274441) (xy 137.260207 -380.295729) (xy 137.260584 -380.306834) (xy 137.260584 -380.360428)
			(xy 137.996168 -380.360428) (xy 137.996168 -379.496828) (xy 137.996654 -379.469577) (xy 138.00441 -379.415629)
			(xy 138.019765 -379.363334) (xy 138.042407 -379.313757) (xy 138.071873 -379.267907) (xy 138.107564 -379.226716)
			(xy 138.148755 -379.191025) (xy 138.194605 -379.161559) (xy 138.244182 -379.138917) (xy 138.296477 -379.123562)
			(xy 138.350425 -379.115806) (xy 138.404927 -379.115806) (xy 138.458875 -379.123562) (xy 138.51117 -379.138917)
			(xy 138.560747 -379.161559) (xy 138.606597 -379.191025) (xy 138.647788 -379.226716) (xy 138.683479 -379.267907)
			(xy 138.712945 -379.313757) (xy 138.735587 -379.363334) (xy 138.750942 -379.415629) (xy 138.758698 -379.469577)
			(xy 138.759184 -379.496828) (xy 138.759184 -380.360428) (xy 138.758698 -380.387679) (xy 138.750942 -380.441627)
			(xy 138.735587 -380.493922) (xy 138.732057 -380.501652) (xy 168.949116 -380.501652) (xy 168.949116 -380.306834)
			(xy 168.94947 -380.295725) (xy 168.955801 -380.274429) (xy 168.961562 -380.264924) (xy 169.154094 -379.97003)
			(xy 169.15977 -379.960629) (xy 169.166045 -379.939597) (xy 169.166051 -379.917649) (xy 169.15979 -379.896614)
			(xy 169.154094 -379.887226) (xy 168.961562 -379.593602) (xy 168.955798 -379.5841) (xy 168.949483 -379.5628)
			(xy 168.949116 -379.551692) (xy 168.949116 -379.355858) (xy 168.949571 -379.343769) (xy 168.957036 -379.320771)
			(xy 168.971227 -379.301193) (xy 168.990761 -379.286943) (xy 169.013736 -379.279408) (xy 169.025824 -379.278896)
			(xy 169.711624 -379.278896) (xy 169.7237 -379.279344) (xy 169.746669 -379.286814) (xy 169.766206 -379.301014)
			(xy 169.780399 -379.320556) (xy 169.78786 -379.343528) (xy 169.788332 -379.355604) (xy 169.788332 -379.550422)
			(xy 169.787947 -379.561527) (xy 169.781626 -379.582819) (xy 169.775886 -379.592332) (xy 169.583354 -379.885956)
			(xy 169.577665 -379.895348) (xy 169.57132 -379.916357) (xy 169.571241 -379.938302) (xy 169.577435 -379.959356)
			(xy 169.5831 -379.96876) (xy 169.775886 -380.264924) (xy 169.781618 -380.274443) (xy 169.787954 -380.29573)
			(xy 169.788332 -380.306834) (xy 169.788332 -380.360428) (xy 170.523916 -380.360428) (xy 170.523916 -379.496828)
			(xy 170.524402 -379.469577) (xy 170.532158 -379.415629) (xy 170.547513 -379.363334) (xy 170.570155 -379.313757)
			(xy 170.599621 -379.267907) (xy 170.635312 -379.226716) (xy 170.676503 -379.191025) (xy 170.722353 -379.161559)
			(xy 170.77193 -379.138917) (xy 170.824225 -379.123562) (xy 170.878173 -379.115806) (xy 170.932675 -379.115806)
			(xy 170.986623 -379.123562) (xy 171.038918 -379.138917) (xy 171.088495 -379.161559) (xy 171.134345 -379.191025)
			(xy 171.175536 -379.226716) (xy 171.211227 -379.267907) (xy 171.240693 -379.313757) (xy 171.263335 -379.363334)
			(xy 171.27869 -379.415629) (xy 171.286446 -379.469577) (xy 171.286932 -379.496828) (xy 171.286932 -380.360428)
			(xy 171.286446 -380.387679) (xy 171.27869 -380.441627) (xy 171.263335 -380.493922) (xy 171.240693 -380.543499)
			(xy 171.211227 -380.589349) (xy 171.175536 -380.63054) (xy 171.134345 -380.666231) (xy 171.088495 -380.695697)
			(xy 171.038918 -380.718339) (xy 170.986623 -380.733694) (xy 170.932675 -380.74145) (xy 170.878173 -380.74145)
			(xy 170.824225 -380.733694) (xy 170.77193 -380.718339) (xy 170.722353 -380.695697) (xy 170.676503 -380.666231)
			(xy 170.635312 -380.63054) (xy 170.599621 -380.589349) (xy 170.570155 -380.543499) (xy 170.547513 -380.493922)
			(xy 170.532158 -380.441627) (xy 170.524402 -380.387679) (xy 170.523916 -380.360428) (xy 169.788332 -380.360428)
			(xy 169.788332 -380.501398) (xy 169.78789 -380.51349) (xy 169.780431 -380.536495) (xy 169.766239 -380.556078)
			(xy 169.746698 -380.570327) (xy 169.723715 -380.577854) (xy 169.711624 -380.57836) (xy 169.025824 -380.57836)
			(xy 169.013738 -380.577966) (xy 168.990748 -380.570499) (xy 168.971193 -380.55629) (xy 168.95699 -380.536731)
			(xy 168.94953 -380.513738) (xy 168.949116 -380.501652) (xy 138.732057 -380.501652) (xy 138.712945 -380.543499)
			(xy 138.683479 -380.589349) (xy 138.647788 -380.63054) (xy 138.606597 -380.666231) (xy 138.560747 -380.695697)
			(xy 138.51117 -380.718339) (xy 138.458875 -380.733694) (xy 138.404927 -380.74145) (xy 138.350425 -380.74145)
			(xy 138.296477 -380.733694) (xy 138.244182 -380.718339) (xy 138.194605 -380.695697) (xy 138.148755 -380.666231)
			(xy 138.107564 -380.63054) (xy 138.071873 -380.589349) (xy 138.042407 -380.543499) (xy 138.019765 -380.493922)
			(xy 138.00441 -380.441627) (xy 137.996654 -380.387679) (xy 137.996168 -380.360428) (xy 137.260584 -380.360428)
			(xy 137.260584 -380.501398) (xy 137.260091 -380.513485) (xy 137.252638 -380.536482) (xy 137.238457 -380.556059)
			(xy 137.218931 -380.570311) (xy 137.195961 -380.577847) (xy 137.183876 -380.57836) (xy 136.498076 -380.57836)
			(xy 136.485987 -380.578007) (xy 136.462996 -380.570527) (xy 136.443442 -380.556307) (xy 136.42924 -380.53674)
			(xy 136.421782 -380.513741) (xy 136.421368 -380.501652) (xy 104.160141 -380.501652) (xy 104.140974 -380.543621)
			(xy 104.111488 -380.589502) (xy 104.075773 -380.630719) (xy 104.034556 -380.666434) (xy 103.988675 -380.69592)
			(xy 103.939065 -380.718577) (xy 103.886735 -380.733942) (xy 103.832751 -380.741704) (xy 103.778213 -380.741704)
			(xy 103.724229 -380.733942) (xy 103.671899 -380.718577) (xy 103.622289 -380.69592) (xy 103.576408 -380.666434)
			(xy 103.535191 -380.630719) (xy 103.499476 -380.589502) (xy 103.46999 -380.543621) (xy 103.447333 -380.494011)
			(xy 103.431968 -380.441681) (xy 103.424206 -380.387697) (xy 103.42372 -380.360428) (xy 102.688644 -380.360428)
			(xy 102.688644 -380.501398) (xy 102.688238 -380.513522) (xy 102.680744 -380.536584) (xy 102.666489 -380.556201)
			(xy 102.64687 -380.570451) (xy 102.623807 -380.57794) (xy 102.611682 -380.57836) (xy 101.925882 -380.57836)
			(xy 101.913766 -380.577904) (xy 101.890722 -380.570411) (xy 101.87112 -380.556165) (xy 101.85688 -380.53656)
			(xy 101.849393 -380.513514) (xy 101.84892 -380.501398) (xy 71.632509 -380.501398) (xy 71.613226 -380.543621)
			(xy 71.58374 -380.589502) (xy 71.548025 -380.630719) (xy 71.506808 -380.666434) (xy 71.460927 -380.69592)
			(xy 71.411317 -380.718577) (xy 71.358987 -380.733942) (xy 71.305003 -380.741704) (xy 71.250465 -380.741704)
			(xy 71.196481 -380.733942) (xy 71.144151 -380.718577) (xy 71.094541 -380.69592) (xy 71.04866 -380.666434)
			(xy 71.007443 -380.630719) (xy 70.971728 -380.589502) (xy 70.942242 -380.543621) (xy 70.919585 -380.494011)
			(xy 70.90422 -380.441681) (xy 70.896458 -380.387697) (xy 70.895972 -380.360428) (xy 70.160896 -380.360428)
			(xy 70.160896 -380.501398) (xy 70.160387 -380.513509) (xy 70.152904 -380.536546) (xy 70.138671 -380.556145)
			(xy 70.119079 -380.570388) (xy 70.096045 -380.577881) (xy 70.083934 -380.57836) (xy 69.398134 -380.57836)
			(xy 69.386013 -380.577911) (xy 69.362955 -380.570428) (xy 69.343339 -380.556184) (xy 69.329087 -380.536574)
			(xy 69.321594 -380.513519) (xy 69.321172 -380.501398) (xy 2.509012 -380.501398) (xy 2.509012 -382.36906)
			(xy 41.04894 -382.36906) (xy 41.04894 -381.50546) (xy 41.049426 -381.478191) (xy 41.057188 -381.424207)
			(xy 41.072553 -381.371877) (xy 41.09521 -381.322267) (xy 41.124696 -381.276386) (xy 41.160411 -381.235169)
			(xy 41.201628 -381.199454) (xy 41.247509 -381.169968) (xy 41.297119 -381.147311) (xy 41.349449 -381.131946)
			(xy 41.403433 -381.124184) (xy 41.457971 -381.124184) (xy 41.511955 -381.131946) (xy 41.564285 -381.147311)
			(xy 41.613895 -381.169968) (xy 41.659776 -381.199454) (xy 41.700993 -381.235169) (xy 41.736708 -381.276386)
			(xy 41.766194 -381.322267) (xy 41.788851 -381.371877) (xy 41.804216 -381.424207) (xy 41.811978 -381.478191)
			(xy 41.812464 -381.50546) (xy 41.812464 -382.36906) (xy 41.811978 -382.396329) (xy 41.804216 -382.450313)
			(xy 41.788851 -382.502643) (xy 41.785477 -382.51003) (xy 42.54754 -382.51003) (xy 42.54754 -382.315466)
			(xy 42.547957 -382.304341) (xy 42.554414 -382.283044) (xy 42.56024 -382.273556) (xy 42.752772 -381.978662)
			(xy 42.758507 -381.969293) (xy 42.764771 -381.948246) (xy 42.764761 -381.926287) (xy 42.758479 -381.905245)
			(xy 42.752772 -381.895858) (xy 42.56024 -381.602234) (xy 42.554421 -381.592745) (xy 42.547978 -381.571447)
			(xy 42.54754 -381.560324) (xy 42.54754 -381.36449) (xy 42.548004 -381.352375) (xy 42.555494 -381.329331)
			(xy 42.569738 -381.309729) (xy 42.589342 -381.295488) (xy 42.612387 -381.288002) (xy 42.624502 -381.287528)
			(xy 43.310302 -381.287528) (xy 43.322416 -381.28801) (xy 43.345457 -381.295497) (xy 43.365058 -381.309736)
			(xy 43.3793 -381.329336) (xy 43.386789 -381.352376) (xy 43.387264 -381.36449) (xy 43.387264 -381.559054)
			(xy 43.386854 -381.57018) (xy 43.380392 -381.591477) (xy 43.374564 -381.600964) (xy 43.182032 -381.894588)
			(xy 43.176317 -381.903966) (xy 43.16998 -381.924981) (xy 43.169909 -381.946931) (xy 43.17611 -381.967987)
			(xy 43.181778 -381.977392) (xy 43.374564 -382.273556) (xy 43.38038 -382.283047) (xy 43.386825 -382.304343)
			(xy 43.387264 -382.315466) (xy 43.387264 -382.36906) (xy 73.576688 -382.36906) (xy 73.576688 -381.50546)
			(xy 73.577174 -381.478191) (xy 73.584936 -381.424207) (xy 73.600301 -381.371877) (xy 73.622958 -381.322267)
			(xy 73.652444 -381.276386) (xy 73.688159 -381.235169) (xy 73.729376 -381.199454) (xy 73.775257 -381.169968)
			(xy 73.824867 -381.147311) (xy 73.877197 -381.131946) (xy 73.931181 -381.124184) (xy 73.985719 -381.124184)
			(xy 74.039703 -381.131946) (xy 74.092033 -381.147311) (xy 74.141643 -381.169968) (xy 74.187524 -381.199454)
			(xy 74.228741 -381.235169) (xy 74.264456 -381.276386) (xy 74.293942 -381.322267) (xy 74.316599 -381.371877)
			(xy 74.331964 -381.424207) (xy 74.339726 -381.478191) (xy 74.340212 -381.50546) (xy 74.340212 -382.36906)
			(xy 74.339726 -382.396329) (xy 74.331964 -382.450313) (xy 74.316599 -382.502643) (xy 74.313225 -382.51003)
			(xy 75.075288 -382.51003) (xy 75.075288 -382.315466) (xy 75.075713 -382.304341) (xy 75.082166 -382.283045)
			(xy 75.087988 -382.273556) (xy 75.28052 -381.978662) (xy 75.286259 -381.969295) (xy 75.292527 -381.948247)
			(xy 75.292517 -381.926286) (xy 75.28623 -381.905244) (xy 75.28052 -381.895858) (xy 75.087988 -381.602234)
			(xy 75.082165 -381.592748) (xy 75.075725 -381.571447) (xy 75.075288 -381.560324) (xy 75.075288 -381.36449)
			(xy 75.075803 -381.35238) (xy 75.083287 -381.329345) (xy 75.097519 -381.309748) (xy 75.117109 -381.295505)
			(xy 75.14014 -381.288009) (xy 75.15225 -381.287528) (xy 75.83805 -381.287528) (xy 75.850166 -381.287969)
			(xy 75.873209 -381.295469) (xy 75.892809 -381.309719) (xy 75.90705 -381.329327) (xy 75.914537 -381.352374)
			(xy 75.915012 -381.36449) (xy 75.915012 -381.559054) (xy 75.914595 -381.570179) (xy 75.908137 -381.591476)
			(xy 75.902312 -381.600964) (xy 75.70978 -381.894588) (xy 75.704068 -381.903967) (xy 75.697735 -381.924982)
			(xy 75.697664 -381.94693) (xy 75.703861 -381.967986) (xy 75.709526 -381.977392) (xy 75.902312 -382.273556)
			(xy 75.908131 -382.283044) (xy 75.914573 -382.304343) (xy 75.915012 -382.315466) (xy 75.915012 -382.36906)
			(xy 108.149136 -382.36906) (xy 108.149136 -381.50546) (xy 108.149622 -381.478209) (xy 108.157378 -381.424261)
			(xy 108.172733 -381.371966) (xy 108.195375 -381.322389) (xy 108.224841 -381.276539) (xy 108.260532 -381.235348)
			(xy 108.301723 -381.199657) (xy 108.347573 -381.170191) (xy 108.39715 -381.147549) (xy 108.449445 -381.132194)
			(xy 108.503393 -381.124438) (xy 108.557895 -381.124438) (xy 108.611843 -381.132194) (xy 108.664138 -381.147549)
			(xy 108.713715 -381.170191) (xy 108.759565 -381.199657) (xy 108.800756 -381.235348) (xy 108.836447 -381.276539)
			(xy 108.865913 -381.322389) (xy 108.888555 -381.371966) (xy 108.90391 -381.424261) (xy 108.911666 -381.478209)
			(xy 108.912152 -381.50546) (xy 108.912152 -382.36906) (xy 108.911666 -382.396311) (xy 108.90391 -382.450259)
			(xy 108.888555 -382.502554) (xy 108.885025 -382.510284) (xy 109.647736 -382.510284) (xy 109.647736 -382.315466)
			(xy 109.648099 -382.304358) (xy 109.654424 -382.283062) (xy 109.660182 -382.273556) (xy 109.852714 -381.978662)
			(xy 109.858453 -381.969295) (xy 109.864722 -381.948247) (xy 109.864712 -381.926286) (xy 109.858425 -381.905244)
			(xy 109.852714 -381.895858) (xy 109.660182 -381.602234) (xy 109.654432 -381.592725) (xy 109.648108 -381.571431)
			(xy 109.647736 -381.560324) (xy 109.647736 -381.36449) (xy 109.648199 -381.3524) (xy 109.655658 -381.3294)
			(xy 109.669846 -381.309821) (xy 109.68938 -381.295571) (xy 109.712356 -381.288038) (xy 109.724444 -381.287528)
			(xy 110.410244 -381.287528) (xy 110.422324 -381.287927) (xy 110.445299 -381.295406) (xy 110.464839 -381.309618)
			(xy 110.47903 -381.329173) (xy 110.486485 -381.352155) (xy 110.486952 -381.364236) (xy 110.486952 -381.559054)
			(xy 110.486577 -381.570159) (xy 110.48025 -381.591451) (xy 110.474506 -381.600964) (xy 110.281974 -381.894588)
			(xy 110.276262 -381.903967) (xy 110.26993 -381.924982) (xy 110.269859 -381.94693) (xy 110.276055 -381.967986)
			(xy 110.28172 -381.977392) (xy 110.474506 -382.273556) (xy 110.480252 -382.283068) (xy 110.486579 -382.30436)
			(xy 110.486952 -382.315466) (xy 110.486952 -382.36906) (xy 140.676884 -382.36906) (xy 140.676884 -381.50546)
			(xy 140.67737 -381.478209) (xy 140.685126 -381.424261) (xy 140.700481 -381.371966) (xy 140.723123 -381.322389)
			(xy 140.752589 -381.276539) (xy 140.78828 -381.235348) (xy 140.829471 -381.199657) (xy 140.875321 -381.170191)
			(xy 140.924898 -381.147549) (xy 140.977193 -381.132194) (xy 141.031141 -381.124438) (xy 141.085643 -381.124438)
			(xy 141.139591 -381.132194) (xy 141.191886 -381.147549) (xy 141.241463 -381.170191) (xy 141.287313 -381.199657)
			(xy 141.328504 -381.235348) (xy 141.364195 -381.276539) (xy 141.393661 -381.322389) (xy 141.416303 -381.371966)
			(xy 141.431658 -381.424261) (xy 141.439414 -381.478209) (xy 141.4399 -381.50546) (xy 141.4399 -382.36906)
			(xy 141.439414 -382.396311) (xy 141.431658 -382.450259) (xy 141.416303 -382.502554) (xy 141.412773 -382.510284)
			(xy 142.175484 -382.510284) (xy 142.175484 -382.315466) (xy 142.175855 -382.304359) (xy 142.182175 -382.283063)
			(xy 142.18793 -382.273556) (xy 142.380462 -381.978662) (xy 142.386198 -381.969294) (xy 142.392463 -381.948247)
			(xy 142.392453 -381.926287) (xy 142.386169 -381.905245) (xy 142.380462 -381.895858) (xy 142.18793 -381.602234)
			(xy 142.182183 -381.592723) (xy 142.175856 -381.57143) (xy 142.175484 -381.560324) (xy 142.175484 -381.36449)
			(xy 142.1759 -381.352396) (xy 142.183365 -381.329387) (xy 142.197563 -381.309804) (xy 142.21711 -381.295555)
			(xy 142.240099 -381.288031) (xy 142.252192 -381.287528) (xy 142.937992 -381.287528) (xy 142.950078 -381.28792)
			(xy 142.973067 -381.295389) (xy 142.99262 -381.3096) (xy 143.006823 -381.329159) (xy 143.014285 -381.35215)
			(xy 143.0147 -381.364236) (xy 143.0147 -381.559054) (xy 143.014318 -381.570159) (xy 143.007994 -381.59145)
			(xy 143.002254 -381.600964) (xy 142.809722 -381.894588) (xy 142.804008 -381.903966) (xy 142.797672 -381.924981)
			(xy 142.7976 -381.946931) (xy 142.8038 -381.967987) (xy 142.809468 -381.977392) (xy 143.002254 -382.273556)
			(xy 143.008004 -382.283065) (xy 143.014328 -382.30436) (xy 143.0147 -382.315466) (xy 143.0147 -382.51003)
			(xy 143.014219 -382.522117) (xy 143.006759 -382.545112) (xy 142.992574 -382.564688) (xy 142.973047 -382.578939)
			(xy 142.950078 -382.586477) (xy 142.937992 -382.586992) (xy 142.252192 -382.586992) (xy 142.240107 -382.586594)
			(xy 142.217121 -382.579122) (xy 142.19757 -382.564913) (xy 142.183367 -382.545357) (xy 142.175902 -382.522369)
			(xy 142.175484 -382.510284) (xy 141.412773 -382.510284) (xy 141.393661 -382.552131) (xy 141.364195 -382.597981)
			(xy 141.328504 -382.639172) (xy 141.287313 -382.674863) (xy 141.241463 -382.704329) (xy 141.191886 -382.726971)
			(xy 141.139591 -382.742326) (xy 141.085643 -382.750082) (xy 141.031141 -382.750082) (xy 140.977193 -382.742326)
			(xy 140.924898 -382.726971) (xy 140.875321 -382.704329) (xy 140.829471 -382.674863) (xy 140.78828 -382.639172)
			(xy 140.752589 -382.597981) (xy 140.723123 -382.552131) (xy 140.700481 -382.502554) (xy 140.685126 -382.450259)
			(xy 140.67737 -382.396311) (xy 140.676884 -382.36906) (xy 110.486952 -382.36906) (xy 110.486952 -382.51003)
			(xy 110.486518 -382.522122) (xy 110.479052 -382.545125) (xy 110.464857 -382.564705) (xy 110.445317 -382.578954)
			(xy 110.422335 -382.586484) (xy 110.410244 -382.586992) (xy 109.724444 -382.586992) (xy 109.712362 -382.58655)
			(xy 109.689378 -382.579092) (xy 109.669826 -382.564894) (xy 109.655621 -382.545347) (xy 109.648155 -382.522366)
			(xy 109.647736 -382.510284) (xy 108.885025 -382.510284) (xy 108.865913 -382.552131) (xy 108.836447 -382.597981)
			(xy 108.800756 -382.639172) (xy 108.759565 -382.674863) (xy 108.713715 -382.704329) (xy 108.664138 -382.726971)
			(xy 108.611843 -382.742326) (xy 108.557895 -382.750082) (xy 108.503393 -382.750082) (xy 108.449445 -382.742326)
			(xy 108.39715 -382.726971) (xy 108.347573 -382.704329) (xy 108.301723 -382.674863) (xy 108.260532 -382.639172)
			(xy 108.224841 -382.597981) (xy 108.195375 -382.552131) (xy 108.172733 -382.502554) (xy 108.157378 -382.450259)
			(xy 108.149622 -382.396311) (xy 108.149136 -382.36906) (xy 75.915012 -382.36906) (xy 75.915012 -382.51003)
			(xy 75.914515 -382.522141) (xy 75.907025 -382.545177) (xy 75.892788 -382.564774) (xy 75.873195 -382.579016)
			(xy 75.850161 -382.586512) (xy 75.83805 -382.586992) (xy 75.15225 -382.586992) (xy 75.140136 -382.586531)
			(xy 75.117096 -382.579034) (xy 75.097498 -382.564788) (xy 75.083257 -382.545186) (xy 75.075766 -382.522144)
			(xy 75.075288 -382.51003) (xy 74.313225 -382.51003) (xy 74.293942 -382.552253) (xy 74.264456 -382.598134)
			(xy 74.228741 -382.639351) (xy 74.187524 -382.675066) (xy 74.141643 -382.704552) (xy 74.092033 -382.727209)
			(xy 74.039703 -382.742574) (xy 73.985719 -382.750336) (xy 73.931181 -382.750336) (xy 73.877197 -382.742574)
			(xy 73.824867 -382.727209) (xy 73.775257 -382.704552) (xy 73.729376 -382.675066) (xy 73.688159 -382.639351)
			(xy 73.652444 -382.598134) (xy 73.622958 -382.552253) (xy 73.600301 -382.502643) (xy 73.584936 -382.450313)
			(xy 73.577174 -382.396329) (xy 73.576688 -382.36906) (xy 43.387264 -382.36906) (xy 43.387264 -382.51003)
			(xy 43.386814 -382.522146) (xy 43.379319 -382.54519) (xy 43.365071 -382.564791) (xy 43.345465 -382.579032)
			(xy 43.322418 -382.586518) (xy 43.310302 -382.586992) (xy 42.624502 -382.586992) (xy 42.612391 -382.586487)
			(xy 42.589353 -382.579004) (xy 42.569753 -382.564769) (xy 42.555511 -382.545176) (xy 42.548018 -382.522141)
			(xy 42.54754 -382.51003) (xy 41.785477 -382.51003) (xy 41.766194 -382.552253) (xy 41.736708 -382.598134)
			(xy 41.700993 -382.639351) (xy 41.659776 -382.675066) (xy 41.613895 -382.704552) (xy 41.564285 -382.727209)
			(xy 41.511955 -382.742574) (xy 41.457971 -382.750336) (xy 41.403433 -382.750336) (xy 41.349449 -382.742574)
			(xy 41.297119 -382.727209) (xy 41.247509 -382.704552) (xy 41.201628 -382.675066) (xy 41.160411 -382.639351)
			(xy 41.124696 -382.598134) (xy 41.09521 -382.552253) (xy 41.072553 -382.502643) (xy 41.057188 -382.450313)
			(xy 41.049426 -382.396329) (xy 41.04894 -382.36906) (xy 2.509012 -382.36906) (xy 2.509012 -383.440686)
			(xy 46.990508 -383.440686) (xy 46.990508 -383.364486) (xy 46.990973 -383.34906) (xy 46.998356 -383.319105)
			(xy 47.012693 -383.291787) (xy 47.033152 -383.268694) (xy 47.058542 -383.251168) (xy 47.087389 -383.240228)
			(xy 47.118016 -383.23651) (xy 47.148643 -383.240228) (xy 47.17749 -383.251168) (xy 47.20288 -383.268694)
			(xy 47.223339 -383.291787) (xy 47.237676 -383.319105) (xy 47.245059 -383.34906) (xy 47.245524 -383.364486)
			(xy 47.245524 -383.440686) (xy 48.190404 -383.440686) (xy 48.190404 -383.364486) (xy 48.190869 -383.34906)
			(xy 48.198252 -383.319105) (xy 48.212589 -383.291787) (xy 48.233048 -383.268694) (xy 48.258438 -383.251168)
			(xy 48.287285 -383.240228) (xy 48.317912 -383.23651) (xy 48.348539 -383.240228) (xy 48.377386 -383.251168)
			(xy 48.402776 -383.268694) (xy 48.423235 -383.291787) (xy 48.437572 -383.319105) (xy 48.444955 -383.34906)
			(xy 48.44542 -383.364486) (xy 48.44542 -383.440686) (xy 49.3903 -383.440686) (xy 49.3903 -383.364486)
			(xy 49.390766 -383.349029) (xy 49.398164 -383.319015) (xy 49.41253 -383.291642) (xy 49.433029 -383.268504)
			(xy 49.45847 -383.250943) (xy 49.487374 -383.239981) (xy 49.518062 -383.236255) (xy 49.54875 -383.239981)
			(xy 49.577654 -383.250943) (xy 49.603095 -383.268504) (xy 49.623594 -383.291642) (xy 49.63796 -383.319015)
			(xy 49.645358 -383.349029) (xy 49.645824 -383.364486) (xy 49.645824 -383.440686) (xy 50.590196 -383.440686)
			(xy 50.590196 -383.364486) (xy 50.590662 -383.349029) (xy 50.59806 -383.319015) (xy 50.612426 -383.291642)
			(xy 50.632925 -383.268504) (xy 50.658366 -383.250943) (xy 50.68727 -383.239981) (xy 50.717958 -383.236255)
			(xy 50.748646 -383.239981) (xy 50.77755 -383.250943) (xy 50.802991 -383.268504) (xy 50.82349 -383.291642)
			(xy 50.837856 -383.319015) (xy 50.845254 -383.349029) (xy 50.84572 -383.364486) (xy 50.84572 -383.440686)
			(xy 51.7906 -383.440686) (xy 51.7906 -383.364486) (xy 51.791065 -383.34906) (xy 51.798448 -383.319105)
			(xy 51.812785 -383.291787) (xy 51.833244 -383.268694) (xy 51.858634 -383.251168) (xy 51.887481 -383.240228)
			(xy 51.918108 -383.23651) (xy 51.948735 -383.240228) (xy 51.977582 -383.251168) (xy 52.002972 -383.268694)
			(xy 52.023431 -383.291787) (xy 52.037768 -383.319105) (xy 52.045151 -383.34906) (xy 52.045616 -383.364486)
			(xy 52.045616 -383.440686) (xy 52.990496 -383.440686) (xy 52.990496 -383.364486) (xy 52.990961 -383.34906)
			(xy 52.998344 -383.319105) (xy 53.012681 -383.291787) (xy 53.03314 -383.268694) (xy 53.05853 -383.251168)
			(xy 53.087377 -383.240228) (xy 53.118004 -383.23651) (xy 53.148631 -383.240228) (xy 53.177478 -383.251168)
			(xy 53.202868 -383.268694) (xy 53.223327 -383.291787) (xy 53.237664 -383.319105) (xy 53.245047 -383.34906)
			(xy 53.245512 -383.364486) (xy 53.245512 -383.440686) (xy 54.190392 -383.440686) (xy 54.190392 -383.364486)
			(xy 54.190858 -383.349029) (xy 54.198256 -383.319015) (xy 54.212622 -383.291642) (xy 54.233121 -383.268504)
			(xy 54.258562 -383.250943) (xy 54.287466 -383.239981) (xy 54.318154 -383.236255) (xy 54.348842 -383.239981)
			(xy 54.377746 -383.250943) (xy 54.403187 -383.268504) (xy 54.423686 -383.291642) (xy 54.438052 -383.319015)
			(xy 54.44545 -383.349029) (xy 54.445916 -383.364486) (xy 54.445916 -383.440686) (xy 55.390288 -383.440686)
			(xy 55.390288 -383.364486) (xy 55.390754 -383.349029) (xy 55.398152 -383.319015) (xy 55.412518 -383.291642)
			(xy 55.433017 -383.268504) (xy 55.458458 -383.250943) (xy 55.487362 -383.239981) (xy 55.51805 -383.236255)
			(xy 55.548738 -383.239981) (xy 55.577642 -383.250943) (xy 55.603083 -383.268504) (xy 55.623582 -383.291642)
			(xy 55.637948 -383.319015) (xy 55.645346 -383.349029) (xy 55.645812 -383.364486) (xy 55.645812 -383.440686)
			(xy 56.590184 -383.440686) (xy 56.590184 -383.364486) (xy 56.59065 -383.349029) (xy 56.598048 -383.319015)
			(xy 56.612414 -383.291642) (xy 56.632913 -383.268504) (xy 56.658354 -383.250943) (xy 56.687258 -383.239981)
			(xy 56.717946 -383.236255) (xy 56.748634 -383.239981) (xy 56.777538 -383.250943) (xy 56.802979 -383.268504)
			(xy 56.823478 -383.291642) (xy 56.837844 -383.319015) (xy 56.845242 -383.349029) (xy 56.845708 -383.364486)
			(xy 56.845708 -383.440686) (xy 57.790588 -383.440686) (xy 57.790588 -383.364486) (xy 57.791053 -383.34906)
			(xy 57.798436 -383.319105) (xy 57.812773 -383.291787) (xy 57.833232 -383.268694) (xy 57.858622 -383.251168)
			(xy 57.887469 -383.240228) (xy 57.918096 -383.23651) (xy 57.948723 -383.240228) (xy 57.97757 -383.251168)
			(xy 58.00296 -383.268694) (xy 58.023419 -383.291787) (xy 58.037756 -383.319105) (xy 58.045139 -383.34906)
			(xy 58.045604 -383.364486) (xy 58.045604 -383.440686) (xy 58.990484 -383.440686) (xy 58.990484 -383.364486)
			(xy 58.990949 -383.34906) (xy 58.998332 -383.319105) (xy 59.012669 -383.291787) (xy 59.033128 -383.268694)
			(xy 59.058518 -383.251168) (xy 59.087365 -383.240228) (xy 59.117992 -383.23651) (xy 59.148619 -383.240228)
			(xy 59.177466 -383.251168) (xy 59.202856 -383.268694) (xy 59.223315 -383.291787) (xy 59.237652 -383.319105)
			(xy 59.245035 -383.34906) (xy 59.2455 -383.364486) (xy 59.2455 -383.440686) (xy 60.19038 -383.440686)
			(xy 60.19038 -383.364486) (xy 60.190846 -383.349029) (xy 60.198244 -383.319015) (xy 60.21261 -383.291642)
			(xy 60.233109 -383.268504) (xy 60.25855 -383.250943) (xy 60.287454 -383.239981) (xy 60.318142 -383.236255)
			(xy 60.34883 -383.239981) (xy 60.377734 -383.250943) (xy 60.403175 -383.268504) (xy 60.423674 -383.291642)
			(xy 60.43804 -383.319015) (xy 60.445438 -383.349029) (xy 60.445904 -383.364486) (xy 60.445904 -383.440686)
			(xy 61.390276 -383.440686) (xy 61.390276 -383.364486) (xy 61.390742 -383.349029) (xy 61.39814 -383.319015)
			(xy 61.412506 -383.291642) (xy 61.433005 -383.268504) (xy 61.458446 -383.250943) (xy 61.48735 -383.239981)
			(xy 61.518038 -383.236255) (xy 61.548726 -383.239981) (xy 61.57763 -383.250943) (xy 61.603071 -383.268504)
			(xy 61.62357 -383.291642) (xy 61.637936 -383.319015) (xy 61.645334 -383.349029) (xy 61.6458 -383.364486)
			(xy 61.6458 -383.440686) (xy 62.590172 -383.440686) (xy 62.590172 -383.364486) (xy 62.590638 -383.349029)
			(xy 62.598036 -383.319015) (xy 62.612402 -383.291642) (xy 62.632901 -383.268504) (xy 62.658342 -383.250943)
			(xy 62.687246 -383.239981) (xy 62.717934 -383.236255) (xy 62.748622 -383.239981) (xy 62.777526 -383.250943)
			(xy 62.802967 -383.268504) (xy 62.823466 -383.291642) (xy 62.837832 -383.319015) (xy 62.84523 -383.349029)
			(xy 62.845696 -383.364486) (xy 62.845696 -383.440686) (xy 63.790576 -383.440686) (xy 63.790576 -383.364486)
			(xy 63.791041 -383.34906) (xy 63.798424 -383.319105) (xy 63.812761 -383.291787) (xy 63.83322 -383.268694)
			(xy 63.85861 -383.251168) (xy 63.887457 -383.240228) (xy 63.918084 -383.23651) (xy 63.948711 -383.240228)
			(xy 63.977558 -383.251168) (xy 64.002948 -383.268694) (xy 64.023407 -383.291787) (xy 64.037744 -383.319105)
			(xy 64.045127 -383.34906) (xy 64.045592 -383.364486) (xy 64.045592 -383.440686) (xy 64.990472 -383.440686)
			(xy 64.990472 -383.364486) (xy 64.990937 -383.34906) (xy 64.99832 -383.319105) (xy 65.012657 -383.291787)
			(xy 65.033116 -383.268694) (xy 65.058506 -383.251168) (xy 65.087353 -383.240228) (xy 65.11798 -383.23651)
			(xy 65.148607 -383.240228) (xy 65.177454 -383.251168) (xy 65.202844 -383.268694) (xy 65.223303 -383.291787)
			(xy 65.23764 -383.319105) (xy 65.245023 -383.34906) (xy 65.245488 -383.364486) (xy 65.245488 -383.440686)
			(xy 79.518256 -383.440686) (xy 79.518256 -383.364486) (xy 79.518721 -383.34906) (xy 79.526104 -383.319105)
			(xy 79.540441 -383.291787) (xy 79.5609 -383.268694) (xy 79.58629 -383.251168) (xy 79.615137 -383.240228)
			(xy 79.645764 -383.23651) (xy 79.676391 -383.240228) (xy 79.705238 -383.251168) (xy 79.730628 -383.268694)
			(xy 79.751087 -383.291787) (xy 79.765424 -383.319105) (xy 79.772807 -383.34906) (xy 79.773272 -383.364486)
			(xy 79.773272 -383.440686) (xy 80.718152 -383.440686) (xy 80.718152 -383.364486) (xy 80.718617 -383.34906)
			(xy 80.726 -383.319105) (xy 80.740337 -383.291787) (xy 80.760796 -383.268694) (xy 80.786186 -383.251168)
			(xy 80.815033 -383.240228) (xy 80.84566 -383.23651) (xy 80.876287 -383.240228) (xy 80.905134 -383.251168)
			(xy 80.930524 -383.268694) (xy 80.950983 -383.291787) (xy 80.96532 -383.319105) (xy 80.972703 -383.34906)
			(xy 80.973168 -383.364486) (xy 80.973168 -383.440686) (xy 81.918048 -383.440686) (xy 81.918048 -383.364486)
			(xy 81.918514 -383.349029) (xy 81.925912 -383.319015) (xy 81.940278 -383.291642) (xy 81.960777 -383.268504)
			(xy 81.986218 -383.250943) (xy 82.015122 -383.239981) (xy 82.04581 -383.236255) (xy 82.076498 -383.239981)
			(xy 82.105402 -383.250943) (xy 82.130843 -383.268504) (xy 82.151342 -383.291642) (xy 82.165708 -383.319015)
			(xy 82.173106 -383.349029) (xy 82.173572 -383.364486) (xy 82.173572 -383.440686) (xy 83.117944 -383.440686)
			(xy 83.117944 -383.364486) (xy 83.11841 -383.349029) (xy 83.125808 -383.319015) (xy 83.140174 -383.291642)
			(xy 83.160673 -383.268504) (xy 83.186114 -383.250943) (xy 83.215018 -383.239981) (xy 83.245706 -383.236255)
			(xy 83.276394 -383.239981) (xy 83.305298 -383.250943) (xy 83.330739 -383.268504) (xy 83.351238 -383.291642)
			(xy 83.365604 -383.319015) (xy 83.373002 -383.349029) (xy 83.373468 -383.364486) (xy 83.373468 -383.440686)
			(xy 84.318348 -383.440686) (xy 84.318348 -383.364486) (xy 84.318813 -383.34906) (xy 84.326196 -383.319105)
			(xy 84.340533 -383.291787) (xy 84.360992 -383.268694) (xy 84.386382 -383.251168) (xy 84.415229 -383.240228)
			(xy 84.445856 -383.23651) (xy 84.476483 -383.240228) (xy 84.50533 -383.251168) (xy 84.53072 -383.268694)
			(xy 84.551179 -383.291787) (xy 84.565516 -383.319105) (xy 84.572899 -383.34906) (xy 84.573364 -383.364486)
			(xy 84.573364 -383.440686) (xy 85.518244 -383.440686) (xy 85.518244 -383.364486) (xy 85.518709 -383.34906)
			(xy 85.526092 -383.319105) (xy 85.540429 -383.291787) (xy 85.560888 -383.268694) (xy 85.586278 -383.251168)
			(xy 85.615125 -383.240228) (xy 85.645752 -383.23651) (xy 85.676379 -383.240228) (xy 85.705226 -383.251168)
			(xy 85.730616 -383.268694) (xy 85.751075 -383.291787) (xy 85.765412 -383.319105) (xy 85.772795 -383.34906)
			(xy 85.77326 -383.364486) (xy 85.77326 -383.440686) (xy 86.71814 -383.440686) (xy 86.71814 -383.364486)
			(xy 86.718606 -383.349029) (xy 86.726004 -383.319015) (xy 86.74037 -383.291642) (xy 86.760869 -383.268504)
			(xy 86.78631 -383.250943) (xy 86.815214 -383.239981) (xy 86.845902 -383.236255) (xy 86.87659 -383.239981)
			(xy 86.905494 -383.250943) (xy 86.930935 -383.268504) (xy 86.951434 -383.291642) (xy 86.9658 -383.319015)
			(xy 86.973198 -383.349029) (xy 86.973664 -383.364486) (xy 86.973664 -383.440686) (xy 87.918036 -383.440686)
			(xy 87.918036 -383.364486) (xy 87.918502 -383.349029) (xy 87.9259 -383.319015) (xy 87.940266 -383.291642)
			(xy 87.960765 -383.268504) (xy 87.986206 -383.250943) (xy 88.01511 -383.239981) (xy 88.045798 -383.236255)
			(xy 88.076486 -383.239981) (xy 88.10539 -383.250943) (xy 88.130831 -383.268504) (xy 88.15133 -383.291642)
			(xy 88.165696 -383.319015) (xy 88.173094 -383.349029) (xy 88.17356 -383.364486) (xy 88.17356 -383.440686)
			(xy 89.117932 -383.440686) (xy 89.117932 -383.364486) (xy 89.118398 -383.349029) (xy 89.125796 -383.319015)
			(xy 89.140162 -383.291642) (xy 89.160661 -383.268504) (xy 89.186102 -383.250943) (xy 89.215006 -383.239981)
			(xy 89.245694 -383.236255) (xy 89.276382 -383.239981) (xy 89.305286 -383.250943) (xy 89.330727 -383.268504)
			(xy 89.351226 -383.291642) (xy 89.365592 -383.319015) (xy 89.37299 -383.349029) (xy 89.373456 -383.364486)
			(xy 89.373456 -383.440686) (xy 90.318336 -383.440686) (xy 90.318336 -383.364486) (xy 90.318801 -383.34906)
			(xy 90.326184 -383.319105) (xy 90.340521 -383.291787) (xy 90.36098 -383.268694) (xy 90.38637 -383.251168)
			(xy 90.415217 -383.240228) (xy 90.445844 -383.23651) (xy 90.476471 -383.240228) (xy 90.505318 -383.251168)
			(xy 90.530708 -383.268694) (xy 90.551167 -383.291787) (xy 90.565504 -383.319105) (xy 90.572887 -383.34906)
			(xy 90.573352 -383.364486) (xy 90.573352 -383.440686) (xy 91.518232 -383.440686) (xy 91.518232 -383.364486)
			(xy 91.518697 -383.34906) (xy 91.52608 -383.319105) (xy 91.540417 -383.291787) (xy 91.560876 -383.268694)
			(xy 91.586266 -383.251168) (xy 91.615113 -383.240228) (xy 91.64574 -383.23651) (xy 91.676367 -383.240228)
			(xy 91.705214 -383.251168) (xy 91.730604 -383.268694) (xy 91.751063 -383.291787) (xy 91.7654 -383.319105)
			(xy 91.772783 -383.34906) (xy 91.773248 -383.364486) (xy 91.773248 -383.440686) (xy 92.718128 -383.440686)
			(xy 92.718128 -383.364486) (xy 92.718594 -383.349029) (xy 92.725992 -383.319015) (xy 92.740358 -383.291642)
			(xy 92.760857 -383.268504) (xy 92.786298 -383.250943) (xy 92.815202 -383.239981) (xy 92.84589 -383.236255)
			(xy 92.876578 -383.239981) (xy 92.905482 -383.250943) (xy 92.930923 -383.268504) (xy 92.951422 -383.291642)
			(xy 92.965788 -383.319015) (xy 92.973186 -383.349029) (xy 92.973652 -383.364486) (xy 92.973652 -383.440686)
			(xy 93.918024 -383.440686) (xy 93.918024 -383.364486) (xy 93.91849 -383.349029) (xy 93.925888 -383.319015)
			(xy 93.940254 -383.291642) (xy 93.960753 -383.268504) (xy 93.986194 -383.250943) (xy 94.015098 -383.239981)
			(xy 94.045786 -383.236255) (xy 94.076474 -383.239981) (xy 94.105378 -383.250943) (xy 94.130819 -383.268504)
			(xy 94.151318 -383.291642) (xy 94.165684 -383.319015) (xy 94.173082 -383.349029) (xy 94.173548 -383.364486)
			(xy 94.173548 -383.440686) (xy 95.11792 -383.440686) (xy 95.11792 -383.364486) (xy 95.118386 -383.349029)
			(xy 95.125784 -383.319015) (xy 95.14015 -383.291642) (xy 95.160649 -383.268504) (xy 95.18609 -383.250943)
			(xy 95.214994 -383.239981) (xy 95.245682 -383.236255) (xy 95.27637 -383.239981) (xy 95.305274 -383.250943)
			(xy 95.330715 -383.268504) (xy 95.351214 -383.291642) (xy 95.36558 -383.319015) (xy 95.372978 -383.349029)
			(xy 95.373444 -383.364486) (xy 95.373444 -383.440686) (xy 96.318324 -383.440686) (xy 96.318324 -383.364486)
			(xy 96.318789 -383.34906) (xy 96.326172 -383.319105) (xy 96.340509 -383.291787) (xy 96.360968 -383.268694)
			(xy 96.386358 -383.251168) (xy 96.415205 -383.240228) (xy 96.445832 -383.23651) (xy 96.476459 -383.240228)
			(xy 96.505306 -383.251168) (xy 96.530696 -383.268694) (xy 96.551155 -383.291787) (xy 96.565492 -383.319105)
			(xy 96.572875 -383.34906) (xy 96.57334 -383.364486) (xy 96.57334 -383.440686) (xy 97.51822 -383.440686)
			(xy 97.51822 -383.364486) (xy 97.518685 -383.34906) (xy 97.526068 -383.319105) (xy 97.540405 -383.291787)
			(xy 97.560864 -383.268694) (xy 97.586254 -383.251168) (xy 97.615101 -383.240228) (xy 97.645728 -383.23651)
			(xy 97.676355 -383.240228) (xy 97.705202 -383.251168) (xy 97.730592 -383.268694) (xy 97.751051 -383.291787)
			(xy 97.765388 -383.319105) (xy 97.772771 -383.34906) (xy 97.773236 -383.364486) (xy 97.773236 -383.440686)
			(xy 114.090196 -383.440686) (xy 114.090196 -383.364486) (xy 114.090662 -383.349029) (xy 114.09806 -383.319015)
			(xy 114.112426 -383.291642) (xy 114.132925 -383.268504) (xy 114.158366 -383.250943) (xy 114.18727 -383.239981)
			(xy 114.217958 -383.236255) (xy 114.248646 -383.239981) (xy 114.27755 -383.250943) (xy 114.302991 -383.268504)
			(xy 114.32349 -383.291642) (xy 114.337856 -383.319015) (xy 114.345254 -383.349029) (xy 114.34572 -383.364486)
			(xy 114.34572 -383.440686) (xy 115.290092 -383.440686) (xy 115.290092 -383.364486) (xy 115.290558 -383.349029)
			(xy 115.297956 -383.319015) (xy 115.312322 -383.291642) (xy 115.332821 -383.268504) (xy 115.358262 -383.250943)
			(xy 115.387166 -383.239981) (xy 115.417854 -383.236255) (xy 115.448542 -383.239981) (xy 115.477446 -383.250943)
			(xy 115.502887 -383.268504) (xy 115.523386 -383.291642) (xy 115.537752 -383.319015) (xy 115.54515 -383.349029)
			(xy 115.545616 -383.364486) (xy 115.545616 -383.440686) (xy 116.490496 -383.440686) (xy 116.490496 -383.364486)
			(xy 116.490961 -383.34906) (xy 116.498344 -383.319105) (xy 116.512681 -383.291787) (xy 116.53314 -383.268694)
			(xy 116.55853 -383.251168) (xy 116.587377 -383.240228) (xy 116.618004 -383.23651) (xy 116.648631 -383.240228)
			(xy 116.677478 -383.251168) (xy 116.702868 -383.268694) (xy 116.723327 -383.291787) (xy 116.737664 -383.319105)
			(xy 116.745047 -383.34906) (xy 116.745512 -383.364486) (xy 116.745512 -383.440686) (xy 117.690392 -383.440686)
			(xy 117.690392 -383.364486) (xy 117.690857 -383.34906) (xy 117.69824 -383.319105) (xy 117.712577 -383.291787)
			(xy 117.733036 -383.268694) (xy 117.758426 -383.251168) (xy 117.787273 -383.240228) (xy 117.8179 -383.23651)
			(xy 117.848527 -383.240228) (xy 117.877374 -383.251168) (xy 117.902764 -383.268694) (xy 117.923223 -383.291787)
			(xy 117.93756 -383.319105) (xy 117.944943 -383.34906) (xy 117.945408 -383.364486) (xy 117.945408 -383.440686)
			(xy 118.890288 -383.440686) (xy 118.890288 -383.364486) (xy 118.890754 -383.349029) (xy 118.898152 -383.319015)
			(xy 118.912518 -383.291642) (xy 118.933017 -383.268504) (xy 118.958458 -383.250943) (xy 118.987362 -383.239981)
			(xy 119.01805 -383.236255) (xy 119.048738 -383.239981) (xy 119.077642 -383.250943) (xy 119.103083 -383.268504)
			(xy 119.123582 -383.291642) (xy 119.137948 -383.319015) (xy 119.145346 -383.349029) (xy 119.145812 -383.364486)
			(xy 119.145812 -383.440686) (xy 120.090184 -383.440686) (xy 120.090184 -383.364486) (xy 120.09065 -383.349029)
			(xy 120.098048 -383.319015) (xy 120.112414 -383.291642) (xy 120.132913 -383.268504) (xy 120.158354 -383.250943)
			(xy 120.187258 -383.239981) (xy 120.217946 -383.236255) (xy 120.248634 -383.239981) (xy 120.277538 -383.250943)
			(xy 120.302979 -383.268504) (xy 120.323478 -383.291642) (xy 120.337844 -383.319015) (xy 120.345242 -383.349029)
			(xy 120.345708 -383.364486) (xy 120.345708 -383.440686) (xy 121.290588 -383.440686) (xy 121.290588 -383.364486)
			(xy 121.291053 -383.34906) (xy 121.298436 -383.319105) (xy 121.312773 -383.291787) (xy 121.333232 -383.268694)
			(xy 121.358622 -383.251168) (xy 121.387469 -383.240228) (xy 121.418096 -383.23651) (xy 121.448723 -383.240228)
			(xy 121.47757 -383.251168) (xy 121.50296 -383.268694) (xy 121.523419 -383.291787) (xy 121.537756 -383.319105)
			(xy 121.545139 -383.34906) (xy 121.545604 -383.364486) (xy 121.545604 -383.440686) (xy 122.490484 -383.440686)
			(xy 122.490484 -383.364486) (xy 122.490949 -383.34906) (xy 122.498332 -383.319105) (xy 122.512669 -383.291787)
			(xy 122.533128 -383.268694) (xy 122.558518 -383.251168) (xy 122.587365 -383.240228) (xy 122.617992 -383.23651)
			(xy 122.648619 -383.240228) (xy 122.677466 -383.251168) (xy 122.702856 -383.268694) (xy 122.723315 -383.291787)
			(xy 122.737652 -383.319105) (xy 122.745035 -383.34906) (xy 122.7455 -383.364486) (xy 122.7455 -383.440686)
			(xy 123.69038 -383.440686) (xy 123.69038 -383.364486) (xy 123.690845 -383.34906) (xy 123.698228 -383.319105)
			(xy 123.712565 -383.291787) (xy 123.733024 -383.268694) (xy 123.758414 -383.251168) (xy 123.787261 -383.240228)
			(xy 123.817888 -383.23651) (xy 123.848515 -383.240228) (xy 123.877362 -383.251168) (xy 123.902752 -383.268694)
			(xy 123.923211 -383.291787) (xy 123.937548 -383.319105) (xy 123.944931 -383.34906) (xy 123.945396 -383.364486)
			(xy 123.945396 -383.440686) (xy 124.890276 -383.440686) (xy 124.890276 -383.364486) (xy 124.890742 -383.349029)
			(xy 124.89814 -383.319015) (xy 124.912506 -383.291642) (xy 124.933005 -383.268504) (xy 124.958446 -383.250943)
			(xy 124.98735 -383.239981) (xy 125.018038 -383.236255) (xy 125.048726 -383.239981) (xy 125.07763 -383.250943)
			(xy 125.103071 -383.268504) (xy 125.12357 -383.291642) (xy 125.137936 -383.319015) (xy 125.145334 -383.349029)
			(xy 125.1458 -383.364486) (xy 125.1458 -383.440686) (xy 126.090172 -383.440686) (xy 126.090172 -383.364486)
			(xy 126.090638 -383.349029) (xy 126.098036 -383.319015) (xy 126.112402 -383.291642) (xy 126.132901 -383.268504)
			(xy 126.158342 -383.250943) (xy 126.187246 -383.239981) (xy 126.217934 -383.236255) (xy 126.248622 -383.239981)
			(xy 126.277526 -383.250943) (xy 126.302967 -383.268504) (xy 126.323466 -383.291642) (xy 126.337832 -383.319015)
			(xy 126.34523 -383.349029) (xy 126.345696 -383.364486) (xy 126.345696 -383.440686) (xy 127.290576 -383.440686)
			(xy 127.290576 -383.364486) (xy 127.291041 -383.34906) (xy 127.298424 -383.319105) (xy 127.312761 -383.291787)
			(xy 127.33322 -383.268694) (xy 127.35861 -383.251168) (xy 127.387457 -383.240228) (xy 127.418084 -383.23651)
			(xy 127.448711 -383.240228) (xy 127.477558 -383.251168) (xy 127.502948 -383.268694) (xy 127.523407 -383.291787)
			(xy 127.537744 -383.319105) (xy 127.545127 -383.34906) (xy 127.545592 -383.364486) (xy 127.545592 -383.440686)
			(xy 128.490472 -383.440686) (xy 128.490472 -383.364486) (xy 128.490937 -383.34906) (xy 128.49832 -383.319105)
			(xy 128.512657 -383.291787) (xy 128.533116 -383.268694) (xy 128.558506 -383.251168) (xy 128.587353 -383.240228)
			(xy 128.61798 -383.23651) (xy 128.648607 -383.240228) (xy 128.677454 -383.251168) (xy 128.702844 -383.268694)
			(xy 128.723303 -383.291787) (xy 128.73764 -383.319105) (xy 128.745023 -383.34906) (xy 128.745488 -383.364486)
			(xy 128.745488 -383.440686) (xy 129.690368 -383.440686) (xy 129.690368 -383.364486) (xy 129.690833 -383.34906)
			(xy 129.698216 -383.319105) (xy 129.712553 -383.291787) (xy 129.733012 -383.268694) (xy 129.758402 -383.251168)
			(xy 129.787249 -383.240228) (xy 129.817876 -383.23651) (xy 129.848503 -383.240228) (xy 129.87735 -383.251168)
			(xy 129.90274 -383.268694) (xy 129.923199 -383.291787) (xy 129.937536 -383.319105) (xy 129.944919 -383.34906)
			(xy 129.945384 -383.364486) (xy 129.945384 -383.440686) (xy 130.890264 -383.440686) (xy 130.890264 -383.364486)
			(xy 130.89073 -383.349029) (xy 130.898128 -383.319015) (xy 130.912494 -383.291642) (xy 130.932993 -383.268504)
			(xy 130.958434 -383.250943) (xy 130.987338 -383.239981) (xy 131.018026 -383.236255) (xy 131.048714 -383.239981)
			(xy 131.077618 -383.250943) (xy 131.103059 -383.268504) (xy 131.123558 -383.291642) (xy 131.137924 -383.319015)
			(xy 131.145322 -383.349029) (xy 131.145788 -383.364486) (xy 131.145788 -383.440686) (xy 132.09016 -383.440686)
			(xy 132.09016 -383.364486) (xy 132.090626 -383.349029) (xy 132.098024 -383.319015) (xy 132.11239 -383.291642)
			(xy 132.132889 -383.268504) (xy 132.15833 -383.250943) (xy 132.187234 -383.239981) (xy 132.217922 -383.236255)
			(xy 132.24861 -383.239981) (xy 132.277514 -383.250943) (xy 132.302955 -383.268504) (xy 132.323454 -383.291642)
			(xy 132.33782 -383.319015) (xy 132.345218 -383.349029) (xy 132.345684 -383.364486) (xy 132.345684 -383.440686)
			(xy 146.617944 -383.440686) (xy 146.617944 -383.364486) (xy 146.61841 -383.349029) (xy 146.625808 -383.319015)
			(xy 146.640174 -383.291642) (xy 146.660673 -383.268504) (xy 146.686114 -383.250943) (xy 146.715018 -383.239981)
			(xy 146.745706 -383.236255) (xy 146.776394 -383.239981) (xy 146.805298 -383.250943) (xy 146.830739 -383.268504)
			(xy 146.851238 -383.291642) (xy 146.865604 -383.319015) (xy 146.873002 -383.349029) (xy 146.873468 -383.364486)
			(xy 146.873468 -383.440686) (xy 147.81784 -383.440686) (xy 147.81784 -383.364486) (xy 147.818306 -383.349029)
			(xy 147.825704 -383.319015) (xy 147.84007 -383.291642) (xy 147.860569 -383.268504) (xy 147.88601 -383.250943)
			(xy 147.914914 -383.239981) (xy 147.945602 -383.236255) (xy 147.97629 -383.239981) (xy 148.005194 -383.250943)
			(xy 148.030635 -383.268504) (xy 148.051134 -383.291642) (xy 148.0655 -383.319015) (xy 148.072898 -383.349029)
			(xy 148.073364 -383.364486) (xy 148.073364 -383.440686) (xy 149.018244 -383.440686) (xy 149.018244 -383.364486)
			(xy 149.018709 -383.34906) (xy 149.026092 -383.319105) (xy 149.040429 -383.291787) (xy 149.060888 -383.268694)
			(xy 149.086278 -383.251168) (xy 149.115125 -383.240228) (xy 149.145752 -383.23651) (xy 149.176379 -383.240228)
			(xy 149.205226 -383.251168) (xy 149.230616 -383.268694) (xy 149.251075 -383.291787) (xy 149.265412 -383.319105)
			(xy 149.272795 -383.34906) (xy 149.27326 -383.364486) (xy 149.27326 -383.440686) (xy 150.21814 -383.440686)
			(xy 150.21814 -383.364486) (xy 150.218605 -383.34906) (xy 150.225988 -383.319105) (xy 150.240325 -383.291787)
			(xy 150.260784 -383.268694) (xy 150.286174 -383.251168) (xy 150.315021 -383.240228) (xy 150.345648 -383.23651)
			(xy 150.376275 -383.240228) (xy 150.405122 -383.251168) (xy 150.430512 -383.268694) (xy 150.450971 -383.291787)
			(xy 150.465308 -383.319105) (xy 150.472691 -383.34906) (xy 150.473156 -383.364486) (xy 150.473156 -383.440686)
			(xy 151.418036 -383.440686) (xy 151.418036 -383.364486) (xy 151.418502 -383.349029) (xy 151.4259 -383.319015)
			(xy 151.440266 -383.291642) (xy 151.460765 -383.268504) (xy 151.486206 -383.250943) (xy 151.51511 -383.239981)
			(xy 151.545798 -383.236255) (xy 151.576486 -383.239981) (xy 151.60539 -383.250943) (xy 151.630831 -383.268504)
			(xy 151.65133 -383.291642) (xy 151.665696 -383.319015) (xy 151.673094 -383.349029) (xy 151.67356 -383.364486)
			(xy 151.67356 -383.440686) (xy 152.617932 -383.440686) (xy 152.617932 -383.364486) (xy 152.618398 -383.349029)
			(xy 152.625796 -383.319015) (xy 152.640162 -383.291642) (xy 152.660661 -383.268504) (xy 152.686102 -383.250943)
			(xy 152.715006 -383.239981) (xy 152.745694 -383.236255) (xy 152.776382 -383.239981) (xy 152.805286 -383.250943)
			(xy 152.830727 -383.268504) (xy 152.851226 -383.291642) (xy 152.865592 -383.319015) (xy 152.87299 -383.349029)
			(xy 152.873456 -383.364486) (xy 152.873456 -383.440686) (xy 153.818336 -383.440686) (xy 153.818336 -383.364486)
			(xy 153.818801 -383.34906) (xy 153.826184 -383.319105) (xy 153.840521 -383.291787) (xy 153.86098 -383.268694)
			(xy 153.88637 -383.251168) (xy 153.915217 -383.240228) (xy 153.945844 -383.23651) (xy 153.976471 -383.240228)
			(xy 154.005318 -383.251168) (xy 154.030708 -383.268694) (xy 154.051167 -383.291787) (xy 154.065504 -383.319105)
			(xy 154.072887 -383.34906) (xy 154.073352 -383.364486) (xy 154.073352 -383.440686) (xy 155.018232 -383.440686)
			(xy 155.018232 -383.364486) (xy 155.018697 -383.34906) (xy 155.02608 -383.319105) (xy 155.040417 -383.291787)
			(xy 155.060876 -383.268694) (xy 155.086266 -383.251168) (xy 155.115113 -383.240228) (xy 155.14574 -383.23651)
			(xy 155.176367 -383.240228) (xy 155.205214 -383.251168) (xy 155.230604 -383.268694) (xy 155.251063 -383.291787)
			(xy 155.2654 -383.319105) (xy 155.272783 -383.34906) (xy 155.273248 -383.364486) (xy 155.273248 -383.440686)
			(xy 156.218128 -383.440686) (xy 156.218128 -383.364486) (xy 156.218593 -383.34906) (xy 156.225976 -383.319105)
			(xy 156.240313 -383.291787) (xy 156.260772 -383.268694) (xy 156.286162 -383.251168) (xy 156.315009 -383.240228)
			(xy 156.345636 -383.23651) (xy 156.376263 -383.240228) (xy 156.40511 -383.251168) (xy 156.4305 -383.268694)
			(xy 156.450959 -383.291787) (xy 156.465296 -383.319105) (xy 156.472679 -383.34906) (xy 156.473144 -383.364486)
			(xy 156.473144 -383.440686) (xy 157.418024 -383.440686) (xy 157.418024 -383.364486) (xy 157.41849 -383.349029)
			(xy 157.425888 -383.319015) (xy 157.440254 -383.291642) (xy 157.460753 -383.268504) (xy 157.486194 -383.250943)
			(xy 157.515098 -383.239981) (xy 157.545786 -383.236255) (xy 157.576474 -383.239981) (xy 157.605378 -383.250943)
			(xy 157.630819 -383.268504) (xy 157.651318 -383.291642) (xy 157.665684 -383.319015) (xy 157.673082 -383.349029)
			(xy 157.673548 -383.364486) (xy 157.673548 -383.440686) (xy 158.61792 -383.440686) (xy 158.61792 -383.364486)
			(xy 158.618386 -383.349029) (xy 158.625784 -383.319015) (xy 158.64015 -383.291642) (xy 158.660649 -383.268504)
			(xy 158.68609 -383.250943) (xy 158.714994 -383.239981) (xy 158.745682 -383.236255) (xy 158.77637 -383.239981)
			(xy 158.805274 -383.250943) (xy 158.830715 -383.268504) (xy 158.851214 -383.291642) (xy 158.86558 -383.319015)
			(xy 158.872978 -383.349029) (xy 158.873444 -383.364486) (xy 158.873444 -383.440686) (xy 159.818324 -383.440686)
			(xy 159.818324 -383.364486) (xy 159.818789 -383.34906) (xy 159.826172 -383.319105) (xy 159.840509 -383.291787)
			(xy 159.860968 -383.268694) (xy 159.886358 -383.251168) (xy 159.915205 -383.240228) (xy 159.945832 -383.23651)
			(xy 159.976459 -383.240228) (xy 160.005306 -383.251168) (xy 160.030696 -383.268694) (xy 160.051155 -383.291787)
			(xy 160.065492 -383.319105) (xy 160.072875 -383.34906) (xy 160.07334 -383.364486) (xy 160.07334 -383.440686)
			(xy 161.01822 -383.440686) (xy 161.01822 -383.364486) (xy 161.018685 -383.34906) (xy 161.026068 -383.319105)
			(xy 161.040405 -383.291787) (xy 161.060864 -383.268694) (xy 161.086254 -383.251168) (xy 161.115101 -383.240228)
			(xy 161.145728 -383.23651) (xy 161.176355 -383.240228) (xy 161.205202 -383.251168) (xy 161.230592 -383.268694)
			(xy 161.251051 -383.291787) (xy 161.265388 -383.319105) (xy 161.272771 -383.34906) (xy 161.273236 -383.364486)
			(xy 161.273236 -383.440686) (xy 162.218116 -383.440686) (xy 162.218116 -383.364486) (xy 162.218581 -383.34906)
			(xy 162.225964 -383.319105) (xy 162.240301 -383.291787) (xy 162.26076 -383.268694) (xy 162.28615 -383.251168)
			(xy 162.314997 -383.240228) (xy 162.345624 -383.23651) (xy 162.376251 -383.240228) (xy 162.405098 -383.251168)
			(xy 162.430488 -383.268694) (xy 162.450947 -383.291787) (xy 162.465284 -383.319105) (xy 162.472667 -383.34906)
			(xy 162.473132 -383.364486) (xy 162.473132 -383.440686) (xy 163.418012 -383.440686) (xy 163.418012 -383.364486)
			(xy 163.418478 -383.349029) (xy 163.425876 -383.319015) (xy 163.440242 -383.291642) (xy 163.460741 -383.268504)
			(xy 163.486182 -383.250943) (xy 163.515086 -383.239981) (xy 163.545774 -383.236255) (xy 163.576462 -383.239981)
			(xy 163.605366 -383.250943) (xy 163.630807 -383.268504) (xy 163.651306 -383.291642) (xy 163.665672 -383.319015)
			(xy 163.67307 -383.349029) (xy 163.673536 -383.364486) (xy 163.673536 -383.440686) (xy 164.617908 -383.440686)
			(xy 164.617908 -383.364486) (xy 164.618374 -383.349029) (xy 164.625772 -383.319015) (xy 164.640138 -383.291642)
			(xy 164.660637 -383.268504) (xy 164.686078 -383.250943) (xy 164.714982 -383.239981) (xy 164.74567 -383.236255)
			(xy 164.776358 -383.239981) (xy 164.805262 -383.250943) (xy 164.830703 -383.268504) (xy 164.851202 -383.291642)
			(xy 164.865568 -383.319015) (xy 164.872966 -383.349029) (xy 164.873432 -383.364486) (xy 164.873432 -383.440686)
			(xy 164.872966 -383.456143) (xy 164.865568 -383.486157) (xy 164.851202 -383.51353) (xy 164.830703 -383.536668)
			(xy 164.805262 -383.554229) (xy 164.776358 -383.565191) (xy 164.74567 -383.568917) (xy 164.714982 -383.565191)
			(xy 164.686078 -383.554229) (xy 164.660637 -383.536668) (xy 164.640138 -383.51353) (xy 164.625772 -383.486157)
			(xy 164.618374 -383.456143) (xy 164.617908 -383.440686) (xy 163.673536 -383.440686) (xy 163.67307 -383.456143)
			(xy 163.665672 -383.486157) (xy 163.651306 -383.51353) (xy 163.630807 -383.536668) (xy 163.605366 -383.554229)
			(xy 163.576462 -383.565191) (xy 163.545774 -383.568917) (xy 163.515086 -383.565191) (xy 163.486182 -383.554229)
			(xy 163.460741 -383.536668) (xy 163.440242 -383.51353) (xy 163.425876 -383.486157) (xy 163.418478 -383.456143)
			(xy 163.418012 -383.440686) (xy 162.473132 -383.440686) (xy 162.472667 -383.456112) (xy 162.465284 -383.486067)
			(xy 162.450947 -383.513385) (xy 162.430488 -383.536478) (xy 162.405098 -383.554004) (xy 162.376251 -383.564944)
			(xy 162.345624 -383.568663) (xy 162.314997 -383.564944) (xy 162.28615 -383.554004) (xy 162.26076 -383.536478)
			(xy 162.240301 -383.513385) (xy 162.225964 -383.486067) (xy 162.218581 -383.456112) (xy 162.218116 -383.440686)
			(xy 161.273236 -383.440686) (xy 161.272771 -383.456112) (xy 161.265388 -383.486067) (xy 161.251051 -383.513385)
			(xy 161.230592 -383.536478) (xy 161.205202 -383.554004) (xy 161.176355 -383.564944) (xy 161.145728 -383.568663)
			(xy 161.115101 -383.564944) (xy 161.086254 -383.554004) (xy 161.060864 -383.536478) (xy 161.040405 -383.513385)
			(xy 161.026068 -383.486067) (xy 161.018685 -383.456112) (xy 161.01822 -383.440686) (xy 160.07334 -383.440686)
			(xy 160.072875 -383.456112) (xy 160.065492 -383.486067) (xy 160.051155 -383.513385) (xy 160.030696 -383.536478)
			(xy 160.005306 -383.554004) (xy 159.976459 -383.564944) (xy 159.945832 -383.568663) (xy 159.915205 -383.564944)
			(xy 159.886358 -383.554004) (xy 159.860968 -383.536478) (xy 159.840509 -383.513385) (xy 159.826172 -383.486067)
			(xy 159.818789 -383.456112) (xy 159.818324 -383.440686) (xy 158.873444 -383.440686) (xy 158.872978 -383.456143)
			(xy 158.86558 -383.486157) (xy 158.851214 -383.51353) (xy 158.830715 -383.536668) (xy 158.805274 -383.554229)
			(xy 158.77637 -383.565191) (xy 158.745682 -383.568917) (xy 158.714994 -383.565191) (xy 158.68609 -383.554229)
			(xy 158.660649 -383.536668) (xy 158.64015 -383.51353) (xy 158.625784 -383.486157) (xy 158.618386 -383.456143)
			(xy 158.61792 -383.440686) (xy 157.673548 -383.440686) (xy 157.673082 -383.456143) (xy 157.665684 -383.486157)
			(xy 157.651318 -383.51353) (xy 157.630819 -383.536668) (xy 157.605378 -383.554229) (xy 157.576474 -383.565191)
			(xy 157.545786 -383.568917) (xy 157.515098 -383.565191) (xy 157.486194 -383.554229) (xy 157.460753 -383.536668)
			(xy 157.440254 -383.51353) (xy 157.425888 -383.486157) (xy 157.41849 -383.456143) (xy 157.418024 -383.440686)
			(xy 156.473144 -383.440686) (xy 156.472679 -383.456112) (xy 156.465296 -383.486067) (xy 156.450959 -383.513385)
			(xy 156.4305 -383.536478) (xy 156.40511 -383.554004) (xy 156.376263 -383.564944) (xy 156.345636 -383.568663)
			(xy 156.315009 -383.564944) (xy 156.286162 -383.554004) (xy 156.260772 -383.536478) (xy 156.240313 -383.513385)
			(xy 156.225976 -383.486067) (xy 156.218593 -383.456112) (xy 156.218128 -383.440686) (xy 155.273248 -383.440686)
			(xy 155.272783 -383.456112) (xy 155.2654 -383.486067) (xy 155.251063 -383.513385) (xy 155.230604 -383.536478)
			(xy 155.205214 -383.554004) (xy 155.176367 -383.564944) (xy 155.14574 -383.568663) (xy 155.115113 -383.564944)
			(xy 155.086266 -383.554004) (xy 155.060876 -383.536478) (xy 155.040417 -383.513385) (xy 155.02608 -383.486067)
			(xy 155.018697 -383.456112) (xy 155.018232 -383.440686) (xy 154.073352 -383.440686) (xy 154.072887 -383.456112)
			(xy 154.065504 -383.486067) (xy 154.051167 -383.513385) (xy 154.030708 -383.536478) (xy 154.005318 -383.554004)
			(xy 153.976471 -383.564944) (xy 153.945844 -383.568663) (xy 153.915217 -383.564944) (xy 153.88637 -383.554004)
			(xy 153.86098 -383.536478) (xy 153.840521 -383.513385) (xy 153.826184 -383.486067) (xy 153.818801 -383.456112)
			(xy 153.818336 -383.440686) (xy 152.873456 -383.440686) (xy 152.87299 -383.456143) (xy 152.865592 -383.486157)
			(xy 152.851226 -383.51353) (xy 152.830727 -383.536668) (xy 152.805286 -383.554229) (xy 152.776382 -383.565191)
			(xy 152.745694 -383.568917) (xy 152.715006 -383.565191) (xy 152.686102 -383.554229) (xy 152.660661 -383.536668)
			(xy 152.640162 -383.51353) (xy 152.625796 -383.486157) (xy 152.618398 -383.456143) (xy 152.617932 -383.440686)
			(xy 151.67356 -383.440686) (xy 151.673094 -383.456143) (xy 151.665696 -383.486157) (xy 151.65133 -383.51353)
			(xy 151.630831 -383.536668) (xy 151.60539 -383.554229) (xy 151.576486 -383.565191) (xy 151.545798 -383.568917)
			(xy 151.51511 -383.565191) (xy 151.486206 -383.554229) (xy 151.460765 -383.536668) (xy 151.440266 -383.51353)
			(xy 151.4259 -383.486157) (xy 151.418502 -383.456143) (xy 151.418036 -383.440686) (xy 150.473156 -383.440686)
			(xy 150.472691 -383.456112) (xy 150.465308 -383.486067) (xy 150.450971 -383.513385) (xy 150.430512 -383.536478)
			(xy 150.405122 -383.554004) (xy 150.376275 -383.564944) (xy 150.345648 -383.568663) (xy 150.315021 -383.564944)
			(xy 150.286174 -383.554004) (xy 150.260784 -383.536478) (xy 150.240325 -383.513385) (xy 150.225988 -383.486067)
			(xy 150.218605 -383.456112) (xy 150.21814 -383.440686) (xy 149.27326 -383.440686) (xy 149.272795 -383.456112)
			(xy 149.265412 -383.486067) (xy 149.251075 -383.513385) (xy 149.230616 -383.536478) (xy 149.205226 -383.554004)
			(xy 149.176379 -383.564944) (xy 149.145752 -383.568663) (xy 149.115125 -383.564944) (xy 149.086278 -383.554004)
			(xy 149.060888 -383.536478) (xy 149.040429 -383.513385) (xy 149.026092 -383.486067) (xy 149.018709 -383.456112)
			(xy 149.018244 -383.440686) (xy 148.073364 -383.440686) (xy 148.072898 -383.456143) (xy 148.0655 -383.486157)
			(xy 148.051134 -383.51353) (xy 148.030635 -383.536668) (xy 148.005194 -383.554229) (xy 147.97629 -383.565191)
			(xy 147.945602 -383.568917) (xy 147.914914 -383.565191) (xy 147.88601 -383.554229) (xy 147.860569 -383.536668)
			(xy 147.84007 -383.51353) (xy 147.825704 -383.486157) (xy 147.818306 -383.456143) (xy 147.81784 -383.440686)
			(xy 146.873468 -383.440686) (xy 146.873002 -383.456143) (xy 146.865604 -383.486157) (xy 146.851238 -383.51353)
			(xy 146.830739 -383.536668) (xy 146.805298 -383.554229) (xy 146.776394 -383.565191) (xy 146.745706 -383.568917)
			(xy 146.715018 -383.565191) (xy 146.686114 -383.554229) (xy 146.660673 -383.536668) (xy 146.640174 -383.51353)
			(xy 146.625808 -383.486157) (xy 146.61841 -383.456143) (xy 146.617944 -383.440686) (xy 132.345684 -383.440686)
			(xy 132.345218 -383.456143) (xy 132.33782 -383.486157) (xy 132.323454 -383.51353) (xy 132.302955 -383.536668)
			(xy 132.277514 -383.554229) (xy 132.24861 -383.565191) (xy 132.217922 -383.568917) (xy 132.187234 -383.565191)
			(xy 132.15833 -383.554229) (xy 132.132889 -383.536668) (xy 132.11239 -383.51353) (xy 132.098024 -383.486157)
			(xy 132.090626 -383.456143) (xy 132.09016 -383.440686) (xy 131.145788 -383.440686) (xy 131.145322 -383.456143)
			(xy 131.137924 -383.486157) (xy 131.123558 -383.51353) (xy 131.103059 -383.536668) (xy 131.077618 -383.554229)
			(xy 131.048714 -383.565191) (xy 131.018026 -383.568917) (xy 130.987338 -383.565191) (xy 130.958434 -383.554229)
			(xy 130.932993 -383.536668) (xy 130.912494 -383.51353) (xy 130.898128 -383.486157) (xy 130.89073 -383.456143)
			(xy 130.890264 -383.440686) (xy 129.945384 -383.440686) (xy 129.944919 -383.456112) (xy 129.937536 -383.486067)
			(xy 129.923199 -383.513385) (xy 129.90274 -383.536478) (xy 129.87735 -383.554004) (xy 129.848503 -383.564944)
			(xy 129.817876 -383.568663) (xy 129.787249 -383.564944) (xy 129.758402 -383.554004) (xy 129.733012 -383.536478)
			(xy 129.712553 -383.513385) (xy 129.698216 -383.486067) (xy 129.690833 -383.456112) (xy 129.690368 -383.440686)
			(xy 128.745488 -383.440686) (xy 128.745023 -383.456112) (xy 128.73764 -383.486067) (xy 128.723303 -383.513385)
			(xy 128.702844 -383.536478) (xy 128.677454 -383.554004) (xy 128.648607 -383.564944) (xy 128.61798 -383.568663)
			(xy 128.587353 -383.564944) (xy 128.558506 -383.554004) (xy 128.533116 -383.536478) (xy 128.512657 -383.513385)
			(xy 128.49832 -383.486067) (xy 128.490937 -383.456112) (xy 128.490472 -383.440686) (xy 127.545592 -383.440686)
			(xy 127.545127 -383.456112) (xy 127.537744 -383.486067) (xy 127.523407 -383.513385) (xy 127.502948 -383.536478)
			(xy 127.477558 -383.554004) (xy 127.448711 -383.564944) (xy 127.418084 -383.568663) (xy 127.387457 -383.564944)
			(xy 127.35861 -383.554004) (xy 127.33322 -383.536478) (xy 127.312761 -383.513385) (xy 127.298424 -383.486067)
			(xy 127.291041 -383.456112) (xy 127.290576 -383.440686) (xy 126.345696 -383.440686) (xy 126.34523 -383.456143)
			(xy 126.337832 -383.486157) (xy 126.323466 -383.51353) (xy 126.302967 -383.536668) (xy 126.277526 -383.554229)
			(xy 126.248622 -383.565191) (xy 126.217934 -383.568917) (xy 126.187246 -383.565191) (xy 126.158342 -383.554229)
			(xy 126.132901 -383.536668) (xy 126.112402 -383.51353) (xy 126.098036 -383.486157) (xy 126.090638 -383.456143)
			(xy 126.090172 -383.440686) (xy 125.1458 -383.440686) (xy 125.145334 -383.456143) (xy 125.137936 -383.486157)
			(xy 125.12357 -383.51353) (xy 125.103071 -383.536668) (xy 125.07763 -383.554229) (xy 125.048726 -383.565191)
			(xy 125.018038 -383.568917) (xy 124.98735 -383.565191) (xy 124.958446 -383.554229) (xy 124.933005 -383.536668)
			(xy 124.912506 -383.51353) (xy 124.89814 -383.486157) (xy 124.890742 -383.456143) (xy 124.890276 -383.440686)
			(xy 123.945396 -383.440686) (xy 123.944931 -383.456112) (xy 123.937548 -383.486067) (xy 123.923211 -383.513385)
			(xy 123.902752 -383.536478) (xy 123.877362 -383.554004) (xy 123.848515 -383.564944) (xy 123.817888 -383.568663)
			(xy 123.787261 -383.564944) (xy 123.758414 -383.554004) (xy 123.733024 -383.536478) (xy 123.712565 -383.513385)
			(xy 123.698228 -383.486067) (xy 123.690845 -383.456112) (xy 123.69038 -383.440686) (xy 122.7455 -383.440686)
			(xy 122.745035 -383.456112) (xy 122.737652 -383.486067) (xy 122.723315 -383.513385) (xy 122.702856 -383.536478)
			(xy 122.677466 -383.554004) (xy 122.648619 -383.564944) (xy 122.617992 -383.568663) (xy 122.587365 -383.564944)
			(xy 122.558518 -383.554004) (xy 122.533128 -383.536478) (xy 122.512669 -383.513385) (xy 122.498332 -383.486067)
			(xy 122.490949 -383.456112) (xy 122.490484 -383.440686) (xy 121.545604 -383.440686) (xy 121.545139 -383.456112)
			(xy 121.537756 -383.486067) (xy 121.523419 -383.513385) (xy 121.50296 -383.536478) (xy 121.47757 -383.554004)
			(xy 121.448723 -383.564944) (xy 121.418096 -383.568663) (xy 121.387469 -383.564944) (xy 121.358622 -383.554004)
			(xy 121.333232 -383.536478) (xy 121.312773 -383.513385) (xy 121.298436 -383.486067) (xy 121.291053 -383.456112)
			(xy 121.290588 -383.440686) (xy 120.345708 -383.440686) (xy 120.345242 -383.456143) (xy 120.337844 -383.486157)
			(xy 120.323478 -383.51353) (xy 120.302979 -383.536668) (xy 120.277538 -383.554229) (xy 120.248634 -383.565191)
			(xy 120.217946 -383.568917) (xy 120.187258 -383.565191) (xy 120.158354 -383.554229) (xy 120.132913 -383.536668)
			(xy 120.112414 -383.51353) (xy 120.098048 -383.486157) (xy 120.09065 -383.456143) (xy 120.090184 -383.440686)
			(xy 119.145812 -383.440686) (xy 119.145346 -383.456143) (xy 119.137948 -383.486157) (xy 119.123582 -383.51353)
			(xy 119.103083 -383.536668) (xy 119.077642 -383.554229) (xy 119.048738 -383.565191) (xy 119.01805 -383.568917)
			(xy 118.987362 -383.565191) (xy 118.958458 -383.554229) (xy 118.933017 -383.536668) (xy 118.912518 -383.51353)
			(xy 118.898152 -383.486157) (xy 118.890754 -383.456143) (xy 118.890288 -383.440686) (xy 117.945408 -383.440686)
			(xy 117.944943 -383.456112) (xy 117.93756 -383.486067) (xy 117.923223 -383.513385) (xy 117.902764 -383.536478)
			(xy 117.877374 -383.554004) (xy 117.848527 -383.564944) (xy 117.8179 -383.568663) (xy 117.787273 -383.564944)
			(xy 117.758426 -383.554004) (xy 117.733036 -383.536478) (xy 117.712577 -383.513385) (xy 117.69824 -383.486067)
			(xy 117.690857 -383.456112) (xy 117.690392 -383.440686) (xy 116.745512 -383.440686) (xy 116.745047 -383.456112)
			(xy 116.737664 -383.486067) (xy 116.723327 -383.513385) (xy 116.702868 -383.536478) (xy 116.677478 -383.554004)
			(xy 116.648631 -383.564944) (xy 116.618004 -383.568663) (xy 116.587377 -383.564944) (xy 116.55853 -383.554004)
			(xy 116.53314 -383.536478) (xy 116.512681 -383.513385) (xy 116.498344 -383.486067) (xy 116.490961 -383.456112)
			(xy 116.490496 -383.440686) (xy 115.545616 -383.440686) (xy 115.54515 -383.456143) (xy 115.537752 -383.486157)
			(xy 115.523386 -383.51353) (xy 115.502887 -383.536668) (xy 115.477446 -383.554229) (xy 115.448542 -383.565191)
			(xy 115.417854 -383.568917) (xy 115.387166 -383.565191) (xy 115.358262 -383.554229) (xy 115.332821 -383.536668)
			(xy 115.312322 -383.51353) (xy 115.297956 -383.486157) (xy 115.290558 -383.456143) (xy 115.290092 -383.440686)
			(xy 114.34572 -383.440686) (xy 114.345254 -383.456143) (xy 114.337856 -383.486157) (xy 114.32349 -383.51353)
			(xy 114.302991 -383.536668) (xy 114.27755 -383.554229) (xy 114.248646 -383.565191) (xy 114.217958 -383.568917)
			(xy 114.18727 -383.565191) (xy 114.158366 -383.554229) (xy 114.132925 -383.536668) (xy 114.112426 -383.51353)
			(xy 114.09806 -383.486157) (xy 114.090662 -383.456143) (xy 114.090196 -383.440686) (xy 97.773236 -383.440686)
			(xy 97.772771 -383.456112) (xy 97.765388 -383.486067) (xy 97.751051 -383.513385) (xy 97.730592 -383.536478)
			(xy 97.705202 -383.554004) (xy 97.676355 -383.564944) (xy 97.645728 -383.568663) (xy 97.615101 -383.564944)
			(xy 97.586254 -383.554004) (xy 97.560864 -383.536478) (xy 97.540405 -383.513385) (xy 97.526068 -383.486067)
			(xy 97.518685 -383.456112) (xy 97.51822 -383.440686) (xy 96.57334 -383.440686) (xy 96.572875 -383.456112)
			(xy 96.565492 -383.486067) (xy 96.551155 -383.513385) (xy 96.530696 -383.536478) (xy 96.505306 -383.554004)
			(xy 96.476459 -383.564944) (xy 96.445832 -383.568663) (xy 96.415205 -383.564944) (xy 96.386358 -383.554004)
			(xy 96.360968 -383.536478) (xy 96.340509 -383.513385) (xy 96.326172 -383.486067) (xy 96.318789 -383.456112)
			(xy 96.318324 -383.440686) (xy 95.373444 -383.440686) (xy 95.372978 -383.456143) (xy 95.36558 -383.486157)
			(xy 95.351214 -383.51353) (xy 95.330715 -383.536668) (xy 95.305274 -383.554229) (xy 95.27637 -383.565191)
			(xy 95.245682 -383.568917) (xy 95.214994 -383.565191) (xy 95.18609 -383.554229) (xy 95.160649 -383.536668)
			(xy 95.14015 -383.51353) (xy 95.125784 -383.486157) (xy 95.118386 -383.456143) (xy 95.11792 -383.440686)
			(xy 94.173548 -383.440686) (xy 94.173082 -383.456143) (xy 94.165684 -383.486157) (xy 94.151318 -383.51353)
			(xy 94.130819 -383.536668) (xy 94.105378 -383.554229) (xy 94.076474 -383.565191) (xy 94.045786 -383.568917)
			(xy 94.015098 -383.565191) (xy 93.986194 -383.554229) (xy 93.960753 -383.536668) (xy 93.940254 -383.51353)
			(xy 93.925888 -383.486157) (xy 93.91849 -383.456143) (xy 93.918024 -383.440686) (xy 92.973652 -383.440686)
			(xy 92.973186 -383.456143) (xy 92.965788 -383.486157) (xy 92.951422 -383.51353) (xy 92.930923 -383.536668)
			(xy 92.905482 -383.554229) (xy 92.876578 -383.565191) (xy 92.84589 -383.568917) (xy 92.815202 -383.565191)
			(xy 92.786298 -383.554229) (xy 92.760857 -383.536668) (xy 92.740358 -383.51353) (xy 92.725992 -383.486157)
			(xy 92.718594 -383.456143) (xy 92.718128 -383.440686) (xy 91.773248 -383.440686) (xy 91.772783 -383.456112)
			(xy 91.7654 -383.486067) (xy 91.751063 -383.513385) (xy 91.730604 -383.536478) (xy 91.705214 -383.554004)
			(xy 91.676367 -383.564944) (xy 91.64574 -383.568663) (xy 91.615113 -383.564944) (xy 91.586266 -383.554004)
			(xy 91.560876 -383.536478) (xy 91.540417 -383.513385) (xy 91.52608 -383.486067) (xy 91.518697 -383.456112)
			(xy 91.518232 -383.440686) (xy 90.573352 -383.440686) (xy 90.572887 -383.456112) (xy 90.565504 -383.486067)
			(xy 90.551167 -383.513385) (xy 90.530708 -383.536478) (xy 90.505318 -383.554004) (xy 90.476471 -383.564944)
			(xy 90.445844 -383.568663) (xy 90.415217 -383.564944) (xy 90.38637 -383.554004) (xy 90.36098 -383.536478)
			(xy 90.340521 -383.513385) (xy 90.326184 -383.486067) (xy 90.318801 -383.456112) (xy 90.318336 -383.440686)
			(xy 89.373456 -383.440686) (xy 89.37299 -383.456143) (xy 89.365592 -383.486157) (xy 89.351226 -383.51353)
			(xy 89.330727 -383.536668) (xy 89.305286 -383.554229) (xy 89.276382 -383.565191) (xy 89.245694 -383.568917)
			(xy 89.215006 -383.565191) (xy 89.186102 -383.554229) (xy 89.160661 -383.536668) (xy 89.140162 -383.51353)
			(xy 89.125796 -383.486157) (xy 89.118398 -383.456143) (xy 89.117932 -383.440686) (xy 88.17356 -383.440686)
			(xy 88.173094 -383.456143) (xy 88.165696 -383.486157) (xy 88.15133 -383.51353) (xy 88.130831 -383.536668)
			(xy 88.10539 -383.554229) (xy 88.076486 -383.565191) (xy 88.045798 -383.568917) (xy 88.01511 -383.565191)
			(xy 87.986206 -383.554229) (xy 87.960765 -383.536668) (xy 87.940266 -383.51353) (xy 87.9259 -383.486157)
			(xy 87.918502 -383.456143) (xy 87.918036 -383.440686) (xy 86.973664 -383.440686) (xy 86.973198 -383.456143)
			(xy 86.9658 -383.486157) (xy 86.951434 -383.51353) (xy 86.930935 -383.536668) (xy 86.905494 -383.554229)
			(xy 86.87659 -383.565191) (xy 86.845902 -383.568917) (xy 86.815214 -383.565191) (xy 86.78631 -383.554229)
			(xy 86.760869 -383.536668) (xy 86.74037 -383.51353) (xy 86.726004 -383.486157) (xy 86.718606 -383.456143)
			(xy 86.71814 -383.440686) (xy 85.77326 -383.440686) (xy 85.772795 -383.456112) (xy 85.765412 -383.486067)
			(xy 85.751075 -383.513385) (xy 85.730616 -383.536478) (xy 85.705226 -383.554004) (xy 85.676379 -383.564944)
			(xy 85.645752 -383.568663) (xy 85.615125 -383.564944) (xy 85.586278 -383.554004) (xy 85.560888 -383.536478)
			(xy 85.540429 -383.513385) (xy 85.526092 -383.486067) (xy 85.518709 -383.456112) (xy 85.518244 -383.440686)
			(xy 84.573364 -383.440686) (xy 84.572899 -383.456112) (xy 84.565516 -383.486067) (xy 84.551179 -383.513385)
			(xy 84.53072 -383.536478) (xy 84.50533 -383.554004) (xy 84.476483 -383.564944) (xy 84.445856 -383.568663)
			(xy 84.415229 -383.564944) (xy 84.386382 -383.554004) (xy 84.360992 -383.536478) (xy 84.340533 -383.513385)
			(xy 84.326196 -383.486067) (xy 84.318813 -383.456112) (xy 84.318348 -383.440686) (xy 83.373468 -383.440686)
			(xy 83.373002 -383.456143) (xy 83.365604 -383.486157) (xy 83.351238 -383.51353) (xy 83.330739 -383.536668)
			(xy 83.305298 -383.554229) (xy 83.276394 -383.565191) (xy 83.245706 -383.568917) (xy 83.215018 -383.565191)
			(xy 83.186114 -383.554229) (xy 83.160673 -383.536668) (xy 83.140174 -383.51353) (xy 83.125808 -383.486157)
			(xy 83.11841 -383.456143) (xy 83.117944 -383.440686) (xy 82.173572 -383.440686) (xy 82.173106 -383.456143)
			(xy 82.165708 -383.486157) (xy 82.151342 -383.51353) (xy 82.130843 -383.536668) (xy 82.105402 -383.554229)
			(xy 82.076498 -383.565191) (xy 82.04581 -383.568917) (xy 82.015122 -383.565191) (xy 81.986218 -383.554229)
			(xy 81.960777 -383.536668) (xy 81.940278 -383.51353) (xy 81.925912 -383.486157) (xy 81.918514 -383.456143)
			(xy 81.918048 -383.440686) (xy 80.973168 -383.440686) (xy 80.972703 -383.456112) (xy 80.96532 -383.486067)
			(xy 80.950983 -383.513385) (xy 80.930524 -383.536478) (xy 80.905134 -383.554004) (xy 80.876287 -383.564944)
			(xy 80.84566 -383.568663) (xy 80.815033 -383.564944) (xy 80.786186 -383.554004) (xy 80.760796 -383.536478)
			(xy 80.740337 -383.513385) (xy 80.726 -383.486067) (xy 80.718617 -383.456112) (xy 80.718152 -383.440686)
			(xy 79.773272 -383.440686) (xy 79.772807 -383.456112) (xy 79.765424 -383.486067) (xy 79.751087 -383.513385)
			(xy 79.730628 -383.536478) (xy 79.705238 -383.554004) (xy 79.676391 -383.564944) (xy 79.645764 -383.568663)
			(xy 79.615137 -383.564944) (xy 79.58629 -383.554004) (xy 79.5609 -383.536478) (xy 79.540441 -383.513385)
			(xy 79.526104 -383.486067) (xy 79.518721 -383.456112) (xy 79.518256 -383.440686) (xy 65.245488 -383.440686)
			(xy 65.245023 -383.456112) (xy 65.23764 -383.486067) (xy 65.223303 -383.513385) (xy 65.202844 -383.536478)
			(xy 65.177454 -383.554004) (xy 65.148607 -383.564944) (xy 65.11798 -383.568663) (xy 65.087353 -383.564944)
			(xy 65.058506 -383.554004) (xy 65.033116 -383.536478) (xy 65.012657 -383.513385) (xy 64.99832 -383.486067)
			(xy 64.990937 -383.456112) (xy 64.990472 -383.440686) (xy 64.045592 -383.440686) (xy 64.045127 -383.456112)
			(xy 64.037744 -383.486067) (xy 64.023407 -383.513385) (xy 64.002948 -383.536478) (xy 63.977558 -383.554004)
			(xy 63.948711 -383.564944) (xy 63.918084 -383.568663) (xy 63.887457 -383.564944) (xy 63.85861 -383.554004)
			(xy 63.83322 -383.536478) (xy 63.812761 -383.513385) (xy 63.798424 -383.486067) (xy 63.791041 -383.456112)
			(xy 63.790576 -383.440686) (xy 62.845696 -383.440686) (xy 62.84523 -383.456143) (xy 62.837832 -383.486157)
			(xy 62.823466 -383.51353) (xy 62.802967 -383.536668) (xy 62.777526 -383.554229) (xy 62.748622 -383.565191)
			(xy 62.717934 -383.568917) (xy 62.687246 -383.565191) (xy 62.658342 -383.554229) (xy 62.632901 -383.536668)
			(xy 62.612402 -383.51353) (xy 62.598036 -383.486157) (xy 62.590638 -383.456143) (xy 62.590172 -383.440686)
			(xy 61.6458 -383.440686) (xy 61.645334 -383.456143) (xy 61.637936 -383.486157) (xy 61.62357 -383.51353)
			(xy 61.603071 -383.536668) (xy 61.57763 -383.554229) (xy 61.548726 -383.565191) (xy 61.518038 -383.568917)
			(xy 61.48735 -383.565191) (xy 61.458446 -383.554229) (xy 61.433005 -383.536668) (xy 61.412506 -383.51353)
			(xy 61.39814 -383.486157) (xy 61.390742 -383.456143) (xy 61.390276 -383.440686) (xy 60.445904 -383.440686)
			(xy 60.445438 -383.456143) (xy 60.43804 -383.486157) (xy 60.423674 -383.51353) (xy 60.403175 -383.536668)
			(xy 60.377734 -383.554229) (xy 60.34883 -383.565191) (xy 60.318142 -383.568917) (xy 60.287454 -383.565191)
			(xy 60.25855 -383.554229) (xy 60.233109 -383.536668) (xy 60.21261 -383.51353) (xy 60.198244 -383.486157)
			(xy 60.190846 -383.456143) (xy 60.19038 -383.440686) (xy 59.2455 -383.440686) (xy 59.245035 -383.456112)
			(xy 59.237652 -383.486067) (xy 59.223315 -383.513385) (xy 59.202856 -383.536478) (xy 59.177466 -383.554004)
			(xy 59.148619 -383.564944) (xy 59.117992 -383.568663) (xy 59.087365 -383.564944) (xy 59.058518 -383.554004)
			(xy 59.033128 -383.536478) (xy 59.012669 -383.513385) (xy 58.998332 -383.486067) (xy 58.990949 -383.456112)
			(xy 58.990484 -383.440686) (xy 58.045604 -383.440686) (xy 58.045139 -383.456112) (xy 58.037756 -383.486067)
			(xy 58.023419 -383.513385) (xy 58.00296 -383.536478) (xy 57.97757 -383.554004) (xy 57.948723 -383.564944)
			(xy 57.918096 -383.568663) (xy 57.887469 -383.564944) (xy 57.858622 -383.554004) (xy 57.833232 -383.536478)
			(xy 57.812773 -383.513385) (xy 57.798436 -383.486067) (xy 57.791053 -383.456112) (xy 57.790588 -383.440686)
			(xy 56.845708 -383.440686) (xy 56.845242 -383.456143) (xy 56.837844 -383.486157) (xy 56.823478 -383.51353)
			(xy 56.802979 -383.536668) (xy 56.777538 -383.554229) (xy 56.748634 -383.565191) (xy 56.717946 -383.568917)
			(xy 56.687258 -383.565191) (xy 56.658354 -383.554229) (xy 56.632913 -383.536668) (xy 56.612414 -383.51353)
			(xy 56.598048 -383.486157) (xy 56.59065 -383.456143) (xy 56.590184 -383.440686) (xy 55.645812 -383.440686)
			(xy 55.645346 -383.456143) (xy 55.637948 -383.486157) (xy 55.623582 -383.51353) (xy 55.603083 -383.536668)
			(xy 55.577642 -383.554229) (xy 55.548738 -383.565191) (xy 55.51805 -383.568917) (xy 55.487362 -383.565191)
			(xy 55.458458 -383.554229) (xy 55.433017 -383.536668) (xy 55.412518 -383.51353) (xy 55.398152 -383.486157)
			(xy 55.390754 -383.456143) (xy 55.390288 -383.440686) (xy 54.445916 -383.440686) (xy 54.44545 -383.456143)
			(xy 54.438052 -383.486157) (xy 54.423686 -383.51353) (xy 54.403187 -383.536668) (xy 54.377746 -383.554229)
			(xy 54.348842 -383.565191) (xy 54.318154 -383.568917) (xy 54.287466 -383.565191) (xy 54.258562 -383.554229)
			(xy 54.233121 -383.536668) (xy 54.212622 -383.51353) (xy 54.198256 -383.486157) (xy 54.190858 -383.456143)
			(xy 54.190392 -383.440686) (xy 53.245512 -383.440686) (xy 53.245047 -383.456112) (xy 53.237664 -383.486067)
			(xy 53.223327 -383.513385) (xy 53.202868 -383.536478) (xy 53.177478 -383.554004) (xy 53.148631 -383.564944)
			(xy 53.118004 -383.568663) (xy 53.087377 -383.564944) (xy 53.05853 -383.554004) (xy 53.03314 -383.536478)
			(xy 53.012681 -383.513385) (xy 52.998344 -383.486067) (xy 52.990961 -383.456112) (xy 52.990496 -383.440686)
			(xy 52.045616 -383.440686) (xy 52.045151 -383.456112) (xy 52.037768 -383.486067) (xy 52.023431 -383.513385)
			(xy 52.002972 -383.536478) (xy 51.977582 -383.554004) (xy 51.948735 -383.564944) (xy 51.918108 -383.568663)
			(xy 51.887481 -383.564944) (xy 51.858634 -383.554004) (xy 51.833244 -383.536478) (xy 51.812785 -383.513385)
			(xy 51.798448 -383.486067) (xy 51.791065 -383.456112) (xy 51.7906 -383.440686) (xy 50.84572 -383.440686)
			(xy 50.845254 -383.456143) (xy 50.837856 -383.486157) (xy 50.82349 -383.51353) (xy 50.802991 -383.536668)
			(xy 50.77755 -383.554229) (xy 50.748646 -383.565191) (xy 50.717958 -383.568917) (xy 50.68727 -383.565191)
			(xy 50.658366 -383.554229) (xy 50.632925 -383.536668) (xy 50.612426 -383.51353) (xy 50.59806 -383.486157)
			(xy 50.590662 -383.456143) (xy 50.590196 -383.440686) (xy 49.645824 -383.440686) (xy 49.645358 -383.456143)
			(xy 49.63796 -383.486157) (xy 49.623594 -383.51353) (xy 49.603095 -383.536668) (xy 49.577654 -383.554229)
			(xy 49.54875 -383.565191) (xy 49.518062 -383.568917) (xy 49.487374 -383.565191) (xy 49.45847 -383.554229)
			(xy 49.433029 -383.536668) (xy 49.41253 -383.51353) (xy 49.398164 -383.486157) (xy 49.390766 -383.456143)
			(xy 49.3903 -383.440686) (xy 48.44542 -383.440686) (xy 48.444955 -383.456112) (xy 48.437572 -383.486067)
			(xy 48.423235 -383.513385) (xy 48.402776 -383.536478) (xy 48.377386 -383.554004) (xy 48.348539 -383.564944)
			(xy 48.317912 -383.568663) (xy 48.287285 -383.564944) (xy 48.258438 -383.554004) (xy 48.233048 -383.536478)
			(xy 48.212589 -383.513385) (xy 48.198252 -383.486067) (xy 48.190869 -383.456112) (xy 48.190404 -383.440686)
			(xy 47.245524 -383.440686) (xy 47.245059 -383.456112) (xy 47.237676 -383.486067) (xy 47.223339 -383.513385)
			(xy 47.20288 -383.536478) (xy 47.17749 -383.554004) (xy 47.148643 -383.564944) (xy 47.118016 -383.568663)
			(xy 47.087389 -383.564944) (xy 47.058542 -383.554004) (xy 47.033152 -383.536478) (xy 47.012693 -383.513385)
			(xy 46.998356 -383.486067) (xy 46.990973 -383.456112) (xy 46.990508 -383.440686) (xy 2.509012 -383.440686)
			(xy 2.509012 -383.92227) (xy 47.264307 -383.92227) (xy 47.268449 -383.886828) (xy 47.280653 -383.853297)
			(xy 47.300262 -383.823484) (xy 47.326217 -383.798997) (xy 47.357119 -383.781155) (xy 47.391303 -383.770921)
			(xy 47.426926 -383.768847) (xy 47.462067 -383.775043) (xy 47.494832 -383.789176) (xy 47.523454 -383.810485)
			(xy 47.546391 -383.83782) (xy 47.562405 -383.869707) (xy 47.570634 -383.904428) (xy 47.571152 -383.92227)
			(xy 48.464203 -383.92227) (xy 48.468345 -383.886828) (xy 48.480549 -383.853297) (xy 48.500158 -383.823484)
			(xy 48.526113 -383.798997) (xy 48.557015 -383.781155) (xy 48.591199 -383.770921) (xy 48.626822 -383.768847)
			(xy 48.661963 -383.775043) (xy 48.694728 -383.789176) (xy 48.72335 -383.810485) (xy 48.746287 -383.83782)
			(xy 48.762301 -383.869707) (xy 48.77053 -383.904428) (xy 48.771048 -383.92227) (xy 49.664353 -383.92227)
			(xy 49.668495 -383.886828) (xy 49.680699 -383.853297) (xy 49.700308 -383.823484) (xy 49.726263 -383.798997)
			(xy 49.757165 -383.781155) (xy 49.791349 -383.770921) (xy 49.826972 -383.768847) (xy 49.862113 -383.775043)
			(xy 49.894878 -383.789176) (xy 49.9235 -383.810485) (xy 49.946437 -383.83782) (xy 49.962451 -383.869707)
			(xy 49.97068 -383.904428) (xy 49.971198 -383.92227) (xy 50.864249 -383.92227) (xy 50.868391 -383.886828)
			(xy 50.880595 -383.853297) (xy 50.900204 -383.823484) (xy 50.926159 -383.798997) (xy 50.957061 -383.781155)
			(xy 50.991245 -383.770921) (xy 51.026868 -383.768847) (xy 51.062009 -383.775043) (xy 51.094774 -383.789176)
			(xy 51.123396 -383.810485) (xy 51.146333 -383.83782) (xy 51.162347 -383.869707) (xy 51.170576 -383.904428)
			(xy 51.171094 -383.92227) (xy 52.064399 -383.92227) (xy 52.068541 -383.886828) (xy 52.080745 -383.853297)
			(xy 52.100354 -383.823484) (xy 52.126309 -383.798997) (xy 52.157211 -383.781155) (xy 52.191395 -383.770921)
			(xy 52.227018 -383.768847) (xy 52.262159 -383.775043) (xy 52.294924 -383.789176) (xy 52.323546 -383.810485)
			(xy 52.346483 -383.83782) (xy 52.362497 -383.869707) (xy 52.370726 -383.904428) (xy 52.371244 -383.92227)
			(xy 53.264295 -383.92227) (xy 53.268437 -383.886828) (xy 53.280641 -383.853297) (xy 53.30025 -383.823484)
			(xy 53.326205 -383.798997) (xy 53.357107 -383.781155) (xy 53.391291 -383.770921) (xy 53.426914 -383.768847)
			(xy 53.462055 -383.775043) (xy 53.49482 -383.789176) (xy 53.523442 -383.810485) (xy 53.546379 -383.83782)
			(xy 53.562393 -383.869707) (xy 53.570622 -383.904428) (xy 53.57114 -383.92227) (xy 54.464445 -383.92227)
			(xy 54.468587 -383.886828) (xy 54.480791 -383.853297) (xy 54.5004 -383.823484) (xy 54.526355 -383.798997)
			(xy 54.557257 -383.781155) (xy 54.591441 -383.770921) (xy 54.627064 -383.768847) (xy 54.662205 -383.775043)
			(xy 54.69497 -383.789176) (xy 54.723592 -383.810485) (xy 54.746529 -383.83782) (xy 54.762543 -383.869707)
			(xy 54.770772 -383.904428) (xy 54.77129 -383.92227) (xy 55.664341 -383.92227) (xy 55.668483 -383.886828)
			(xy 55.680687 -383.853297) (xy 55.700296 -383.823484) (xy 55.726251 -383.798997) (xy 55.757153 -383.781155)
			(xy 55.791337 -383.770921) (xy 55.82696 -383.768847) (xy 55.862101 -383.775043) (xy 55.894866 -383.789176)
			(xy 55.923488 -383.810485) (xy 55.946425 -383.83782) (xy 55.962439 -383.869707) (xy 55.970668 -383.904428)
			(xy 55.971186 -383.92227) (xy 56.864237 -383.92227) (xy 56.868379 -383.886828) (xy 56.880583 -383.853297)
			(xy 56.900192 -383.823484) (xy 56.926147 -383.798997) (xy 56.957049 -383.781155) (xy 56.991233 -383.770921)
			(xy 57.026856 -383.768847) (xy 57.061997 -383.775043) (xy 57.094762 -383.789176) (xy 57.123384 -383.810485)
			(xy 57.146321 -383.83782) (xy 57.162335 -383.869707) (xy 57.170564 -383.904428) (xy 57.171082 -383.92227)
			(xy 58.064387 -383.92227) (xy 58.068529 -383.886828) (xy 58.080733 -383.853297) (xy 58.100342 -383.823484)
			(xy 58.126297 -383.798997) (xy 58.157199 -383.781155) (xy 58.191383 -383.770921) (xy 58.227006 -383.768847)
			(xy 58.262147 -383.775043) (xy 58.294912 -383.789176) (xy 58.323534 -383.810485) (xy 58.346471 -383.83782)
			(xy 58.362485 -383.869707) (xy 58.370714 -383.904428) (xy 58.371232 -383.92227) (xy 59.264283 -383.92227)
			(xy 59.268425 -383.886828) (xy 59.280629 -383.853297) (xy 59.300238 -383.823484) (xy 59.326193 -383.798997)
			(xy 59.357095 -383.781155) (xy 59.391279 -383.770921) (xy 59.426902 -383.768847) (xy 59.462043 -383.775043)
			(xy 59.494808 -383.789176) (xy 59.52343 -383.810485) (xy 59.546367 -383.83782) (xy 59.562381 -383.869707)
			(xy 59.57061 -383.904428) (xy 59.571128 -383.92227) (xy 60.464433 -383.92227) (xy 60.468575 -383.886828)
			(xy 60.480779 -383.853297) (xy 60.500388 -383.823484) (xy 60.526343 -383.798997) (xy 60.557245 -383.781155)
			(xy 60.591429 -383.770921) (xy 60.627052 -383.768847) (xy 60.662193 -383.775043) (xy 60.694958 -383.789176)
			(xy 60.72358 -383.810485) (xy 60.746517 -383.83782) (xy 60.762531 -383.869707) (xy 60.77076 -383.904428)
			(xy 60.771278 -383.92227) (xy 61.664329 -383.92227) (xy 61.668471 -383.886828) (xy 61.680675 -383.853297)
			(xy 61.700284 -383.823484) (xy 61.726239 -383.798997) (xy 61.757141 -383.781155) (xy 61.791325 -383.770921)
			(xy 61.826948 -383.768847) (xy 61.862089 -383.775043) (xy 61.894854 -383.789176) (xy 61.923476 -383.810485)
			(xy 61.946413 -383.83782) (xy 61.962427 -383.869707) (xy 61.970656 -383.904428) (xy 61.971174 -383.92227)
			(xy 62.864225 -383.92227) (xy 62.868367 -383.886828) (xy 62.880571 -383.853297) (xy 62.90018 -383.823484)
			(xy 62.926135 -383.798997) (xy 62.957037 -383.781155) (xy 62.991221 -383.770921) (xy 63.026844 -383.768847)
			(xy 63.061985 -383.775043) (xy 63.09475 -383.789176) (xy 63.123372 -383.810485) (xy 63.146309 -383.83782)
			(xy 63.162323 -383.869707) (xy 63.170552 -383.904428) (xy 63.17107 -383.92227) (xy 64.064375 -383.92227)
			(xy 64.068517 -383.886828) (xy 64.080721 -383.853297) (xy 64.10033 -383.823484) (xy 64.126285 -383.798997)
			(xy 64.157187 -383.781155) (xy 64.191371 -383.770921) (xy 64.226994 -383.768847) (xy 64.262135 -383.775043)
			(xy 64.2949 -383.789176) (xy 64.323522 -383.810485) (xy 64.346459 -383.83782) (xy 64.362473 -383.869707)
			(xy 64.370702 -383.904428) (xy 64.37122 -383.92227) (xy 65.264271 -383.92227) (xy 65.268413 -383.886828)
			(xy 65.280617 -383.853297) (xy 65.300226 -383.823484) (xy 65.326181 -383.798997) (xy 65.357083 -383.781155)
			(xy 65.391267 -383.770921) (xy 65.42689 -383.768847) (xy 65.462031 -383.775043) (xy 65.494796 -383.789176)
			(xy 65.523418 -383.810485) (xy 65.546355 -383.83782) (xy 65.562369 -383.869707) (xy 65.570598 -383.904428)
			(xy 65.571116 -383.92227) (xy 79.792055 -383.92227) (xy 79.796197 -383.886828) (xy 79.808401 -383.853297)
			(xy 79.82801 -383.823484) (xy 79.853965 -383.798997) (xy 79.884867 -383.781155) (xy 79.919051 -383.770921)
			(xy 79.954674 -383.768847) (xy 79.989815 -383.775043) (xy 80.02258 -383.789176) (xy 80.051202 -383.810485)
			(xy 80.074139 -383.83782) (xy 80.090153 -383.869707) (xy 80.098382 -383.904428) (xy 80.0989 -383.92227)
			(xy 80.991951 -383.92227) (xy 80.996093 -383.886828) (xy 81.008297 -383.853297) (xy 81.027906 -383.823484)
			(xy 81.053861 -383.798997) (xy 81.084763 -383.781155) (xy 81.118947 -383.770921) (xy 81.15457 -383.768847)
			(xy 81.189711 -383.775043) (xy 81.222476 -383.789176) (xy 81.251098 -383.810485) (xy 81.274035 -383.83782)
			(xy 81.290049 -383.869707) (xy 81.298278 -383.904428) (xy 81.298796 -383.92227) (xy 82.192101 -383.92227)
			(xy 82.196243 -383.886828) (xy 82.208447 -383.853297) (xy 82.228056 -383.823484) (xy 82.254011 -383.798997)
			(xy 82.284913 -383.781155) (xy 82.319097 -383.770921) (xy 82.35472 -383.768847) (xy 82.389861 -383.775043)
			(xy 82.422626 -383.789176) (xy 82.451248 -383.810485) (xy 82.474185 -383.83782) (xy 82.490199 -383.869707)
			(xy 82.498428 -383.904428) (xy 82.498946 -383.92227) (xy 83.391997 -383.92227) (xy 83.396139 -383.886828)
			(xy 83.408343 -383.853297) (xy 83.427952 -383.823484) (xy 83.453907 -383.798997) (xy 83.484809 -383.781155)
			(xy 83.518993 -383.770921) (xy 83.554616 -383.768847) (xy 83.589757 -383.775043) (xy 83.622522 -383.789176)
			(xy 83.651144 -383.810485) (xy 83.674081 -383.83782) (xy 83.690095 -383.869707) (xy 83.698324 -383.904428)
			(xy 83.698842 -383.92227) (xy 84.592147 -383.92227) (xy 84.596289 -383.886828) (xy 84.608493 -383.853297)
			(xy 84.628102 -383.823484) (xy 84.654057 -383.798997) (xy 84.684959 -383.781155) (xy 84.719143 -383.770921)
			(xy 84.754766 -383.768847) (xy 84.789907 -383.775043) (xy 84.822672 -383.789176) (xy 84.851294 -383.810485)
			(xy 84.874231 -383.83782) (xy 84.890245 -383.869707) (xy 84.898474 -383.904428) (xy 84.898992 -383.92227)
			(xy 85.792043 -383.92227) (xy 85.796185 -383.886828) (xy 85.808389 -383.853297) (xy 85.827998 -383.823484)
			(xy 85.853953 -383.798997) (xy 85.884855 -383.781155) (xy 85.919039 -383.770921) (xy 85.954662 -383.768847)
			(xy 85.989803 -383.775043) (xy 86.022568 -383.789176) (xy 86.05119 -383.810485) (xy 86.074127 -383.83782)
			(xy 86.090141 -383.869707) (xy 86.09837 -383.904428) (xy 86.098888 -383.92227) (xy 86.992193 -383.92227)
			(xy 86.996335 -383.886828) (xy 87.008539 -383.853297) (xy 87.028148 -383.823484) (xy 87.054103 -383.798997)
			(xy 87.085005 -383.781155) (xy 87.119189 -383.770921) (xy 87.154812 -383.768847) (xy 87.189953 -383.775043)
			(xy 87.222718 -383.789176) (xy 87.25134 -383.810485) (xy 87.274277 -383.83782) (xy 87.290291 -383.869707)
			(xy 87.29852 -383.904428) (xy 87.299038 -383.92227) (xy 88.192089 -383.92227) (xy 88.196231 -383.886828)
			(xy 88.208435 -383.853297) (xy 88.228044 -383.823484) (xy 88.253999 -383.798997) (xy 88.284901 -383.781155)
			(xy 88.319085 -383.770921) (xy 88.354708 -383.768847) (xy 88.389849 -383.775043) (xy 88.422614 -383.789176)
			(xy 88.451236 -383.810485) (xy 88.474173 -383.83782) (xy 88.490187 -383.869707) (xy 88.498416 -383.904428)
			(xy 88.498934 -383.92227) (xy 89.391985 -383.92227) (xy 89.396127 -383.886828) (xy 89.408331 -383.853297)
			(xy 89.42794 -383.823484) (xy 89.453895 -383.798997) (xy 89.484797 -383.781155) (xy 89.518981 -383.770921)
			(xy 89.554604 -383.768847) (xy 89.589745 -383.775043) (xy 89.62251 -383.789176) (xy 89.651132 -383.810485)
			(xy 89.674069 -383.83782) (xy 89.690083 -383.869707) (xy 89.698312 -383.904428) (xy 89.69883 -383.92227)
			(xy 90.592135 -383.92227) (xy 90.596277 -383.886828) (xy 90.608481 -383.853297) (xy 90.62809 -383.823484)
			(xy 90.654045 -383.798997) (xy 90.684947 -383.781155) (xy 90.719131 -383.770921) (xy 90.754754 -383.768847)
			(xy 90.789895 -383.775043) (xy 90.82266 -383.789176) (xy 90.851282 -383.810485) (xy 90.874219 -383.83782)
			(xy 90.890233 -383.869707) (xy 90.898462 -383.904428) (xy 90.89898 -383.92227) (xy 91.792031 -383.92227)
			(xy 91.796173 -383.886828) (xy 91.808377 -383.853297) (xy 91.827986 -383.823484) (xy 91.853941 -383.798997)
			(xy 91.884843 -383.781155) (xy 91.919027 -383.770921) (xy 91.95465 -383.768847) (xy 91.989791 -383.775043)
			(xy 92.022556 -383.789176) (xy 92.051178 -383.810485) (xy 92.074115 -383.83782) (xy 92.090129 -383.869707)
			(xy 92.098358 -383.904428) (xy 92.098876 -383.92227) (xy 92.992181 -383.92227) (xy 92.996323 -383.886828)
			(xy 93.008527 -383.853297) (xy 93.028136 -383.823484) (xy 93.054091 -383.798997) (xy 93.084993 -383.781155)
			(xy 93.119177 -383.770921) (xy 93.1548 -383.768847) (xy 93.189941 -383.775043) (xy 93.222706 -383.789176)
			(xy 93.251328 -383.810485) (xy 93.274265 -383.83782) (xy 93.290279 -383.869707) (xy 93.298508 -383.904428)
			(xy 93.299026 -383.92227) (xy 94.192077 -383.92227) (xy 94.196219 -383.886828) (xy 94.208423 -383.853297)
			(xy 94.228032 -383.823484) (xy 94.253987 -383.798997) (xy 94.284889 -383.781155) (xy 94.319073 -383.770921)
			(xy 94.354696 -383.768847) (xy 94.389837 -383.775043) (xy 94.422602 -383.789176) (xy 94.451224 -383.810485)
			(xy 94.474161 -383.83782) (xy 94.490175 -383.869707) (xy 94.498404 -383.904428) (xy 94.498922 -383.92227)
			(xy 95.391973 -383.92227) (xy 95.396115 -383.886828) (xy 95.408319 -383.853297) (xy 95.427928 -383.823484)
			(xy 95.453883 -383.798997) (xy 95.484785 -383.781155) (xy 95.518969 -383.770921) (xy 95.554592 -383.768847)
			(xy 95.589733 -383.775043) (xy 95.622498 -383.789176) (xy 95.65112 -383.810485) (xy 95.674057 -383.83782)
			(xy 95.690071 -383.869707) (xy 95.6983 -383.904428) (xy 95.698818 -383.92227) (xy 96.592123 -383.92227)
			(xy 96.596265 -383.886828) (xy 96.608469 -383.853297) (xy 96.628078 -383.823484) (xy 96.654033 -383.798997)
			(xy 96.684935 -383.781155) (xy 96.719119 -383.770921) (xy 96.754742 -383.768847) (xy 96.789883 -383.775043)
			(xy 96.822648 -383.789176) (xy 96.85127 -383.810485) (xy 96.874207 -383.83782) (xy 96.890221 -383.869707)
			(xy 96.89845 -383.904428) (xy 96.898968 -383.92227) (xy 97.792019 -383.92227) (xy 97.796161 -383.886828)
			(xy 97.808365 -383.853297) (xy 97.827974 -383.823484) (xy 97.853929 -383.798997) (xy 97.884831 -383.781155)
			(xy 97.919015 -383.770921) (xy 97.954638 -383.768847) (xy 97.989779 -383.775043) (xy 98.022544 -383.789176)
			(xy 98.051166 -383.810485) (xy 98.074103 -383.83782) (xy 98.090117 -383.869707) (xy 98.098346 -383.904428)
			(xy 98.098864 -383.92227) (xy 114.364249 -383.92227) (xy 114.368391 -383.886828) (xy 114.380595 -383.853297)
			(xy 114.400204 -383.823484) (xy 114.426159 -383.798997) (xy 114.457061 -383.781155) (xy 114.491245 -383.770921)
			(xy 114.526868 -383.768847) (xy 114.562009 -383.775043) (xy 114.594774 -383.789176) (xy 114.623396 -383.810485)
			(xy 114.646333 -383.83782) (xy 114.662347 -383.869707) (xy 114.670576 -383.904428) (xy 114.671094 -383.92227)
			(xy 115.564145 -383.92227) (xy 115.568287 -383.886828) (xy 115.580491 -383.853297) (xy 115.6001 -383.823484)
			(xy 115.626055 -383.798997) (xy 115.656957 -383.781155) (xy 115.691141 -383.770921) (xy 115.726764 -383.768847)
			(xy 115.761905 -383.775043) (xy 115.79467 -383.789176) (xy 115.823292 -383.810485) (xy 115.846229 -383.83782)
			(xy 115.862243 -383.869707) (xy 115.870472 -383.904428) (xy 115.87099 -383.92227) (xy 116.764295 -383.92227)
			(xy 116.768437 -383.886828) (xy 116.780641 -383.853297) (xy 116.80025 -383.823484) (xy 116.826205 -383.798997)
			(xy 116.857107 -383.781155) (xy 116.891291 -383.770921) (xy 116.926914 -383.768847) (xy 116.962055 -383.775043)
			(xy 116.99482 -383.789176) (xy 117.023442 -383.810485) (xy 117.046379 -383.83782) (xy 117.062393 -383.869707)
			(xy 117.070622 -383.904428) (xy 117.07114 -383.92227) (xy 117.964191 -383.92227) (xy 117.968333 -383.886828)
			(xy 117.980537 -383.853297) (xy 118.000146 -383.823484) (xy 118.026101 -383.798997) (xy 118.057003 -383.781155)
			(xy 118.091187 -383.770921) (xy 118.12681 -383.768847) (xy 118.161951 -383.775043) (xy 118.194716 -383.789176)
			(xy 118.223338 -383.810485) (xy 118.246275 -383.83782) (xy 118.262289 -383.869707) (xy 118.270518 -383.904428)
			(xy 118.271036 -383.92227) (xy 119.164341 -383.92227) (xy 119.168483 -383.886828) (xy 119.180687 -383.853297)
			(xy 119.200296 -383.823484) (xy 119.226251 -383.798997) (xy 119.257153 -383.781155) (xy 119.291337 -383.770921)
			(xy 119.32696 -383.768847) (xy 119.362101 -383.775043) (xy 119.394866 -383.789176) (xy 119.423488 -383.810485)
			(xy 119.446425 -383.83782) (xy 119.462439 -383.869707) (xy 119.470668 -383.904428) (xy 119.471186 -383.92227)
			(xy 120.364237 -383.92227) (xy 120.368379 -383.886828) (xy 120.380583 -383.853297) (xy 120.400192 -383.823484)
			(xy 120.426147 -383.798997) (xy 120.457049 -383.781155) (xy 120.491233 -383.770921) (xy 120.526856 -383.768847)
			(xy 120.561997 -383.775043) (xy 120.594762 -383.789176) (xy 120.623384 -383.810485) (xy 120.646321 -383.83782)
			(xy 120.662335 -383.869707) (xy 120.670564 -383.904428) (xy 120.671082 -383.92227) (xy 121.564387 -383.92227)
			(xy 121.568529 -383.886828) (xy 121.580733 -383.853297) (xy 121.600342 -383.823484) (xy 121.626297 -383.798997)
			(xy 121.657199 -383.781155) (xy 121.691383 -383.770921) (xy 121.727006 -383.768847) (xy 121.762147 -383.775043)
			(xy 121.794912 -383.789176) (xy 121.823534 -383.810485) (xy 121.846471 -383.83782) (xy 121.862485 -383.869707)
			(xy 121.870714 -383.904428) (xy 121.871232 -383.92227) (xy 122.764283 -383.92227) (xy 122.768425 -383.886828)
			(xy 122.780629 -383.853297) (xy 122.800238 -383.823484) (xy 122.826193 -383.798997) (xy 122.857095 -383.781155)
			(xy 122.891279 -383.770921) (xy 122.926902 -383.768847) (xy 122.962043 -383.775043) (xy 122.994808 -383.789176)
			(xy 123.02343 -383.810485) (xy 123.046367 -383.83782) (xy 123.062381 -383.869707) (xy 123.07061 -383.904428)
			(xy 123.071128 -383.92227) (xy 123.964179 -383.92227) (xy 123.968321 -383.886828) (xy 123.980525 -383.853297)
			(xy 124.000134 -383.823484) (xy 124.026089 -383.798997) (xy 124.056991 -383.781155) (xy 124.091175 -383.770921)
			(xy 124.126798 -383.768847) (xy 124.161939 -383.775043) (xy 124.194704 -383.789176) (xy 124.223326 -383.810485)
			(xy 124.246263 -383.83782) (xy 124.262277 -383.869707) (xy 124.270506 -383.904428) (xy 124.271024 -383.92227)
			(xy 125.164329 -383.92227) (xy 125.168471 -383.886828) (xy 125.180675 -383.853297) (xy 125.200284 -383.823484)
			(xy 125.226239 -383.798997) (xy 125.257141 -383.781155) (xy 125.291325 -383.770921) (xy 125.326948 -383.768847)
			(xy 125.362089 -383.775043) (xy 125.394854 -383.789176) (xy 125.423476 -383.810485) (xy 125.446413 -383.83782)
			(xy 125.462427 -383.869707) (xy 125.470656 -383.904428) (xy 125.471174 -383.92227) (xy 126.364225 -383.92227)
			(xy 126.368367 -383.886828) (xy 126.380571 -383.853297) (xy 126.40018 -383.823484) (xy 126.426135 -383.798997)
			(xy 126.457037 -383.781155) (xy 126.491221 -383.770921) (xy 126.526844 -383.768847) (xy 126.561985 -383.775043)
			(xy 126.59475 -383.789176) (xy 126.623372 -383.810485) (xy 126.646309 -383.83782) (xy 126.662323 -383.869707)
			(xy 126.670552 -383.904428) (xy 126.67107 -383.92227) (xy 127.564375 -383.92227) (xy 127.568517 -383.886828)
			(xy 127.580721 -383.853297) (xy 127.60033 -383.823484) (xy 127.626285 -383.798997) (xy 127.657187 -383.781155)
			(xy 127.691371 -383.770921) (xy 127.726994 -383.768847) (xy 127.762135 -383.775043) (xy 127.7949 -383.789176)
			(xy 127.823522 -383.810485) (xy 127.846459 -383.83782) (xy 127.862473 -383.869707) (xy 127.870702 -383.904428)
			(xy 127.87122 -383.92227) (xy 128.764271 -383.92227) (xy 128.768413 -383.886828) (xy 128.780617 -383.853297)
			(xy 128.800226 -383.823484) (xy 128.826181 -383.798997) (xy 128.857083 -383.781155) (xy 128.891267 -383.770921)
			(xy 128.92689 -383.768847) (xy 128.962031 -383.775043) (xy 128.994796 -383.789176) (xy 129.023418 -383.810485)
			(xy 129.046355 -383.83782) (xy 129.062369 -383.869707) (xy 129.070598 -383.904428) (xy 129.071116 -383.92227)
			(xy 129.964167 -383.92227) (xy 129.968309 -383.886828) (xy 129.980513 -383.853297) (xy 130.000122 -383.823484)
			(xy 130.026077 -383.798997) (xy 130.056979 -383.781155) (xy 130.091163 -383.770921) (xy 130.126786 -383.768847)
			(xy 130.161927 -383.775043) (xy 130.194692 -383.789176) (xy 130.223314 -383.810485) (xy 130.246251 -383.83782)
			(xy 130.262265 -383.869707) (xy 130.270494 -383.904428) (xy 130.271012 -383.92227) (xy 131.164317 -383.92227)
			(xy 131.168459 -383.886828) (xy 131.180663 -383.853297) (xy 131.200272 -383.823484) (xy 131.226227 -383.798997)
			(xy 131.257129 -383.781155) (xy 131.291313 -383.770921) (xy 131.326936 -383.768847) (xy 131.362077 -383.775043)
			(xy 131.394842 -383.789176) (xy 131.423464 -383.810485) (xy 131.446401 -383.83782) (xy 131.462415 -383.869707)
			(xy 131.470644 -383.904428) (xy 131.471162 -383.92227) (xy 132.364213 -383.92227) (xy 132.368355 -383.886828)
			(xy 132.380559 -383.853297) (xy 132.400168 -383.823484) (xy 132.426123 -383.798997) (xy 132.457025 -383.781155)
			(xy 132.491209 -383.770921) (xy 132.526832 -383.768847) (xy 132.561973 -383.775043) (xy 132.594738 -383.789176)
			(xy 132.62336 -383.810485) (xy 132.646297 -383.83782) (xy 132.662311 -383.869707) (xy 132.67054 -383.904428)
			(xy 132.671058 -383.92227) (xy 146.891997 -383.92227) (xy 146.896139 -383.886828) (xy 146.908343 -383.853297)
			(xy 146.927952 -383.823484) (xy 146.953907 -383.798997) (xy 146.984809 -383.781155) (xy 147.018993 -383.770921)
			(xy 147.054616 -383.768847) (xy 147.089757 -383.775043) (xy 147.122522 -383.789176) (xy 147.151144 -383.810485)
			(xy 147.174081 -383.83782) (xy 147.190095 -383.869707) (xy 147.198324 -383.904428) (xy 147.198842 -383.92227)
			(xy 148.091893 -383.92227) (xy 148.096035 -383.886828) (xy 148.108239 -383.853297) (xy 148.127848 -383.823484)
			(xy 148.153803 -383.798997) (xy 148.184705 -383.781155) (xy 148.218889 -383.770921) (xy 148.254512 -383.768847)
			(xy 148.289653 -383.775043) (xy 148.322418 -383.789176) (xy 148.35104 -383.810485) (xy 148.373977 -383.83782)
			(xy 148.389991 -383.869707) (xy 148.39822 -383.904428) (xy 148.398738 -383.92227) (xy 149.292043 -383.92227)
			(xy 149.296185 -383.886828) (xy 149.308389 -383.853297) (xy 149.327998 -383.823484) (xy 149.353953 -383.798997)
			(xy 149.384855 -383.781155) (xy 149.419039 -383.770921) (xy 149.454662 -383.768847) (xy 149.489803 -383.775043)
			(xy 149.522568 -383.789176) (xy 149.55119 -383.810485) (xy 149.574127 -383.83782) (xy 149.590141 -383.869707)
			(xy 149.59837 -383.904428) (xy 149.598888 -383.92227) (xy 150.491939 -383.92227) (xy 150.496081 -383.886828)
			(xy 150.508285 -383.853297) (xy 150.527894 -383.823484) (xy 150.553849 -383.798997) (xy 150.584751 -383.781155)
			(xy 150.618935 -383.770921) (xy 150.654558 -383.768847) (xy 150.689699 -383.775043) (xy 150.722464 -383.789176)
			(xy 150.751086 -383.810485) (xy 150.774023 -383.83782) (xy 150.790037 -383.869707) (xy 150.798266 -383.904428)
			(xy 150.798784 -383.92227) (xy 151.692089 -383.92227) (xy 151.696231 -383.886828) (xy 151.708435 -383.853297)
			(xy 151.728044 -383.823484) (xy 151.753999 -383.798997) (xy 151.784901 -383.781155) (xy 151.819085 -383.770921)
			(xy 151.854708 -383.768847) (xy 151.889849 -383.775043) (xy 151.922614 -383.789176) (xy 151.951236 -383.810485)
			(xy 151.974173 -383.83782) (xy 151.990187 -383.869707) (xy 151.998416 -383.904428) (xy 151.998934 -383.92227)
			(xy 152.891985 -383.92227) (xy 152.896127 -383.886828) (xy 152.908331 -383.853297) (xy 152.92794 -383.823484)
			(xy 152.953895 -383.798997) (xy 152.984797 -383.781155) (xy 153.018981 -383.770921) (xy 153.054604 -383.768847)
			(xy 153.089745 -383.775043) (xy 153.12251 -383.789176) (xy 153.151132 -383.810485) (xy 153.174069 -383.83782)
			(xy 153.190083 -383.869707) (xy 153.198312 -383.904428) (xy 153.19883 -383.92227) (xy 154.092135 -383.92227)
			(xy 154.096277 -383.886828) (xy 154.108481 -383.853297) (xy 154.12809 -383.823484) (xy 154.154045 -383.798997)
			(xy 154.184947 -383.781155) (xy 154.219131 -383.770921) (xy 154.254754 -383.768847) (xy 154.289895 -383.775043)
			(xy 154.32266 -383.789176) (xy 154.351282 -383.810485) (xy 154.374219 -383.83782) (xy 154.390233 -383.869707)
			(xy 154.398462 -383.904428) (xy 154.39898 -383.92227) (xy 155.292031 -383.92227) (xy 155.296173 -383.886828)
			(xy 155.308377 -383.853297) (xy 155.327986 -383.823484) (xy 155.353941 -383.798997) (xy 155.384843 -383.781155)
			(xy 155.419027 -383.770921) (xy 155.45465 -383.768847) (xy 155.489791 -383.775043) (xy 155.522556 -383.789176)
			(xy 155.551178 -383.810485) (xy 155.574115 -383.83782) (xy 155.590129 -383.869707) (xy 155.598358 -383.904428)
			(xy 155.598876 -383.92227) (xy 156.491927 -383.92227) (xy 156.496069 -383.886828) (xy 156.508273 -383.853297)
			(xy 156.527882 -383.823484) (xy 156.553837 -383.798997) (xy 156.584739 -383.781155) (xy 156.618923 -383.770921)
			(xy 156.654546 -383.768847) (xy 156.689687 -383.775043) (xy 156.722452 -383.789176) (xy 156.751074 -383.810485)
			(xy 156.774011 -383.83782) (xy 156.790025 -383.869707) (xy 156.798254 -383.904428) (xy 156.798772 -383.92227)
			(xy 157.692077 -383.92227) (xy 157.696219 -383.886828) (xy 157.708423 -383.853297) (xy 157.728032 -383.823484)
			(xy 157.753987 -383.798997) (xy 157.784889 -383.781155) (xy 157.819073 -383.770921) (xy 157.854696 -383.768847)
			(xy 157.889837 -383.775043) (xy 157.922602 -383.789176) (xy 157.951224 -383.810485) (xy 157.974161 -383.83782)
			(xy 157.990175 -383.869707) (xy 157.998404 -383.904428) (xy 157.998922 -383.92227) (xy 158.891973 -383.92227)
			(xy 158.896115 -383.886828) (xy 158.908319 -383.853297) (xy 158.927928 -383.823484) (xy 158.953883 -383.798997)
			(xy 158.984785 -383.781155) (xy 159.018969 -383.770921) (xy 159.054592 -383.768847) (xy 159.089733 -383.775043)
			(xy 159.122498 -383.789176) (xy 159.15112 -383.810485) (xy 159.174057 -383.83782) (xy 159.190071 -383.869707)
			(xy 159.1983 -383.904428) (xy 159.198818 -383.92227) (xy 160.092123 -383.92227) (xy 160.096265 -383.886828)
			(xy 160.108469 -383.853297) (xy 160.128078 -383.823484) (xy 160.154033 -383.798997) (xy 160.184935 -383.781155)
			(xy 160.219119 -383.770921) (xy 160.254742 -383.768847) (xy 160.289883 -383.775043) (xy 160.322648 -383.789176)
			(xy 160.35127 -383.810485) (xy 160.374207 -383.83782) (xy 160.390221 -383.869707) (xy 160.39845 -383.904428)
			(xy 160.398968 -383.92227) (xy 161.292019 -383.92227) (xy 161.296161 -383.886828) (xy 161.308365 -383.853297)
			(xy 161.327974 -383.823484) (xy 161.353929 -383.798997) (xy 161.384831 -383.781155) (xy 161.419015 -383.770921)
			(xy 161.454638 -383.768847) (xy 161.489779 -383.775043) (xy 161.522544 -383.789176) (xy 161.551166 -383.810485)
			(xy 161.574103 -383.83782) (xy 161.590117 -383.869707) (xy 161.598346 -383.904428) (xy 161.598864 -383.92227)
			(xy 162.491915 -383.92227) (xy 162.496057 -383.886828) (xy 162.508261 -383.853297) (xy 162.52787 -383.823484)
			(xy 162.553825 -383.798997) (xy 162.584727 -383.781155) (xy 162.618911 -383.770921) (xy 162.654534 -383.768847)
			(xy 162.689675 -383.775043) (xy 162.72244 -383.789176) (xy 162.751062 -383.810485) (xy 162.773999 -383.83782)
			(xy 162.790013 -383.869707) (xy 162.798242 -383.904428) (xy 162.79876 -383.92227) (xy 163.692065 -383.92227)
			(xy 163.696207 -383.886828) (xy 163.708411 -383.853297) (xy 163.72802 -383.823484) (xy 163.753975 -383.798997)
			(xy 163.784877 -383.781155) (xy 163.819061 -383.770921) (xy 163.854684 -383.768847) (xy 163.889825 -383.775043)
			(xy 163.92259 -383.789176) (xy 163.951212 -383.810485) (xy 163.974149 -383.83782) (xy 163.990163 -383.869707)
			(xy 163.998392 -383.904428) (xy 163.99891 -383.92227) (xy 164.891961 -383.92227) (xy 164.896103 -383.886828)
			(xy 164.908307 -383.853297) (xy 164.927916 -383.823484) (xy 164.953871 -383.798997) (xy 164.984773 -383.781155)
			(xy 165.018957 -383.770921) (xy 165.05458 -383.768847) (xy 165.089721 -383.775043) (xy 165.122486 -383.789176)
			(xy 165.151108 -383.810485) (xy 165.174045 -383.83782) (xy 165.190059 -383.869707) (xy 165.198288 -383.904428)
			(xy 165.198806 -383.92227) (xy 165.198288 -383.940112) (xy 165.190059 -383.974833) (xy 165.174045 -384.00672)
			(xy 165.151108 -384.034055) (xy 165.122486 -384.055364) (xy 165.089721 -384.069497) (xy 165.05458 -384.075693)
			(xy 165.018957 -384.073619) (xy 164.984773 -384.063385) (xy 164.953871 -384.045543) (xy 164.927916 -384.021056)
			(xy 164.908307 -383.991243) (xy 164.896103 -383.957712) (xy 164.891961 -383.92227) (xy 163.99891 -383.92227)
			(xy 163.998392 -383.940112) (xy 163.990163 -383.974833) (xy 163.974149 -384.00672) (xy 163.951212 -384.034055)
			(xy 163.92259 -384.055364) (xy 163.889825 -384.069497) (xy 163.854684 -384.075693) (xy 163.819061 -384.073619)
			(xy 163.784877 -384.063385) (xy 163.753975 -384.045543) (xy 163.72802 -384.021056) (xy 163.708411 -383.991243)
			(xy 163.696207 -383.957712) (xy 163.692065 -383.92227) (xy 162.79876 -383.92227) (xy 162.798242 -383.940112)
			(xy 162.790013 -383.974833) (xy 162.773999 -384.00672) (xy 162.751062 -384.034055) (xy 162.72244 -384.055364)
			(xy 162.689675 -384.069497) (xy 162.654534 -384.075693) (xy 162.618911 -384.073619) (xy 162.584727 -384.063385)
			(xy 162.553825 -384.045543) (xy 162.52787 -384.021056) (xy 162.508261 -383.991243) (xy 162.496057 -383.957712)
			(xy 162.491915 -383.92227) (xy 161.598864 -383.92227) (xy 161.598346 -383.940112) (xy 161.590117 -383.974833)
			(xy 161.574103 -384.00672) (xy 161.551166 -384.034055) (xy 161.522544 -384.055364) (xy 161.489779 -384.069497)
			(xy 161.454638 -384.075693) (xy 161.419015 -384.073619) (xy 161.384831 -384.063385) (xy 161.353929 -384.045543)
			(xy 161.327974 -384.021056) (xy 161.308365 -383.991243) (xy 161.296161 -383.957712) (xy 161.292019 -383.92227)
			(xy 160.398968 -383.92227) (xy 160.39845 -383.940112) (xy 160.390221 -383.974833) (xy 160.374207 -384.00672)
			(xy 160.35127 -384.034055) (xy 160.322648 -384.055364) (xy 160.289883 -384.069497) (xy 160.254742 -384.075693)
			(xy 160.219119 -384.073619) (xy 160.184935 -384.063385) (xy 160.154033 -384.045543) (xy 160.128078 -384.021056)
			(xy 160.108469 -383.991243) (xy 160.096265 -383.957712) (xy 160.092123 -383.92227) (xy 159.198818 -383.92227)
			(xy 159.1983 -383.940112) (xy 159.190071 -383.974833) (xy 159.174057 -384.00672) (xy 159.15112 -384.034055)
			(xy 159.122498 -384.055364) (xy 159.089733 -384.069497) (xy 159.054592 -384.075693) (xy 159.018969 -384.073619)
			(xy 158.984785 -384.063385) (xy 158.953883 -384.045543) (xy 158.927928 -384.021056) (xy 158.908319 -383.991243)
			(xy 158.896115 -383.957712) (xy 158.891973 -383.92227) (xy 157.998922 -383.92227) (xy 157.998404 -383.940112)
			(xy 157.990175 -383.974833) (xy 157.974161 -384.00672) (xy 157.951224 -384.034055) (xy 157.922602 -384.055364)
			(xy 157.889837 -384.069497) (xy 157.854696 -384.075693) (xy 157.819073 -384.073619) (xy 157.784889 -384.063385)
			(xy 157.753987 -384.045543) (xy 157.728032 -384.021056) (xy 157.708423 -383.991243) (xy 157.696219 -383.957712)
			(xy 157.692077 -383.92227) (xy 156.798772 -383.92227) (xy 156.798254 -383.940112) (xy 156.790025 -383.974833)
			(xy 156.774011 -384.00672) (xy 156.751074 -384.034055) (xy 156.722452 -384.055364) (xy 156.689687 -384.069497)
			(xy 156.654546 -384.075693) (xy 156.618923 -384.073619) (xy 156.584739 -384.063385) (xy 156.553837 -384.045543)
			(xy 156.527882 -384.021056) (xy 156.508273 -383.991243) (xy 156.496069 -383.957712) (xy 156.491927 -383.92227)
			(xy 155.598876 -383.92227) (xy 155.598358 -383.940112) (xy 155.590129 -383.974833) (xy 155.574115 -384.00672)
			(xy 155.551178 -384.034055) (xy 155.522556 -384.055364) (xy 155.489791 -384.069497) (xy 155.45465 -384.075693)
			(xy 155.419027 -384.073619) (xy 155.384843 -384.063385) (xy 155.353941 -384.045543) (xy 155.327986 -384.021056)
			(xy 155.308377 -383.991243) (xy 155.296173 -383.957712) (xy 155.292031 -383.92227) (xy 154.39898 -383.92227)
			(xy 154.398462 -383.940112) (xy 154.390233 -383.974833) (xy 154.374219 -384.00672) (xy 154.351282 -384.034055)
			(xy 154.32266 -384.055364) (xy 154.289895 -384.069497) (xy 154.254754 -384.075693) (xy 154.219131 -384.073619)
			(xy 154.184947 -384.063385) (xy 154.154045 -384.045543) (xy 154.12809 -384.021056) (xy 154.108481 -383.991243)
			(xy 154.096277 -383.957712) (xy 154.092135 -383.92227) (xy 153.19883 -383.92227) (xy 153.198312 -383.940112)
			(xy 153.190083 -383.974833) (xy 153.174069 -384.00672) (xy 153.151132 -384.034055) (xy 153.12251 -384.055364)
			(xy 153.089745 -384.069497) (xy 153.054604 -384.075693) (xy 153.018981 -384.073619) (xy 152.984797 -384.063385)
			(xy 152.953895 -384.045543) (xy 152.92794 -384.021056) (xy 152.908331 -383.991243) (xy 152.896127 -383.957712)
			(xy 152.891985 -383.92227) (xy 151.998934 -383.92227) (xy 151.998416 -383.940112) (xy 151.990187 -383.974833)
			(xy 151.974173 -384.00672) (xy 151.951236 -384.034055) (xy 151.922614 -384.055364) (xy 151.889849 -384.069497)
			(xy 151.854708 -384.075693) (xy 151.819085 -384.073619) (xy 151.784901 -384.063385) (xy 151.753999 -384.045543)
			(xy 151.728044 -384.021056) (xy 151.708435 -383.991243) (xy 151.696231 -383.957712) (xy 151.692089 -383.92227)
			(xy 150.798784 -383.92227) (xy 150.798266 -383.940112) (xy 150.790037 -383.974833) (xy 150.774023 -384.00672)
			(xy 150.751086 -384.034055) (xy 150.722464 -384.055364) (xy 150.689699 -384.069497) (xy 150.654558 -384.075693)
			(xy 150.618935 -384.073619) (xy 150.584751 -384.063385) (xy 150.553849 -384.045543) (xy 150.527894 -384.021056)
			(xy 150.508285 -383.991243) (xy 150.496081 -383.957712) (xy 150.491939 -383.92227) (xy 149.598888 -383.92227)
			(xy 149.59837 -383.940112) (xy 149.590141 -383.974833) (xy 149.574127 -384.00672) (xy 149.55119 -384.034055)
			(xy 149.522568 -384.055364) (xy 149.489803 -384.069497) (xy 149.454662 -384.075693) (xy 149.419039 -384.073619)
			(xy 149.384855 -384.063385) (xy 149.353953 -384.045543) (xy 149.327998 -384.021056) (xy 149.308389 -383.991243)
			(xy 149.296185 -383.957712) (xy 149.292043 -383.92227) (xy 148.398738 -383.92227) (xy 148.39822 -383.940112)
			(xy 148.389991 -383.974833) (xy 148.373977 -384.00672) (xy 148.35104 -384.034055) (xy 148.322418 -384.055364)
			(xy 148.289653 -384.069497) (xy 148.254512 -384.075693) (xy 148.218889 -384.073619) (xy 148.184705 -384.063385)
			(xy 148.153803 -384.045543) (xy 148.127848 -384.021056) (xy 148.108239 -383.991243) (xy 148.096035 -383.957712)
			(xy 148.091893 -383.92227) (xy 147.198842 -383.92227) (xy 147.198324 -383.940112) (xy 147.190095 -383.974833)
			(xy 147.174081 -384.00672) (xy 147.151144 -384.034055) (xy 147.122522 -384.055364) (xy 147.089757 -384.069497)
			(xy 147.054616 -384.075693) (xy 147.018993 -384.073619) (xy 146.984809 -384.063385) (xy 146.953907 -384.045543)
			(xy 146.927952 -384.021056) (xy 146.908343 -383.991243) (xy 146.896139 -383.957712) (xy 146.891997 -383.92227)
			(xy 132.671058 -383.92227) (xy 132.67054 -383.940112) (xy 132.662311 -383.974833) (xy 132.646297 -384.00672)
			(xy 132.62336 -384.034055) (xy 132.594738 -384.055364) (xy 132.561973 -384.069497) (xy 132.526832 -384.075693)
			(xy 132.491209 -384.073619) (xy 132.457025 -384.063385) (xy 132.426123 -384.045543) (xy 132.400168 -384.021056)
			(xy 132.380559 -383.991243) (xy 132.368355 -383.957712) (xy 132.364213 -383.92227) (xy 131.471162 -383.92227)
			(xy 131.470644 -383.940112) (xy 131.462415 -383.974833) (xy 131.446401 -384.00672) (xy 131.423464 -384.034055)
			(xy 131.394842 -384.055364) (xy 131.362077 -384.069497) (xy 131.326936 -384.075693) (xy 131.291313 -384.073619)
			(xy 131.257129 -384.063385) (xy 131.226227 -384.045543) (xy 131.200272 -384.021056) (xy 131.180663 -383.991243)
			(xy 131.168459 -383.957712) (xy 131.164317 -383.92227) (xy 130.271012 -383.92227) (xy 130.270494 -383.940112)
			(xy 130.262265 -383.974833) (xy 130.246251 -384.00672) (xy 130.223314 -384.034055) (xy 130.194692 -384.055364)
			(xy 130.161927 -384.069497) (xy 130.126786 -384.075693) (xy 130.091163 -384.073619) (xy 130.056979 -384.063385)
			(xy 130.026077 -384.045543) (xy 130.000122 -384.021056) (xy 129.980513 -383.991243) (xy 129.968309 -383.957712)
			(xy 129.964167 -383.92227) (xy 129.071116 -383.92227) (xy 129.070598 -383.940112) (xy 129.062369 -383.974833)
			(xy 129.046355 -384.00672) (xy 129.023418 -384.034055) (xy 128.994796 -384.055364) (xy 128.962031 -384.069497)
			(xy 128.92689 -384.075693) (xy 128.891267 -384.073619) (xy 128.857083 -384.063385) (xy 128.826181 -384.045543)
			(xy 128.800226 -384.021056) (xy 128.780617 -383.991243) (xy 128.768413 -383.957712) (xy 128.764271 -383.92227)
			(xy 127.87122 -383.92227) (xy 127.870702 -383.940112) (xy 127.862473 -383.974833) (xy 127.846459 -384.00672)
			(xy 127.823522 -384.034055) (xy 127.7949 -384.055364) (xy 127.762135 -384.069497) (xy 127.726994 -384.075693)
			(xy 127.691371 -384.073619) (xy 127.657187 -384.063385) (xy 127.626285 -384.045543) (xy 127.60033 -384.021056)
			(xy 127.580721 -383.991243) (xy 127.568517 -383.957712) (xy 127.564375 -383.92227) (xy 126.67107 -383.92227)
			(xy 126.670552 -383.940112) (xy 126.662323 -383.974833) (xy 126.646309 -384.00672) (xy 126.623372 -384.034055)
			(xy 126.59475 -384.055364) (xy 126.561985 -384.069497) (xy 126.526844 -384.075693) (xy 126.491221 -384.073619)
			(xy 126.457037 -384.063385) (xy 126.426135 -384.045543) (xy 126.40018 -384.021056) (xy 126.380571 -383.991243)
			(xy 126.368367 -383.957712) (xy 126.364225 -383.92227) (xy 125.471174 -383.92227) (xy 125.470656 -383.940112)
			(xy 125.462427 -383.974833) (xy 125.446413 -384.00672) (xy 125.423476 -384.034055) (xy 125.394854 -384.055364)
			(xy 125.362089 -384.069497) (xy 125.326948 -384.075693) (xy 125.291325 -384.073619) (xy 125.257141 -384.063385)
			(xy 125.226239 -384.045543) (xy 125.200284 -384.021056) (xy 125.180675 -383.991243) (xy 125.168471 -383.957712)
			(xy 125.164329 -383.92227) (xy 124.271024 -383.92227) (xy 124.270506 -383.940112) (xy 124.262277 -383.974833)
			(xy 124.246263 -384.00672) (xy 124.223326 -384.034055) (xy 124.194704 -384.055364) (xy 124.161939 -384.069497)
			(xy 124.126798 -384.075693) (xy 124.091175 -384.073619) (xy 124.056991 -384.063385) (xy 124.026089 -384.045543)
			(xy 124.000134 -384.021056) (xy 123.980525 -383.991243) (xy 123.968321 -383.957712) (xy 123.964179 -383.92227)
			(xy 123.071128 -383.92227) (xy 123.07061 -383.940112) (xy 123.062381 -383.974833) (xy 123.046367 -384.00672)
			(xy 123.02343 -384.034055) (xy 122.994808 -384.055364) (xy 122.962043 -384.069497) (xy 122.926902 -384.075693)
			(xy 122.891279 -384.073619) (xy 122.857095 -384.063385) (xy 122.826193 -384.045543) (xy 122.800238 -384.021056)
			(xy 122.780629 -383.991243) (xy 122.768425 -383.957712) (xy 122.764283 -383.92227) (xy 121.871232 -383.92227)
			(xy 121.870714 -383.940112) (xy 121.862485 -383.974833) (xy 121.846471 -384.00672) (xy 121.823534 -384.034055)
			(xy 121.794912 -384.055364) (xy 121.762147 -384.069497) (xy 121.727006 -384.075693) (xy 121.691383 -384.073619)
			(xy 121.657199 -384.063385) (xy 121.626297 -384.045543) (xy 121.600342 -384.021056) (xy 121.580733 -383.991243)
			(xy 121.568529 -383.957712) (xy 121.564387 -383.92227) (xy 120.671082 -383.92227) (xy 120.670564 -383.940112)
			(xy 120.662335 -383.974833) (xy 120.646321 -384.00672) (xy 120.623384 -384.034055) (xy 120.594762 -384.055364)
			(xy 120.561997 -384.069497) (xy 120.526856 -384.075693) (xy 120.491233 -384.073619) (xy 120.457049 -384.063385)
			(xy 120.426147 -384.045543) (xy 120.400192 -384.021056) (xy 120.380583 -383.991243) (xy 120.368379 -383.957712)
			(xy 120.364237 -383.92227) (xy 119.471186 -383.92227) (xy 119.470668 -383.940112) (xy 119.462439 -383.974833)
			(xy 119.446425 -384.00672) (xy 119.423488 -384.034055) (xy 119.394866 -384.055364) (xy 119.362101 -384.069497)
			(xy 119.32696 -384.075693) (xy 119.291337 -384.073619) (xy 119.257153 -384.063385) (xy 119.226251 -384.045543)
			(xy 119.200296 -384.021056) (xy 119.180687 -383.991243) (xy 119.168483 -383.957712) (xy 119.164341 -383.92227)
			(xy 118.271036 -383.92227) (xy 118.270518 -383.940112) (xy 118.262289 -383.974833) (xy 118.246275 -384.00672)
			(xy 118.223338 -384.034055) (xy 118.194716 -384.055364) (xy 118.161951 -384.069497) (xy 118.12681 -384.075693)
			(xy 118.091187 -384.073619) (xy 118.057003 -384.063385) (xy 118.026101 -384.045543) (xy 118.000146 -384.021056)
			(xy 117.980537 -383.991243) (xy 117.968333 -383.957712) (xy 117.964191 -383.92227) (xy 117.07114 -383.92227)
			(xy 117.070622 -383.940112) (xy 117.062393 -383.974833) (xy 117.046379 -384.00672) (xy 117.023442 -384.034055)
			(xy 116.99482 -384.055364) (xy 116.962055 -384.069497) (xy 116.926914 -384.075693) (xy 116.891291 -384.073619)
			(xy 116.857107 -384.063385) (xy 116.826205 -384.045543) (xy 116.80025 -384.021056) (xy 116.780641 -383.991243)
			(xy 116.768437 -383.957712) (xy 116.764295 -383.92227) (xy 115.87099 -383.92227) (xy 115.870472 -383.940112)
			(xy 115.862243 -383.974833) (xy 115.846229 -384.00672) (xy 115.823292 -384.034055) (xy 115.79467 -384.055364)
			(xy 115.761905 -384.069497) (xy 115.726764 -384.075693) (xy 115.691141 -384.073619) (xy 115.656957 -384.063385)
			(xy 115.626055 -384.045543) (xy 115.6001 -384.021056) (xy 115.580491 -383.991243) (xy 115.568287 -383.957712)
			(xy 115.564145 -383.92227) (xy 114.671094 -383.92227) (xy 114.670576 -383.940112) (xy 114.662347 -383.974833)
			(xy 114.646333 -384.00672) (xy 114.623396 -384.034055) (xy 114.594774 -384.055364) (xy 114.562009 -384.069497)
			(xy 114.526868 -384.075693) (xy 114.491245 -384.073619) (xy 114.457061 -384.063385) (xy 114.426159 -384.045543)
			(xy 114.400204 -384.021056) (xy 114.380595 -383.991243) (xy 114.368391 -383.957712) (xy 114.364249 -383.92227)
			(xy 98.098864 -383.92227) (xy 98.098346 -383.940112) (xy 98.090117 -383.974833) (xy 98.074103 -384.00672)
			(xy 98.051166 -384.034055) (xy 98.022544 -384.055364) (xy 97.989779 -384.069497) (xy 97.954638 -384.075693)
			(xy 97.919015 -384.073619) (xy 97.884831 -384.063385) (xy 97.853929 -384.045543) (xy 97.827974 -384.021056)
			(xy 97.808365 -383.991243) (xy 97.796161 -383.957712) (xy 97.792019 -383.92227) (xy 96.898968 -383.92227)
			(xy 96.89845 -383.940112) (xy 96.890221 -383.974833) (xy 96.874207 -384.00672) (xy 96.85127 -384.034055)
			(xy 96.822648 -384.055364) (xy 96.789883 -384.069497) (xy 96.754742 -384.075693) (xy 96.719119 -384.073619)
			(xy 96.684935 -384.063385) (xy 96.654033 -384.045543) (xy 96.628078 -384.021056) (xy 96.608469 -383.991243)
			(xy 96.596265 -383.957712) (xy 96.592123 -383.92227) (xy 95.698818 -383.92227) (xy 95.6983 -383.940112)
			(xy 95.690071 -383.974833) (xy 95.674057 -384.00672) (xy 95.65112 -384.034055) (xy 95.622498 -384.055364)
			(xy 95.589733 -384.069497) (xy 95.554592 -384.075693) (xy 95.518969 -384.073619) (xy 95.484785 -384.063385)
			(xy 95.453883 -384.045543) (xy 95.427928 -384.021056) (xy 95.408319 -383.991243) (xy 95.396115 -383.957712)
			(xy 95.391973 -383.92227) (xy 94.498922 -383.92227) (xy 94.498404 -383.940112) (xy 94.490175 -383.974833)
			(xy 94.474161 -384.00672) (xy 94.451224 -384.034055) (xy 94.422602 -384.055364) (xy 94.389837 -384.069497)
			(xy 94.354696 -384.075693) (xy 94.319073 -384.073619) (xy 94.284889 -384.063385) (xy 94.253987 -384.045543)
			(xy 94.228032 -384.021056) (xy 94.208423 -383.991243) (xy 94.196219 -383.957712) (xy 94.192077 -383.92227)
			(xy 93.299026 -383.92227) (xy 93.298508 -383.940112) (xy 93.290279 -383.974833) (xy 93.274265 -384.00672)
			(xy 93.251328 -384.034055) (xy 93.222706 -384.055364) (xy 93.189941 -384.069497) (xy 93.1548 -384.075693)
			(xy 93.119177 -384.073619) (xy 93.084993 -384.063385) (xy 93.054091 -384.045543) (xy 93.028136 -384.021056)
			(xy 93.008527 -383.991243) (xy 92.996323 -383.957712) (xy 92.992181 -383.92227) (xy 92.098876 -383.92227)
			(xy 92.098358 -383.940112) (xy 92.090129 -383.974833) (xy 92.074115 -384.00672) (xy 92.051178 -384.034055)
			(xy 92.022556 -384.055364) (xy 91.989791 -384.069497) (xy 91.95465 -384.075693) (xy 91.919027 -384.073619)
			(xy 91.884843 -384.063385) (xy 91.853941 -384.045543) (xy 91.827986 -384.021056) (xy 91.808377 -383.991243)
			(xy 91.796173 -383.957712) (xy 91.792031 -383.92227) (xy 90.89898 -383.92227) (xy 90.898462 -383.940112)
			(xy 90.890233 -383.974833) (xy 90.874219 -384.00672) (xy 90.851282 -384.034055) (xy 90.82266 -384.055364)
			(xy 90.789895 -384.069497) (xy 90.754754 -384.075693) (xy 90.719131 -384.073619) (xy 90.684947 -384.063385)
			(xy 90.654045 -384.045543) (xy 90.62809 -384.021056) (xy 90.608481 -383.991243) (xy 90.596277 -383.957712)
			(xy 90.592135 -383.92227) (xy 89.69883 -383.92227) (xy 89.698312 -383.940112) (xy 89.690083 -383.974833)
			(xy 89.674069 -384.00672) (xy 89.651132 -384.034055) (xy 89.62251 -384.055364) (xy 89.589745 -384.069497)
			(xy 89.554604 -384.075693) (xy 89.518981 -384.073619) (xy 89.484797 -384.063385) (xy 89.453895 -384.045543)
			(xy 89.42794 -384.021056) (xy 89.408331 -383.991243) (xy 89.396127 -383.957712) (xy 89.391985 -383.92227)
			(xy 88.498934 -383.92227) (xy 88.498416 -383.940112) (xy 88.490187 -383.974833) (xy 88.474173 -384.00672)
			(xy 88.451236 -384.034055) (xy 88.422614 -384.055364) (xy 88.389849 -384.069497) (xy 88.354708 -384.075693)
			(xy 88.319085 -384.073619) (xy 88.284901 -384.063385) (xy 88.253999 -384.045543) (xy 88.228044 -384.021056)
			(xy 88.208435 -383.991243) (xy 88.196231 -383.957712) (xy 88.192089 -383.92227) (xy 87.299038 -383.92227)
			(xy 87.29852 -383.940112) (xy 87.290291 -383.974833) (xy 87.274277 -384.00672) (xy 87.25134 -384.034055)
			(xy 87.222718 -384.055364) (xy 87.189953 -384.069497) (xy 87.154812 -384.075693) (xy 87.119189 -384.073619)
			(xy 87.085005 -384.063385) (xy 87.054103 -384.045543) (xy 87.028148 -384.021056) (xy 87.008539 -383.991243)
			(xy 86.996335 -383.957712) (xy 86.992193 -383.92227) (xy 86.098888 -383.92227) (xy 86.09837 -383.940112)
			(xy 86.090141 -383.974833) (xy 86.074127 -384.00672) (xy 86.05119 -384.034055) (xy 86.022568 -384.055364)
			(xy 85.989803 -384.069497) (xy 85.954662 -384.075693) (xy 85.919039 -384.073619) (xy 85.884855 -384.063385)
			(xy 85.853953 -384.045543) (xy 85.827998 -384.021056) (xy 85.808389 -383.991243) (xy 85.796185 -383.957712)
			(xy 85.792043 -383.92227) (xy 84.898992 -383.92227) (xy 84.898474 -383.940112) (xy 84.890245 -383.974833)
			(xy 84.874231 -384.00672) (xy 84.851294 -384.034055) (xy 84.822672 -384.055364) (xy 84.789907 -384.069497)
			(xy 84.754766 -384.075693) (xy 84.719143 -384.073619) (xy 84.684959 -384.063385) (xy 84.654057 -384.045543)
			(xy 84.628102 -384.021056) (xy 84.608493 -383.991243) (xy 84.596289 -383.957712) (xy 84.592147 -383.92227)
			(xy 83.698842 -383.92227) (xy 83.698324 -383.940112) (xy 83.690095 -383.974833) (xy 83.674081 -384.00672)
			(xy 83.651144 -384.034055) (xy 83.622522 -384.055364) (xy 83.589757 -384.069497) (xy 83.554616 -384.075693)
			(xy 83.518993 -384.073619) (xy 83.484809 -384.063385) (xy 83.453907 -384.045543) (xy 83.427952 -384.021056)
			(xy 83.408343 -383.991243) (xy 83.396139 -383.957712) (xy 83.391997 -383.92227) (xy 82.498946 -383.92227)
			(xy 82.498428 -383.940112) (xy 82.490199 -383.974833) (xy 82.474185 -384.00672) (xy 82.451248 -384.034055)
			(xy 82.422626 -384.055364) (xy 82.389861 -384.069497) (xy 82.35472 -384.075693) (xy 82.319097 -384.073619)
			(xy 82.284913 -384.063385) (xy 82.254011 -384.045543) (xy 82.228056 -384.021056) (xy 82.208447 -383.991243)
			(xy 82.196243 -383.957712) (xy 82.192101 -383.92227) (xy 81.298796 -383.92227) (xy 81.298278 -383.940112)
			(xy 81.290049 -383.974833) (xy 81.274035 -384.00672) (xy 81.251098 -384.034055) (xy 81.222476 -384.055364)
			(xy 81.189711 -384.069497) (xy 81.15457 -384.075693) (xy 81.118947 -384.073619) (xy 81.084763 -384.063385)
			(xy 81.053861 -384.045543) (xy 81.027906 -384.021056) (xy 81.008297 -383.991243) (xy 80.996093 -383.957712)
			(xy 80.991951 -383.92227) (xy 80.0989 -383.92227) (xy 80.098382 -383.940112) (xy 80.090153 -383.974833)
			(xy 80.074139 -384.00672) (xy 80.051202 -384.034055) (xy 80.02258 -384.055364) (xy 79.989815 -384.069497)
			(xy 79.954674 -384.075693) (xy 79.919051 -384.073619) (xy 79.884867 -384.063385) (xy 79.853965 -384.045543)
			(xy 79.82801 -384.021056) (xy 79.808401 -383.991243) (xy 79.796197 -383.957712) (xy 79.792055 -383.92227)
			(xy 65.571116 -383.92227) (xy 65.570598 -383.940112) (xy 65.562369 -383.974833) (xy 65.546355 -384.00672)
			(xy 65.523418 -384.034055) (xy 65.494796 -384.055364) (xy 65.462031 -384.069497) (xy 65.42689 -384.075693)
			(xy 65.391267 -384.073619) (xy 65.357083 -384.063385) (xy 65.326181 -384.045543) (xy 65.300226 -384.021056)
			(xy 65.280617 -383.991243) (xy 65.268413 -383.957712) (xy 65.264271 -383.92227) (xy 64.37122 -383.92227)
			(xy 64.370702 -383.940112) (xy 64.362473 -383.974833) (xy 64.346459 -384.00672) (xy 64.323522 -384.034055)
			(xy 64.2949 -384.055364) (xy 64.262135 -384.069497) (xy 64.226994 -384.075693) (xy 64.191371 -384.073619)
			(xy 64.157187 -384.063385) (xy 64.126285 -384.045543) (xy 64.10033 -384.021056) (xy 64.080721 -383.991243)
			(xy 64.068517 -383.957712) (xy 64.064375 -383.92227) (xy 63.17107 -383.92227) (xy 63.170552 -383.940112)
			(xy 63.162323 -383.974833) (xy 63.146309 -384.00672) (xy 63.123372 -384.034055) (xy 63.09475 -384.055364)
			(xy 63.061985 -384.069497) (xy 63.026844 -384.075693) (xy 62.991221 -384.073619) (xy 62.957037 -384.063385)
			(xy 62.926135 -384.045543) (xy 62.90018 -384.021056) (xy 62.880571 -383.991243) (xy 62.868367 -383.957712)
			(xy 62.864225 -383.92227) (xy 61.971174 -383.92227) (xy 61.970656 -383.940112) (xy 61.962427 -383.974833)
			(xy 61.946413 -384.00672) (xy 61.923476 -384.034055) (xy 61.894854 -384.055364) (xy 61.862089 -384.069497)
			(xy 61.826948 -384.075693) (xy 61.791325 -384.073619) (xy 61.757141 -384.063385) (xy 61.726239 -384.045543)
			(xy 61.700284 -384.021056) (xy 61.680675 -383.991243) (xy 61.668471 -383.957712) (xy 61.664329 -383.92227)
			(xy 60.771278 -383.92227) (xy 60.77076 -383.940112) (xy 60.762531 -383.974833) (xy 60.746517 -384.00672)
			(xy 60.72358 -384.034055) (xy 60.694958 -384.055364) (xy 60.662193 -384.069497) (xy 60.627052 -384.075693)
			(xy 60.591429 -384.073619) (xy 60.557245 -384.063385) (xy 60.526343 -384.045543) (xy 60.500388 -384.021056)
			(xy 60.480779 -383.991243) (xy 60.468575 -383.957712) (xy 60.464433 -383.92227) (xy 59.571128 -383.92227)
			(xy 59.57061 -383.940112) (xy 59.562381 -383.974833) (xy 59.546367 -384.00672) (xy 59.52343 -384.034055)
			(xy 59.494808 -384.055364) (xy 59.462043 -384.069497) (xy 59.426902 -384.075693) (xy 59.391279 -384.073619)
			(xy 59.357095 -384.063385) (xy 59.326193 -384.045543) (xy 59.300238 -384.021056) (xy 59.280629 -383.991243)
			(xy 59.268425 -383.957712) (xy 59.264283 -383.92227) (xy 58.371232 -383.92227) (xy 58.370714 -383.940112)
			(xy 58.362485 -383.974833) (xy 58.346471 -384.00672) (xy 58.323534 -384.034055) (xy 58.294912 -384.055364)
			(xy 58.262147 -384.069497) (xy 58.227006 -384.075693) (xy 58.191383 -384.073619) (xy 58.157199 -384.063385)
			(xy 58.126297 -384.045543) (xy 58.100342 -384.021056) (xy 58.080733 -383.991243) (xy 58.068529 -383.957712)
			(xy 58.064387 -383.92227) (xy 57.171082 -383.92227) (xy 57.170564 -383.940112) (xy 57.162335 -383.974833)
			(xy 57.146321 -384.00672) (xy 57.123384 -384.034055) (xy 57.094762 -384.055364) (xy 57.061997 -384.069497)
			(xy 57.026856 -384.075693) (xy 56.991233 -384.073619) (xy 56.957049 -384.063385) (xy 56.926147 -384.045543)
			(xy 56.900192 -384.021056) (xy 56.880583 -383.991243) (xy 56.868379 -383.957712) (xy 56.864237 -383.92227)
			(xy 55.971186 -383.92227) (xy 55.970668 -383.940112) (xy 55.962439 -383.974833) (xy 55.946425 -384.00672)
			(xy 55.923488 -384.034055) (xy 55.894866 -384.055364) (xy 55.862101 -384.069497) (xy 55.82696 -384.075693)
			(xy 55.791337 -384.073619) (xy 55.757153 -384.063385) (xy 55.726251 -384.045543) (xy 55.700296 -384.021056)
			(xy 55.680687 -383.991243) (xy 55.668483 -383.957712) (xy 55.664341 -383.92227) (xy 54.77129 -383.92227)
			(xy 54.770772 -383.940112) (xy 54.762543 -383.974833) (xy 54.746529 -384.00672) (xy 54.723592 -384.034055)
			(xy 54.69497 -384.055364) (xy 54.662205 -384.069497) (xy 54.627064 -384.075693) (xy 54.591441 -384.073619)
			(xy 54.557257 -384.063385) (xy 54.526355 -384.045543) (xy 54.5004 -384.021056) (xy 54.480791 -383.991243)
			(xy 54.468587 -383.957712) (xy 54.464445 -383.92227) (xy 53.57114 -383.92227) (xy 53.570622 -383.940112)
			(xy 53.562393 -383.974833) (xy 53.546379 -384.00672) (xy 53.523442 -384.034055) (xy 53.49482 -384.055364)
			(xy 53.462055 -384.069497) (xy 53.426914 -384.075693) (xy 53.391291 -384.073619) (xy 53.357107 -384.063385)
			(xy 53.326205 -384.045543) (xy 53.30025 -384.021056) (xy 53.280641 -383.991243) (xy 53.268437 -383.957712)
			(xy 53.264295 -383.92227) (xy 52.371244 -383.92227) (xy 52.370726 -383.940112) (xy 52.362497 -383.974833)
			(xy 52.346483 -384.00672) (xy 52.323546 -384.034055) (xy 52.294924 -384.055364) (xy 52.262159 -384.069497)
			(xy 52.227018 -384.075693) (xy 52.191395 -384.073619) (xy 52.157211 -384.063385) (xy 52.126309 -384.045543)
			(xy 52.100354 -384.021056) (xy 52.080745 -383.991243) (xy 52.068541 -383.957712) (xy 52.064399 -383.92227)
			(xy 51.171094 -383.92227) (xy 51.170576 -383.940112) (xy 51.162347 -383.974833) (xy 51.146333 -384.00672)
			(xy 51.123396 -384.034055) (xy 51.094774 -384.055364) (xy 51.062009 -384.069497) (xy 51.026868 -384.075693)
			(xy 50.991245 -384.073619) (xy 50.957061 -384.063385) (xy 50.926159 -384.045543) (xy 50.900204 -384.021056)
			(xy 50.880595 -383.991243) (xy 50.868391 -383.957712) (xy 50.864249 -383.92227) (xy 49.971198 -383.92227)
			(xy 49.97068 -383.940112) (xy 49.962451 -383.974833) (xy 49.946437 -384.00672) (xy 49.9235 -384.034055)
			(xy 49.894878 -384.055364) (xy 49.862113 -384.069497) (xy 49.826972 -384.075693) (xy 49.791349 -384.073619)
			(xy 49.757165 -384.063385) (xy 49.726263 -384.045543) (xy 49.700308 -384.021056) (xy 49.680699 -383.991243)
			(xy 49.668495 -383.957712) (xy 49.664353 -383.92227) (xy 48.771048 -383.92227) (xy 48.77053 -383.940112)
			(xy 48.762301 -383.974833) (xy 48.746287 -384.00672) (xy 48.72335 -384.034055) (xy 48.694728 -384.055364)
			(xy 48.661963 -384.069497) (xy 48.626822 -384.075693) (xy 48.591199 -384.073619) (xy 48.557015 -384.063385)
			(xy 48.526113 -384.045543) (xy 48.500158 -384.021056) (xy 48.480549 -383.991243) (xy 48.468345 -383.957712)
			(xy 48.464203 -383.92227) (xy 47.571152 -383.92227) (xy 47.570634 -383.940112) (xy 47.562405 -383.974833)
			(xy 47.546391 -384.00672) (xy 47.523454 -384.034055) (xy 47.494832 -384.055364) (xy 47.462067 -384.069497)
			(xy 47.426926 -384.075693) (xy 47.391303 -384.073619) (xy 47.357119 -384.063385) (xy 47.326217 -384.045543)
			(xy 47.300262 -384.021056) (xy 47.280653 -383.991243) (xy 47.268449 -383.957712) (xy 47.264307 -383.92227)
			(xy 2.509012 -383.92227) (xy 2.509012 -385.3104) (xy 47.079309 -385.3104) (xy 47.083496 -385.270563)
			(xy 47.095876 -385.232467) (xy 47.115905 -385.197778) (xy 47.14271 -385.168012) (xy 47.175118 -385.144469)
			(xy 47.211713 -385.12818) (xy 47.250896 -385.119856) (xy 47.270924 -385.119372) (xy 47.271432 -385.119372)
			(xy 47.292908 -385.119979) (xy 47.334772 -385.129597) (xy 47.373443 -385.148296) (xy 47.390558 -385.161282)
			(xy 47.390812 -385.161536) (xy 47.399318 -385.167633) (xy 47.419518 -385.173018) (xy 47.429928 -385.17195)
			(xy 47.51451 -385.159504) (xy 47.532544 -385.148074) (xy 47.538386 -385.139184) (xy 47.552734 -385.118892)
			(xy 47.586915 -385.082817) (xy 47.62648 -385.052747) (xy 47.670387 -385.029471) (xy 47.717482 -385.013602)
			(xy 47.766522 -385.00556) (xy 47.79137 -385.005072) (xy 47.815305 -385.005523) (xy 47.862591 -385.012984)
			(xy 47.908134 -385.027728) (xy 47.950821 -385.049394) (xy 47.989606 -385.077452) (xy 48.023541 -385.111216)
			(xy 48.051795 -385.149858) (xy 48.06315 -385.170934) (xy 48.063658 -385.17195) (xy 48.110648 -385.25323)
			(xy 48.115783 -385.261275) (xy 48.130664 -385.273198) (xy 48.148861 -385.278895) (xy 48.1584 -385.27863)
			(xy 48.24984 -385.271772) (xy 48.259224 -385.270657) (xy 48.276276 -385.262539) (xy 48.289275 -385.24884)
			(xy 48.293274 -385.240276) (xy 48.293274 -385.239768) (xy 48.300729 -385.22229) (xy 48.321483 -385.190468)
			(xy 48.348106 -385.163364) (xy 48.37955 -385.142041) (xy 48.414581 -385.127337) (xy 48.451824 -385.11983)
			(xy 48.47082 -385.119372) (xy 48.471328 -385.119372) (xy 48.492807 -385.11993) (xy 48.534673 -385.129568)
			(xy 48.573341 -385.148287) (xy 48.590454 -385.161282) (xy 48.590708 -385.161536) (xy 48.599215 -385.167631)
			(xy 48.619414 -385.173017) (xy 48.629824 -385.17195) (xy 48.714406 -385.159504) (xy 48.73244 -385.148074)
			(xy 48.738282 -385.139184) (xy 48.752633 -385.118893) (xy 48.786813 -385.082819) (xy 48.826377 -385.052748)
			(xy 48.870284 -385.029472) (xy 48.917378 -385.013603) (xy 48.966418 -385.00556) (xy 48.991266 -385.005072)
			(xy 49.015201 -385.005526) (xy 49.062486 -385.012986) (xy 49.10803 -385.02773) (xy 49.150716 -385.049395)
			(xy 49.189502 -385.077453) (xy 49.223437 -385.111216) (xy 49.251691 -385.149859) (xy 49.263046 -385.170934)
			(xy 49.263554 -385.17195) (xy 49.310544 -385.25323) (xy 49.315682 -385.261273) (xy 49.330562 -385.273196)
			(xy 49.348758 -385.278895) (xy 49.358296 -385.27863) (xy 49.449736 -385.271772) (xy 49.45912 -385.270654)
			(xy 49.476171 -385.262538) (xy 49.48917 -385.24884) (xy 49.49317 -385.240276) (xy 49.49317 -385.239768)
			(xy 49.500628 -385.222292) (xy 49.521382 -385.19047) (xy 49.548004 -385.163365) (xy 49.579447 -385.142043)
			(xy 49.614478 -385.127338) (xy 49.65172 -385.119831) (xy 49.670716 -385.119372) (xy 49.671224 -385.119372)
			(xy 49.692703 -385.119932) (xy 49.734569 -385.129569) (xy 49.773237 -385.148287) (xy 49.79035 -385.161282)
			(xy 49.790604 -385.161536) (xy 49.799113 -385.167629) (xy 49.81931 -385.173016) (xy 49.82972 -385.17195)
			(xy 49.914302 -385.159504) (xy 49.932336 -385.148074) (xy 49.938178 -385.139184) (xy 49.952531 -385.118895)
			(xy 49.986711 -385.082821) (xy 50.026275 -385.05275) (xy 50.070181 -385.029473) (xy 50.117275 -385.013604)
			(xy 50.166315 -385.005561) (xy 50.191162 -385.005072) (xy 50.215097 -385.005529) (xy 50.262382 -385.012989)
			(xy 50.307925 -385.027732) (xy 50.350612 -385.049397) (xy 50.389397 -385.077454) (xy 50.423333 -385.111217)
			(xy 50.451587 -385.149859) (xy 50.462942 -385.170934) (xy 50.46345 -385.17195) (xy 50.510694 -385.253738)
			(xy 50.51582 -385.261771) (xy 50.530722 -385.273622) (xy 50.548923 -385.279212) (xy 50.558446 -385.278884)
			(xy 50.66411 -385.27101) (xy 50.687732 -385.253738) (xy 50.693066 -385.240022) (xy 50.700499 -385.222498)
			(xy 50.721275 -385.190608) (xy 50.747935 -385.163445) (xy 50.779431 -385.142077) (xy 50.814525 -385.127345)
			(xy 50.851836 -385.119828) (xy 50.870866 -385.119372) (xy 50.871374 -385.119372) (xy 50.892852 -385.119958)
			(xy 50.934716 -385.129584) (xy 50.973386 -385.148292) (xy 50.9905 -385.161282) (xy 50.990754 -385.161536)
			(xy 50.999247 -385.167655) (xy 51.019457 -385.173026) (xy 51.02987 -385.17195) (xy 51.114452 -385.159504)
			(xy 51.132486 -385.148074) (xy 51.138328 -385.139184) (xy 51.152712 -385.118919) (xy 51.186886 -385.082843)
			(xy 51.226443 -385.05277) (xy 51.270344 -385.029489) (xy 51.317431 -385.013615) (xy 51.366466 -385.005565)
			(xy 51.391312 -385.005072) (xy 51.415246 -385.00557) (xy 51.462529 -385.013022) (xy 51.508071 -385.027757)
			(xy 51.550758 -385.049416) (xy 51.589544 -385.077467) (xy 51.62348 -385.111224) (xy 51.651736 -385.149861)
			(xy 51.663092 -385.170934) (xy 51.6636 -385.17195) (xy 51.71059 -385.25323) (xy 51.715697 -385.261295)
			(xy 51.730591 -385.273215) (xy 51.7488 -385.278903) (xy 51.758342 -385.27863) (xy 51.849782 -385.271772)
			(xy 51.85916 -385.270618) (xy 51.876211 -385.262519) (xy 51.889214 -385.248835) (xy 51.893216 -385.240276)
			(xy 51.893216 -385.239768) (xy 51.900637 -385.222274) (xy 51.921397 -385.190451) (xy 51.948026 -385.163347)
			(xy 51.979477 -385.142026) (xy 52.014515 -385.127327) (xy 52.051764 -385.119826) (xy 52.070762 -385.119372)
			(xy 52.07127 -385.119372) (xy 52.092748 -385.11996) (xy 52.134612 -385.129586) (xy 52.173282 -385.148293)
			(xy 52.190396 -385.161282) (xy 52.19065 -385.161536) (xy 52.199144 -385.167653) (xy 52.219353 -385.173025)
			(xy 52.229766 -385.17195) (xy 52.314348 -385.159504) (xy 52.332382 -385.148074) (xy 52.338224 -385.139184)
			(xy 52.352611 -385.118921) (xy 52.386784 -385.082845) (xy 52.426341 -385.052771) (xy 52.470241 -385.029491)
			(xy 52.517328 -385.013616) (xy 52.566363 -385.005565) (xy 52.591208 -385.005072) (xy 52.615141 -385.005573)
			(xy 52.662424 -385.013024) (xy 52.707967 -385.027759) (xy 52.750653 -385.049417) (xy 52.789439 -385.077468)
			(xy 52.823376 -385.111224) (xy 52.851632 -385.149861) (xy 52.862988 -385.170934) (xy 52.863496 -385.17195)
			(xy 52.91074 -385.253738) (xy 52.915835 -385.261794) (xy 52.930751 -385.273641) (xy 52.948965 -385.27922)
			(xy 52.958492 -385.278884) (xy 53.064156 -385.27101) (xy 53.087778 -385.253738) (xy 53.093112 -385.240022)
			(xy 53.100588 -385.222518) (xy 53.121357 -385.19063) (xy 53.148009 -385.163467) (xy 53.179496 -385.142096)
			(xy 53.214581 -385.127358) (xy 53.251885 -385.119833) (xy 53.270912 -385.119372) (xy 53.27142 -385.119372)
			(xy 53.292899 -385.119934) (xy 53.334765 -385.12957) (xy 53.373433 -385.148288) (xy 53.390546 -385.161282)
			(xy 53.3908 -385.161536) (xy 53.39931 -385.167627) (xy 53.419506 -385.173015) (xy 53.429916 -385.17195)
			(xy 53.514498 -385.159504) (xy 53.532532 -385.148074) (xy 53.538374 -385.139184) (xy 53.55273 -385.118897)
			(xy 53.586909 -385.082823) (xy 53.626472 -385.052751) (xy 53.670378 -385.029474) (xy 53.717471 -385.013605)
			(xy 53.766511 -385.005561) (xy 53.791358 -385.005072) (xy 53.815293 -385.005532) (xy 53.862578 -385.012992)
			(xy 53.908121 -385.027734) (xy 53.950807 -385.049398) (xy 53.989593 -385.077455) (xy 54.023528 -385.111217)
			(xy 54.051783 -385.149859) (xy 54.063138 -385.170934) (xy 54.063646 -385.17195) (xy 54.110636 -385.25323)
			(xy 54.115779 -385.261269) (xy 54.130656 -385.273193) (xy 54.148851 -385.278893) (xy 54.158388 -385.27863)
			(xy 54.249828 -385.271772) (xy 54.259211 -385.270649) (xy 54.276263 -385.262535) (xy 54.289262 -385.248839)
			(xy 54.293262 -385.240276) (xy 54.293262 -385.239768) (xy 54.300726 -385.222295) (xy 54.321479 -385.190473)
			(xy 54.3481 -385.163369) (xy 54.379542 -385.142045) (xy 54.414572 -385.12734) (xy 54.451813 -385.119831)
			(xy 54.470808 -385.119372) (xy 54.471316 -385.119372) (xy 54.492795 -385.119936) (xy 54.53466 -385.129572)
			(xy 54.573329 -385.148288) (xy 54.590442 -385.161282) (xy 54.590696 -385.161536) (xy 54.599207 -385.167625)
			(xy 54.619403 -385.173015) (xy 54.629812 -385.17195) (xy 54.714394 -385.159504) (xy 54.732428 -385.148074)
			(xy 54.73827 -385.139184) (xy 54.752628 -385.118899) (xy 54.786807 -385.082825) (xy 54.82637 -385.052753)
			(xy 54.870275 -385.029476) (xy 54.917368 -385.013606) (xy 54.966407 -385.005561) (xy 54.991254 -385.005072)
			(xy 55.015189 -385.005536) (xy 55.062474 -385.012994) (xy 55.108017 -385.027736) (xy 55.150703 -385.0494)
			(xy 55.189489 -385.077456) (xy 55.223424 -385.111218) (xy 55.251679 -385.149859) (xy 55.263034 -385.170934)
			(xy 55.263542 -385.17195) (xy 55.310532 -385.25323) (xy 55.315678 -385.261267) (xy 55.330554 -385.273191)
			(xy 55.348747 -385.278892) (xy 55.358284 -385.27863) (xy 55.449724 -385.271772) (xy 55.459107 -385.270646)
			(xy 55.476158 -385.262534) (xy 55.489158 -385.248839) (xy 55.493158 -385.240276) (xy 55.493158 -385.239768)
			(xy 55.500625 -385.222296) (xy 55.521378 -385.190475) (xy 55.547998 -385.16337) (xy 55.579439 -385.142047)
			(xy 55.614468 -385.127341) (xy 55.651709 -385.119832) (xy 55.670704 -385.119372) (xy 55.671212 -385.119372)
			(xy 55.692691 -385.119938) (xy 55.734556 -385.129573) (xy 55.773225 -385.148288) (xy 55.790338 -385.161282)
			(xy 55.790592 -385.161536) (xy 55.799105 -385.167623) (xy 55.819299 -385.173014) (xy 55.829708 -385.17195)
			(xy 55.91429 -385.159504) (xy 55.932324 -385.148074) (xy 55.938166 -385.139184) (xy 55.952527 -385.118901)
			(xy 55.986705 -385.082826) (xy 56.026267 -385.052755) (xy 56.070172 -385.029477) (xy 56.117264 -385.013607)
			(xy 56.166303 -385.005562) (xy 56.19115 -385.005072) (xy 56.215085 -385.005539) (xy 56.262369 -385.012997)
			(xy 56.307912 -385.027738) (xy 56.350599 -385.049401) (xy 56.389384 -385.077457) (xy 56.42332 -385.111218)
			(xy 56.451575 -385.149859) (xy 56.46293 -385.170934) (xy 56.463438 -385.17195) (xy 56.510682 -385.253738)
			(xy 56.515816 -385.261765) (xy 56.530715 -385.273617) (xy 56.548912 -385.279209) (xy 56.558434 -385.278884)
			(xy 56.664098 -385.27101) (xy 56.68772 -385.253738) (xy 56.693054 -385.240022) (xy 56.700496 -385.222503)
			(xy 56.721271 -385.190613) (xy 56.747929 -385.16345) (xy 56.779424 -385.142082) (xy 56.814515 -385.127348)
			(xy 56.851824 -385.119829) (xy 56.870854 -385.119372) (xy 56.871362 -385.119372) (xy 56.892839 -385.119964)
			(xy 56.934704 -385.129588) (xy 56.973373 -385.148293) (xy 56.990488 -385.161282) (xy 56.990742 -385.161536)
			(xy 56.999239 -385.167649) (xy 57.019446 -385.173024) (xy 57.029858 -385.17195) (xy 57.11444 -385.159504)
			(xy 57.132474 -385.148074) (xy 57.138316 -385.139184) (xy 57.152645 -385.118878) (xy 57.18683 -385.082804)
			(xy 57.226399 -385.052734) (xy 57.27031 -385.029461) (xy 57.317408 -385.013596) (xy 57.366451 -385.005558)
			(xy 57.3913 -385.005072) (xy 57.391554 -385.005072) (xy 57.415489 -385.005536) (xy 57.462774 -385.012994)
			(xy 57.508317 -385.027736) (xy 57.551003 -385.0494) (xy 57.589789 -385.077456) (xy 57.623724 -385.111218)
			(xy 57.651979 -385.149859) (xy 57.663334 -385.170934) (xy 57.663842 -385.17195) (xy 57.710832 -385.25323)
			(xy 57.715934 -385.26128) (xy 57.730847 -385.273129) (xy 57.749058 -385.27871) (xy 57.758584 -385.278376)
			(xy 57.84977 -385.271518) (xy 57.859153 -385.270387) (xy 57.876208 -385.262282) (xy 57.889207 -385.248586)
			(xy 57.893204 -385.240022) (xy 57.893204 -385.239768) (xy 57.900634 -385.222279) (xy 57.921393 -385.190456)
			(xy 57.94802 -385.163352) (xy 57.979469 -385.142031) (xy 58.014505 -385.12733) (xy 58.051753 -385.119828)
			(xy 58.07075 -385.119372) (xy 58.071258 -385.119372) (xy 58.092735 -385.119966) (xy 58.134599 -385.129589)
			(xy 58.173269 -385.148294) (xy 58.190384 -385.161282) (xy 58.190638 -385.161536) (xy 58.199136 -385.167647)
			(xy 58.219342 -385.173023) (xy 58.229754 -385.17195) (xy 58.314336 -385.159504) (xy 58.33237 -385.148074)
			(xy 58.338212 -385.139184) (xy 58.352544 -385.118879) (xy 58.386728 -385.082806) (xy 58.426296 -385.052736)
			(xy 58.470207 -385.029462) (xy 58.517304 -385.013597) (xy 58.566347 -385.005558) (xy 58.591196 -385.005072)
			(xy 58.59145 -385.005072) (xy 58.615385 -385.005539) (xy 58.662669 -385.012997) (xy 58.708212 -385.027738)
			(xy 58.750899 -385.049401) (xy 58.789684 -385.077457) (xy 58.82362 -385.111218) (xy 58.851875 -385.149859)
			(xy 58.86323 -385.170934) (xy 58.863738 -385.17195) (xy 58.910728 -385.25323) (xy 58.915876 -385.261265)
			(xy 58.930751 -385.273189) (xy 58.948943 -385.278892) (xy 58.95848 -385.27863) (xy 59.04992 -385.271772)
			(xy 59.059302 -385.270644) (xy 59.076354 -385.262533) (xy 59.089354 -385.248838) (xy 59.093354 -385.240276)
			(xy 59.093354 -385.239768) (xy 59.100825 -385.222298) (xy 59.121577 -385.190476) (xy 59.148196 -385.163372)
			(xy 59.179637 -385.142048) (xy 59.214665 -385.127342) (xy 59.251905 -385.119832) (xy 59.2709 -385.119372)
			(xy 59.271408 -385.119372) (xy 59.292887 -385.11994) (xy 59.334752 -385.129574) (xy 59.373421 -385.148289)
			(xy 59.390534 -385.161282) (xy 59.390788 -385.161536) (xy 59.399302 -385.167621) (xy 59.419495 -385.173013)
			(xy 59.429904 -385.17195) (xy 59.514486 -385.159504) (xy 59.53252 -385.148074) (xy 59.538362 -385.139184)
			(xy 59.552725 -385.118903) (xy 59.586903 -385.082828) (xy 59.626465 -385.052756) (xy 59.670369 -385.029478)
			(xy 59.717461 -385.013608) (xy 59.766499 -385.005562) (xy 59.791346 -385.005072) (xy 59.7916 -385.005072)
			(xy 59.815533 -385.00558) (xy 59.862816 -385.01303) (xy 59.908358 -385.027764) (xy 59.951044 -385.04942)
			(xy 59.989831 -385.07747) (xy 60.023768 -385.111226) (xy 60.052024 -385.149862) (xy 60.06338 -385.170934)
			(xy 60.063888 -385.17195) (xy 60.110878 -385.25323) (xy 60.116017 -385.261253) (xy 60.130913 -385.273106)
			(xy 60.149109 -385.278701) (xy 60.15863 -385.278376) (xy 60.249816 -385.271518) (xy 60.259204 -385.270418)
			(xy 60.276259 -385.262298) (xy 60.289255 -385.248591) (xy 60.29325 -385.240022) (xy 60.29325 -385.239768)
			(xy 60.300724 -385.222299) (xy 60.321476 -385.190478) (xy 60.348094 -385.163374) (xy 60.379534 -385.14205)
			(xy 60.414562 -385.127343) (xy 60.451801 -385.119833) (xy 60.470796 -385.119372) (xy 60.471304 -385.119372)
			(xy 60.492783 -385.119942) (xy 60.534648 -385.129575) (xy 60.573317 -385.148289) (xy 60.59043 -385.161282)
			(xy 60.590684 -385.161536) (xy 60.599199 -385.167619) (xy 60.619391 -385.173012) (xy 60.6298 -385.17195)
			(xy 60.714382 -385.159504) (xy 60.732416 -385.148074) (xy 60.738258 -385.139184) (xy 60.752624 -385.118905)
			(xy 60.786801 -385.08283) (xy 60.826362 -385.052758) (xy 60.870266 -385.02948) (xy 60.917357 -385.013609)
			(xy 60.966395 -385.005562) (xy 60.991242 -385.005072) (xy 60.991496 -385.005072) (xy 61.015432 -385.005502)
			(xy 61.062718 -385.012966) (xy 61.108262 -385.027714) (xy 61.150949 -385.049384) (xy 61.189734 -385.077445)
			(xy 61.223668 -385.111212) (xy 61.251922 -385.149857) (xy 61.263276 -385.170934) (xy 61.263784 -385.17195)
			(xy 61.310774 -385.25323) (xy 61.315915 -385.261251) (xy 61.33081 -385.273105) (xy 61.349005 -385.2787)
			(xy 61.358526 -385.278376) (xy 61.449712 -385.271518) (xy 61.459099 -385.270415) (xy 61.476154 -385.262297)
			(xy 61.489151 -385.24859) (xy 61.493146 -385.240022) (xy 61.493146 -385.239768) (xy 61.500543 -385.222263)
			(xy 61.521307 -385.190439) (xy 61.547941 -385.163335) (xy 61.579397 -385.142016) (xy 61.614439 -385.12732)
			(xy 61.651692 -385.119824) (xy 61.670692 -385.119372) (xy 61.6712 -385.119372) (xy 61.692679 -385.119944)
			(xy 61.734544 -385.129576) (xy 61.773213 -385.148289) (xy 61.790326 -385.161282) (xy 61.79058 -385.161536)
			(xy 61.799096 -385.167617) (xy 61.819288 -385.173011) (xy 61.829696 -385.17195) (xy 61.914278 -385.159504)
			(xy 61.932312 -385.148074) (xy 61.938154 -385.139184) (xy 61.952522 -385.118907) (xy 61.986699 -385.082832)
			(xy 62.02626 -385.052759) (xy 62.070163 -385.029481) (xy 62.117254 -385.013609) (xy 62.166291 -385.005563)
			(xy 62.191138 -385.005072) (xy 62.191392 -385.005072) (xy 62.215328 -385.005505) (xy 62.262614 -385.012969)
			(xy 62.308158 -385.027716) (xy 62.350844 -385.049385) (xy 62.38963 -385.077446) (xy 62.423564 -385.111212)
			(xy 62.451818 -385.149857) (xy 62.463172 -385.170934) (xy 62.46368 -385.17195) (xy 62.51067 -385.25323)
			(xy 62.51579 -385.261286) (xy 62.530678 -385.273207) (xy 62.548881 -385.278899) (xy 62.558422 -385.27863)
			(xy 62.649862 -385.271772) (xy 62.659238 -385.270605) (xy 62.676289 -385.262513) (xy 62.689293 -385.248833)
			(xy 62.693296 -385.240276) (xy 62.693296 -385.239768) (xy 62.700733 -385.222282) (xy 62.721491 -385.190459)
			(xy 62.748116 -385.163355) (xy 62.779564 -385.142033) (xy 62.814599 -385.127332) (xy 62.851845 -385.119828)
			(xy 62.870842 -385.119372) (xy 62.87135 -385.119372) (xy 62.892827 -385.11997) (xy 62.934691 -385.129591)
			(xy 62.973361 -385.148294) (xy 62.990476 -385.161282) (xy 62.99073 -385.161536) (xy 62.999231 -385.167642)
			(xy 63.019434 -385.173021) (xy 63.029846 -385.17195) (xy 63.114428 -385.159504) (xy 63.132462 -385.148074)
			(xy 63.138304 -385.139184) (xy 63.152641 -385.118883) (xy 63.186824 -385.082809) (xy 63.226391 -385.052739)
			(xy 63.270301 -385.029465) (xy 63.317397 -385.013599) (xy 63.36644 -385.005559) (xy 63.391288 -385.005072)
			(xy 63.391542 -385.005072) (xy 63.415476 -385.005545) (xy 63.462761 -385.013002) (xy 63.508303 -385.027742)
			(xy 63.55099 -385.049404) (xy 63.589776 -385.077459) (xy 63.623712 -385.11122) (xy 63.651967 -385.14986)
			(xy 63.663322 -385.170934) (xy 63.66383 -385.17195) (xy 63.71082 -385.25323) (xy 63.715931 -385.261274)
			(xy 63.73084 -385.273124) (xy 63.749047 -385.278708) (xy 63.758572 -385.278376) (xy 63.849758 -385.271518)
			(xy 63.859139 -385.270379) (xy 63.876194 -385.262278) (xy 63.889194 -385.248585) (xy 63.893192 -385.240022)
			(xy 63.893192 -385.239768) (xy 63.900632 -385.222283) (xy 63.921389 -385.190461) (xy 63.948014 -385.163356)
			(xy 63.979462 -385.142035) (xy 64.014496 -385.127333) (xy 64.051741 -385.119829) (xy 64.070738 -385.119372)
			(xy 64.071246 -385.119372) (xy 64.092723 -385.119972) (xy 64.134587 -385.129593) (xy 64.173257 -385.148295)
			(xy 64.190372 -385.161282) (xy 64.190626 -385.161536) (xy 64.199128 -385.16764) (xy 64.219331 -385.173021)
			(xy 64.229742 -385.17195) (xy 64.314324 -385.159504) (xy 64.332358 -385.148074) (xy 64.3382 -385.139184)
			(xy 64.352539 -385.118885) (xy 64.386722 -385.082811) (xy 64.426289 -385.052741) (xy 64.470198 -385.029466)
			(xy 64.517294 -385.013599) (xy 64.566336 -385.005559) (xy 64.591184 -385.005072) (xy 64.591438 -385.005072)
			(xy 64.615372 -385.005549) (xy 64.662656 -385.013005) (xy 64.708199 -385.027744) (xy 64.750886 -385.049406)
			(xy 64.789672 -385.07746) (xy 64.823607 -385.11122) (xy 64.851863 -385.14986) (xy 64.863218 -385.170934)
			(xy 64.863726 -385.17195) (xy 64.910716 -385.25323) (xy 64.915829 -385.261272) (xy 64.930737 -385.273122)
			(xy 64.948944 -385.278707) (xy 64.958468 -385.278376) (xy 65.049654 -385.271518) (xy 65.059035 -385.270376)
			(xy 65.07609 -385.262277) (xy 65.08909 -385.248585) (xy 65.093088 -385.240022) (xy 65.093088 -385.239768)
			(xy 65.100531 -385.222285) (xy 65.121288 -385.190462) (xy 65.147913 -385.163358) (xy 65.179359 -385.142036)
			(xy 65.214393 -385.127334) (xy 65.251637 -385.119829) (xy 65.270634 -385.119372) (xy 65.270888 -385.119372)
			(xy 65.292464 -385.119956) (xy 65.334518 -385.129636) (xy 65.373347 -385.148464) (xy 65.390522 -385.161536)
			(xy 65.398904 -385.168394) (xy 65.41897 -385.173728) (xy 65.514474 -385.159504) (xy 65.532508 -385.148074)
			(xy 65.53835 -385.139184) (xy 65.552721 -385.118908) (xy 65.586897 -385.082834) (xy 65.626457 -385.052761)
			(xy 65.67036 -385.029482) (xy 65.71745 -385.01361) (xy 65.766488 -385.005563) (xy 65.791334 -385.005072)
			(xy 65.791588 -385.005072) (xy 65.815524 -385.005508) (xy 65.86281 -385.012972) (xy 65.908353 -385.027718)
			(xy 65.95104 -385.049387) (xy 65.989825 -385.077447) (xy 66.02376 -385.111213) (xy 66.052014 -385.149858)
			(xy 66.063368 -385.170934) (xy 66.063876 -385.17195) (xy 66.1439 -385.3104) (xy 79.607146 -385.3104)
			(xy 79.611331 -385.270577) (xy 79.623704 -385.232495) (xy 79.643723 -385.197816) (xy 79.670514 -385.168058)
			(xy 79.702907 -385.144519) (xy 79.739485 -385.128228) (xy 79.778651 -385.119898) (xy 79.798672 -385.119372)
			(xy 79.79918 -385.119372) (xy 79.820658 -385.119955) (xy 79.862523 -385.129583) (xy 79.901192 -385.148292)
			(xy 79.918306 -385.161282) (xy 79.91856 -385.161536) (xy 79.927051 -385.167658) (xy 79.947263 -385.173027)
			(xy 79.957676 -385.17195) (xy 80.042258 -385.159504) (xy 80.060292 -385.148074) (xy 80.066134 -385.139184)
			(xy 80.080515 -385.118916) (xy 80.114689 -385.082841) (xy 80.154247 -385.052767) (xy 80.198148 -385.029487)
			(xy 80.245237 -385.013614) (xy 80.294272 -385.005564) (xy 80.319118 -385.005072) (xy 80.343052 -385.005565)
			(xy 80.390335 -385.013018) (xy 80.435877 -385.027754) (xy 80.478564 -385.049413) (xy 80.51735 -385.077465)
			(xy 80.551287 -385.111223) (xy 80.579542 -385.149861) (xy 80.590898 -385.170934) (xy 80.591406 -385.17195)
			(xy 80.638396 -385.25323) (xy 80.643499 -385.261298) (xy 80.658395 -385.273218) (xy 80.676605 -385.278904)
			(xy 80.686148 -385.27863) (xy 80.777588 -385.271772) (xy 80.786967 -385.270622) (xy 80.804018 -385.262521)
			(xy 80.81702 -385.248835) (xy 80.821022 -385.240276) (xy 80.821022 -385.239768) (xy 80.828438 -385.222272)
			(xy 80.849199 -385.190448) (xy 80.875829 -385.163344) (xy 80.907281 -385.142024) (xy 80.94232 -385.127326)
			(xy 80.97957 -385.119826) (xy 80.998568 -385.119372) (xy 80.999076 -385.119372) (xy 81.020554 -385.119957)
			(xy 81.062418 -385.129584) (xy 81.101088 -385.148292) (xy 81.118202 -385.161282) (xy 81.118456 -385.161536)
			(xy 81.126948 -385.167656) (xy 81.147159 -385.173027) (xy 81.157572 -385.17195) (xy 81.242154 -385.159504)
			(xy 81.260188 -385.148074) (xy 81.26603 -385.139184) (xy 81.280413 -385.118918) (xy 81.314587 -385.082843)
			(xy 81.354145 -385.052769) (xy 81.398045 -385.029489) (xy 81.445133 -385.013615) (xy 81.494168 -385.005565)
			(xy 81.519014 -385.005072) (xy 81.542948 -385.005568) (xy 81.590231 -385.013021) (xy 81.635773 -385.027756)
			(xy 81.67846 -385.049415) (xy 81.717246 -385.077466) (xy 81.751182 -385.111224) (xy 81.779438 -385.149861)
			(xy 81.790794 -385.170934) (xy 81.791302 -385.17195) (xy 81.838292 -385.25323) (xy 81.843397 -385.261296)
			(xy 81.858292 -385.273216) (xy 81.876502 -385.278903) (xy 81.886044 -385.27863) (xy 81.977484 -385.271772)
			(xy 81.986862 -385.270619) (xy 82.003914 -385.26252) (xy 82.016916 -385.248835) (xy 82.020918 -385.240276)
			(xy 82.020918 -385.239768) (xy 82.028337 -385.222273) (xy 82.049098 -385.19045) (xy 82.075727 -385.163346)
			(xy 82.107179 -385.142026) (xy 82.142217 -385.127327) (xy 82.179466 -385.119826) (xy 82.198464 -385.119372)
			(xy 82.198972 -385.119372) (xy 82.22045 -385.119959) (xy 82.262314 -385.129585) (xy 82.300984 -385.148292)
			(xy 82.318098 -385.161282) (xy 82.318352 -385.161536) (xy 82.326846 -385.167654) (xy 82.347055 -385.173026)
			(xy 82.357468 -385.17195) (xy 82.44205 -385.159504) (xy 82.460084 -385.148074) (xy 82.465926 -385.139184)
			(xy 82.480312 -385.11892) (xy 82.514485 -385.082844) (xy 82.554042 -385.052771) (xy 82.597942 -385.02949)
			(xy 82.64503 -385.013615) (xy 82.694065 -385.005565) (xy 82.71891 -385.005072) (xy 82.742843 -385.005571)
			(xy 82.790127 -385.013023) (xy 82.835669 -385.027758) (xy 82.878355 -385.049416) (xy 82.917142 -385.077467)
			(xy 82.951078 -385.111224) (xy 82.979334 -385.149861) (xy 82.99069 -385.170934) (xy 82.991198 -385.17195)
			(xy 83.038442 -385.253738) (xy 83.043535 -385.261795) (xy 83.058453 -385.273642) (xy 83.076667 -385.27922)
			(xy 83.086194 -385.278884) (xy 83.191858 -385.27101) (xy 83.21548 -385.253738) (xy 83.220814 -385.240022)
			(xy 83.228288 -385.222518) (xy 83.249057 -385.19063) (xy 83.27571 -385.163466) (xy 83.307198 -385.142096)
			(xy 83.342283 -385.127358) (xy 83.379587 -385.119833) (xy 83.398614 -385.119372) (xy 83.399122 -385.119372)
			(xy 83.420601 -385.119933) (xy 83.462467 -385.12957) (xy 83.501135 -385.148287) (xy 83.518248 -385.161282)
			(xy 83.518502 -385.161536) (xy 83.527011 -385.167628) (xy 83.547208 -385.173016) (xy 83.557618 -385.17195)
			(xy 83.6422 -385.159504) (xy 83.660234 -385.148074) (xy 83.666076 -385.139184) (xy 83.68043 -385.118896)
			(xy 83.71461 -385.082822) (xy 83.754173 -385.052751) (xy 83.79808 -385.029474) (xy 83.845173 -385.013605)
			(xy 83.894213 -385.005561) (xy 83.91906 -385.005072) (xy 83.942995 -385.005531) (xy 83.99028 -385.01299)
			(xy 84.035823 -385.027733) (xy 84.07851 -385.049398) (xy 84.117295 -385.077455) (xy 84.151231 -385.111217)
			(xy 84.179485 -385.149859) (xy 84.19084 -385.170934) (xy 84.191348 -385.17195) (xy 84.238338 -385.25323)
			(xy 84.24348 -385.26127) (xy 84.258358 -385.273193) (xy 84.276552 -385.278893) (xy 84.28609 -385.27863)
			(xy 84.37753 -385.271772) (xy 84.386913 -385.27065) (xy 84.403965 -385.262536) (xy 84.416964 -385.248839)
			(xy 84.420964 -385.240276) (xy 84.420964 -385.239768) (xy 84.428427 -385.222294) (xy 84.44918 -385.190472)
			(xy 84.475801 -385.163368) (xy 84.507243 -385.142045) (xy 84.542273 -385.12734) (xy 84.579515 -385.119831)
			(xy 84.59851 -385.119372) (xy 84.599018 -385.119372) (xy 84.620497 -385.119935) (xy 84.662363 -385.129571)
			(xy 84.701031 -385.148288) (xy 84.718144 -385.161282) (xy 84.718398 -385.161536) (xy 84.726909 -385.167626)
			(xy 84.747104 -385.173015) (xy 84.757514 -385.17195) (xy 84.842096 -385.159504) (xy 84.86013 -385.148074)
			(xy 84.865972 -385.139184) (xy 84.880329 -385.118898) (xy 84.914508 -385.082824) (xy 84.954071 -385.052752)
			(xy 84.997977 -385.029475) (xy 85.04507 -385.013605) (xy 85.094109 -385.005561) (xy 85.118956 -385.005072)
			(xy 85.142891 -385.005534) (xy 85.190176 -385.012993) (xy 85.235719 -385.027735) (xy 85.278405 -385.049399)
			(xy 85.317191 -385.077456) (xy 85.351126 -385.111218) (xy 85.379381 -385.149859) (xy 85.390736 -385.170934)
			(xy 85.391244 -385.17195) (xy 85.438488 -385.253738) (xy 85.443618 -385.261768) (xy 85.458518 -385.273619)
			(xy 85.476718 -385.27921) (xy 85.48624 -385.278884) (xy 85.591904 -385.27101) (xy 85.615526 -385.253738)
			(xy 85.62086 -385.240022) (xy 85.628297 -385.2225) (xy 85.649073 -385.190611) (xy 85.675732 -385.163448)
			(xy 85.707227 -385.142079) (xy 85.74232 -385.127347) (xy 85.77963 -385.119828) (xy 85.79866 -385.119372)
			(xy 85.799168 -385.119372) (xy 85.820646 -385.119961) (xy 85.86251 -385.129586) (xy 85.901179 -385.148293)
			(xy 85.918294 -385.161282) (xy 85.918548 -385.161536) (xy 85.927043 -385.167652) (xy 85.947251 -385.173025)
			(xy 85.957664 -385.17195) (xy 86.042246 -385.159504) (xy 86.06028 -385.148074) (xy 86.066122 -385.139184)
			(xy 86.08051 -385.118921) (xy 86.114683 -385.082846) (xy 86.15424 -385.052772) (xy 86.198139 -385.029491)
			(xy 86.245226 -385.013616) (xy 86.294261 -385.005565) (xy 86.319106 -385.005072) (xy 86.343039 -385.005575)
			(xy 86.390322 -385.013026) (xy 86.435864 -385.02776) (xy 86.478551 -385.049418) (xy 86.517337 -385.077468)
			(xy 86.551274 -385.111225) (xy 86.57953 -385.149861) (xy 86.590886 -385.170934) (xy 86.591394 -385.17195)
			(xy 86.638384 -385.25323) (xy 86.643495 -385.261292) (xy 86.658387 -385.273213) (xy 86.676594 -385.278902)
			(xy 86.686136 -385.27863) (xy 86.777576 -385.271772) (xy 86.786953 -385.270614) (xy 86.804005 -385.262517)
			(xy 86.817008 -385.248834) (xy 86.82101 -385.240276) (xy 86.82101 -385.239768) (xy 86.828436 -385.222276)
			(xy 86.849195 -385.190453) (xy 86.875823 -385.163349) (xy 86.907273 -385.142028) (xy 86.94231 -385.127329)
			(xy 86.979558 -385.119827) (xy 86.998556 -385.119372) (xy 86.999064 -385.119372) (xy 87.020541 -385.119963)
			(xy 87.062406 -385.129587) (xy 87.101075 -385.148293) (xy 87.11819 -385.161282) (xy 87.118444 -385.161536)
			(xy 87.12694 -385.16765) (xy 87.147148 -385.173024) (xy 87.15756 -385.17195) (xy 87.242142 -385.159504)
			(xy 87.260176 -385.148074) (xy 87.266018 -385.139184) (xy 87.280346 -385.118877) (xy 87.314531 -385.082803)
			(xy 87.3541 -385.052734) (xy 87.398012 -385.02946) (xy 87.445109 -385.013596) (xy 87.494153 -385.005558)
			(xy 87.519002 -385.005072) (xy 87.542935 -385.005578) (xy 87.590218 -385.013028) (xy 87.63576 -385.027763)
			(xy 87.678447 -385.04942) (xy 87.717233 -385.077469) (xy 87.75117 -385.111225) (xy 87.779426 -385.149861)
			(xy 87.790782 -385.170934) (xy 87.79129 -385.17195) (xy 87.83828 -385.25323) (xy 87.843393 -385.26129)
			(xy 87.858284 -385.273211) (xy 87.876491 -385.278901) (xy 87.886032 -385.27863) (xy 87.977472 -385.271772)
			(xy 87.986849 -385.270611) (xy 88.0039 -385.262516) (xy 88.016903 -385.248834) (xy 88.020906 -385.240276)
			(xy 88.020906 -385.239768) (xy 88.028335 -385.222278) (xy 88.049094 -385.190455) (xy 88.075721 -385.163351)
			(xy 88.107171 -385.14203) (xy 88.142207 -385.12733) (xy 88.179454 -385.119827) (xy 88.198452 -385.119372)
			(xy 88.19896 -385.119372) (xy 88.220437 -385.119965) (xy 88.262302 -385.129589) (xy 88.300971 -385.148293)
			(xy 88.318086 -385.161282) (xy 88.31834 -385.161536) (xy 88.326837 -385.167648) (xy 88.347044 -385.173023)
			(xy 88.357456 -385.17195) (xy 88.442038 -385.159504) (xy 88.460072 -385.148074) (xy 88.465914 -385.139184)
			(xy 88.480245 -385.118879) (xy 88.514429 -385.082805) (xy 88.553997 -385.052735) (xy 88.597909 -385.029462)
			(xy 88.645006 -385.013596) (xy 88.694049 -385.005558) (xy 88.718898 -385.005072) (xy 88.742834 -385.0055)
			(xy 88.790121 -385.012965) (xy 88.835664 -385.027713) (xy 88.878351 -385.049383) (xy 88.917136 -385.077445)
			(xy 88.95107 -385.111212) (xy 88.979324 -385.149857) (xy 88.990678 -385.170934) (xy 88.991186 -385.17195)
			(xy 89.03843 -385.253738) (xy 89.043532 -385.261789) (xy 89.058445 -385.273637) (xy 89.076656 -385.279218)
			(xy 89.086182 -385.278884) (xy 89.191846 -385.27101) (xy 89.215468 -385.253738) (xy 89.220802 -385.240022)
			(xy 89.228206 -385.222485) (xy 89.248986 -385.190593) (xy 89.275652 -385.163431) (xy 89.307155 -385.142065)
			(xy 89.342254 -385.127336) (xy 89.37957 -385.119824) (xy 89.398602 -385.119372) (xy 89.39911 -385.119372)
			(xy 89.420589 -385.119939) (xy 89.462454 -385.129573) (xy 89.501123 -385.148288) (xy 89.518236 -385.161282)
			(xy 89.51849 -385.161536) (xy 89.527003 -385.167622) (xy 89.547197 -385.173013) (xy 89.557606 -385.17195)
			(xy 89.642188 -385.159504) (xy 89.660222 -385.148074) (xy 89.666064 -385.139184) (xy 89.680426 -385.118902)
			(xy 89.714604 -385.082827) (xy 89.754166 -385.052755) (xy 89.798071 -385.029478) (xy 89.845163 -385.013607)
			(xy 89.894201 -385.005562) (xy 89.919048 -385.005072) (xy 89.942983 -385.005541) (xy 89.990267 -385.012998)
			(xy 90.03581 -385.027739) (xy 90.078497 -385.049402) (xy 90.117282 -385.077458) (xy 90.151218 -385.111219)
			(xy 90.179473 -385.149859) (xy 90.190828 -385.170934) (xy 90.191336 -385.17195) (xy 90.238326 -385.25323)
			(xy 90.243476 -385.261264) (xy 90.25835 -385.273189) (xy 90.276541 -385.278891) (xy 90.286078 -385.27863)
			(xy 90.377518 -385.271772) (xy 90.3869 -385.270642) (xy 90.403951 -385.262532) (xy 90.416952 -385.248838)
			(xy 90.420952 -385.240276) (xy 90.420952 -385.239768) (xy 90.428424 -385.222298) (xy 90.449176 -385.190477)
			(xy 90.475795 -385.163373) (xy 90.507236 -385.142049) (xy 90.542263 -385.127343) (xy 90.579503 -385.119832)
			(xy 90.598498 -385.119372) (xy 90.599006 -385.119372) (xy 90.620485 -385.119941) (xy 90.66235 -385.129575)
			(xy 90.701019 -385.148289) (xy 90.718132 -385.161282) (xy 90.718386 -385.161536) (xy 90.7269 -385.16762)
			(xy 90.747093 -385.173013) (xy 90.757502 -385.17195) (xy 90.842084 -385.159504) (xy 90.860118 -385.148074)
			(xy 90.86596 -385.139184) (xy 90.880324 -385.118904) (xy 90.914502 -385.082829) (xy 90.954063 -385.052757)
			(xy 90.997968 -385.029479) (xy 91.045059 -385.013608) (xy 91.094097 -385.005562) (xy 91.118944 -385.005072)
			(xy 91.142878 -385.005544) (xy 91.190163 -385.013001) (xy 91.235706 -385.027741) (xy 91.278392 -385.049404)
			(xy 91.317178 -385.077459) (xy 91.351114 -385.111219) (xy 91.379369 -385.14986) (xy 91.390724 -385.170934)
			(xy 91.391232 -385.17195) (xy 91.438476 -385.253738) (xy 91.443614 -385.261762) (xy 91.458511 -385.273614)
			(xy 91.476707 -385.279208) (xy 91.486228 -385.278884) (xy 91.591892 -385.27101) (xy 91.615514 -385.253738)
			(xy 91.620848 -385.240022) (xy 91.628295 -385.222505) (xy 91.649069 -385.190616) (xy 91.675726 -385.163452)
			(xy 91.70722 -385.142084) (xy 91.74231 -385.127349) (xy 91.779619 -385.119829) (xy 91.798648 -385.119372)
			(xy 91.799156 -385.119372) (xy 91.820633 -385.119967) (xy 91.862497 -385.12959) (xy 91.901167 -385.148294)
			(xy 91.918282 -385.161282) (xy 91.918536 -385.161536) (xy 91.927035 -385.167646) (xy 91.94724 -385.173023)
			(xy 91.957652 -385.17195) (xy 92.042234 -385.159504) (xy 92.060268 -385.148074) (xy 92.06611 -385.139184)
			(xy 92.080443 -385.11888) (xy 92.114627 -385.082807) (xy 92.154195 -385.052737) (xy 92.198106 -385.029463)
			(xy 92.245202 -385.013597) (xy 92.294245 -385.005558) (xy 92.319094 -385.005072) (xy 92.34303 -385.005503)
			(xy 92.390316 -385.012968) (xy 92.43586 -385.027715) (xy 92.478547 -385.049385) (xy 92.517332 -385.077446)
			(xy 92.551266 -385.111212) (xy 92.57952 -385.149857) (xy 92.590874 -385.170934) (xy 92.591382 -385.17195)
			(xy 92.638372 -385.25323) (xy 92.643491 -385.261287) (xy 92.658379 -385.273208) (xy 92.676583 -385.278899)
			(xy 92.686124 -385.27863) (xy 92.777564 -385.271772) (xy 92.78694 -385.270606) (xy 92.803991 -385.262513)
			(xy 92.816995 -385.248833) (xy 92.820998 -385.240276) (xy 92.820998 -385.239768) (xy 92.828433 -385.222281)
			(xy 92.849191 -385.190458) (xy 92.875817 -385.163354) (xy 92.907265 -385.142033) (xy 92.942301 -385.127332)
			(xy 92.979547 -385.119828) (xy 92.998544 -385.119372) (xy 92.999052 -385.119372) (xy 93.020529 -385.119969)
			(xy 93.062393 -385.129591) (xy 93.101063 -385.148294) (xy 93.118178 -385.161282) (xy 93.118432 -385.161536)
			(xy 93.126932 -385.167644) (xy 93.147136 -385.173022) (xy 93.157548 -385.17195) (xy 93.24213 -385.159504)
			(xy 93.260164 -385.148074) (xy 93.266006 -385.139184) (xy 93.280342 -385.118882) (xy 93.314525 -385.082808)
			(xy 93.354092 -385.052738) (xy 93.398003 -385.029464) (xy 93.445099 -385.013598) (xy 93.494141 -385.005559)
			(xy 93.51899 -385.005072) (xy 93.542926 -385.005506) (xy 93.590212 -385.01297) (xy 93.635756 -385.027717)
			(xy 93.678442 -385.049386) (xy 93.717227 -385.077447) (xy 93.751162 -385.111213) (xy 93.779416 -385.149857)
			(xy 93.79077 -385.170934) (xy 93.791278 -385.17195) (xy 93.838268 -385.25323) (xy 93.843389 -385.261285)
			(xy 93.858277 -385.273206) (xy 93.87648 -385.278899) (xy 93.88602 -385.27863) (xy 93.97746 -385.271772)
			(xy 93.986836 -385.270604) (xy 94.003887 -385.262512) (xy 94.016891 -385.248832) (xy 94.020894 -385.240276)
			(xy 94.020894 -385.239768) (xy 94.028333 -385.222283) (xy 94.04909 -385.19046) (xy 94.075715 -385.163356)
			(xy 94.107163 -385.142034) (xy 94.142197 -385.127333) (xy 94.179443 -385.119828) (xy 94.19844 -385.119372)
			(xy 94.198948 -385.119372) (xy 94.220425 -385.119971) (xy 94.262289 -385.129592) (xy 94.300959 -385.148295)
			(xy 94.318074 -385.161282) (xy 94.318328 -385.161536) (xy 94.326829 -385.167641) (xy 94.347033 -385.173021)
			(xy 94.357444 -385.17195) (xy 94.442026 -385.159504) (xy 94.46006 -385.148074) (xy 94.465902 -385.139184)
			(xy 94.48024 -385.118884) (xy 94.514423 -385.08281) (xy 94.55399 -385.05274) (xy 94.597899 -385.029465)
			(xy 94.644995 -385.013599) (xy 94.694038 -385.005559) (xy 94.718886 -385.005072) (xy 94.742822 -385.00551)
			(xy 94.790108 -385.012973) (xy 94.835651 -385.027719) (xy 94.878338 -385.049388) (xy 94.917123 -385.077448)
			(xy 94.951058 -385.111213) (xy 94.979312 -385.149858) (xy 94.990666 -385.170934) (xy 94.991174 -385.17195)
			(xy 95.038418 -385.253738) (xy 95.043528 -385.261783) (xy 95.058437 -385.273632) (xy 95.076645 -385.279216)
			(xy 95.08617 -385.278884) (xy 95.191834 -385.27101) (xy 95.215456 -385.253738) (xy 95.22079 -385.240022)
			(xy 95.228203 -385.222489) (xy 95.248982 -385.190598) (xy 95.275647 -385.163435) (xy 95.307147 -385.142069)
			(xy 95.342244 -385.127339) (xy 95.379558 -385.119825) (xy 95.39859 -385.119372) (xy 95.399098 -385.119372)
			(xy 95.420577 -385.119945) (xy 95.462442 -385.129577) (xy 95.501111 -385.14829) (xy 95.518224 -385.161282)
			(xy 95.518478 -385.161536) (xy 95.526995 -385.167616) (xy 95.547186 -385.173011) (xy 95.557594 -385.17195)
			(xy 95.642176 -385.159504) (xy 95.66021 -385.148074) (xy 95.666052 -385.139184) (xy 95.680421 -385.118907)
			(xy 95.714598 -385.082833) (xy 95.754158 -385.05276) (xy 95.798062 -385.029482) (xy 95.845152 -385.01361)
			(xy 95.89419 -385.005563) (xy 95.919036 -385.005072) (xy 95.94297 -385.00555) (xy 95.990254 -385.013006)
			(xy 96.035797 -385.027745) (xy 96.078484 -385.049407) (xy 96.117269 -385.077461) (xy 96.151205 -385.11122)
			(xy 96.179461 -385.14986) (xy 96.190816 -385.170934) (xy 96.191324 -385.17195) (xy 96.238314 -385.25323)
			(xy 96.243405 -385.261307) (xy 96.258306 -385.273225) (xy 96.276522 -385.278907) (xy 96.286066 -385.27863)
			(xy 96.377506 -385.271772) (xy 96.386887 -385.270634) (xy 96.403938 -385.262528) (xy 96.416939 -385.248837)
			(xy 96.42094 -385.240276) (xy 96.42094 -385.239768) (xy 96.428342 -385.222265) (xy 96.449105 -385.190441)
			(xy 96.475738 -385.163337) (xy 96.507193 -385.142018) (xy 96.542235 -385.127321) (xy 96.579487 -385.119824)
			(xy 96.598486 -385.119372) (xy 96.598994 -385.119372) (xy 96.620472 -385.119947) (xy 96.662337 -385.129578)
			(xy 96.701006 -385.14829) (xy 96.71812 -385.161282) (xy 96.718374 -385.161536) (xy 96.726892 -385.167614)
			(xy 96.747082 -385.17301) (xy 96.75749 -385.17195) (xy 96.842072 -385.159504) (xy 96.860106 -385.148074)
			(xy 96.865948 -385.139184) (xy 96.88032 -385.118909) (xy 96.914496 -385.082835) (xy 96.954056 -385.052762)
			(xy 96.997959 -385.029483) (xy 97.045049 -385.013611) (xy 97.094086 -385.005563) (xy 97.118932 -385.005072)
			(xy 97.142866 -385.005554) (xy 97.19015 -385.013009) (xy 97.235693 -385.027747) (xy 97.278379 -385.049408)
			(xy 97.317165 -385.077462) (xy 97.351101 -385.111221) (xy 97.379357 -385.14986) (xy 97.390712 -385.170934)
			(xy 97.39122 -385.17195) (xy 97.43821 -385.25323) (xy 97.443303 -385.261305) (xy 97.458203 -385.273223)
			(xy 97.476418 -385.278906) (xy 97.485962 -385.27863) (xy 97.577402 -385.271772) (xy 97.586782 -385.270631)
			(xy 97.603833 -385.262526) (xy 97.616835 -385.248836) (xy 97.620836 -385.240276) (xy 97.620836 -385.239768)
			(xy 97.628241 -385.222267) (xy 97.649004 -385.190443) (xy 97.675636 -385.163339) (xy 97.70709 -385.142019)
			(xy 97.742131 -385.127322) (xy 97.779383 -385.119825) (xy 97.798382 -385.119372) (xy 97.798636 -385.119372)
			(xy 97.820214 -385.119931) (xy 97.862268 -385.129622) (xy 97.901096 -385.148459) (xy 97.91827 -385.161536)
			(xy 97.926652 -385.168394) (xy 97.946718 -385.173728) (xy 98.042222 -385.159504) (xy 98.060256 -385.148074)
			(xy 98.066098 -385.139184) (xy 98.080439 -385.118886) (xy 98.114621 -385.082812) (xy 98.154187 -385.052742)
			(xy 98.198096 -385.029467) (xy 98.245192 -385.0136) (xy 98.294234 -385.005559) (xy 98.319082 -385.005072)
			(xy 98.343018 -385.005513) (xy 98.390303 -385.012976) (xy 98.435847 -385.027721) (xy 98.478534 -385.049389)
			(xy 98.517319 -385.077449) (xy 98.551254 -385.111214) (xy 98.579508 -385.149858) (xy 98.590862 -385.170934)
			(xy 98.59137 -385.17195) (xy 98.671394 -385.3104) (xy 114.179346 -385.3104) (xy 114.183531 -385.270578)
			(xy 114.195903 -385.232496) (xy 114.215922 -385.197818) (xy 114.242712 -385.16806) (xy 114.275103 -385.144521)
			(xy 114.311681 -385.12823) (xy 114.350846 -385.119899) (xy 114.370866 -385.119372) (xy 114.371374 -385.119372)
			(xy 114.392852 -385.119958) (xy 114.434716 -385.129584) (xy 114.473386 -385.148292) (xy 114.4905 -385.161282)
			(xy 114.490754 -385.161536) (xy 114.499247 -385.167655) (xy 114.519457 -385.173026) (xy 114.52987 -385.17195)
			(xy 114.614452 -385.159504) (xy 114.632486 -385.148074) (xy 114.638328 -385.139184) (xy 114.652712 -385.118919)
			(xy 114.686886 -385.082843) (xy 114.726443 -385.05277) (xy 114.770344 -385.029489) (xy 114.817431 -385.013615)
			(xy 114.866466 -385.005565) (xy 114.891312 -385.005072) (xy 114.915246 -385.00557) (xy 114.962529 -385.013022)
			(xy 115.008071 -385.027757) (xy 115.050758 -385.049416) (xy 115.089544 -385.077467) (xy 115.12348 -385.111224)
			(xy 115.151736 -385.149861) (xy 115.163092 -385.170934) (xy 115.1636 -385.17195) (xy 115.21059 -385.25323)
			(xy 115.215697 -385.261295) (xy 115.230591 -385.273215) (xy 115.2488 -385.278903) (xy 115.258342 -385.27863)
			(xy 115.349782 -385.271772) (xy 115.35916 -385.270618) (xy 115.376211 -385.262519) (xy 115.389214 -385.248835)
			(xy 115.393216 -385.240276) (xy 115.393216 -385.239768) (xy 115.400637 -385.222274) (xy 115.421397 -385.190451)
			(xy 115.448026 -385.163347) (xy 115.479477 -385.142026) (xy 115.514515 -385.127327) (xy 115.551764 -385.119826)
			(xy 115.570762 -385.119372) (xy 115.57127 -385.119372) (xy 115.592748 -385.11996) (xy 115.634612 -385.129586)
			(xy 115.673282 -385.148293) (xy 115.690396 -385.161282) (xy 115.69065 -385.161536) (xy 115.699144 -385.167653)
			(xy 115.719353 -385.173025) (xy 115.729766 -385.17195) (xy 115.814348 -385.159504) (xy 115.832382 -385.148074)
			(xy 115.838224 -385.139184) (xy 115.852611 -385.118921) (xy 115.886784 -385.082845) (xy 115.926341 -385.052771)
			(xy 115.970241 -385.029491) (xy 116.017328 -385.013616) (xy 116.066363 -385.005565) (xy 116.091208 -385.005072)
			(xy 116.115141 -385.005573) (xy 116.162424 -385.013024) (xy 116.207967 -385.027759) (xy 116.250653 -385.049417)
			(xy 116.289439 -385.077468) (xy 116.323376 -385.111224) (xy 116.351632 -385.149861) (xy 116.362988 -385.170934)
			(xy 116.363496 -385.17195) (xy 116.410486 -385.25323) (xy 116.415595 -385.261293) (xy 116.430488 -385.273213)
			(xy 116.448696 -385.278902) (xy 116.458238 -385.27863) (xy 116.549678 -385.271772) (xy 116.559056 -385.270615)
			(xy 116.576107 -385.262518) (xy 116.58911 -385.248834) (xy 116.593112 -385.240276) (xy 116.593112 -385.239768)
			(xy 116.600536 -385.222276) (xy 116.621296 -385.190453) (xy 116.647924 -385.163348) (xy 116.679375 -385.142028)
			(xy 116.714412 -385.127328) (xy 116.75166 -385.119827) (xy 116.770658 -385.119372) (xy 116.771166 -385.119372)
			(xy 116.792643 -385.119962) (xy 116.834508 -385.129587) (xy 116.873177 -385.148293) (xy 116.890292 -385.161282)
			(xy 116.890546 -385.161536) (xy 116.899042 -385.167651) (xy 116.919249 -385.173025) (xy 116.929662 -385.17195)
			(xy 117.014244 -385.159504) (xy 117.032278 -385.148074) (xy 117.03812 -385.139184) (xy 117.052509 -385.118922)
			(xy 117.086682 -385.082847) (xy 117.126238 -385.052773) (xy 117.170138 -385.029492) (xy 117.217225 -385.013617)
			(xy 117.266259 -385.005565) (xy 117.291104 -385.005072) (xy 117.315037 -385.005576) (xy 117.36232 -385.013027)
			(xy 117.407862 -385.027762) (xy 117.450549 -385.049419) (xy 117.489335 -385.077469) (xy 117.523272 -385.111225)
			(xy 117.551528 -385.149861) (xy 117.562884 -385.170934) (xy 117.563392 -385.17195) (xy 117.610636 -385.253738)
			(xy 117.615733 -385.261792) (xy 117.630649 -385.273639) (xy 117.648862 -385.279219) (xy 117.658388 -385.278884)
			(xy 117.764052 -385.27101) (xy 117.787674 -385.253738) (xy 117.793008 -385.240022) (xy 117.800487 -385.22252)
			(xy 117.821255 -385.190632) (xy 117.847907 -385.163469) (xy 117.879394 -385.142098) (xy 117.914478 -385.127359)
			(xy 117.951781 -385.119833) (xy 117.970808 -385.119372) (xy 117.971316 -385.119372) (xy 117.992795 -385.119936)
			(xy 118.03466 -385.129572) (xy 118.073329 -385.148288) (xy 118.090442 -385.161282) (xy 118.090696 -385.161536)
			(xy 118.099207 -385.167625) (xy 118.119403 -385.173015) (xy 118.129812 -385.17195) (xy 118.214394 -385.159504)
			(xy 118.232428 -385.148074) (xy 118.23827 -385.139184) (xy 118.252628 -385.118899) (xy 118.286807 -385.082825)
			(xy 118.32637 -385.052753) (xy 118.370275 -385.029476) (xy 118.417368 -385.013606) (xy 118.466407 -385.005561)
			(xy 118.491254 -385.005072) (xy 118.515189 -385.005536) (xy 118.562474 -385.012994) (xy 118.608017 -385.027736)
			(xy 118.650703 -385.0494) (xy 118.689489 -385.077456) (xy 118.723424 -385.111218) (xy 118.751679 -385.149859)
			(xy 118.763034 -385.170934) (xy 118.763542 -385.17195) (xy 118.810532 -385.25323) (xy 118.815678 -385.261267)
			(xy 118.830554 -385.273191) (xy 118.848747 -385.278892) (xy 118.858284 -385.27863) (xy 118.949724 -385.271772)
			(xy 118.959107 -385.270646) (xy 118.976158 -385.262534) (xy 118.989158 -385.248839) (xy 118.993158 -385.240276)
			(xy 118.993158 -385.239768) (xy 119.000625 -385.222296) (xy 119.021378 -385.190475) (xy 119.047998 -385.16337)
			(xy 119.079439 -385.142047) (xy 119.114468 -385.127341) (xy 119.151709 -385.119832) (xy 119.170704 -385.119372)
			(xy 119.171212 -385.119372) (xy 119.192691 -385.119938) (xy 119.234556 -385.129573) (xy 119.273225 -385.148288)
			(xy 119.290338 -385.161282) (xy 119.290592 -385.161536) (xy 119.299105 -385.167623) (xy 119.319299 -385.173014)
			(xy 119.329708 -385.17195) (xy 119.41429 -385.159504) (xy 119.432324 -385.148074) (xy 119.438166 -385.139184)
			(xy 119.452527 -385.118901) (xy 119.486705 -385.082826) (xy 119.526267 -385.052755) (xy 119.570172 -385.029477)
			(xy 119.617264 -385.013607) (xy 119.666303 -385.005562) (xy 119.69115 -385.005072) (xy 119.715085 -385.005539)
			(xy 119.762369 -385.012997) (xy 119.807912 -385.027738) (xy 119.850599 -385.049401) (xy 119.889384 -385.077457)
			(xy 119.92332 -385.111218) (xy 119.951575 -385.149859) (xy 119.96293 -385.170934) (xy 119.963438 -385.17195)
			(xy 120.010682 -385.253738) (xy 120.015816 -385.261765) (xy 120.030715 -385.273617) (xy 120.048912 -385.279209)
			(xy 120.058434 -385.278884) (xy 120.164098 -385.27101) (xy 120.18772 -385.253738) (xy 120.193054 -385.240022)
			(xy 120.200496 -385.222503) (xy 120.221271 -385.190613) (xy 120.247929 -385.16345) (xy 120.279424 -385.142082)
			(xy 120.314515 -385.127348) (xy 120.351824 -385.119829) (xy 120.370854 -385.119372) (xy 120.371362 -385.119372)
			(xy 120.392839 -385.119964) (xy 120.434704 -385.129588) (xy 120.473373 -385.148293) (xy 120.490488 -385.161282)
			(xy 120.490742 -385.161536) (xy 120.499239 -385.167649) (xy 120.519446 -385.173024) (xy 120.529858 -385.17195)
			(xy 120.61444 -385.159504) (xy 120.632474 -385.148074) (xy 120.638316 -385.139184) (xy 120.652645 -385.118878)
			(xy 120.68683 -385.082804) (xy 120.726399 -385.052734) (xy 120.77031 -385.029461) (xy 120.817408 -385.013596)
			(xy 120.866451 -385.005558) (xy 120.8913 -385.005072) (xy 120.915233 -385.00558) (xy 120.962516 -385.01303)
			(xy 121.008058 -385.027764) (xy 121.050744 -385.04942) (xy 121.089531 -385.07747) (xy 121.123468 -385.111226)
			(xy 121.151724 -385.149862) (xy 121.16308 -385.170934) (xy 121.163588 -385.17195) (xy 121.210578 -385.25323)
			(xy 121.215693 -385.261289) (xy 121.230583 -385.27321) (xy 121.248789 -385.278901) (xy 121.25833 -385.27863)
			(xy 121.34977 -385.271772) (xy 121.359147 -385.27061) (xy 121.376198 -385.262515) (xy 121.389201 -385.248833)
			(xy 121.393204 -385.240276) (xy 121.393204 -385.239768) (xy 121.400634 -385.222279) (xy 121.421393 -385.190456)
			(xy 121.44802 -385.163352) (xy 121.479469 -385.142031) (xy 121.514505 -385.12733) (xy 121.551753 -385.119828)
			(xy 121.57075 -385.119372) (xy 121.571258 -385.119372) (xy 121.592735 -385.119966) (xy 121.634599 -385.129589)
			(xy 121.673269 -385.148294) (xy 121.690384 -385.161282) (xy 121.690638 -385.161536) (xy 121.699136 -385.167647)
			(xy 121.719342 -385.173023) (xy 121.729754 -385.17195) (xy 121.814336 -385.159504) (xy 121.83237 -385.148074)
			(xy 121.838212 -385.139184) (xy 121.852544 -385.118879) (xy 121.886728 -385.082806) (xy 121.926296 -385.052736)
			(xy 121.970207 -385.029462) (xy 122.017304 -385.013597) (xy 122.066347 -385.005558) (xy 122.091196 -385.005072)
			(xy 122.115132 -385.005502) (xy 122.162418 -385.012966) (xy 122.207962 -385.027714) (xy 122.250649 -385.049384)
			(xy 122.289434 -385.077445) (xy 122.323368 -385.111212) (xy 122.351622 -385.149857) (xy 122.362976 -385.170934)
			(xy 122.363484 -385.17195) (xy 122.410474 -385.25323) (xy 122.415591 -385.261288) (xy 122.430481 -385.273208)
			(xy 122.448685 -385.2789) (xy 122.458226 -385.27863) (xy 122.549666 -385.271772) (xy 122.559042 -385.270607)
			(xy 122.576094 -385.262514) (xy 122.589097 -385.248833) (xy 122.5931 -385.240276) (xy 122.5931 -385.239768)
			(xy 122.600534 -385.22228) (xy 122.621292 -385.190457) (xy 122.647918 -385.163353) (xy 122.679367 -385.142032)
			(xy 122.714402 -385.127331) (xy 122.751649 -385.119828) (xy 122.770646 -385.119372) (xy 122.771154 -385.119372)
			(xy 122.792631 -385.119968) (xy 122.834495 -385.12959) (xy 122.873165 -385.148294) (xy 122.89028 -385.161282)
			(xy 122.890534 -385.161536) (xy 122.899033 -385.167645) (xy 122.919238 -385.173022) (xy 122.92965 -385.17195)
			(xy 123.014232 -385.159504) (xy 123.032266 -385.148074) (xy 123.038108 -385.139184) (xy 123.052442 -385.118881)
			(xy 123.086626 -385.082808) (xy 123.126194 -385.052738) (xy 123.170104 -385.029463) (xy 123.217201 -385.013598)
			(xy 123.266243 -385.005558) (xy 123.291092 -385.005072) (xy 123.315028 -385.005505) (xy 123.362314 -385.012969)
			(xy 123.407858 -385.027716) (xy 123.450544 -385.049385) (xy 123.48933 -385.077446) (xy 123.523264 -385.111212)
			(xy 123.551518 -385.149857) (xy 123.562872 -385.170934) (xy 123.56338 -385.17195) (xy 123.610624 -385.253738)
			(xy 123.61573 -385.261786) (xy 123.630641 -385.273634) (xy 123.648851 -385.279217) (xy 123.658376 -385.278884)
			(xy 123.76404 -385.27101) (xy 123.787662 -385.253738) (xy 123.792996 -385.240022) (xy 123.800404 -385.222487)
			(xy 123.821184 -385.190596) (xy 123.84785 -385.163433) (xy 123.879351 -385.142067) (xy 123.914449 -385.127338)
			(xy 123.951764 -385.119825) (xy 123.970796 -385.119372) (xy 123.971304 -385.119372) (xy 123.992783 -385.119942)
			(xy 124.034648 -385.129575) (xy 124.073317 -385.148289) (xy 124.09043 -385.161282) (xy 124.090684 -385.161536)
			(xy 124.099199 -385.167619) (xy 124.119391 -385.173012) (xy 124.1298 -385.17195) (xy 124.214382 -385.159504)
			(xy 124.232416 -385.148074) (xy 124.238258 -385.139184) (xy 124.252624 -385.118905) (xy 124.286801 -385.08283)
			(xy 124.326362 -385.052758) (xy 124.370266 -385.02948) (xy 124.417357 -385.013609) (xy 124.466395 -385.005562)
			(xy 124.491242 -385.005072) (xy 124.515176 -385.005545) (xy 124.562461 -385.013002) (xy 124.608003 -385.027742)
			(xy 124.65069 -385.049404) (xy 124.689476 -385.077459) (xy 124.723412 -385.11122) (xy 124.751667 -385.14986)
			(xy 124.763022 -385.170934) (xy 124.76353 -385.17195) (xy 124.81052 -385.25323) (xy 124.815674 -385.261261)
			(xy 124.830546 -385.273186) (xy 124.848736 -385.27889) (xy 124.858272 -385.27863) (xy 124.949712 -385.271772)
			(xy 124.959093 -385.270638) (xy 124.976145 -385.26253) (xy 124.989145 -385.248837) (xy 124.993146 -385.240276)
			(xy 124.993146 -385.239768) (xy 125.000543 -385.222263) (xy 125.021307 -385.190439) (xy 125.047941 -385.163335)
			(xy 125.079397 -385.142016) (xy 125.114439 -385.12732) (xy 125.151692 -385.119824) (xy 125.170692 -385.119372)
			(xy 125.1712 -385.119372) (xy 125.192679 -385.119944) (xy 125.234544 -385.129576) (xy 125.273213 -385.148289)
			(xy 125.290326 -385.161282) (xy 125.29058 -385.161536) (xy 125.299096 -385.167617) (xy 125.319288 -385.173011)
			(xy 125.329696 -385.17195) (xy 125.414278 -385.159504) (xy 125.432312 -385.148074) (xy 125.438154 -385.139184)
			(xy 125.452522 -385.118907) (xy 125.486699 -385.082832) (xy 125.52626 -385.052759) (xy 125.570163 -385.029481)
			(xy 125.617254 -385.013609) (xy 125.666291 -385.005563) (xy 125.691138 -385.005072) (xy 125.715072 -385.005549)
			(xy 125.762356 -385.013005) (xy 125.807899 -385.027744) (xy 125.850586 -385.049406) (xy 125.889372 -385.07746)
			(xy 125.923307 -385.11122) (xy 125.951563 -385.14986) (xy 125.962918 -385.170934) (xy 125.963426 -385.17195)
			(xy 126.01067 -385.253738) (xy 126.015812 -385.261759) (xy 126.030707 -385.273612) (xy 126.048902 -385.279207)
			(xy 126.058422 -385.278884) (xy 126.164086 -385.27101) (xy 126.187708 -385.253738) (xy 126.193042 -385.240022)
			(xy 126.200494 -385.222507) (xy 126.221267 -385.190618) (xy 126.247923 -385.163455) (xy 126.279416 -385.142086)
			(xy 126.314506 -385.127351) (xy 126.351813 -385.11983) (xy 126.370842 -385.119372) (xy 126.37135 -385.119372)
			(xy 126.392827 -385.11997) (xy 126.434691 -385.129591) (xy 126.473361 -385.148294) (xy 126.490476 -385.161282)
			(xy 126.49073 -385.161536) (xy 126.499231 -385.167642) (xy 126.519434 -385.173021) (xy 126.529846 -385.17195)
			(xy 126.614428 -385.159504) (xy 126.632462 -385.148074) (xy 126.638304 -385.139184) (xy 126.652641 -385.118883)
			(xy 126.686824 -385.082809) (xy 126.726391 -385.052739) (xy 126.770301 -385.029465) (xy 126.817397 -385.013599)
			(xy 126.86644 -385.005559) (xy 126.891288 -385.005072) (xy 126.915224 -385.005508) (xy 126.96251 -385.012972)
			(xy 127.008053 -385.027718) (xy 127.05074 -385.049387) (xy 127.089525 -385.077447) (xy 127.12346 -385.111213)
			(xy 127.151714 -385.149858) (xy 127.163068 -385.170934) (xy 127.163576 -385.17195) (xy 127.210566 -385.25323)
			(xy 127.215689 -385.261284) (xy 127.230576 -385.273205) (xy 127.248778 -385.278898) (xy 127.258318 -385.27863)
			(xy 127.349758 -385.271772) (xy 127.359133 -385.270602) (xy 127.376185 -385.262511) (xy 127.389189 -385.248832)
			(xy 127.393192 -385.240276) (xy 127.393192 -385.239768) (xy 127.400632 -385.222283) (xy 127.421389 -385.190461)
			(xy 127.448014 -385.163356) (xy 127.479462 -385.142035) (xy 127.514496 -385.127333) (xy 127.551741 -385.119829)
			(xy 127.570738 -385.119372) (xy 127.571246 -385.119372) (xy 127.592723 -385.119972) (xy 127.634587 -385.129593)
			(xy 127.673257 -385.148295) (xy 127.690372 -385.161282) (xy 127.690626 -385.161536) (xy 127.699128 -385.16764)
			(xy 127.719331 -385.173021) (xy 127.729742 -385.17195) (xy 127.814324 -385.159504) (xy 127.832358 -385.148074)
			(xy 127.8382 -385.139184) (xy 127.852539 -385.118885) (xy 127.886722 -385.082811) (xy 127.926289 -385.052741)
			(xy 127.970198 -385.029466) (xy 128.017294 -385.013599) (xy 128.066336 -385.005559) (xy 128.091184 -385.005072)
			(xy 128.11512 -385.005511) (xy 128.162406 -385.012974) (xy 128.207949 -385.02772) (xy 128.250636 -385.049388)
			(xy 128.289421 -385.077448) (xy 128.323356 -385.111214) (xy 128.35161 -385.149858) (xy 128.362964 -385.170934)
			(xy 128.363472 -385.17195) (xy 128.410462 -385.25323) (xy 128.415587 -385.261282) (xy 128.430473 -385.273203)
			(xy 128.448674 -385.278898) (xy 128.458214 -385.27863) (xy 128.549654 -385.271772) (xy 128.559029 -385.2706)
			(xy 128.57608 -385.26251) (xy 128.589085 -385.248832) (xy 128.593088 -385.240276) (xy 128.593088 -385.239768)
			(xy 128.600531 -385.222285) (xy 128.621288 -385.190462) (xy 128.647913 -385.163358) (xy 128.679359 -385.142036)
			(xy 128.714393 -385.127334) (xy 128.751637 -385.119829) (xy 128.770634 -385.119372) (xy 128.771142 -385.119372)
			(xy 128.792619 -385.119974) (xy 128.834483 -385.129594) (xy 128.873153 -385.148295) (xy 128.890268 -385.161282)
			(xy 128.890522 -385.161536) (xy 128.899025 -385.167638) (xy 128.919227 -385.17302) (xy 128.929638 -385.17195)
			(xy 129.01422 -385.159504) (xy 129.032254 -385.148074) (xy 129.038096 -385.139184) (xy 129.052438 -385.118887)
			(xy 129.08662 -385.082813) (xy 129.126186 -385.052743) (xy 129.170095 -385.029467) (xy 129.21719 -385.0136)
			(xy 129.266232 -385.005559) (xy 129.29108 -385.005072) (xy 129.315016 -385.005515) (xy 129.362301 -385.012977)
			(xy 129.407845 -385.027722) (xy 129.450531 -385.04939) (xy 129.489317 -385.077449) (xy 129.523252 -385.111214)
			(xy 129.551506 -385.149858) (xy 129.56286 -385.170934) (xy 129.563368 -385.17195) (xy 129.610612 -385.253738)
			(xy 129.615726 -385.26178) (xy 129.630634 -385.273629) (xy 129.64884 -385.279215) (xy 129.658364 -385.278884)
			(xy 129.764028 -385.27101) (xy 129.78765 -385.253738) (xy 129.792984 -385.240022) (xy 129.800402 -385.222491)
			(xy 129.821181 -385.190601) (xy 129.847844 -385.163438) (xy 129.879343 -385.142071) (xy 129.91444 -385.127341)
			(xy 129.951753 -385.119826) (xy 129.970784 -385.119372) (xy 129.971292 -385.119372) (xy 129.99277 -385.119948)
			(xy 130.034635 -385.129579) (xy 130.073304 -385.14829) (xy 130.090418 -385.161282) (xy 130.090672 -385.161536)
			(xy 130.099159 -385.167664) (xy 130.119374 -385.17303) (xy 130.129788 -385.17195) (xy 130.21437 -385.159504)
			(xy 130.232404 -385.148074) (xy 130.238246 -385.139184) (xy 130.252619 -385.11891) (xy 130.286795 -385.082835)
			(xy 130.326355 -385.052763) (xy 130.370257 -385.029483) (xy 130.417347 -385.013611) (xy 130.466384 -385.005563)
			(xy 130.49123 -385.005072) (xy 130.515164 -385.005555) (xy 130.562448 -385.01301) (xy 130.60799 -385.027748)
			(xy 130.650677 -385.049409) (xy 130.689463 -385.077462) (xy 130.723399 -385.111221) (xy 130.751655 -385.14986)
			(xy 130.76301 -385.170934) (xy 130.763518 -385.17195) (xy 130.810508 -385.25323) (xy 130.815603 -385.261304)
			(xy 130.830502 -385.273223) (xy 130.848716 -385.278906) (xy 130.85826 -385.27863) (xy 130.9497 -385.271772)
			(xy 130.95908 -385.27063) (xy 130.976131 -385.262526) (xy 130.989133 -385.248836) (xy 130.993134 -385.240276)
			(xy 130.993134 -385.239768) (xy 131.00054 -385.222267) (xy 131.021303 -385.190443) (xy 131.047935 -385.163339)
			(xy 131.079389 -385.14202) (xy 131.11443 -385.127323) (xy 131.151681 -385.119825) (xy 131.17068 -385.119372)
			(xy 131.171188 -385.119372) (xy 131.192666 -385.11995) (xy 131.234531 -385.12958) (xy 131.2732 -385.14829)
			(xy 131.290314 -385.161282) (xy 131.290568 -385.161536) (xy 131.299057 -385.167662) (xy 131.31927 -385.173029)
			(xy 131.329684 -385.17195) (xy 131.414266 -385.159504) (xy 131.4323 -385.148074) (xy 131.438142 -385.139184)
			(xy 131.452518 -385.118912) (xy 131.486693 -385.082837) (xy 131.526252 -385.052764) (xy 131.570154 -385.029485)
			(xy 131.617244 -385.013612) (xy 131.66628 -385.005564) (xy 131.691126 -385.005072) (xy 131.71506 -385.005558)
			(xy 131.762344 -385.013013) (xy 131.807886 -385.02775) (xy 131.850573 -385.04941) (xy 131.889359 -385.077463)
			(xy 131.923295 -385.111222) (xy 131.951551 -385.14986) (xy 131.962906 -385.170934) (xy 131.963414 -385.17195)
			(xy 132.010404 -385.25323) (xy 132.015501 -385.261302) (xy 132.0304 -385.273221) (xy 132.048612 -385.278905)
			(xy 132.058156 -385.27863) (xy 132.149596 -385.271772) (xy 132.158976 -385.270627) (xy 132.176027 -385.262524)
			(xy 132.189028 -385.248836) (xy 132.19303 -385.240276) (xy 132.19303 -385.239768) (xy 132.20044 -385.222269)
			(xy 132.221202 -385.190445) (xy 132.247833 -385.163341) (xy 132.279286 -385.142021) (xy 132.314326 -385.127324)
			(xy 132.351577 -385.119825) (xy 132.370576 -385.119372) (xy 132.37083 -385.119372) (xy 132.392407 -385.119934)
			(xy 132.434462 -385.129623) (xy 132.47329 -385.14846) (xy 132.490464 -385.161536) (xy 132.498846 -385.168394)
			(xy 132.518912 -385.173728) (xy 132.614416 -385.159504) (xy 132.63245 -385.148074) (xy 132.638292 -385.139184)
			(xy 132.652636 -385.118889) (xy 132.686818 -385.082815) (xy 132.726384 -385.052744) (xy 132.770292 -385.029469)
			(xy 132.817387 -385.013601) (xy 132.866428 -385.00556) (xy 132.891276 -385.005072) (xy 132.915211 -385.005518)
			(xy 132.962497 -385.01298) (xy 133.00804 -385.027724) (xy 133.050727 -385.049391) (xy 133.089512 -385.07745)
			(xy 133.123447 -385.111215) (xy 133.151701 -385.149858) (xy 133.163056 -385.170934) (xy 133.163564 -385.17195)
			(xy 133.243588 -385.3104) (xy 146.707009 -385.3104) (xy 146.711196 -385.270564) (xy 146.723574 -385.232469)
			(xy 146.743603 -385.197781) (xy 146.770406 -385.168015) (xy 146.802813 -385.144473) (xy 146.839406 -385.128183)
			(xy 146.878586 -385.119857) (xy 146.898614 -385.119372) (xy 146.899122 -385.119372) (xy 146.920601 -385.119933)
			(xy 146.962467 -385.12957) (xy 147.001135 -385.148287) (xy 147.018248 -385.161282) (xy 147.018502 -385.161536)
			(xy 147.027011 -385.167628) (xy 147.047208 -385.173016) (xy 147.057618 -385.17195) (xy 147.1422 -385.159504)
			(xy 147.160234 -385.148074) (xy 147.166076 -385.139184) (xy 147.18043 -385.118896) (xy 147.21461 -385.082822)
			(xy 147.254173 -385.052751) (xy 147.29808 -385.029474) (xy 147.345173 -385.013605) (xy 147.394213 -385.005561)
			(xy 147.41906 -385.005072) (xy 147.442995 -385.005531) (xy 147.49028 -385.01299) (xy 147.535823 -385.027733)
			(xy 147.57851 -385.049398) (xy 147.617295 -385.077455) (xy 147.651231 -385.111217) (xy 147.679485 -385.149859)
			(xy 147.69084 -385.170934) (xy 147.691348 -385.17195) (xy 147.738338 -385.25323) (xy 147.74348 -385.26127)
			(xy 147.758358 -385.273193) (xy 147.776552 -385.278893) (xy 147.78609 -385.27863) (xy 147.87753 -385.271772)
			(xy 147.886913 -385.27065) (xy 147.903965 -385.262536) (xy 147.916964 -385.248839) (xy 147.920964 -385.240276)
			(xy 147.920964 -385.239768) (xy 147.928427 -385.222294) (xy 147.94918 -385.190472) (xy 147.975801 -385.163368)
			(xy 148.007243 -385.142045) (xy 148.042273 -385.12734) (xy 148.079515 -385.119831) (xy 148.09851 -385.119372)
			(xy 148.099018 -385.119372) (xy 148.120497 -385.119935) (xy 148.162363 -385.129571) (xy 148.201031 -385.148288)
			(xy 148.218144 -385.161282) (xy 148.218398 -385.161536) (xy 148.226909 -385.167626) (xy 148.247104 -385.173015)
			(xy 148.257514 -385.17195) (xy 148.342096 -385.159504) (xy 148.36013 -385.148074) (xy 148.365972 -385.139184)
			(xy 148.380329 -385.118898) (xy 148.414508 -385.082824) (xy 148.454071 -385.052752) (xy 148.497977 -385.029475)
			(xy 148.54507 -385.013605) (xy 148.594109 -385.005561) (xy 148.618956 -385.005072) (xy 148.642891 -385.005534)
			(xy 148.690176 -385.012993) (xy 148.735719 -385.027735) (xy 148.778405 -385.049399) (xy 148.817191 -385.077456)
			(xy 148.851126 -385.111218) (xy 148.879381 -385.149859) (xy 148.890736 -385.170934) (xy 148.891244 -385.17195)
			(xy 148.938234 -385.25323) (xy 148.943378 -385.261268) (xy 148.958255 -385.273192) (xy 148.976449 -385.278893)
			(xy 148.985986 -385.27863) (xy 149.077426 -385.271772) (xy 149.086809 -385.270648) (xy 149.10386 -385.262535)
			(xy 149.11686 -385.248839) (xy 149.12086 -385.240276) (xy 149.12086 -385.239768) (xy 149.128326 -385.222295)
			(xy 149.149079 -385.190474) (xy 149.175699 -385.163369) (xy 149.207141 -385.142046) (xy 149.24217 -385.127341)
			(xy 149.279411 -385.119832) (xy 149.298406 -385.119372) (xy 149.298914 -385.119372) (xy 149.320393 -385.119937)
			(xy 149.362258 -385.129572) (xy 149.400927 -385.148288) (xy 149.41804 -385.161282) (xy 149.418294 -385.161536)
			(xy 149.426806 -385.167624) (xy 149.447001 -385.173014) (xy 149.45741 -385.17195) (xy 149.541992 -385.159504)
			(xy 149.560026 -385.148074) (xy 149.565868 -385.139184) (xy 149.580227 -385.1189) (xy 149.614406 -385.082826)
			(xy 149.653968 -385.052754) (xy 149.697874 -385.029476) (xy 149.744966 -385.013606) (xy 149.794005 -385.005562)
			(xy 149.818852 -385.005072) (xy 149.842787 -385.005537) (xy 149.890071 -385.012995) (xy 149.935614 -385.027737)
			(xy 149.978301 -385.049401) (xy 150.017087 -385.077457) (xy 150.051022 -385.111218) (xy 150.079277 -385.149859)
			(xy 150.090632 -385.170934) (xy 150.09114 -385.17195) (xy 150.138384 -385.253738) (xy 150.143516 -385.261766)
			(xy 150.158416 -385.273617) (xy 150.176614 -385.27921) (xy 150.186136 -385.278884) (xy 150.2918 -385.27101)
			(xy 150.315422 -385.253738) (xy 150.320756 -385.240022) (xy 150.328197 -385.222502) (xy 150.348971 -385.190612)
			(xy 150.37563 -385.163449) (xy 150.407125 -385.142081) (xy 150.442217 -385.127348) (xy 150.479526 -385.119829)
			(xy 150.498556 -385.119372) (xy 150.499064 -385.119372) (xy 150.520541 -385.119963) (xy 150.562406 -385.129587)
			(xy 150.601075 -385.148293) (xy 150.61819 -385.161282) (xy 150.618444 -385.161536) (xy 150.62694 -385.16765)
			(xy 150.647148 -385.173024) (xy 150.65756 -385.17195) (xy 150.742142 -385.159504) (xy 150.760176 -385.148074)
			(xy 150.766018 -385.139184) (xy 150.780346 -385.118877) (xy 150.814531 -385.082803) (xy 150.8541 -385.052734)
			(xy 150.898012 -385.02946) (xy 150.945109 -385.013596) (xy 150.994153 -385.005558) (xy 151.019002 -385.005072)
			(xy 151.042935 -385.005578) (xy 151.090218 -385.013028) (xy 151.13576 -385.027763) (xy 151.178447 -385.04942)
			(xy 151.217233 -385.077469) (xy 151.25117 -385.111225) (xy 151.279426 -385.149861) (xy 151.290782 -385.170934)
			(xy 151.29129 -385.17195) (xy 151.33828 -385.25323) (xy 151.343393 -385.26129) (xy 151.358284 -385.273211)
			(xy 151.376491 -385.278901) (xy 151.386032 -385.27863) (xy 151.477472 -385.271772) (xy 151.486849 -385.270611)
			(xy 151.5039 -385.262516) (xy 151.516903 -385.248834) (xy 151.520906 -385.240276) (xy 151.520906 -385.239768)
			(xy 151.528335 -385.222278) (xy 151.549094 -385.190455) (xy 151.575721 -385.163351) (xy 151.607171 -385.14203)
			(xy 151.642207 -385.12733) (xy 151.679454 -385.119827) (xy 151.698452 -385.119372) (xy 151.69896 -385.119372)
			(xy 151.720437 -385.119965) (xy 151.762302 -385.129589) (xy 151.800971 -385.148293) (xy 151.818086 -385.161282)
			(xy 151.81834 -385.161536) (xy 151.826837 -385.167648) (xy 151.847044 -385.173023) (xy 151.857456 -385.17195)
			(xy 151.942038 -385.159504) (xy 151.960072 -385.148074) (xy 151.965914 -385.139184) (xy 151.980245 -385.118879)
			(xy 152.014429 -385.082805) (xy 152.053997 -385.052735) (xy 152.097909 -385.029462) (xy 152.145006 -385.013596)
			(xy 152.194049 -385.005558) (xy 152.218898 -385.005072) (xy 152.242834 -385.0055) (xy 152.290121 -385.012965)
			(xy 152.335664 -385.027713) (xy 152.378351 -385.049383) (xy 152.417136 -385.077445) (xy 152.45107 -385.111212)
			(xy 152.479324 -385.149857) (xy 152.490678 -385.170934) (xy 152.491186 -385.17195) (xy 152.53843 -385.253738)
			(xy 152.543532 -385.261789) (xy 152.558445 -385.273637) (xy 152.576656 -385.279218) (xy 152.586182 -385.278884)
			(xy 152.691846 -385.27101) (xy 152.715468 -385.253738) (xy 152.720802 -385.240022) (xy 152.728206 -385.222485)
			(xy 152.748986 -385.190593) (xy 152.775652 -385.163431) (xy 152.807155 -385.142065) (xy 152.842254 -385.127336)
			(xy 152.87957 -385.119824) (xy 152.898602 -385.119372) (xy 152.89911 -385.119372) (xy 152.920589 -385.119939)
			(xy 152.962454 -385.129573) (xy 153.001123 -385.148288) (xy 153.018236 -385.161282) (xy 153.01849 -385.161536)
			(xy 153.027003 -385.167622) (xy 153.047197 -385.173013) (xy 153.057606 -385.17195) (xy 153.142188 -385.159504)
			(xy 153.160222 -385.148074) (xy 153.166064 -385.139184) (xy 153.180426 -385.118902) (xy 153.214604 -385.082827)
			(xy 153.254166 -385.052755) (xy 153.298071 -385.029478) (xy 153.345163 -385.013607) (xy 153.394201 -385.005562)
			(xy 153.419048 -385.005072) (xy 153.442983 -385.005541) (xy 153.490267 -385.012998) (xy 153.53581 -385.027739)
			(xy 153.578497 -385.049402) (xy 153.617282 -385.077458) (xy 153.651218 -385.111219) (xy 153.679473 -385.149859)
			(xy 153.690828 -385.170934) (xy 153.691336 -385.17195) (xy 153.738326 -385.25323) (xy 153.743476 -385.261264)
			(xy 153.75835 -385.273189) (xy 153.776541 -385.278891) (xy 153.786078 -385.27863) (xy 153.877518 -385.271772)
			(xy 153.8869 -385.270642) (xy 153.903951 -385.262532) (xy 153.916952 -385.248838) (xy 153.920952 -385.240276)
			(xy 153.920952 -385.239768) (xy 153.928424 -385.222298) (xy 153.949176 -385.190477) (xy 153.975795 -385.163373)
			(xy 154.007236 -385.142049) (xy 154.042263 -385.127343) (xy 154.079503 -385.119832) (xy 154.098498 -385.119372)
			(xy 154.099006 -385.119372) (xy 154.120485 -385.119941) (xy 154.16235 -385.129575) (xy 154.201019 -385.148289)
			(xy 154.218132 -385.161282) (xy 154.218386 -385.161536) (xy 154.2269 -385.16762) (xy 154.247093 -385.173013)
			(xy 154.257502 -385.17195) (xy 154.342084 -385.159504) (xy 154.360118 -385.148074) (xy 154.36596 -385.139184)
			(xy 154.380324 -385.118904) (xy 154.414502 -385.082829) (xy 154.454063 -385.052757) (xy 154.497968 -385.029479)
			(xy 154.545059 -385.013608) (xy 154.594097 -385.005562) (xy 154.618944 -385.005072) (xy 154.642878 -385.005544)
			(xy 154.690163 -385.013001) (xy 154.735706 -385.027741) (xy 154.778392 -385.049404) (xy 154.817178 -385.077459)
			(xy 154.851114 -385.111219) (xy 154.879369 -385.14986) (xy 154.890724 -385.170934) (xy 154.891232 -385.17195)
			(xy 154.938222 -385.25323) (xy 154.943374 -385.261262) (xy 154.958248 -385.273187) (xy 154.976438 -385.278891)
			(xy 154.985974 -385.27863) (xy 155.077414 -385.271772) (xy 155.086795 -385.270639) (xy 155.103847 -385.26253)
			(xy 155.116847 -385.248838) (xy 155.120848 -385.240276) (xy 155.120848 -385.239768) (xy 155.128243 -385.222262)
			(xy 155.149008 -385.190438) (xy 155.175642 -385.163334) (xy 155.207098 -385.142015) (xy 155.242141 -385.127319)
			(xy 155.279394 -385.119823) (xy 155.298394 -385.119372) (xy 155.298902 -385.119372) (xy 155.320381 -385.119943)
			(xy 155.362246 -385.129576) (xy 155.400915 -385.148289) (xy 155.418028 -385.161282) (xy 155.418282 -385.161536)
			(xy 155.426798 -385.167618) (xy 155.446989 -385.173012) (xy 155.457398 -385.17195) (xy 155.54198 -385.159504)
			(xy 155.560014 -385.148074) (xy 155.565856 -385.139184) (xy 155.580223 -385.118906) (xy 155.6144 -385.082831)
			(xy 155.653961 -385.052759) (xy 155.697865 -385.02948) (xy 155.744956 -385.013609) (xy 155.793993 -385.005562)
			(xy 155.81884 -385.005072) (xy 155.842774 -385.005547) (xy 155.890059 -385.013003) (xy 155.935601 -385.027743)
			(xy 155.978288 -385.049405) (xy 156.017074 -385.07746) (xy 156.05101 -385.11122) (xy 156.079265 -385.14986)
			(xy 156.09062 -385.170934) (xy 156.091128 -385.17195) (xy 156.138372 -385.253738) (xy 156.143512 -385.26176)
			(xy 156.158408 -385.273612) (xy 156.176603 -385.279208) (xy 156.186124 -385.278884) (xy 156.291788 -385.27101)
			(xy 156.31541 -385.253738) (xy 156.320744 -385.240022) (xy 156.328194 -385.222506) (xy 156.348967 -385.190617)
			(xy 156.375624 -385.163454) (xy 156.407117 -385.142085) (xy 156.442207 -385.12735) (xy 156.479515 -385.11983)
			(xy 156.498544 -385.119372) (xy 156.499052 -385.119372) (xy 156.520529 -385.119969) (xy 156.562393 -385.129591)
			(xy 156.601063 -385.148294) (xy 156.618178 -385.161282) (xy 156.618432 -385.161536) (xy 156.626932 -385.167644)
			(xy 156.647136 -385.173022) (xy 156.657548 -385.17195) (xy 156.74213 -385.159504) (xy 156.760164 -385.148074)
			(xy 156.766006 -385.139184) (xy 156.780342 -385.118882) (xy 156.814525 -385.082808) (xy 156.854092 -385.052738)
			(xy 156.898003 -385.029464) (xy 156.945099 -385.013598) (xy 156.994141 -385.005559) (xy 157.01899 -385.005072)
			(xy 157.042926 -385.005506) (xy 157.090212 -385.01297) (xy 157.135756 -385.027717) (xy 157.178442 -385.049386)
			(xy 157.217227 -385.077447) (xy 157.251162 -385.111213) (xy 157.279416 -385.149857) (xy 157.29077 -385.170934)
			(xy 157.291278 -385.17195) (xy 157.338268 -385.25323) (xy 157.343389 -385.261285) (xy 157.358277 -385.273206)
			(xy 157.37648 -385.278899) (xy 157.38602 -385.27863) (xy 157.47746 -385.271772) (xy 157.486836 -385.270604)
			(xy 157.503887 -385.262512) (xy 157.516891 -385.248832) (xy 157.520894 -385.240276) (xy 157.520894 -385.239768)
			(xy 157.528333 -385.222283) (xy 157.54909 -385.19046) (xy 157.575715 -385.163356) (xy 157.607163 -385.142034)
			(xy 157.642197 -385.127333) (xy 157.679443 -385.119828) (xy 157.69844 -385.119372) (xy 157.698948 -385.119372)
			(xy 157.720425 -385.119971) (xy 157.762289 -385.129592) (xy 157.800959 -385.148295) (xy 157.818074 -385.161282)
			(xy 157.818328 -385.161536) (xy 157.826829 -385.167641) (xy 157.847033 -385.173021) (xy 157.857444 -385.17195)
			(xy 157.942026 -385.159504) (xy 157.96006 -385.148074) (xy 157.965902 -385.139184) (xy 157.98024 -385.118884)
			(xy 158.014423 -385.08281) (xy 158.05399 -385.05274) (xy 158.097899 -385.029465) (xy 158.144995 -385.013599)
			(xy 158.194038 -385.005559) (xy 158.218886 -385.005072) (xy 158.242822 -385.00551) (xy 158.290108 -385.012973)
			(xy 158.335651 -385.027719) (xy 158.378338 -385.049388) (xy 158.417123 -385.077448) (xy 158.451058 -385.111213)
			(xy 158.479312 -385.149858) (xy 158.490666 -385.170934) (xy 158.491174 -385.17195) (xy 158.538418 -385.253738)
			(xy 158.543528 -385.261783) (xy 158.558437 -385.273632) (xy 158.576645 -385.279216) (xy 158.58617 -385.278884)
			(xy 158.691834 -385.27101) (xy 158.715456 -385.253738) (xy 158.72079 -385.240022) (xy 158.728203 -385.222489)
			(xy 158.748982 -385.190598) (xy 158.775647 -385.163435) (xy 158.807147 -385.142069) (xy 158.842244 -385.127339)
			(xy 158.879558 -385.119825) (xy 158.89859 -385.119372) (xy 158.899098 -385.119372) (xy 158.920577 -385.119945)
			(xy 158.962442 -385.129577) (xy 159.001111 -385.14829) (xy 159.018224 -385.161282) (xy 159.018478 -385.161536)
			(xy 159.026995 -385.167616) (xy 159.047186 -385.173011) (xy 159.057594 -385.17195) (xy 159.142176 -385.159504)
			(xy 159.16021 -385.148074) (xy 159.166052 -385.139184) (xy 159.180421 -385.118907) (xy 159.214598 -385.082833)
			(xy 159.254158 -385.05276) (xy 159.298062 -385.029482) (xy 159.345152 -385.01361) (xy 159.39419 -385.005563)
			(xy 159.419036 -385.005072) (xy 159.44297 -385.00555) (xy 159.490254 -385.013006) (xy 159.535797 -385.027745)
			(xy 159.578484 -385.049407) (xy 159.617269 -385.077461) (xy 159.651205 -385.11122) (xy 159.679461 -385.14986)
			(xy 159.690816 -385.170934) (xy 159.691324 -385.17195) (xy 159.738314 -385.25323) (xy 159.743405 -385.261307)
			(xy 159.758306 -385.273225) (xy 159.776522 -385.278907) (xy 159.786066 -385.27863) (xy 159.877506 -385.271772)
			(xy 159.886887 -385.270634) (xy 159.903938 -385.262528) (xy 159.916939 -385.248837) (xy 159.92094 -385.240276)
			(xy 159.92094 -385.239768) (xy 159.928342 -385.222265) (xy 159.949105 -385.190441) (xy 159.975738 -385.163337)
			(xy 160.007193 -385.142018) (xy 160.042235 -385.127321) (xy 160.079487 -385.119824) (xy 160.098486 -385.119372)
			(xy 160.098994 -385.119372) (xy 160.120472 -385.119947) (xy 160.162337 -385.129578) (xy 160.201006 -385.14829)
			(xy 160.21812 -385.161282) (xy 160.218374 -385.161536) (xy 160.226892 -385.167614) (xy 160.247082 -385.17301)
			(xy 160.25749 -385.17195) (xy 160.342072 -385.159504) (xy 160.360106 -385.148074) (xy 160.365948 -385.139184)
			(xy 160.38032 -385.118909) (xy 160.414496 -385.082835) (xy 160.454056 -385.052762) (xy 160.497959 -385.029483)
			(xy 160.545049 -385.013611) (xy 160.594086 -385.005563) (xy 160.618932 -385.005072) (xy 160.642866 -385.005554)
			(xy 160.69015 -385.013009) (xy 160.735693 -385.027747) (xy 160.778379 -385.049408) (xy 160.817165 -385.077462)
			(xy 160.851101 -385.111221) (xy 160.879357 -385.14986) (xy 160.890712 -385.170934) (xy 160.89122 -385.17195)
			(xy 160.93821 -385.25323) (xy 160.943303 -385.261305) (xy 160.958203 -385.273223) (xy 160.976418 -385.278906)
			(xy 160.985962 -385.27863) (xy 161.077402 -385.271772) (xy 161.086782 -385.270631) (xy 161.103833 -385.262526)
			(xy 161.116835 -385.248836) (xy 161.120836 -385.240276) (xy 161.120836 -385.239768) (xy 161.128241 -385.222267)
			(xy 161.149004 -385.190443) (xy 161.175636 -385.163339) (xy 161.20709 -385.142019) (xy 161.242131 -385.127322)
			(xy 161.279383 -385.119825) (xy 161.298382 -385.119372) (xy 161.29889 -385.119372) (xy 161.320368 -385.119949)
			(xy 161.362233 -385.129579) (xy 161.400902 -385.14829) (xy 161.418016 -385.161282) (xy 161.41827 -385.161536)
			(xy 161.426758 -385.167663) (xy 161.446972 -385.17303) (xy 161.457386 -385.17195) (xy 161.541968 -385.159504)
			(xy 161.560002 -385.148074) (xy 161.565844 -385.139184) (xy 161.580218 -385.118911) (xy 161.614394 -385.082836)
			(xy 161.653953 -385.052763) (xy 161.697856 -385.029484) (xy 161.744945 -385.013612) (xy 161.793982 -385.005563)
			(xy 161.818828 -385.005072) (xy 161.842762 -385.005557) (xy 161.890046 -385.013011) (xy 161.935588 -385.027749)
			(xy 161.978275 -385.04941) (xy 162.017061 -385.077463) (xy 162.050997 -385.111222) (xy 162.079253 -385.14986)
			(xy 162.090608 -385.170934) (xy 162.091116 -385.17195) (xy 162.13836 -385.253738) (xy 162.143509 -385.261754)
			(xy 162.158401 -385.273607) (xy 162.176592 -385.279205) (xy 162.186112 -385.278884) (xy 162.291776 -385.27101)
			(xy 162.315398 -385.253738) (xy 162.320732 -385.240022) (xy 162.328192 -385.222511) (xy 162.348963 -385.190622)
			(xy 162.375618 -385.163459) (xy 162.407109 -385.142089) (xy 162.442198 -385.127353) (xy 162.479504 -385.119831)
			(xy 162.498532 -385.119372) (xy 162.49904 -385.119372) (xy 162.520517 -385.119975) (xy 162.562381 -385.129594)
			(xy 162.601051 -385.148295) (xy 162.618166 -385.161282) (xy 162.61842 -385.161536) (xy 162.626924 -385.167637)
			(xy 162.647125 -385.173019) (xy 162.657536 -385.17195) (xy 162.742118 -385.159504) (xy 162.760152 -385.148074)
			(xy 162.765994 -385.139184) (xy 162.780337 -385.118888) (xy 162.814519 -385.082814) (xy 162.854085 -385.052743)
			(xy 162.897993 -385.029468) (xy 162.945089 -385.013601) (xy 162.99413 -385.005559) (xy 163.018978 -385.005072)
			(xy 163.042913 -385.005516) (xy 163.090199 -385.012978) (xy 163.135743 -385.027723) (xy 163.178429 -385.049391)
			(xy 163.217215 -385.07745) (xy 163.251149 -385.111214) (xy 163.279404 -385.149858) (xy 163.290758 -385.170934)
			(xy 163.291266 -385.17195) (xy 163.338256 -385.25323) (xy 163.343385 -385.261279) (xy 163.358269 -385.273201)
			(xy 163.376469 -385.278897) (xy 163.386008 -385.27863) (xy 163.477448 -385.271772) (xy 163.486822 -385.270595)
			(xy 163.503873 -385.262507) (xy 163.516878 -385.248831) (xy 163.520882 -385.240276) (xy 163.520882 -385.239768)
			(xy 163.52833 -385.222287) (xy 163.549086 -385.190465) (xy 163.57571 -385.163361) (xy 163.607155 -385.142038)
			(xy 163.642188 -385.127336) (xy 163.679432 -385.11983) (xy 163.698428 -385.119372) (xy 163.698936 -385.119372)
			(xy 163.720413 -385.119977) (xy 163.762276 -385.129596) (xy 163.800947 -385.148296) (xy 163.818062 -385.161282)
			(xy 163.818316 -385.161536) (xy 163.826821 -385.167635) (xy 163.847021 -385.173019) (xy 163.857432 -385.17195)
			(xy 163.942014 -385.159504) (xy 163.960048 -385.148074) (xy 163.96589 -385.139184) (xy 163.980236 -385.11889)
			(xy 164.014417 -385.082816) (xy 164.053982 -385.052745) (xy 164.09789 -385.029469) (xy 164.144985 -385.013602)
			(xy 164.194026 -385.00556) (xy 164.218874 -385.005072) (xy 164.242809 -385.005519) (xy 164.290095 -385.012981)
			(xy 164.335638 -385.027726) (xy 164.378325 -385.049392) (xy 164.41711 -385.077451) (xy 164.451045 -385.111215)
			(xy 164.479299 -385.149858) (xy 164.490654 -385.170934) (xy 164.491162 -385.17195) (xy 164.538152 -385.25323)
			(xy 164.543284 -385.261277) (xy 164.558167 -385.273199) (xy 164.576365 -385.278896) (xy 164.585904 -385.27863)
			(xy 164.677344 -385.271772) (xy 164.686718 -385.270592) (xy 164.703769 -385.262506) (xy 164.716774 -385.248831)
			(xy 164.720778 -385.240276) (xy 164.720778 -385.239768) (xy 164.728229 -385.222289) (xy 164.748985 -385.190467)
			(xy 164.775608 -385.163362) (xy 164.807052 -385.14204) (xy 164.842084 -385.127336) (xy 164.879328 -385.11983)
			(xy 164.898324 -385.119372) (xy 164.898578 -385.119372) (xy 164.920154 -385.119962) (xy 164.962207 -385.129639)
			(xy 165.001036 -385.148465) (xy 165.018212 -385.161536) (xy 165.026594 -385.168394) (xy 165.04666 -385.173728)
			(xy 165.142164 -385.159504) (xy 165.160198 -385.148074) (xy 165.16604 -385.139184) (xy 165.180417 -385.118913)
			(xy 165.214592 -385.082838) (xy 165.254151 -385.052765) (xy 165.298053 -385.029485) (xy 165.345142 -385.013612)
			(xy 165.394178 -385.005564) (xy 165.419024 -385.005072) (xy 165.442958 -385.00556) (xy 165.490242 -385.013014)
			(xy 165.535784 -385.027751) (xy 165.578471 -385.049411) (xy 165.617257 -385.077464) (xy 165.651193 -385.111222)
			(xy 165.679449 -385.14986) (xy 165.690804 -385.170934) (xy 165.691312 -385.17195) (xy 166.083742 -385.850892)
			(xy 166.096567 -385.874224) (xy 166.114787 -385.924247) (xy 166.124047 -385.976673) (xy 166.124636 -386.003292)
			(xy 166.124131 -386.027269) (xy 166.116635 -386.074633) (xy 166.101826 -386.120243) (xy 166.080068 -386.162977)
			(xy 166.051896 -386.201783) (xy 166.018004 -386.235708) (xy 165.979224 -386.263916) (xy 165.936511 -386.285715)
			(xy 165.890916 -386.300567) (xy 165.843558 -386.308108) (xy 165.819582 -386.3086) (xy 165.819074 -386.3086)
			(xy 165.795499 -386.308227) (xy 165.74891 -386.300982) (xy 165.703991 -386.286652) (xy 165.661813 -386.26558)
			(xy 165.62338 -386.238267) (xy 165.589609 -386.205365) (xy 165.561304 -386.167657) (xy 165.549834 -386.147056)
			(xy 165.549326 -386.146294) (xy 165.535864 -386.122926) (xy 165.530463 -386.114487) (xy 165.514581 -386.1023)
			(xy 165.495245 -386.097121) (xy 165.475398 -386.099739) (xy 165.466522 -386.104384) (xy 165.457378 -386.109718)
			(xy 165.451282 -386.1181) (xy 165.440333 -386.131982) (xy 165.414256 -386.155848) (xy 165.384235 -386.174513)
			(xy 165.351294 -386.18734) (xy 165.316556 -386.193891) (xy 165.298882 -386.1943) (xy 165.298374 -386.1943)
			(xy 165.279599 -386.193827) (xy 165.24277 -386.186504) (xy 165.208074 -386.172144) (xy 165.176842 -386.151298)
			(xy 165.150272 -386.124764) (xy 165.129382 -386.093561) (xy 165.114973 -386.058885) (xy 165.107599 -386.022066)
			(xy 165.107112 -386.003292) (xy 165.107588 -385.984178) (xy 165.115149 -385.946707) (xy 165.130008 -385.911486)
			(xy 165.151571 -385.879921) (xy 165.178978 -385.853272) (xy 165.211135 -385.832604) (xy 165.228778 -385.825238)
			(xy 165.238938 -385.821174) (xy 165.254432 -385.805426) (xy 165.283642 -385.722114) (xy 165.286867 -385.711535)
			(xy 165.284889 -385.689532) (xy 165.279832 -385.679696) (xy 165.151562 -385.457954) (xy 165.13937 -385.43357)
			(xy 165.134586 -385.424024) (xy 165.118789 -385.409692) (xy 165.098534 -385.403006) (xy 165.077309 -385.405118)
			(xy 165.058769 -385.415663) (xy 165.051994 -385.423918) (xy 165.041067 -385.438027) (xy 165.014901 -385.462288)
			(xy 164.984687 -385.481272) (xy 164.951475 -385.494317) (xy 164.916419 -385.500973) (xy 164.898578 -385.501388)
			(xy 164.89807 -385.501388) (xy 164.89119 -385.501389) (xy 164.87746 -385.500496) (xy 164.870638 -385.49961)
			(xy 164.85616 -385.497324) (xy 164.82949 -385.509008) (xy 164.7698 -385.596892) (xy 164.764816 -385.605047)
			(xy 164.760634 -385.623677) (xy 164.763556 -385.642546) (xy 164.768022 -385.650994) (xy 164.883592 -385.850892)
			(xy 164.896324 -385.87421) (xy 164.914419 -385.924158) (xy 164.923635 -385.976477) (xy 164.924232 -386.003038)
			(xy 164.924232 -386.003292) (xy 164.92373 -386.027282) (xy 164.916226 -386.074671) (xy 164.901401 -386.120303)
			(xy 164.879621 -386.163054) (xy 164.851421 -386.201871) (xy 164.817496 -386.2358) (xy 164.778681 -386.264004)
			(xy 164.735932 -386.285789) (xy 164.690302 -386.300618) (xy 164.642914 -386.308128) (xy 164.618924 -386.3086)
			(xy 164.595351 -386.308187) (xy 164.548763 -386.300949) (xy 164.503845 -386.286627) (xy 164.461667 -386.265561)
			(xy 164.423233 -386.238255) (xy 164.389461 -386.205358) (xy 164.361155 -386.167655) (xy 164.349684 -386.147056)
			(xy 164.349176 -386.146294) (xy 164.335714 -386.122926) (xy 164.330364 -386.114449) (xy 164.314464 -386.102263)
			(xy 164.29511 -386.097093) (xy 164.275251 -386.099729) (xy 164.266372 -386.104384) (xy 164.257228 -386.109718)
			(xy 164.251132 -386.1181) (xy 164.240212 -386.132005) (xy 164.214127 -386.15587) (xy 164.184099 -386.174531)
			(xy 164.151152 -386.187352) (xy 164.116409 -386.193895) (xy 164.098732 -386.1943) (xy 164.098224 -386.1943)
			(xy 164.079454 -386.193857) (xy 164.042635 -386.186537) (xy 164.007951 -386.172174) (xy 163.976736 -386.15132)
			(xy 163.95019 -386.124776) (xy 163.929334 -386.093563) (xy 163.914968 -386.058881) (xy 163.907645 -386.022062)
			(xy 163.907216 -386.003292) (xy 163.90768 -385.984197) (xy 163.915249 -385.946765) (xy 163.930085 -385.911575)
			(xy 163.9516 -385.880023) (xy 163.97894 -385.853359) (xy 164.011021 -385.832641) (xy 164.028628 -385.825238)
			(xy 164.038788 -385.821174) (xy 164.054282 -385.805426) (xy 164.083492 -385.722114) (xy 164.086723 -385.711536)
			(xy 164.084743 -385.689531) (xy 164.079682 -385.679696) (xy 163.951412 -385.457954) (xy 163.939474 -385.433824)
			(xy 163.934687 -385.424283) (xy 163.918887 -385.409963) (xy 163.898637 -385.403282) (xy 163.877417 -385.40539)
			(xy 163.858877 -385.415924) (xy 163.852098 -385.424172) (xy 163.841161 -385.438257) (xy 163.814976 -385.462461)
			(xy 163.784756 -385.481388) (xy 163.75155 -385.494382) (xy 163.716511 -385.500992) (xy 163.698682 -385.501388)
			(xy 163.698174 -385.501388) (xy 163.691294 -385.501389) (xy 163.677564 -385.500496) (xy 163.670742 -385.49961)
			(xy 163.656264 -385.497324) (xy 163.629594 -385.509008) (xy 163.569904 -385.596892) (xy 163.56492 -385.605047)
			(xy 163.560738 -385.623677) (xy 163.56366 -385.642547) (xy 163.568126 -385.650994) (xy 163.683696 -385.850892)
			(xy 163.696428 -385.87421) (xy 163.714523 -385.924158) (xy 163.723739 -385.976477) (xy 163.724336 -386.003038)
			(xy 163.724336 -386.003292) (xy 163.72383 -386.027282) (xy 163.716326 -386.07467) (xy 163.701501 -386.120302)
			(xy 163.679721 -386.163053) (xy 163.651522 -386.20187) (xy 163.617597 -386.235798) (xy 163.578783 -386.264002)
			(xy 163.536035 -386.285788) (xy 163.490405 -386.300618) (xy 163.443018 -386.308127) (xy 163.419028 -386.3086)
			(xy 163.395455 -386.308184) (xy 163.348868 -386.300946) (xy 163.30395 -386.286625) (xy 163.261771 -386.26556)
			(xy 163.223338 -386.238254) (xy 163.189565 -386.205357) (xy 163.161259 -386.167654) (xy 163.149788 -386.147056)
			(xy 163.14928 -386.146294) (xy 163.135818 -386.122926) (xy 163.130464 -386.114452) (xy 163.114565 -386.102266)
			(xy 163.095212 -386.097096) (xy 163.075355 -386.099729) (xy 163.066476 -386.104384) (xy 163.057332 -386.109718)
			(xy 163.051236 -386.1181) (xy 163.040313 -386.132003) (xy 163.01423 -386.155868) (xy 162.984202 -386.174529)
			(xy 162.951255 -386.187351) (xy 162.916512 -386.193895) (xy 162.898836 -386.1943) (xy 162.898328 -386.1943)
			(xy 162.879558 -386.193853) (xy 162.842739 -386.186534) (xy 162.808055 -386.172172) (xy 162.776841 -386.151318)
			(xy 162.750295 -386.124775) (xy 162.729438 -386.093562) (xy 162.715072 -386.05888) (xy 162.707749 -386.022062)
			(xy 162.70732 -386.003292) (xy 162.707782 -385.984197) (xy 162.715351 -385.946765) (xy 162.730187 -385.911575)
			(xy 162.751702 -385.880022) (xy 162.779043 -385.853358) (xy 162.811125 -385.832641) (xy 162.828732 -385.825238)
			(xy 162.838892 -385.821174) (xy 162.854386 -385.805426) (xy 162.883596 -385.722114) (xy 162.886827 -385.711536)
			(xy 162.884847 -385.689531) (xy 162.879786 -385.679696) (xy 162.751516 -385.457954) (xy 162.739578 -385.433824)
			(xy 162.734785 -385.424287) (xy 162.718987 -385.409966) (xy 162.698738 -385.403286) (xy 162.67752 -385.405392)
			(xy 162.658981 -385.415925) (xy 162.652202 -385.424172) (xy 162.64128 -385.438237) (xy 162.615139 -385.462413)
			(xy 162.584973 -385.481329) (xy 162.551825 -385.494332) (xy 162.516843 -385.50097) (xy 162.49904 -385.501388)
			(xy 162.498532 -385.501388) (xy 162.470846 -385.499356) (xy 162.470592 -385.499356) (xy 162.461122 -385.498419)
			(xy 162.442609 -385.502746) (xy 162.426957 -385.513539) (xy 162.421316 -385.5212) (xy 162.369754 -385.596892)
			(xy 162.364772 -385.605047) (xy 162.360594 -385.623677) (xy 162.363513 -385.642546) (xy 162.367976 -385.650994)
			(xy 162.483546 -385.850892) (xy 162.496371 -385.874224) (xy 162.514591 -385.924247) (xy 162.523851 -385.976673)
			(xy 162.52444 -386.003292) (xy 162.523931 -386.027269) (xy 162.516435 -386.074633) (xy 162.501626 -386.120242)
			(xy 162.479869 -386.162976) (xy 162.451698 -386.201782) (xy 162.417806 -386.235706) (xy 162.379027 -386.263915)
			(xy 162.336314 -386.285714) (xy 162.290719 -386.300566) (xy 162.243362 -386.308108) (xy 162.219386 -386.3086)
			(xy 162.218878 -386.3086) (xy 162.195303 -386.308224) (xy 162.148714 -386.300979) (xy 162.103795 -386.28665)
			(xy 162.061617 -386.265579) (xy 162.023184 -386.238266) (xy 161.989413 -386.205364) (xy 161.961108 -386.167657)
			(xy 161.949638 -386.147056) (xy 161.94913 -386.146294) (xy 161.935668 -386.122926) (xy 161.930263 -386.11449)
			(xy 161.914383 -386.102303) (xy 161.895047 -386.097123) (xy 161.875202 -386.09974) (xy 161.866326 -386.104384)
			(xy 161.857182 -386.109718) (xy 161.851086 -386.1181) (xy 161.840135 -386.13198) (xy 161.814058 -386.155846)
			(xy 161.784038 -386.174511) (xy 161.751098 -386.187339) (xy 161.71636 -386.19389) (xy 161.698686 -386.1943)
			(xy 161.698178 -386.1943) (xy 161.679403 -386.193824) (xy 161.642574 -386.186501) (xy 161.607878 -386.172142)
			(xy 161.576646 -386.151296) (xy 161.550076 -386.124763) (xy 161.529186 -386.09356) (xy 161.514777 -386.058885)
			(xy 161.507403 -386.022066) (xy 161.506916 -386.003292) (xy 161.50739 -385.984178) (xy 161.514951 -385.946706)
			(xy 161.52981 -385.911485) (xy 161.551373 -385.87992) (xy 161.578781 -385.853272) (xy 161.610938 -385.832603)
			(xy 161.628582 -385.825238) (xy 161.638742 -385.821174) (xy 161.654236 -385.805426) (xy 161.683446 -385.722114)
			(xy 161.686671 -385.711535) (xy 161.684693 -385.689532) (xy 161.679636 -385.679696) (xy 161.551366 -385.457954)
			(xy 161.539428 -385.433824) (xy 161.534565 -385.424328) (xy 161.518787 -385.410013) (xy 161.498559 -385.403329)
			(xy 161.477358 -385.405423) (xy 161.458829 -385.415936) (xy 161.452052 -385.424172) (xy 161.441084 -385.438232)
			(xy 161.414907 -385.462437) (xy 161.384695 -385.481369) (xy 161.351496 -385.494369) (xy 161.316463 -385.500987)
			(xy 161.298636 -385.501388) (xy 161.298128 -385.501388) (xy 161.291248 -385.501383) (xy 161.277519 -385.500494)
			(xy 161.270696 -385.49961) (xy 161.256218 -385.497324) (xy 161.229548 -385.509008) (xy 161.169858 -385.596892)
			(xy 161.164876 -385.605047) (xy 161.160698 -385.623677) (xy 161.163617 -385.642546) (xy 161.16808 -385.650994)
			(xy 161.28365 -385.850892) (xy 161.296476 -385.874224) (xy 161.314695 -385.924247) (xy 161.323955 -385.976673)
			(xy 161.324544 -386.003292) (xy 161.324031 -386.027269) (xy 161.316535 -386.074632) (xy 161.301727 -386.120241)
			(xy 161.279969 -386.162974) (xy 161.251799 -386.20178) (xy 161.217907 -386.235705) (xy 161.179129 -386.263913)
			(xy 161.136417 -386.285712) (xy 161.090822 -386.300566) (xy 161.043466 -386.308108) (xy 161.01949 -386.3086)
			(xy 161.018982 -386.3086) (xy 160.995407 -386.308221) (xy 160.948819 -386.300977) (xy 160.9039 -386.286648)
			(xy 160.861721 -386.265577) (xy 160.823288 -386.238265) (xy 160.789517 -386.205364) (xy 160.761212 -386.167657)
			(xy 160.749742 -386.147056) (xy 160.749234 -386.146294) (xy 160.735772 -386.122926) (xy 160.730363 -386.114493)
			(xy 160.714484 -386.102306) (xy 160.69515 -386.097126) (xy 160.675306 -386.099741) (xy 160.66643 -386.104384)
			(xy 160.657286 -386.109718) (xy 160.65119 -386.1181) (xy 160.640237 -386.131978) (xy 160.614161 -386.155845)
			(xy 160.584141 -386.17451) (xy 160.551201 -386.187338) (xy 160.516464 -386.19389) (xy 160.49879 -386.1943)
			(xy 160.498282 -386.1943) (xy 160.479507 -386.19382) (xy 160.442678 -386.186498) (xy 160.407983 -386.17214)
			(xy 160.376751 -386.151294) (xy 160.35018 -386.124762) (xy 160.32929 -386.09356) (xy 160.314881 -386.058884)
			(xy 160.307507 -386.022066) (xy 160.30702 -386.003292) (xy 160.307491 -385.984178) (xy 160.315053 -385.946706)
			(xy 160.329912 -385.911484) (xy 160.351476 -385.87992) (xy 160.378884 -385.853271) (xy 160.411042 -385.832603)
			(xy 160.428686 -385.825238) (xy 160.438846 -385.821174) (xy 160.45434 -385.805426) (xy 160.48355 -385.722114)
			(xy 160.486774 -385.711535) (xy 160.484796 -385.689532) (xy 160.47974 -385.679696) (xy 160.35147 -385.457954)
			(xy 160.339532 -385.433824) (xy 160.334663 -385.424331) (xy 160.318887 -385.410017) (xy 160.29866 -385.403332)
			(xy 160.277461 -385.405425) (xy 160.258933 -385.415937) (xy 160.252156 -385.424172) (xy 160.241185 -385.43823)
			(xy 160.215009 -385.462436) (xy 160.184798 -385.481367) (xy 160.1516 -385.494368) (xy 160.116566 -385.500987)
			(xy 160.09874 -385.501388) (xy 160.098232 -385.501388) (xy 160.091352 -385.501382) (xy 160.077623 -385.500494)
			(xy 160.0708 -385.49961) (xy 160.056322 -385.497324) (xy 160.029652 -385.509008) (xy 159.969962 -385.596892)
			(xy 159.96498 -385.605047) (xy 159.960801 -385.623677) (xy 159.963721 -385.642546) (xy 159.968184 -385.650994)
			(xy 160.083754 -385.850892) (xy 160.09658 -385.874224) (xy 160.114799 -385.924247) (xy 160.124059 -385.976673)
			(xy 160.124648 -386.003292) (xy 160.124131 -386.027268) (xy 160.116636 -386.074632) (xy 160.101827 -386.12024)
			(xy 160.08007 -386.162973) (xy 160.0519 -386.201779) (xy 160.018009 -386.235703) (xy 159.979231 -386.263912)
			(xy 159.93652 -386.285711) (xy 159.890926 -386.300565) (xy 159.84357 -386.308107) (xy 159.819594 -386.3086)
			(xy 159.819086 -386.3086) (xy 159.795512 -386.308217) (xy 159.748923 -386.300974) (xy 159.704004 -386.286646)
			(xy 159.661826 -386.265576) (xy 159.623393 -386.238264) (xy 159.589621 -386.205363) (xy 159.561316 -386.167656)
			(xy 159.549846 -386.147056) (xy 159.549338 -386.146294) (xy 159.535876 -386.122926) (xy 159.530463 -386.114496)
			(xy 159.514586 -386.102309) (xy 159.495253 -386.097128) (xy 159.47541 -386.099742) (xy 159.466534 -386.104384)
			(xy 159.45739 -386.109718) (xy 159.451294 -386.1181) (xy 159.440338 -386.131976) (xy 159.414263 -386.155843)
			(xy 159.384244 -386.174509) (xy 159.351304 -386.187337) (xy 159.316568 -386.19389) (xy 159.298894 -386.1943)
			(xy 159.298386 -386.1943) (xy 159.279611 -386.193816) (xy 159.242783 -386.186496) (xy 159.208087 -386.172137)
			(xy 159.176855 -386.151293) (xy 159.150284 -386.124761) (xy 159.129394 -386.093559) (xy 159.114985 -386.058884)
			(xy 159.107611 -386.022066) (xy 159.107124 -386.003292) (xy 159.107593 -385.984178) (xy 159.115154 -385.946705)
			(xy 159.130014 -385.911484) (xy 159.151578 -385.879919) (xy 159.178987 -385.853271) (xy 159.211146 -385.832603)
			(xy 159.22879 -385.825238) (xy 159.23895 -385.821174) (xy 159.254444 -385.805426) (xy 159.283654 -385.722114)
			(xy 159.286878 -385.711535) (xy 159.2849 -385.689532) (xy 159.279844 -385.679696) (xy 159.151574 -385.457954)
			(xy 159.139636 -385.433824) (xy 159.134762 -385.424334) (xy 159.118987 -385.410021) (xy 159.098762 -385.403336)
			(xy 159.077564 -385.405428) (xy 159.059037 -385.415938) (xy 159.05226 -385.424172) (xy 159.041304 -385.438209)
			(xy 159.015172 -385.462388) (xy 158.985014 -385.481309) (xy 158.951874 -385.494318) (xy 158.916898 -385.500965)
			(xy 158.899098 -385.501388) (xy 158.89859 -385.501388) (xy 158.870904 -385.499356) (xy 158.87065 -385.499356)
			(xy 158.861182 -385.498385) (xy 158.842665 -385.502727) (xy 158.827013 -385.513533) (xy 158.821374 -385.5212)
			(xy 158.769812 -385.596892) (xy 158.764828 -385.605047) (xy 158.760645 -385.623677) (xy 158.763567 -385.642547)
			(xy 158.768034 -385.650994) (xy 158.883604 -385.850892) (xy 158.896337 -385.87421) (xy 158.914431 -385.924158)
			(xy 158.923647 -385.976477) (xy 158.924244 -386.003038) (xy 158.924244 -386.003292) (xy 158.92373 -386.027281)
			(xy 158.916226 -386.074669) (xy 158.901402 -386.1203) (xy 158.879623 -386.16305) (xy 158.851424 -386.201867)
			(xy 158.817501 -386.235796) (xy 158.778688 -386.264) (xy 158.735941 -386.285785) (xy 158.690312 -386.300616)
			(xy 158.642925 -386.308127) (xy 158.618936 -386.3086) (xy 158.595363 -386.308177) (xy 158.548776 -386.300941)
			(xy 158.503858 -386.286621) (xy 158.46168 -386.265557) (xy 158.423246 -386.238252) (xy 158.389474 -386.205356)
			(xy 158.361167 -386.167654) (xy 158.349696 -386.147056) (xy 158.349188 -386.146294) (xy 158.335726 -386.122926)
			(xy 158.330364 -386.114458) (xy 158.314468 -386.102272) (xy 158.295118 -386.0971) (xy 158.275262 -386.099731)
			(xy 158.266384 -386.104384) (xy 158.25724 -386.109718) (xy 158.251144 -386.1181) (xy 158.240217 -386.132)
			(xy 158.214134 -386.155865) (xy 158.184108 -386.174527) (xy 158.151162 -386.187349) (xy 158.11642 -386.193894)
			(xy 158.098744 -386.1943) (xy 158.098236 -386.1943) (xy 158.079466 -386.193846) (xy 158.042647 -386.186528)
			(xy 158.007964 -386.172167) (xy 157.976749 -386.151315) (xy 157.950203 -386.124773) (xy 157.929346 -386.093561)
			(xy 157.91498 -386.058879) (xy 157.907657 -386.022062) (xy 157.907228 -386.003292) (xy 157.907685 -385.984197)
			(xy 157.915254 -385.946764) (xy 157.930091 -385.911573) (xy 157.951607 -385.880021) (xy 157.978949 -385.853357)
			(xy 158.011032 -385.83264) (xy 158.02864 -385.825238) (xy 158.0388 -385.821174) (xy 158.054294 -385.805426)
			(xy 158.083504 -385.722114) (xy 158.086734 -385.711536) (xy 158.084754 -385.689532) (xy 158.079694 -385.679696)
			(xy 157.951424 -385.457954) (xy 157.939486 -385.433824) (xy 157.934682 -385.424293) (xy 157.918887 -385.409974)
			(xy 157.898642 -385.403292) (xy 157.877426 -385.405397) (xy 157.858888 -385.415927) (xy 157.85211 -385.424172)
			(xy 157.841166 -385.438252) (xy 157.814983 -385.462456) (xy 157.784765 -385.481384) (xy 157.751561 -385.494379)
			(xy 157.716522 -385.500991) (xy 157.698694 -385.501388) (xy 157.698186 -385.501388) (xy 157.691306 -385.501387)
			(xy 157.677576 -385.500496) (xy 157.670754 -385.49961) (xy 157.656276 -385.497324) (xy 157.629606 -385.509008)
			(xy 157.569916 -385.596892) (xy 157.564931 -385.605047) (xy 157.560748 -385.623677) (xy 157.563671 -385.642547)
			(xy 157.568138 -385.650994) (xy 157.683708 -385.850892) (xy 157.696441 -385.87421) (xy 157.714535 -385.924158)
			(xy 157.723751 -385.976477) (xy 157.724348 -386.003038) (xy 157.724348 -386.003292) (xy 157.72383 -386.027281)
			(xy 157.716326 -386.074669) (xy 157.701503 -386.120299) (xy 157.679724 -386.163049) (xy 157.651525 -386.201866)
			(xy 157.617603 -386.235794) (xy 157.57879 -386.263998) (xy 157.536043 -386.285784) (xy 157.490415 -386.300615)
			(xy 157.443029 -386.308126) (xy 157.41904 -386.3086) (xy 157.395467 -386.308174) (xy 157.34888 -386.300939)
			(xy 157.303963 -386.286618) (xy 157.261784 -386.265555) (xy 157.223351 -386.238251) (xy 157.189578 -386.205355)
			(xy 157.161271 -386.167654) (xy 157.1498 -386.147056) (xy 157.149292 -386.146294) (xy 157.13583 -386.122926)
			(xy 157.130464 -386.114461) (xy 157.11457 -386.102275) (xy 157.095221 -386.097102) (xy 157.075366 -386.099732)
			(xy 157.066488 -386.104384) (xy 157.057344 -386.109718) (xy 157.051248 -386.1181) (xy 157.040318 -386.131998)
			(xy 157.014236 -386.155863) (xy 156.984211 -386.174525) (xy 156.951265 -386.187348) (xy 156.916524 -386.193894)
			(xy 156.898848 -386.1943) (xy 156.89834 -386.1943) (xy 156.879571 -386.193842) (xy 156.842752 -386.186525)
			(xy 156.808068 -386.172165) (xy 156.776853 -386.151313) (xy 156.750307 -386.124771) (xy 156.72945 -386.09356)
			(xy 156.715084 -386.058879) (xy 156.707761 -386.022061) (xy 156.707332 -386.003292) (xy 156.707786 -385.984197)
			(xy 156.715356 -385.946764) (xy 156.730193 -385.911573) (xy 156.75171 -385.88002) (xy 156.779052 -385.853357)
			(xy 156.811136 -385.83264) (xy 156.828744 -385.825238) (xy 156.838904 -385.821174) (xy 156.854398 -385.805426)
			(xy 156.883608 -385.722114) (xy 156.886837 -385.711536) (xy 156.884858 -385.689532) (xy 156.879798 -385.679696)
			(xy 156.751528 -385.457954) (xy 156.73959 -385.433824) (xy 156.73478 -385.424296) (xy 156.718987 -385.409978)
			(xy 156.698743 -385.403296) (xy 156.677529 -385.4054) (xy 156.658992 -385.415927) (xy 156.652214 -385.424172)
			(xy 156.641285 -385.438231) (xy 156.615146 -385.462408) (xy 156.584981 -385.481325) (xy 156.551835 -385.494329)
			(xy 156.516854 -385.500969) (xy 156.499052 -385.501388) (xy 156.498544 -385.501388) (xy 156.470858 -385.499356)
			(xy 156.470604 -385.499356) (xy 156.461134 -385.498428) (xy 156.442622 -385.502752) (xy 156.42697 -385.51354)
			(xy 156.421328 -385.5212) (xy 156.369766 -385.596892) (xy 156.364784 -385.605047) (xy 156.360605 -385.623677)
			(xy 156.363524 -385.642546) (xy 156.367988 -385.650994) (xy 156.483558 -385.850892) (xy 156.496384 -385.874224)
			(xy 156.514604 -385.924247) (xy 156.523863 -385.976673) (xy 156.524452 -386.003292) (xy 156.523931 -386.027268)
			(xy 156.516436 -386.074631) (xy 156.501627 -386.120239) (xy 156.479871 -386.162972) (xy 156.451701 -386.201778)
			(xy 156.417811 -386.235702) (xy 156.379033 -386.263911) (xy 156.336323 -386.28571) (xy 156.290729 -386.300564)
			(xy 156.243374 -386.308107) (xy 156.219398 -386.3086) (xy 156.21889 -386.3086) (xy 156.195316 -386.308214)
			(xy 156.148727 -386.300971) (xy 156.103808 -386.286644) (xy 156.06163 -386.265574) (xy 156.023197 -386.238263)
			(xy 155.989426 -386.205363) (xy 155.96112 -386.167656) (xy 155.94965 -386.147056) (xy 155.949142 -386.146294)
			(xy 155.93568 -386.122926) (xy 155.930263 -386.114499) (xy 155.914387 -386.102312) (xy 155.895056 -386.09713)
			(xy 155.875213 -386.099743) (xy 155.866338 -386.104384) (xy 155.857194 -386.109718) (xy 155.851098 -386.1181)
			(xy 155.84014 -386.131974) (xy 155.814065 -386.155841) (xy 155.784047 -386.174507) (xy 155.751108 -386.187336)
			(xy 155.716372 -386.193889) (xy 155.698698 -386.1943) (xy 155.69819 -386.1943) (xy 155.679416 -386.193812)
			(xy 155.642587 -386.186492) (xy 155.607891 -386.172135) (xy 155.576659 -386.151291) (xy 155.550089 -386.124759)
			(xy 155.529199 -386.093558) (xy 155.51479 -386.058883) (xy 155.507416 -386.022066) (xy 155.506928 -386.003292)
			(xy 155.507394 -385.984177) (xy 155.514956 -385.946705) (xy 155.529816 -385.911483) (xy 155.551381 -385.879918)
			(xy 155.57879 -385.85327) (xy 155.61095 -385.832602) (xy 155.628594 -385.825238) (xy 155.638754 -385.821174)
			(xy 155.654248 -385.805426) (xy 155.683458 -385.722114) (xy 155.686681 -385.711535) (xy 155.684704 -385.689532)
			(xy 155.679648 -385.679696) (xy 155.551378 -385.457954) (xy 155.53944 -385.433824) (xy 155.53456 -385.424338)
			(xy 155.518787 -385.410025) (xy 155.498564 -385.403339) (xy 155.477367 -385.40543) (xy 155.458841 -385.415939)
			(xy 155.452064 -385.424172) (xy 155.441089 -385.438226) (xy 155.414913 -385.462432) (xy 155.384703 -385.481364)
			(xy 155.351506 -385.494366) (xy 155.316474 -385.500986) (xy 155.298648 -385.501388) (xy 155.29814 -385.501388)
			(xy 155.29126 -385.501381) (xy 155.277531 -385.500494) (xy 155.270708 -385.49961) (xy 155.25623 -385.497324)
			(xy 155.22956 -385.509008) (xy 155.16987 -385.596892) (xy 155.164887 -385.605047) (xy 155.160708 -385.623677)
			(xy 155.163628 -385.642546) (xy 155.168092 -385.650994) (xy 155.283662 -385.850892) (xy 155.296489 -385.874224)
			(xy 155.314708 -385.924247) (xy 155.323967 -385.976673) (xy 155.324556 -386.003292) (xy 155.324031 -386.027268)
			(xy 155.316536 -386.07463) (xy 155.301728 -386.120239) (xy 155.279972 -386.162971) (xy 155.251802 -386.201776)
			(xy 155.217912 -386.235701) (xy 155.179135 -386.263909) (xy 155.136425 -386.285709) (xy 155.090832 -386.300563)
			(xy 155.043477 -386.308107) (xy 155.019502 -386.3086) (xy 155.018994 -386.3086) (xy 154.99542 -386.308211)
			(xy 154.948831 -386.300969) (xy 154.903913 -386.286642) (xy 154.861734 -386.265573) (xy 154.823301 -386.238262)
			(xy 154.78953 -386.205362) (xy 154.761224 -386.167656) (xy 154.749754 -386.147056) (xy 154.749246 -386.146294)
			(xy 154.735784 -386.122926) (xy 154.730363 -386.114502) (xy 154.714489 -386.102315) (xy 154.695159 -386.097132)
			(xy 154.675317 -386.099743) (xy 154.666442 -386.104384) (xy 154.657298 -386.109718) (xy 154.651202 -386.1181)
			(xy 154.640242 -386.131972) (xy 154.614168 -386.155839) (xy 154.58415 -386.174506) (xy 154.551211 -386.187335)
			(xy 154.516476 -386.193889) (xy 154.498802 -386.1943) (xy 154.498294 -386.1943) (xy 154.47952 -386.193809)
			(xy 154.442691 -386.186489) (xy 154.407996 -386.172133) (xy 154.376764 -386.151289) (xy 154.350193 -386.124758)
			(xy 154.329303 -386.093557) (xy 154.314894 -386.058883) (xy 154.30752 -386.022066) (xy 154.307032 -386.003292)
			(xy 154.307496 -385.984177) (xy 154.315058 -385.946704) (xy 154.329918 -385.911482) (xy 154.351483 -385.879917)
			(xy 154.378893 -385.853269) (xy 154.411053 -385.832602) (xy 154.428698 -385.825238) (xy 154.438858 -385.821174)
			(xy 154.454352 -385.805426) (xy 154.483562 -385.722114) (xy 154.486785 -385.711535) (xy 154.484808 -385.689532)
			(xy 154.479752 -385.679696) (xy 154.351482 -385.457954) (xy 154.339544 -385.433824) (xy 154.334799 -385.424258)
			(xy 154.318987 -385.409934) (xy 154.298724 -385.403256) (xy 154.277494 -385.405372) (xy 154.258947 -385.415917)
			(xy 154.252168 -385.424172) (xy 154.241191 -385.438224) (xy 154.215016 -385.46243) (xy 154.184806 -385.481363)
			(xy 154.15161 -385.494365) (xy 154.116578 -385.500986) (xy 154.098752 -385.501388) (xy 154.098244 -385.501388)
			(xy 154.091364 -385.501381) (xy 154.077635 -385.500494) (xy 154.070812 -385.49961) (xy 154.056334 -385.497324)
			(xy 154.029664 -385.509008) (xy 153.969974 -385.596892) (xy 153.964991 -385.605047) (xy 153.960811 -385.623677)
			(xy 153.963732 -385.642546) (xy 153.968196 -385.650994) (xy 154.083766 -385.850892) (xy 154.096593 -385.874223)
			(xy 154.114812 -385.924247) (xy 154.124071 -385.976673) (xy 154.12466 -386.003292) (xy 154.124231 -386.027273)
			(xy 154.116732 -386.074644) (xy 154.101919 -386.120261) (xy 154.080154 -386.162999) (xy 154.051974 -386.201809)
			(xy 154.018072 -386.235735) (xy 153.979282 -386.263942) (xy 153.936559 -386.285737) (xy 153.890953 -386.300582)
			(xy 153.843586 -386.308114) (xy 153.819606 -386.3086) (xy 153.819098 -386.3086) (xy 153.795524 -386.308208)
			(xy 153.748936 -386.300966) (xy 153.704017 -386.28664) (xy 153.661839 -386.265571) (xy 153.623406 -386.238261)
			(xy 153.589634 -386.205361) (xy 153.561328 -386.167656) (xy 153.549858 -386.147056) (xy 153.54935 -386.146294)
			(xy 153.535888 -386.122926) (xy 153.530463 -386.114504) (xy 153.51459 -386.102318) (xy 153.495261 -386.097134)
			(xy 153.475421 -386.099744) (xy 153.466546 -386.104384) (xy 153.457402 -386.109718) (xy 153.451306 -386.1181)
			(xy 153.4404 -386.132018) (xy 153.414312 -386.155881) (xy 153.384281 -386.17454) (xy 153.35133 -386.187358)
			(xy 153.316584 -386.193897) (xy 153.298906 -386.1943) (xy 153.298398 -386.1943) (xy 153.279624 -386.193805)
			(xy 153.242796 -386.186486) (xy 153.2081 -386.17213) (xy 153.176868 -386.151287) (xy 153.150297 -386.124757)
			(xy 153.129407 -386.093556) (xy 153.114998 -386.058883) (xy 153.107624 -386.022065) (xy 153.107136 -386.003292)
			(xy 153.107597 -385.984177) (xy 153.115159 -385.946704) (xy 153.13002 -385.911482) (xy 153.151586 -385.879917)
			(xy 153.178996 -385.853269) (xy 153.211157 -385.832602) (xy 153.228802 -385.825238) (xy 153.238962 -385.821174)
			(xy 153.254456 -385.805426) (xy 153.283666 -385.722114) (xy 153.286889 -385.711535) (xy 153.284911 -385.689532)
			(xy 153.279856 -385.679696) (xy 153.151586 -385.457954) (xy 153.139648 -385.433824) (xy 153.134898 -385.424262)
			(xy 153.119087 -385.409938) (xy 153.098826 -385.403259) (xy 153.077597 -385.405374) (xy 153.059051 -385.415918)
			(xy 153.052272 -385.424172) (xy 153.041367 -385.438251) (xy 153.015222 -385.462426) (xy 152.985051 -385.48134)
			(xy 152.9519 -385.494339) (xy 152.916914 -385.500973) (xy 152.89911 -385.501388) (xy 152.898602 -385.501388)
			(xy 152.870916 -385.499356) (xy 152.870662 -385.499356) (xy 152.861193 -385.498395) (xy 152.842678 -385.502733)
			(xy 152.827026 -385.513535) (xy 152.821386 -385.5212) (xy 152.769824 -385.596892) (xy 152.764839 -385.605047)
			(xy 152.760655 -385.623677) (xy 152.763578 -385.642547) (xy 152.768046 -385.650994) (xy 152.883616 -385.850892)
			(xy 152.89635 -385.874209) (xy 152.914443 -385.924158) (xy 152.923659 -385.976477) (xy 152.924256 -386.003038)
			(xy 152.924256 -386.003292) (xy 152.92373 -386.027281) (xy 152.916227 -386.074667) (xy 152.901403 -386.120297)
			(xy 152.879625 -386.163047) (xy 152.851428 -386.201863) (xy 152.817506 -386.235791) (xy 152.778694 -386.263996)
			(xy 152.735949 -386.285782) (xy 152.690322 -386.300614) (xy 152.642937 -386.308126) (xy 152.618948 -386.3086)
			(xy 152.595375 -386.308168) (xy 152.548789 -386.300933) (xy 152.503871 -386.286614) (xy 152.461693 -386.265552)
			(xy 152.423259 -386.238248) (xy 152.389486 -386.205354) (xy 152.361179 -386.167654) (xy 152.349708 -386.147056)
			(xy 152.3492 -386.146294) (xy 152.335738 -386.122926) (xy 152.330363 -386.114467) (xy 152.314472 -386.102281)
			(xy 152.295126 -386.097107) (xy 152.275274 -386.099734) (xy 152.266396 -386.104384) (xy 152.257252 -386.109718)
			(xy 152.251156 -386.1181) (xy 152.240222 -386.131994) (xy 152.214141 -386.155859) (xy 152.184116 -386.174522)
			(xy 152.151172 -386.187346) (xy 152.116432 -386.193893) (xy 152.098756 -386.1943) (xy 152.098248 -386.1943)
			(xy 152.079479 -386.193835) (xy 152.04266 -386.18652) (xy 152.007977 -386.17216) (xy 151.976762 -386.15131)
			(xy 151.950216 -386.124769) (xy 151.929358 -386.093558) (xy 151.914992 -386.058878) (xy 151.907669 -386.022061)
			(xy 151.90724 -386.003292) (xy 151.907689 -385.984196) (xy 151.915259 -385.946763) (xy 151.930097 -385.911571)
			(xy 151.951615 -385.880018) (xy 151.978958 -385.853355) (xy 152.011043 -385.83264) (xy 152.028652 -385.825238)
			(xy 152.038812 -385.821174) (xy 152.054306 -385.805426) (xy 152.083516 -385.722114) (xy 152.086745 -385.711535)
			(xy 152.084765 -385.689532) (xy 152.079706 -385.679696) (xy 151.951436 -385.457954) (xy 151.939498 -385.433824)
			(xy 151.934677 -385.424303) (xy 151.918887 -385.409985) (xy 151.898646 -385.403303) (xy 151.877435 -385.405404)
			(xy 151.8589 -385.415929) (xy 151.852122 -385.424172) (xy 151.841171 -385.438246) (xy 151.814989 -385.46245)
			(xy 151.784773 -385.481379) (xy 151.751571 -385.494376) (xy 151.716534 -385.50099) (xy 151.698706 -385.501388)
			(xy 151.698198 -385.501388) (xy 151.691318 -385.501386) (xy 151.677588 -385.500495) (xy 151.670766 -385.49961)
			(xy 151.656288 -385.497324) (xy 151.629618 -385.509008) (xy 151.569928 -385.596892) (xy 151.564943 -385.605047)
			(xy 151.560759 -385.623677) (xy 151.563682 -385.642547) (xy 151.56815 -385.650994) (xy 151.68372 -385.850892)
			(xy 151.696454 -385.874209) (xy 151.714548 -385.924158) (xy 151.723763 -385.976476) (xy 151.72436 -386.003038)
			(xy 151.72436 -386.003292) (xy 151.723954 -386.027287) (xy 151.716447 -386.074687) (xy 151.701617 -386.120329)
			(xy 151.679828 -386.163088) (xy 151.651618 -386.201912) (xy 151.617682 -386.235844) (xy 151.578854 -386.264049)
			(xy 151.536092 -386.285832) (xy 151.490448 -386.300657) (xy 151.443047 -386.308157) (xy 151.419052 -386.3086)
			(xy 151.395479 -386.308164) (xy 151.348893 -386.300931) (xy 151.303976 -386.286612) (xy 151.261797 -386.265551)
			(xy 151.223364 -386.238247) (xy 151.189591 -386.205354) (xy 151.161283 -386.167653) (xy 151.149812 -386.147056)
			(xy 151.149304 -386.146294) (xy 151.135842 -386.122926) (xy 151.130463 -386.11447) (xy 151.114574 -386.102284)
			(xy 151.095229 -386.097109) (xy 151.075377 -386.099735) (xy 151.0665 -386.104384) (xy 151.057356 -386.109718)
			(xy 151.05126 -386.1181) (xy 151.040324 -386.131992) (xy 151.014243 -386.155858) (xy 150.984219 -386.174521)
			(xy 150.951276 -386.187345) (xy 150.916535 -386.193893) (xy 150.89886 -386.1943) (xy 150.898352 -386.1943)
			(xy 150.879583 -386.193891) (xy 150.842766 -386.18656) (xy 150.808088 -386.172187) (xy 150.776879 -386.151326)
			(xy 150.750338 -386.124778) (xy 150.729487 -386.093563) (xy 150.715124 -386.05888) (xy 150.707803 -386.022062)
			(xy 150.707344 -386.003292) (xy 150.707791 -385.984196) (xy 150.715361 -385.946762) (xy 150.730199 -385.911571)
			(xy 150.751717 -385.880018) (xy 150.779061 -385.853355) (xy 150.811147 -385.832639) (xy 150.828756 -385.825238)
			(xy 150.838916 -385.821174) (xy 150.85441 -385.805426) (xy 150.88362 -385.722114) (xy 150.886848 -385.711535)
			(xy 150.884869 -385.689532) (xy 150.87981 -385.679696) (xy 150.75154 -385.457954) (xy 150.739602 -385.433824)
			(xy 150.734776 -385.424306) (xy 150.718987 -385.409989) (xy 150.698748 -385.403306) (xy 150.677538 -385.405407)
			(xy 150.659004 -385.41593) (xy 150.652226 -385.424172) (xy 150.64129 -385.438225) (xy 150.615153 -385.462402)
			(xy 150.58499 -385.481321) (xy 150.551845 -385.494326) (xy 150.516866 -385.500968) (xy 150.499064 -385.501388)
			(xy 150.498556 -385.501388) (xy 150.47087 -385.499356) (xy 150.470616 -385.499356) (xy 150.461145 -385.498438)
			(xy 150.442634 -385.502757) (xy 150.426982 -385.513542) (xy 150.42134 -385.5212) (xy 150.369778 -385.596892)
			(xy 150.364795 -385.605047) (xy 150.360615 -385.623677) (xy 150.363535 -385.642546) (xy 150.368 -385.650994)
			(xy 150.48357 -385.850892) (xy 150.496397 -385.874223) (xy 150.514616 -385.924247) (xy 150.523875 -385.976673)
			(xy 150.524464 -386.003292) (xy 150.524031 -386.027273) (xy 150.516533 -386.074644) (xy 150.501719 -386.12026)
			(xy 150.479955 -386.162998) (xy 150.451775 -386.201808) (xy 150.417874 -386.235733) (xy 150.379084 -386.263941)
			(xy 150.336361 -386.285735) (xy 150.290756 -386.300581) (xy 150.24339 -386.308114) (xy 150.21941 -386.3086)
			(xy 150.218902 -386.3086) (xy 150.195328 -386.308205) (xy 150.14874 -386.300963) (xy 150.103821 -386.286638)
			(xy 150.061643 -386.26557) (xy 150.02321 -386.23826) (xy 149.989438 -386.205361) (xy 149.961133 -386.167656)
			(xy 149.949662 -386.147056) (xy 149.949154 -386.146294) (xy 149.935692 -386.122926) (xy 149.930263 -386.114507)
			(xy 149.914391 -386.102321) (xy 149.895064 -386.097137) (xy 149.875225 -386.099745) (xy 149.86635 -386.104384)
			(xy 149.857206 -386.109718) (xy 149.85111 -386.1181) (xy 149.840202 -386.132016) (xy 149.814115 -386.155879)
			(xy 149.784083 -386.174539) (xy 149.751133 -386.187357) (xy 149.716387 -386.193897) (xy 149.69871 -386.1943)
			(xy 149.698202 -386.1943) (xy 149.679428 -386.193802) (xy 149.6426 -386.186484) (xy 149.607904 -386.172128)
			(xy 149.576672 -386.151286) (xy 149.550101 -386.124756) (xy 149.529211 -386.093555) (xy 149.514802 -386.058882)
			(xy 149.507428 -386.022065) (xy 149.50694 -386.003292) (xy 149.507399 -385.984177) (xy 149.514961 -385.946703)
			(xy 149.529822 -385.911481) (xy 149.551388 -385.879916) (xy 149.578799 -385.853268) (xy 149.610961 -385.832602)
			(xy 149.628606 -385.825238) (xy 149.638766 -385.821174) (xy 149.65426 -385.805426) (xy 149.68347 -385.722114)
			(xy 149.686692 -385.711534) (xy 149.684715 -385.689533) (xy 149.67966 -385.679696) (xy 149.55139 -385.457954)
			(xy 149.539452 -385.433824) (xy 149.534696 -385.424265) (xy 149.518887 -385.409942) (xy 149.498627 -385.403263)
			(xy 149.4774 -385.405376) (xy 149.458855 -385.415919) (xy 149.452076 -385.424172) (xy 149.441151 -385.438268)
			(xy 149.414963 -385.462471) (xy 149.38474 -385.481396) (xy 149.351532 -385.494387) (xy 149.31649 -385.500994)
			(xy 149.29866 -385.501388) (xy 149.298152 -385.501388) (xy 149.291272 -385.50138) (xy 149.277543 -385.500493)
			(xy 149.27072 -385.49961) (xy 149.256242 -385.497324) (xy 149.229572 -385.509008) (xy 149.169882 -385.596892)
			(xy 149.164899 -385.605047) (xy 149.160719 -385.623677) (xy 149.16364 -385.642546) (xy 149.168104 -385.650994)
			(xy 149.283674 -385.850892) (xy 149.296501 -385.874223) (xy 149.31472 -385.924247) (xy 149.323979 -385.976673)
			(xy 149.324568 -386.003292) (xy 149.324131 -386.027272) (xy 149.316633 -386.074643) (xy 149.301819 -386.120259)
			(xy 149.280055 -386.162997) (xy 149.251876 -386.201806) (xy 149.217975 -386.235732) (xy 149.179187 -386.263939)
			(xy 149.136464 -386.285734) (xy 149.090859 -386.300581) (xy 149.043494 -386.308113) (xy 149.019514 -386.3086)
			(xy 149.019006 -386.3086) (xy 148.995432 -386.308201) (xy 148.948844 -386.300961) (xy 148.903926 -386.286636)
			(xy 148.861747 -386.265568) (xy 148.823314 -386.238259) (xy 148.789542 -386.20536) (xy 148.761237 -386.167655)
			(xy 148.749766 -386.147056) (xy 148.749258 -386.146294) (xy 148.735796 -386.122926) (xy 148.730464 -386.114436)
			(xy 148.714557 -386.10225) (xy 148.695197 -386.097084) (xy 148.675334 -386.099725) (xy 148.666454 -386.104384)
			(xy 148.65731 -386.109718) (xy 148.651214 -386.1181) (xy 148.640304 -386.132014) (xy 148.614217 -386.155878)
			(xy 148.584186 -386.174537) (xy 148.551237 -386.187356) (xy 148.516491 -386.193897) (xy 148.498814 -386.1943)
			(xy 148.498306 -386.1943) (xy 148.479532 -386.193798) (xy 148.442704 -386.186481) (xy 148.408009 -386.172126)
			(xy 148.376777 -386.151284) (xy 148.350206 -386.124754) (xy 148.329315 -386.093555) (xy 148.314906 -386.058882)
			(xy 148.307532 -386.022065) (xy 148.307044 -386.003292) (xy 148.3075 -385.984177) (xy 148.315063 -385.946703)
			(xy 148.329924 -385.91148) (xy 148.351491 -385.879915) (xy 148.378902 -385.853268) (xy 148.411064 -385.832601)
			(xy 148.42871 -385.825238) (xy 148.43887 -385.821174) (xy 148.454364 -385.805426) (xy 148.483574 -385.722114)
			(xy 148.486796 -385.711534) (xy 148.484819 -385.689533) (xy 148.479764 -385.679696) (xy 148.351494 -385.457954)
			(xy 148.339556 -385.433824) (xy 148.334794 -385.424268) (xy 148.318987 -385.409946) (xy 148.298729 -385.403266)
			(xy 148.277503 -385.405379) (xy 148.258959 -385.41592) (xy 148.25218 -385.424172) (xy 148.241253 -385.438266)
			(xy 148.215065 -385.462469) (xy 148.184843 -385.481395) (xy 148.151635 -385.494386) (xy 148.116594 -385.500994)
			(xy 148.098764 -385.501388) (xy 148.098256 -385.501388) (xy 148.091376 -385.50138) (xy 148.077647 -385.500493)
			(xy 148.070824 -385.49961) (xy 148.056346 -385.497324) (xy 148.029676 -385.509008) (xy 147.969986 -385.596892)
			(xy 147.965003 -385.605047) (xy 147.960822 -385.623677) (xy 147.963743 -385.642546) (xy 147.968208 -385.650994)
			(xy 148.083778 -385.850892) (xy 148.096606 -385.874223) (xy 148.114824 -385.924247) (xy 148.124083 -385.976673)
			(xy 148.124672 -386.003292) (xy 148.124231 -386.027272) (xy 148.116733 -386.074643) (xy 148.10192 -386.120258)
			(xy 148.080156 -386.162996) (xy 148.051978 -386.201805) (xy 148.018077 -386.235731) (xy 147.979289 -386.263938)
			(xy 147.936567 -386.285733) (xy 147.890963 -386.30058) (xy 147.843598 -386.308113) (xy 147.819618 -386.3086)
			(xy 147.81911 -386.3086) (xy 147.795536 -386.308198) (xy 147.748948 -386.300958) (xy 147.70403 -386.286634)
			(xy 147.661852 -386.265566) (xy 147.623418 -386.238258) (xy 147.589647 -386.20536) (xy 147.561341 -386.167655)
			(xy 147.54987 -386.147056) (xy 147.549362 -386.146294) (xy 147.5359 -386.122926) (xy 147.530564 -386.114439)
			(xy 147.514659 -386.102253) (xy 147.4953 -386.097086) (xy 147.475437 -386.099726) (xy 147.466558 -386.104384)
			(xy 147.457414 -386.109718) (xy 147.451318 -386.1181) (xy 147.440405 -386.132012) (xy 147.414319 -386.155876)
			(xy 147.384289 -386.174536) (xy 147.35134 -386.187355) (xy 147.316595 -386.193896) (xy 147.298918 -386.1943)
			(xy 147.29841 -386.1943) (xy 147.279636 -386.193794) (xy 147.242808 -386.186478) (xy 147.208113 -386.172124)
			(xy 147.176881 -386.151282) (xy 147.15031 -386.124753) (xy 147.129419 -386.093554) (xy 147.11501 -386.058881)
			(xy 147.107636 -386.022065) (xy 147.107148 -386.003292) (xy 147.107602 -385.984177) (xy 147.115164 -385.946702)
			(xy 147.130026 -385.91148) (xy 147.151593 -385.879914) (xy 147.179005 -385.853267) (xy 147.211168 -385.832601)
			(xy 147.228814 -385.825238) (xy 147.238974 -385.821174) (xy 147.254468 -385.805426) (xy 147.283678 -385.722114)
			(xy 147.286899 -385.711534) (xy 147.284922 -385.689533) (xy 147.279868 -385.679696) (xy 147.151598 -385.457954)
			(xy 147.13966 -385.433824) (xy 147.134892 -385.424272) (xy 147.119087 -385.40995) (xy 147.098831 -385.40327)
			(xy 147.077606 -385.405382) (xy 147.059063 -385.415921) (xy 147.052284 -385.424172) (xy 147.041372 -385.438245)
			(xy 147.015229 -385.462421) (xy 146.98506 -385.481336) (xy 146.95191 -385.494336) (xy 146.916926 -385.500972)
			(xy 146.899122 -385.501388) (xy 146.898614 -385.501388) (xy 146.878586 -385.500943) (xy 146.839406 -385.492617)
			(xy 146.802813 -385.476327) (xy 146.770406 -385.452785) (xy 146.743603 -385.423019) (xy 146.723574 -385.388331)
			(xy 146.711196 -385.350236) (xy 146.707009 -385.3104) (xy 133.243588 -385.3104) (xy 133.555994 -385.850892)
			(xy 133.568823 -385.874222) (xy 133.587041 -385.924246) (xy 133.596299 -385.976673) (xy 133.596888 -386.003292)
			(xy 133.596431 -386.027271) (xy 133.588933 -386.07464) (xy 133.574121 -386.120254) (xy 133.552359 -386.162991)
			(xy 133.524182 -386.2018) (xy 133.490284 -386.235725) (xy 133.451498 -386.263932) (xy 133.408778 -386.285728)
			(xy 133.363176 -386.300577) (xy 133.315813 -386.308112) (xy 133.291834 -386.3086) (xy 133.291326 -386.3086)
			(xy 133.267753 -386.308185) (xy 133.221165 -386.300948) (xy 133.176247 -386.286626) (xy 133.134069 -386.26556)
			(xy 133.095636 -386.238254) (xy 133.061863 -386.205357) (xy 133.033557 -386.167655) (xy 133.022086 -386.147056)
			(xy 133.021578 -386.146294) (xy 133.008116 -386.122926) (xy 133.002764 -386.114451) (xy 132.986865 -386.102264)
			(xy 132.967511 -386.097095) (xy 132.947653 -386.099729) (xy 132.938774 -386.104384) (xy 132.92963 -386.109718)
			(xy 132.923534 -386.1181) (xy 132.912612 -386.132004) (xy 132.886528 -386.155869) (xy 132.856501 -386.17453)
			(xy 132.823553 -386.187351) (xy 132.78881 -386.193895) (xy 132.771134 -386.1943) (xy 132.770626 -386.1943)
			(xy 132.751853 -386.19378) (xy 132.715026 -386.186466) (xy 132.68033 -386.172115) (xy 132.649098 -386.151276)
			(xy 132.622527 -386.124748) (xy 132.601636 -386.093551) (xy 132.587226 -386.058879) (xy 132.579852 -386.022064)
			(xy 132.579364 -386.003292) (xy 132.579808 -385.984176) (xy 132.587371 -385.946701) (xy 132.602234 -385.911477)
			(xy 132.623803 -385.879911) (xy 132.651218 -385.853265) (xy 132.683383 -385.8326) (xy 132.70103 -385.825238)
			(xy 132.71119 -385.821174) (xy 132.726684 -385.805426) (xy 132.755894 -385.722114) (xy 132.759125 -385.711536)
			(xy 132.757145 -385.689531) (xy 132.752084 -385.679696) (xy 132.623814 -385.457954) (xy 132.611622 -385.43357)
			(xy 132.606765 -385.424067) (xy 132.590989 -385.409741) (xy 132.570756 -385.403051) (xy 132.549549 -385.40515)
			(xy 132.53102 -385.415675) (xy 132.524246 -385.423918) (xy 132.513289 -385.438003) (xy 132.487131 -385.462266)
			(xy 132.456925 -385.481253) (xy 132.423719 -385.494305) (xy 132.388669 -385.500968) (xy 132.37083 -385.501388)
			(xy 132.370322 -385.501388) (xy 132.363442 -385.501383) (xy 132.349712 -385.500495) (xy 132.34289 -385.49961)
			(xy 132.328412 -385.497324) (xy 132.301742 -385.509008) (xy 132.242052 -385.596892) (xy 132.23707 -385.605047)
			(xy 132.232892 -385.623677) (xy 132.235811 -385.642546) (xy 132.240274 -385.650994) (xy 132.355844 -385.850892)
			(xy 132.36858 -385.874208) (xy 132.386672 -385.924157) (xy 132.395888 -385.976476) (xy 132.396484 -386.003038)
			(xy 132.396484 -386.003292) (xy 132.396054 -386.027286) (xy 132.388548 -386.074684) (xy 132.373719 -386.120323)
			(xy 132.351933 -386.163081) (xy 132.323725 -386.201904) (xy 132.289792 -386.235836) (xy 132.250967 -386.264041)
			(xy 132.208208 -386.285825) (xy 132.162568 -386.300652) (xy 132.11517 -386.308156) (xy 132.091176 -386.3086)
			(xy 132.067601 -386.308226) (xy 132.021012 -386.30098) (xy 131.976093 -386.286651) (xy 131.933915 -386.265579)
			(xy 131.895482 -386.238267) (xy 131.861711 -386.205365) (xy 131.833406 -386.167657) (xy 131.821936 -386.147056)
			(xy 131.821428 -386.146294) (xy 131.807966 -386.122926) (xy 131.802563 -386.114488) (xy 131.786682 -386.102302)
			(xy 131.767346 -386.097122) (xy 131.7475 -386.09974) (xy 131.738624 -386.104384) (xy 131.72948 -386.109718)
			(xy 131.723384 -386.1181) (xy 131.712434 -386.131981) (xy 131.686357 -386.155847) (xy 131.656337 -386.174512)
			(xy 131.623396 -386.187339) (xy 131.588658 -386.193891) (xy 131.570984 -386.1943) (xy 131.570476 -386.1943)
			(xy 131.551707 -386.19387) (xy 131.514892 -386.186542) (xy 131.480214 -386.172174) (xy 131.449004 -386.151316)
			(xy 131.422464 -386.124771) (xy 131.401611 -386.093558) (xy 131.387248 -386.058877) (xy 131.379927 -386.022061)
			(xy 131.379468 -386.003292) (xy 131.3799 -385.984195) (xy 131.387471 -385.946759) (xy 131.402311 -385.911567)
			(xy 131.423832 -385.880013) (xy 131.45118 -385.853351) (xy 131.483269 -385.832638) (xy 131.50088 -385.825238)
			(xy 131.51104 -385.821174) (xy 131.526534 -385.805426) (xy 131.555744 -385.722114) (xy 131.558969 -385.711535)
			(xy 131.556991 -385.689532) (xy 131.551934 -385.679696) (xy 131.423664 -385.457954) (xy 131.411726 -385.433824)
			(xy 131.406866 -385.424326) (xy 131.391087 -385.410012) (xy 131.370858 -385.403327) (xy 131.349657 -385.405422)
			(xy 131.331127 -385.415936) (xy 131.32435 -385.424172) (xy 131.313383 -385.438233) (xy 131.287205 -385.462438)
			(xy 131.256993 -385.481369) (xy 131.223794 -385.494369) (xy 131.188761 -385.500987) (xy 131.170934 -385.501388)
			(xy 131.170426 -385.501388) (xy 131.163546 -385.501383) (xy 131.149817 -385.500494) (xy 131.142994 -385.49961)
			(xy 131.128516 -385.497324) (xy 131.101846 -385.509008) (xy 131.042156 -385.596892) (xy 131.037174 -385.605047)
			(xy 131.032996 -385.623677) (xy 131.035915 -385.642546) (xy 131.040378 -385.650994) (xy 131.155948 -385.850892)
			(xy 131.168685 -385.874208) (xy 131.186776 -385.924157) (xy 131.195992 -385.976476) (xy 131.196588 -386.003038)
			(xy 131.196588 -386.003292) (xy 131.196154 -386.027286) (xy 131.188648 -386.074683) (xy 131.17382 -386.120322)
			(xy 131.152033 -386.16308) (xy 131.123826 -386.201902) (xy 131.089893 -386.235834) (xy 131.05107 -386.26404)
			(xy 131.008311 -386.285824) (xy 130.962671 -386.300651) (xy 130.915274 -386.308155) (xy 130.89128 -386.3086)
			(xy 130.867705 -386.308222) (xy 130.821116 -386.300978) (xy 130.776197 -386.286649) (xy 130.734019 -386.265578)
			(xy 130.695586 -386.238266) (xy 130.661815 -386.205364) (xy 130.63351 -386.167657) (xy 130.62204 -386.147056)
			(xy 130.621532 -386.146294) (xy 130.60807 -386.122926) (xy 130.602663 -386.114491) (xy 130.586784 -386.102304)
			(xy 130.567449 -386.097125) (xy 130.547604 -386.099741) (xy 130.538728 -386.104384) (xy 130.529584 -386.109718)
			(xy 130.523488 -386.1181) (xy 130.512536 -386.131979) (xy 130.48646 -386.155845) (xy 130.456439 -386.174511)
			(xy 130.423499 -386.187338) (xy 130.388762 -386.19389) (xy 130.371088 -386.1943) (xy 130.37058 -386.1943)
			(xy 130.351811 -386.193866) (xy 130.314996 -386.186539) (xy 130.280318 -386.172171) (xy 130.249109 -386.151314)
			(xy 130.222568 -386.12477) (xy 130.201715 -386.093557) (xy 130.187353 -386.058877) (xy 130.180031 -386.022061)
			(xy 130.179572 -386.003292) (xy 130.180001 -385.984195) (xy 130.187573 -385.946759) (xy 130.202413 -385.911566)
			(xy 130.223935 -385.880013) (xy 130.251283 -385.853351) (xy 130.283373 -385.832638) (xy 130.300984 -385.825238)
			(xy 130.311144 -385.821174) (xy 130.326638 -385.805426) (xy 130.355848 -385.722114) (xy 130.359073 -385.711535)
			(xy 130.357095 -385.689532) (xy 130.352038 -385.679696) (xy 130.223768 -385.457954) (xy 130.21183 -385.433824)
			(xy 130.206964 -385.424329) (xy 130.191187 -385.410015) (xy 130.17096 -385.403331) (xy 130.14976 -385.405424)
			(xy 130.131231 -385.415936) (xy 130.124454 -385.424172) (xy 130.113502 -385.438212) (xy 130.087369 -385.46239)
			(xy 130.05721 -385.481311) (xy 130.024069 -385.494319) (xy 129.989093 -385.500966) (xy 129.971292 -385.501388)
			(xy 129.970784 -385.501388) (xy 129.943098 -385.499356) (xy 129.942844 -385.499356) (xy 129.933376 -385.498381)
			(xy 129.914859 -385.502725) (xy 129.899207 -385.513532) (xy 129.893568 -385.5212) (xy 129.842006 -385.596892)
			(xy 129.837022 -385.605047) (xy 129.83284 -385.623677) (xy 129.835762 -385.642547) (xy 129.840228 -385.650994)
			(xy 129.955798 -385.850892) (xy 129.968619 -385.874226) (xy 129.986842 -385.924248) (xy 129.996103 -385.976674)
			(xy 129.996692 -386.003292) (xy 129.996231 -386.027271) (xy 129.988734 -386.07464) (xy 129.973922 -386.120253)
			(xy 129.95216 -386.16299) (xy 129.923983 -386.201798) (xy 129.890086 -386.235723) (xy 129.8513 -386.263931)
			(xy 129.808581 -386.285727) (xy 129.762979 -386.300576) (xy 129.715617 -386.308112) (xy 129.691638 -386.3086)
			(xy 129.69113 -386.3086) (xy 129.667557 -386.308182) (xy 129.62097 -386.300945) (xy 129.576052 -386.286624)
			(xy 129.533873 -386.265559) (xy 129.49544 -386.238253) (xy 129.461668 -386.205357) (xy 129.433361 -386.167654)
			(xy 129.42189 -386.147056) (xy 129.421382 -386.146294) (xy 129.40792 -386.122926) (xy 129.402564 -386.114454)
			(xy 129.386666 -386.102267) (xy 129.367314 -386.097097) (xy 129.347456 -386.09973) (xy 129.338578 -386.104384)
			(xy 129.329434 -386.109718) (xy 129.323338 -386.1181) (xy 129.312414 -386.132002) (xy 129.286331 -386.155867)
			(xy 129.256304 -386.174529) (xy 129.223357 -386.18735) (xy 129.188614 -386.193895) (xy 129.170938 -386.1943)
			(xy 129.17043 -386.1943) (xy 129.151657 -386.193776) (xy 129.11483 -386.186463) (xy 129.080135 -386.172112)
			(xy 129.048902 -386.151274) (xy 129.022331 -386.124747) (xy 129.00144 -386.09355) (xy 128.98703 -386.058879)
			(xy 128.979656 -386.022064) (xy 128.979168 -386.003292) (xy 128.979609 -385.984176) (xy 128.987172 -385.9467)
			(xy 129.002036 -385.911476) (xy 129.023606 -385.879911) (xy 129.051021 -385.853264) (xy 129.083187 -385.8326)
			(xy 129.100834 -385.825238) (xy 129.110994 -385.821174) (xy 129.126488 -385.805426) (xy 129.155698 -385.722114)
			(xy 129.158928 -385.711536) (xy 129.156948 -385.689531) (xy 129.151888 -385.679696) (xy 129.023618 -385.457954)
			(xy 129.01168 -385.433824) (xy 129.006884 -385.424288) (xy 128.991087 -385.409968) (xy 128.970839 -385.403287)
			(xy 128.949622 -385.405394) (xy 128.931082 -385.415925) (xy 128.924304 -385.424172) (xy 128.913363 -385.438255)
			(xy 128.887179 -385.462458) (xy 128.85696 -385.481386) (xy 128.823755 -385.494381) (xy 128.788717 -385.500992)
			(xy 128.770888 -385.501388) (xy 128.77038 -385.501388) (xy 128.7635 -385.501388) (xy 128.74977 -385.500496)
			(xy 128.742948 -385.49961) (xy 128.72847 -385.497324) (xy 128.7018 -385.509008) (xy 128.64211 -385.596892)
			(xy 128.637126 -385.605047) (xy 128.632943 -385.623677) (xy 128.635865 -385.642547) (xy 128.640332 -385.650994)
			(xy 128.755902 -385.850892) (xy 128.768724 -385.874226) (xy 128.786946 -385.924248) (xy 128.796207 -385.976674)
			(xy 128.796796 -386.003292) (xy 128.796331 -386.027271) (xy 128.788834 -386.074639) (xy 128.774022 -386.120252)
			(xy 128.752261 -386.162989) (xy 128.724085 -386.201797) (xy 128.690187 -386.235722) (xy 128.651402 -386.26393)
			(xy 128.608684 -386.285726) (xy 128.563083 -386.300575) (xy 128.515721 -386.308111) (xy 128.491742 -386.3086)
			(xy 128.491234 -386.3086) (xy 128.467661 -386.308179) (xy 128.421074 -386.300942) (xy 128.376156 -386.286622)
			(xy 128.333978 -386.265557) (xy 128.295544 -386.238252) (xy 128.261772 -386.205356) (xy 128.233465 -386.167654)
			(xy 128.221994 -386.147056) (xy 128.221486 -386.146294) (xy 128.208024 -386.122926) (xy 128.202664 -386.114456)
			(xy 128.186767 -386.10227) (xy 128.167417 -386.097099) (xy 128.14756 -386.099731) (xy 128.138682 -386.104384)
			(xy 128.129538 -386.109718) (xy 128.123442 -386.1181) (xy 128.112516 -386.132001) (xy 128.086433 -386.155866)
			(xy 128.056406 -386.174527) (xy 128.02346 -386.187349) (xy 127.988718 -386.193894) (xy 127.971042 -386.1943)
			(xy 127.970534 -386.1943) (xy 127.951761 -386.193773) (xy 127.914934 -386.186461) (xy 127.880239 -386.17211)
			(xy 127.849007 -386.151272) (xy 127.822435 -386.124746) (xy 127.801544 -386.093549) (xy 127.787134 -386.058879)
			(xy 127.77976 -386.022064) (xy 127.779272 -386.003292) (xy 127.77971 -385.984176) (xy 127.787274 -385.9467)
			(xy 127.802138 -385.911476) (xy 127.823708 -385.87991) (xy 127.851124 -385.853263) (xy 127.88329 -385.8326)
			(xy 127.900938 -385.825238) (xy 127.911098 -385.821174) (xy 127.926592 -385.805426) (xy 127.955802 -385.722114)
			(xy 127.959032 -385.711536) (xy 127.957052 -385.689531) (xy 127.951992 -385.679696) (xy 127.823722 -385.457954)
			(xy 127.811784 -385.433824) (xy 127.806983 -385.424291) (xy 127.791187 -385.409972) (xy 127.770941 -385.403291)
			(xy 127.749725 -385.405396) (xy 127.731186 -385.415926) (xy 127.724408 -385.424172) (xy 127.713465 -385.438253)
			(xy 127.687281 -385.462457) (xy 127.657063 -385.481384) (xy 127.623859 -385.49438) (xy 127.58882 -385.500991)
			(xy 127.570992 -385.501388) (xy 127.570484 -385.501388) (xy 127.563604 -385.501388) (xy 127.549874 -385.500496)
			(xy 127.543052 -385.49961) (xy 127.528574 -385.497324) (xy 127.501904 -385.509008) (xy 127.442214 -385.596892)
			(xy 127.437229 -385.605047) (xy 127.433047 -385.623677) (xy 127.435969 -385.642547) (xy 127.440436 -385.650994)
			(xy 127.556006 -385.850892) (xy 127.568828 -385.874226) (xy 127.58705 -385.924248) (xy 127.596311 -385.976674)
			(xy 127.5969 -386.003292) (xy 127.596431 -386.027271) (xy 127.588934 -386.074639) (xy 127.574122 -386.120251)
			(xy 127.552361 -386.162988) (xy 127.524186 -386.201795) (xy 127.490289 -386.235721) (xy 127.451504 -386.263928)
			(xy 127.408786 -386.285725) (xy 127.363186 -386.300574) (xy 127.315824 -386.308111) (xy 127.291846 -386.3086)
			(xy 127.291338 -386.3086) (xy 127.267765 -386.308176) (xy 127.221178 -386.30094) (xy 127.17626 -386.28662)
			(xy 127.134082 -386.265556) (xy 127.095648 -386.238251) (xy 127.061876 -386.205356) (xy 127.033569 -386.167654)
			(xy 127.022098 -386.147056) (xy 127.02159 -386.146294) (xy 127.008128 -386.122926) (xy 127.002764 -386.114459)
			(xy 126.986869 -386.102273) (xy 126.967519 -386.097101) (xy 126.947664 -386.099731) (xy 126.938786 -386.104384)
			(xy 126.929642 -386.109718) (xy 126.923546 -386.1181) (xy 126.912618 -386.131999) (xy 126.886535 -386.155864)
			(xy 126.856509 -386.174526) (xy 126.823564 -386.187348) (xy 126.788822 -386.193894) (xy 126.771146 -386.1943)
			(xy 126.770638 -386.1943) (xy 126.751865 -386.193769) (xy 126.715038 -386.186458) (xy 126.680343 -386.172108)
			(xy 126.649111 -386.151271) (xy 126.622539 -386.124745) (xy 126.601648 -386.093548) (xy 126.587239 -386.058878)
			(xy 126.579864 -386.022064) (xy 126.579376 -386.003292) (xy 126.579875 -385.98418) (xy 126.587434 -385.946711)
			(xy 126.602289 -385.911492) (xy 126.623848 -385.879928) (xy 126.65125 -385.853278) (xy 126.683401 -385.832606)
			(xy 126.701042 -385.825238) (xy 126.711202 -385.821174) (xy 126.726696 -385.805426) (xy 126.755906 -385.722114)
			(xy 126.759135 -385.711536) (xy 126.757156 -385.689532) (xy 126.752096 -385.679696) (xy 126.623826 -385.457954)
			(xy 126.611888 -385.433824) (xy 126.607081 -385.424295) (xy 126.591287 -385.409976) (xy 126.571042 -385.403294)
			(xy 126.549828 -385.405398) (xy 126.53129 -385.415927) (xy 126.524512 -385.424172) (xy 126.513584 -385.438232)
			(xy 126.487445 -385.462409) (xy 126.45728 -385.481326) (xy 126.424134 -385.49433) (xy 126.389152 -385.50097)
			(xy 126.37135 -385.501388) (xy 126.370842 -385.501388) (xy 126.343156 -385.499356) (xy 126.342902 -385.499356)
			(xy 126.333432 -385.498427) (xy 126.31492 -385.502751) (xy 126.299268 -385.51354) (xy 126.293626 -385.5212)
			(xy 126.242064 -385.596892) (xy 126.237082 -385.605047) (xy 126.232903 -385.623677) (xy 126.235822 -385.642546)
			(xy 126.240286 -385.650994) (xy 126.355856 -385.850892) (xy 126.368593 -385.874208) (xy 126.386685 -385.924157)
			(xy 126.3959 -385.976476) (xy 126.396496 -386.003038) (xy 126.396496 -386.003292) (xy 126.396054 -386.027286)
			(xy 126.388548 -386.074682) (xy 126.37372 -386.12032) (xy 126.351935 -386.163077) (xy 126.323729 -386.2019)
			(xy 126.289797 -386.235831) (xy 126.250974 -386.264037) (xy 126.208217 -386.285822) (xy 126.162578 -386.300649)
			(xy 126.115182 -386.308155) (xy 126.091188 -386.3086) (xy 126.067614 -386.308216) (xy 126.021025 -386.300973)
			(xy 125.976106 -386.286645) (xy 125.933928 -386.265575) (xy 125.895495 -386.238264) (xy 125.861723 -386.205363)
			(xy 125.833418 -386.167656) (xy 125.821948 -386.147056) (xy 125.82144 -386.146294) (xy 125.807978 -386.122926)
			(xy 125.802563 -386.114497) (xy 125.786686 -386.10231) (xy 125.767354 -386.097129) (xy 125.747511 -386.099742)
			(xy 125.738636 -386.104384) (xy 125.729492 -386.109718) (xy 125.723396 -386.1181) (xy 125.712439 -386.131975)
			(xy 125.686364 -386.155842) (xy 125.656345 -386.174508) (xy 125.623406 -386.187336) (xy 125.58867 -386.193889)
			(xy 125.570996 -386.1943) (xy 125.570488 -386.1943) (xy 125.55172 -386.193859) (xy 125.514905 -386.186534)
			(xy 125.480227 -386.172167) (xy 125.449017 -386.151311) (xy 125.422476 -386.124767) (xy 125.401624 -386.093556)
			(xy 125.387261 -386.058876) (xy 125.379939 -386.02206) (xy 125.37948 -386.003292) (xy 125.379904 -385.984195)
			(xy 125.387476 -385.946758) (xy 125.402317 -385.911565) (xy 125.42384 -385.880011) (xy 125.451189 -385.853349)
			(xy 125.48328 -385.832637) (xy 125.500892 -385.825238) (xy 125.511052 -385.821174) (xy 125.526546 -385.805426)
			(xy 125.555756 -385.722114) (xy 125.55898 -385.711535) (xy 125.557002 -385.689532) (xy 125.551946 -385.679696)
			(xy 125.423676 -385.457954) (xy 125.411738 -385.433824) (xy 125.406861 -385.424336) (xy 125.391087 -385.410023)
			(xy 125.370863 -385.403337) (xy 125.349666 -385.405429) (xy 125.331139 -385.415938) (xy 125.324362 -385.424172)
			(xy 125.313388 -385.438227) (xy 125.287212 -385.462433) (xy 125.257002 -385.481365) (xy 125.223805 -385.494367)
			(xy 125.188772 -385.500986) (xy 125.170946 -385.501388) (xy 125.170438 -385.501388) (xy 125.163558 -385.501382)
			(xy 125.149829 -385.500494) (xy 125.143006 -385.49961) (xy 125.128528 -385.497324) (xy 125.101858 -385.509008)
			(xy 125.042168 -385.596892) (xy 125.037185 -385.605047) (xy 125.033006 -385.623677) (xy 125.035926 -385.642546)
			(xy 125.04039 -385.650994) (xy 125.15596 -385.850892) (xy 125.168698 -385.874207) (xy 125.186789 -385.924157)
			(xy 125.196004 -385.976476) (xy 125.1966 -386.003038) (xy 125.1966 -386.003292) (xy 125.196154 -386.027285)
			(xy 125.188649 -386.074681) (xy 125.173821 -386.12032) (xy 125.152036 -386.163076) (xy 125.12383 -386.201898)
			(xy 125.089898 -386.23583) (xy 125.051076 -386.264036) (xy 125.00832 -386.285821) (xy 124.962681 -386.300649)
			(xy 124.915285 -386.308154) (xy 124.891292 -386.3086) (xy 124.867718 -386.308213) (xy 124.821129 -386.30097)
			(xy 124.77621 -386.286643) (xy 124.734032 -386.265573) (xy 124.695599 -386.238263) (xy 124.661828 -386.205362)
			(xy 124.633522 -386.167656) (xy 124.622052 -386.147056) (xy 124.621544 -386.146294) (xy 124.608082 -386.122926)
			(xy 124.602663 -386.1145) (xy 124.586788 -386.102313) (xy 124.567457 -386.097131) (xy 124.547615 -386.099743)
			(xy 124.53874 -386.104384) (xy 124.529596 -386.109718) (xy 124.5235 -386.1181) (xy 124.512541 -386.131973)
			(xy 124.486466 -386.15584) (xy 124.456448 -386.174506) (xy 124.423509 -386.187335) (xy 124.388774 -386.193889)
			(xy 124.3711 -386.1943) (xy 124.370592 -386.1943) (xy 124.351824 -386.193855) (xy 124.315009 -386.186531)
			(xy 124.280331 -386.172165) (xy 124.249121 -386.151309) (xy 124.22258 -386.124766) (xy 124.201728 -386.093555)
			(xy 124.187365 -386.058875) (xy 124.180043 -386.02206) (xy 124.179584 -386.003292) (xy 124.180006 -385.984194)
			(xy 124.187578 -385.946758) (xy 124.202419 -385.911564) (xy 124.223942 -385.88001) (xy 124.251292 -385.853349)
			(xy 124.283384 -385.832637) (xy 124.300996 -385.825238) (xy 124.311156 -385.821174) (xy 124.32665 -385.805426)
			(xy 124.35586 -385.722114) (xy 124.359084 -385.711535) (xy 124.357106 -385.689532) (xy 124.35205 -385.679696)
			(xy 124.22378 -385.457954) (xy 124.211842 -385.433824) (xy 124.2071 -385.424257) (xy 124.191287 -385.409933)
			(xy 124.171023 -385.403254) (xy 124.149793 -385.40537) (xy 124.131245 -385.415917) (xy 124.124466 -385.424172)
			(xy 124.113507 -385.438206) (xy 124.087375 -385.462385) (xy 124.057218 -385.481307) (xy 124.024079 -385.494316)
			(xy 123.989104 -385.500965) (xy 123.971304 -385.501388) (xy 123.970796 -385.501388) (xy 123.94311 -385.499356)
			(xy 123.942856 -385.499356) (xy 123.933388 -385.49839) (xy 123.914871 -385.50273) (xy 123.89922 -385.513534)
			(xy 123.89358 -385.5212) (xy 123.842018 -385.596892) (xy 123.837033 -385.605047) (xy 123.83285 -385.623677)
			(xy 123.835773 -385.642547) (xy 123.84024 -385.650994) (xy 123.95581 -385.850892) (xy 123.968632 -385.874226)
			(xy 123.986854 -385.924248) (xy 123.996115 -385.976673) (xy 123.996704 -386.003292) (xy 123.996231 -386.027271)
			(xy 123.988734 -386.074638) (xy 123.973923 -386.120251) (xy 123.952162 -386.162986) (xy 123.923987 -386.201794)
			(xy 123.890091 -386.235719) (xy 123.851307 -386.263927) (xy 123.808589 -386.285724) (xy 123.762989 -386.300574)
			(xy 123.715628 -386.308111) (xy 123.69165 -386.3086) (xy 123.691142 -386.3086) (xy 123.667569 -386.308172)
			(xy 123.620983 -386.300937) (xy 123.576065 -386.286617) (xy 123.533886 -386.265554) (xy 123.495453 -386.23825)
			(xy 123.46168 -386.205355) (xy 123.433373 -386.167654) (xy 123.421902 -386.147056) (xy 123.421394 -386.146294)
			(xy 123.407932 -386.122926) (xy 123.402563 -386.114463) (xy 123.38667 -386.102277) (xy 123.367322 -386.097104)
			(xy 123.347468 -386.099733) (xy 123.33859 -386.104384) (xy 123.329446 -386.109718) (xy 123.32335 -386.1181)
			(xy 123.312419 -386.131997) (xy 123.286338 -386.155862) (xy 123.256312 -386.174524) (xy 123.223367 -386.187347)
			(xy 123.188626 -386.193894) (xy 123.17095 -386.1943) (xy 123.170442 -386.1943) (xy 123.151669 -386.193765)
			(xy 123.114843 -386.186455) (xy 123.080148 -386.172106) (xy 123.048915 -386.151269) (xy 123.022343 -386.124744)
			(xy 123.001452 -386.093548) (xy 122.987043 -386.058878) (xy 122.979668 -386.022064) (xy 122.97918 -386.003292)
			(xy 122.979677 -385.984179) (xy 122.987236 -385.94671) (xy 123.002092 -385.911491) (xy 123.023651 -385.879927)
			(xy 123.051053 -385.853277) (xy 123.083205 -385.832606) (xy 123.100846 -385.825238) (xy 123.111006 -385.821174)
			(xy 123.1265 -385.805426) (xy 123.15571 -385.722114) (xy 123.158939 -385.711536) (xy 123.156959 -385.689532)
			(xy 123.1519 -385.679696) (xy 123.02363 -385.457954) (xy 123.011692 -385.433824) (xy 123.00688 -385.424298)
			(xy 122.991087 -385.409979) (xy 122.970844 -385.403298) (xy 122.949631 -385.405401) (xy 122.931094 -385.415928)
			(xy 122.924316 -385.424172) (xy 122.913368 -385.438249) (xy 122.887186 -385.462453) (xy 122.856969 -385.481382)
			(xy 122.823766 -385.494378) (xy 122.788728 -385.50099) (xy 122.7709 -385.501388) (xy 122.770392 -385.501388)
			(xy 122.763512 -385.501387) (xy 122.749782 -385.500496) (xy 122.74296 -385.49961) (xy 122.728482 -385.497324)
			(xy 122.701812 -385.509008) (xy 122.642122 -385.596892) (xy 122.637137 -385.605047) (xy 122.632953 -385.623677)
			(xy 122.635877 -385.642547) (xy 122.640344 -385.650994) (xy 122.755914 -385.850892) (xy 122.768737 -385.874226)
			(xy 122.786958 -385.924248) (xy 122.796219 -385.976673) (xy 122.796808 -386.003292) (xy 122.796331 -386.02727)
			(xy 122.788834 -386.074637) (xy 122.774023 -386.12025) (xy 122.752263 -386.162985) (xy 122.724088 -386.201793)
			(xy 122.690192 -386.235718) (xy 122.651409 -386.263926) (xy 122.608692 -386.285723) (xy 122.563092 -386.300573)
			(xy 122.515732 -386.30811) (xy 122.491754 -386.3086) (xy 122.491246 -386.3086) (xy 122.467673 -386.308169)
			(xy 122.421087 -386.300935) (xy 122.376169 -386.286615) (xy 122.333991 -386.265553) (xy 122.295557 -386.238249)
			(xy 122.261784 -386.205355) (xy 122.233477 -386.167654) (xy 122.222006 -386.147056) (xy 122.221498 -386.146294)
			(xy 122.208036 -386.122926) (xy 122.202663 -386.114466) (xy 122.186771 -386.102279) (xy 122.167425 -386.097106)
			(xy 122.147572 -386.099734) (xy 122.138694 -386.104384) (xy 122.12955 -386.109718) (xy 122.123454 -386.1181)
			(xy 122.112521 -386.131995) (xy 122.08644 -386.15586) (xy 122.056415 -386.174523) (xy 122.02347 -386.187346)
			(xy 121.98873 -386.193893) (xy 121.971054 -386.1943) (xy 121.970546 -386.1943) (xy 121.951773 -386.193762)
			(xy 121.914947 -386.186452) (xy 121.880252 -386.172104) (xy 121.849019 -386.151267) (xy 121.822448 -386.124742)
			(xy 121.801556 -386.093547) (xy 121.787147 -386.058877) (xy 121.779772 -386.022064) (xy 121.779284 -386.003292)
			(xy 121.779778 -385.984179) (xy 121.787338 -385.94671) (xy 121.802194 -385.91149) (xy 121.823753 -385.879926)
			(xy 121.851156 -385.853277) (xy 121.883309 -385.832605) (xy 121.90095 -385.825238) (xy 121.91111 -385.821174)
			(xy 121.926604 -385.805426) (xy 121.955814 -385.722114) (xy 121.959042 -385.711535) (xy 121.957063 -385.689532)
			(xy 121.952004 -385.679696) (xy 121.823734 -385.457954) (xy 121.811796 -385.433824) (xy 121.806978 -385.424301)
			(xy 121.791187 -385.409983) (xy 121.770946 -385.403301) (xy 121.749734 -385.405403) (xy 121.731198 -385.415929)
			(xy 121.72442 -385.424172) (xy 121.71347 -385.438247) (xy 121.687288 -385.462451) (xy 121.657072 -385.48138)
			(xy 121.623869 -385.494377) (xy 121.588832 -385.50099) (xy 121.571004 -385.501388) (xy 121.570496 -385.501388)
			(xy 121.563616 -385.501386) (xy 121.549886 -385.500495) (xy 121.543064 -385.49961) (xy 121.528586 -385.497324)
			(xy 121.501916 -385.509008) (xy 121.442226 -385.596892) (xy 121.437241 -385.605047) (xy 121.433057 -385.623677)
			(xy 121.43598 -385.642547) (xy 121.440448 -385.650994) (xy 121.556018 -385.850892) (xy 121.568841 -385.874226)
			(xy 121.587062 -385.924248) (xy 121.596323 -385.976673) (xy 121.596912 -386.003292) (xy 121.596431 -386.02727)
			(xy 121.588934 -386.074637) (xy 121.574124 -386.120249) (xy 121.552364 -386.162984) (xy 121.524189 -386.201791)
			(xy 121.490294 -386.235716) (xy 121.451511 -386.263924) (xy 121.408795 -386.285722) (xy 121.363196 -386.300572)
			(xy 121.315836 -386.30811) (xy 121.291858 -386.3086) (xy 121.29135 -386.3086) (xy 121.267777 -386.308166)
			(xy 121.221191 -386.300932) (xy 121.176273 -386.286613) (xy 121.134095 -386.265551) (xy 121.095661 -386.238248)
			(xy 121.061888 -386.205354) (xy 121.033581 -386.167653) (xy 121.02211 -386.147056) (xy 121.021602 -386.146294)
			(xy 121.00814 -386.122926) (xy 121.002763 -386.114469) (xy 120.986873 -386.102282) (xy 120.967528 -386.097108)
			(xy 120.947675 -386.099734) (xy 120.938798 -386.104384) (xy 120.929654 -386.109718) (xy 120.923558 -386.1181)
			(xy 120.912623 -386.131993) (xy 120.886542 -386.155859) (xy 120.856518 -386.174522) (xy 120.823574 -386.187345)
			(xy 120.788833 -386.193893) (xy 120.771158 -386.1943) (xy 120.77065 -386.1943) (xy 120.751878 -386.193758)
			(xy 120.715051 -386.186449) (xy 120.680356 -386.172101) (xy 120.649124 -386.151266) (xy 120.622552 -386.124741)
			(xy 120.60166 -386.093546) (xy 120.587251 -386.058877) (xy 120.579876 -386.022064) (xy 120.579388 -386.003292)
			(xy 120.57988 -385.984179) (xy 120.587439 -385.946709) (xy 120.602296 -385.91149) (xy 120.623856 -385.879925)
			(xy 120.651259 -385.853276) (xy 120.683412 -385.832605) (xy 120.701054 -385.825238) (xy 120.711214 -385.821174)
			(xy 120.726708 -385.805426) (xy 120.755918 -385.722114) (xy 120.759146 -385.711535) (xy 120.757167 -385.689532)
			(xy 120.752108 -385.679696) (xy 120.623838 -385.457954) (xy 120.6119 -385.433824) (xy 120.607076 -385.424305)
			(xy 120.591287 -385.409987) (xy 120.571047 -385.403304) (xy 120.549837 -385.405406) (xy 120.531302 -385.41593)
			(xy 120.524524 -385.424172) (xy 120.513589 -385.438226) (xy 120.487451 -385.462403) (xy 120.457288 -385.481322)
			(xy 120.424144 -385.494327) (xy 120.389164 -385.500968) (xy 120.371362 -385.501388) (xy 120.370854 -385.501388)
			(xy 120.343168 -385.499356) (xy 120.342914 -385.499356) (xy 120.333443 -385.498436) (xy 120.314932 -385.502756)
			(xy 120.29928 -385.513541) (xy 120.293638 -385.5212) (xy 120.242076 -385.596892) (xy 120.237093 -385.605047)
			(xy 120.232913 -385.623677) (xy 120.235834 -385.642546) (xy 120.240298 -385.650994) (xy 120.355868 -385.850892)
			(xy 120.368606 -385.874207) (xy 120.386697 -385.924157) (xy 120.395912 -385.976476) (xy 120.396508 -386.003038)
			(xy 120.396508 -386.003292) (xy 120.396054 -386.027285) (xy 120.388549 -386.07468) (xy 120.373721 -386.120318)
			(xy 120.351937 -386.163074) (xy 120.323732 -386.201896) (xy 120.289802 -386.235827) (xy 120.250981 -386.264033)
			(xy 120.208225 -386.285818) (xy 120.162588 -386.300647) (xy 120.115193 -386.308154) (xy 120.0912 -386.3086)
			(xy 120.067626 -386.308206) (xy 120.021038 -386.300965) (xy 119.976119 -386.286639) (xy 119.933941 -386.26557)
			(xy 119.895508 -386.238261) (xy 119.861736 -386.205361) (xy 119.83343 -386.167656) (xy 119.82196 -386.147056)
			(xy 119.821452 -386.146294) (xy 119.80799 -386.122926) (xy 119.802563 -386.114506) (xy 119.786691 -386.102319)
			(xy 119.767363 -386.097136) (xy 119.747523 -386.099745) (xy 119.738648 -386.104384) (xy 119.729504 -386.109718)
			(xy 119.723408 -386.1181) (xy 119.712501 -386.132017) (xy 119.686413 -386.15588) (xy 119.656382 -386.174539)
			(xy 119.623431 -386.187357) (xy 119.588686 -386.193897) (xy 119.571008 -386.1943) (xy 119.5705 -386.1943)
			(xy 119.551729 -386.193878) (xy 119.514909 -386.186554) (xy 119.480225 -386.172187) (xy 119.449011 -386.15133)
			(xy 119.422465 -386.124783) (xy 119.401609 -386.093568) (xy 119.387244 -386.058883) (xy 119.379921 -386.022063)
			(xy 119.379492 -386.003292) (xy 119.379971 -385.984198) (xy 119.387539 -385.946768) (xy 119.402372 -385.911579)
			(xy 119.423884 -385.880027) (xy 119.451221 -385.853362) (xy 119.483298 -385.832642) (xy 119.500904 -385.825238)
			(xy 119.511064 -385.821174) (xy 119.526558 -385.805426) (xy 119.555768 -385.722114) (xy 119.558991 -385.711535)
			(xy 119.557013 -385.689532) (xy 119.551958 -385.679696) (xy 119.423688 -385.457954) (xy 119.41175 -385.433824)
			(xy 119.406997 -385.424263) (xy 119.391187 -385.40994) (xy 119.370927 -385.403261) (xy 119.349699 -385.405375)
			(xy 119.331153 -385.415918) (xy 119.324374 -385.424172) (xy 119.313451 -385.438269) (xy 119.287262 -385.462471)
			(xy 119.257039 -385.481397) (xy 119.22383 -385.494388) (xy 119.188788 -385.500994) (xy 119.170958 -385.501388)
			(xy 119.17045 -385.501388) (xy 119.16357 -385.50138) (xy 119.149841 -385.500493) (xy 119.143018 -385.49961)
			(xy 119.12854 -385.497324) (xy 119.10187 -385.509008) (xy 119.04218 -385.596892) (xy 119.037197 -385.605047)
			(xy 119.033017 -385.623677) (xy 119.035937 -385.642546) (xy 119.040402 -385.650994) (xy 119.155972 -385.850892)
			(xy 119.168711 -385.874207) (xy 119.186801 -385.924157) (xy 119.196016 -385.976476) (xy 119.196612 -386.003038)
			(xy 119.196612 -386.003292) (xy 119.196154 -386.027285) (xy 119.188649 -386.07468) (xy 119.173822 -386.120317)
			(xy 119.152038 -386.163073) (xy 119.123834 -386.201894) (xy 119.089903 -386.235826) (xy 119.051083 -386.264032)
			(xy 119.008328 -386.285817) (xy 118.962691 -386.300646) (xy 118.915297 -386.308154) (xy 118.891304 -386.3086)
			(xy 118.86773 -386.308203) (xy 118.821142 -386.300962) (xy 118.776223 -386.286637) (xy 118.734045 -386.265569)
			(xy 118.695612 -386.23826) (xy 118.66184 -386.205361) (xy 118.633535 -386.167656) (xy 118.622064 -386.147056)
			(xy 118.621556 -386.146294) (xy 118.608094 -386.122926) (xy 118.602764 -386.114434) (xy 118.586857 -386.102248)
			(xy 118.567495 -386.097082) (xy 118.547632 -386.099724) (xy 118.538752 -386.104384) (xy 118.529608 -386.109718)
			(xy 118.523512 -386.1181) (xy 118.512603 -386.132015) (xy 118.486516 -386.155879) (xy 118.456485 -386.174538)
			(xy 118.423535 -386.187356) (xy 118.388789 -386.193897) (xy 118.371112 -386.1943) (xy 118.370604 -386.1943)
			(xy 118.351833 -386.193875) (xy 118.315013 -386.186551) (xy 118.280329 -386.172185) (xy 118.249115 -386.151328)
			(xy 118.222569 -386.124782) (xy 118.201713 -386.093567) (xy 118.187348 -386.058883) (xy 118.180025 -386.022063)
			(xy 118.179596 -386.003292) (xy 118.180073 -385.984198) (xy 118.187641 -385.946768) (xy 118.202475 -385.911579)
			(xy 118.223987 -385.880026) (xy 118.251324 -385.853362) (xy 118.283402 -385.832643) (xy 118.301008 -385.825238)
			(xy 118.311168 -385.821174) (xy 118.326662 -385.805426) (xy 118.355872 -385.722114) (xy 118.359094 -385.711534)
			(xy 118.357117 -385.689533) (xy 118.352062 -385.679696) (xy 118.223792 -385.457954) (xy 118.211854 -385.433824)
			(xy 118.207095 -385.424267) (xy 118.191287 -385.409944) (xy 118.171028 -385.403265) (xy 118.149802 -385.405378)
			(xy 118.131257 -385.415919) (xy 118.124478 -385.424172) (xy 118.113569 -385.438248) (xy 118.087425 -385.462423)
			(xy 118.057256 -385.481338) (xy 118.024105 -385.494338) (xy 117.98912 -385.500973) (xy 117.971316 -385.501388)
			(xy 117.970808 -385.501388) (xy 117.943122 -385.499356) (xy 117.942868 -385.499356) (xy 117.933399 -385.4984)
			(xy 117.914884 -385.502736) (xy 117.899232 -385.513535) (xy 117.893592 -385.5212) (xy 117.84203 -385.596892)
			(xy 117.837045 -385.605047) (xy 117.83286 -385.623677) (xy 117.835784 -385.642547) (xy 117.840252 -385.650994)
			(xy 117.955822 -385.850892) (xy 117.968645 -385.874225) (xy 117.986866 -385.924248) (xy 117.996127 -385.976673)
			(xy 117.996716 -386.003292) (xy 117.996231 -386.02727) (xy 117.988734 -386.074636) (xy 117.973924 -386.120248)
			(xy 117.952164 -386.162983) (xy 117.92399 -386.20179) (xy 117.890096 -386.235715) (xy 117.851313 -386.263923)
			(xy 117.808598 -386.28572) (xy 117.762999 -386.300571) (xy 117.71564 -386.30811) (xy 117.691662 -386.3086)
			(xy 117.691154 -386.3086) (xy 117.667582 -386.308163) (xy 117.620995 -386.300929) (xy 117.576078 -386.286611)
			(xy 117.533899 -386.26555) (xy 117.495466 -386.238247) (xy 117.461693 -386.205353) (xy 117.433385 -386.167653)
			(xy 117.421914 -386.147056) (xy 117.421406 -386.146294) (xy 117.407944 -386.122926) (xy 117.402563 -386.114472)
			(xy 117.386674 -386.102285) (xy 117.367331 -386.09711) (xy 117.347479 -386.099735) (xy 117.338602 -386.104384)
			(xy 117.329458 -386.109718) (xy 117.323362 -386.1181) (xy 117.312425 -386.131991) (xy 117.286345 -386.155857)
			(xy 117.256321 -386.17452) (xy 117.223377 -386.187344) (xy 117.188637 -386.193892) (xy 117.170962 -386.1943)
			(xy 117.170454 -386.1943) (xy 117.151678 -386.193845) (xy 117.114848 -386.186519) (xy 117.080152 -386.172155)
			(xy 117.048921 -386.151306) (xy 117.022351 -386.12477) (xy 117.001461 -386.093565) (xy 116.987053 -386.058888)
			(xy 116.979679 -386.022067) (xy 116.979192 -386.003292) (xy 116.979681 -385.984179) (xy 116.987241 -385.946709)
			(xy 117.002098 -385.911489) (xy 117.023658 -385.879925) (xy 117.051062 -385.853276) (xy 117.083216 -385.832605)
			(xy 117.100858 -385.825238) (xy 117.111018 -385.821174) (xy 117.126512 -385.805426) (xy 117.155722 -385.722114)
			(xy 117.15895 -385.711535) (xy 117.156971 -385.689532) (xy 117.151912 -385.679696) (xy 117.023642 -385.457954)
			(xy 117.011704 -385.433824) (xy 117.006875 -385.424308) (xy 116.991087 -385.409991) (xy 116.970849 -385.403308)
			(xy 116.94964 -385.405408) (xy 116.931106 -385.41593) (xy 116.924328 -385.424172) (xy 116.913374 -385.438243)
			(xy 116.887193 -385.462448) (xy 116.856978 -385.481377) (xy 116.823776 -385.494375) (xy 116.78874 -385.500989)
			(xy 116.770912 -385.501388) (xy 116.770404 -385.501388) (xy 116.763524 -385.501385) (xy 116.749794 -385.500495)
			(xy 116.742972 -385.49961) (xy 116.728494 -385.497324) (xy 116.701824 -385.509008) (xy 116.642134 -385.596892)
			(xy 116.637148 -385.605047) (xy 116.632964 -385.623677) (xy 116.635888 -385.642547) (xy 116.640356 -385.650994)
			(xy 116.755926 -385.850892) (xy 116.76875 -385.874225) (xy 116.786971 -385.924247) (xy 116.796231 -385.976673)
			(xy 116.79682 -386.003292) (xy 116.796331 -386.02727) (xy 116.788835 -386.074636) (xy 116.774024 -386.120247)
			(xy 116.752265 -386.162982) (xy 116.724092 -386.201789) (xy 116.690197 -386.235713) (xy 116.651416 -386.263922)
			(xy 116.6087 -386.285719) (xy 116.563102 -386.30057) (xy 116.515743 -386.30811) (xy 116.491766 -386.3086)
			(xy 116.491258 -386.3086) (xy 116.467686 -386.308159) (xy 116.4211 -386.300927) (xy 116.376182 -386.286609)
			(xy 116.334004 -386.265548) (xy 116.29557 -386.238246) (xy 116.261797 -386.205353) (xy 116.23349 -386.167653)
			(xy 116.222018 -386.147056) (xy 116.22151 -386.146294) (xy 116.208048 -386.122926) (xy 116.202663 -386.114475)
			(xy 116.186776 -386.102288) (xy 116.167433 -386.097113) (xy 116.147583 -386.099736) (xy 116.138706 -386.104384)
			(xy 116.129562 -386.109718) (xy 116.123466 -386.1181) (xy 116.112526 -386.131989) (xy 116.086447 -386.155855)
			(xy 116.056424 -386.174519) (xy 116.023481 -386.187343) (xy 115.988741 -386.193892) (xy 115.971066 -386.1943)
			(xy 115.970558 -386.1943) (xy 115.951782 -386.193842) (xy 115.914953 -386.186516) (xy 115.880257 -386.172153)
			(xy 115.849025 -386.151304) (xy 115.822455 -386.124769) (xy 115.801565 -386.093564) (xy 115.787157 -386.058887)
			(xy 115.779783 -386.022067) (xy 115.779296 -386.003292) (xy 115.779782 -385.984179) (xy 115.787343 -385.946708)
			(xy 115.8022 -385.911488) (xy 115.823761 -385.879924) (xy 115.851165 -385.853275) (xy 115.88332 -385.832605)
			(xy 115.900962 -385.825238) (xy 115.911122 -385.821174) (xy 115.926616 -385.805426) (xy 115.955826 -385.722114)
			(xy 115.959053 -385.711535) (xy 115.957074 -385.689532) (xy 115.952016 -385.679696) (xy 115.823746 -385.457954)
			(xy 115.811808 -385.433824) (xy 115.806973 -385.424311) (xy 115.791187 -385.409994) (xy 115.770951 -385.403311)
			(xy 115.749743 -385.40541) (xy 115.73121 -385.415931) (xy 115.724432 -385.424172) (xy 115.713475 -385.438241)
			(xy 115.687295 -385.462446) (xy 115.65708 -385.481376) (xy 115.623879 -385.494374) (xy 115.588843 -385.500989)
			(xy 115.571016 -385.501388) (xy 115.570508 -385.501388) (xy 115.563628 -385.501385) (xy 115.549898 -385.500495)
			(xy 115.543076 -385.49961) (xy 115.528598 -385.497324) (xy 115.501928 -385.509008) (xy 115.442238 -385.596892)
			(xy 115.437252 -385.605047) (xy 115.433067 -385.623677) (xy 115.435991 -385.642547) (xy 115.44046 -385.650994)
			(xy 115.55603 -385.850892) (xy 115.568854 -385.874225) (xy 115.587075 -385.924247) (xy 115.596335 -385.976673)
			(xy 115.596924 -386.003292) (xy 115.596431 -386.02727) (xy 115.588935 -386.074635) (xy 115.574125 -386.120246)
			(xy 115.552366 -386.16298) (xy 115.524193 -386.201787) (xy 115.490299 -386.235712) (xy 115.451518 -386.26392)
			(xy 115.408803 -386.285718) (xy 115.363206 -386.30057) (xy 115.315847 -386.308109) (xy 115.29187 -386.3086)
			(xy 115.291362 -386.3086) (xy 115.26779 -386.308156) (xy 115.221204 -386.300924) (xy 115.176286 -386.286607)
			(xy 115.134108 -386.265547) (xy 115.095674 -386.238245) (xy 115.061901 -386.205352) (xy 115.033594 -386.167653)
			(xy 115.022122 -386.147056) (xy 115.021614 -386.146294) (xy 115.008152 -386.122926) (xy 115.002763 -386.114478)
			(xy 114.986877 -386.102291) (xy 114.967536 -386.097115) (xy 114.947687 -386.099737) (xy 114.93881 -386.104384)
			(xy 114.929666 -386.109718) (xy 114.92357 -386.1181) (xy 114.912628 -386.131987) (xy 114.886549 -386.155853)
			(xy 114.856527 -386.174517) (xy 114.823584 -386.187342) (xy 114.788845 -386.193892) (xy 114.77117 -386.1943)
			(xy 114.770662 -386.1943) (xy 114.751887 -386.193838) (xy 114.715057 -386.186513) (xy 114.680361 -386.172151)
			(xy 114.649129 -386.151303) (xy 114.622559 -386.124768) (xy 114.601669 -386.093563) (xy 114.587261 -386.058887)
			(xy 114.579887 -386.022067) (xy 114.5794 -386.003292) (xy 114.579884 -385.984179) (xy 114.587444 -385.946708)
			(xy 114.602302 -385.911488) (xy 114.623863 -385.879923) (xy 114.651268 -385.853274) (xy 114.683424 -385.832604)
			(xy 114.701066 -385.825238) (xy 114.711226 -385.821174) (xy 114.72672 -385.805426) (xy 114.75593 -385.722114)
			(xy 114.759157 -385.711535) (xy 114.757178 -385.689532) (xy 114.75212 -385.679696) (xy 114.62385 -385.457954)
			(xy 114.611912 -385.433824) (xy 114.607072 -385.424314) (xy 114.591287 -385.409998) (xy 114.571052 -385.403315)
			(xy 114.549846 -385.405413) (xy 114.531313 -385.415932) (xy 114.524536 -385.424172) (xy 114.513594 -385.438221)
			(xy 114.487458 -385.462398) (xy 114.457297 -385.481317) (xy 114.424154 -385.494324) (xy 114.389175 -385.500967)
			(xy 114.371374 -385.501388) (xy 114.370866 -385.501388) (xy 114.350846 -385.500901) (xy 114.311681 -385.49257)
			(xy 114.275103 -385.476279) (xy 114.242712 -385.45274) (xy 114.215922 -385.422982) (xy 114.195903 -385.388304)
			(xy 114.183531 -385.350222) (xy 114.179346 -385.3104) (xy 98.671394 -385.3104) (xy 98.9838 -385.850892)
			(xy 98.996533 -385.87421) (xy 99.014627 -385.924158) (xy 99.023843 -385.976477) (xy 99.02444 -386.003038)
			(xy 99.02444 -386.003292) (xy 99.02393 -386.027281) (xy 99.016426 -386.07467) (xy 99.001602 -386.120301)
			(xy 98.979822 -386.163051) (xy 98.951623 -386.201869) (xy 98.917699 -386.235797) (xy 98.878886 -386.264001)
			(xy 98.836138 -386.285787) (xy 98.790509 -386.300617) (xy 98.743121 -386.308127) (xy 98.719132 -386.3086)
			(xy 98.695559 -386.30818) (xy 98.648972 -386.300944) (xy 98.604054 -386.286623) (xy 98.561875 -386.265558)
			(xy 98.523442 -386.238253) (xy 98.48967 -386.205357) (xy 98.461363 -386.167654) (xy 98.449892 -386.147056)
			(xy 98.449384 -386.146294) (xy 98.435922 -386.122926) (xy 98.430564 -386.114455) (xy 98.414667 -386.102269)
			(xy 98.395315 -386.097098) (xy 98.375458 -386.09973) (xy 98.36658 -386.104384) (xy 98.357436 -386.109718)
			(xy 98.35134 -386.1181) (xy 98.340415 -386.132002) (xy 98.314332 -386.155866) (xy 98.284305 -386.174528)
			(xy 98.251359 -386.18735) (xy 98.216616 -386.193894) (xy 98.19894 -386.1943) (xy 98.198432 -386.1943)
			(xy 98.179662 -386.193849) (xy 98.142843 -386.186531) (xy 98.10816 -386.172169) (xy 98.076945 -386.151316)
			(xy 98.050399 -386.124774) (xy 98.029542 -386.093562) (xy 98.015176 -386.05888) (xy 98.007853 -386.022062)
			(xy 98.007424 -386.003292) (xy 98.007883 -385.984197) (xy 98.015453 -385.946764) (xy 98.030289 -385.911574)
			(xy 98.051805 -385.880021) (xy 98.079146 -385.853358) (xy 98.111228 -385.832641) (xy 98.128836 -385.825238)
			(xy 98.138996 -385.821174) (xy 98.15449 -385.805426) (xy 98.1837 -385.722114) (xy 98.18693 -385.711536)
			(xy 98.18495 -385.689531) (xy 98.17989 -385.679696) (xy 98.05162 -385.457954) (xy 98.039428 -385.43357)
			(xy 98.034563 -385.424072) (xy 98.018789 -385.409746) (xy 97.998558 -385.403056) (xy 97.977354 -385.405153)
			(xy 97.958825 -385.415676) (xy 97.952052 -385.423918) (xy 97.941092 -385.438) (xy 97.914934 -385.462263)
			(xy 97.884729 -385.481251) (xy 97.851524 -385.494303) (xy 97.816474 -385.500967) (xy 97.798636 -385.501388)
			(xy 97.798128 -385.501388) (xy 97.791248 -385.501383) (xy 97.777519 -385.500494) (xy 97.770696 -385.49961)
			(xy 97.756218 -385.497324) (xy 97.729548 -385.509008) (xy 97.669858 -385.596892) (xy 97.664876 -385.605047)
			(xy 97.660698 -385.623677) (xy 97.663617 -385.642546) (xy 97.66808 -385.650994) (xy 97.78365 -385.850892)
			(xy 97.796476 -385.874224) (xy 97.814695 -385.924247) (xy 97.823955 -385.976673) (xy 97.824544 -386.003292)
			(xy 97.824031 -386.027269) (xy 97.816535 -386.074632) (xy 97.801727 -386.120241) (xy 97.779969 -386.162974)
			(xy 97.751799 -386.20178) (xy 97.717907 -386.235705) (xy 97.679129 -386.263913) (xy 97.636417 -386.285712)
			(xy 97.590822 -386.300566) (xy 97.543466 -386.308108) (xy 97.51949 -386.3086) (xy 97.518982 -386.3086)
			(xy 97.495407 -386.308221) (xy 97.448819 -386.300977) (xy 97.4039 -386.286648) (xy 97.361721 -386.265577)
			(xy 97.323288 -386.238265) (xy 97.289517 -386.205364) (xy 97.261212 -386.167657) (xy 97.249742 -386.147056)
			(xy 97.249234 -386.146294) (xy 97.235772 -386.122926) (xy 97.230363 -386.114493) (xy 97.214484 -386.102306)
			(xy 97.19515 -386.097126) (xy 97.175306 -386.099741) (xy 97.16643 -386.104384) (xy 97.157286 -386.109718)
			(xy 97.15119 -386.1181) (xy 97.140237 -386.131978) (xy 97.114161 -386.155845) (xy 97.084141 -386.17451)
			(xy 97.051201 -386.187338) (xy 97.016464 -386.19389) (xy 96.99879 -386.1943) (xy 96.998282 -386.1943)
			(xy 96.979507 -386.19382) (xy 96.942678 -386.186498) (xy 96.907983 -386.17214) (xy 96.876751 -386.151294)
			(xy 96.85018 -386.124762) (xy 96.82929 -386.09356) (xy 96.814881 -386.058884) (xy 96.807507 -386.022066)
			(xy 96.80702 -386.003292) (xy 96.807491 -385.984178) (xy 96.815053 -385.946706) (xy 96.829912 -385.911484)
			(xy 96.851476 -385.87992) (xy 96.878884 -385.853271) (xy 96.911042 -385.832603) (xy 96.928686 -385.825238)
			(xy 96.938846 -385.821174) (xy 96.95434 -385.805426) (xy 96.98355 -385.722114) (xy 96.986774 -385.711535)
			(xy 96.984796 -385.689532) (xy 96.97974 -385.679696) (xy 96.85147 -385.457954) (xy 96.839532 -385.433824)
			(xy 96.834663 -385.424331) (xy 96.818887 -385.410017) (xy 96.79866 -385.403332) (xy 96.777461 -385.405425)
			(xy 96.758933 -385.415937) (xy 96.752156 -385.424172) (xy 96.741185 -385.43823) (xy 96.715009 -385.462436)
			(xy 96.684798 -385.481367) (xy 96.6516 -385.494368) (xy 96.616566 -385.500987) (xy 96.59874 -385.501388)
			(xy 96.598232 -385.501388) (xy 96.591352 -385.501382) (xy 96.577623 -385.500494) (xy 96.5708 -385.49961)
			(xy 96.556322 -385.497324) (xy 96.529652 -385.509008) (xy 96.469962 -385.596892) (xy 96.46498 -385.605047)
			(xy 96.460801 -385.623677) (xy 96.463721 -385.642546) (xy 96.468184 -385.650994) (xy 96.583754 -385.850892)
			(xy 96.59658 -385.874224) (xy 96.614799 -385.924247) (xy 96.624059 -385.976673) (xy 96.624648 -386.003292)
			(xy 96.624131 -386.027268) (xy 96.616636 -386.074632) (xy 96.601827 -386.12024) (xy 96.58007 -386.162973)
			(xy 96.5519 -386.201779) (xy 96.518009 -386.235703) (xy 96.479231 -386.263912) (xy 96.43652 -386.285711)
			(xy 96.390926 -386.300565) (xy 96.34357 -386.308107) (xy 96.319594 -386.3086) (xy 96.319086 -386.3086)
			(xy 96.295512 -386.308217) (xy 96.248923 -386.300974) (xy 96.204004 -386.286646) (xy 96.161826 -386.265576)
			(xy 96.123393 -386.238264) (xy 96.089621 -386.205363) (xy 96.061316 -386.167656) (xy 96.049846 -386.147056)
			(xy 96.049338 -386.146294) (xy 96.035876 -386.122926) (xy 96.030463 -386.114496) (xy 96.014586 -386.102309)
			(xy 95.995253 -386.097128) (xy 95.97541 -386.099742) (xy 95.966534 -386.104384) (xy 95.95739 -386.109718)
			(xy 95.951294 -386.1181) (xy 95.940338 -386.131976) (xy 95.914263 -386.155843) (xy 95.884244 -386.174509)
			(xy 95.851304 -386.187337) (xy 95.816568 -386.19389) (xy 95.798894 -386.1943) (xy 95.798386 -386.1943)
			(xy 95.779611 -386.193816) (xy 95.742783 -386.186496) (xy 95.708087 -386.172137) (xy 95.676855 -386.151293)
			(xy 95.650284 -386.124761) (xy 95.629394 -386.093559) (xy 95.614985 -386.058884) (xy 95.607611 -386.022066)
			(xy 95.607124 -386.003292) (xy 95.607593 -385.984178) (xy 95.615154 -385.946705) (xy 95.630014 -385.911484)
			(xy 95.651578 -385.879919) (xy 95.678987 -385.853271) (xy 95.711146 -385.832603) (xy 95.72879 -385.825238)
			(xy 95.73895 -385.821174) (xy 95.754444 -385.805426) (xy 95.783654 -385.722114) (xy 95.786878 -385.711535)
			(xy 95.7849 -385.689532) (xy 95.779844 -385.679696) (xy 95.651574 -385.457954) (xy 95.639636 -385.433824)
			(xy 95.634762 -385.424334) (xy 95.618987 -385.410021) (xy 95.598762 -385.403336) (xy 95.577564 -385.405428)
			(xy 95.559037 -385.415938) (xy 95.55226 -385.424172) (xy 95.541304 -385.438209) (xy 95.515172 -385.462388)
			(xy 95.485014 -385.481309) (xy 95.451874 -385.494318) (xy 95.416898 -385.500965) (xy 95.399098 -385.501388)
			(xy 95.39859 -385.501388) (xy 95.370904 -385.499356) (xy 95.37065 -385.499356) (xy 95.361182 -385.498385)
			(xy 95.342665 -385.502727) (xy 95.327013 -385.513533) (xy 95.321374 -385.5212) (xy 95.269812 -385.596892)
			(xy 95.264828 -385.605047) (xy 95.260645 -385.623677) (xy 95.263567 -385.642547) (xy 95.268034 -385.650994)
			(xy 95.383604 -385.850892) (xy 95.396337 -385.87421) (xy 95.414431 -385.924158) (xy 95.423647 -385.976477)
			(xy 95.424244 -386.003038) (xy 95.424244 -386.003292) (xy 95.42373 -386.027281) (xy 95.416226 -386.074669)
			(xy 95.401402 -386.1203) (xy 95.379623 -386.16305) (xy 95.351424 -386.201867) (xy 95.317501 -386.235796)
			(xy 95.278688 -386.264) (xy 95.235941 -386.285785) (xy 95.190312 -386.300616) (xy 95.142925 -386.308127)
			(xy 95.118936 -386.3086) (xy 95.095363 -386.308177) (xy 95.048776 -386.300941) (xy 95.003858 -386.286621)
			(xy 94.96168 -386.265557) (xy 94.923246 -386.238252) (xy 94.889474 -386.205356) (xy 94.861167 -386.167654)
			(xy 94.849696 -386.147056) (xy 94.849188 -386.146294) (xy 94.835726 -386.122926) (xy 94.830364 -386.114458)
			(xy 94.814468 -386.102272) (xy 94.795118 -386.0971) (xy 94.775262 -386.099731) (xy 94.766384 -386.104384)
			(xy 94.75724 -386.109718) (xy 94.751144 -386.1181) (xy 94.740217 -386.132) (xy 94.714134 -386.155865)
			(xy 94.684108 -386.174527) (xy 94.651162 -386.187349) (xy 94.61642 -386.193894) (xy 94.598744 -386.1943)
			(xy 94.598236 -386.1943) (xy 94.579466 -386.193846) (xy 94.542647 -386.186528) (xy 94.507964 -386.172167)
			(xy 94.476749 -386.151315) (xy 94.450203 -386.124773) (xy 94.429346 -386.093561) (xy 94.41498 -386.058879)
			(xy 94.407657 -386.022062) (xy 94.407228 -386.003292) (xy 94.407685 -385.984197) (xy 94.415254 -385.946764)
			(xy 94.430091 -385.911573) (xy 94.451607 -385.880021) (xy 94.478949 -385.853357) (xy 94.511032 -385.83264)
			(xy 94.52864 -385.825238) (xy 94.5388 -385.821174) (xy 94.554294 -385.805426) (xy 94.583504 -385.722114)
			(xy 94.586734 -385.711536) (xy 94.584754 -385.689532) (xy 94.579694 -385.679696) (xy 94.451424 -385.457954)
			(xy 94.439486 -385.433824) (xy 94.434682 -385.424293) (xy 94.418887 -385.409974) (xy 94.398642 -385.403292)
			(xy 94.377426 -385.405397) (xy 94.358888 -385.415927) (xy 94.35211 -385.424172) (xy 94.341166 -385.438252)
			(xy 94.314983 -385.462456) (xy 94.284765 -385.481384) (xy 94.251561 -385.494379) (xy 94.216522 -385.500991)
			(xy 94.198694 -385.501388) (xy 94.198186 -385.501388) (xy 94.191306 -385.501387) (xy 94.177576 -385.500496)
			(xy 94.170754 -385.49961) (xy 94.156276 -385.497324) (xy 94.129606 -385.509008) (xy 94.069916 -385.596892)
			(xy 94.064931 -385.605047) (xy 94.060748 -385.623677) (xy 94.063671 -385.642547) (xy 94.068138 -385.650994)
			(xy 94.183708 -385.850892) (xy 94.196441 -385.87421) (xy 94.214535 -385.924158) (xy 94.223751 -385.976477)
			(xy 94.224348 -386.003038) (xy 94.224348 -386.003292) (xy 94.22383 -386.027281) (xy 94.216326 -386.074669)
			(xy 94.201503 -386.120299) (xy 94.179724 -386.163049) (xy 94.151525 -386.201866) (xy 94.117603 -386.235794)
			(xy 94.07879 -386.263998) (xy 94.036043 -386.285784) (xy 93.990415 -386.300615) (xy 93.943029 -386.308126)
			(xy 93.91904 -386.3086) (xy 93.895467 -386.308174) (xy 93.84888 -386.300939) (xy 93.803963 -386.286618)
			(xy 93.761784 -386.265555) (xy 93.723351 -386.238251) (xy 93.689578 -386.205355) (xy 93.661271 -386.167654)
			(xy 93.6498 -386.147056) (xy 93.649292 -386.146294) (xy 93.63583 -386.122926) (xy 93.630464 -386.114461)
			(xy 93.61457 -386.102275) (xy 93.595221 -386.097102) (xy 93.575366 -386.099732) (xy 93.566488 -386.104384)
			(xy 93.557344 -386.109718) (xy 93.551248 -386.1181) (xy 93.540318 -386.131998) (xy 93.514236 -386.155863)
			(xy 93.484211 -386.174525) (xy 93.451265 -386.187348) (xy 93.416524 -386.193894) (xy 93.398848 -386.1943)
			(xy 93.39834 -386.1943) (xy 93.379571 -386.193842) (xy 93.342752 -386.186525) (xy 93.308068 -386.172165)
			(xy 93.276853 -386.151313) (xy 93.250307 -386.124771) (xy 93.22945 -386.09356) (xy 93.215084 -386.058879)
			(xy 93.207761 -386.022061) (xy 93.207332 -386.003292) (xy 93.207786 -385.984197) (xy 93.215356 -385.946764)
			(xy 93.230193 -385.911573) (xy 93.25171 -385.88002) (xy 93.279052 -385.853357) (xy 93.311136 -385.83264)
			(xy 93.328744 -385.825238) (xy 93.338904 -385.821174) (xy 93.354398 -385.805426) (xy 93.383608 -385.722114)
			(xy 93.386837 -385.711536) (xy 93.384858 -385.689532) (xy 93.379798 -385.679696) (xy 93.251528 -385.457954)
			(xy 93.23959 -385.433824) (xy 93.23478 -385.424296) (xy 93.218987 -385.409978) (xy 93.198743 -385.403296)
			(xy 93.177529 -385.4054) (xy 93.158992 -385.415927) (xy 93.152214 -385.424172) (xy 93.141268 -385.43825)
			(xy 93.115085 -385.462454) (xy 93.084868 -385.481382) (xy 93.051664 -385.494378) (xy 93.016626 -385.500991)
			(xy 92.998798 -385.501388) (xy 92.99829 -385.501388) (xy 92.99141 -385.501387) (xy 92.97768 -385.500496)
			(xy 92.970858 -385.49961) (xy 92.95638 -385.497324) (xy 92.92971 -385.509008) (xy 92.87002 -385.596892)
			(xy 92.865035 -385.605047) (xy 92.860852 -385.623677) (xy 92.863775 -385.642547) (xy 92.868242 -385.650994)
			(xy 92.983812 -385.850892) (xy 92.996546 -385.87421) (xy 93.014639 -385.924158) (xy 93.023855 -385.976477)
			(xy 93.024452 -386.003038) (xy 93.024452 -386.003292) (xy 93.02393 -386.027281) (xy 93.016427 -386.074668)
			(xy 93.001603 -386.120298) (xy 92.979824 -386.163048) (xy 92.951627 -386.201865) (xy 92.917704 -386.235793)
			(xy 92.878892 -386.263997) (xy 92.836146 -386.285783) (xy 92.790519 -386.300614) (xy 92.743133 -386.308126)
			(xy 92.719144 -386.3086) (xy 92.695571 -386.308171) (xy 92.648985 -386.300936) (xy 92.604067 -386.286616)
			(xy 92.561889 -386.265554) (xy 92.523455 -386.238249) (xy 92.489682 -386.205355) (xy 92.461375 -386.167654)
			(xy 92.449904 -386.147056) (xy 92.449396 -386.146294) (xy 92.435934 -386.122926) (xy 92.430563 -386.114464)
			(xy 92.414671 -386.102278) (xy 92.395324 -386.097105) (xy 92.37547 -386.099733) (xy 92.366592 -386.104384)
			(xy 92.357448 -386.109718) (xy 92.351352 -386.1181) (xy 92.34042 -386.131996) (xy 92.314339 -386.155861)
			(xy 92.284314 -386.174524) (xy 92.251369 -386.187347) (xy 92.216628 -386.193893) (xy 92.198952 -386.1943)
			(xy 92.198444 -386.1943) (xy 92.179675 -386.193839) (xy 92.142856 -386.186522) (xy 92.108173 -386.172163)
			(xy 92.076958 -386.151311) (xy 92.050412 -386.12477) (xy 92.029554 -386.093559) (xy 92.015188 -386.058879)
			(xy 92.007865 -386.022061) (xy 92.007436 -386.003292) (xy 92.007888 -385.984196) (xy 92.015458 -385.946763)
			(xy 92.030295 -385.911572) (xy 92.051812 -385.880019) (xy 92.079155 -385.853356) (xy 92.111239 -385.83264)
			(xy 92.128848 -385.825238) (xy 92.139008 -385.821174) (xy 92.154502 -385.805426) (xy 92.183712 -385.722114)
			(xy 92.186941 -385.711535) (xy 92.184961 -385.689532) (xy 92.179902 -385.679696) (xy 92.051632 -385.457954)
			(xy 92.039694 -385.433824) (xy 92.034879 -385.4243) (xy 92.019087 -385.409981) (xy 91.998845 -385.403299)
			(xy 91.977632 -385.405402) (xy 91.959096 -385.415928) (xy 91.952318 -385.424172) (xy 91.941386 -385.438229)
			(xy 91.915248 -385.462406) (xy 91.885084 -385.481324) (xy 91.851939 -385.494328) (xy 91.816958 -385.500969)
			(xy 91.799156 -385.501388) (xy 91.798648 -385.501388) (xy 91.770962 -385.499356) (xy 91.770708 -385.499356)
			(xy 91.761238 -385.498432) (xy 91.742726 -385.502753) (xy 91.727074 -385.513541) (xy 91.721432 -385.5212)
			(xy 91.66987 -385.596892) (xy 91.664887 -385.605047) (xy 91.660708 -385.623677) (xy 91.663628 -385.642546)
			(xy 91.668092 -385.650994) (xy 91.783662 -385.850892) (xy 91.796489 -385.874224) (xy 91.814708 -385.924247)
			(xy 91.823967 -385.976673) (xy 91.824556 -386.003292) (xy 91.824031 -386.027268) (xy 91.816536 -386.07463)
			(xy 91.801728 -386.120239) (xy 91.779972 -386.162971) (xy 91.751802 -386.201776) (xy 91.717912 -386.235701)
			(xy 91.679135 -386.263909) (xy 91.636425 -386.285709) (xy 91.590832 -386.300563) (xy 91.543477 -386.308107)
			(xy 91.519502 -386.3086) (xy 91.518994 -386.3086) (xy 91.49542 -386.308211) (xy 91.448831 -386.300969)
			(xy 91.403913 -386.286642) (xy 91.361734 -386.265573) (xy 91.323301 -386.238262) (xy 91.28953 -386.205362)
			(xy 91.261224 -386.167656) (xy 91.249754 -386.147056) (xy 91.249246 -386.146294) (xy 91.235784 -386.122926)
			(xy 91.230363 -386.114502) (xy 91.214489 -386.102315) (xy 91.195159 -386.097132) (xy 91.175317 -386.099743)
			(xy 91.166442 -386.104384) (xy 91.157298 -386.109718) (xy 91.151202 -386.1181) (xy 91.140242 -386.131972)
			(xy 91.114168 -386.155839) (xy 91.08415 -386.174506) (xy 91.051211 -386.187335) (xy 91.016476 -386.193889)
			(xy 90.998802 -386.1943) (xy 90.998294 -386.1943) (xy 90.97952 -386.193809) (xy 90.942691 -386.186489)
			(xy 90.907996 -386.172133) (xy 90.876764 -386.151289) (xy 90.850193 -386.124758) (xy 90.829303 -386.093557)
			(xy 90.814894 -386.058883) (xy 90.80752 -386.022066) (xy 90.807032 -386.003292) (xy 90.807496 -385.984177)
			(xy 90.815058 -385.946704) (xy 90.829918 -385.911482) (xy 90.851483 -385.879917) (xy 90.878893 -385.853269)
			(xy 90.911053 -385.832602) (xy 90.928698 -385.825238) (xy 90.938858 -385.821174) (xy 90.954352 -385.805426)
			(xy 90.983562 -385.722114) (xy 90.986785 -385.711535) (xy 90.984808 -385.689532) (xy 90.979752 -385.679696)
			(xy 90.851482 -385.457954) (xy 90.839544 -385.433824) (xy 90.834799 -385.424258) (xy 90.818987 -385.409934)
			(xy 90.798724 -385.403256) (xy 90.777494 -385.405372) (xy 90.758947 -385.415917) (xy 90.752168 -385.424172)
			(xy 90.741191 -385.438224) (xy 90.715016 -385.46243) (xy 90.684806 -385.481363) (xy 90.65161 -385.494365)
			(xy 90.616578 -385.500986) (xy 90.598752 -385.501388) (xy 90.598244 -385.501388) (xy 90.591364 -385.501381)
			(xy 90.577635 -385.500494) (xy 90.570812 -385.49961) (xy 90.556334 -385.497324) (xy 90.529664 -385.509008)
			(xy 90.469974 -385.596892) (xy 90.464991 -385.605047) (xy 90.460811 -385.623677) (xy 90.463732 -385.642546)
			(xy 90.468196 -385.650994) (xy 90.583766 -385.850892) (xy 90.596593 -385.874223) (xy 90.614812 -385.924247)
			(xy 90.624071 -385.976673) (xy 90.62466 -386.003292) (xy 90.624231 -386.027273) (xy 90.616732 -386.074644)
			(xy 90.601919 -386.120261) (xy 90.580154 -386.162999) (xy 90.551974 -386.201809) (xy 90.518072 -386.235735)
			(xy 90.479282 -386.263942) (xy 90.436559 -386.285737) (xy 90.390953 -386.300582) (xy 90.343586 -386.308114)
			(xy 90.319606 -386.3086) (xy 90.319098 -386.3086) (xy 90.295524 -386.308208) (xy 90.248936 -386.300966)
			(xy 90.204017 -386.28664) (xy 90.161839 -386.265571) (xy 90.123406 -386.238261) (xy 90.089634 -386.205361)
			(xy 90.061328 -386.167656) (xy 90.049858 -386.147056) (xy 90.04935 -386.146294) (xy 90.035888 -386.122926)
			(xy 90.030463 -386.114504) (xy 90.01459 -386.102318) (xy 89.995261 -386.097134) (xy 89.975421 -386.099744)
			(xy 89.966546 -386.104384) (xy 89.957402 -386.109718) (xy 89.951306 -386.1181) (xy 89.9404 -386.132018)
			(xy 89.914312 -386.155881) (xy 89.884281 -386.17454) (xy 89.85133 -386.187358) (xy 89.816584 -386.193897)
			(xy 89.798906 -386.1943) (xy 89.798398 -386.1943) (xy 89.779624 -386.193805) (xy 89.742796 -386.186486)
			(xy 89.7081 -386.17213) (xy 89.676868 -386.151287) (xy 89.650297 -386.124757) (xy 89.629407 -386.093556)
			(xy 89.614998 -386.058883) (xy 89.607624 -386.022065) (xy 89.607136 -386.003292) (xy 89.607597 -385.984177)
			(xy 89.615159 -385.946704) (xy 89.63002 -385.911482) (xy 89.651586 -385.879917) (xy 89.678996 -385.853269)
			(xy 89.711157 -385.832602) (xy 89.728802 -385.825238) (xy 89.738962 -385.821174) (xy 89.754456 -385.805426)
			(xy 89.783666 -385.722114) (xy 89.786889 -385.711535) (xy 89.784911 -385.689532) (xy 89.779856 -385.679696)
			(xy 89.651586 -385.457954) (xy 89.639648 -385.433824) (xy 89.634898 -385.424262) (xy 89.619087 -385.409938)
			(xy 89.598826 -385.403259) (xy 89.577597 -385.405374) (xy 89.559051 -385.415918) (xy 89.552272 -385.424172)
			(xy 89.541367 -385.438251) (xy 89.515222 -385.462426) (xy 89.485051 -385.48134) (xy 89.4519 -385.494339)
			(xy 89.416914 -385.500973) (xy 89.39911 -385.501388) (xy 89.398602 -385.501388) (xy 89.370916 -385.499356)
			(xy 89.370662 -385.499356) (xy 89.361193 -385.498395) (xy 89.342678 -385.502733) (xy 89.327026 -385.513535)
			(xy 89.321386 -385.5212) (xy 89.269824 -385.596892) (xy 89.264839 -385.605047) (xy 89.260655 -385.623677)
			(xy 89.263578 -385.642547) (xy 89.268046 -385.650994) (xy 89.383616 -385.850892) (xy 89.39635 -385.874209)
			(xy 89.414443 -385.924158) (xy 89.423659 -385.976477) (xy 89.424256 -386.003038) (xy 89.424256 -386.003292)
			(xy 89.42373 -386.027281) (xy 89.416227 -386.074667) (xy 89.401403 -386.120297) (xy 89.379625 -386.163047)
			(xy 89.351428 -386.201863) (xy 89.317506 -386.235791) (xy 89.278694 -386.263996) (xy 89.235949 -386.285782)
			(xy 89.190322 -386.300614) (xy 89.142937 -386.308126) (xy 89.118948 -386.3086) (xy 89.095375 -386.308168)
			(xy 89.048789 -386.300933) (xy 89.003871 -386.286614) (xy 88.961693 -386.265552) (xy 88.923259 -386.238248)
			(xy 88.889486 -386.205354) (xy 88.861179 -386.167654) (xy 88.849708 -386.147056) (xy 88.8492 -386.146294)
			(xy 88.835738 -386.122926) (xy 88.830363 -386.114467) (xy 88.814472 -386.102281) (xy 88.795126 -386.097107)
			(xy 88.775274 -386.099734) (xy 88.766396 -386.104384) (xy 88.757252 -386.109718) (xy 88.751156 -386.1181)
			(xy 88.740222 -386.131994) (xy 88.714141 -386.155859) (xy 88.684116 -386.174522) (xy 88.651172 -386.187346)
			(xy 88.616432 -386.193893) (xy 88.598756 -386.1943) (xy 88.598248 -386.1943) (xy 88.579479 -386.193835)
			(xy 88.54266 -386.18652) (xy 88.507977 -386.17216) (xy 88.476762 -386.15131) (xy 88.450216 -386.124769)
			(xy 88.429358 -386.093558) (xy 88.414992 -386.058878) (xy 88.407669 -386.022061) (xy 88.40724 -386.003292)
			(xy 88.407689 -385.984196) (xy 88.415259 -385.946763) (xy 88.430097 -385.911571) (xy 88.451615 -385.880018)
			(xy 88.478958 -385.853355) (xy 88.511043 -385.83264) (xy 88.528652 -385.825238) (xy 88.538812 -385.821174)
			(xy 88.554306 -385.805426) (xy 88.583516 -385.722114) (xy 88.586745 -385.711535) (xy 88.584765 -385.689532)
			(xy 88.579706 -385.679696) (xy 88.451436 -385.457954) (xy 88.439498 -385.433824) (xy 88.434677 -385.424303)
			(xy 88.418887 -385.409985) (xy 88.398646 -385.403303) (xy 88.377435 -385.405404) (xy 88.3589 -385.415929)
			(xy 88.352122 -385.424172) (xy 88.341171 -385.438246) (xy 88.314989 -385.46245) (xy 88.284773 -385.481379)
			(xy 88.251571 -385.494376) (xy 88.216534 -385.50099) (xy 88.198706 -385.501388) (xy 88.198198 -385.501388)
			(xy 88.191318 -385.501386) (xy 88.177588 -385.500495) (xy 88.170766 -385.49961) (xy 88.156288 -385.497324)
			(xy 88.129618 -385.509008) (xy 88.069928 -385.596892) (xy 88.064943 -385.605047) (xy 88.060759 -385.623677)
			(xy 88.063682 -385.642547) (xy 88.06815 -385.650994) (xy 88.18372 -385.850892) (xy 88.196454 -385.874209)
			(xy 88.214548 -385.924158) (xy 88.223763 -385.976476) (xy 88.22436 -386.003038) (xy 88.22436 -386.003292)
			(xy 88.223954 -386.027287) (xy 88.216447 -386.074687) (xy 88.201617 -386.120329) (xy 88.179828 -386.163088)
			(xy 88.151618 -386.201912) (xy 88.117682 -386.235844) (xy 88.078854 -386.264049) (xy 88.036092 -386.285832)
			(xy 87.990448 -386.300657) (xy 87.943047 -386.308157) (xy 87.919052 -386.3086) (xy 87.895479 -386.308164)
			(xy 87.848893 -386.300931) (xy 87.803976 -386.286612) (xy 87.761797 -386.265551) (xy 87.723364 -386.238247)
			(xy 87.689591 -386.205354) (xy 87.661283 -386.167653) (xy 87.649812 -386.147056) (xy 87.649304 -386.146294)
			(xy 87.635842 -386.122926) (xy 87.630463 -386.11447) (xy 87.614574 -386.102284) (xy 87.595229 -386.097109)
			(xy 87.575377 -386.099735) (xy 87.5665 -386.104384) (xy 87.557356 -386.109718) (xy 87.55126 -386.1181)
			(xy 87.540324 -386.131992) (xy 87.514243 -386.155858) (xy 87.484219 -386.174521) (xy 87.451276 -386.187345)
			(xy 87.416535 -386.193893) (xy 87.39886 -386.1943) (xy 87.398352 -386.1943) (xy 87.379583 -386.193891)
			(xy 87.342766 -386.18656) (xy 87.308088 -386.172187) (xy 87.276879 -386.151326) (xy 87.250338 -386.124778)
			(xy 87.229487 -386.093563) (xy 87.215124 -386.05888) (xy 87.207803 -386.022062) (xy 87.207344 -386.003292)
			(xy 87.207791 -385.984196) (xy 87.215361 -385.946762) (xy 87.230199 -385.911571) (xy 87.251717 -385.880018)
			(xy 87.279061 -385.853355) (xy 87.311147 -385.832639) (xy 87.328756 -385.825238) (xy 87.338916 -385.821174)
			(xy 87.35441 -385.805426) (xy 87.38362 -385.722114) (xy 87.386848 -385.711535) (xy 87.384869 -385.689532)
			(xy 87.37981 -385.679696) (xy 87.25154 -385.457954) (xy 87.239602 -385.433824) (xy 87.234776 -385.424306)
			(xy 87.218987 -385.409989) (xy 87.198748 -385.403306) (xy 87.177538 -385.405407) (xy 87.159004 -385.41593)
			(xy 87.152226 -385.424172) (xy 87.141273 -385.438244) (xy 87.115092 -385.462449) (xy 87.084876 -385.481378)
			(xy 87.051674 -385.494375) (xy 87.016638 -385.50099) (xy 86.99881 -385.501388) (xy 86.998302 -385.501388)
			(xy 86.991422 -385.501386) (xy 86.977692 -385.500495) (xy 86.97087 -385.49961) (xy 86.956392 -385.497324)
			(xy 86.929722 -385.509008) (xy 86.870032 -385.596892) (xy 86.865047 -385.605047) (xy 86.860862 -385.623677)
			(xy 86.863786 -385.642547) (xy 86.868254 -385.650994) (xy 86.983824 -385.850892) (xy 86.996559 -385.874209)
			(xy 87.014652 -385.924158) (xy 87.023867 -385.976476) (xy 87.024464 -386.003038) (xy 87.024464 -386.003292)
			(xy 87.024054 -386.027287) (xy 87.016547 -386.074687) (xy 87.001717 -386.120328) (xy 86.979929 -386.163087)
			(xy 86.951719 -386.201911) (xy 86.917783 -386.235843) (xy 86.878956 -386.264048) (xy 86.836195 -386.285831)
			(xy 86.790552 -386.300656) (xy 86.743151 -386.308157) (xy 86.719156 -386.3086) (xy 86.695584 -386.308161)
			(xy 86.648997 -386.300928) (xy 86.60408 -386.28661) (xy 86.561902 -386.265549) (xy 86.523468 -386.238246)
			(xy 86.489695 -386.205353) (xy 86.461387 -386.167653) (xy 86.449916 -386.147056) (xy 86.449408 -386.146294)
			(xy 86.435946 -386.122926) (xy 86.430563 -386.114473) (xy 86.414675 -386.102287) (xy 86.395332 -386.097111)
			(xy 86.375481 -386.099736) (xy 86.366604 -386.104384) (xy 86.35746 -386.109718) (xy 86.351364 -386.1181)
			(xy 86.340425 -386.13199) (xy 86.314346 -386.155856) (xy 86.284322 -386.174519) (xy 86.251379 -386.187344)
			(xy 86.216639 -386.193892) (xy 86.198964 -386.1943) (xy 86.198456 -386.1943) (xy 86.179687 -386.193888)
			(xy 86.142871 -386.186557) (xy 86.108192 -386.172185) (xy 86.076983 -386.151324) (xy 86.050443 -386.124777)
			(xy 86.029591 -386.093562) (xy 86.015228 -386.058879) (xy 86.007907 -386.022061) (xy 86.007448 -386.003292)
			(xy 86.007892 -385.984196) (xy 86.015463 -385.946762) (xy 86.030301 -385.91157) (xy 86.05182 -385.880017)
			(xy 86.079164 -385.853354) (xy 86.111251 -385.832639) (xy 86.12886 -385.825238) (xy 86.13902 -385.821174)
			(xy 86.154514 -385.805426) (xy 86.183724 -385.722114) (xy 86.186952 -385.711535) (xy 86.184973 -385.689532)
			(xy 86.179914 -385.679696) (xy 86.051644 -385.457954) (xy 86.039706 -385.433824) (xy 86.034874 -385.424309)
			(xy 86.019087 -385.409993) (xy 85.99885 -385.40331) (xy 85.977641 -385.405409) (xy 85.959108 -385.415931)
			(xy 85.95233 -385.424172) (xy 85.941392 -385.438223) (xy 85.915255 -385.462401) (xy 85.885093 -385.481319)
			(xy 85.851949 -385.494325) (xy 85.81697 -385.500968) (xy 85.799168 -385.501388) (xy 85.79866 -385.501388)
			(xy 85.770974 -385.499356) (xy 85.77072 -385.499356) (xy 85.761253 -385.498362) (xy 85.742733 -385.502714)
			(xy 85.727082 -385.513529) (xy 85.721444 -385.5212) (xy 85.669882 -385.596892) (xy 85.664899 -385.605047)
			(xy 85.660719 -385.623677) (xy 85.66364 -385.642546) (xy 85.668104 -385.650994) (xy 85.783674 -385.850892)
			(xy 85.796501 -385.874223) (xy 85.81472 -385.924247) (xy 85.823979 -385.976673) (xy 85.824568 -386.003292)
			(xy 85.824131 -386.027272) (xy 85.816633 -386.074643) (xy 85.801819 -386.120259) (xy 85.780055 -386.162997)
			(xy 85.751876 -386.201806) (xy 85.717975 -386.235732) (xy 85.679187 -386.263939) (xy 85.636464 -386.285734)
			(xy 85.590859 -386.300581) (xy 85.543494 -386.308113) (xy 85.519514 -386.3086) (xy 85.519006 -386.3086)
			(xy 85.495432 -386.308201) (xy 85.448844 -386.300961) (xy 85.403926 -386.286636) (xy 85.361747 -386.265568)
			(xy 85.323314 -386.238259) (xy 85.289542 -386.20536) (xy 85.261237 -386.167655) (xy 85.249766 -386.147056)
			(xy 85.249258 -386.146294) (xy 85.235796 -386.122926) (xy 85.230464 -386.114436) (xy 85.214557 -386.10225)
			(xy 85.195197 -386.097084) (xy 85.175334 -386.099725) (xy 85.166454 -386.104384) (xy 85.15731 -386.109718)
			(xy 85.151214 -386.1181) (xy 85.140304 -386.132014) (xy 85.114217 -386.155878) (xy 85.084186 -386.174537)
			(xy 85.051237 -386.187356) (xy 85.016491 -386.193897) (xy 84.998814 -386.1943) (xy 84.998306 -386.1943)
			(xy 84.979532 -386.193798) (xy 84.942704 -386.186481) (xy 84.908009 -386.172126) (xy 84.876777 -386.151284)
			(xy 84.850206 -386.124754) (xy 84.829315 -386.093555) (xy 84.814906 -386.058882) (xy 84.807532 -386.022065)
			(xy 84.807044 -386.003292) (xy 84.8075 -385.984177) (xy 84.815063 -385.946703) (xy 84.829924 -385.91148)
			(xy 84.851491 -385.879915) (xy 84.878902 -385.853268) (xy 84.911064 -385.832601) (xy 84.92871 -385.825238)
			(xy 84.93887 -385.821174) (xy 84.954364 -385.805426) (xy 84.983574 -385.722114) (xy 84.986796 -385.711534)
			(xy 84.984819 -385.689533) (xy 84.979764 -385.679696) (xy 84.851494 -385.457954) (xy 84.839556 -385.433824)
			(xy 84.834794 -385.424268) (xy 84.818987 -385.409946) (xy 84.798729 -385.403266) (xy 84.777503 -385.405379)
			(xy 84.758959 -385.41592) (xy 84.75218 -385.424172) (xy 84.741253 -385.438266) (xy 84.715065 -385.462469)
			(xy 84.684843 -385.481395) (xy 84.651635 -385.494386) (xy 84.616594 -385.500994) (xy 84.598764 -385.501388)
			(xy 84.598256 -385.501388) (xy 84.591376 -385.50138) (xy 84.577647 -385.500493) (xy 84.570824 -385.49961)
			(xy 84.556346 -385.497324) (xy 84.529676 -385.509008) (xy 84.469986 -385.596892) (xy 84.465003 -385.605047)
			(xy 84.460822 -385.623677) (xy 84.463743 -385.642546) (xy 84.468208 -385.650994) (xy 84.583778 -385.850892)
			(xy 84.596606 -385.874223) (xy 84.614824 -385.924247) (xy 84.624083 -385.976673) (xy 84.624672 -386.003292)
			(xy 84.624231 -386.027272) (xy 84.616733 -386.074643) (xy 84.60192 -386.120258) (xy 84.580156 -386.162996)
			(xy 84.551978 -386.201805) (xy 84.518077 -386.235731) (xy 84.479289 -386.263938) (xy 84.436567 -386.285733)
			(xy 84.390963 -386.30058) (xy 84.343598 -386.308113) (xy 84.319618 -386.3086) (xy 84.31911 -386.3086)
			(xy 84.295536 -386.308198) (xy 84.248948 -386.300958) (xy 84.20403 -386.286634) (xy 84.161852 -386.265566)
			(xy 84.123418 -386.238258) (xy 84.089647 -386.20536) (xy 84.061341 -386.167655) (xy 84.04987 -386.147056)
			(xy 84.049362 -386.146294) (xy 84.0359 -386.122926) (xy 84.030564 -386.114439) (xy 84.014659 -386.102253)
			(xy 83.9953 -386.097086) (xy 83.975437 -386.099726) (xy 83.966558 -386.104384) (xy 83.957414 -386.109718)
			(xy 83.951318 -386.1181) (xy 83.940405 -386.132012) (xy 83.914319 -386.155876) (xy 83.884289 -386.174536)
			(xy 83.85134 -386.187355) (xy 83.816595 -386.193896) (xy 83.798918 -386.1943) (xy 83.79841 -386.1943)
			(xy 83.779636 -386.193794) (xy 83.742808 -386.186478) (xy 83.708113 -386.172124) (xy 83.676881 -386.151282)
			(xy 83.65031 -386.124753) (xy 83.629419 -386.093554) (xy 83.61501 -386.058881) (xy 83.607636 -386.022065)
			(xy 83.607148 -386.003292) (xy 83.607602 -385.984177) (xy 83.615164 -385.946702) (xy 83.630026 -385.91148)
			(xy 83.651593 -385.879914) (xy 83.679005 -385.853267) (xy 83.711168 -385.832601) (xy 83.728814 -385.825238)
			(xy 83.738974 -385.821174) (xy 83.754468 -385.805426) (xy 83.783678 -385.722114) (xy 83.786899 -385.711534)
			(xy 83.784922 -385.689533) (xy 83.779868 -385.679696) (xy 83.651598 -385.457954) (xy 83.63966 -385.433824)
			(xy 83.634892 -385.424272) (xy 83.619087 -385.40995) (xy 83.598831 -385.40327) (xy 83.577606 -385.405382)
			(xy 83.559063 -385.415921) (xy 83.552284 -385.424172) (xy 83.541372 -385.438245) (xy 83.515229 -385.462421)
			(xy 83.48506 -385.481336) (xy 83.45191 -385.494336) (xy 83.416926 -385.500972) (xy 83.399122 -385.501388)
			(xy 83.398614 -385.501388) (xy 83.370928 -385.499356) (xy 83.370674 -385.499356) (xy 83.361205 -385.498405)
			(xy 83.34269 -385.502738) (xy 83.327039 -385.513536) (xy 83.321398 -385.5212) (xy 83.269836 -385.596892)
			(xy 83.26485 -385.605047) (xy 83.260666 -385.623677) (xy 83.26359 -385.642547) (xy 83.268058 -385.650994)
			(xy 83.383628 -385.850892) (xy 83.396363 -385.874209) (xy 83.414456 -385.924157) (xy 83.423671 -385.976476)
			(xy 83.424268 -386.003038) (xy 83.424268 -386.003292) (xy 83.423854 -386.027287) (xy 83.416348 -386.074686)
			(xy 83.401518 -386.120327) (xy 83.37973 -386.163086) (xy 83.351521 -386.201909) (xy 83.317585 -386.235841)
			(xy 83.278758 -386.264047) (xy 83.235997 -386.28583) (xy 83.190355 -386.300655) (xy 83.142955 -386.308157)
			(xy 83.11896 -386.3086) (xy 83.095388 -386.308158) (xy 83.048802 -386.300925) (xy 83.003884 -386.286608)
			(xy 82.961706 -386.265548) (xy 82.923272 -386.238245) (xy 82.889499 -386.205353) (xy 82.861192 -386.167653)
			(xy 82.84972 -386.147056) (xy 82.849212 -386.146294) (xy 82.83575 -386.122926) (xy 82.830363 -386.114476)
			(xy 82.814476 -386.10229) (xy 82.795135 -386.097114) (xy 82.775285 -386.099736) (xy 82.766408 -386.104384)
			(xy 82.757264 -386.109718) (xy 82.751168 -386.1181) (xy 82.740227 -386.131988) (xy 82.714148 -386.155854)
			(xy 82.684125 -386.174518) (xy 82.651182 -386.187343) (xy 82.616443 -386.193892) (xy 82.598768 -386.1943)
			(xy 82.59826 -386.1943) (xy 82.579491 -386.193884) (xy 82.542675 -386.186554) (xy 82.507996 -386.172183)
			(xy 82.476787 -386.151323) (xy 82.450247 -386.124776) (xy 82.429395 -386.093561) (xy 82.415032 -386.058879)
			(xy 82.407711 -386.022061) (xy 82.407252 -386.003292) (xy 82.407694 -385.984196) (xy 82.415264 -385.946761)
			(xy 82.430103 -385.911569) (xy 82.451622 -385.880016) (xy 82.478967 -385.853354) (xy 82.511054 -385.832639)
			(xy 82.528664 -385.825238) (xy 82.538824 -385.821174) (xy 82.554318 -385.805426) (xy 82.583528 -385.722114)
			(xy 82.586755 -385.711535) (xy 82.584776 -385.689532) (xy 82.579718 -385.679696) (xy 82.451448 -385.457954)
			(xy 82.43951 -385.433824) (xy 82.434672 -385.424313) (xy 82.418887 -385.409996) (xy 82.398651 -385.403313)
			(xy 82.377444 -385.405412) (xy 82.358912 -385.415932) (xy 82.352134 -385.424172) (xy 82.341176 -385.43824)
			(xy 82.314996 -385.462445) (xy 82.284782 -385.481375) (xy 82.251581 -385.494373) (xy 82.216545 -385.500989)
			(xy 82.198718 -385.501388) (xy 82.19821 -385.501388) (xy 82.19133 -385.501385) (xy 82.1776 -385.500495)
			(xy 82.170778 -385.49961) (xy 82.1563 -385.497324) (xy 82.12963 -385.509008) (xy 82.06994 -385.596892)
			(xy 82.064955 -385.605047) (xy 82.06077 -385.623677) (xy 82.063694 -385.642547) (xy 82.068162 -385.650994)
			(xy 82.183732 -385.850892) (xy 82.196467 -385.874209) (xy 82.21456 -385.924157) (xy 82.223775 -385.976476)
			(xy 82.224372 -386.003038) (xy 82.224372 -386.003292) (xy 82.223954 -386.027287) (xy 82.216448 -386.074685)
			(xy 82.201618 -386.120326) (xy 82.179831 -386.163085) (xy 82.151622 -386.201908) (xy 82.117687 -386.23584)
			(xy 82.078861 -386.264045) (xy 82.0361 -386.285829) (xy 81.990458 -386.300654) (xy 81.943059 -386.308156)
			(xy 81.919064 -386.3086) (xy 81.895492 -386.308155) (xy 81.848906 -386.300923) (xy 81.803989 -386.286606)
			(xy 81.76181 -386.265546) (xy 81.723376 -386.238244) (xy 81.689603 -386.205352) (xy 81.661296 -386.167653)
			(xy 81.649824 -386.147056) (xy 81.649316 -386.146294) (xy 81.635854 -386.122926) (xy 81.630463 -386.114479)
			(xy 81.614578 -386.102293) (xy 81.595238 -386.097116) (xy 81.575389 -386.099737) (xy 81.566512 -386.104384)
			(xy 81.557368 -386.109718) (xy 81.551272 -386.1181) (xy 81.540329 -386.131986) (xy 81.51425 -386.155852)
			(xy 81.484228 -386.174517) (xy 81.451286 -386.187342) (xy 81.416547 -386.193892) (xy 81.398872 -386.1943)
			(xy 81.398364 -386.1943) (xy 81.379595 -386.19388) (xy 81.342779 -386.186551) (xy 81.308101 -386.17218)
			(xy 81.276891 -386.151321) (xy 81.250351 -386.124774) (xy 81.229499 -386.09356) (xy 81.215136 -386.058879)
			(xy 81.207815 -386.022061) (xy 81.207356 -386.003292) (xy 81.207795 -385.984196) (xy 81.215366 -385.946761)
			(xy 81.230205 -385.911569) (xy 81.251725 -385.880016) (xy 81.279071 -385.853353) (xy 81.311158 -385.832639)
			(xy 81.328768 -385.825238) (xy 81.338928 -385.821174) (xy 81.354422 -385.805426) (xy 81.383632 -385.722114)
			(xy 81.386859 -385.711535) (xy 81.38488 -385.689532) (xy 81.379822 -385.679696) (xy 81.251552 -385.457954)
			(xy 81.239614 -385.433824) (xy 81.234771 -385.424316) (xy 81.218987 -385.41) (xy 81.198753 -385.403316)
			(xy 81.177548 -385.405414) (xy 81.159015 -385.415933) (xy 81.152238 -385.424172) (xy 81.141278 -385.438238)
			(xy 81.115099 -385.462443) (xy 81.084885 -385.481374) (xy 81.051684 -385.494372) (xy 81.016649 -385.500989)
			(xy 80.998822 -385.501388) (xy 80.998314 -385.501388) (xy 80.991434 -385.501384) (xy 80.977704 -385.500495)
			(xy 80.970882 -385.49961) (xy 80.956404 -385.497324) (xy 80.929734 -385.509008) (xy 80.870044 -385.596892)
			(xy 80.865058 -385.605047) (xy 80.860873 -385.623677) (xy 80.863797 -385.642547) (xy 80.868266 -385.650994)
			(xy 80.983836 -385.850892) (xy 80.996572 -385.874209) (xy 81.014664 -385.924157) (xy 81.023879 -385.976476)
			(xy 81.024476 -386.003038) (xy 81.024476 -386.003292) (xy 81.024054 -386.027287) (xy 81.016548 -386.074685)
			(xy 81.001718 -386.120325) (xy 80.979931 -386.163083) (xy 80.951723 -386.201907) (xy 80.917788 -386.235839)
			(xy 80.878963 -386.264044) (xy 80.836203 -386.285828) (xy 80.790561 -386.300653) (xy 80.743163 -386.308156)
			(xy 80.719168 -386.3086) (xy 80.695596 -386.308151) (xy 80.64901 -386.30092) (xy 80.604093 -386.286604)
			(xy 80.561915 -386.265545) (xy 80.523481 -386.238243) (xy 80.489707 -386.205351) (xy 80.4614 -386.167653)
			(xy 80.449928 -386.147056) (xy 80.44942 -386.146294) (xy 80.435958 -386.122926) (xy 80.430563 -386.114482)
			(xy 80.414679 -386.102296) (xy 80.39534 -386.097118) (xy 80.375493 -386.099738) (xy 80.366616 -386.104384)
			(xy 80.357472 -386.109718) (xy 80.351376 -386.1181) (xy 80.340431 -386.131984) (xy 80.314353 -386.155851)
			(xy 80.284331 -386.174515) (xy 80.251389 -386.187341) (xy 80.216651 -386.193891) (xy 80.198976 -386.1943)
			(xy 80.198468 -386.1943) (xy 80.179699 -386.193877) (xy 80.142884 -386.186548) (xy 80.108205 -386.172178)
			(xy 80.076996 -386.151319) (xy 80.050455 -386.124773) (xy 80.029603 -386.09356) (xy 80.01524 -386.058878)
			(xy 80.007919 -386.022061) (xy 80.00746 -386.003292) (xy 80.007897 -385.984195) (xy 80.015468 -385.94676)
			(xy 80.030307 -385.911568) (xy 80.051827 -385.880015) (xy 80.079174 -385.853352) (xy 80.111262 -385.832638)
			(xy 80.128872 -385.825238) (xy 80.139032 -385.821174) (xy 80.154526 -385.805426) (xy 80.183736 -385.722114)
			(xy 80.186962 -385.711535) (xy 80.184984 -385.689532) (xy 80.179926 -385.679696) (xy 80.051656 -385.457954)
			(xy 80.039718 -385.433824) (xy 80.034869 -385.42432) (xy 80.019087 -385.410004) (xy 79.998855 -385.40332)
			(xy 79.977651 -385.405417) (xy 79.95912 -385.415934) (xy 79.952342 -385.424172) (xy 79.941397 -385.438218)
			(xy 79.915262 -385.462395) (xy 79.885101 -385.481315) (xy 79.851959 -385.494322) (xy 79.816981 -385.500967)
			(xy 79.79918 -385.501388) (xy 79.798672 -385.501388) (xy 79.778651 -385.500902) (xy 79.739485 -385.492572)
			(xy 79.702907 -385.476281) (xy 79.670514 -385.452742) (xy 79.643723 -385.422984) (xy 79.623704 -385.388305)
			(xy 79.611331 -385.350223) (xy 79.607146 -385.3104) (xy 66.1439 -385.3104) (xy 66.456306 -385.850892)
			(xy 66.469128 -385.874226) (xy 66.48735 -385.924248) (xy 66.496611 -385.976674) (xy 66.4972 -386.003292)
			(xy 66.496754 -386.027298) (xy 66.48924 -386.074718) (xy 66.474396 -386.120378) (xy 66.452589 -386.163152)
			(xy 66.424356 -386.201985) (xy 66.390392 -386.235921) (xy 66.351535 -386.264122) (xy 66.308743 -386.285894)
			(xy 66.263071 -386.300699) (xy 66.215644 -386.308173) (xy 66.191638 -386.3086) (xy 66.191384 -386.3086)
			(xy 66.16781 -386.308219) (xy 66.121221 -386.300975) (xy 66.076302 -386.286647) (xy 66.034123 -386.265576)
			(xy 65.995691 -386.238265) (xy 65.961919 -386.205363) (xy 65.933614 -386.167656) (xy 65.922144 -386.147056)
			(xy 65.921636 -386.146294) (xy 65.908174 -386.122926) (xy 65.902763 -386.114494) (xy 65.886885 -386.102307)
			(xy 65.867552 -386.097127) (xy 65.847708 -386.099741) (xy 65.838832 -386.104384) (xy 65.829688 -386.109718)
			(xy 65.823592 -386.1181) (xy 65.812638 -386.131977) (xy 65.786562 -386.155844) (xy 65.756542 -386.174509)
			(xy 65.723603 -386.187337) (xy 65.688866 -386.19389) (xy 65.671192 -386.1943) (xy 65.670684 -386.1943)
			(xy 65.651916 -386.193862) (xy 65.615101 -386.186536) (xy 65.580422 -386.172169) (xy 65.549213 -386.151313)
			(xy 65.522672 -386.124769) (xy 65.501819 -386.093557) (xy 65.487457 -386.058876) (xy 65.480135 -386.02206)
			(xy 65.479676 -386.003292) (xy 65.480103 -385.984195) (xy 65.487674 -385.946758) (xy 65.502515 -385.911565)
			(xy 65.524037 -385.880012) (xy 65.551386 -385.85335) (xy 65.583477 -385.832637) (xy 65.601088 -385.825238)
			(xy 65.611248 -385.821174) (xy 65.626742 -385.805426) (xy 65.655952 -385.722114) (xy 65.659176 -385.711535)
			(xy 65.657198 -385.689532) (xy 65.652142 -385.679696) (xy 65.523872 -385.457954) (xy 65.51168 -385.43357)
			(xy 65.506882 -385.424032) (xy 65.491089 -385.409701) (xy 65.470839 -385.403015) (xy 65.449617 -385.405124)
			(xy 65.431079 -385.415665) (xy 65.424304 -385.423918) (xy 65.413371 -385.438023) (xy 65.387207 -385.462284)
			(xy 65.356995 -385.481268) (xy 65.323784 -385.494315) (xy 65.288728 -385.500972) (xy 65.270888 -385.501388)
			(xy 65.27038 -385.501388) (xy 65.243202 -385.49961) (xy 65.22847 -385.497578) (xy 65.202054 -385.509008)
			(xy 65.142618 -385.596892) (xy 65.137625 -385.604983) (xy 65.133526 -385.623538) (xy 65.136422 -385.642319)
			(xy 65.14084 -385.65074) (xy 65.256156 -385.850892) (xy 65.268893 -385.874208) (xy 65.286985 -385.924157)
			(xy 65.2962 -385.976476) (xy 65.296796 -386.003038) (xy 65.296796 -386.003292) (xy 65.296354 -386.027286)
			(xy 65.288848 -386.074682) (xy 65.27402 -386.12032) (xy 65.252235 -386.163077) (xy 65.224029 -386.2019)
			(xy 65.190097 -386.235831) (xy 65.151274 -386.264037) (xy 65.108517 -386.285822) (xy 65.062878 -386.300649)
			(xy 65.015482 -386.308155) (xy 64.991488 -386.3086) (xy 64.991234 -386.3086) (xy 64.967661 -386.308179)
			(xy 64.921074 -386.300942) (xy 64.876156 -386.286622) (xy 64.833978 -386.265557) (xy 64.795544 -386.238252)
			(xy 64.761772 -386.205356) (xy 64.733465 -386.167654) (xy 64.721994 -386.147056) (xy 64.721486 -386.146294)
			(xy 64.708024 -386.122926) (xy 64.702664 -386.114456) (xy 64.686767 -386.10227) (xy 64.667417 -386.097099)
			(xy 64.64756 -386.099731) (xy 64.638682 -386.104384) (xy 64.629538 -386.109718) (xy 64.623442 -386.1181)
			(xy 64.612516 -386.132001) (xy 64.586433 -386.155866) (xy 64.556406 -386.174527) (xy 64.52346 -386.187349)
			(xy 64.488718 -386.193894) (xy 64.471042 -386.1943) (xy 64.470534 -386.1943) (xy 64.451761 -386.193773)
			(xy 64.414934 -386.186461) (xy 64.380239 -386.17211) (xy 64.349007 -386.151272) (xy 64.322435 -386.124746)
			(xy 64.301544 -386.093549) (xy 64.287134 -386.058879) (xy 64.27976 -386.022064) (xy 64.279272 -386.003292)
			(xy 64.27971 -385.984176) (xy 64.287274 -385.9467) (xy 64.302138 -385.911476) (xy 64.323708 -385.87991)
			(xy 64.351124 -385.853263) (xy 64.38329 -385.8326) (xy 64.400938 -385.825238) (xy 64.411098 -385.821174)
			(xy 64.426592 -385.805426) (xy 64.455802 -385.722114) (xy 64.459032 -385.711536) (xy 64.457052 -385.689531)
			(xy 64.451992 -385.679696) (xy 64.323722 -385.457954) (xy 64.311784 -385.433824) (xy 64.306983 -385.424291)
			(xy 64.291187 -385.409972) (xy 64.270941 -385.403291) (xy 64.249725 -385.405396) (xy 64.231186 -385.415926)
			(xy 64.224408 -385.424172) (xy 64.213465 -385.438253) (xy 64.187281 -385.462457) (xy 64.157063 -385.481384)
			(xy 64.123859 -385.49438) (xy 64.08882 -385.500991) (xy 64.070992 -385.501388) (xy 64.070484 -385.501388)
			(xy 64.043306 -385.49961) (xy 64.028574 -385.497578) (xy 64.002158 -385.509008) (xy 63.942722 -385.596892)
			(xy 63.937733 -385.604983) (xy 63.933642 -385.623538) (xy 63.936532 -385.642318) (xy 63.940944 -385.65074)
			(xy 64.05626 -385.850892) (xy 64.068998 -385.874207) (xy 64.087089 -385.924157) (xy 64.096304 -385.976476)
			(xy 64.0969 -386.003038) (xy 64.0969 -386.003292) (xy 64.096454 -386.027285) (xy 64.088949 -386.074681)
			(xy 64.074121 -386.12032) (xy 64.052336 -386.163076) (xy 64.02413 -386.201898) (xy 63.990198 -386.23583)
			(xy 63.951376 -386.264036) (xy 63.90862 -386.285821) (xy 63.862981 -386.300649) (xy 63.815585 -386.308154)
			(xy 63.791592 -386.3086) (xy 63.791338 -386.3086) (xy 63.767765 -386.308176) (xy 63.721178 -386.30094)
			(xy 63.67626 -386.28662) (xy 63.634082 -386.265556) (xy 63.595648 -386.238251) (xy 63.561876 -386.205356)
			(xy 63.533569 -386.167654) (xy 63.522098 -386.147056) (xy 63.52159 -386.146294) (xy 63.508128 -386.122926)
			(xy 63.502764 -386.114459) (xy 63.486869 -386.102273) (xy 63.467519 -386.097101) (xy 63.447664 -386.099731)
			(xy 63.438786 -386.104384) (xy 63.429642 -386.109718) (xy 63.423546 -386.1181) (xy 63.412618 -386.131999)
			(xy 63.386535 -386.155864) (xy 63.356509 -386.174526) (xy 63.323564 -386.187348) (xy 63.288822 -386.193894)
			(xy 63.271146 -386.1943) (xy 63.270638 -386.1943) (xy 63.251865 -386.193769) (xy 63.215038 -386.186458)
			(xy 63.180343 -386.172108) (xy 63.149111 -386.151271) (xy 63.122539 -386.124745) (xy 63.101648 -386.093548)
			(xy 63.087239 -386.058878) (xy 63.079864 -386.022064) (xy 63.079376 -386.003292) (xy 63.079875 -385.98418)
			(xy 63.087434 -385.946711) (xy 63.102289 -385.911492) (xy 63.123848 -385.879928) (xy 63.15125 -385.853278)
			(xy 63.183401 -385.832606) (xy 63.201042 -385.825238) (xy 63.211202 -385.821174) (xy 63.226696 -385.805426)
			(xy 63.255906 -385.722114) (xy 63.259135 -385.711536) (xy 63.257156 -385.689532) (xy 63.252096 -385.679696)
			(xy 63.123826 -385.457954) (xy 63.111888 -385.433824) (xy 63.107081 -385.424295) (xy 63.091287 -385.409976)
			(xy 63.071042 -385.403294) (xy 63.049828 -385.405398) (xy 63.03129 -385.415927) (xy 63.024512 -385.424172)
			(xy 63.013567 -385.438251) (xy 62.987384 -385.462455) (xy 62.957166 -385.481383) (xy 62.923962 -385.494379)
			(xy 62.888924 -385.500991) (xy 62.871096 -385.501388) (xy 62.870588 -385.501388) (xy 62.863708 -385.501387)
			(xy 62.849978 -385.500496) (xy 62.843156 -385.49961) (xy 62.828678 -385.497324) (xy 62.802008 -385.509008)
			(xy 62.742318 -385.596892) (xy 62.737333 -385.605047) (xy 62.73315 -385.623677) (xy 62.736073 -385.642547)
			(xy 62.74054 -385.650994) (xy 62.85611 -385.850892) (xy 62.868932 -385.874226) (xy 62.887154 -385.924248)
			(xy 62.896415 -385.976673) (xy 62.897004 -386.003292) (xy 62.896554 -386.027298) (xy 62.88904 -386.074718)
			(xy 62.874197 -386.120377) (xy 62.85239 -386.163151) (xy 62.824157 -386.201984) (xy 62.790194 -386.23592)
			(xy 62.751337 -386.264121) (xy 62.708546 -386.285893) (xy 62.662874 -386.300698) (xy 62.615448 -386.308173)
			(xy 62.591442 -386.3086) (xy 62.591188 -386.3086) (xy 62.567614 -386.308216) (xy 62.521025 -386.300973)
			(xy 62.476106 -386.286645) (xy 62.433928 -386.265575) (xy 62.395495 -386.238264) (xy 62.361723 -386.205363)
			(xy 62.333418 -386.167656) (xy 62.321948 -386.147056) (xy 62.32144 -386.146294) (xy 62.307978 -386.122926)
			(xy 62.302563 -386.114497) (xy 62.286686 -386.10231) (xy 62.267354 -386.097129) (xy 62.247511 -386.099742)
			(xy 62.238636 -386.104384) (xy 62.229492 -386.109718) (xy 62.223396 -386.1181) (xy 62.212439 -386.131975)
			(xy 62.186364 -386.155842) (xy 62.156345 -386.174508) (xy 62.123406 -386.187336) (xy 62.08867 -386.193889)
			(xy 62.070996 -386.1943) (xy 62.070488 -386.1943) (xy 62.05172 -386.193859) (xy 62.014905 -386.186534)
			(xy 61.980227 -386.172167) (xy 61.949017 -386.151311) (xy 61.922476 -386.124767) (xy 61.901624 -386.093556)
			(xy 61.887261 -386.058876) (xy 61.879939 -386.02206) (xy 61.87948 -386.003292) (xy 61.879904 -385.984195)
			(xy 61.887476 -385.946758) (xy 61.902317 -385.911565) (xy 61.92384 -385.880011) (xy 61.951189 -385.853349)
			(xy 61.98328 -385.832637) (xy 62.000892 -385.825238) (xy 62.011052 -385.821174) (xy 62.026546 -385.805426)
			(xy 62.055756 -385.722114) (xy 62.05898 -385.711535) (xy 62.057002 -385.689532) (xy 62.051946 -385.679696)
			(xy 61.923676 -385.457954) (xy 61.911738 -385.433824) (xy 61.906861 -385.424336) (xy 61.891087 -385.410023)
			(xy 61.870863 -385.403337) (xy 61.849666 -385.405429) (xy 61.831139 -385.415938) (xy 61.824362 -385.424172)
			(xy 61.813388 -385.438227) (xy 61.787212 -385.462433) (xy 61.757002 -385.481365) (xy 61.723805 -385.494367)
			(xy 61.688772 -385.500986) (xy 61.670946 -385.501388) (xy 61.670438 -385.501388) (xy 61.64326 -385.49961)
			(xy 61.628528 -385.497578) (xy 61.602112 -385.509008) (xy 61.542676 -385.596892) (xy 61.537685 -385.604983)
			(xy 61.533589 -385.623538) (xy 61.536482 -385.642319) (xy 61.540898 -385.65074) (xy 61.656214 -385.850892)
			(xy 61.669037 -385.874226) (xy 61.687258 -385.924248) (xy 61.696519 -385.976673) (xy 61.697108 -386.003292)
			(xy 61.696654 -386.027298) (xy 61.68914 -386.074717) (xy 61.674297 -386.120377) (xy 61.652491 -386.16315)
			(xy 61.624258 -386.201983) (xy 61.590295 -386.235918) (xy 61.55144 -386.264119) (xy 61.508649 -386.285891)
			(xy 61.462978 -386.300698) (xy 61.415552 -386.308173) (xy 61.391546 -386.3086) (xy 61.391292 -386.3086)
			(xy 61.367718 -386.308213) (xy 61.321129 -386.30097) (xy 61.27621 -386.286643) (xy 61.234032 -386.265573)
			(xy 61.195599 -386.238263) (xy 61.161828 -386.205362) (xy 61.133522 -386.167656) (xy 61.122052 -386.147056)
			(xy 61.121544 -386.146294) (xy 61.108082 -386.122926) (xy 61.102663 -386.1145) (xy 61.086788 -386.102313)
			(xy 61.067457 -386.097131) (xy 61.047615 -386.099743) (xy 61.03874 -386.104384) (xy 61.029596 -386.109718)
			(xy 61.0235 -386.1181) (xy 61.012541 -386.131973) (xy 60.986466 -386.15584) (xy 60.956448 -386.174506)
			(xy 60.923509 -386.187335) (xy 60.888774 -386.193889) (xy 60.8711 -386.1943) (xy 60.870592 -386.1943)
			(xy 60.851824 -386.193855) (xy 60.815009 -386.186531) (xy 60.780331 -386.172165) (xy 60.749121 -386.151309)
			(xy 60.72258 -386.124766) (xy 60.701728 -386.093555) (xy 60.687365 -386.058875) (xy 60.680043 -386.02206)
			(xy 60.679584 -386.003292) (xy 60.680006 -385.984194) (xy 60.687578 -385.946758) (xy 60.702419 -385.911564)
			(xy 60.723942 -385.88001) (xy 60.751292 -385.853349) (xy 60.783384 -385.832637) (xy 60.800996 -385.825238)
			(xy 60.811156 -385.821174) (xy 60.82665 -385.805426) (xy 60.85586 -385.722114) (xy 60.859084 -385.711535)
			(xy 60.857106 -385.689532) (xy 60.85205 -385.679696) (xy 60.72378 -385.457954) (xy 60.711842 -385.433824)
			(xy 60.7071 -385.424257) (xy 60.691287 -385.409933) (xy 60.671023 -385.403254) (xy 60.649793 -385.40537)
			(xy 60.631245 -385.415917) (xy 60.624466 -385.424172) (xy 60.61349 -385.438225) (xy 60.587315 -385.462431)
			(xy 60.557105 -385.481364) (xy 60.523908 -385.494366) (xy 60.488876 -385.500986) (xy 60.47105 -385.501388)
			(xy 60.470542 -385.501388) (xy 60.443364 -385.49961) (xy 60.428632 -385.497578) (xy 60.402216 -385.509008)
			(xy 60.34278 -385.596892) (xy 60.337788 -385.604983) (xy 60.333693 -385.623538) (xy 60.336586 -385.642319)
			(xy 60.341002 -385.65074) (xy 60.456318 -385.850892) (xy 60.469141 -385.874226) (xy 60.487362 -385.924248)
			(xy 60.496623 -385.976673) (xy 60.497212 -386.003292) (xy 60.496754 -386.027297) (xy 60.48924 -386.074717)
			(xy 60.474398 -386.120376) (xy 60.452591 -386.163149) (xy 60.424359 -386.201981) (xy 60.390397 -386.235917)
			(xy 60.351542 -386.264118) (xy 60.308752 -386.28589) (xy 60.263081 -386.300697) (xy 60.215656 -386.308172)
			(xy 60.19165 -386.3086) (xy 60.191396 -386.3086) (xy 60.167822 -386.308209) (xy 60.121233 -386.300967)
			(xy 60.076315 -386.286641) (xy 60.034136 -386.265572) (xy 59.995703 -386.238262) (xy 59.961932 -386.205362)
			(xy 59.933626 -386.167656) (xy 59.922156 -386.147056) (xy 59.921648 -386.146294) (xy 59.908186 -386.122926)
			(xy 59.902763 -386.114503) (xy 59.886889 -386.102316) (xy 59.86756 -386.097133) (xy 59.847719 -386.099744)
			(xy 59.838844 -386.104384) (xy 59.8297 -386.109718) (xy 59.823604 -386.1181) (xy 59.812643 -386.131971)
			(xy 59.786569 -386.155839) (xy 59.756551 -386.174505) (xy 59.723613 -386.187334) (xy 59.688878 -386.193889)
			(xy 59.671204 -386.1943) (xy 59.670696 -386.1943) (xy 59.651925 -386.193882) (xy 59.615105 -386.186557)
			(xy 59.580421 -386.172189) (xy 59.549206 -386.151331) (xy 59.522661 -386.124784) (xy 59.501805 -386.093569)
			(xy 59.48744 -386.058884) (xy 59.480117 -386.022063) (xy 59.479688 -386.003292) (xy 59.480107 -385.984194)
			(xy 59.487679 -385.946757) (xy 59.502521 -385.911563) (xy 59.524045 -385.88001) (xy 59.551395 -385.853348)
			(xy 59.583488 -385.832637) (xy 59.6011 -385.825238) (xy 59.61126 -385.821174) (xy 59.626754 -385.805426)
			(xy 59.655964 -385.722114) (xy 59.659187 -385.711535) (xy 59.65721 -385.689532) (xy 59.652154 -385.679696)
			(xy 59.523884 -385.457954) (xy 59.511946 -385.433824) (xy 59.507198 -385.42426) (xy 59.491387 -385.409936)
			(xy 59.471125 -385.403258) (xy 59.449896 -385.405373) (xy 59.431349 -385.415918) (xy 59.42457 -385.424172)
			(xy 59.413649 -385.438271) (xy 59.38746 -385.462473) (xy 59.357236 -385.481398) (xy 59.324027 -385.494389)
			(xy 59.288984 -385.500995) (xy 59.271154 -385.501388) (xy 59.270646 -385.501388) (xy 59.263766 -385.501381)
			(xy 59.250037 -385.500494) (xy 59.243214 -385.49961) (xy 59.228736 -385.497324) (xy 59.202066 -385.509008)
			(xy 59.142376 -385.596892) (xy 59.137393 -385.605047) (xy 59.133213 -385.623677) (xy 59.136134 -385.642546)
			(xy 59.140598 -385.650994) (xy 59.256168 -385.850892) (xy 59.268906 -385.874207) (xy 59.286997 -385.924157)
			(xy 59.296212 -385.976476) (xy 59.296808 -386.003038) (xy 59.296808 -386.003292) (xy 59.296354 -386.027285)
			(xy 59.288849 -386.07468) (xy 59.274021 -386.120318) (xy 59.252237 -386.163074) (xy 59.224032 -386.201896)
			(xy 59.190102 -386.235827) (xy 59.151281 -386.264033) (xy 59.108525 -386.285818) (xy 59.062888 -386.300647)
			(xy 59.015493 -386.308154) (xy 58.9915 -386.3086) (xy 58.991246 -386.3086) (xy 58.967673 -386.308169)
			(xy 58.921087 -386.300935) (xy 58.876169 -386.286615) (xy 58.833991 -386.265553) (xy 58.795557 -386.238249)
			(xy 58.761784 -386.205355) (xy 58.733477 -386.167654) (xy 58.722006 -386.147056) (xy 58.721498 -386.146294)
			(xy 58.708036 -386.122926) (xy 58.702663 -386.114466) (xy 58.686771 -386.102279) (xy 58.667425 -386.097106)
			(xy 58.647572 -386.099734) (xy 58.638694 -386.104384) (xy 58.62955 -386.109718) (xy 58.623454 -386.1181)
			(xy 58.612521 -386.131995) (xy 58.58644 -386.15586) (xy 58.556415 -386.174523) (xy 58.52347 -386.187346)
			(xy 58.48873 -386.193893) (xy 58.471054 -386.1943) (xy 58.470546 -386.1943) (xy 58.451773 -386.193762)
			(xy 58.414947 -386.186452) (xy 58.380252 -386.172104) (xy 58.349019 -386.151267) (xy 58.322448 -386.124742)
			(xy 58.301556 -386.093547) (xy 58.287147 -386.058877) (xy 58.279772 -386.022064) (xy 58.279284 -386.003292)
			(xy 58.279778 -385.984179) (xy 58.287338 -385.94671) (xy 58.302194 -385.91149) (xy 58.323753 -385.879926)
			(xy 58.351156 -385.853277) (xy 58.383309 -385.832605) (xy 58.40095 -385.825238) (xy 58.41111 -385.821174)
			(xy 58.426604 -385.805426) (xy 58.455814 -385.722114) (xy 58.459042 -385.711535) (xy 58.457063 -385.689532)
			(xy 58.452004 -385.679696) (xy 58.323734 -385.457954) (xy 58.311796 -385.433824) (xy 58.306978 -385.424301)
			(xy 58.291187 -385.409983) (xy 58.270946 -385.403301) (xy 58.249734 -385.405403) (xy 58.231198 -385.415929)
			(xy 58.22442 -385.424172) (xy 58.21347 -385.438247) (xy 58.187288 -385.462451) (xy 58.157072 -385.48138)
			(xy 58.123869 -385.494377) (xy 58.088832 -385.50099) (xy 58.071004 -385.501388) (xy 58.070496 -385.501388)
			(xy 58.043318 -385.49961) (xy 58.028586 -385.497578) (xy 58.00217 -385.509008) (xy 57.942734 -385.596892)
			(xy 57.937744 -385.604983) (xy 57.933652 -385.623538) (xy 57.936543 -385.642318) (xy 57.940956 -385.65074)
			(xy 58.056272 -385.850892) (xy 58.069011 -385.874207) (xy 58.087101 -385.924157) (xy 58.096316 -385.976476)
			(xy 58.096912 -386.003038) (xy 58.096912 -386.003292) (xy 58.096454 -386.027285) (xy 58.088949 -386.07468)
			(xy 58.074122 -386.120317) (xy 58.052338 -386.163073) (xy 58.024134 -386.201894) (xy 57.990203 -386.235826)
			(xy 57.951383 -386.264032) (xy 57.908628 -386.285817) (xy 57.862991 -386.300646) (xy 57.815597 -386.308154)
			(xy 57.791604 -386.3086) (xy 57.79135 -386.3086) (xy 57.767777 -386.308166) (xy 57.721191 -386.300932)
			(xy 57.676273 -386.286613) (xy 57.634095 -386.265551) (xy 57.595661 -386.238248) (xy 57.561888 -386.205354)
			(xy 57.533581 -386.167653) (xy 57.52211 -386.147056) (xy 57.521602 -386.146294) (xy 57.50814 -386.122926)
			(xy 57.502763 -386.114469) (xy 57.486873 -386.102282) (xy 57.467528 -386.097108) (xy 57.447675 -386.099734)
			(xy 57.438798 -386.104384) (xy 57.429654 -386.109718) (xy 57.423558 -386.1181) (xy 57.412623 -386.131993)
			(xy 57.386542 -386.155859) (xy 57.356518 -386.174522) (xy 57.323574 -386.187345) (xy 57.288833 -386.193893)
			(xy 57.271158 -386.1943) (xy 57.27065 -386.1943) (xy 57.251878 -386.193758) (xy 57.215051 -386.186449)
			(xy 57.180356 -386.172101) (xy 57.149124 -386.151266) (xy 57.122552 -386.124741) (xy 57.10166 -386.093546)
			(xy 57.087251 -386.058877) (xy 57.079876 -386.022064) (xy 57.079388 -386.003292) (xy 57.07988 -385.984179)
			(xy 57.087439 -385.946709) (xy 57.102296 -385.91149) (xy 57.123856 -385.879925) (xy 57.151259 -385.853276)
			(xy 57.183412 -385.832605) (xy 57.201054 -385.825238) (xy 57.211214 -385.821174) (xy 57.226708 -385.805426)
			(xy 57.255918 -385.722114) (xy 57.259146 -385.711535) (xy 57.257167 -385.689532) (xy 57.252108 -385.679696)
			(xy 57.123838 -385.457954) (xy 57.1119 -385.433824) (xy 57.107076 -385.424305) (xy 57.091287 -385.409987)
			(xy 57.071047 -385.403304) (xy 57.049837 -385.405406) (xy 57.031302 -385.41593) (xy 57.024524 -385.424172)
			(xy 57.013589 -385.438226) (xy 56.987451 -385.462403) (xy 56.957288 -385.481322) (xy 56.924144 -385.494327)
			(xy 56.889164 -385.500968) (xy 56.871362 -385.501388) (xy 56.870854 -385.501388) (xy 56.843168 -385.499356)
			(xy 56.842914 -385.499356) (xy 56.833443 -385.498436) (xy 56.814932 -385.502756) (xy 56.79928 -385.513541)
			(xy 56.793638 -385.5212) (xy 56.742076 -385.596892) (xy 56.737093 -385.605047) (xy 56.732913 -385.623677)
			(xy 56.735834 -385.642546) (xy 56.740298 -385.650994) (xy 56.855868 -385.850892) (xy 56.868606 -385.874207)
			(xy 56.886697 -385.924157) (xy 56.895912 -385.976476) (xy 56.896508 -386.003038) (xy 56.896508 -386.003292)
			(xy 56.896054 -386.027285) (xy 56.888549 -386.07468) (xy 56.873721 -386.120318) (xy 56.851937 -386.163074)
			(xy 56.823732 -386.201896) (xy 56.789802 -386.235827) (xy 56.750981 -386.264033) (xy 56.708225 -386.285818)
			(xy 56.662588 -386.300647) (xy 56.615193 -386.308154) (xy 56.5912 -386.3086) (xy 56.567626 -386.308206)
			(xy 56.521038 -386.300965) (xy 56.476119 -386.286639) (xy 56.433941 -386.26557) (xy 56.395508 -386.238261)
			(xy 56.361736 -386.205361) (xy 56.33343 -386.167656) (xy 56.32196 -386.147056) (xy 56.321452 -386.146294)
			(xy 56.30799 -386.122926) (xy 56.302563 -386.114506) (xy 56.286691 -386.102319) (xy 56.267363 -386.097136)
			(xy 56.247523 -386.099745) (xy 56.238648 -386.104384) (xy 56.229504 -386.109718) (xy 56.223408 -386.1181)
			(xy 56.212501 -386.132017) (xy 56.186413 -386.15588) (xy 56.156382 -386.174539) (xy 56.123431 -386.187357)
			(xy 56.088686 -386.193897) (xy 56.071008 -386.1943) (xy 56.0705 -386.1943) (xy 56.051729 -386.193878)
			(xy 56.014909 -386.186554) (xy 55.980225 -386.172187) (xy 55.949011 -386.15133) (xy 55.922465 -386.124783)
			(xy 55.901609 -386.093568) (xy 55.887244 -386.058883) (xy 55.879921 -386.022063) (xy 55.879492 -386.003292)
			(xy 55.879971 -385.984198) (xy 55.887539 -385.946768) (xy 55.902372 -385.911579) (xy 55.923884 -385.880027)
			(xy 55.951221 -385.853362) (xy 55.983298 -385.832642) (xy 56.000904 -385.825238) (xy 56.011064 -385.821174)
			(xy 56.026558 -385.805426) (xy 56.055768 -385.722114) (xy 56.058991 -385.711535) (xy 56.057013 -385.689532)
			(xy 56.051958 -385.679696) (xy 55.923688 -385.457954) (xy 55.91175 -385.433824) (xy 55.906997 -385.424263)
			(xy 55.891187 -385.40994) (xy 55.870927 -385.403261) (xy 55.849699 -385.405375) (xy 55.831153 -385.415918)
			(xy 55.824374 -385.424172) (xy 55.813451 -385.438269) (xy 55.787262 -385.462471) (xy 55.757039 -385.481397)
			(xy 55.72383 -385.494388) (xy 55.688788 -385.500994) (xy 55.670958 -385.501388) (xy 55.67045 -385.501388)
			(xy 55.66357 -385.50138) (xy 55.649841 -385.500493) (xy 55.643018 -385.49961) (xy 55.62854 -385.497324)
			(xy 55.60187 -385.509008) (xy 55.54218 -385.596892) (xy 55.537197 -385.605047) (xy 55.533017 -385.623677)
			(xy 55.535937 -385.642546) (xy 55.540402 -385.650994) (xy 55.655972 -385.850892) (xy 55.668711 -385.874207)
			(xy 55.686801 -385.924157) (xy 55.696016 -385.976476) (xy 55.696612 -386.003038) (xy 55.696612 -386.003292)
			(xy 55.696154 -386.027285) (xy 55.688649 -386.07468) (xy 55.673822 -386.120317) (xy 55.652038 -386.163073)
			(xy 55.623834 -386.201894) (xy 55.589903 -386.235826) (xy 55.551083 -386.264032) (xy 55.508328 -386.285817)
			(xy 55.462691 -386.300646) (xy 55.415297 -386.308154) (xy 55.391304 -386.3086) (xy 55.36773 -386.308203)
			(xy 55.321142 -386.300962) (xy 55.276223 -386.286637) (xy 55.234045 -386.265569) (xy 55.195612 -386.23826)
			(xy 55.16184 -386.205361) (xy 55.133535 -386.167656) (xy 55.122064 -386.147056) (xy 55.121556 -386.146294)
			(xy 55.108094 -386.122926) (xy 55.102764 -386.114434) (xy 55.086857 -386.102248) (xy 55.067495 -386.097082)
			(xy 55.047632 -386.099724) (xy 55.038752 -386.104384) (xy 55.029608 -386.109718) (xy 55.023512 -386.1181)
			(xy 55.012603 -386.132015) (xy 54.986516 -386.155879) (xy 54.956485 -386.174538) (xy 54.923535 -386.187356)
			(xy 54.888789 -386.193897) (xy 54.871112 -386.1943) (xy 54.870604 -386.1943) (xy 54.851833 -386.193875)
			(xy 54.815013 -386.186551) (xy 54.780329 -386.172185) (xy 54.749115 -386.151328) (xy 54.722569 -386.124782)
			(xy 54.701713 -386.093567) (xy 54.687348 -386.058883) (xy 54.680025 -386.022063) (xy 54.679596 -386.003292)
			(xy 54.680073 -385.984198) (xy 54.687641 -385.946768) (xy 54.702475 -385.911579) (xy 54.723987 -385.880026)
			(xy 54.751324 -385.853362) (xy 54.783402 -385.832643) (xy 54.801008 -385.825238) (xy 54.811168 -385.821174)
			(xy 54.826662 -385.805426) (xy 54.855872 -385.722114) (xy 54.859094 -385.711534) (xy 54.857117 -385.689533)
			(xy 54.852062 -385.679696) (xy 54.723792 -385.457954) (xy 54.711854 -385.433824) (xy 54.707095 -385.424267)
			(xy 54.691287 -385.409944) (xy 54.671028 -385.403265) (xy 54.649802 -385.405378) (xy 54.631257 -385.415919)
			(xy 54.624478 -385.424172) (xy 54.613552 -385.438267) (xy 54.587364 -385.46247) (xy 54.557142 -385.481395)
			(xy 54.523933 -385.494387) (xy 54.488892 -385.500994) (xy 54.471062 -385.501388) (xy 54.470554 -385.501388)
			(xy 54.463674 -385.50138) (xy 54.449945 -385.500493) (xy 54.443122 -385.49961) (xy 54.428644 -385.497324)
			(xy 54.401974 -385.509008) (xy 54.342284 -385.596892) (xy 54.337301 -385.605047) (xy 54.333121 -385.623677)
			(xy 54.336041 -385.642546) (xy 54.340506 -385.650994) (xy 54.456076 -385.850892) (xy 54.468815 -385.874207)
			(xy 54.486905 -385.924157) (xy 54.49612 -385.976476) (xy 54.496716 -386.003038) (xy 54.496716 -386.003292)
			(xy 54.49623 -386.027283) (xy 54.488725 -386.074673) (xy 54.4739 -386.120306) (xy 54.452118 -386.163059)
			(xy 54.423916 -386.201877) (xy 54.389989 -386.235806) (xy 54.351172 -386.264009) (xy 54.308421 -386.285793)
			(xy 54.262789 -386.300622) (xy 54.215399 -386.308129) (xy 54.191408 -386.3086) (xy 54.167834 -386.3082)
			(xy 54.121246 -386.30096) (xy 54.076328 -386.286635) (xy 54.034149 -386.265567) (xy 53.995716 -386.238259)
			(xy 53.961944 -386.20536) (xy 53.933639 -386.167655) (xy 53.922168 -386.147056) (xy 53.92166 -386.146294)
			(xy 53.908198 -386.122926) (xy 53.902864 -386.114437) (xy 53.886958 -386.102251) (xy 53.867598 -386.097085)
			(xy 53.847736 -386.099725) (xy 53.838856 -386.104384) (xy 53.829712 -386.109718) (xy 53.823616 -386.1181)
			(xy 53.812705 -386.132013) (xy 53.786618 -386.155877) (xy 53.756588 -386.174537) (xy 53.723638 -386.187356)
			(xy 53.688893 -386.193897) (xy 53.671216 -386.1943) (xy 53.670708 -386.1943) (xy 53.651937 -386.193871)
			(xy 53.615117 -386.186548) (xy 53.580434 -386.172183) (xy 53.549219 -386.151326) (xy 53.522674 -386.124781)
			(xy 53.501817 -386.093566) (xy 53.487452 -386.058883) (xy 53.480129 -386.022063) (xy 53.4797 -386.003292)
			(xy 53.480175 -385.984198) (xy 53.487743 -385.946767) (xy 53.502577 -385.911578) (xy 53.524089 -385.880026)
			(xy 53.551427 -385.853361) (xy 53.583506 -385.832642) (xy 53.601112 -385.825238) (xy 53.611272 -385.821174)
			(xy 53.626766 -385.805426) (xy 53.655976 -385.722114) (xy 53.659198 -385.711534) (xy 53.657221 -385.689533)
			(xy 53.652166 -385.679696) (xy 53.523896 -385.457954) (xy 53.511958 -385.433824) (xy 53.507194 -385.42427)
			(xy 53.491387 -385.409947) (xy 53.47113 -385.403268) (xy 53.449905 -385.40538) (xy 53.431361 -385.41592)
			(xy 53.424582 -385.424172) (xy 53.413671 -385.438246) (xy 53.387527 -385.462422) (xy 53.357358 -385.481337)
			(xy 53.324208 -385.494337) (xy 53.289224 -385.500972) (xy 53.27142 -385.501388) (xy 53.270912 -385.501388)
			(xy 53.243226 -385.499356) (xy 53.242972 -385.499356) (xy 53.233503 -385.498403) (xy 53.214988 -385.502737)
			(xy 53.199337 -385.513536) (xy 53.193696 -385.5212) (xy 53.142134 -385.596892) (xy 53.137148 -385.605047)
			(xy 53.132964 -385.623677) (xy 53.135888 -385.642547) (xy 53.140356 -385.650994) (xy 53.255926 -385.850892)
			(xy 53.26875 -385.874225) (xy 53.286971 -385.924247) (xy 53.296231 -385.976673) (xy 53.29682 -386.003292)
			(xy 53.296331 -386.02727) (xy 53.288835 -386.074636) (xy 53.274024 -386.120247) (xy 53.252265 -386.162982)
			(xy 53.224092 -386.201789) (xy 53.190197 -386.235713) (xy 53.151416 -386.263922) (xy 53.1087 -386.285719)
			(xy 53.063102 -386.30057) (xy 53.015743 -386.30811) (xy 52.991766 -386.3086) (xy 52.991258 -386.3086)
			(xy 52.967686 -386.308159) (xy 52.9211 -386.300927) (xy 52.876182 -386.286609) (xy 52.834004 -386.265548)
			(xy 52.79557 -386.238246) (xy 52.761797 -386.205353) (xy 52.73349 -386.167653) (xy 52.722018 -386.147056)
			(xy 52.72151 -386.146294) (xy 52.708048 -386.122926) (xy 52.702663 -386.114475) (xy 52.686776 -386.102288)
			(xy 52.667433 -386.097113) (xy 52.647583 -386.099736) (xy 52.638706 -386.104384) (xy 52.629562 -386.109718)
			(xy 52.623466 -386.1181) (xy 52.612526 -386.131989) (xy 52.586447 -386.155855) (xy 52.556424 -386.174519)
			(xy 52.523481 -386.187343) (xy 52.488741 -386.193892) (xy 52.471066 -386.1943) (xy 52.470558 -386.1943)
			(xy 52.451782 -386.193842) (xy 52.414953 -386.186516) (xy 52.380257 -386.172153) (xy 52.349025 -386.151304)
			(xy 52.322455 -386.124769) (xy 52.301565 -386.093564) (xy 52.287157 -386.058887) (xy 52.279783 -386.022067)
			(xy 52.279296 -386.003292) (xy 52.279782 -385.984179) (xy 52.287343 -385.946708) (xy 52.3022 -385.911488)
			(xy 52.323761 -385.879924) (xy 52.351165 -385.853275) (xy 52.38332 -385.832605) (xy 52.400962 -385.825238)
			(xy 52.411122 -385.821174) (xy 52.426616 -385.805426) (xy 52.455826 -385.722114) (xy 52.459053 -385.711535)
			(xy 52.457074 -385.689532) (xy 52.452016 -385.679696) (xy 52.323746 -385.457954) (xy 52.311808 -385.433824)
			(xy 52.306973 -385.424311) (xy 52.291187 -385.409994) (xy 52.270951 -385.403311) (xy 52.249743 -385.40541)
			(xy 52.23121 -385.415931) (xy 52.224432 -385.424172) (xy 52.213475 -385.438241) (xy 52.187295 -385.462446)
			(xy 52.15708 -385.481376) (xy 52.123879 -385.494374) (xy 52.088843 -385.500989) (xy 52.071016 -385.501388)
			(xy 52.070508 -385.501388) (xy 52.063628 -385.501385) (xy 52.049898 -385.500495) (xy 52.043076 -385.49961)
			(xy 52.028598 -385.497324) (xy 52.001928 -385.509008) (xy 51.942238 -385.596892) (xy 51.937252 -385.605047)
			(xy 51.933067 -385.623677) (xy 51.935991 -385.642547) (xy 51.94046 -385.650994) (xy 52.05603 -385.850892)
			(xy 52.068854 -385.874225) (xy 52.087075 -385.924247) (xy 52.096335 -385.976673) (xy 52.096924 -386.003292)
			(xy 52.096431 -386.02727) (xy 52.088935 -386.074635) (xy 52.074125 -386.120246) (xy 52.052366 -386.16298)
			(xy 52.024193 -386.201787) (xy 51.990299 -386.235712) (xy 51.951518 -386.26392) (xy 51.908803 -386.285718)
			(xy 51.863206 -386.30057) (xy 51.815847 -386.308109) (xy 51.79187 -386.3086) (xy 51.791362 -386.3086)
			(xy 51.76779 -386.308156) (xy 51.721204 -386.300924) (xy 51.676286 -386.286607) (xy 51.634108 -386.265547)
			(xy 51.595674 -386.238245) (xy 51.561901 -386.205352) (xy 51.533594 -386.167653) (xy 51.522122 -386.147056)
			(xy 51.521614 -386.146294) (xy 51.508152 -386.122926) (xy 51.502763 -386.114478) (xy 51.486877 -386.102291)
			(xy 51.467536 -386.097115) (xy 51.447687 -386.099737) (xy 51.43881 -386.104384) (xy 51.429666 -386.109718)
			(xy 51.42357 -386.1181) (xy 51.412628 -386.131987) (xy 51.386549 -386.155853) (xy 51.356527 -386.174517)
			(xy 51.323584 -386.187342) (xy 51.288845 -386.193892) (xy 51.27117 -386.1943) (xy 51.270662 -386.1943)
			(xy 51.251887 -386.193838) (xy 51.215057 -386.186513) (xy 51.180361 -386.172151) (xy 51.149129 -386.151303)
			(xy 51.122559 -386.124768) (xy 51.101669 -386.093563) (xy 51.087261 -386.058887) (xy 51.079887 -386.022067)
			(xy 51.0794 -386.003292) (xy 51.079884 -385.984179) (xy 51.087444 -385.946708) (xy 51.102302 -385.911488)
			(xy 51.123863 -385.879923) (xy 51.151268 -385.853274) (xy 51.183424 -385.832604) (xy 51.201066 -385.825238)
			(xy 51.211226 -385.821174) (xy 51.22672 -385.805426) (xy 51.25593 -385.722114) (xy 51.259157 -385.711535)
			(xy 51.257178 -385.689532) (xy 51.25212 -385.679696) (xy 51.12385 -385.457954) (xy 51.111912 -385.433824)
			(xy 51.107072 -385.424314) (xy 51.091287 -385.409998) (xy 51.071052 -385.403315) (xy 51.049846 -385.405413)
			(xy 51.031313 -385.415932) (xy 51.024536 -385.424172) (xy 51.013594 -385.438221) (xy 50.987458 -385.462398)
			(xy 50.957297 -385.481317) (xy 50.924154 -385.494324) (xy 50.889175 -385.500967) (xy 50.871374 -385.501388)
			(xy 50.870866 -385.501388) (xy 50.84318 -385.499356) (xy 50.842926 -385.499356) (xy 50.833459 -385.498366)
			(xy 50.81494 -385.502717) (xy 50.799288 -385.51353) (xy 50.79365 -385.5212) (xy 50.742088 -385.596892)
			(xy 50.737105 -385.605047) (xy 50.732924 -385.623677) (xy 50.735845 -385.642546) (xy 50.74031 -385.650994)
			(xy 50.85588 -385.850892) (xy 50.868619 -385.874207) (xy 50.886709 -385.924157) (xy 50.895924 -385.976476)
			(xy 50.89652 -386.003038) (xy 50.89652 -386.003292) (xy 50.89603 -386.027282) (xy 50.888526 -386.074673)
			(xy 50.8737 -386.120306) (xy 50.851918 -386.163057) (xy 50.823717 -386.201876) (xy 50.789791 -386.235804)
			(xy 50.750974 -386.264008) (xy 50.708224 -386.285792) (xy 50.662592 -386.300621) (xy 50.615202 -386.308128)
			(xy 50.591212 -386.3086) (xy 50.567638 -386.308197) (xy 50.521051 -386.300957) (xy 50.476132 -386.286633)
			(xy 50.433954 -386.265566) (xy 50.395521 -386.238258) (xy 50.361749 -386.205359) (xy 50.333443 -386.167655)
			(xy 50.321972 -386.147056) (xy 50.321464 -386.146294) (xy 50.308002 -386.122926) (xy 50.302664 -386.11444)
			(xy 50.28676 -386.102254) (xy 50.267401 -386.097087) (xy 50.247539 -386.099726) (xy 50.23866 -386.104384)
			(xy 50.229516 -386.109718) (xy 50.22342 -386.1181) (xy 50.212506 -386.132011) (xy 50.18642 -386.155875)
			(xy 50.156391 -386.174535) (xy 50.123442 -386.187355) (xy 50.088697 -386.193896) (xy 50.07102 -386.1943)
			(xy 50.070512 -386.1943) (xy 50.051742 -386.193867) (xy 50.014922 -386.186545) (xy 49.980238 -386.17218)
			(xy 49.949024 -386.151325) (xy 49.922478 -386.12478) (xy 49.901621 -386.093566) (xy 49.887256 -386.058882)
			(xy 49.879933 -386.022062) (xy 49.879504 -386.003292) (xy 49.879976 -385.984198) (xy 49.887544 -385.946767)
			(xy 49.902379 -385.911577) (xy 49.923892 -385.880025) (xy 49.95123 -385.853361) (xy 49.98331 -385.832642)
			(xy 50.000916 -385.825238) (xy 50.011076 -385.821174) (xy 50.02657 -385.805426) (xy 50.05578 -385.722114)
			(xy 50.059001 -385.711534) (xy 50.057024 -385.689533) (xy 50.05197 -385.679696) (xy 49.9237 -385.457954)
			(xy 49.911762 -385.433824) (xy 49.906992 -385.424273) (xy 49.891187 -385.409952) (xy 49.870932 -385.403272)
			(xy 49.849708 -385.405383) (xy 49.831165 -385.415921) (xy 49.824386 -385.424172) (xy 49.813456 -385.438263)
			(xy 49.787269 -385.462466) (xy 49.757048 -385.481392) (xy 49.72384 -385.494385) (xy 49.688799 -385.500993)
			(xy 49.67097 -385.501388) (xy 49.670462 -385.501388) (xy 49.663582 -385.50139) (xy 49.649852 -385.500497)
			(xy 49.64303 -385.49961) (xy 49.628552 -385.497324) (xy 49.601882 -385.509008) (xy 49.542192 -385.596892)
			(xy 49.537209 -385.605047) (xy 49.533028 -385.623677) (xy 49.535949 -385.642546) (xy 49.540414 -385.650994)
			(xy 49.655984 -385.850892) (xy 49.668715 -385.874211) (xy 49.68681 -385.924158) (xy 49.696027 -385.976477)
			(xy 49.696624 -386.003038) (xy 49.696624 -386.003292) (xy 49.69613 -386.027282) (xy 49.688626 -386.074672)
			(xy 49.6738 -386.120305) (xy 49.652019 -386.163056) (xy 49.623818 -386.201874) (xy 49.589892 -386.235803)
			(xy 49.551077 -386.264007) (xy 49.508327 -386.285791) (xy 49.462695 -386.30062) (xy 49.415306 -386.308128)
			(xy 49.391316 -386.3086) (xy 49.367742 -386.308193) (xy 49.321155 -386.300954) (xy 49.276236 -386.286631)
			(xy 49.234058 -386.265564) (xy 49.195625 -386.238257) (xy 49.161853 -386.205359) (xy 49.133547 -386.167655)
			(xy 49.122076 -386.147056) (xy 49.121568 -386.146294) (xy 49.108106 -386.122926) (xy 49.102764 -386.114443)
			(xy 49.086861 -386.102257) (xy 49.067504 -386.097089) (xy 49.047643 -386.099727) (xy 49.038764 -386.104384)
			(xy 49.02962 -386.109718) (xy 49.023524 -386.1181) (xy 49.012608 -386.132009) (xy 48.986523 -386.155873)
			(xy 48.956494 -386.174534) (xy 48.923545 -386.187354) (xy 48.888801 -386.193896) (xy 48.871124 -386.1943)
			(xy 48.870616 -386.1943) (xy 48.851846 -386.193864) (xy 48.815026 -386.186543) (xy 48.780342 -386.172178)
			(xy 48.749128 -386.151323) (xy 48.722582 -386.124778) (xy 48.701726 -386.093565) (xy 48.68736 -386.058882)
			(xy 48.680037 -386.022062) (xy 48.679608 -386.003292) (xy 48.680077 -385.984198) (xy 48.687646 -385.946766)
			(xy 48.702481 -385.911577) (xy 48.723994 -385.880024) (xy 48.751333 -385.85336) (xy 48.783413 -385.832642)
			(xy 48.80102 -385.825238) (xy 48.81118 -385.821174) (xy 48.826674 -385.805426) (xy 48.855884 -385.722114)
			(xy 48.859105 -385.711534) (xy 48.857128 -385.689533) (xy 48.852074 -385.679696) (xy 48.723804 -385.457954)
			(xy 48.711866 -385.433824) (xy 48.70709 -385.424277) (xy 48.691287 -385.409955) (xy 48.671033 -385.403275)
			(xy 48.649811 -385.405385) (xy 48.631269 -385.415922) (xy 48.62449 -385.424172) (xy 48.613557 -385.438261)
			(xy 48.587371 -385.462464) (xy 48.55715 -385.481391) (xy 48.523944 -385.494384) (xy 48.488903 -385.500993)
			(xy 48.471074 -385.501388) (xy 48.470566 -385.501388) (xy 48.463686 -385.50139) (xy 48.449956 -385.500497)
			(xy 48.443134 -385.49961) (xy 48.428656 -385.497324) (xy 48.401986 -385.509008) (xy 48.342296 -385.596892)
			(xy 48.337312 -385.605047) (xy 48.333131 -385.623677) (xy 48.336053 -385.642546) (xy 48.340518 -385.650994)
			(xy 48.456088 -385.850892) (xy 48.46882 -385.874211) (xy 48.486915 -385.924158) (xy 48.496131 -385.976477)
			(xy 48.496728 -386.003038) (xy 48.496728 -386.003292) (xy 48.49623 -386.027282) (xy 48.488726 -386.074672)
			(xy 48.473901 -386.120304) (xy 48.45212 -386.163055) (xy 48.42392 -386.201873) (xy 48.389994 -386.235801)
			(xy 48.351179 -386.264005) (xy 48.30843 -386.28579) (xy 48.262799 -386.300619) (xy 48.21541 -386.308128)
			(xy 48.19142 -386.3086) (xy 48.167847 -386.30819) (xy 48.121259 -386.300952) (xy 48.076341 -386.286629)
			(xy 48.034162 -386.265563) (xy 47.995729 -386.238256) (xy 47.961957 -386.205358) (xy 47.933651 -386.167655)
			(xy 47.92218 -386.147056) (xy 47.921672 -386.146294) (xy 47.90821 -386.122926) (xy 47.902864 -386.114446)
			(xy 47.886962 -386.10226) (xy 47.867607 -386.097091) (xy 47.847747 -386.099728) (xy 47.838868 -386.104384)
			(xy 47.829724 -386.109718) (xy 47.823628 -386.1181) (xy 47.81271 -386.132007) (xy 47.786625 -386.155872)
			(xy 47.756596 -386.174532) (xy 47.723648 -386.187353) (xy 47.688905 -386.193895) (xy 47.671228 -386.1943)
			(xy 47.67072 -386.1943) (xy 47.65195 -386.19386) (xy 47.61513 -386.18654) (xy 47.580447 -386.172176)
			(xy 47.549232 -386.151321) (xy 47.522686 -386.124777) (xy 47.50183 -386.093564) (xy 47.487464 -386.058881)
			(xy 47.480141 -386.022062) (xy 47.479712 -386.003292) (xy 47.480179 -385.984197) (xy 47.487748 -385.946766)
			(xy 47.502583 -385.911576) (xy 47.524097 -385.880024) (xy 47.551436 -385.85336) (xy 47.583517 -385.832642)
			(xy 47.601124 -385.825238) (xy 47.611284 -385.821174) (xy 47.626778 -385.805426) (xy 47.655988 -385.722114)
			(xy 47.65922 -385.711536) (xy 47.657239 -385.689531) (xy 47.652178 -385.679696) (xy 47.523908 -385.457954)
			(xy 47.51197 -385.433824) (xy 47.507188 -385.42428) (xy 47.491387 -385.409959) (xy 47.471135 -385.403279)
			(xy 47.449914 -385.405388) (xy 47.431373 -385.415923) (xy 47.424594 -385.424172) (xy 47.413676 -385.43824)
			(xy 47.387534 -385.462416) (xy 47.357367 -385.481332) (xy 47.324218 -385.494334) (xy 47.289235 -385.500971)
			(xy 47.271432 -385.501388) (xy 47.270924 -385.501388) (xy 47.250896 -385.500944) (xy 47.211713 -385.49262)
			(xy 47.175118 -385.476331) (xy 47.14271 -385.452788) (xy 47.115905 -385.423022) (xy 47.095876 -385.388333)
			(xy 47.083496 -385.350237) (xy 47.079309 -385.3104) (xy 2.509012 -385.3104) (xy 2.509012 -387.789674)
			(xy 40.901112 -387.789674) (xy 40.901112 -386.926074) (xy 40.901598 -386.898805) (xy 40.90936 -386.844821)
			(xy 40.924725 -386.792491) (xy 40.947382 -386.742881) (xy 40.976868 -386.697) (xy 41.012583 -386.655783)
			(xy 41.0538 -386.620068) (xy 41.099681 -386.590582) (xy 41.149291 -386.567925) (xy 41.201621 -386.55256)
			(xy 41.255605 -386.544798) (xy 41.310143 -386.544798) (xy 41.364127 -386.55256) (xy 41.416457 -386.567925)
			(xy 41.466067 -386.590582) (xy 41.511948 -386.620068) (xy 41.553165 -386.655783) (xy 41.58888 -386.697)
			(xy 41.618366 -386.742881) (xy 41.641023 -386.792491) (xy 41.656388 -386.844821) (xy 41.66415 -386.898805)
			(xy 41.664636 -386.926074) (xy 41.664636 -387.789674) (xy 73.42886 -387.789674) (xy 73.42886 -386.926074)
			(xy 73.429346 -386.898805) (xy 73.437108 -386.844821) (xy 73.452473 -386.792491) (xy 73.47513 -386.742881)
			(xy 73.504616 -386.697) (xy 73.540331 -386.655783) (xy 73.581548 -386.620068) (xy 73.627429 -386.590582)
			(xy 73.677039 -386.567925) (xy 73.729369 -386.55256) (xy 73.783353 -386.544798) (xy 73.837891 -386.544798)
			(xy 73.891875 -386.55256) (xy 73.944205 -386.567925) (xy 73.993815 -386.590582) (xy 74.039696 -386.620068)
			(xy 74.080913 -386.655783) (xy 74.116628 -386.697) (xy 74.146114 -386.742881) (xy 74.168771 -386.792491)
			(xy 74.184136 -386.844821) (xy 74.191898 -386.898805) (xy 74.192384 -386.926074) (xy 74.192384 -387.789674)
			(xy 108.001308 -387.789674) (xy 108.001308 -386.926074) (xy 108.001794 -386.898823) (xy 108.00955 -386.844875)
			(xy 108.024905 -386.79258) (xy 108.047547 -386.743003) (xy 108.077013 -386.697153) (xy 108.112704 -386.655962)
			(xy 108.153895 -386.620271) (xy 108.199745 -386.590805) (xy 108.249322 -386.568163) (xy 108.301617 -386.552808)
			(xy 108.355565 -386.545052) (xy 108.410067 -386.545052) (xy 108.464015 -386.552808) (xy 108.51631 -386.568163)
			(xy 108.565887 -386.590805) (xy 108.611737 -386.620271) (xy 108.652928 -386.655962) (xy 108.688619 -386.697153)
			(xy 108.718085 -386.743003) (xy 108.740727 -386.79258) (xy 108.756082 -386.844875) (xy 108.763838 -386.898823)
			(xy 108.764324 -386.926074) (xy 108.764324 -387.789674) (xy 140.529056 -387.789674) (xy 140.529056 -386.926074)
			(xy 140.529542 -386.898823) (xy 140.537298 -386.844875) (xy 140.552653 -386.79258) (xy 140.575295 -386.743003)
			(xy 140.604761 -386.697153) (xy 140.640452 -386.655962) (xy 140.681643 -386.620271) (xy 140.727493 -386.590805)
			(xy 140.77707 -386.568163) (xy 140.829365 -386.552808) (xy 140.883313 -386.545052) (xy 140.937815 -386.545052)
			(xy 140.991763 -386.552808) (xy 141.044058 -386.568163) (xy 141.093635 -386.590805) (xy 141.139485 -386.620271)
			(xy 141.180676 -386.655962) (xy 141.216367 -386.697153) (xy 141.245833 -386.743003) (xy 141.268475 -386.79258)
			(xy 141.28383 -386.844875) (xy 141.291586 -386.898823) (xy 141.292072 -386.926074) (xy 141.292072 -387.789674)
			(xy 141.291586 -387.816925) (xy 141.28383 -387.870873) (xy 141.268475 -387.923168) (xy 141.245833 -387.972745)
			(xy 141.216367 -388.018595) (xy 141.180676 -388.059786) (xy 141.139485 -388.095477) (xy 141.093635 -388.124943)
			(xy 141.044058 -388.147585) (xy 140.991763 -388.16294) (xy 140.937815 -388.170696) (xy 140.883313 -388.170696)
			(xy 140.829365 -388.16294) (xy 140.77707 -388.147585) (xy 140.727493 -388.124943) (xy 140.681643 -388.095477)
			(xy 140.640452 -388.059786) (xy 140.604761 -388.018595) (xy 140.575295 -387.972745) (xy 140.552653 -387.923168)
			(xy 140.537298 -387.870873) (xy 140.529542 -387.816925) (xy 140.529056 -387.789674) (xy 108.764324 -387.789674)
			(xy 108.763838 -387.816925) (xy 108.756082 -387.870873) (xy 108.740727 -387.923168) (xy 108.718085 -387.972745)
			(xy 108.688619 -388.018595) (xy 108.652928 -388.059786) (xy 108.611737 -388.095477) (xy 108.565887 -388.124943)
			(xy 108.51631 -388.147585) (xy 108.464015 -388.16294) (xy 108.410067 -388.170696) (xy 108.355565 -388.170696)
			(xy 108.301617 -388.16294) (xy 108.249322 -388.147585) (xy 108.199745 -388.124943) (xy 108.153895 -388.095477)
			(xy 108.112704 -388.059786) (xy 108.077013 -388.018595) (xy 108.047547 -387.972745) (xy 108.024905 -387.923168)
			(xy 108.00955 -387.870873) (xy 108.001794 -387.816925) (xy 108.001308 -387.789674) (xy 74.192384 -387.789674)
			(xy 74.191898 -387.816943) (xy 74.184136 -387.870927) (xy 74.168771 -387.923257) (xy 74.146114 -387.972867)
			(xy 74.116628 -388.018748) (xy 74.080913 -388.059965) (xy 74.039696 -388.09568) (xy 73.993815 -388.125166)
			(xy 73.944205 -388.147823) (xy 73.891875 -388.163188) (xy 73.837891 -388.17095) (xy 73.783353 -388.17095)
			(xy 73.729369 -388.163188) (xy 73.677039 -388.147823) (xy 73.627429 -388.125166) (xy 73.581548 -388.09568)
			(xy 73.540331 -388.059965) (xy 73.504616 -388.018748) (xy 73.47513 -387.972867) (xy 73.452473 -387.923257)
			(xy 73.437108 -387.870927) (xy 73.429346 -387.816943) (xy 73.42886 -387.789674) (xy 41.664636 -387.789674)
			(xy 41.66415 -387.816943) (xy 41.656388 -387.870927) (xy 41.641023 -387.923257) (xy 41.618366 -387.972867)
			(xy 41.58888 -388.018748) (xy 41.553165 -388.059965) (xy 41.511948 -388.09568) (xy 41.466067 -388.125166)
			(xy 41.416457 -388.147823) (xy 41.364127 -388.163188) (xy 41.310143 -388.17095) (xy 41.255605 -388.17095)
			(xy 41.201621 -388.163188) (xy 41.149291 -388.147823) (xy 41.099681 -388.125166) (xy 41.0538 -388.09568)
			(xy 41.012583 -388.059965) (xy 40.976868 -388.018748) (xy 40.947382 -387.972867) (xy 40.924725 -387.923257)
			(xy 40.90936 -387.870927) (xy 40.901598 -387.816943) (xy 40.901112 -387.789674) (xy 2.509012 -387.789674)
			(xy 2.509012 -388.7744) (xy 47.079361 -388.7744) (xy 47.083547 -388.734574) (xy 47.095923 -388.696488)
			(xy 47.115947 -388.661808) (xy 47.142745 -388.63205) (xy 47.175144 -388.608514) (xy 47.21173 -388.59223)
			(xy 47.250901 -388.583908) (xy 47.270924 -388.583424) (xy 47.271432 -388.583424) (xy 47.292908 -388.584041)
			(xy 47.33477 -388.593656) (xy 47.373442 -388.61235) (xy 47.390558 -388.625334) (xy 47.398686 -388.631938)
			(xy 47.41926 -388.637526) (xy 47.503842 -388.624826) (xy 47.514099 -388.622723) (xy 47.531799 -388.611575)
			(xy 47.538132 -388.603236) (xy 47.538386 -388.602982) (xy 47.552403 -388.582996) (xy 47.585833 -388.547423)
			(xy 47.624495 -388.517619) (xy 47.667403 -388.494342) (xy 47.713467 -388.478184) (xy 47.761515 -388.469556)
			(xy 47.810323 -388.468679) (xy 47.858649 -388.475574) (xy 47.905264 -388.490067) (xy 47.948982 -388.511787)
			(xy 47.988689 -388.540183) (xy 48.023375 -388.574532) (xy 48.052158 -388.613959) (xy 48.063658 -388.635494)
			(xy 48.064166 -388.636764) (xy 48.110648 -388.717282) (xy 48.115767 -388.725337) (xy 48.130658 -388.737254)
			(xy 48.14886 -388.742948) (xy 48.1584 -388.742682) (xy 48.24984 -388.735824) (xy 48.25923 -388.734736)
			(xy 48.276285 -388.72661) (xy 48.28928 -388.712898) (xy 48.293274 -388.704328) (xy 48.293274 -388.70382)
			(xy 48.300754 -388.686353) (xy 48.321501 -388.654529) (xy 48.348117 -388.627422) (xy 48.379557 -388.606096)
			(xy 48.414585 -388.591391) (xy 48.451825 -388.583882) (xy 48.47082 -388.583424) (xy 48.471328 -388.583424)
			(xy 48.492807 -388.583992) (xy 48.534671 -388.593628) (xy 48.57334 -388.612342) (xy 48.590454 -388.625334)
			(xy 48.598582 -388.631938) (xy 48.619156 -388.637526) (xy 48.703738 -388.624826) (xy 48.713995 -388.622721)
			(xy 48.731695 -388.611574) (xy 48.738028 -388.603236) (xy 48.738282 -388.602982) (xy 48.752305 -388.583)
			(xy 48.785734 -388.547427) (xy 48.824395 -388.517623) (xy 48.867303 -388.494346) (xy 48.913366 -388.478188)
			(xy 48.961413 -388.46956) (xy 49.010221 -388.468683) (xy 49.058547 -388.475578) (xy 49.105161 -388.490069)
			(xy 49.148878 -388.511789) (xy 49.188585 -388.540185) (xy 49.223271 -388.574533) (xy 49.252054 -388.61396)
			(xy 49.263554 -388.635494) (xy 49.264062 -388.636764) (xy 49.310544 -388.717282) (xy 49.315666 -388.725335)
			(xy 49.330555 -388.737252) (xy 49.348756 -388.742947) (xy 49.358296 -388.742682) (xy 49.449736 -388.735824)
			(xy 49.459126 -388.734734) (xy 49.47618 -388.726609) (xy 49.489176 -388.712898) (xy 49.49317 -388.704328)
			(xy 49.49317 -388.70382) (xy 49.500654 -388.686355) (xy 49.5214 -388.654531) (xy 49.548015 -388.627423)
			(xy 49.579454 -388.606098) (xy 49.614482 -388.591392) (xy 49.651722 -388.583883) (xy 49.670716 -388.583424)
			(xy 49.671224 -388.583424) (xy 49.692703 -388.583994) (xy 49.734567 -388.593629) (xy 49.773236 -388.612342)
			(xy 49.79035 -388.625334) (xy 49.798478 -388.631938) (xy 49.819052 -388.637526) (xy 49.903634 -388.624826)
			(xy 49.91389 -388.622719) (xy 49.931591 -388.611574) (xy 49.937924 -388.603236) (xy 49.938178 -388.602982)
			(xy 49.952206 -388.583004) (xy 49.985635 -388.547432) (xy 50.024295 -388.517627) (xy 50.067202 -388.49435)
			(xy 50.113265 -388.478192) (xy 50.161311 -388.469564) (xy 50.210118 -388.468686) (xy 50.258444 -388.475581)
			(xy 50.305058 -388.490072) (xy 50.348775 -388.511791) (xy 50.388481 -388.540186) (xy 50.423168 -388.574534)
			(xy 50.45195 -388.61396) (xy 50.46345 -388.635494) (xy 50.463958 -388.636764) (xy 50.510694 -388.717536)
			(xy 50.515796 -388.725605) (xy 50.530693 -388.737523) (xy 50.548903 -388.743209) (xy 50.558446 -388.742936)
			(xy 50.66411 -388.735062) (xy 50.687732 -388.71779) (xy 50.693066 -388.704074) (xy 50.700524 -388.686561)
			(xy 50.721292 -388.654669) (xy 50.747947 -388.627503) (xy 50.779438 -388.606133) (xy 50.814529 -388.591398)
			(xy 50.851837 -388.58388) (xy 50.870866 -388.583424) (xy 50.871374 -388.583424) (xy 50.892851 -388.58402)
			(xy 50.934715 -388.593644) (xy 50.973385 -388.612347) (xy 50.9905 -388.625334) (xy 50.998628 -388.631938)
			(xy 51.019202 -388.637526) (xy 51.103784 -388.624826) (xy 51.114034 -388.622695) (xy 51.131738 -388.611567)
			(xy 51.138074 -388.603236) (xy 51.138328 -388.602982) (xy 51.152424 -388.583054) (xy 51.185844 -388.547483)
			(xy 51.224496 -388.517679) (xy 51.267396 -388.494401) (xy 51.313451 -388.478241) (xy 51.36149 -388.469611)
			(xy 51.41029 -388.468729) (xy 51.45861 -388.475619) (xy 51.505219 -388.490104) (xy 51.548931 -388.511817)
			(xy 51.588635 -388.540205) (xy 51.623319 -388.574545) (xy 51.6521 -388.613964) (xy 51.6636 -388.635494)
			(xy 51.664108 -388.636764) (xy 51.71059 -388.717282) (xy 51.715681 -388.725358) (xy 51.730585 -388.737271)
			(xy 51.748798 -388.742955) (xy 51.758342 -388.742682) (xy 51.849782 -388.735824) (xy 51.859165 -388.734698)
			(xy 51.87622 -388.72659) (xy 51.889219 -388.712893) (xy 51.893216 -388.704328) (xy 51.893216 -388.70382)
			(xy 51.900663 -388.686338) (xy 51.921415 -388.654512) (xy 51.948038 -388.627405) (xy 51.979484 -388.606082)
			(xy 52.014519 -388.59138) (xy 52.051765 -388.583879) (xy 52.070762 -388.583424) (xy 52.07127 -388.583424)
			(xy 52.092747 -388.584022) (xy 52.13461 -388.593645) (xy 52.173281 -388.612347) (xy 52.190396 -388.625334)
			(xy 52.198524 -388.631938) (xy 52.219098 -388.637526) (xy 52.30368 -388.624826) (xy 52.313929 -388.622694)
			(xy 52.331633 -388.611567) (xy 52.33797 -388.603236) (xy 52.338224 -388.602982) (xy 52.352325 -388.583058)
			(xy 52.385745 -388.547487) (xy 52.424397 -388.517684) (xy 52.467295 -388.494405) (xy 52.51335 -388.478245)
			(xy 52.561388 -388.469614) (xy 52.610188 -388.468732) (xy 52.658507 -388.475622) (xy 52.705116 -388.490107)
			(xy 52.748828 -388.511819) (xy 52.788531 -388.540206) (xy 52.823215 -388.574546) (xy 52.851996 -388.613964)
			(xy 52.863496 -388.635494) (xy 52.864004 -388.636764) (xy 52.91074 -388.717536) (xy 52.915878 -388.725578)
			(xy 52.930758 -388.737501) (xy 52.948954 -388.7432) (xy 52.958492 -388.742936) (xy 53.064156 -388.735062)
			(xy 53.087778 -388.71779) (xy 53.093112 -388.704074) (xy 53.100614 -388.686582) (xy 53.121374 -388.654691)
			(xy 53.14802 -388.627525) (xy 53.179503 -388.606152) (xy 53.214585 -388.591412) (xy 53.251886 -388.583885)
			(xy 53.270912 -388.583424) (xy 53.27142 -388.583424) (xy 53.292898 -388.583996) (xy 53.334763 -388.59363)
			(xy 53.373432 -388.612342) (xy 53.390546 -388.625334) (xy 53.398674 -388.631938) (xy 53.419248 -388.637526)
			(xy 53.50383 -388.624826) (xy 53.514086 -388.622717) (xy 53.531787 -388.611573) (xy 53.53812 -388.603236)
			(xy 53.538374 -388.602982) (xy 53.552408 -388.583008) (xy 53.585836 -388.547436) (xy 53.624495 -388.517631)
			(xy 53.667402 -388.494354) (xy 53.713464 -388.478196) (xy 53.76151 -388.469568) (xy 53.810316 -388.468689)
			(xy 53.858641 -388.475584) (xy 53.905255 -388.490075) (xy 53.948971 -388.511793) (xy 53.988678 -388.540188)
			(xy 54.023364 -388.574535) (xy 54.052146 -388.61396) (xy 54.063646 -388.635494) (xy 54.064154 -388.636764)
			(xy 54.110636 -388.717282) (xy 54.115763 -388.725331) (xy 54.13065 -388.737249) (xy 54.148849 -388.742946)
			(xy 54.158388 -388.742682) (xy 54.249828 -388.735824) (xy 54.259217 -388.734728) (xy 54.276271 -388.726606)
			(xy 54.289267 -388.712897) (xy 54.293262 -388.704328) (xy 54.293262 -388.70382) (xy 54.300752 -388.686358)
			(xy 54.321497 -388.654534) (xy 54.348111 -388.627427) (xy 54.379549 -388.606101) (xy 54.414575 -388.591394)
			(xy 54.451814 -388.583884) (xy 54.470808 -388.583424) (xy 54.471316 -388.583424) (xy 54.492794 -388.583998)
			(xy 54.534659 -388.593631) (xy 54.573328 -388.612343) (xy 54.590442 -388.625334) (xy 54.59857 -388.631938)
			(xy 54.619144 -388.637526) (xy 54.703726 -388.624826) (xy 54.713981 -388.622715) (xy 54.731682 -388.611573)
			(xy 54.738016 -388.603236) (xy 54.73827 -388.602982) (xy 54.752309 -388.583012) (xy 54.785736 -388.54744)
			(xy 54.824395 -388.517636) (xy 54.867301 -388.494358) (xy 54.913363 -388.4782) (xy 54.961408 -388.469571)
			(xy 55.010214 -388.468693) (xy 55.058538 -388.475587) (xy 55.105152 -388.490077) (xy 55.148868 -388.511796)
			(xy 55.188574 -388.540189) (xy 55.22326 -388.574536) (xy 55.252042 -388.613961) (xy 55.263542 -388.635494)
			(xy 55.26405 -388.636764) (xy 55.310532 -388.717282) (xy 55.315662 -388.725329) (xy 55.330548 -388.737247)
			(xy 55.348745 -388.742945) (xy 55.358284 -388.742682) (xy 55.449724 -388.735824) (xy 55.459112 -388.734725)
			(xy 55.476167 -388.726605) (xy 55.489163 -388.712897) (xy 55.493158 -388.704328) (xy 55.493158 -388.70382)
			(xy 55.500651 -388.686359) (xy 55.521396 -388.654536) (xy 55.54801 -388.627428) (xy 55.579447 -388.606102)
			(xy 55.614472 -388.591395) (xy 55.65171 -388.583884) (xy 55.670704 -388.583424) (xy 55.671212 -388.583424)
			(xy 55.69269 -388.584) (xy 55.734554 -388.593632) (xy 55.773224 -388.612343) (xy 55.790338 -388.625334)
			(xy 55.798466 -388.631938) (xy 55.81904 -388.637526) (xy 55.903622 -388.624826) (xy 55.913877 -388.622713)
			(xy 55.931578 -388.611572) (xy 55.937912 -388.603236) (xy 55.938166 -388.602982) (xy 55.95221 -388.583016)
			(xy 55.985637 -388.547444) (xy 56.024295 -388.51764) (xy 56.067201 -388.494362) (xy 56.113262 -388.478204)
			(xy 56.161306 -388.469575) (xy 56.210112 -388.468696) (xy 56.258436 -388.47559) (xy 56.305049 -388.49008)
			(xy 56.348764 -388.511798) (xy 56.38847 -388.540191) (xy 56.423156 -388.574537) (xy 56.451938 -388.613961)
			(xy 56.463438 -388.635494) (xy 56.463946 -388.636764) (xy 56.510682 -388.717536) (xy 56.515792 -388.725599)
			(xy 56.530685 -388.737518) (xy 56.548892 -388.743207) (xy 56.558434 -388.742936) (xy 56.664098 -388.735062)
			(xy 56.68772 -388.71779) (xy 56.693054 -388.704074) (xy 56.700522 -388.686566) (xy 56.721288 -388.654674)
			(xy 56.747941 -388.627508) (xy 56.779431 -388.606137) (xy 56.814519 -388.591401) (xy 56.851826 -388.583881)
			(xy 56.870854 -388.583424) (xy 56.871362 -388.583424) (xy 56.892839 -388.584026) (xy 56.934702 -388.593647)
			(xy 56.973372 -388.612348) (xy 56.990488 -388.625334) (xy 56.998616 -388.631938) (xy 57.01919 -388.637526)
			(xy 57.103772 -388.624826) (xy 57.11402 -388.62269) (xy 57.131725 -388.611566) (xy 57.138062 -388.603236)
			(xy 57.138316 -388.602982) (xy 57.152428 -388.583066) (xy 57.185847 -388.547495) (xy 57.224497 -388.517692)
			(xy 57.267394 -388.494414) (xy 57.313448 -388.478253) (xy 57.361485 -388.469622) (xy 57.410284 -388.468739)
			(xy 57.458601 -388.475628) (xy 57.505209 -388.490112) (xy 57.548921 -388.511823) (xy 57.588623 -388.540209)
			(xy 57.623307 -388.574548) (xy 57.652089 -388.613965) (xy 57.663588 -388.635494) (xy 57.664096 -388.636764)
			(xy 57.710578 -388.717282) (xy 57.715677 -388.725352) (xy 57.730577 -388.737266) (xy 57.748787 -388.742953)
			(xy 57.75833 -388.742682) (xy 57.84977 -388.735824) (xy 57.859152 -388.734689) (xy 57.876207 -388.726586)
			(xy 57.889206 -388.712891) (xy 57.893204 -388.704328) (xy 57.893204 -388.70382) (xy 57.90066 -388.686342)
			(xy 57.921411 -388.654517) (xy 57.948032 -388.62741) (xy 57.979476 -388.606086) (xy 58.014509 -388.591383)
			(xy 58.051754 -388.58388) (xy 58.07075 -388.583424) (xy 58.071258 -388.583424) (xy 58.092734 -388.584028)
			(xy 58.134598 -388.593648) (xy 58.173268 -388.612348) (xy 58.190384 -388.625334) (xy 58.198512 -388.631938)
			(xy 58.219086 -388.637526) (xy 58.303668 -388.624826) (xy 58.313928 -388.622734) (xy 58.331627 -388.611578)
			(xy 58.337958 -388.603236) (xy 58.338212 -388.602982) (xy 58.352329 -388.58307) (xy 58.385748 -388.547499)
			(xy 58.424397 -388.517696) (xy 58.467294 -388.494418) (xy 58.513347 -388.478257) (xy 58.561383 -388.469626)
			(xy 58.610181 -388.468743) (xy 58.658499 -388.475631) (xy 58.705106 -388.490114) (xy 58.748817 -388.511825)
			(xy 58.78852 -388.540211) (xy 58.823203 -388.574549) (xy 58.851985 -388.613965) (xy 58.863484 -388.635494)
			(xy 58.863992 -388.636764) (xy 58.910728 -388.717536) (xy 58.915874 -388.725572) (xy 58.930751 -388.737496)
			(xy 58.948943 -388.743198) (xy 58.95848 -388.742936) (xy 59.064144 -388.735062) (xy 59.087766 -388.71779)
			(xy 59.0931 -388.704074) (xy 59.100531 -388.686549) (xy 59.121304 -388.654655) (xy 59.147963 -388.627489)
			(xy 59.17946 -388.606121) (xy 59.214556 -388.59139) (xy 59.251869 -388.583877) (xy 59.2709 -388.583424)
			(xy 59.271408 -388.583424) (xy 59.292886 -388.584002) (xy 59.33475 -388.593634) (xy 59.37342 -388.612344)
			(xy 59.390534 -388.625334) (xy 59.398662 -388.631938) (xy 59.419236 -388.637526) (xy 59.503818 -388.624826)
			(xy 59.514072 -388.622712) (xy 59.531774 -388.611572) (xy 59.538108 -388.603236) (xy 59.538362 -388.602982)
			(xy 59.552412 -388.58302) (xy 59.585838 -388.547448) (xy 59.624495 -388.517644) (xy 59.6674 -388.494366)
			(xy 59.713461 -388.478208) (xy 59.761505 -388.469579) (xy 59.810309 -388.4687) (xy 59.858633 -388.475593)
			(xy 59.905245 -388.490082) (xy 59.948961 -388.5118) (xy 59.988666 -388.540192) (xy 60.023352 -388.574537)
			(xy 60.052134 -388.613961) (xy 60.063634 -388.635494) (xy 60.064142 -388.636764) (xy 60.110624 -388.717282)
			(xy 60.115759 -388.725325) (xy 60.130643 -388.737244) (xy 60.148838 -388.742944) (xy 60.158376 -388.742682)
			(xy 60.249816 -388.735824) (xy 60.259203 -388.73472) (xy 60.276258 -388.726602) (xy 60.289254 -388.712896)
			(xy 60.29325 -388.704328) (xy 60.29325 -388.70382) (xy 60.30075 -388.686362) (xy 60.321493 -388.654539)
			(xy 60.348106 -388.627432) (xy 60.379541 -388.606105) (xy 60.414566 -388.591397) (xy 60.451803 -388.583885)
			(xy 60.470796 -388.583424) (xy 60.471304 -388.583424) (xy 60.492782 -388.584004) (xy 60.534646 -388.593635)
			(xy 60.573315 -388.612344) (xy 60.59043 -388.625334) (xy 60.598558 -388.631938) (xy 60.619132 -388.637526)
			(xy 60.703714 -388.624826) (xy 60.713967 -388.622709) (xy 60.731669 -388.611571) (xy 60.738004 -388.603236)
			(xy 60.738258 -388.602982) (xy 60.752313 -388.583024) (xy 60.785739 -388.547452) (xy 60.824395 -388.517648)
			(xy 60.8673 -388.49437) (xy 60.91336 -388.478212) (xy 60.961403 -388.469583) (xy 61.010207 -388.468703)
			(xy 61.05853 -388.475596) (xy 61.105142 -388.490085) (xy 61.148857 -388.511802) (xy 61.188563 -388.540194)
			(xy 61.223248 -388.574538) (xy 61.25203 -388.613962) (xy 61.26353 -388.635494) (xy 61.264038 -388.636764)
			(xy 61.31052 -388.717282) (xy 61.315658 -388.725323) (xy 61.33054 -388.737242) (xy 61.348734 -388.742943)
			(xy 61.358272 -388.742682) (xy 61.449712 -388.735824) (xy 61.459099 -388.734717) (xy 61.476153 -388.726601)
			(xy 61.48915 -388.712896) (xy 61.493146 -388.704328) (xy 61.493146 -388.70382) (xy 61.500568 -388.686326)
			(xy 61.521325 -388.654499) (xy 61.547952 -388.627393) (xy 61.579404 -388.606071) (xy 61.614443 -388.591373)
			(xy 61.651693 -388.583876) (xy 61.670692 -388.583424) (xy 61.6712 -388.583424) (xy 61.692678 -388.584006)
			(xy 61.734542 -388.593636) (xy 61.773211 -388.612344) (xy 61.790326 -388.625334) (xy 61.798454 -388.631938)
			(xy 61.819028 -388.637526) (xy 61.90361 -388.624826) (xy 61.913863 -388.622707) (xy 61.931565 -388.61157)
			(xy 61.9379 -388.603236) (xy 61.938154 -388.602982) (xy 61.952215 -388.583028) (xy 61.985639 -388.547456)
			(xy 62.024296 -388.517652) (xy 62.067199 -388.494375) (xy 62.113258 -388.478216) (xy 62.161301 -388.469586)
			(xy 62.210105 -388.468707) (xy 62.258427 -388.475599) (xy 62.305039 -388.490087) (xy 62.348754 -388.511804)
			(xy 62.388459 -388.540195) (xy 62.423144 -388.574539) (xy 62.451926 -388.613962) (xy 62.463426 -388.635494)
			(xy 62.463934 -388.636764) (xy 62.51067 -388.717536) (xy 62.515788 -388.725593) (xy 62.530677 -388.737513)
			(xy 62.548881 -388.743205) (xy 62.558422 -388.742936) (xy 62.664086 -388.735062) (xy 62.687708 -388.71779)
			(xy 62.693042 -388.704074) (xy 62.70052 -388.68657) (xy 62.721284 -388.654679) (xy 62.747935 -388.627513)
			(xy 62.779423 -388.606141) (xy 62.814509 -388.591404) (xy 62.851814 -388.583882) (xy 62.870842 -388.583424)
			(xy 62.87135 -388.583424) (xy 62.892826 -388.584032) (xy 62.934689 -388.593651) (xy 62.97336 -388.612349)
			(xy 62.990476 -388.625334) (xy 62.998604 -388.631938) (xy 63.019178 -388.637526) (xy 63.10376 -388.624826)
			(xy 63.114019 -388.622731) (xy 63.131718 -388.611577) (xy 63.13805 -388.603236) (xy 63.138304 -388.602982)
			(xy 63.152432 -388.583078) (xy 63.185849 -388.547508) (xy 63.224497 -388.517704) (xy 63.267393 -388.494426)
			(xy 63.313444 -388.478265) (xy 63.36148 -388.469633) (xy 63.410277 -388.46875) (xy 63.458593 -388.475637)
			(xy 63.5052 -388.49012) (xy 63.54891 -388.51183) (xy 63.588612 -388.540214) (xy 63.623295 -388.574551)
			(xy 63.652077 -388.613966) (xy 63.663576 -388.635494) (xy 63.664084 -388.636764) (xy 63.710566 -388.717282)
			(xy 63.715673 -388.725346) (xy 63.730569 -388.737261) (xy 63.748776 -388.742951) (xy 63.758318 -388.742682)
			(xy 63.849758 -388.735824) (xy 63.859139 -388.734681) (xy 63.876193 -388.726582) (xy 63.889194 -388.71289)
			(xy 63.893192 -388.704328) (xy 63.893192 -388.70382) (xy 63.900658 -388.686347) (xy 63.921407 -388.654522)
			(xy 63.948026 -388.627414) (xy 63.979469 -388.60609) (xy 64.014499 -388.591386) (xy 64.051742 -388.583881)
			(xy 64.070738 -388.583424) (xy 64.071246 -388.583424) (xy 64.092722 -388.584034) (xy 64.134585 -388.593652)
			(xy 64.173256 -388.612349) (xy 64.190372 -388.625334) (xy 64.1985 -388.631938) (xy 64.219074 -388.637526)
			(xy 64.303656 -388.624826) (xy 64.313915 -388.622729) (xy 64.331614 -388.611577) (xy 64.337946 -388.603236)
			(xy 64.3382 -388.602982) (xy 64.352333 -388.583082) (xy 64.38575 -388.547512) (xy 64.424397 -388.517709)
			(xy 64.467292 -388.49443) (xy 64.513343 -388.478269) (xy 64.561378 -388.469637) (xy 64.610175 -388.468753)
			(xy 64.658491 -388.47564) (xy 64.705097 -388.490122) (xy 64.748807 -388.511832) (xy 64.788508 -388.540215)
			(xy 64.823191 -388.574552) (xy 64.851973 -388.613966) (xy 64.863472 -388.635494) (xy 64.86398 -388.636764)
			(xy 64.910716 -388.717536) (xy 64.915804 -388.725615) (xy 64.930707 -388.737532) (xy 64.948923 -388.743213)
			(xy 64.958468 -388.742936) (xy 65.064132 -388.735062) (xy 65.087754 -388.71779) (xy 65.093088 -388.704074)
			(xy 65.100529 -388.686553) (xy 65.1213 -388.65466) (xy 65.147957 -388.627494) (xy 65.179453 -388.606125)
			(xy 65.214546 -388.591393) (xy 65.251858 -388.583878) (xy 65.270888 -388.583424) (xy 65.271396 -388.583424)
			(xy 65.292874 -388.584008) (xy 65.334738 -388.593637) (xy 65.373407 -388.612345) (xy 65.390522 -388.625334)
			(xy 65.39865 -388.631938) (xy 65.419224 -388.637526) (xy 65.503806 -388.624826) (xy 65.514058 -388.622706)
			(xy 65.531761 -388.61157) (xy 65.538096 -388.603236) (xy 65.53835 -388.602982) (xy 65.552416 -388.583032)
			(xy 65.58584 -388.54746) (xy 65.624496 -388.517656) (xy 65.667399 -388.494379) (xy 65.713457 -388.478219)
			(xy 65.7615 -388.46959) (xy 65.810303 -388.46871) (xy 65.858625 -388.475602) (xy 65.905236 -388.49009)
			(xy 65.94895 -388.511806) (xy 65.988655 -388.540197) (xy 66.02334 -388.57454) (xy 66.052122 -388.613962)
			(xy 66.063622 -388.635494) (xy 66.06413 -388.636764) (xy 66.14367 -388.7744) (xy 79.607198 -388.7744)
			(xy 79.611382 -388.734588) (xy 79.623751 -388.696516) (xy 79.643765 -388.661847) (xy 79.670549 -388.632096)
			(xy 79.702933 -388.608564) (xy 79.739501 -388.592278) (xy 79.778657 -388.58395) (xy 79.798672 -388.583424)
			(xy 79.79918 -388.583424) (xy 79.820657 -388.584017) (xy 79.862521 -388.593642) (xy 79.901191 -388.612346)
			(xy 79.918306 -388.625334) (xy 79.926434 -388.631938) (xy 79.947008 -388.637526) (xy 80.03159 -388.624826)
			(xy 80.04184 -388.622698) (xy 80.059544 -388.611568) (xy 80.06588 -388.603236) (xy 80.066134 -388.602982)
			(xy 80.080222 -388.583048) (xy 80.113643 -388.547477) (xy 80.152296 -388.517673) (xy 80.195197 -388.494395)
			(xy 80.241253 -388.478235) (xy 80.289293 -388.469605) (xy 80.338094 -388.468724) (xy 80.386414 -388.475614)
			(xy 80.433023 -388.4901) (xy 80.476736 -388.511814) (xy 80.51644 -388.540203) (xy 80.551124 -388.574544)
			(xy 80.579906 -388.613963) (xy 80.591406 -388.635494) (xy 80.591914 -388.636764) (xy 80.638396 -388.717282)
			(xy 80.643483 -388.725361) (xy 80.658388 -388.737274) (xy 80.676604 -388.742956) (xy 80.686148 -388.742682)
			(xy 80.777588 -388.735824) (xy 80.786972 -388.734702) (xy 80.804027 -388.726592) (xy 80.817025 -388.712893)
			(xy 80.821022 -388.704328) (xy 80.821022 -388.70382) (xy 80.828464 -388.686335) (xy 80.849217 -388.654509)
			(xy 80.875841 -388.627402) (xy 80.907288 -388.60608) (xy 80.942324 -388.591379) (xy 80.979571 -388.583878)
			(xy 80.998568 -388.583424) (xy 80.999076 -388.583424) (xy 81.020553 -388.584019) (xy 81.062417 -388.593643)
			(xy 81.101087 -388.612346) (xy 81.118202 -388.625334) (xy 81.12633 -388.631938) (xy 81.146904 -388.637526)
			(xy 81.231486 -388.624826) (xy 81.241736 -388.622696) (xy 81.25944 -388.611567) (xy 81.265776 -388.603236)
			(xy 81.26603 -388.602982) (xy 81.280123 -388.583052) (xy 81.313544 -388.547481) (xy 81.352196 -388.517677)
			(xy 81.395096 -388.494399) (xy 81.441152 -388.478239) (xy 81.489191 -388.469609) (xy 81.537991 -388.468727)
			(xy 81.586311 -388.475617) (xy 81.63292 -388.490103) (xy 81.676633 -388.511816) (xy 81.716336 -388.540204)
			(xy 81.751021 -388.574545) (xy 81.779802 -388.613964) (xy 81.791302 -388.635494) (xy 81.79181 -388.636764)
			(xy 81.838292 -388.717282) (xy 81.843382 -388.725359) (xy 81.858286 -388.737272) (xy 81.8765 -388.742956)
			(xy 81.886044 -388.742682) (xy 81.977484 -388.735824) (xy 81.986868 -388.734699) (xy 82.003922 -388.726591)
			(xy 82.016921 -388.712893) (xy 82.020918 -388.704328) (xy 82.020918 -388.70382) (xy 82.028363 -388.686337)
			(xy 82.049116 -388.654511) (xy 82.075739 -388.627404) (xy 82.107186 -388.606081) (xy 82.14222 -388.59138)
			(xy 82.179467 -388.583878) (xy 82.198464 -388.583424) (xy 82.198972 -388.583424) (xy 82.220449 -388.584021)
			(xy 82.262312 -388.593644) (xy 82.300983 -388.612347) (xy 82.318098 -388.625334) (xy 82.326226 -388.631938)
			(xy 82.3468 -388.637526) (xy 82.431382 -388.624826) (xy 82.441631 -388.622695) (xy 82.459335 -388.611567)
			(xy 82.465672 -388.603236) (xy 82.465926 -388.602982) (xy 82.480024 -388.583056) (xy 82.513445 -388.547485)
			(xy 82.552097 -388.517681) (xy 82.594996 -388.494403) (xy 82.641051 -388.478243) (xy 82.689089 -388.469613)
			(xy 82.737889 -388.468731) (xy 82.786208 -388.47562) (xy 82.832817 -388.490105) (xy 82.876529 -388.511818)
			(xy 82.916233 -388.540206) (xy 82.950917 -388.574546) (xy 82.979698 -388.613964) (xy 82.991198 -388.635494)
			(xy 82.991706 -388.636764) (xy 83.038442 -388.717536) (xy 83.043579 -388.725579) (xy 83.05846 -388.737502)
			(xy 83.076656 -388.7432) (xy 83.086194 -388.742936) (xy 83.191858 -388.735062) (xy 83.21548 -388.71779)
			(xy 83.220814 -388.704074) (xy 83.228314 -388.686581) (xy 83.249075 -388.65469) (xy 83.275721 -388.627524)
			(xy 83.307205 -388.606151) (xy 83.342287 -388.591411) (xy 83.379588 -388.583885) (xy 83.398614 -388.583424)
			(xy 83.399122 -388.583424) (xy 83.4206 -388.583995) (xy 83.462465 -388.59363) (xy 83.501134 -388.612342)
			(xy 83.518248 -388.625334) (xy 83.526376 -388.631938) (xy 83.54695 -388.637526) (xy 83.631532 -388.624826)
			(xy 83.641788 -388.622718) (xy 83.659489 -388.611574) (xy 83.665822 -388.603236) (xy 83.666076 -388.602982)
			(xy 83.680107 -388.583006) (xy 83.713535 -388.547434) (xy 83.752195 -388.517629) (xy 83.795102 -388.494352)
			(xy 83.841165 -388.478194) (xy 83.889211 -388.469566) (xy 83.938017 -388.468688) (xy 83.986342 -388.475582)
			(xy 84.032956 -388.490073) (xy 84.076673 -388.511792) (xy 84.11638 -388.540187) (xy 84.151066 -388.574534)
			(xy 84.179848 -388.61396) (xy 84.191348 -388.635494) (xy 84.191856 -388.636764) (xy 84.238338 -388.717282)
			(xy 84.243464 -388.725332) (xy 84.258352 -388.73725) (xy 84.276551 -388.742946) (xy 84.28609 -388.742682)
			(xy 84.37753 -388.735824) (xy 84.386919 -388.734729) (xy 84.403973 -388.726607) (xy 84.416969 -388.712897)
			(xy 84.420964 -388.704328) (xy 84.420964 -388.70382) (xy 84.428452 -388.686357) (xy 84.449198 -388.654533)
			(xy 84.475812 -388.627426) (xy 84.50725 -388.6061) (xy 84.542277 -388.591393) (xy 84.579516 -388.583883)
			(xy 84.59851 -388.583424) (xy 84.599018 -388.583424) (xy 84.620496 -388.583997) (xy 84.662361 -388.593631)
			(xy 84.70103 -388.612343) (xy 84.718144 -388.625334) (xy 84.726272 -388.631938) (xy 84.746846 -388.637526)
			(xy 84.831428 -388.624826) (xy 84.841683 -388.622716) (xy 84.859385 -388.611573) (xy 84.865718 -388.603236)
			(xy 84.865972 -388.602982) (xy 84.880008 -388.58301) (xy 84.913436 -388.547438) (xy 84.952095 -388.517634)
			(xy 84.995001 -388.494356) (xy 85.041064 -388.478198) (xy 85.089109 -388.469569) (xy 85.137915 -388.468691)
			(xy 85.18624 -388.475585) (xy 85.232853 -388.490076) (xy 85.27657 -388.511794) (xy 85.316276 -388.540188)
			(xy 85.350962 -388.574535) (xy 85.379744 -388.613961) (xy 85.391244 -388.635494) (xy 85.391752 -388.636764)
			(xy 85.438488 -388.717536) (xy 85.443594 -388.725602) (xy 85.458489 -388.737521) (xy 85.476698 -388.743208)
			(xy 85.48624 -388.742936) (xy 85.591904 -388.735062) (xy 85.615526 -388.71779) (xy 85.62086 -388.704074)
			(xy 85.628323 -388.686564) (xy 85.64909 -388.654671) (xy 85.675744 -388.627506) (xy 85.707234 -388.606135)
			(xy 85.742324 -388.5914) (xy 85.779631 -388.58388) (xy 85.79866 -388.583424) (xy 85.799168 -388.583424)
			(xy 85.820645 -388.584023) (xy 85.862508 -388.593645) (xy 85.901179 -388.612347) (xy 85.918294 -388.625334)
			(xy 85.926422 -388.631938) (xy 85.946996 -388.637526) (xy 86.031578 -388.624826) (xy 86.041827 -388.622693)
			(xy 86.059531 -388.611567) (xy 86.065868 -388.603236) (xy 86.066122 -388.602982) (xy 86.080226 -388.58306)
			(xy 86.113646 -388.547489) (xy 86.152297 -388.517686) (xy 86.195195 -388.494408) (xy 86.24125 -388.478247)
			(xy 86.289288 -388.469616) (xy 86.338087 -388.468734) (xy 86.386406 -388.475623) (xy 86.433014 -388.490108)
			(xy 86.476726 -388.51182) (xy 86.516429 -388.540207) (xy 86.551113 -388.574547) (xy 86.579894 -388.613964)
			(xy 86.591394 -388.635494) (xy 86.591902 -388.636764) (xy 86.638384 -388.717282) (xy 86.643479 -388.725355)
			(xy 86.658381 -388.737269) (xy 86.676593 -388.742954) (xy 86.686136 -388.742682) (xy 86.777576 -388.735824)
			(xy 86.786959 -388.734694) (xy 86.804014 -388.726588) (xy 86.817013 -388.712892) (xy 86.82101 -388.704328)
			(xy 86.82101 -388.70382) (xy 86.828461 -388.68634) (xy 86.849213 -388.654514) (xy 86.875835 -388.627407)
			(xy 86.90728 -388.606084) (xy 86.942314 -388.591382) (xy 86.979559 -388.583879) (xy 86.998556 -388.583424)
			(xy 86.999064 -388.583424) (xy 87.020541 -388.584025) (xy 87.062404 -388.593647) (xy 87.101074 -388.612348)
			(xy 87.11819 -388.625334) (xy 87.126318 -388.631938) (xy 87.146892 -388.637526) (xy 87.231474 -388.624826)
			(xy 87.241722 -388.622691) (xy 87.259427 -388.611566) (xy 87.265764 -388.603236) (xy 87.266018 -388.602982)
			(xy 87.280127 -388.583064) (xy 87.313546 -388.547493) (xy 87.352197 -388.51769) (xy 87.395095 -388.494412)
			(xy 87.441148 -388.478251) (xy 87.489186 -388.46962) (xy 87.537985 -388.468738) (xy 87.586303 -388.475626)
			(xy 87.632911 -388.490111) (xy 87.676622 -388.511822) (xy 87.716325 -388.540209) (xy 87.751009 -388.574547)
			(xy 87.779791 -388.613965) (xy 87.79129 -388.635494) (xy 87.791798 -388.636764) (xy 87.83828 -388.717282)
			(xy 87.843378 -388.725353) (xy 87.858278 -388.737267) (xy 87.876489 -388.742953) (xy 87.886032 -388.742682)
			(xy 87.977472 -388.735824) (xy 87.986854 -388.734691) (xy 88.003909 -388.726587) (xy 88.016908 -388.712892)
			(xy 88.020906 -388.704328) (xy 88.020906 -388.70382) (xy 88.028361 -388.686341) (xy 88.049112 -388.654516)
			(xy 88.075733 -388.627409) (xy 88.107178 -388.606085) (xy 88.142211 -388.591383) (xy 88.179456 -388.583879)
			(xy 88.198452 -388.583424) (xy 88.19896 -388.583424) (xy 88.220437 -388.584027) (xy 88.2623 -388.593648)
			(xy 88.30097 -388.612348) (xy 88.318086 -388.625334) (xy 88.326214 -388.631938) (xy 88.346788 -388.637526)
			(xy 88.43137 -388.624826) (xy 88.441631 -388.622735) (xy 88.459329 -388.611578) (xy 88.46566 -388.603236)
			(xy 88.465914 -388.602982) (xy 88.480029 -388.583068) (xy 88.513447 -388.547497) (xy 88.552097 -388.517694)
			(xy 88.594994 -388.494416) (xy 88.641047 -388.478255) (xy 88.689084 -388.469624) (xy 88.737882 -388.468741)
			(xy 88.7862 -388.475629) (xy 88.832808 -388.490113) (xy 88.876519 -388.511824) (xy 88.916221 -388.54021)
			(xy 88.950905 -388.574548) (xy 88.979687 -388.613965) (xy 88.991186 -388.635494) (xy 88.991694 -388.636764)
			(xy 89.03843 -388.717536) (xy 89.043575 -388.725573) (xy 89.058452 -388.737497) (xy 89.076645 -388.743198)
			(xy 89.086182 -388.742936) (xy 89.191846 -388.735062) (xy 89.215468 -388.71779) (xy 89.220802 -388.704074)
			(xy 89.228231 -388.686548) (xy 89.249004 -388.654654) (xy 89.275664 -388.627489) (xy 89.307162 -388.60612)
			(xy 89.342258 -388.591389) (xy 89.379571 -388.583876) (xy 89.398602 -388.583424) (xy 89.39911 -388.583424)
			(xy 89.420588 -388.584001) (xy 89.462452 -388.593633) (xy 89.501122 -388.612343) (xy 89.518236 -388.625334)
			(xy 89.526364 -388.631938) (xy 89.546938 -388.637526) (xy 89.63152 -388.624826) (xy 89.641774 -388.622712)
			(xy 89.659476 -388.611572) (xy 89.66581 -388.603236) (xy 89.666064 -388.602982) (xy 89.680111 -388.583018)
			(xy 89.713538 -388.547446) (xy 89.752195 -388.517642) (xy 89.7951 -388.494364) (xy 89.841161 -388.478206)
			(xy 89.889206 -388.469577) (xy 89.938011 -388.468698) (xy 89.986334 -388.475591) (xy 90.032947 -388.490081)
			(xy 90.076663 -388.511799) (xy 90.116368 -388.540191) (xy 90.151054 -388.574537) (xy 90.179836 -388.613961)
			(xy 90.191336 -388.635494) (xy 90.191844 -388.636764) (xy 90.238326 -388.717282) (xy 90.24346 -388.725326)
			(xy 90.258344 -388.737245) (xy 90.27654 -388.742944) (xy 90.286078 -388.742682) (xy 90.377518 -388.735824)
			(xy 90.386905 -388.734721) (xy 90.40396 -388.726603) (xy 90.416957 -388.712896) (xy 90.420952 -388.704328)
			(xy 90.420952 -388.70382) (xy 90.42845 -388.686362) (xy 90.449194 -388.654538) (xy 90.475807 -388.627431)
			(xy 90.507243 -388.606104) (xy 90.542267 -388.591396) (xy 90.579505 -388.583885) (xy 90.598498 -388.583424)
			(xy 90.599006 -388.583424) (xy 90.620484 -388.584003) (xy 90.662348 -388.593634) (xy 90.701018 -388.612344)
			(xy 90.718132 -388.625334) (xy 90.72626 -388.631938) (xy 90.746834 -388.637526) (xy 90.831416 -388.624826)
			(xy 90.84167 -388.62271) (xy 90.859371 -388.611571) (xy 90.865706 -388.603236) (xy 90.86596 -388.602982)
			(xy 90.880013 -388.583022) (xy 90.913438 -388.54745) (xy 90.952095 -388.517646) (xy 90.995 -388.494368)
			(xy 91.04106 -388.47821) (xy 91.089104 -388.469581) (xy 91.137908 -388.468701) (xy 91.186232 -388.475594)
			(xy 91.232844 -388.490084) (xy 91.276559 -388.511801) (xy 91.316265 -388.540193) (xy 91.35095 -388.574538)
			(xy 91.379732 -388.613961) (xy 91.391232 -388.635494) (xy 91.39174 -388.636764) (xy 91.438476 -388.717536)
			(xy 91.44359 -388.725596) (xy 91.458481 -388.737516) (xy 91.476687 -388.743206) (xy 91.486228 -388.742936)
			(xy 91.591892 -388.735062) (xy 91.615514 -388.71779) (xy 91.620848 -388.704074) (xy 91.628321 -388.686568)
			(xy 91.649086 -388.654676) (xy 91.675738 -388.62751) (xy 91.707227 -388.606139) (xy 91.742314 -388.591403)
			(xy 91.77962 -388.583882) (xy 91.798648 -388.583424) (xy 91.799156 -388.583424) (xy 91.820632 -388.584029)
			(xy 91.862496 -388.593649) (xy 91.901166 -388.612348) (xy 91.918282 -388.625334) (xy 91.92641 -388.631938)
			(xy 91.946984 -388.637526) (xy 92.031566 -388.624826) (xy 92.041826 -388.622734) (xy 92.059525 -388.611578)
			(xy 92.065856 -388.603236) (xy 92.06611 -388.602982) (xy 92.08023 -388.583072) (xy 92.113648 -388.547502)
			(xy 92.152297 -388.517698) (xy 92.195194 -388.49442) (xy 92.241246 -388.478259) (xy 92.289282 -388.469628)
			(xy 92.33808 -388.468744) (xy 92.386397 -388.475632) (xy 92.433005 -388.490116) (xy 92.476715 -388.511826)
			(xy 92.516418 -388.540212) (xy 92.551101 -388.574549) (xy 92.579883 -388.613965) (xy 92.591382 -388.635494)
			(xy 92.59189 -388.636764) (xy 92.638372 -388.717282) (xy 92.643475 -388.725349) (xy 92.658373 -388.737264)
			(xy 92.676582 -388.742952) (xy 92.686124 -388.742682) (xy 92.777564 -388.735824) (xy 92.786945 -388.734685)
			(xy 92.804 -388.726584) (xy 92.817 -388.712891) (xy 92.820998 -388.704328) (xy 92.820998 -388.70382)
			(xy 92.828459 -388.686344) (xy 92.849209 -388.654519) (xy 92.875829 -388.627412) (xy 92.907273 -388.606088)
			(xy 92.942304 -388.591385) (xy 92.979548 -388.58388) (xy 92.998544 -388.583424) (xy 92.999052 -388.583424)
			(xy 93.020528 -388.584031) (xy 93.062391 -388.59365) (xy 93.101062 -388.612349) (xy 93.118178 -388.625334)
			(xy 93.126306 -388.631938) (xy 93.14688 -388.637526) (xy 93.231462 -388.624826) (xy 93.241722 -388.622732)
			(xy 93.259421 -388.611577) (xy 93.265752 -388.603236) (xy 93.266006 -388.602982) (xy 93.280131 -388.583076)
			(xy 93.313549 -388.547506) (xy 93.352197 -388.517702) (xy 93.395093 -388.494424) (xy 93.441145 -388.478263)
			(xy 93.489181 -388.469631) (xy 93.537978 -388.468748) (xy 93.586295 -388.475635) (xy 93.632901 -388.490118)
			(xy 93.676612 -388.511828) (xy 93.716314 -388.540213) (xy 93.750997 -388.57455) (xy 93.779779 -388.613966)
			(xy 93.791278 -388.635494) (xy 93.791786 -388.636764) (xy 93.838268 -388.717282) (xy 93.843374 -388.725347)
			(xy 93.858271 -388.737262) (xy 93.876478 -388.742951) (xy 93.88602 -388.742682) (xy 93.97746 -388.735824)
			(xy 93.986841 -388.734683) (xy 94.003896 -388.726582) (xy 94.016896 -388.71289) (xy 94.020894 -388.704328)
			(xy 94.020894 -388.70382) (xy 94.028358 -388.686346) (xy 94.049108 -388.654521) (xy 94.075727 -388.627414)
			(xy 94.10717 -388.606089) (xy 94.142201 -388.591386) (xy 94.179444 -388.583881) (xy 94.19844 -388.583424)
			(xy 94.198948 -388.583424) (xy 94.220424 -388.584033) (xy 94.262287 -388.593651) (xy 94.300958 -388.612349)
			(xy 94.318074 -388.625334) (xy 94.326202 -388.631938) (xy 94.346776 -388.637526) (xy 94.431358 -388.624826)
			(xy 94.441617 -388.62273) (xy 94.459316 -388.611577) (xy 94.465648 -388.603236) (xy 94.465902 -388.602982)
			(xy 94.480033 -388.58308) (xy 94.513449 -388.54751) (xy 94.552097 -388.517706) (xy 94.594993 -388.494428)
			(xy 94.641044 -388.478267) (xy 94.689079 -388.469635) (xy 94.737876 -388.468751) (xy 94.786192 -388.475638)
			(xy 94.832798 -388.490121) (xy 94.876508 -388.511831) (xy 94.91621 -388.540215) (xy 94.950893 -388.574551)
			(xy 94.979675 -388.613966) (xy 94.991174 -388.635494) (xy 94.991682 -388.636764) (xy 95.038418 -388.717536)
			(xy 95.043504 -388.725616) (xy 95.058408 -388.737533) (xy 95.076625 -388.743214) (xy 95.08617 -388.742936)
			(xy 95.191834 -388.735062) (xy 95.215456 -388.71779) (xy 95.22079 -388.704074) (xy 95.228229 -388.686552)
			(xy 95.249 -388.654659) (xy 95.275658 -388.627493) (xy 95.307154 -388.606124) (xy 95.342248 -388.591392)
			(xy 95.37956 -388.583878) (xy 95.39859 -388.583424) (xy 95.399098 -388.583424) (xy 95.420576 -388.584007)
			(xy 95.46244 -388.593637) (xy 95.501109 -388.612344) (xy 95.518224 -388.625334) (xy 95.526352 -388.631938)
			(xy 95.546926 -388.637526) (xy 95.631508 -388.624826) (xy 95.641761 -388.622706) (xy 95.659463 -388.61157)
			(xy 95.665798 -388.603236) (xy 95.666052 -388.602982) (xy 95.680115 -388.58303) (xy 95.71354 -388.547458)
			(xy 95.752196 -388.517654) (xy 95.795099 -388.494377) (xy 95.841158 -388.478218) (xy 95.8892 -388.469588)
			(xy 95.938004 -388.468708) (xy 95.986326 -388.4756) (xy 96.032938 -388.490089) (xy 96.076652 -388.511805)
			(xy 96.116357 -388.540196) (xy 96.151042 -388.57454) (xy 96.179824 -388.613962) (xy 96.191324 -388.635494)
			(xy 96.191832 -388.636764) (xy 96.238314 -388.717282) (xy 96.243389 -388.72537) (xy 96.2583 -388.737281)
			(xy 96.27652 -388.742959) (xy 96.286066 -388.742682) (xy 96.377506 -388.735824) (xy 96.386892 -388.734714)
			(xy 96.403947 -388.726598) (xy 96.416944 -388.712895) (xy 96.42094 -388.704328) (xy 96.42094 -388.70382)
			(xy 96.428367 -388.686329) (xy 96.449123 -388.654502) (xy 96.475749 -388.627395) (xy 96.5072 -388.606073)
			(xy 96.542238 -388.591374) (xy 96.579488 -388.583876) (xy 96.598486 -388.583424) (xy 96.598994 -388.583424)
			(xy 96.620472 -388.584009) (xy 96.662336 -388.593638) (xy 96.701005 -388.612345) (xy 96.71812 -388.625334)
			(xy 96.726248 -388.631938) (xy 96.746822 -388.637526) (xy 96.831404 -388.624826) (xy 96.841656 -388.622705)
			(xy 96.859359 -388.61157) (xy 96.865694 -388.603236) (xy 96.865948 -388.602982) (xy 96.880017 -388.583034)
			(xy 96.913441 -388.547462) (xy 96.952096 -388.517659) (xy 96.994998 -388.494381) (xy 97.041057 -388.478221)
			(xy 97.089099 -388.469592) (xy 97.137902 -388.468712) (xy 97.186223 -388.475603) (xy 97.232834 -388.490091)
			(xy 97.276549 -388.511807) (xy 97.316253 -388.540197) (xy 97.350938 -388.574541) (xy 97.37972 -388.613962)
			(xy 97.39122 -388.635494) (xy 97.391728 -388.636764) (xy 97.438464 -388.717536) (xy 97.443586 -388.72559)
			(xy 97.458474 -388.737511) (xy 97.476676 -388.743204) (xy 97.486216 -388.742936) (xy 97.59188 -388.735062)
			(xy 97.615502 -388.71779) (xy 97.620836 -388.704074) (xy 97.628319 -388.686573) (xy 97.649082 -388.654681)
			(xy 97.675732 -388.627515) (xy 97.707219 -388.606143) (xy 97.742304 -388.591406) (xy 97.779609 -388.583883)
			(xy 97.798636 -388.583424) (xy 97.799144 -388.583424) (xy 97.82062 -388.584035) (xy 97.862483 -388.593652)
			(xy 97.901154 -388.612349) (xy 97.91827 -388.625334) (xy 97.926398 -388.631938) (xy 97.946972 -388.637526)
			(xy 98.031554 -388.624826) (xy 98.041813 -388.622728) (xy 98.059512 -388.611576) (xy 98.065844 -388.603236)
			(xy 98.066098 -388.602982) (xy 98.080234 -388.583084) (xy 98.11365 -388.547514) (xy 98.152297 -388.517711)
			(xy 98.195192 -388.494432) (xy 98.241243 -388.478271) (xy 98.289277 -388.469639) (xy 98.338073 -388.468755)
			(xy 98.386389 -388.475641) (xy 98.432995 -388.490123) (xy 98.476705 -388.511833) (xy 98.516406 -388.540216)
			(xy 98.551089 -388.574552) (xy 98.579871 -388.613966) (xy 98.59137 -388.635494) (xy 98.591878 -388.636764)
			(xy 98.671418 -388.7744) (xy 114.179398 -388.7744) (xy 114.183582 -388.734589) (xy 114.195951 -388.696517)
			(xy 114.215964 -388.661849) (xy 114.242747 -388.632098) (xy 114.275129 -388.608566) (xy 114.311697 -388.592279)
			(xy 114.350851 -388.58395) (xy 114.370866 -388.583424) (xy 114.371374 -388.583424) (xy 114.392851 -388.58402)
			(xy 114.434715 -388.593644) (xy 114.473385 -388.612347) (xy 114.4905 -388.625334) (xy 114.498628 -388.631938)
			(xy 114.519202 -388.637526) (xy 114.603784 -388.624826) (xy 114.614034 -388.622695) (xy 114.631738 -388.611567)
			(xy 114.638074 -388.603236) (xy 114.638328 -388.602982) (xy 114.652424 -388.583054) (xy 114.685844 -388.547483)
			(xy 114.724496 -388.517679) (xy 114.767396 -388.494401) (xy 114.813451 -388.478241) (xy 114.86149 -388.469611)
			(xy 114.91029 -388.468729) (xy 114.95861 -388.475619) (xy 115.005219 -388.490104) (xy 115.048931 -388.511817)
			(xy 115.088635 -388.540205) (xy 115.123319 -388.574545) (xy 115.1521 -388.613964) (xy 115.1636 -388.635494)
			(xy 115.164108 -388.636764) (xy 115.21059 -388.717282) (xy 115.215681 -388.725358) (xy 115.230585 -388.737271)
			(xy 115.248798 -388.742955) (xy 115.258342 -388.742682) (xy 115.349782 -388.735824) (xy 115.359165 -388.734698)
			(xy 115.37622 -388.72659) (xy 115.389219 -388.712893) (xy 115.393216 -388.704328) (xy 115.393216 -388.70382)
			(xy 115.400663 -388.686338) (xy 115.421415 -388.654512) (xy 115.448038 -388.627405) (xy 115.479484 -388.606082)
			(xy 115.514519 -388.59138) (xy 115.551765 -388.583879) (xy 115.570762 -388.583424) (xy 115.57127 -388.583424)
			(xy 115.592747 -388.584022) (xy 115.63461 -388.593645) (xy 115.673281 -388.612347) (xy 115.690396 -388.625334)
			(xy 115.698524 -388.631938) (xy 115.719098 -388.637526) (xy 115.80368 -388.624826) (xy 115.813929 -388.622694)
			(xy 115.831633 -388.611567) (xy 115.83797 -388.603236) (xy 115.838224 -388.602982) (xy 115.852325 -388.583058)
			(xy 115.885745 -388.547487) (xy 115.924397 -388.517684) (xy 115.967295 -388.494405) (xy 116.01335 -388.478245)
			(xy 116.061388 -388.469614) (xy 116.110188 -388.468732) (xy 116.158507 -388.475622) (xy 116.205116 -388.490107)
			(xy 116.248828 -388.511819) (xy 116.288531 -388.540206) (xy 116.323215 -388.574546) (xy 116.351996 -388.613964)
			(xy 116.363496 -388.635494) (xy 116.364004 -388.636764) (xy 116.410486 -388.717282) (xy 116.41558 -388.725356)
			(xy 116.430482 -388.73727) (xy 116.448694 -388.742954) (xy 116.458238 -388.742682) (xy 116.549678 -388.735824)
			(xy 116.559061 -388.734695) (xy 116.576116 -388.726589) (xy 116.589115 -388.712892) (xy 116.593112 -388.704328)
			(xy 116.593112 -388.70382) (xy 116.600562 -388.686339) (xy 116.621314 -388.654513) (xy 116.647936 -388.627406)
			(xy 116.679382 -388.606083) (xy 116.714416 -388.591381) (xy 116.751661 -388.583879) (xy 116.770658 -388.583424)
			(xy 116.771166 -388.583424) (xy 116.792643 -388.584024) (xy 116.834506 -388.593646) (xy 116.873176 -388.612347)
			(xy 116.890292 -388.625334) (xy 116.89842 -388.631938) (xy 116.918994 -388.637526) (xy 117.003576 -388.624826)
			(xy 117.013825 -388.622692) (xy 117.031529 -388.611566) (xy 117.037866 -388.603236) (xy 117.03812 -388.602982)
			(xy 117.052226 -388.583062) (xy 117.085646 -388.547491) (xy 117.124297 -388.517688) (xy 117.167195 -388.49441)
			(xy 117.213249 -388.478249) (xy 117.261287 -388.469618) (xy 117.310086 -388.468736) (xy 117.358404 -388.475625)
			(xy 117.405012 -388.490109) (xy 117.448724 -388.511821) (xy 117.488427 -388.540208) (xy 117.523111 -388.574547)
			(xy 117.551893 -388.613964) (xy 117.563392 -388.635494) (xy 117.5639 -388.636764) (xy 117.610636 -388.717536)
			(xy 117.615777 -388.725576) (xy 117.630656 -388.737499) (xy 117.64885 -388.743199) (xy 117.658388 -388.742936)
			(xy 117.764052 -388.735062) (xy 117.787674 -388.71779) (xy 117.793008 -388.704074) (xy 117.800513 -388.686583)
			(xy 117.821273 -388.654693) (xy 117.847918 -388.627527) (xy 117.879401 -388.606153) (xy 117.914482 -388.591413)
			(xy 117.951782 -388.583885) (xy 117.970808 -388.583424) (xy 117.971316 -388.583424) (xy 117.992794 -388.583998)
			(xy 118.034659 -388.593631) (xy 118.073328 -388.612343) (xy 118.090442 -388.625334) (xy 118.09857 -388.631938)
			(xy 118.119144 -388.637526) (xy 118.203726 -388.624826) (xy 118.213981 -388.622715) (xy 118.231682 -388.611573)
			(xy 118.238016 -388.603236) (xy 118.23827 -388.602982) (xy 118.252309 -388.583012) (xy 118.285736 -388.54744)
			(xy 118.324395 -388.517636) (xy 118.367301 -388.494358) (xy 118.413363 -388.4782) (xy 118.461408 -388.469571)
			(xy 118.510214 -388.468693) (xy 118.558538 -388.475587) (xy 118.605152 -388.490077) (xy 118.648868 -388.511796)
			(xy 118.688574 -388.540189) (xy 118.72326 -388.574536) (xy 118.752042 -388.613961) (xy 118.763542 -388.635494)
			(xy 118.76405 -388.636764) (xy 118.810532 -388.717282) (xy 118.815662 -388.725329) (xy 118.830548 -388.737247)
			(xy 118.848745 -388.742945) (xy 118.858284 -388.742682) (xy 118.949724 -388.735824) (xy 118.959112 -388.734725)
			(xy 118.976167 -388.726605) (xy 118.989163 -388.712897) (xy 118.993158 -388.704328) (xy 118.993158 -388.70382)
			(xy 119.000651 -388.686359) (xy 119.021396 -388.654536) (xy 119.04801 -388.627428) (xy 119.079447 -388.606102)
			(xy 119.114472 -388.591395) (xy 119.15171 -388.583884) (xy 119.170704 -388.583424) (xy 119.171212 -388.583424)
			(xy 119.19269 -388.584) (xy 119.234554 -388.593632) (xy 119.273224 -388.612343) (xy 119.290338 -388.625334)
			(xy 119.298466 -388.631938) (xy 119.31904 -388.637526) (xy 119.403622 -388.624826) (xy 119.413877 -388.622713)
			(xy 119.431578 -388.611572) (xy 119.437912 -388.603236) (xy 119.438166 -388.602982) (xy 119.45221 -388.583016)
			(xy 119.485637 -388.547444) (xy 119.524295 -388.51764) (xy 119.567201 -388.494362) (xy 119.613262 -388.478204)
			(xy 119.661306 -388.469575) (xy 119.710112 -388.468696) (xy 119.758436 -388.47559) (xy 119.805049 -388.49008)
			(xy 119.848764 -388.511798) (xy 119.88847 -388.540191) (xy 119.923156 -388.574537) (xy 119.951938 -388.613961)
			(xy 119.963438 -388.635494) (xy 119.963946 -388.636764) (xy 120.010682 -388.717536) (xy 120.015792 -388.725599)
			(xy 120.030685 -388.737518) (xy 120.048892 -388.743207) (xy 120.058434 -388.742936) (xy 120.164098 -388.735062)
			(xy 120.18772 -388.71779) (xy 120.193054 -388.704074) (xy 120.200522 -388.686566) (xy 120.221288 -388.654674)
			(xy 120.247941 -388.627508) (xy 120.279431 -388.606137) (xy 120.314519 -388.591401) (xy 120.351826 -388.583881)
			(xy 120.370854 -388.583424) (xy 120.371362 -388.583424) (xy 120.392839 -388.584026) (xy 120.434702 -388.593647)
			(xy 120.473372 -388.612348) (xy 120.490488 -388.625334) (xy 120.498616 -388.631938) (xy 120.51919 -388.637526)
			(xy 120.603772 -388.624826) (xy 120.61402 -388.62269) (xy 120.631725 -388.611566) (xy 120.638062 -388.603236)
			(xy 120.638316 -388.602982) (xy 120.652428 -388.583066) (xy 120.685847 -388.547495) (xy 120.724497 -388.517692)
			(xy 120.767394 -388.494414) (xy 120.813448 -388.478253) (xy 120.861485 -388.469622) (xy 120.910284 -388.468739)
			(xy 120.958601 -388.475628) (xy 121.005209 -388.490112) (xy 121.048921 -388.511823) (xy 121.088623 -388.540209)
			(xy 121.123307 -388.574548) (xy 121.152089 -388.613965) (xy 121.163588 -388.635494) (xy 121.164096 -388.636764)
			(xy 121.210578 -388.717282) (xy 121.215677 -388.725352) (xy 121.230577 -388.737266) (xy 121.248787 -388.742953)
			(xy 121.25833 -388.742682) (xy 121.34977 -388.735824) (xy 121.359152 -388.734689) (xy 121.376207 -388.726586)
			(xy 121.389206 -388.712891) (xy 121.393204 -388.704328) (xy 121.393204 -388.70382) (xy 121.40066 -388.686342)
			(xy 121.421411 -388.654517) (xy 121.448032 -388.62741) (xy 121.479476 -388.606086) (xy 121.514509 -388.591383)
			(xy 121.551754 -388.58388) (xy 121.57075 -388.583424) (xy 121.571258 -388.583424) (xy 121.592734 -388.584028)
			(xy 121.634598 -388.593648) (xy 121.673268 -388.612348) (xy 121.690384 -388.625334) (xy 121.698512 -388.631938)
			(xy 121.719086 -388.637526) (xy 121.803668 -388.624826) (xy 121.813928 -388.622734) (xy 121.831627 -388.611578)
			(xy 121.837958 -388.603236) (xy 121.838212 -388.602982) (xy 121.852329 -388.58307) (xy 121.885748 -388.547499)
			(xy 121.924397 -388.517696) (xy 121.967294 -388.494418) (xy 122.013347 -388.478257) (xy 122.061383 -388.469626)
			(xy 122.110181 -388.468743) (xy 122.158499 -388.475631) (xy 122.205106 -388.490114) (xy 122.248817 -388.511825)
			(xy 122.28852 -388.540211) (xy 122.323203 -388.574549) (xy 122.351985 -388.613965) (xy 122.363484 -388.635494)
			(xy 122.363992 -388.636764) (xy 122.410474 -388.717282) (xy 122.415576 -388.72535) (xy 122.430474 -388.737265)
			(xy 122.448684 -388.742952) (xy 122.458226 -388.742682) (xy 122.549666 -388.735824) (xy 122.559048 -388.734687)
			(xy 122.576102 -388.726584) (xy 122.589102 -388.712891) (xy 122.5931 -388.704328) (xy 122.5931 -388.70382)
			(xy 122.600559 -388.686344) (xy 122.62131 -388.654518) (xy 122.64793 -388.627411) (xy 122.679374 -388.606087)
			(xy 122.714406 -388.591384) (xy 122.75165 -388.58388) (xy 122.770646 -388.583424) (xy 122.771154 -388.583424)
			(xy 122.79263 -388.58403) (xy 122.834494 -388.593649) (xy 122.873164 -388.612348) (xy 122.89028 -388.625334)
			(xy 122.898408 -388.631938) (xy 122.918982 -388.637526) (xy 123.003564 -388.624826) (xy 123.013824 -388.622733)
			(xy 123.031523 -388.611578) (xy 123.037854 -388.603236) (xy 123.038108 -388.602982) (xy 123.052231 -388.583074)
			(xy 123.085648 -388.547504) (xy 123.124297 -388.5177) (xy 123.167193 -388.494422) (xy 123.213246 -388.478261)
			(xy 123.261282 -388.469629) (xy 123.310079 -388.468746) (xy 123.358396 -388.475634) (xy 123.405003 -388.490117)
			(xy 123.448714 -388.511827) (xy 123.488416 -388.540212) (xy 123.523099 -388.57455) (xy 123.551881 -388.613965)
			(xy 123.56338 -388.635494) (xy 123.563888 -388.636764) (xy 123.610624 -388.717536) (xy 123.615773 -388.72557)
			(xy 123.630648 -388.737494) (xy 123.648839 -388.743197) (xy 123.658376 -388.742936) (xy 123.76404 -388.735062)
			(xy 123.787662 -388.71779) (xy 123.792996 -388.704074) (xy 123.80043 -388.68655) (xy 123.821202 -388.654657)
			(xy 123.847861 -388.627491) (xy 123.879358 -388.606122) (xy 123.914453 -388.591391) (xy 123.951765 -388.583877)
			(xy 123.970796 -388.583424) (xy 123.971304 -388.583424) (xy 123.992782 -388.584004) (xy 124.034646 -388.593635)
			(xy 124.073315 -388.612344) (xy 124.09043 -388.625334) (xy 124.098558 -388.631938) (xy 124.119132 -388.637526)
			(xy 124.203714 -388.624826) (xy 124.213967 -388.622709) (xy 124.231669 -388.611571) (xy 124.238004 -388.603236)
			(xy 124.238258 -388.602982) (xy 124.252313 -388.583024) (xy 124.285739 -388.547452) (xy 124.324395 -388.517648)
			(xy 124.3673 -388.49437) (xy 124.41336 -388.478212) (xy 124.461403 -388.469583) (xy 124.510207 -388.468703)
			(xy 124.55853 -388.475596) (xy 124.605142 -388.490085) (xy 124.648857 -388.511802) (xy 124.688563 -388.540194)
			(xy 124.723248 -388.574538) (xy 124.75203 -388.613962) (xy 124.76353 -388.635494) (xy 124.764038 -388.636764)
			(xy 124.81052 -388.717282) (xy 124.815658 -388.725323) (xy 124.83054 -388.737242) (xy 124.848734 -388.742943)
			(xy 124.858272 -388.742682) (xy 124.949712 -388.735824) (xy 124.959099 -388.734717) (xy 124.976153 -388.726601)
			(xy 124.98915 -388.712896) (xy 124.993146 -388.704328) (xy 124.993146 -388.70382) (xy 125.000568 -388.686326)
			(xy 125.021325 -388.654499) (xy 125.047952 -388.627393) (xy 125.079404 -388.606071) (xy 125.114443 -388.591373)
			(xy 125.151693 -388.583876) (xy 125.170692 -388.583424) (xy 125.1712 -388.583424) (xy 125.192678 -388.584006)
			(xy 125.234542 -388.593636) (xy 125.273211 -388.612344) (xy 125.290326 -388.625334) (xy 125.298454 -388.631938)
			(xy 125.319028 -388.637526) (xy 125.40361 -388.624826) (xy 125.413863 -388.622707) (xy 125.431565 -388.61157)
			(xy 125.4379 -388.603236) (xy 125.438154 -388.602982) (xy 125.452215 -388.583028) (xy 125.485639 -388.547456)
			(xy 125.524296 -388.517652) (xy 125.567199 -388.494375) (xy 125.613258 -388.478216) (xy 125.661301 -388.469586)
			(xy 125.710105 -388.468707) (xy 125.758427 -388.475599) (xy 125.805039 -388.490087) (xy 125.848754 -388.511804)
			(xy 125.888459 -388.540195) (xy 125.923144 -388.574539) (xy 125.951926 -388.613962) (xy 125.963426 -388.635494)
			(xy 125.963934 -388.636764) (xy 126.01067 -388.717536) (xy 126.015788 -388.725593) (xy 126.030677 -388.737513)
			(xy 126.048881 -388.743205) (xy 126.058422 -388.742936) (xy 126.164086 -388.735062) (xy 126.187708 -388.71779)
			(xy 126.193042 -388.704074) (xy 126.20052 -388.68657) (xy 126.221284 -388.654679) (xy 126.247935 -388.627513)
			(xy 126.279423 -388.606141) (xy 126.314509 -388.591404) (xy 126.351814 -388.583882) (xy 126.370842 -388.583424)
			(xy 126.37135 -388.583424) (xy 126.392826 -388.584032) (xy 126.434689 -388.593651) (xy 126.47336 -388.612349)
			(xy 126.490476 -388.625334) (xy 126.498604 -388.631938) (xy 126.519178 -388.637526) (xy 126.60376 -388.624826)
			(xy 126.614019 -388.622731) (xy 126.631718 -388.611577) (xy 126.63805 -388.603236) (xy 126.638304 -388.602982)
			(xy 126.652432 -388.583078) (xy 126.685849 -388.547508) (xy 126.724497 -388.517704) (xy 126.767393 -388.494426)
			(xy 126.813444 -388.478265) (xy 126.86148 -388.469633) (xy 126.910277 -388.46875) (xy 126.958593 -388.475637)
			(xy 127.0052 -388.49012) (xy 127.04891 -388.51183) (xy 127.088612 -388.540214) (xy 127.123295 -388.574551)
			(xy 127.152077 -388.613966) (xy 127.163576 -388.635494) (xy 127.164084 -388.636764) (xy 127.210566 -388.717282)
			(xy 127.215673 -388.725346) (xy 127.230569 -388.737261) (xy 127.248776 -388.742951) (xy 127.258318 -388.742682)
			(xy 127.349758 -388.735824) (xy 127.359139 -388.734681) (xy 127.376193 -388.726582) (xy 127.389194 -388.71289)
			(xy 127.393192 -388.704328) (xy 127.393192 -388.70382) (xy 127.400658 -388.686347) (xy 127.421407 -388.654522)
			(xy 127.448026 -388.627414) (xy 127.479469 -388.60609) (xy 127.514499 -388.591386) (xy 127.551742 -388.583881)
			(xy 127.570738 -388.583424) (xy 127.571246 -388.583424) (xy 127.592722 -388.584034) (xy 127.634585 -388.593652)
			(xy 127.673256 -388.612349) (xy 127.690372 -388.625334) (xy 127.6985 -388.631938) (xy 127.719074 -388.637526)
			(xy 127.803656 -388.624826) (xy 127.813915 -388.622729) (xy 127.831614 -388.611577) (xy 127.837946 -388.603236)
			(xy 127.8382 -388.602982) (xy 127.852333 -388.583082) (xy 127.88575 -388.547512) (xy 127.924397 -388.517709)
			(xy 127.967292 -388.49443) (xy 128.013343 -388.478269) (xy 128.061378 -388.469637) (xy 128.110175 -388.468753)
			(xy 128.158491 -388.47564) (xy 128.205097 -388.490122) (xy 128.248807 -388.511832) (xy 128.288508 -388.540215)
			(xy 128.323191 -388.574552) (xy 128.351973 -388.613966) (xy 128.363472 -388.635494) (xy 128.36398 -388.636764)
			(xy 128.410462 -388.717282) (xy 128.415572 -388.725344) (xy 128.430467 -388.73726) (xy 128.448673 -388.74295)
			(xy 128.458214 -388.742682) (xy 128.549654 -388.735824) (xy 128.559034 -388.734679) (xy 128.576089 -388.72658)
			(xy 128.58909 -388.71289) (xy 128.593088 -388.704328) (xy 128.593088 -388.70382) (xy 128.600557 -388.686348)
			(xy 128.621306 -388.654523) (xy 128.647924 -388.627416) (xy 128.679366 -388.606092) (xy 128.714396 -388.591387)
			(xy 128.751639 -388.583881) (xy 128.770634 -388.583424) (xy 128.771142 -388.583424) (xy 128.792618 -388.584036)
			(xy 128.834481 -388.593653) (xy 128.873152 -388.61235) (xy 128.890268 -388.625334) (xy 128.898396 -388.631938)
			(xy 128.91897 -388.637526) (xy 129.003552 -388.624826) (xy 129.01381 -388.622727) (xy 129.03151 -388.611576)
			(xy 129.037842 -388.603236) (xy 129.038096 -388.602982) (xy 129.0521 -388.582986) (xy 129.085531 -388.547413)
			(xy 129.124194 -388.517609) (xy 129.167104 -388.494331) (xy 129.21317 -388.478174) (xy 129.261219 -388.469547)
			(xy 129.310029 -388.468671) (xy 129.358356 -388.475567) (xy 129.404972 -388.49006) (xy 129.44869 -388.511782)
			(xy 129.488398 -388.540179) (xy 129.523085 -388.57453) (xy 129.551868 -388.613959) (xy 129.563368 -388.635494)
			(xy 129.563876 -388.636764) (xy 129.610612 -388.717536) (xy 129.615702 -388.725613) (xy 129.630604 -388.737531)
			(xy 129.64882 -388.743213) (xy 129.658364 -388.742936) (xy 129.764028 -388.735062) (xy 129.78765 -388.71779)
			(xy 129.792984 -388.704074) (xy 129.800428 -388.686555) (xy 129.821198 -388.654662) (xy 129.847855 -388.627496)
			(xy 129.87935 -388.606126) (xy 129.914443 -388.591394) (xy 129.951754 -388.583878) (xy 129.970784 -388.583424)
			(xy 129.971292 -388.583424) (xy 129.99277 -388.58401) (xy 130.034633 -388.593638) (xy 130.073303 -388.612345)
			(xy 130.090418 -388.625334) (xy 130.098546 -388.631938) (xy 130.11912 -388.637526) (xy 130.203702 -388.624826)
			(xy 130.213954 -388.622704) (xy 130.231657 -388.611569) (xy 130.237992 -388.603236) (xy 130.238246 -388.602982)
			(xy 130.252317 -388.583036) (xy 130.285741 -388.547464) (xy 130.324396 -388.517661) (xy 130.367298 -388.494383)
			(xy 130.413356 -388.478223) (xy 130.461398 -388.469594) (xy 130.5102 -388.468713) (xy 130.558522 -388.475605)
			(xy 130.605133 -388.490093) (xy 130.648847 -388.511808) (xy 130.688551 -388.540198) (xy 130.723236 -388.574541)
			(xy 130.752018 -388.613962) (xy 130.763518 -388.635494) (xy 130.764026 -388.636764) (xy 130.810508 -388.717282)
			(xy 130.815587 -388.725367) (xy 130.830496 -388.737279) (xy 130.848714 -388.742958) (xy 130.85826 -388.742682)
			(xy 130.9497 -388.735824) (xy 130.959085 -388.73471) (xy 130.97614 -388.726596) (xy 130.989138 -388.712894)
			(xy 130.993134 -388.704328) (xy 130.993134 -388.70382) (xy 131.000566 -388.686331) (xy 131.021321 -388.654504)
			(xy 131.047947 -388.627397) (xy 131.079396 -388.606075) (xy 131.114433 -388.591376) (xy 131.151682 -388.583877)
			(xy 131.17068 -388.583424) (xy 131.171188 -388.583424) (xy 131.192665 -388.584013) (xy 131.234529 -388.593639)
			(xy 131.273199 -388.612345) (xy 131.290314 -388.625334) (xy 131.298442 -388.631938) (xy 131.319016 -388.637526)
			(xy 131.403598 -388.624826) (xy 131.413849 -388.622702) (xy 131.431552 -388.611569) (xy 131.437888 -388.603236)
			(xy 131.438142 -388.602982) (xy 131.452219 -388.58304) (xy 131.485642 -388.547469) (xy 131.524296 -388.517665)
			(xy 131.567198 -388.494387) (xy 131.613255 -388.478227) (xy 131.661296 -388.469598) (xy 131.710098 -388.468717)
			(xy 131.758419 -388.475608) (xy 131.80503 -388.490095) (xy 131.848743 -388.51181) (xy 131.888448 -388.5402)
			(xy 131.923132 -388.574542) (xy 131.951914 -388.613963) (xy 131.963414 -388.635494) (xy 131.963922 -388.636764)
			(xy 132.010658 -388.717536) (xy 132.015784 -388.725587) (xy 132.03067 -388.737508) (xy 132.04887 -388.743203)
			(xy 132.05841 -388.742936) (xy 132.164074 -388.735062) (xy 132.187696 -388.71779) (xy 132.19303 -388.704074)
			(xy 132.200517 -388.686575) (xy 132.22128 -388.654684) (xy 132.247929 -388.627518) (xy 132.279415 -388.606145)
			(xy 132.3145 -388.591407) (xy 132.351803 -388.583883) (xy 132.37083 -388.583424) (xy 132.371338 -388.583424)
			(xy 132.392814 -388.584038) (xy 132.434677 -388.593654) (xy 132.473348 -388.61235) (xy 132.490464 -388.625334)
			(xy 132.498592 -388.631938) (xy 132.519166 -388.637526) (xy 132.603748 -388.624826) (xy 132.614006 -388.622725)
			(xy 132.631706 -388.611576) (xy 132.638038 -388.603236) (xy 132.638292 -388.602982) (xy 132.652301 -388.58299)
			(xy 132.685732 -388.547417) (xy 132.724394 -388.517613) (xy 132.767304 -388.494335) (xy 132.813369 -388.478178)
			(xy 132.861417 -388.469551) (xy 132.910226 -388.468674) (xy 132.958553 -388.47557) (xy 133.005169 -388.490063)
			(xy 133.048887 -388.511784) (xy 133.088595 -388.540181) (xy 133.123281 -388.574531) (xy 133.152064 -388.613959)
			(xy 133.163564 -388.635494) (xy 133.164072 -388.636764) (xy 133.243612 -388.7744) (xy 146.707061 -388.7744)
			(xy 146.711247 -388.734575) (xy 146.723622 -388.696491) (xy 146.743645 -388.661812) (xy 146.770441 -388.632054)
			(xy 146.802839 -388.608518) (xy 146.839422 -388.592232) (xy 146.878592 -388.583909) (xy 146.898614 -388.583424)
			(xy 146.899122 -388.583424) (xy 146.9206 -388.583995) (xy 146.962465 -388.59363) (xy 147.001134 -388.612342)
			(xy 147.018248 -388.625334) (xy 147.026376 -388.631938) (xy 147.04695 -388.637526) (xy 147.131532 -388.624826)
			(xy 147.141788 -388.622718) (xy 147.159489 -388.611574) (xy 147.165822 -388.603236) (xy 147.166076 -388.602982)
			(xy 147.180107 -388.583006) (xy 147.213535 -388.547434) (xy 147.252195 -388.517629) (xy 147.295102 -388.494352)
			(xy 147.341165 -388.478194) (xy 147.389211 -388.469566) (xy 147.438017 -388.468688) (xy 147.486342 -388.475582)
			(xy 147.532956 -388.490073) (xy 147.576673 -388.511792) (xy 147.61638 -388.540187) (xy 147.651066 -388.574534)
			(xy 147.679848 -388.61396) (xy 147.691348 -388.635494) (xy 147.691856 -388.636764) (xy 147.738338 -388.717282)
			(xy 147.743464 -388.725332) (xy 147.758352 -388.73725) (xy 147.776551 -388.742946) (xy 147.78609 -388.742682)
			(xy 147.87753 -388.735824) (xy 147.886919 -388.734729) (xy 147.903973 -388.726607) (xy 147.916969 -388.712897)
			(xy 147.920964 -388.704328) (xy 147.920964 -388.70382) (xy 147.928452 -388.686357) (xy 147.949198 -388.654533)
			(xy 147.975812 -388.627426) (xy 148.00725 -388.6061) (xy 148.042277 -388.591393) (xy 148.079516 -388.583883)
			(xy 148.09851 -388.583424) (xy 148.099018 -388.583424) (xy 148.120496 -388.583997) (xy 148.162361 -388.593631)
			(xy 148.20103 -388.612343) (xy 148.218144 -388.625334) (xy 148.226272 -388.631938) (xy 148.246846 -388.637526)
			(xy 148.331428 -388.624826) (xy 148.341683 -388.622716) (xy 148.359385 -388.611573) (xy 148.365718 -388.603236)
			(xy 148.365972 -388.602982) (xy 148.380008 -388.58301) (xy 148.413436 -388.547438) (xy 148.452095 -388.517634)
			(xy 148.495001 -388.494356) (xy 148.541064 -388.478198) (xy 148.589109 -388.469569) (xy 148.637915 -388.468691)
			(xy 148.68624 -388.475585) (xy 148.732853 -388.490076) (xy 148.77657 -388.511794) (xy 148.816276 -388.540188)
			(xy 148.850962 -388.574535) (xy 148.879744 -388.613961) (xy 148.891244 -388.635494) (xy 148.891752 -388.636764)
			(xy 148.938234 -388.717282) (xy 148.943363 -388.72533) (xy 148.958249 -388.737248) (xy 148.976447 -388.742945)
			(xy 148.985986 -388.742682) (xy 149.077426 -388.735824) (xy 149.086814 -388.734727) (xy 149.103869 -388.726605)
			(xy 149.116865 -388.712897) (xy 149.12086 -388.704328) (xy 149.12086 -388.70382) (xy 149.128352 -388.686359)
			(xy 149.149097 -388.654535) (xy 149.17571 -388.627427) (xy 149.207148 -388.606101) (xy 149.242174 -388.591394)
			(xy 149.279412 -388.583884) (xy 149.298406 -388.583424) (xy 149.316267 -388.58388) (xy 149.351366 -388.590522)
			(xy 149.384626 -388.603555) (xy 149.414894 -388.622528) (xy 149.441119 -388.646783) (xy 149.452076 -388.660894)
			(xy 149.458315 -388.668528) (xy 149.475115 -388.678805) (xy 149.494548 -388.681999) (xy 149.513753 -388.677639)
			(xy 149.529902 -388.666368) (xy 149.535642 -388.658354) (xy 149.539452 -388.650988) (xy 149.549358 -388.630668)
			(xy 149.561087 -388.609816) (xy 149.589876 -388.571614) (xy 149.624267 -388.538365) (xy 149.663419 -388.510882)
			(xy 149.706377 -388.489837) (xy 149.752089 -388.475745) (xy 149.79944 -388.468949) (xy 149.84727 -388.469617)
			(xy 149.894413 -388.477731) (xy 149.939714 -388.493093) (xy 149.982068 -388.515327) (xy 150.020439 -388.543891)
			(xy 150.053889 -388.578087) (xy 150.081601 -388.617078) (xy 150.092664 -388.638288) (xy 150.093426 -388.639812)
			(xy 150.138384 -388.717536) (xy 150.143493 -388.7256) (xy 150.158386 -388.737519) (xy 150.176594 -388.743208)
			(xy 150.186136 -388.742936) (xy 150.2918 -388.735062) (xy 150.315422 -388.71779) (xy 150.320756 -388.704074)
			(xy 150.328222 -388.686565) (xy 150.348989 -388.654673) (xy 150.375642 -388.627507) (xy 150.407132 -388.606136)
			(xy 150.442221 -388.591401) (xy 150.479527 -388.583881) (xy 150.498556 -388.583424) (xy 150.499064 -388.583424)
			(xy 150.520541 -388.584025) (xy 150.562404 -388.593647) (xy 150.601074 -388.612348) (xy 150.61819 -388.625334)
			(xy 150.626318 -388.631938) (xy 150.646892 -388.637526) (xy 150.731474 -388.624826) (xy 150.741722 -388.622691)
			(xy 150.759427 -388.611566) (xy 150.765764 -388.603236) (xy 150.766018 -388.602982) (xy 150.780127 -388.583064)
			(xy 150.813546 -388.547493) (xy 150.852197 -388.51769) (xy 150.895095 -388.494412) (xy 150.941148 -388.478251)
			(xy 150.989186 -388.46962) (xy 151.037985 -388.468738) (xy 151.086303 -388.475626) (xy 151.132911 -388.490111)
			(xy 151.176622 -388.511822) (xy 151.216325 -388.540209) (xy 151.251009 -388.574547) (xy 151.279791 -388.613965)
			(xy 151.29129 -388.635494) (xy 151.291798 -388.636764) (xy 151.33828 -388.717282) (xy 151.343378 -388.725353)
			(xy 151.358278 -388.737267) (xy 151.376489 -388.742953) (xy 151.386032 -388.742682) (xy 151.477472 -388.735824)
			(xy 151.486854 -388.734691) (xy 151.503909 -388.726587) (xy 151.516908 -388.712892) (xy 151.520906 -388.704328)
			(xy 151.520906 -388.70382) (xy 151.528361 -388.686341) (xy 151.549112 -388.654516) (xy 151.575733 -388.627409)
			(xy 151.607178 -388.606085) (xy 151.642211 -388.591383) (xy 151.679456 -388.583879) (xy 151.698452 -388.583424)
			(xy 151.69896 -388.583424) (xy 151.720437 -388.584027) (xy 151.7623 -388.593648) (xy 151.80097 -388.612348)
			(xy 151.818086 -388.625334) (xy 151.826214 -388.631938) (xy 151.846788 -388.637526) (xy 151.93137 -388.624826)
			(xy 151.941631 -388.622735) (xy 151.959329 -388.611578) (xy 151.96566 -388.603236) (xy 151.965914 -388.602982)
			(xy 151.980029 -388.583068) (xy 152.013447 -388.547497) (xy 152.052097 -388.517694) (xy 152.094994 -388.494416)
			(xy 152.141047 -388.478255) (xy 152.189084 -388.469624) (xy 152.237882 -388.468741) (xy 152.2862 -388.475629)
			(xy 152.332808 -388.490113) (xy 152.376519 -388.511824) (xy 152.416221 -388.54021) (xy 152.450905 -388.574548)
			(xy 152.479687 -388.613965) (xy 152.491186 -388.635494) (xy 152.491694 -388.636764) (xy 152.53843 -388.717536)
			(xy 152.543575 -388.725573) (xy 152.558452 -388.737497) (xy 152.576645 -388.743198) (xy 152.586182 -388.742936)
			(xy 152.691846 -388.735062) (xy 152.715468 -388.71779) (xy 152.720802 -388.704074) (xy 152.728231 -388.686548)
			(xy 152.749004 -388.654654) (xy 152.775664 -388.627489) (xy 152.807162 -388.60612) (xy 152.842258 -388.591389)
			(xy 152.879571 -388.583876) (xy 152.898602 -388.583424) (xy 152.89911 -388.583424) (xy 152.920588 -388.584001)
			(xy 152.962452 -388.593633) (xy 153.001122 -388.612343) (xy 153.018236 -388.625334) (xy 153.026364 -388.631938)
			(xy 153.046938 -388.637526) (xy 153.13152 -388.624826) (xy 153.141774 -388.622712) (xy 153.159476 -388.611572)
			(xy 153.16581 -388.603236) (xy 153.166064 -388.602982) (xy 153.180111 -388.583018) (xy 153.213538 -388.547446)
			(xy 153.252195 -388.517642) (xy 153.2951 -388.494364) (xy 153.341161 -388.478206) (xy 153.389206 -388.469577)
			(xy 153.438011 -388.468698) (xy 153.486334 -388.475591) (xy 153.532947 -388.490081) (xy 153.576663 -388.511799)
			(xy 153.616368 -388.540191) (xy 153.651054 -388.574537) (xy 153.679836 -388.613961) (xy 153.691336 -388.635494)
			(xy 153.691844 -388.636764) (xy 153.738326 -388.717282) (xy 153.74346 -388.725326) (xy 153.758344 -388.737245)
			(xy 153.77654 -388.742944) (xy 153.786078 -388.742682) (xy 153.877518 -388.735824) (xy 153.886905 -388.734721)
			(xy 153.90396 -388.726603) (xy 153.916957 -388.712896) (xy 153.920952 -388.704328) (xy 153.920952 -388.70382)
			(xy 153.92845 -388.686362) (xy 153.949194 -388.654538) (xy 153.975807 -388.627431) (xy 154.007243 -388.606104)
			(xy 154.042267 -388.591396) (xy 154.079505 -388.583885) (xy 154.098498 -388.583424) (xy 154.099006 -388.583424)
			(xy 154.120484 -388.584003) (xy 154.162348 -388.593634) (xy 154.201018 -388.612344) (xy 154.218132 -388.625334)
			(xy 154.22626 -388.631938) (xy 154.246834 -388.637526) (xy 154.331416 -388.624826) (xy 154.34167 -388.62271)
			(xy 154.359371 -388.611571) (xy 154.365706 -388.603236) (xy 154.36596 -388.602982) (xy 154.380013 -388.583022)
			(xy 154.413438 -388.54745) (xy 154.452095 -388.517646) (xy 154.495 -388.494368) (xy 154.54106 -388.47821)
			(xy 154.589104 -388.469581) (xy 154.637908 -388.468701) (xy 154.686232 -388.475594) (xy 154.732844 -388.490084)
			(xy 154.776559 -388.511801) (xy 154.816265 -388.540193) (xy 154.85095 -388.574538) (xy 154.879732 -388.613961)
			(xy 154.891232 -388.635494) (xy 154.89174 -388.636764) (xy 154.938222 -388.717282) (xy 154.943359 -388.725324)
			(xy 154.958241 -388.737243) (xy 154.976436 -388.742943) (xy 154.985974 -388.742682) (xy 155.077414 -388.735824)
			(xy 155.086801 -388.734719) (xy 155.103856 -388.726601) (xy 155.116852 -388.712896) (xy 155.120848 -388.704328)
			(xy 155.120848 -388.70382) (xy 155.128269 -388.686326) (xy 155.149026 -388.654499) (xy 155.175653 -388.627392)
			(xy 155.207105 -388.60607) (xy 155.242145 -388.591372) (xy 155.279395 -388.583876) (xy 155.298394 -388.583424)
			(xy 155.316258 -388.583818) (xy 155.35136 -388.590475) (xy 155.384621 -388.603523) (xy 155.414887 -388.62251)
			(xy 155.441109 -388.646777) (xy 155.452064 -388.660894) (xy 155.458317 -388.668515) (xy 155.475112 -388.678792)
			(xy 155.49454 -388.681988) (xy 155.513742 -388.677632) (xy 155.52989 -388.666365) (xy 155.53563 -388.658354)
			(xy 155.53944 -388.650988) (xy 155.549346 -388.630668) (xy 155.560943 -388.609739) (xy 155.589744 -388.571531)
			(xy 155.624148 -388.538278) (xy 155.663314 -388.510793) (xy 155.706286 -388.489749) (xy 155.752012 -388.475659)
			(xy 155.799375 -388.468868) (xy 155.847218 -388.469542) (xy 155.894371 -388.477664) (xy 155.939682 -388.493036)
			(xy 155.982044 -388.515282) (xy 156.020421 -388.543858) (xy 156.053875 -388.578067) (xy 156.081588 -388.617071)
			(xy 156.092652 -388.638288) (xy 156.093414 -388.639812) (xy 156.138372 -388.717536) (xy 156.143489 -388.725594)
			(xy 156.158379 -388.737514) (xy 156.176583 -388.743205) (xy 156.186124 -388.742936) (xy 156.291788 -388.735062)
			(xy 156.31541 -388.71779) (xy 156.320744 -388.704074) (xy 156.32822 -388.68657) (xy 156.348985 -388.654678)
			(xy 156.375636 -388.627512) (xy 156.407124 -388.60614) (xy 156.442211 -388.591404) (xy 156.479516 -388.583882)
			(xy 156.498544 -388.583424) (xy 156.499052 -388.583424) (xy 156.520528 -388.584031) (xy 156.562391 -388.59365)
			(xy 156.601062 -388.612349) (xy 156.618178 -388.625334) (xy 156.626306 -388.631938) (xy 156.64688 -388.637526)
			(xy 156.731462 -388.624826) (xy 156.741722 -388.622732) (xy 156.759421 -388.611577) (xy 156.765752 -388.603236)
			(xy 156.766006 -388.602982) (xy 156.780131 -388.583076) (xy 156.813549 -388.547506) (xy 156.852197 -388.517702)
			(xy 156.895093 -388.494424) (xy 156.941145 -388.478263) (xy 156.989181 -388.469631) (xy 157.037978 -388.468748)
			(xy 157.086295 -388.475635) (xy 157.132901 -388.490118) (xy 157.176612 -388.511828) (xy 157.216314 -388.540213)
			(xy 157.250997 -388.57455) (xy 157.279779 -388.613966) (xy 157.291278 -388.635494) (xy 157.291786 -388.636764)
			(xy 157.338268 -388.717282) (xy 157.343374 -388.725347) (xy 157.358271 -388.737262) (xy 157.376478 -388.742951)
			(xy 157.38602 -388.742682) (xy 157.47746 -388.735824) (xy 157.486841 -388.734683) (xy 157.503896 -388.726582)
			(xy 157.516896 -388.71289) (xy 157.520894 -388.704328) (xy 157.520894 -388.70382) (xy 157.528358 -388.686346)
			(xy 157.549108 -388.654521) (xy 157.575727 -388.627414) (xy 157.60717 -388.606089) (xy 157.642201 -388.591386)
			(xy 157.679444 -388.583881) (xy 157.69844 -388.583424) (xy 157.698948 -388.583424) (xy 157.720424 -388.584033)
			(xy 157.762287 -388.593651) (xy 157.800958 -388.612349) (xy 157.818074 -388.625334) (xy 157.826202 -388.631938)
			(xy 157.846776 -388.637526) (xy 157.931358 -388.624826) (xy 157.941617 -388.62273) (xy 157.959316 -388.611577)
			(xy 157.965648 -388.603236) (xy 157.965902 -388.602982) (xy 157.980033 -388.58308) (xy 158.013449 -388.54751)
			(xy 158.052097 -388.517706) (xy 158.094993 -388.494428) (xy 158.141044 -388.478267) (xy 158.189079 -388.469635)
			(xy 158.237876 -388.468751) (xy 158.286192 -388.475638) (xy 158.332798 -388.490121) (xy 158.376508 -388.511831)
			(xy 158.41621 -388.540215) (xy 158.450893 -388.574551) (xy 158.479675 -388.613966) (xy 158.491174 -388.635494)
			(xy 158.491682 -388.636764) (xy 158.538418 -388.717536) (xy 158.543504 -388.725616) (xy 158.558408 -388.737533)
			(xy 158.576625 -388.743214) (xy 158.58617 -388.742936) (xy 158.691834 -388.735062) (xy 158.715456 -388.71779)
			(xy 158.72079 -388.704074) (xy 158.728229 -388.686552) (xy 158.749 -388.654659) (xy 158.775658 -388.627493)
			(xy 158.807154 -388.606124) (xy 158.842248 -388.591392) (xy 158.87956 -388.583878) (xy 158.89859 -388.583424)
			(xy 158.899098 -388.583424) (xy 158.920576 -388.584007) (xy 158.96244 -388.593637) (xy 159.001109 -388.612344)
			(xy 159.018224 -388.625334) (xy 159.026352 -388.631938) (xy 159.046926 -388.637526) (xy 159.131508 -388.624826)
			(xy 159.141761 -388.622706) (xy 159.159463 -388.61157) (xy 159.165798 -388.603236) (xy 159.166052 -388.602982)
			(xy 159.180115 -388.58303) (xy 159.21354 -388.547458) (xy 159.252196 -388.517654) (xy 159.295099 -388.494377)
			(xy 159.341158 -388.478218) (xy 159.3892 -388.469588) (xy 159.438004 -388.468708) (xy 159.486326 -388.4756)
			(xy 159.532938 -388.490089) (xy 159.576652 -388.511805) (xy 159.616357 -388.540196) (xy 159.651042 -388.57454)
			(xy 159.679824 -388.613962) (xy 159.691324 -388.635494) (xy 159.691832 -388.636764) (xy 159.738314 -388.717282)
			(xy 159.743389 -388.72537) (xy 159.7583 -388.737281) (xy 159.77652 -388.742959) (xy 159.786066 -388.742682)
			(xy 159.877506 -388.735824) (xy 159.886892 -388.734714) (xy 159.903947 -388.726598) (xy 159.916944 -388.712895)
			(xy 159.92094 -388.704328) (xy 159.92094 -388.70382) (xy 159.928367 -388.686329) (xy 159.949123 -388.654502)
			(xy 159.975749 -388.627395) (xy 160.0072 -388.606073) (xy 160.042238 -388.591374) (xy 160.079488 -388.583876)
			(xy 160.098486 -388.583424) (xy 160.098994 -388.583424) (xy 160.120472 -388.584009) (xy 160.162336 -388.593638)
			(xy 160.201005 -388.612345) (xy 160.21812 -388.625334) (xy 160.226248 -388.631938) (xy 160.246822 -388.637526)
			(xy 160.331404 -388.624826) (xy 160.341656 -388.622705) (xy 160.359359 -388.61157) (xy 160.365694 -388.603236)
			(xy 160.365948 -388.602982) (xy 160.380017 -388.583034) (xy 160.413441 -388.547462) (xy 160.452096 -388.517659)
			(xy 160.494998 -388.494381) (xy 160.541057 -388.478221) (xy 160.589099 -388.469592) (xy 160.637902 -388.468712)
			(xy 160.686223 -388.475603) (xy 160.732834 -388.490091) (xy 160.776549 -388.511807) (xy 160.816253 -388.540197)
			(xy 160.850938 -388.574541) (xy 160.87972 -388.613962) (xy 160.89122 -388.635494) (xy 160.891728 -388.636764)
			(xy 160.93821 -388.717282) (xy 160.943288 -388.725368) (xy 160.958197 -388.73728) (xy 160.976416 -388.742959)
			(xy 160.985962 -388.742682) (xy 161.077402 -388.735824) (xy 161.086788 -388.734711) (xy 161.103842 -388.726597)
			(xy 161.11684 -388.712895) (xy 161.120836 -388.704328) (xy 161.120836 -388.70382) (xy 161.128266 -388.68633)
			(xy 161.149022 -388.654504) (xy 161.175648 -388.627397) (xy 161.207097 -388.606075) (xy 161.242135 -388.591375)
			(xy 161.279384 -388.583877) (xy 161.298382 -388.583424) (xy 161.316245 -388.583826) (xy 161.351348 -388.590482)
			(xy 161.384608 -388.603528) (xy 161.414874 -388.622513) (xy 161.441097 -388.646778) (xy 161.452052 -388.660894)
			(xy 161.458319 -388.668503) (xy 161.475109 -388.678781) (xy 161.494533 -388.681978) (xy 161.513732 -388.677626)
			(xy 161.529878 -388.666363) (xy 161.535618 -388.658354) (xy 161.539428 -388.650988) (xy 161.549334 -388.630668)
			(xy 161.560949 -388.60975) (xy 161.589748 -388.571542) (xy 161.624151 -388.53829) (xy 161.663315 -388.510806)
			(xy 161.706285 -388.489761) (xy 161.752009 -388.475671) (xy 161.79937 -388.468879) (xy 161.847211 -388.469552)
			(xy 161.894363 -388.477673) (xy 161.939673 -388.493044) (xy 161.982033 -388.515288) (xy 162.020409 -388.543863)
			(xy 162.053863 -388.578069) (xy 162.081577 -388.617072) (xy 162.09264 -388.638288) (xy 162.093402 -388.639812)
			(xy 162.13836 -388.717536) (xy 162.143485 -388.725588) (xy 162.158371 -388.737509) (xy 162.176572 -388.743203)
			(xy 162.186112 -388.742936) (xy 162.291776 -388.735062) (xy 162.315398 -388.71779) (xy 162.320732 -388.704074)
			(xy 162.328218 -388.686574) (xy 162.348981 -388.654683) (xy 162.37563 -388.627517) (xy 162.407116 -388.606145)
			(xy 162.442201 -388.591407) (xy 162.479505 -388.583883) (xy 162.498532 -388.583424) (xy 162.49904 -388.583424)
			(xy 162.520516 -388.584037) (xy 162.562379 -388.593654) (xy 162.60105 -388.61235) (xy 162.618166 -388.625334)
			(xy 162.626294 -388.631938) (xy 162.646868 -388.637526) (xy 162.73145 -388.624826) (xy 162.741708 -388.622726)
			(xy 162.759408 -388.611576) (xy 162.76574 -388.603236) (xy 162.765994 -388.602982) (xy 162.780001 -388.582988)
			(xy 162.813432 -388.547415) (xy 162.852094 -388.517611) (xy 162.895004 -388.494333) (xy 162.94107 -388.478176)
			(xy 162.989118 -388.469549) (xy 163.037927 -388.468672) (xy 163.086255 -388.475568) (xy 163.132871 -388.490062)
			(xy 163.176589 -388.511783) (xy 163.216296 -388.54018) (xy 163.250983 -388.57453) (xy 163.279766 -388.613959)
			(xy 163.291266 -388.635494) (xy 163.291774 -388.636764) (xy 163.338256 -388.717282) (xy 163.34337 -388.725341)
			(xy 163.358263 -388.737257) (xy 163.376467 -388.742949) (xy 163.386008 -388.742682) (xy 163.477448 -388.735824)
			(xy 163.486828 -388.734675) (xy 163.503882 -388.726578) (xy 163.516883 -388.712889) (xy 163.520882 -388.704328)
			(xy 163.520882 -388.70382) (xy 163.528356 -388.68635) (xy 163.549104 -388.654526) (xy 163.575721 -388.627419)
			(xy 163.607162 -388.606094) (xy 163.642191 -388.591389) (xy 163.679433 -388.583882) (xy 163.698428 -388.583424)
			(xy 163.71629 -388.583865) (xy 163.75139 -388.59051) (xy 163.78465 -388.603547) (xy 163.814917 -388.622523)
			(xy 163.841142 -388.646781) (xy 163.852098 -388.660894) (xy 163.858312 -388.66855) (xy 163.87512 -388.678827)
			(xy 163.894561 -388.682017) (xy 163.913772 -388.677651) (xy 163.929924 -388.666372) (xy 163.935664 -388.658354)
			(xy 163.939474 -388.650988) (xy 163.94938 -388.630668) (xy 163.961076 -388.609797) (xy 163.989868 -388.571593)
			(xy 164.024262 -388.538343) (xy 164.063418 -388.51086) (xy 164.106379 -388.489815) (xy 164.152095 -388.475724)
			(xy 164.199449 -388.468929) (xy 164.247282 -388.469598) (xy 164.294427 -388.477714) (xy 164.339731 -388.493078)
			(xy 164.382087 -388.515316) (xy 164.420459 -388.543883) (xy 164.45391 -388.578082) (xy 164.481623 -388.617076)
			(xy 164.492686 -388.638288) (xy 164.493448 -388.639812) (xy 164.538406 -388.717536) (xy 164.5435 -388.72561)
			(xy 164.5584 -388.737528) (xy 164.576614 -388.743211) (xy 164.586158 -388.742936) (xy 164.691822 -388.735062)
			(xy 164.715444 -388.71779) (xy 164.720778 -388.704074) (xy 164.728227 -388.686557) (xy 164.748996 -388.654664)
			(xy 164.775652 -388.627498) (xy 164.807146 -388.606128) (xy 164.842238 -388.591395) (xy 164.879548 -388.583879)
			(xy 164.898578 -388.583424) (xy 164.899086 -388.583424) (xy 164.920563 -388.584014) (xy 164.962427 -388.59364)
			(xy 165.001097 -388.612346) (xy 165.018212 -388.625334) (xy 165.02634 -388.631938) (xy 165.046914 -388.637526)
			(xy 165.131496 -388.624826) (xy 165.141747 -388.622701) (xy 165.15945 -388.611569) (xy 165.165786 -388.603236)
			(xy 165.16604 -388.602982) (xy 165.18012 -388.583042) (xy 165.213542 -388.547471) (xy 165.252196 -388.517667)
			(xy 165.295097 -388.494389) (xy 165.341155 -388.478229) (xy 165.389195 -388.469599) (xy 165.437997 -388.468719)
			(xy 165.486318 -388.475609) (xy 165.532928 -388.490096) (xy 165.576642 -388.511811) (xy 165.616346 -388.5402)
			(xy 165.65103 -388.574542) (xy 165.679812 -388.613963) (xy 165.691312 -388.635494) (xy 165.69182 -388.636764)
			(xy 165.74419 -388.727385) (xy 193.900548 -388.727385) (xy 193.900548 -388.642663) (xy 193.908601 -388.558326)
			(xy 193.924635 -388.475136) (xy 193.948503 -388.393846) (xy 193.979991 -388.315194) (xy 194.018813 -388.239891)
			(xy 194.064616 -388.168619) (xy 194.116987 -388.102023) (xy 194.175452 -388.040708) (xy 194.23948 -387.985227)
			(xy 194.308492 -387.936084) (xy 194.381862 -387.893724) (xy 194.458927 -387.858529) (xy 194.538989 -387.83082)
			(xy 194.621322 -387.810846) (xy 194.705181 -387.798789) (xy 194.789806 -387.794758) (xy 194.874431 -387.798789)
			(xy 194.95829 -387.810846) (xy 195.040623 -387.83082) (xy 195.120685 -387.858529) (xy 195.19775 -387.893724)
			(xy 195.27112 -387.936084) (xy 195.340132 -387.985227) (xy 195.40416 -388.040708) (xy 195.462625 -388.102023)
			(xy 195.514996 -388.168619) (xy 195.560799 -388.239891) (xy 195.599621 -388.315194) (xy 195.631109 -388.393846)
			(xy 195.654977 -388.475136) (xy 195.671011 -388.558326) (xy 195.679064 -388.642663) (xy 195.679568 -388.685024)
			(xy 195.679064 -388.727385) (xy 195.671011 -388.811722) (xy 195.654977 -388.894912) (xy 195.631109 -388.976202)
			(xy 195.599621 -389.054854) (xy 195.560799 -389.130157) (xy 195.514996 -389.201429) (xy 195.462625 -389.268025)
			(xy 195.40416 -389.32934) (xy 195.340132 -389.384821) (xy 195.27112 -389.433964) (xy 195.19775 -389.476324)
			(xy 195.120685 -389.511519) (xy 195.040623 -389.539228) (xy 194.95829 -389.559202) (xy 194.874431 -389.571259)
			(xy 194.789806 -389.575291) (xy 194.705181 -389.571259) (xy 194.621322 -389.559202) (xy 194.538989 -389.539228)
			(xy 194.458927 -389.511519) (xy 194.381862 -389.476324) (xy 194.308492 -389.433964) (xy 194.23948 -389.384821)
			(xy 194.175452 -389.32934) (xy 194.116987 -389.268025) (xy 194.064616 -389.201429) (xy 194.018813 -389.130157)
			(xy 193.979991 -389.054854) (xy 193.948503 -388.976202) (xy 193.924635 -388.894912) (xy 193.908601 -388.811722)
			(xy 193.900548 -388.727385) (xy 165.74419 -388.727385) (xy 166.083742 -389.314944) (xy 166.083996 -389.315452)
			(xy 166.08425 -389.315452) (xy 166.08552 -389.317992) (xy 166.097793 -389.340907) (xy 166.115198 -389.389885)
			(xy 166.124072 -389.441101) (xy 166.124636 -389.46709) (xy 166.124636 -389.467344) (xy 166.124179 -389.491322)
			(xy 166.116675 -389.538688) (xy 166.101859 -389.584299) (xy 166.080095 -389.627033) (xy 166.051917 -389.665839)
			(xy 166.01802 -389.699762) (xy 165.979236 -389.72797) (xy 165.936519 -389.749768) (xy 165.89092 -389.76462)
			(xy 165.84356 -389.77216) (xy 165.819582 -389.772652) (xy 165.819074 -389.772652) (xy 165.795412 -389.772153)
			(xy 165.748653 -389.764854) (xy 165.703579 -389.750433) (xy 165.661267 -389.729237) (xy 165.622728 -389.701771)
			(xy 165.588884 -389.668693) (xy 165.560543 -389.630792) (xy 165.549072 -389.610092) (xy 165.548818 -389.60933)
			(xy 165.535864 -389.586978) (xy 165.53042 -389.57858) (xy 165.514554 -389.566418) (xy 165.495242 -389.561249)
			(xy 165.475422 -389.563861) (xy 165.466522 -389.568436) (xy 165.457378 -389.57377) (xy 165.451282 -389.582152)
			(xy 165.440346 -389.596044) (xy 165.414264 -389.619907) (xy 165.38424 -389.638569) (xy 165.351296 -389.651393)
			(xy 165.316557 -389.657943) (xy 165.298882 -389.658352) (xy 165.298374 -389.658352) (xy 165.279596 -389.657927)
			(xy 165.242761 -389.650602) (xy 165.208061 -389.636237) (xy 165.176826 -389.615384) (xy 165.150254 -389.588843)
			(xy 165.129366 -389.557632) (xy 165.114962 -389.522948) (xy 165.107595 -389.486121) (xy 165.107112 -389.467344)
			(xy 165.107548 -389.448228) (xy 165.115118 -389.410755) (xy 165.129985 -389.375533) (xy 165.151555 -389.343969)
			(xy 165.178969 -389.317321) (xy 165.211132 -389.296654) (xy 165.228778 -389.28929) (xy 165.238938 -389.285226)
			(xy 165.254432 -389.269478) (xy 165.283642 -389.186166) (xy 165.286835 -389.17558) (xy 165.284878 -389.153585)
			(xy 165.279832 -389.143748) (xy 165.151562 -388.922006) (xy 165.139624 -388.897876) (xy 165.134764 -388.888374)
			(xy 165.118989 -388.874047) (xy 165.098757 -388.867356) (xy 165.07755 -388.869455) (xy 165.059021 -388.87998)
			(xy 165.052248 -388.888224) (xy 165.041313 -388.902278) (xy 165.015173 -388.926452) (xy 164.98501 -388.945369)
			(xy 164.951866 -388.958374) (xy 164.916888 -388.965018) (xy 164.899086 -388.96544) (xy 164.898578 -388.96544)
			(xy 164.870892 -388.963408) (xy 164.870638 -388.963408) (xy 164.861171 -388.962405) (xy 164.842648 -388.966756)
			(xy 164.826997 -388.977577) (xy 164.821362 -388.985252) (xy 164.7698 -389.060944) (xy 164.764774 -389.069077)
			(xy 164.760606 -389.087721) (xy 164.763546 -389.106598) (xy 164.768022 -389.115046) (xy 164.865812 -389.283956)
			(xy 164.865812 -389.284464) (xy 164.885624 -389.317992) (xy 164.897897 -389.340907) (xy 164.915302 -389.389885)
			(xy 164.924176 -389.441101) (xy 164.92474 -389.46709) (xy 164.92474 -389.467344) (xy 164.924302 -389.491349)
			(xy 164.916781 -389.538768) (xy 164.901933 -389.584425) (xy 164.880123 -389.627196) (xy 164.851888 -389.666027)
			(xy 164.817925 -389.699961) (xy 164.779069 -389.728162) (xy 164.736279 -389.749935) (xy 164.690609 -389.764744)
			(xy 164.643184 -389.772222) (xy 164.619178 -389.772652) (xy 164.618924 -389.772652) (xy 164.595352 -389.772211)
			(xy 164.548767 -389.764975) (xy 164.503851 -389.750656) (xy 164.461674 -389.729594) (xy 164.423241 -389.702292)
			(xy 164.389467 -389.669401) (xy 164.361157 -389.631704) (xy 164.349684 -389.611108) (xy 164.349176 -389.610346)
			(xy 164.335714 -389.586978) (xy 164.330321 -389.578542) (xy 164.314436 -389.56638) (xy 164.295107 -389.561221)
			(xy 164.275275 -389.56385) (xy 164.266372 -389.568436) (xy 164.257228 -389.57377) (xy 164.251132 -389.582152)
			(xy 164.240225 -389.596068) (xy 164.214135 -389.619929) (xy 164.184104 -389.638587) (xy 164.151154 -389.651405)
			(xy 164.116409 -389.657947) (xy 164.098732 -389.658352) (xy 164.098224 -389.658352) (xy 164.07946 -389.657827)
			(xy 164.042653 -389.65051) (xy 164.00798 -389.636155) (xy 163.976773 -389.615311) (xy 163.950233 -389.588779)
			(xy 163.929378 -389.55758) (xy 163.915009 -389.522912) (xy 163.90768 -389.486108) (xy 163.907216 -389.467344)
			(xy 163.907724 -389.448251) (xy 163.915283 -389.410822) (xy 163.930109 -389.375632) (xy 163.951615 -389.344079)
			(xy 163.978948 -389.317414) (xy 164.011024 -389.296694) (xy 164.028628 -389.28929) (xy 164.038788 -389.285226)
			(xy 164.054282 -389.269478) (xy 164.083492 -389.186166) (xy 164.08669 -389.175581) (xy 164.084732 -389.153584)
			(xy 164.079682 -389.143748) (xy 163.951412 -388.922006) (xy 163.939474 -388.897876) (xy 163.934685 -388.888333)
			(xy 163.91889 -388.874) (xy 163.898636 -388.867313) (xy 163.877412 -388.869424) (xy 163.858872 -388.879969)
			(xy 163.852098 -388.888224) (xy 163.841174 -388.90232) (xy 163.814984 -388.92652) (xy 163.784761 -388.945444)
			(xy 163.751553 -388.958436) (xy 163.716512 -388.965044) (xy 163.698682 -388.96544) (xy 163.698174 -388.96544)
			(xy 163.691294 -388.965441) (xy 163.677564 -388.964548) (xy 163.670742 -388.963662) (xy 163.656264 -388.961376)
			(xy 163.629594 -388.97306) (xy 163.569904 -389.060944) (xy 163.564878 -389.069077) (xy 163.56071 -389.087721)
			(xy 163.56365 -389.106598) (xy 163.568126 -389.115046) (xy 163.683696 -389.314944) (xy 163.68395 -389.315452)
			(xy 163.684204 -389.315452) (xy 163.685474 -389.317992) (xy 163.697704 -389.340918) (xy 163.715026 -389.389903)
			(xy 163.723814 -389.441111) (xy 163.724336 -389.46709) (xy 163.724336 -389.467344) (xy 163.723878 -389.491335)
			(xy 163.716366 -389.538726) (xy 163.701535 -389.584358) (xy 163.679748 -389.627109) (xy 163.651543 -389.665926)
			(xy 163.617613 -389.699853) (xy 163.578795 -389.728056) (xy 163.536043 -389.749841) (xy 163.49041 -389.76467)
			(xy 163.443019 -389.772179) (xy 163.419028 -389.772652) (xy 163.395364 -389.77219) (xy 163.348604 -389.764884)
			(xy 163.303529 -389.750457) (xy 163.261217 -389.729254) (xy 163.222679 -389.701783) (xy 163.188836 -389.668699)
			(xy 163.160497 -389.630794) (xy 163.149026 -389.610092) (xy 163.148772 -389.60933) (xy 163.135818 -389.586978)
			(xy 163.130421 -389.578545) (xy 163.114538 -389.566383) (xy 163.09521 -389.561223) (xy 163.075379 -389.563851)
			(xy 163.066476 -389.568436) (xy 163.057332 -389.57377) (xy 163.051236 -389.582152) (xy 163.040327 -389.596066)
			(xy 163.014238 -389.619927) (xy 162.984207 -389.638585) (xy 162.951257 -389.651404) (xy 162.916513 -389.657947)
			(xy 162.898836 -389.658352) (xy 162.898328 -389.658352) (xy 162.879564 -389.657823) (xy 162.842757 -389.650508)
			(xy 162.808084 -389.636152) (xy 162.776878 -389.615309) (xy 162.750337 -389.588778) (xy 162.729482 -389.55758)
			(xy 162.715113 -389.522912) (xy 162.707784 -389.486107) (xy 162.70732 -389.467344) (xy 162.707825 -389.448251)
			(xy 162.715384 -389.410821) (xy 162.730211 -389.375632) (xy 162.751718 -389.344078) (xy 162.779051 -389.317413)
			(xy 162.811127 -389.296694) (xy 162.828732 -389.28929) (xy 162.838892 -389.285226) (xy 162.854386 -389.269478)
			(xy 162.883596 -389.186166) (xy 162.886794 -389.17558) (xy 162.884835 -389.153584) (xy 162.879786 -389.143748)
			(xy 162.751516 -388.922006) (xy 162.739578 -388.897876) (xy 162.734783 -388.888337) (xy 162.718989 -388.874004)
			(xy 162.698738 -388.867317) (xy 162.677515 -388.869427) (xy 162.658976 -388.87997) (xy 162.652202 -388.888224)
			(xy 162.641293 -388.902299) (xy 162.615147 -388.926472) (xy 162.584977 -388.945385) (xy 162.551827 -388.958385)
			(xy 162.516843 -388.965023) (xy 162.49904 -388.96544) (xy 162.498532 -388.96544) (xy 162.470846 -388.963408)
			(xy 162.470592 -388.963408) (xy 162.461123 -388.962448) (xy 162.442605 -388.966781) (xy 162.426954 -388.977584)
			(xy 162.421316 -388.985252) (xy 162.369754 -389.060944) (xy 162.364731 -389.069077) (xy 162.360567 -389.087721)
			(xy 162.363504 -389.106597) (xy 162.367976 -389.115046) (xy 162.465766 -389.283956) (xy 162.465766 -389.284464)
			(xy 162.485578 -389.317992) (xy 162.497808 -389.340918) (xy 162.51513 -389.389903) (xy 162.523918 -389.441111)
			(xy 162.52444 -389.46709) (xy 162.52444 -389.467344) (xy 162.523978 -389.491335) (xy 162.516466 -389.538725)
			(xy 162.501635 -389.584357) (xy 162.479849 -389.627107) (xy 162.451644 -389.665924) (xy 162.417715 -389.699852)
			(xy 162.378897 -389.728055) (xy 162.336146 -389.74984) (xy 162.290513 -389.764669) (xy 162.243123 -389.772179)
			(xy 162.219132 -389.772652) (xy 162.218878 -389.772652) (xy 162.195305 -389.772249) (xy 162.148718 -389.765005)
			(xy 162.103801 -389.750679) (xy 162.061624 -389.729611) (xy 162.023191 -389.702304) (xy 161.989418 -389.669408)
			(xy 161.96111 -389.631706) (xy 161.949638 -389.611108) (xy 161.94913 -389.610346) (xy 161.935668 -389.586978)
			(xy 161.93022 -389.578583) (xy 161.914355 -389.56642) (xy 161.895045 -389.561251) (xy 161.875226 -389.563861)
			(xy 161.866326 -389.568436) (xy 161.857182 -389.57377) (xy 161.851086 -389.582152) (xy 161.840148 -389.596042)
			(xy 161.814067 -389.619905) (xy 161.784043 -389.638567) (xy 161.7511 -389.651392) (xy 161.716361 -389.657943)
			(xy 161.698686 -389.658352) (xy 161.698178 -389.658352) (xy 161.6794 -389.657923) (xy 161.642565 -389.650599)
			(xy 161.607865 -389.636235) (xy 161.57663 -389.615383) (xy 161.550059 -389.588842) (xy 161.52917 -389.557631)
			(xy 161.514766 -389.522947) (xy 161.507399 -389.486121) (xy 161.506916 -389.467344) (xy 161.50735 -389.448228)
			(xy 161.51492 -389.410754) (xy 161.529787 -389.375533) (xy 161.551358 -389.343968) (xy 161.578773 -389.317321)
			(xy 161.610936 -389.296654) (xy 161.628582 -389.28929) (xy 161.638742 -389.285226) (xy 161.654236 -389.269478)
			(xy 161.683446 -389.186166) (xy 161.686639 -389.17558) (xy 161.684682 -389.153584) (xy 161.679636 -389.143748)
			(xy 161.551366 -388.922006) (xy 161.539428 -388.897876) (xy 161.534562 -388.888377) (xy 161.518789 -388.874051)
			(xy 161.498558 -388.86736) (xy 161.477353 -388.869457) (xy 161.458825 -388.879981) (xy 161.452052 -388.888224)
			(xy 161.441097 -388.902295) (xy 161.414915 -388.926496) (xy 161.384699 -388.945425) (xy 161.351498 -388.958422)
			(xy 161.316463 -388.965039) (xy 161.298636 -388.96544) (xy 161.298128 -388.96544) (xy 161.291248 -388.965435)
			(xy 161.277518 -388.964546) (xy 161.270696 -388.963662) (xy 161.256218 -388.961376) (xy 161.229548 -388.97306)
			(xy 161.169858 -389.060944) (xy 161.164835 -389.069077) (xy 161.16067 -389.087721) (xy 161.163607 -389.106597)
			(xy 161.16808 -389.115046) (xy 161.28365 -389.314944) (xy 161.283904 -389.315452) (xy 161.284158 -389.315452)
			(xy 161.285428 -389.317992) (xy 161.297701 -389.340907) (xy 161.315106 -389.389885) (xy 161.32398 -389.441101)
			(xy 161.324544 -389.46709) (xy 161.324544 -389.467344) (xy 161.324079 -389.491322) (xy 161.316576 -389.538687)
			(xy 161.30176 -389.584297) (xy 161.279996 -389.62703) (xy 161.25182 -389.665836) (xy 161.217923 -389.69976)
			(xy 161.17914 -389.727967) (xy 161.136425 -389.749765) (xy 161.090827 -389.764618) (xy 161.043468 -389.77216)
			(xy 161.01949 -389.772652) (xy 161.018982 -389.772652) (xy 160.995317 -389.772227) (xy 160.948555 -389.764914)
			(xy 160.90348 -389.75048) (xy 160.861167 -389.729272) (xy 160.822629 -389.701795) (xy 160.788787 -389.668706)
			(xy 160.76045 -389.630797) (xy 160.74898 -389.610092) (xy 160.748726 -389.60933) (xy 160.735772 -389.586978)
			(xy 160.73032 -389.578586) (xy 160.714457 -389.566423) (xy 160.695148 -389.561254) (xy 160.67533 -389.563862)
			(xy 160.66643 -389.568436) (xy 160.657286 -389.57377) (xy 160.65119 -389.582152) (xy 160.64025 -389.59604)
			(xy 160.614169 -389.619904) (xy 160.584146 -389.638566) (xy 160.551203 -389.651391) (xy 160.516465 -389.657942)
			(xy 160.49879 -389.658352) (xy 160.498282 -389.658352) (xy 160.479504 -389.65792) (xy 160.44267 -389.650596)
			(xy 160.407969 -389.636233) (xy 160.376734 -389.615381) (xy 160.350163 -389.588841) (xy 160.329274 -389.55763)
			(xy 160.31487 -389.522947) (xy 160.307503 -389.486121) (xy 160.30702 -389.467344) (xy 160.307451 -389.448228)
			(xy 160.315022 -389.410754) (xy 160.329889 -389.375532) (xy 160.351461 -389.343968) (xy 160.378876 -389.317321)
			(xy 160.41104 -389.296654) (xy 160.428686 -389.28929) (xy 160.438846 -389.285226) (xy 160.45434 -389.269478)
			(xy 160.48355 -389.186166) (xy 160.486742 -389.17558) (xy 160.484786 -389.153585) (xy 160.47974 -389.143748)
			(xy 160.35147 -388.922006) (xy 160.339532 -388.897876) (xy 160.334661 -388.888381) (xy 160.318889 -388.874054)
			(xy 160.29866 -388.867363) (xy 160.277456 -388.869459) (xy 160.258929 -388.879982) (xy 160.252156 -388.888224)
			(xy 160.241199 -388.902293) (xy 160.215017 -388.926495) (xy 160.184802 -388.945423) (xy 160.151602 -388.958421)
			(xy 160.116567 -388.965039) (xy 160.09874 -388.96544) (xy 160.098232 -388.96544) (xy 160.091352 -388.965435)
			(xy 160.077623 -388.964546) (xy 160.0708 -388.963662) (xy 160.056322 -388.961376) (xy 160.029652 -388.97306)
			(xy 159.969962 -389.060944) (xy 159.964938 -389.069077) (xy 159.960773 -389.087721) (xy 159.963711 -389.106597)
			(xy 159.968184 -389.115046) (xy 160.083754 -389.314944) (xy 160.084008 -389.315452) (xy 160.084262 -389.315452)
			(xy 160.085532 -389.317992) (xy 160.097806 -389.340907) (xy 160.115211 -389.389885) (xy 160.124084 -389.441101)
			(xy 160.124648 -389.46709) (xy 160.124648 -389.467344) (xy 160.124179 -389.491322) (xy 160.116676 -389.538687)
			(xy 160.10186 -389.584296) (xy 160.080097 -389.627029) (xy 160.051921 -389.665835) (xy 160.018025 -389.699758)
			(xy 159.979243 -389.727966) (xy 159.936528 -389.749764) (xy 159.89093 -389.764617) (xy 159.843571 -389.772159)
			(xy 159.819594 -389.772652) (xy 159.819086 -389.772652) (xy 159.795421 -389.772224) (xy 159.74866 -389.764911)
			(xy 159.703584 -389.750478) (xy 159.661272 -389.72927) (xy 159.622734 -389.701794) (xy 159.588892 -389.668705)
			(xy 159.560554 -389.630796) (xy 159.549084 -389.610092) (xy 159.54883 -389.60933) (xy 159.535876 -389.586978)
			(xy 159.53042 -389.578589) (xy 159.514558 -389.566426) (xy 159.495251 -389.561256) (xy 159.475434 -389.563863)
			(xy 159.466534 -389.568436) (xy 159.45739 -389.57377) (xy 159.451294 -389.582152) (xy 159.440352 -389.596039)
			(xy 159.414271 -389.619902) (xy 159.384248 -389.638564) (xy 159.351307 -389.65139) (xy 159.316569 -389.657942)
			(xy 159.298894 -389.658352) (xy 159.298386 -389.658352) (xy 159.279608 -389.657916) (xy 159.242774 -389.650593)
			(xy 159.208074 -389.63623) (xy 159.176839 -389.615379) (xy 159.150267 -389.58884) (xy 159.129378 -389.55763)
			(xy 159.114974 -389.522947) (xy 159.107607 -389.486121) (xy 159.107124 -389.467344) (xy 159.107553 -389.448228)
			(xy 159.115123 -389.410753) (xy 159.129991 -389.375531) (xy 159.151563 -389.343967) (xy 159.178979 -389.31732)
			(xy 159.211143 -389.296654) (xy 159.22879 -389.28929) (xy 159.23895 -389.285226) (xy 159.254444 -389.269478)
			(xy 159.283654 -389.186166) (xy 159.286846 -389.17558) (xy 159.284889 -389.153585) (xy 159.279844 -389.143748)
			(xy 159.151574 -388.922006) (xy 159.139636 -388.897876) (xy 159.134759 -388.888384) (xy 159.118989 -388.874059)
			(xy 159.098762 -388.867367) (xy 159.077559 -388.869462) (xy 159.059033 -388.879983) (xy 159.05226 -388.888224)
			(xy 159.041318 -388.902272) (xy 159.01518 -388.926447) (xy 158.985019 -388.945365) (xy 158.951876 -388.958371)
			(xy 158.916899 -388.965017) (xy 158.899098 -388.96544) (xy 158.89859 -388.96544) (xy 158.870904 -388.963408)
			(xy 158.87065 -388.963408) (xy 158.861182 -388.962415) (xy 158.84266 -388.966762) (xy 158.82701 -388.977578)
			(xy 158.821374 -388.985252) (xy 158.769812 -389.060944) (xy 158.764786 -389.069077) (xy 158.760617 -389.087721)
			(xy 158.763558 -389.106598) (xy 158.768034 -389.115046) (xy 158.883604 -389.314944) (xy 158.883858 -389.315452)
			(xy 158.884112 -389.315452) (xy 158.885382 -389.317992) (xy 158.897612 -389.340918) (xy 158.914934 -389.389903)
			(xy 158.923722 -389.441111) (xy 158.924244 -389.46709) (xy 158.924244 -389.467344) (xy 158.923778 -389.491335)
			(xy 158.916267 -389.538724) (xy 158.901435 -389.584356) (xy 158.879649 -389.627106) (xy 158.851445 -389.665923)
			(xy 158.817517 -389.69985) (xy 158.778699 -389.728054) (xy 158.735949 -389.749838) (xy 158.690317 -389.764668)
			(xy 158.642927 -389.772179) (xy 158.618936 -389.772652) (xy 158.595273 -389.772184) (xy 158.548513 -389.764878)
			(xy 158.503438 -389.750453) (xy 158.461126 -389.729251) (xy 158.422587 -389.701781) (xy 158.388744 -389.668698)
			(xy 158.360405 -389.630794) (xy 158.348934 -389.610092) (xy 158.34868 -389.60933) (xy 158.335726 -389.586978)
			(xy 158.330321 -389.578551) (xy 158.31444 -389.566389) (xy 158.295116 -389.561228) (xy 158.275286 -389.563852)
			(xy 158.266384 -389.568436) (xy 158.25724 -389.57377) (xy 158.251144 -389.582152) (xy 158.24023 -389.596062)
			(xy 158.214142 -389.619924) (xy 158.184112 -389.638582) (xy 158.151164 -389.651402) (xy 158.116421 -389.657946)
			(xy 158.098744 -389.658352) (xy 158.098236 -389.658352) (xy 158.079473 -389.657816) (xy 158.042666 -389.650502)
			(xy 158.007993 -389.636148) (xy 157.976786 -389.615306) (xy 157.950245 -389.588776) (xy 157.92939 -389.557578)
			(xy 157.915021 -389.522911) (xy 157.907692 -389.486107) (xy 157.907228 -389.467344) (xy 157.907728 -389.448251)
			(xy 157.915288 -389.41082) (xy 157.930115 -389.37563) (xy 157.951623 -389.344077) (xy 157.978958 -389.317412)
			(xy 158.011035 -389.296693) (xy 158.02864 -389.28929) (xy 158.0388 -389.285226) (xy 158.054294 -389.269478)
			(xy 158.083504 -389.186166) (xy 158.086701 -389.17558) (xy 158.084743 -389.153584) (xy 158.079694 -389.143748)
			(xy 157.951424 -388.922006) (xy 157.939486 -388.897876) (xy 157.934679 -388.888343) (xy 157.918889 -388.874012)
			(xy 157.898641 -388.867324) (xy 157.877421 -388.869432) (xy 157.858884 -388.879972) (xy 157.85211 -388.888224)
			(xy 157.841179 -388.902314) (xy 157.814991 -388.926515) (xy 157.784769 -388.94544) (xy 157.751563 -388.958433)
			(xy 157.716523 -388.965043) (xy 157.698694 -388.96544) (xy 157.698186 -388.96544) (xy 157.691306 -388.96544)
			(xy 157.677576 -388.964548) (xy 157.670754 -388.963662) (xy 157.656276 -388.961376) (xy 157.629606 -388.97306)
			(xy 157.569916 -389.060944) (xy 157.56489 -389.069077) (xy 157.560721 -389.087721) (xy 157.563661 -389.106598)
			(xy 157.568138 -389.115046) (xy 157.683708 -389.314944) (xy 157.683962 -389.315452) (xy 157.684216 -389.315452)
			(xy 157.685486 -389.317992) (xy 157.697717 -389.340917) (xy 157.715038 -389.389902) (xy 157.723826 -389.441111)
			(xy 157.724348 -389.46709) (xy 157.724348 -389.467344) (xy 157.723878 -389.491334) (xy 157.716367 -389.538724)
			(xy 157.701536 -389.584355) (xy 157.67975 -389.627105) (xy 157.651546 -389.665922) (xy 157.617618 -389.699849)
			(xy 157.578802 -389.728052) (xy 157.536051 -389.749837) (xy 157.49042 -389.764668) (xy 157.44303 -389.772178)
			(xy 157.41904 -389.772652) (xy 157.395377 -389.77218) (xy 157.348617 -389.764876) (xy 157.303542 -389.750451)
			(xy 157.26123 -389.72925) (xy 157.222692 -389.70178) (xy 157.188848 -389.668698) (xy 157.160509 -389.630794)
			(xy 157.149038 -389.610092) (xy 157.148784 -389.60933) (xy 157.13583 -389.586978) (xy 157.130421 -389.578554)
			(xy 157.114542 -389.566392) (xy 157.095218 -389.56123) (xy 157.07539 -389.563853) (xy 157.066488 -389.568436)
			(xy 157.057344 -389.57377) (xy 157.051248 -389.582152) (xy 157.040332 -389.59606) (xy 157.014245 -389.619922)
			(xy 156.984215 -389.638581) (xy 156.951268 -389.651401) (xy 156.916525 -389.657946) (xy 156.898848 -389.658352)
			(xy 156.89834 -389.658352) (xy 156.879577 -389.657812) (xy 156.84277 -389.650499) (xy 156.808097 -389.636146)
			(xy 156.77689 -389.615304) (xy 156.750349 -389.588775) (xy 156.729494 -389.557577) (xy 156.715125 -389.522911)
			(xy 156.707796 -389.486107) (xy 156.707332 -389.467344) (xy 156.70783 -389.448251) (xy 156.715389 -389.41082)
			(xy 156.730217 -389.37563) (xy 156.751726 -389.344076) (xy 156.779061 -389.317411) (xy 156.811138 -389.296693)
			(xy 156.828744 -389.28929) (xy 156.838904 -389.285226) (xy 156.854398 -389.269478) (xy 156.883608 -389.186166)
			(xy 156.886805 -389.17558) (xy 156.884847 -389.153584) (xy 156.879798 -389.143748) (xy 156.751528 -388.922006)
			(xy 156.73959 -388.897876) (xy 156.734778 -388.888346) (xy 156.718989 -388.874015) (xy 156.698743 -388.867327)
			(xy 156.677524 -388.869434) (xy 156.658988 -388.879973) (xy 156.652214 -388.888224) (xy 156.641298 -388.902294)
			(xy 156.615154 -388.926467) (xy 156.584986 -388.945381) (xy 156.551838 -388.958383) (xy 156.516855 -388.965022)
			(xy 156.499052 -388.96544) (xy 156.498544 -388.96544) (xy 156.470858 -388.963408) (xy 156.470604 -388.963408)
			(xy 156.461134 -388.962458) (xy 156.442617 -388.966786) (xy 156.426966 -388.977586) (xy 156.421328 -388.985252)
			(xy 156.369766 -389.060944) (xy 156.364742 -389.069077) (xy 156.360577 -389.087721) (xy 156.363515 -389.106597)
			(xy 156.367988 -389.115046) (xy 156.465778 -389.283956) (xy 156.465778 -389.284464) (xy 156.48559 -389.317992)
			(xy 156.497821 -389.340917) (xy 156.515142 -389.389902) (xy 156.52393 -389.441111) (xy 156.524452 -389.46709)
			(xy 156.524452 -389.467344) (xy 156.523978 -389.491334) (xy 156.516467 -389.538723) (xy 156.501636 -389.584354)
			(xy 156.479851 -389.627104) (xy 156.451648 -389.66592) (xy 156.41772 -389.699848) (xy 156.378904 -389.728051)
			(xy 156.336154 -389.749836) (xy 156.290523 -389.764667) (xy 156.243134 -389.772178) (xy 156.219144 -389.772652)
			(xy 156.21889 -389.772652) (xy 156.195317 -389.772239) (xy 156.148731 -389.764997) (xy 156.103814 -389.750673)
			(xy 156.061637 -389.729607) (xy 156.023204 -389.702301) (xy 155.989431 -389.669406) (xy 155.961123 -389.631705)
			(xy 155.94965 -389.611108) (xy 155.949142 -389.610346) (xy 155.93568 -389.586978) (xy 155.93022 -389.578592)
			(xy 155.914359 -389.566429) (xy 155.895053 -389.561258) (xy 155.875237 -389.563864) (xy 155.866338 -389.568436)
			(xy 155.857194 -389.57377) (xy 155.851098 -389.582152) (xy 155.840153 -389.596037) (xy 155.814073 -389.6199)
			(xy 155.784051 -389.638563) (xy 155.75111 -389.651389) (xy 155.716372 -389.657941) (xy 155.698698 -389.658352)
			(xy 155.69819 -389.658352) (xy 155.679413 -389.657912) (xy 155.642578 -389.65059) (xy 155.607878 -389.636228)
			(xy 155.576643 -389.615377) (xy 155.550072 -389.588838) (xy 155.529183 -389.557629) (xy 155.514779 -389.522946)
			(xy 155.507411 -389.486121) (xy 155.506928 -389.467344) (xy 155.507354 -389.448228) (xy 155.514925 -389.410753)
			(xy 155.529793 -389.37553) (xy 155.551366 -389.343966) (xy 155.578782 -389.317319) (xy 155.610947 -389.296654)
			(xy 155.628594 -389.28929) (xy 155.638754 -389.285226) (xy 155.654248 -389.269478) (xy 155.683458 -389.186166)
			(xy 155.686649 -389.175579) (xy 155.684693 -389.153585) (xy 155.679648 -389.143748) (xy 155.551378 -388.922006)
			(xy 155.53944 -388.897876) (xy 155.534557 -388.888388) (xy 155.518789 -388.874062) (xy 155.498563 -388.867371)
			(xy 155.477362 -388.869465) (xy 155.458837 -388.879984) (xy 155.452064 -388.888224) (xy 155.441102 -388.902289)
			(xy 155.414922 -388.926491) (xy 155.384708 -388.94542) (xy 155.351509 -388.958419) (xy 155.316475 -388.965038)
			(xy 155.298648 -388.96544) (xy 155.29814 -388.96544) (xy 155.29126 -388.965434) (xy 155.277531 -388.964546)
			(xy 155.270708 -388.963662) (xy 155.25623 -388.961376) (xy 155.22956 -388.97306) (xy 155.16987 -389.060944)
			(xy 155.164846 -389.069077) (xy 155.16068 -389.087721) (xy 155.163618 -389.106597) (xy 155.168092 -389.115046)
			(xy 155.283662 -389.314944) (xy 155.283916 -389.315452) (xy 155.28417 -389.315452) (xy 155.28544 -389.317992)
			(xy 155.297714 -389.340906) (xy 155.315119 -389.389885) (xy 155.323992 -389.441101) (xy 155.324556 -389.46709)
			(xy 155.324556 -389.467344) (xy 155.324079 -389.491321) (xy 155.316576 -389.538686) (xy 155.301761 -389.584295)
			(xy 155.279998 -389.627027) (xy 155.251823 -389.665832) (xy 155.217928 -389.699755) (xy 155.179147 -389.727963)
			(xy 155.136433 -389.749762) (xy 155.090837 -389.764616) (xy 155.043479 -389.772159) (xy 155.019502 -389.772652)
			(xy 155.018994 -389.772652) (xy 154.995329 -389.772217) (xy 154.948568 -389.764906) (xy 154.903493 -389.750474)
			(xy 154.86118 -389.729267) (xy 154.822642 -389.701792) (xy 154.7888 -389.668704) (xy 154.760462 -389.630796)
			(xy 154.748992 -389.610092) (xy 154.748738 -389.60933) (xy 154.735784 -389.586978) (xy 154.730319 -389.578595)
			(xy 154.714461 -389.566432) (xy 154.695156 -389.56126) (xy 154.675341 -389.563865) (xy 154.666442 -389.568436)
			(xy 154.657298 -389.57377) (xy 154.651202 -389.582152) (xy 154.640255 -389.596035) (xy 154.614176 -389.619898)
			(xy 154.584154 -389.638562) (xy 154.551213 -389.651388) (xy 154.516476 -389.657941) (xy 154.498802 -389.658352)
			(xy 154.498294 -389.658352) (xy 154.479517 -389.657908) (xy 154.442683 -389.650587) (xy 154.407983 -389.636225)
			(xy 154.376747 -389.615376) (xy 154.350176 -389.588837) (xy 154.329287 -389.557628) (xy 154.314883 -389.522946)
			(xy 154.307515 -389.486121) (xy 154.307032 -389.467344) (xy 154.307456 -389.448228) (xy 154.315027 -389.410752)
			(xy 154.329895 -389.37553) (xy 154.351468 -389.343965) (xy 154.378885 -389.317319) (xy 154.411051 -389.296653)
			(xy 154.428698 -389.28929) (xy 154.438858 -389.285226) (xy 154.454352 -389.269478) (xy 154.483562 -389.186166)
			(xy 154.486753 -389.175579) (xy 154.484797 -389.153585) (xy 154.479752 -389.143748) (xy 154.351482 -388.922006)
			(xy 154.339544 -388.897876) (xy 154.334797 -388.888308) (xy 154.31899 -388.873972) (xy 154.298724 -388.867288)
			(xy 154.277489 -388.869406) (xy 154.258943 -388.879963) (xy 154.252168 -388.888224) (xy 154.241204 -388.902287)
			(xy 154.215024 -388.926489) (xy 154.184811 -388.945419) (xy 154.151612 -388.958419) (xy 154.116579 -388.965038)
			(xy 154.098752 -388.96544) (xy 154.098244 -388.96544) (xy 154.091364 -388.965433) (xy 154.077635 -388.964546)
			(xy 154.070812 -388.963662) (xy 154.056334 -388.961376) (xy 154.029664 -388.97306) (xy 153.969974 -389.060944)
			(xy 153.96495 -389.069077) (xy 153.960784 -389.087721) (xy 153.963722 -389.106597) (xy 153.968196 -389.115046)
			(xy 154.083766 -389.314944) (xy 154.08402 -389.315452) (xy 154.084274 -389.315452) (xy 154.085544 -389.317992)
			(xy 154.097819 -389.340906) (xy 154.115223 -389.389885) (xy 154.124096 -389.441101) (xy 154.12466 -389.46709)
			(xy 154.12466 -389.467344) (xy 154.124279 -389.491326) (xy 154.116773 -389.5387) (xy 154.101952 -389.584317)
			(xy 154.080181 -389.627055) (xy 154.051995 -389.665865) (xy 154.018088 -389.69979) (xy 153.979294 -389.727996)
			(xy 153.936567 -389.74979) (xy 153.890957 -389.764635) (xy 153.843588 -389.772166) (xy 153.819606 -389.772652)
			(xy 153.819098 -389.772652) (xy 153.795434 -389.772214) (xy 153.748672 -389.764903) (xy 153.703597 -389.750472)
			(xy 153.661285 -389.729266) (xy 153.622747 -389.701791) (xy 153.588904 -389.668704) (xy 153.560566 -389.630796)
			(xy 153.549096 -389.610092) (xy 153.548842 -389.60933) (xy 153.535888 -389.586978) (xy 153.530419 -389.578598)
			(xy 153.514562 -389.566435) (xy 153.495259 -389.561262) (xy 153.475445 -389.563866) (xy 153.466546 -389.568436)
			(xy 153.457402 -389.57377) (xy 153.451306 -389.582152) (xy 153.440414 -389.59608) (xy 153.41432 -389.61994)
			(xy 153.384285 -389.638596) (xy 153.351332 -389.651411) (xy 153.316584 -389.65795) (xy 153.298906 -389.658352)
			(xy 153.298398 -389.658352) (xy 153.279621 -389.657905) (xy 153.242787 -389.650584) (xy 153.208087 -389.636223)
			(xy 153.176852 -389.615374) (xy 153.15028 -389.588836) (xy 153.129391 -389.557627) (xy 153.114987 -389.522945)
			(xy 153.107619 -389.486121) (xy 153.107136 -389.467344) (xy 153.107557 -389.448227) (xy 153.115128 -389.410752)
			(xy 153.129997 -389.375529) (xy 153.151571 -389.343965) (xy 153.178988 -389.317318) (xy 153.211154 -389.296653)
			(xy 153.228802 -389.28929) (xy 153.238962 -389.285226) (xy 153.254456 -389.269478) (xy 153.283666 -389.186166)
			(xy 153.286856 -389.175579) (xy 153.2849 -389.153585) (xy 153.279856 -389.143748) (xy 153.151586 -388.922006)
			(xy 153.139648 -388.897876) (xy 153.134895 -388.888312) (xy 153.11909 -388.873976) (xy 153.098825 -388.867291)
			(xy 153.077592 -388.869408) (xy 153.059047 -388.879964) (xy 153.052272 -388.888224) (xy 153.04138 -388.902314)
			(xy 153.01523 -388.926485) (xy 152.985056 -388.945396) (xy 152.951902 -388.958393) (xy 152.916915 -388.965025)
			(xy 152.89911 -388.96544) (xy 152.898602 -388.96544) (xy 152.870916 -388.963408) (xy 152.870662 -388.963408)
			(xy 152.861194 -388.962424) (xy 152.842673 -388.966767) (xy 152.827022 -388.97758) (xy 152.821386 -388.985252)
			(xy 152.769824 -389.060944) (xy 152.764798 -389.069077) (xy 152.760628 -389.087721) (xy 152.763569 -389.106598)
			(xy 152.768046 -389.115046) (xy 152.883616 -389.314944) (xy 152.88387 -389.315452) (xy 152.884124 -389.315452)
			(xy 152.885394 -389.317992) (xy 152.897625 -389.340917) (xy 152.914946 -389.389902) (xy 152.923734 -389.441111)
			(xy 152.924256 -389.46709) (xy 152.924256 -389.467344) (xy 152.923778 -389.491334) (xy 152.916267 -389.538723)
			(xy 152.901436 -389.584353) (xy 152.879652 -389.627103) (xy 152.851449 -389.665919) (xy 152.817522 -389.699846)
			(xy 152.778706 -389.72805) (xy 152.735957 -389.749835) (xy 152.690327 -389.764666) (xy 152.642938 -389.772178)
			(xy 152.618948 -389.772652) (xy 152.595285 -389.772174) (xy 152.548526 -389.764871) (xy 152.503451 -389.750447)
			(xy 152.461139 -389.729247) (xy 152.4226 -389.701778) (xy 152.388757 -389.668697) (xy 152.360417 -389.630794)
			(xy 152.348946 -389.610092) (xy 152.348692 -389.60933) (xy 152.335738 -389.586978) (xy 152.33032 -389.57856)
			(xy 152.314445 -389.566398) (xy 152.295124 -389.561234) (xy 152.275298 -389.563855) (xy 152.266396 -389.568436)
			(xy 152.257252 -389.57377) (xy 152.251156 -389.582152) (xy 152.240235 -389.596057) (xy 152.214149 -389.619918)
			(xy 152.184121 -389.638578) (xy 152.151174 -389.651399) (xy 152.116432 -389.657945) (xy 152.098756 -389.658352)
			(xy 152.098248 -389.658352) (xy 152.079482 -389.657835) (xy 152.04267 -389.650522) (xy 152.007991 -389.636168)
			(xy 151.97678 -389.615324) (xy 151.950234 -389.588792) (xy 151.929375 -389.55759) (xy 151.915004 -389.522919)
			(xy 151.907674 -389.48611) (xy 151.90724 -389.467344) (xy 151.907733 -389.44825) (xy 151.915293 -389.410819)
			(xy 151.930121 -389.375628) (xy 151.951631 -389.344075) (xy 151.978967 -389.31741) (xy 152.011046 -389.296693)
			(xy 152.028652 -389.28929) (xy 152.038812 -389.285226) (xy 152.054306 -389.269478) (xy 152.083516 -389.186166)
			(xy 152.086712 -389.17558) (xy 152.084754 -389.153584) (xy 152.079706 -389.143748) (xy 151.951436 -388.922006)
			(xy 151.939498 -388.897876) (xy 151.934675 -388.888353) (xy 151.918889 -388.874023) (xy 151.898646 -388.867334)
			(xy 151.87743 -388.869439) (xy 151.858896 -388.879975) (xy 151.852122 -388.888224) (xy 151.841185 -388.902309)
			(xy 151.814998 -388.92651) (xy 151.784778 -388.945435) (xy 151.751573 -388.95843) (xy 151.716534 -388.965042)
			(xy 151.698706 -388.96544) (xy 151.698198 -388.96544) (xy 151.691318 -388.965438) (xy 151.677588 -388.964548)
			(xy 151.670766 -388.963662) (xy 151.656288 -388.961376) (xy 151.629618 -388.97306) (xy 151.569928 -389.060944)
			(xy 151.564901 -389.069077) (xy 151.560731 -389.087721) (xy 151.563672 -389.106598) (xy 151.56815 -389.115046)
			(xy 151.68372 -389.314944) (xy 151.683974 -389.315452) (xy 151.684228 -389.315452) (xy 151.685498 -389.317992)
			(xy 151.697729 -389.340917) (xy 151.71505 -389.389902) (xy 151.723838 -389.441111) (xy 151.72436 -389.46709)
			(xy 151.72436 -389.467344) (xy 151.724002 -389.491341) (xy 151.716487 -389.538742) (xy 151.70165 -389.584385)
			(xy 151.679855 -389.627144) (xy 151.651639 -389.665968) (xy 151.617698 -389.699899) (xy 151.578866 -389.728103)
			(xy 151.5361 -389.749885) (xy 151.490453 -389.764709) (xy 151.443049 -389.772209) (xy 151.419052 -389.772652)
			(xy 151.395389 -389.772171) (xy 151.34863 -389.764868) (xy 151.303556 -389.750445) (xy 151.261243 -389.729245)
			(xy 151.222705 -389.701777) (xy 151.188861 -389.668696) (xy 151.160521 -389.630793) (xy 151.14905 -389.610092)
			(xy 151.148796 -389.60933) (xy 151.135842 -389.586978) (xy 151.13042 -389.578563) (xy 151.114546 -389.566401)
			(xy 151.095227 -389.561237) (xy 151.075401 -389.563856) (xy 151.0665 -389.568436) (xy 151.057356 -389.57377)
			(xy 151.05126 -389.582152) (xy 151.040337 -389.596055) (xy 151.014252 -389.619917) (xy 150.984224 -389.638577)
			(xy 150.951278 -389.651398) (xy 150.916536 -389.657945) (xy 150.89886 -389.658352) (xy 150.898352 -389.658352)
			(xy 150.879586 -389.657892) (xy 150.842776 -389.650562) (xy 150.808102 -389.636195) (xy 150.776896 -389.61534)
			(xy 150.750357 -389.588801) (xy 150.729503 -389.557594) (xy 150.715136 -389.52292) (xy 150.707808 -389.48611)
			(xy 150.707344 -389.467344) (xy 150.707834 -389.44825) (xy 150.715394 -389.410818) (xy 150.730223 -389.375628)
			(xy 150.751733 -389.344074) (xy 150.77907 -389.31741) (xy 150.811149 -389.296692) (xy 150.828756 -389.28929)
			(xy 150.838916 -389.285226) (xy 150.85441 -389.269478) (xy 150.88362 -389.186166) (xy 150.886815 -389.17558)
			(xy 150.884858 -389.153584) (xy 150.87981 -389.143748) (xy 150.75154 -388.922006) (xy 150.739602 -388.897876)
			(xy 150.734773 -388.888356) (xy 150.718989 -388.874026) (xy 150.698748 -388.867338) (xy 150.677533 -388.869441)
			(xy 150.659 -388.879976) (xy 150.652226 -388.888224) (xy 150.641303 -388.902288) (xy 150.615161 -388.926462)
			(xy 150.584995 -388.945377) (xy 150.551848 -388.95838) (xy 150.516866 -388.96502) (xy 150.499064 -388.96544)
			(xy 150.498556 -388.96544) (xy 150.47087 -388.963408) (xy 150.470616 -388.963408) (xy 150.461146 -388.962467)
			(xy 150.44263 -388.966791) (xy 150.426979 -388.977587) (xy 150.42134 -388.985252) (xy 150.369778 -389.060944)
			(xy 150.364754 -389.069077) (xy 150.360587 -389.087721) (xy 150.363526 -389.106597) (xy 150.368 -389.115046)
			(xy 150.46579 -389.283956) (xy 150.46579 -389.284464) (xy 150.485602 -389.317992) (xy 150.497834 -389.340917)
			(xy 150.515155 -389.389902) (xy 150.523942 -389.441111) (xy 150.524464 -389.46709) (xy 150.524464 -389.467344)
			(xy 150.524078 -389.491339) (xy 150.516564 -389.538736) (xy 150.501728 -389.584375) (xy 150.479935 -389.62713)
			(xy 150.451722 -389.66595) (xy 150.417783 -389.699879) (xy 150.378955 -389.728081) (xy 150.336193 -389.749861)
			(xy 150.29055 -389.764684) (xy 150.243151 -389.772185) (xy 150.219156 -389.772652) (xy 150.218902 -389.772652)
			(xy 150.195329 -389.772229) (xy 150.148744 -389.76499) (xy 150.103827 -389.750667) (xy 150.06165 -389.729602)
			(xy 150.023217 -389.702298) (xy 149.989444 -389.669404) (xy 149.961135 -389.631705) (xy 149.949662 -389.611108)
			(xy 149.949154 -389.610346) (xy 149.935692 -389.586978) (xy 149.930219 -389.578601) (xy 149.914364 -389.566438)
			(xy 149.895062 -389.561264) (xy 149.875249 -389.563866) (xy 149.86635 -389.568436) (xy 149.857206 -389.57377)
			(xy 149.85111 -389.582152) (xy 149.840215 -389.596078) (xy 149.814123 -389.619939) (xy 149.784088 -389.638595)
			(xy 149.751135 -389.65141) (xy 149.716388 -389.657949) (xy 149.69871 -389.658352) (xy 149.698202 -389.658352)
			(xy 149.679425 -389.657901) (xy 149.642591 -389.650581) (xy 149.607891 -389.636221) (xy 149.576656 -389.615372)
			(xy 149.550084 -389.588835) (xy 149.529195 -389.557626) (xy 149.514791 -389.522945) (xy 149.507423 -389.48612)
			(xy 149.50694 -389.467344) (xy 149.507359 -389.448227) (xy 149.51493 -389.410751) (xy 149.529799 -389.375528)
			(xy 149.551373 -389.343964) (xy 149.578791 -389.317318) (xy 149.610958 -389.296653) (xy 149.628606 -389.28929)
			(xy 149.638766 -389.285226) (xy 149.65426 -389.269478) (xy 149.68347 -389.186166) (xy 149.68666 -389.175579)
			(xy 149.684704 -389.153585) (xy 149.67966 -389.143748) (xy 149.55139 -388.922006) (xy 149.539452 -388.897876)
			(xy 149.534693 -388.888315) (xy 149.51889 -388.87398) (xy 149.498627 -388.867294) (xy 149.477395 -388.869411)
			(xy 149.458851 -388.879964) (xy 149.452076 -388.888224) (xy 149.441165 -388.902331) (xy 149.414972 -388.92653)
			(xy 149.384745 -388.945452) (xy 149.351534 -388.958441) (xy 149.31649 -388.965046) (xy 149.29866 -388.96544)
			(xy 149.298152 -388.96544) (xy 149.291272 -388.965433) (xy 149.277543 -388.964546) (xy 149.27072 -388.963662)
			(xy 149.256242 -388.961376) (xy 149.229572 -388.97306) (xy 149.169882 -389.060944) (xy 149.164857 -389.069077)
			(xy 149.160691 -389.087721) (xy 149.163629 -389.106597) (xy 149.168104 -389.115046) (xy 149.283674 -389.314944)
			(xy 149.283928 -389.315452) (xy 149.284182 -389.315452) (xy 149.285452 -389.317992) (xy 149.297727 -389.340906)
			(xy 149.315131 -389.389885) (xy 149.324004 -389.441101) (xy 149.324568 -389.46709) (xy 149.324568 -389.467344)
			(xy 149.324179 -389.491326) (xy 149.316673 -389.538698) (xy 149.301852 -389.584315) (xy 149.280082 -389.627053)
			(xy 149.251897 -389.665862) (xy 149.217991 -389.699787) (xy 149.179198 -389.727993) (xy 149.136472 -389.749787)
			(xy 149.090864 -389.764633) (xy 149.043495 -389.772165) (xy 149.019514 -389.772652) (xy 149.019006 -389.772652)
			(xy 148.995342 -389.772208) (xy 148.948581 -389.764898) (xy 148.903506 -389.750468) (xy 148.861193 -389.729263)
			(xy 148.822655 -389.701789) (xy 148.788813 -389.668703) (xy 148.760474 -389.630795) (xy 148.749004 -389.610092)
			(xy 148.74875 -389.60933) (xy 148.735796 -389.586978) (xy 148.730421 -389.578529) (xy 148.71453 -389.566367)
			(xy 148.695194 -389.561211) (xy 148.675358 -389.563846) (xy 148.666454 -389.568436) (xy 148.65731 -389.57377)
			(xy 148.651214 -389.582152) (xy 148.640317 -389.596077) (xy 148.614225 -389.619937) (xy 148.584191 -389.638593)
			(xy 148.551239 -389.651409) (xy 148.516492 -389.657949) (xy 148.498814 -389.658352) (xy 148.498306 -389.658352)
			(xy 148.479529 -389.657898) (xy 148.442696 -389.650578) (xy 148.407996 -389.636219) (xy 148.37676 -389.615371)
			(xy 148.350188 -389.588833) (xy 148.329299 -389.557625) (xy 148.314895 -389.522944) (xy 148.307527 -389.48612)
			(xy 148.307044 -389.467344) (xy 148.30746 -389.448227) (xy 148.315032 -389.410751) (xy 148.329901 -389.375528)
			(xy 148.351476 -389.343963) (xy 148.378894 -389.317317) (xy 148.411062 -389.296653) (xy 148.42871 -389.28929)
			(xy 148.43887 -389.285226) (xy 148.454364 -389.269478) (xy 148.483574 -389.186166) (xy 148.486763 -389.175579)
			(xy 148.484808 -389.153585) (xy 148.479764 -389.143748) (xy 148.351494 -388.922006) (xy 148.339556 -388.897876)
			(xy 148.334792 -388.888318) (xy 148.31899 -388.873983) (xy 148.298729 -388.867298) (xy 148.277498 -388.869413)
			(xy 148.258955 -388.879965) (xy 148.25218 -388.888224) (xy 148.241267 -388.902329) (xy 148.215074 -388.926528)
			(xy 148.184848 -388.94545) (xy 148.151637 -388.95844) (xy 148.116594 -388.965046) (xy 148.098764 -388.96544)
			(xy 148.098256 -388.96544) (xy 148.091376 -388.965432) (xy 148.077647 -388.964545) (xy 148.070824 -388.963662)
			(xy 148.056346 -388.961376) (xy 148.029676 -388.97306) (xy 147.969986 -389.060944) (xy 147.964961 -389.069077)
			(xy 147.960794 -389.087721) (xy 147.963733 -389.106598) (xy 147.968208 -389.115046) (xy 148.083778 -389.314944)
			(xy 148.084032 -389.315452) (xy 148.084286 -389.315452) (xy 148.085556 -389.317992) (xy 148.097831 -389.340906)
			(xy 148.115235 -389.389885) (xy 148.124108 -389.441101) (xy 148.124672 -389.46709) (xy 148.124672 -389.467344)
			(xy 148.124279 -389.491326) (xy 148.116773 -389.538698) (xy 148.101953 -389.584314) (xy 148.080183 -389.627052)
			(xy 148.051999 -389.665861) (xy 148.018093 -389.699785) (xy 147.9793 -389.727992) (xy 147.936575 -389.749786)
			(xy 147.890967 -389.764632) (xy 147.843599 -389.772165) (xy 147.819618 -389.772652) (xy 147.81911 -389.772652)
			(xy 147.795446 -389.772205) (xy 147.748685 -389.764896) (xy 147.70361 -389.750466) (xy 147.661298 -389.729261)
			(xy 147.622759 -389.701788) (xy 147.588917 -389.668702) (xy 147.560578 -389.630795) (xy 147.549108 -389.610092)
			(xy 147.548854 -389.60933) (xy 147.5359 -389.586978) (xy 147.530521 -389.578532) (xy 147.514631 -389.56637)
			(xy 147.495297 -389.561214) (xy 147.475462 -389.563847) (xy 147.466558 -389.568436) (xy 147.457414 -389.57377)
			(xy 147.451318 -389.582152) (xy 147.440419 -389.596075) (xy 147.414327 -389.619935) (xy 147.384294 -389.638592)
			(xy 147.351342 -389.651408) (xy 147.316596 -389.657949) (xy 147.298918 -389.658352) (xy 147.29841 -389.658352)
			(xy 147.279633 -389.657894) (xy 147.2428 -389.650575) (xy 147.2081 -389.636216) (xy 147.176865 -389.615369)
			(xy 147.150293 -389.588832) (xy 147.129404 -389.557625) (xy 147.114999 -389.522944) (xy 147.107631 -389.48612)
			(xy 147.107148 -389.467344) (xy 147.107562 -389.448227) (xy 147.115133 -389.410751) (xy 147.130003 -389.375527)
			(xy 147.151578 -389.343962) (xy 147.178997 -389.317316) (xy 147.211166 -389.296652) (xy 147.228814 -389.28929)
			(xy 147.238974 -389.285226) (xy 147.254468 -389.269478) (xy 147.283678 -389.186166) (xy 147.286867 -389.175579)
			(xy 147.284911 -389.153585) (xy 147.279868 -389.143748) (xy 147.151598 -388.922006) (xy 147.13966 -388.897876)
			(xy 147.13489 -388.888322) (xy 147.11909 -388.873987) (xy 147.09883 -388.867301) (xy 147.077601 -388.869416)
			(xy 147.059059 -388.879966) (xy 147.052284 -388.888224) (xy 147.041385 -388.902308) (xy 147.015237 -388.92648)
			(xy 146.985065 -388.945392) (xy 146.951912 -388.95839) (xy 146.916926 -388.965024) (xy 146.899122 -388.96544)
			(xy 146.898614 -388.96544) (xy 146.878592 -388.964891) (xy 146.839422 -388.956568) (xy 146.802839 -388.940282)
			(xy 146.770441 -388.916746) (xy 146.743645 -388.886988) (xy 146.723622 -388.852309) (xy 146.711247 -388.814225)
			(xy 146.707061 -388.7744) (xy 133.243612 -388.7744) (xy 133.555994 -389.314944) (xy 133.556248 -389.315452)
			(xy 133.556502 -389.315452) (xy 133.557772 -389.317992) (xy 133.570041 -389.340909) (xy 133.587449 -389.389886)
			(xy 133.596324 -389.441102) (xy 133.596888 -389.46709) (xy 133.596888 -389.467344) (xy 133.596479 -389.491325)
			(xy 133.588974 -389.538695) (xy 133.574154 -389.58431) (xy 133.552386 -389.627047) (xy 133.524203 -389.665855)
			(xy 133.4903 -389.69978) (xy 133.451509 -389.727986) (xy 133.408786 -389.749782) (xy 133.36318 -389.764629)
			(xy 133.315814 -389.772164) (xy 133.291834 -389.772652) (xy 133.291326 -389.772652) (xy 133.267662 -389.772192)
			(xy 133.220902 -389.764885) (xy 133.175827 -389.750458) (xy 133.133515 -389.729255) (xy 133.094977 -389.701783)
			(xy 133.061134 -389.6687) (xy 133.032795 -389.630795) (xy 133.021324 -389.610092) (xy 133.02107 -389.60933)
			(xy 133.008116 -389.586978) (xy 133.002721 -389.578544) (xy 132.986837 -389.566382) (xy 132.967509 -389.561222)
			(xy 132.947677 -389.56385) (xy 132.938774 -389.568436) (xy 132.92963 -389.57377) (xy 132.923534 -389.582152)
			(xy 132.912626 -389.596067) (xy 132.886537 -389.619928) (xy 132.856505 -389.638586) (xy 132.823556 -389.651405)
			(xy 132.788811 -389.657947) (xy 132.771134 -389.658352) (xy 132.770626 -389.658352) (xy 132.75185 -389.657879)
			(xy 132.715017 -389.650564) (xy 132.680317 -389.636208) (xy 132.649082 -389.615362) (xy 132.622509 -389.588827)
			(xy 132.60162 -389.557622) (xy 132.587215 -389.522942) (xy 132.579847 -389.48612) (xy 132.579364 -389.467344)
			(xy 132.579768 -389.448226) (xy 132.58734 -389.410749) (xy 132.602212 -389.375524) (xy 132.623789 -389.34396)
			(xy 132.65121 -389.317314) (xy 132.68338 -389.296651) (xy 132.70103 -389.28929) (xy 132.71119 -389.285226)
			(xy 132.726684 -389.269478) (xy 132.755894 -389.186166) (xy 132.759092 -389.175581) (xy 132.757133 -389.153584)
			(xy 132.752084 -389.143748) (xy 132.623814 -388.922006) (xy 132.611876 -388.897876) (xy 132.607084 -388.888335)
			(xy 132.59129 -388.874002) (xy 132.571037 -388.867315) (xy 132.549813 -388.869425) (xy 132.531274 -388.87997)
			(xy 132.5245 -388.888224) (xy 132.513592 -388.9023) (xy 132.487446 -388.926473) (xy 132.457276 -388.945386)
			(xy 132.424126 -388.958386) (xy 132.389142 -388.965023) (xy 132.371338 -388.96544) (xy 132.37083 -388.96544)
			(xy 132.343144 -388.963408) (xy 132.34289 -388.963408) (xy 132.333421 -388.962447) (xy 132.314903 -388.96678)
			(xy 132.299252 -388.977584) (xy 132.293614 -388.985252) (xy 132.242052 -389.060944) (xy 132.237029 -389.069077)
			(xy 132.232865 -389.087721) (xy 132.235802 -389.106597) (xy 132.240274 -389.115046) (xy 132.355844 -389.314944)
			(xy 132.356098 -389.315452) (xy 132.356352 -389.315452) (xy 132.357622 -389.317992) (xy 132.369855 -389.340916)
			(xy 132.387175 -389.389902) (xy 132.395962 -389.441111) (xy 132.396484 -389.46709) (xy 132.396484 -389.467344)
			(xy 132.396078 -389.491338) (xy 132.388564 -389.538733) (xy 132.37373 -389.58437) (xy 132.351938 -389.627124)
			(xy 132.323728 -389.665943) (xy 132.289792 -389.699872) (xy 132.250966 -389.728074) (xy 132.208207 -389.749856)
			(xy 132.162567 -389.76468) (xy 132.11517 -389.772183) (xy 132.091176 -389.772652) (xy 132.067511 -389.772232)
			(xy 132.020749 -389.764918) (xy 131.975673 -389.750483) (xy 131.933361 -389.729274) (xy 131.894823 -389.701796)
			(xy 131.860981 -389.668707) (xy 131.832644 -389.630797) (xy 131.821174 -389.610092) (xy 131.82092 -389.60933)
			(xy 131.807966 -389.586978) (xy 131.80252 -389.578581) (xy 131.786654 -389.566419) (xy 131.767344 -389.56125)
			(xy 131.747524 -389.563861) (xy 131.738624 -389.568436) (xy 131.72948 -389.57377) (xy 131.723384 -389.582152)
			(xy 131.712447 -389.596043) (xy 131.686365 -389.619906) (xy 131.656341 -389.638568) (xy 131.623398 -389.651393)
			(xy 131.588659 -389.657943) (xy 131.570984 -389.658352) (xy 131.570476 -389.658352) (xy 131.551711 -389.65787)
			(xy 131.514901 -389.650545) (xy 131.480228 -389.636181) (xy 131.449022 -389.615331) (xy 131.422482 -389.588794)
			(xy 131.401628 -389.55759) (xy 131.387261 -389.522918) (xy 131.379932 -389.486109) (xy 131.379468 -389.467344)
			(xy 131.379943 -389.448249) (xy 131.387504 -389.410816) (xy 131.402336 -389.375624) (xy 131.423848 -389.34407)
			(xy 131.451189 -389.317406) (xy 131.483272 -389.296691) (xy 131.50088 -389.28929) (xy 131.51104 -389.285226)
			(xy 131.526534 -389.269478) (xy 131.555744 -389.186166) (xy 131.558936 -389.17558) (xy 131.55698 -389.153585)
			(xy 131.551934 -389.143748) (xy 131.423664 -388.922006) (xy 131.411726 -388.897876) (xy 131.406863 -388.888376)
			(xy 131.391089 -388.874049) (xy 131.370857 -388.867358) (xy 131.349652 -388.869456) (xy 131.331123 -388.879981)
			(xy 131.32435 -388.888224) (xy 131.313396 -388.902295) (xy 131.287214 -388.926497) (xy 131.256998 -388.945425)
			(xy 131.223797 -388.958423) (xy 131.188761 -388.96504) (xy 131.170934 -388.96544) (xy 131.170426 -388.96544)
			(xy 131.163546 -388.965435) (xy 131.149816 -388.964547) (xy 131.142994 -388.963662) (xy 131.128516 -388.961376)
			(xy 131.101846 -388.97306) (xy 131.042156 -389.060944) (xy 131.037133 -389.069077) (xy 131.032968 -389.087721)
			(xy 131.035905 -389.106597) (xy 131.040378 -389.115046) (xy 131.155948 -389.314944) (xy 131.156202 -389.315452)
			(xy 131.156456 -389.315452) (xy 131.157726 -389.317992) (xy 131.16996 -389.340916) (xy 131.187279 -389.389902)
			(xy 131.196066 -389.441111) (xy 131.196588 -389.46709) (xy 131.196588 -389.467344) (xy 131.196178 -389.491337)
			(xy 131.188665 -389.538733) (xy 131.17383 -389.584369) (xy 131.152039 -389.627123) (xy 131.123829 -389.665942)
			(xy 131.089893 -389.69987) (xy 131.051068 -389.728073) (xy 131.00831 -389.749854) (xy 130.96267 -389.76468)
			(xy 130.915274 -389.772183) (xy 130.89128 -389.772652) (xy 130.867615 -389.772229) (xy 130.820853 -389.764915)
			(xy 130.775777 -389.750481) (xy 130.733465 -389.729272) (xy 130.694927 -389.701795) (xy 130.661085 -389.668706)
			(xy 130.632748 -389.630797) (xy 130.621278 -389.610092) (xy 130.621024 -389.60933) (xy 130.60807 -389.586978)
			(xy 130.60262 -389.578584) (xy 130.586756 -389.566422) (xy 130.567446 -389.561252) (xy 130.547628 -389.563862)
			(xy 130.538728 -389.568436) (xy 130.529584 -389.57377) (xy 130.523488 -389.582152) (xy 130.512549 -389.596041)
			(xy 130.486468 -389.619905) (xy 130.456444 -389.638567) (xy 130.423502 -389.651392) (xy 130.388763 -389.657942)
			(xy 130.371088 -389.658352) (xy 130.37058 -389.658352) (xy 130.351815 -389.657866) (xy 130.315006 -389.650542)
			(xy 130.280332 -389.636179) (xy 130.249126 -389.615329) (xy 130.222586 -389.588792) (xy 130.201732 -389.557589)
			(xy 130.187365 -389.522917) (xy 130.180036 -389.486109) (xy 130.179572 -389.467344) (xy 130.180044 -389.448249)
			(xy 130.187606 -389.410815) (xy 130.202438 -389.375623) (xy 130.223951 -389.344069) (xy 130.251292 -389.317405)
			(xy 130.283375 -389.296691) (xy 130.300984 -389.28929) (xy 130.311144 -389.285226) (xy 130.326638 -389.269478)
			(xy 130.355848 -389.186166) (xy 130.35904 -389.17558) (xy 130.357084 -389.153584) (xy 130.352038 -389.143748)
			(xy 130.223768 -388.922006) (xy 130.21183 -388.897876) (xy 130.206962 -388.888379) (xy 130.191189 -388.874053)
			(xy 130.170959 -388.867362) (xy 130.149755 -388.869458) (xy 130.131227 -388.879982) (xy 130.124454 -388.888224)
			(xy 130.113515 -388.902275) (xy 130.087377 -388.926449) (xy 130.057215 -388.945367) (xy 130.024071 -388.958373)
			(xy 129.989093 -388.965018) (xy 129.971292 -388.96544) (xy 129.970784 -388.96544) (xy 129.943098 -388.963408)
			(xy 129.942844 -388.963408) (xy 129.933376 -388.96241) (xy 129.914854 -388.966759) (xy 129.899203 -388.977578)
			(xy 129.893568 -388.985252) (xy 129.842006 -389.060944) (xy 129.83698 -389.069077) (xy 129.832811 -389.087721)
			(xy 129.835752 -389.106598) (xy 129.840228 -389.115046) (xy 129.955798 -389.314944) (xy 129.956052 -389.315452)
			(xy 129.956306 -389.315452) (xy 129.957576 -389.317992) (xy 129.969845 -389.340909) (xy 129.987253 -389.389886)
			(xy 129.996128 -389.441102) (xy 129.996692 -389.46709) (xy 129.996692 -389.467344) (xy 129.996279 -389.491325)
			(xy 129.988774 -389.538695) (xy 129.973955 -389.584309) (xy 129.952187 -389.627046) (xy 129.924004 -389.665854)
			(xy 129.890101 -389.699778) (xy 129.851312 -389.727985) (xy 129.808589 -389.74978) (xy 129.762984 -389.764628)
			(xy 129.715618 -389.772164) (xy 129.691638 -389.772652) (xy 129.69113 -389.772652) (xy 129.667466 -389.772188)
			(xy 129.620707 -389.764882) (xy 129.575632 -389.750456) (xy 129.533319 -389.729254) (xy 129.494781 -389.701782)
			(xy 129.460938 -389.668699) (xy 129.432599 -389.630794) (xy 129.421128 -389.610092) (xy 129.420874 -389.60933)
			(xy 129.40792 -389.586978) (xy 129.402521 -389.578547) (xy 129.386638 -389.566385) (xy 129.367311 -389.561225)
			(xy 129.347481 -389.563851) (xy 129.338578 -389.568436) (xy 129.329434 -389.57377) (xy 129.323338 -389.582152)
			(xy 129.312427 -389.596065) (xy 129.286339 -389.619926) (xy 129.256308 -389.638584) (xy 129.223359 -389.651404)
			(xy 129.188615 -389.657947) (xy 129.170938 -389.658352) (xy 129.17043 -389.658352) (xy 129.151654 -389.657876)
			(xy 129.114821 -389.650561) (xy 129.080121 -389.636205) (xy 129.048886 -389.615361) (xy 129.022314 -389.588826)
			(xy 129.001424 -389.557621) (xy 128.987019 -389.522942) (xy 128.979651 -389.486119) (xy 128.979168 -389.467344)
			(xy 128.979569 -389.448226) (xy 128.987142 -389.410748) (xy 129.002014 -389.375524) (xy 129.023591 -389.343959)
			(xy 129.051013 -389.317313) (xy 129.083184 -389.296651) (xy 129.100834 -389.28929) (xy 129.110994 -389.285226)
			(xy 129.126488 -389.269478) (xy 129.155698 -389.186166) (xy 129.158896 -389.17558) (xy 129.156937 -389.153584)
			(xy 129.151888 -389.143748) (xy 129.023618 -388.922006) (xy 129.01168 -388.897876) (xy 129.006882 -388.888338)
			(xy 128.991089 -388.874006) (xy 128.970838 -388.867319) (xy 128.949617 -388.869428) (xy 128.931078 -388.879971)
			(xy 128.924304 -388.888224) (xy 128.913377 -388.902317) (xy 128.887188 -388.926517) (xy 128.856965 -388.945442)
			(xy 128.823758 -388.958434) (xy 128.788717 -388.965044) (xy 128.770888 -388.96544) (xy 128.77038 -388.96544)
			(xy 128.7635 -388.96544) (xy 128.74977 -388.964548) (xy 128.742948 -388.963662) (xy 128.72847 -388.961376)
			(xy 128.7018 -388.97306) (xy 128.64211 -389.060944) (xy 128.637084 -389.069077) (xy 128.632915 -389.087721)
			(xy 128.635855 -389.106598) (xy 128.640332 -389.115046) (xy 128.755902 -389.314944) (xy 128.756156 -389.315452)
			(xy 128.75641 -389.315452) (xy 128.75768 -389.317992) (xy 128.769949 -389.340909) (xy 128.787357 -389.389886)
			(xy 128.796232 -389.441102) (xy 128.796796 -389.46709) (xy 128.796796 -389.467344) (xy 128.796379 -389.491324)
			(xy 128.788874 -389.538694) (xy 128.774055 -389.584308) (xy 128.752287 -389.627045) (xy 128.724106 -389.665852)
			(xy 128.690203 -389.699777) (xy 128.651414 -389.727984) (xy 128.608692 -389.749779) (xy 128.563087 -389.764628)
			(xy 128.515722 -389.772163) (xy 128.491742 -389.772652) (xy 128.491234 -389.772652) (xy 128.467571 -389.772185)
			(xy 128.420811 -389.76488) (xy 128.375736 -389.750454) (xy 128.333424 -389.729252) (xy 128.294885 -389.701781)
			(xy 128.261042 -389.668699) (xy 128.232703 -389.630794) (xy 128.221232 -389.610092) (xy 128.220978 -389.60933)
			(xy 128.208024 -389.586978) (xy 128.202621 -389.57855) (xy 128.18674 -389.566388) (xy 128.167414 -389.561227)
			(xy 128.147584 -389.563852) (xy 128.138682 -389.568436) (xy 128.129538 -389.57377) (xy 128.123442 -389.582152)
			(xy 128.112529 -389.596063) (xy 128.086441 -389.619925) (xy 128.056411 -389.638583) (xy 128.023463 -389.651403)
			(xy 127.988719 -389.657946) (xy 127.971042 -389.658352) (xy 127.970534 -389.658352) (xy 127.951758 -389.657872)
			(xy 127.914926 -389.650558) (xy 127.880226 -389.636203) (xy 127.84899 -389.615359) (xy 127.822418 -389.588825)
			(xy 127.801528 -389.55762) (xy 127.787123 -389.522941) (xy 127.779755 -389.486119) (xy 127.779272 -389.467344)
			(xy 127.77967 -389.448226) (xy 127.787243 -389.410748) (xy 127.802116 -389.375523) (xy 127.823694 -389.343958)
			(xy 127.851116 -389.317313) (xy 127.883288 -389.296651) (xy 127.900938 -389.28929) (xy 127.911098 -389.285226)
			(xy 127.926592 -389.269478) (xy 127.955802 -389.186166) (xy 127.959 -389.17558) (xy 127.957041 -389.153584)
			(xy 127.951992 -389.143748) (xy 127.823722 -388.922006) (xy 127.811784 -388.897876) (xy 127.80698 -388.888342)
			(xy 127.791189 -388.87401) (xy 127.77094 -388.867322) (xy 127.74972 -388.869431) (xy 127.731182 -388.879972)
			(xy 127.724408 -388.888224) (xy 127.713479 -388.902315) (xy 127.68729 -388.926516) (xy 127.657068 -388.94544)
			(xy 127.623861 -388.958433) (xy 127.588821 -388.965043) (xy 127.570992 -388.96544) (xy 127.570484 -388.96544)
			(xy 127.563604 -388.96544) (xy 127.549874 -388.964548) (xy 127.543052 -388.963662) (xy 127.528574 -388.961376)
			(xy 127.501904 -388.97306) (xy 127.442214 -389.060944) (xy 127.437188 -389.069077) (xy 127.433019 -389.087721)
			(xy 127.43596 -389.106598) (xy 127.440436 -389.115046) (xy 127.556006 -389.314944) (xy 127.55626 -389.315452)
			(xy 127.556514 -389.315452) (xy 127.557784 -389.317992) (xy 127.570054 -389.340909) (xy 127.587461 -389.389886)
			(xy 127.596336 -389.441101) (xy 127.5969 -389.46709) (xy 127.5969 -389.467344) (xy 127.596479 -389.491324)
			(xy 127.588974 -389.538694) (xy 127.574156 -389.584307) (xy 127.552388 -389.627044) (xy 127.524207 -389.665851)
			(xy 127.490305 -389.699775) (xy 127.451516 -389.727982) (xy 127.408794 -389.749778) (xy 127.36319 -389.764627)
			(xy 127.315826 -389.772163) (xy 127.291846 -389.772652) (xy 127.291338 -389.772652) (xy 127.267675 -389.772182)
			(xy 127.220915 -389.764877) (xy 127.17584 -389.750452) (xy 127.133528 -389.729251) (xy 127.094989 -389.70178)
			(xy 127.061146 -389.668698) (xy 127.032807 -389.630794) (xy 127.021336 -389.610092) (xy 127.021082 -389.60933)
			(xy 127.008128 -389.586978) (xy 127.002721 -389.578553) (xy 126.986841 -389.566391) (xy 126.967517 -389.561229)
			(xy 126.947688 -389.563853) (xy 126.938786 -389.568436) (xy 126.929642 -389.57377) (xy 126.923546 -389.582152)
			(xy 126.912631 -389.596061) (xy 126.886543 -389.619923) (xy 126.856514 -389.638582) (xy 126.823566 -389.651402)
			(xy 126.788823 -389.657946) (xy 126.771146 -389.658352) (xy 126.770638 -389.658352) (xy 126.751862 -389.657869)
			(xy 126.71503 -389.650555) (xy 126.68033 -389.636201) (xy 126.649095 -389.615357) (xy 126.622522 -389.588824)
			(xy 126.601632 -389.557619) (xy 126.587227 -389.522941) (xy 126.579859 -389.486119) (xy 126.579376 -389.467344)
			(xy 126.579835 -389.44823) (xy 126.587403 -389.410759) (xy 126.602267 -389.375539) (xy 126.623833 -389.343975)
			(xy 126.651241 -389.317327) (xy 126.683399 -389.296657) (xy 126.701042 -389.28929) (xy 126.711202 -389.285226)
			(xy 126.726696 -389.269478) (xy 126.755906 -389.186166) (xy 126.759103 -389.17558) (xy 126.757145 -389.153584)
			(xy 126.752096 -389.143748) (xy 126.623826 -388.922006) (xy 126.611888 -388.897876) (xy 126.607079 -388.888345)
			(xy 126.591289 -388.874013) (xy 126.571042 -388.867326) (xy 126.549823 -388.869433) (xy 126.531286 -388.879973)
			(xy 126.524512 -388.888224) (xy 126.513597 -388.902295) (xy 126.487453 -388.926468) (xy 126.457285 -388.945382)
			(xy 126.424136 -388.958383) (xy 126.389153 -388.965022) (xy 126.37135 -388.96544) (xy 126.370842 -388.96544)
			(xy 126.343156 -388.963408) (xy 126.342902 -388.963408) (xy 126.333432 -388.962456) (xy 126.314915 -388.966785)
			(xy 126.299264 -388.977586) (xy 126.293626 -388.985252) (xy 126.242064 -389.060944) (xy 126.23704 -389.069077)
			(xy 126.232875 -389.087721) (xy 126.235813 -389.106597) (xy 126.240286 -389.115046) (xy 126.355856 -389.314944)
			(xy 126.35611 -389.315452) (xy 126.356364 -389.315452) (xy 126.357634 -389.317992) (xy 126.369868 -389.340915)
			(xy 126.387188 -389.389902) (xy 126.395975 -389.441111) (xy 126.396496 -389.46709) (xy 126.396496 -389.467344)
			(xy 126.396078 -389.491337) (xy 126.388565 -389.538731) (xy 126.373731 -389.584367) (xy 126.351941 -389.627121)
			(xy 126.323731 -389.665939) (xy 126.289797 -389.699868) (xy 126.250973 -389.72807) (xy 126.208215 -389.749852)
			(xy 126.162577 -389.764678) (xy 126.115181 -389.772182) (xy 126.091188 -389.772652) (xy 126.067523 -389.772222)
			(xy 126.020762 -389.76491) (xy 125.975686 -389.750477) (xy 125.933374 -389.729269) (xy 125.894836 -389.701793)
			(xy 125.860994 -389.668705) (xy 125.832656 -389.630796) (xy 125.821186 -389.610092) (xy 125.820932 -389.60933)
			(xy 125.807978 -389.586978) (xy 125.80252 -389.57859) (xy 125.786659 -389.566428) (xy 125.767352 -389.561257)
			(xy 125.747536 -389.563864) (xy 125.738636 -389.568436) (xy 125.729492 -389.57377) (xy 125.723396 -389.582152)
			(xy 125.712453 -389.596038) (xy 125.686372 -389.619901) (xy 125.65635 -389.638564) (xy 125.623408 -389.65139)
			(xy 125.588671 -389.657942) (xy 125.570996 -389.658352) (xy 125.570488 -389.658352) (xy 125.551723 -389.657859)
			(xy 125.514914 -389.650536) (xy 125.480241 -389.636175) (xy 125.449035 -389.615326) (xy 125.422495 -389.58879)
			(xy 125.40164 -389.557587) (xy 125.387273 -389.522916) (xy 125.379944 -389.486109) (xy 125.37948 -389.467344)
			(xy 125.379947 -389.448249) (xy 125.387509 -389.410814) (xy 125.402342 -389.375622) (xy 125.423856 -389.344067)
			(xy 125.451198 -389.317404) (xy 125.483283 -389.29669) (xy 125.500892 -389.28929) (xy 125.511052 -389.285226)
			(xy 125.526546 -389.269478) (xy 125.555756 -389.186166) (xy 125.558947 -389.175579) (xy 125.556991 -389.153585)
			(xy 125.551946 -389.143748) (xy 125.423676 -388.922006) (xy 125.411738 -388.897876) (xy 125.406858 -388.888386)
			(xy 125.391089 -388.87406) (xy 125.370862 -388.867369) (xy 125.349661 -388.869464) (xy 125.331135 -388.879984)
			(xy 125.324362 -388.888224) (xy 125.313402 -388.90229) (xy 125.287221 -388.926492) (xy 125.257007 -388.945421)
			(xy 125.223807 -388.95842) (xy 125.188773 -388.965039) (xy 125.170946 -388.96544) (xy 125.170438 -388.96544)
			(xy 125.163558 -388.965434) (xy 125.149829 -388.964546) (xy 125.143006 -388.963662) (xy 125.128528 -388.961376)
			(xy 125.101858 -388.97306) (xy 125.042168 -389.060944) (xy 125.037144 -389.069077) (xy 125.032979 -389.087721)
			(xy 125.035917 -389.106597) (xy 125.04039 -389.115046) (xy 125.15596 -389.314944) (xy 125.156214 -389.315452)
			(xy 125.156468 -389.315452) (xy 125.157738 -389.317992) (xy 125.169973 -389.340915) (xy 125.187292 -389.389902)
			(xy 125.196079 -389.441111) (xy 125.1966 -389.46709) (xy 125.1966 -389.467344) (xy 125.196178 -389.491337)
			(xy 125.188665 -389.538731) (xy 125.173831 -389.584366) (xy 125.152041 -389.627119) (xy 125.123832 -389.665938)
			(xy 125.089898 -389.699866) (xy 125.051075 -389.728069) (xy 125.008318 -389.749851) (xy 124.96268 -389.764677)
			(xy 124.915285 -389.772182) (xy 124.891292 -389.772652) (xy 124.867627 -389.772219) (xy 124.820866 -389.764907)
			(xy 124.77579 -389.750475) (xy 124.733478 -389.729268) (xy 124.69494 -389.701792) (xy 124.661098 -389.668705)
			(xy 124.63276 -389.630796) (xy 124.62129 -389.610092) (xy 124.621036 -389.60933) (xy 124.608082 -389.586978)
			(xy 124.60262 -389.578593) (xy 124.58676 -389.566431) (xy 124.567455 -389.561259) (xy 124.547639 -389.563864)
			(xy 124.53874 -389.568436) (xy 124.529596 -389.57377) (xy 124.5235 -389.582152) (xy 124.512554 -389.596036)
			(xy 124.486475 -389.619899) (xy 124.456453 -389.638562) (xy 124.423512 -389.651389) (xy 124.388774 -389.657941)
			(xy 124.3711 -389.658352) (xy 124.370592 -389.658352) (xy 124.351827 -389.657856) (xy 124.315019 -389.650534)
			(xy 124.280345 -389.636172) (xy 124.249139 -389.615324) (xy 124.222599 -389.588789) (xy 124.201745 -389.557587)
			(xy 124.187377 -389.522916) (xy 124.180048 -389.486109) (xy 124.179584 -389.467344) (xy 124.180049 -389.448248)
			(xy 124.187611 -389.410814) (xy 124.202444 -389.375621) (xy 124.223958 -389.344067) (xy 124.251301 -389.317404)
			(xy 124.283387 -389.29669) (xy 124.300996 -389.28929) (xy 124.311156 -389.285226) (xy 124.32665 -389.269478)
			(xy 124.35586 -389.186166) (xy 124.359051 -389.175579) (xy 124.357095 -389.153585) (xy 124.35205 -389.143748)
			(xy 124.22378 -388.922006) (xy 124.211842 -388.897876) (xy 124.207097 -388.888307) (xy 124.19129 -388.87397)
			(xy 124.171023 -388.867286) (xy 124.149788 -388.869405) (xy 124.131241 -388.879962) (xy 124.124466 -388.888224)
			(xy 124.11352 -388.902269) (xy 124.087384 -388.926444) (xy 124.057223 -388.945362) (xy 124.024082 -388.95837)
			(xy 123.989105 -388.965017) (xy 123.971304 -388.96544) (xy 123.970796 -388.96544) (xy 123.94311 -388.963408)
			(xy 123.942856 -388.963408) (xy 123.933388 -388.96242) (xy 123.914867 -388.966764) (xy 123.899216 -388.977579)
			(xy 123.89358 -388.985252) (xy 123.842018 -389.060944) (xy 123.836992 -389.069077) (xy 123.832822 -389.087721)
			(xy 123.835763 -389.106598) (xy 123.84024 -389.115046) (xy 123.95581 -389.314944) (xy 123.956064 -389.315452)
			(xy 123.956318 -389.315452) (xy 123.957588 -389.317992) (xy 123.969858 -389.340908) (xy 123.987265 -389.389886)
			(xy 123.99614 -389.441101) (xy 123.996704 -389.46709) (xy 123.996704 -389.467344) (xy 123.996279 -389.491324)
			(xy 123.988774 -389.538693) (xy 123.973956 -389.584307) (xy 123.952189 -389.627042) (xy 123.924008 -389.66585)
			(xy 123.890106 -389.699774) (xy 123.851318 -389.727981) (xy 123.808597 -389.749777) (xy 123.762994 -389.764626)
			(xy 123.71563 -389.772163) (xy 123.69165 -389.772652) (xy 123.691142 -389.772652) (xy 123.667479 -389.772179)
			(xy 123.620719 -389.764875) (xy 123.575645 -389.75045) (xy 123.533332 -389.729249) (xy 123.494794 -389.701779)
			(xy 123.46095 -389.668697) (xy 123.432611 -389.630794) (xy 123.42114 -389.610092) (xy 123.420886 -389.60933)
			(xy 123.407932 -389.586978) (xy 123.40252 -389.578556) (xy 123.386643 -389.566394) (xy 123.36732 -389.561231)
			(xy 123.347492 -389.563854) (xy 123.33859 -389.568436) (xy 123.329446 -389.57377) (xy 123.32335 -389.582152)
			(xy 123.312433 -389.596059) (xy 123.286346 -389.619921) (xy 123.256317 -389.63858) (xy 123.223369 -389.651401)
			(xy 123.188626 -389.657946) (xy 123.17095 -389.658352) (xy 123.170442 -389.658352) (xy 123.151666 -389.657865)
			(xy 123.114834 -389.650552) (xy 123.080134 -389.636199) (xy 123.048899 -389.615356) (xy 123.022326 -389.588823)
			(xy 123.001437 -389.557618) (xy 122.987031 -389.52294) (xy 122.979663 -389.486119) (xy 122.97918 -389.467344)
			(xy 122.979636 -389.44823) (xy 122.987205 -389.410758) (xy 123.002069 -389.375538) (xy 123.023635 -389.343975)
			(xy 123.051044 -389.317326) (xy 123.083202 -389.296656) (xy 123.100846 -389.28929) (xy 123.111006 -389.285226)
			(xy 123.1265 -389.269478) (xy 123.15571 -389.186166) (xy 123.158907 -389.17558) (xy 123.156949 -389.153584)
			(xy 123.1519 -389.143748) (xy 123.02363 -388.922006) (xy 123.011692 -388.897876) (xy 123.006877 -388.888348)
			(xy 122.991089 -388.874017) (xy 122.970843 -388.867329) (xy 122.949626 -388.869435) (xy 122.93109 -388.879973)
			(xy 122.924316 -388.888224) (xy 122.913382 -388.902312) (xy 122.887194 -388.926512) (xy 122.856974 -388.945437)
			(xy 122.823768 -388.958431) (xy 122.788729 -388.965043) (xy 122.7709 -388.96544) (xy 122.770392 -388.96544)
			(xy 122.763512 -388.965439) (xy 122.749782 -388.964548) (xy 122.74296 -388.963662) (xy 122.728482 -388.961376)
			(xy 122.701812 -388.97306) (xy 122.642122 -389.060944) (xy 122.637096 -389.069077) (xy 122.632926 -389.087721)
			(xy 122.635867 -389.106598) (xy 122.640344 -389.115046) (xy 122.755914 -389.314944) (xy 122.756168 -389.315452)
			(xy 122.756422 -389.315452) (xy 122.757692 -389.317992) (xy 122.769962 -389.340908) (xy 122.787369 -389.389886)
			(xy 122.796244 -389.441101) (xy 122.796808 -389.46709) (xy 122.796808 -389.467344) (xy 122.796379 -389.491324)
			(xy 122.788874 -389.538693) (xy 122.774056 -389.584306) (xy 122.752289 -389.627041) (xy 122.724109 -389.665848)
			(xy 122.690208 -389.699772) (xy 122.65142 -389.72798) (xy 122.6087 -389.749776) (xy 122.563097 -389.764625)
			(xy 122.515733 -389.772162) (xy 122.491754 -389.772652) (xy 122.491246 -389.772652) (xy 122.467583 -389.772176)
			(xy 122.420824 -389.764872) (xy 122.375749 -389.750448) (xy 122.333437 -389.729248) (xy 122.294898 -389.701778)
			(xy 122.261054 -389.668697) (xy 122.232715 -389.630794) (xy 122.221244 -389.610092) (xy 122.22099 -389.60933)
			(xy 122.208036 -389.586978) (xy 122.20262 -389.578559) (xy 122.186744 -389.566397) (xy 122.167423 -389.561233)
			(xy 122.147596 -389.563854) (xy 122.138694 -389.568436) (xy 122.12955 -389.57377) (xy 122.123454 -389.582152)
			(xy 122.112534 -389.596058) (xy 122.086448 -389.619919) (xy 122.05642 -389.638579) (xy 122.023473 -389.6514)
			(xy 121.98873 -389.657945) (xy 121.971054 -389.658352) (xy 121.970546 -389.658352) (xy 121.95177 -389.657861)
			(xy 121.914938 -389.650549) (xy 121.880239 -389.636196) (xy 121.849003 -389.615354) (xy 121.822431 -389.588822)
			(xy 121.801541 -389.557618) (xy 121.787135 -389.52294) (xy 121.779767 -389.486119) (xy 121.779284 -389.467344)
			(xy 121.779738 -389.448229) (xy 121.787306 -389.410758) (xy 121.802171 -389.375538) (xy 121.823738 -389.343974)
			(xy 121.851147 -389.317326) (xy 121.883306 -389.296656) (xy 121.90095 -389.28929) (xy 121.91111 -389.285226)
			(xy 121.926604 -389.269478) (xy 121.955814 -389.186166) (xy 121.95901 -389.17558) (xy 121.957052 -389.153584)
			(xy 121.952004 -389.143748) (xy 121.823734 -388.922006) (xy 121.811796 -388.897876) (xy 121.806975 -388.888351)
			(xy 121.791189 -388.874021) (xy 121.770945 -388.867332) (xy 121.749729 -388.869438) (xy 121.731194 -388.879974)
			(xy 121.72442 -388.888224) (xy 121.713484 -388.90231) (xy 121.687297 -388.92651) (xy 121.657077 -388.945436)
			(xy 121.623871 -388.95843) (xy 121.588833 -388.965042) (xy 121.571004 -388.96544) (xy 121.570496 -388.96544)
			(xy 121.563616 -388.965439) (xy 121.549886 -388.964548) (xy 121.543064 -388.963662) (xy 121.528586 -388.961376)
			(xy 121.501916 -388.97306) (xy 121.442226 -389.060944) (xy 121.437199 -389.069077) (xy 121.433029 -389.087721)
			(xy 121.435971 -389.106598) (xy 121.440448 -389.115046) (xy 121.556018 -389.314944) (xy 121.556272 -389.315452)
			(xy 121.556526 -389.315452) (xy 121.557796 -389.317992) (xy 121.570067 -389.340908) (xy 121.587474 -389.389886)
			(xy 121.596348 -389.441101) (xy 121.596912 -389.46709) (xy 121.596912 -389.467344) (xy 121.596479 -389.491324)
			(xy 121.588974 -389.538692) (xy 121.574157 -389.584305) (xy 121.55239 -389.62704) (xy 121.52421 -389.665847)
			(xy 121.49031 -389.699771) (xy 121.451523 -389.727978) (xy 121.408803 -389.749775) (xy 121.3632 -389.764624)
			(xy 121.315837 -389.772162) (xy 121.291858 -389.772652) (xy 121.29135 -389.772652) (xy 121.267687 -389.772172)
			(xy 121.220928 -389.764869) (xy 121.175853 -389.750446) (xy 121.133541 -389.729246) (xy 121.095002 -389.701777)
			(xy 121.061159 -389.668696) (xy 121.032819 -389.630793) (xy 121.021348 -389.610092) (xy 121.021094 -389.60933)
			(xy 121.00814 -389.586978) (xy 121.00272 -389.578562) (xy 120.986845 -389.566399) (xy 120.967525 -389.561236)
			(xy 120.947699 -389.563855) (xy 120.938798 -389.568436) (xy 120.929654 -389.57377) (xy 120.923558 -389.582152)
			(xy 120.912636 -389.596056) (xy 120.88655 -389.619918) (xy 120.856523 -389.638577) (xy 120.823576 -389.651399)
			(xy 120.788834 -389.657945) (xy 120.771158 -389.658352) (xy 120.77065 -389.658352) (xy 120.751875 -389.657858)
			(xy 120.715043 -389.650546) (xy 120.680343 -389.636194) (xy 120.649107 -389.615352) (xy 120.622535 -389.58882)
			(xy 120.601645 -389.557617) (xy 120.587239 -389.522939) (xy 120.579871 -389.486119) (xy 120.579388 -389.467344)
			(xy 120.579839 -389.448229) (xy 120.587408 -389.410757) (xy 120.602273 -389.375537) (xy 120.62384 -389.343973)
			(xy 120.651251 -389.317325) (xy 120.68341 -389.296656) (xy 120.701054 -389.28929) (xy 120.711214 -389.285226)
			(xy 120.726708 -389.269478) (xy 120.755918 -389.186166) (xy 120.759114 -389.17558) (xy 120.757156 -389.153584)
			(xy 120.752108 -389.143748) (xy 120.623838 -388.922006) (xy 120.6119 -388.897876) (xy 120.607074 -388.888355)
			(xy 120.591289 -388.874025) (xy 120.571047 -388.867336) (xy 120.549832 -388.86944) (xy 120.531298 -388.879975)
			(xy 120.524524 -388.888224) (xy 120.513602 -388.902289) (xy 120.48746 -388.926462) (xy 120.457293 -388.945377)
			(xy 120.424146 -388.95838) (xy 120.389165 -388.965021) (xy 120.371362 -388.96544) (xy 120.370854 -388.96544)
			(xy 120.343168 -388.963408) (xy 120.342914 -388.963408) (xy 120.333444 -388.962466) (xy 120.314928 -388.96679)
			(xy 120.299276 -388.977587) (xy 120.293638 -388.985252) (xy 120.242076 -389.060944) (xy 120.237052 -389.069077)
			(xy 120.232886 -389.087721) (xy 120.235824 -389.106597) (xy 120.240298 -389.115046) (xy 120.355868 -389.314944)
			(xy 120.356122 -389.315452) (xy 120.356376 -389.315452) (xy 120.357646 -389.317992) (xy 120.369881 -389.340915)
			(xy 120.3872 -389.389902) (xy 120.395987 -389.441111) (xy 120.396508 -389.46709) (xy 120.396508 -389.467344)
			(xy 120.396078 -389.491336) (xy 120.388565 -389.53873) (xy 120.373732 -389.584364) (xy 120.351943 -389.627117)
			(xy 120.323735 -389.665935) (xy 120.289802 -389.699863) (xy 120.250979 -389.728066) (xy 120.208224 -389.749849)
			(xy 120.162587 -389.764676) (xy 120.115192 -389.772181) (xy 120.0912 -389.772652) (xy 120.067536 -389.772213)
			(xy 120.020775 -389.764902) (xy 119.975699 -389.750471) (xy 119.933387 -389.729265) (xy 119.894849 -389.70179)
			(xy 119.861006 -389.668703) (xy 119.832668 -389.630796) (xy 119.821198 -389.610092) (xy 119.820944 -389.60933)
			(xy 119.80799 -389.586978) (xy 119.802519 -389.578599) (xy 119.786663 -389.566437) (xy 119.76736 -389.561263)
			(xy 119.747547 -389.563866) (xy 119.738648 -389.568436) (xy 119.729504 -389.57377) (xy 119.723408 -389.582152)
			(xy 119.712514 -389.596079) (xy 119.686422 -389.619939) (xy 119.656387 -389.638595) (xy 119.623434 -389.651411)
			(xy 119.588686 -389.657949) (xy 119.571008 -389.658352) (xy 119.5705 -389.658352) (xy 119.551735 -389.657848)
			(xy 119.514927 -389.650528) (xy 119.480254 -389.636168) (xy 119.449048 -389.615321) (xy 119.422507 -389.588786)
			(xy 119.401653 -389.557585) (xy 119.387285 -389.522915) (xy 119.379956 -389.486108) (xy 119.379492 -389.467344)
			(xy 119.380015 -389.448252) (xy 119.387573 -389.410824) (xy 119.402397 -389.375636) (xy 119.4239 -389.344083)
			(xy 119.45123 -389.317417) (xy 119.483301 -389.296696) (xy 119.500904 -389.28929) (xy 119.511064 -389.285226)
			(xy 119.526558 -389.269478) (xy 119.555768 -389.186166) (xy 119.558958 -389.175579) (xy 119.557002 -389.153585)
			(xy 119.551958 -389.143748) (xy 119.423688 -388.922006) (xy 119.41175 -388.897876) (xy 119.406994 -388.888313)
			(xy 119.39119 -388.873978) (xy 119.370926 -388.867293) (xy 119.349694 -388.86941) (xy 119.331149 -388.879964)
			(xy 119.324374 -388.888224) (xy 119.313464 -388.902332) (xy 119.28727 -388.92653) (xy 119.257044 -388.945453)
			(xy 119.223832 -388.958441) (xy 119.188789 -388.965046) (xy 119.170958 -388.96544) (xy 119.17045 -388.96544)
			(xy 119.16357 -388.965433) (xy 119.149841 -388.964546) (xy 119.143018 -388.963662) (xy 119.12854 -388.961376)
			(xy 119.10187 -388.97306) (xy 119.04218 -389.060944) (xy 119.037155 -389.069077) (xy 119.032989 -389.087721)
			(xy 119.035928 -389.106597) (xy 119.040402 -389.115046) (xy 119.155972 -389.314944) (xy 119.156226 -389.315452)
			(xy 119.15648 -389.315452) (xy 119.15775 -389.317992) (xy 119.169986 -389.340915) (xy 119.187304 -389.389901)
			(xy 119.196091 -389.441111) (xy 119.196612 -389.46709) (xy 119.196612 -389.467344) (xy 119.196178 -389.491336)
			(xy 119.188665 -389.538729) (xy 119.173832 -389.584363) (xy 119.152044 -389.627116) (xy 119.123836 -389.665934)
			(xy 119.089903 -389.699862) (xy 119.051082 -389.728065) (xy 119.008326 -389.749848) (xy 118.96269 -389.764675)
			(xy 118.915296 -389.772181) (xy 118.891304 -389.772652) (xy 118.86764 -389.772209) (xy 118.820879 -389.764899)
			(xy 118.775803 -389.750469) (xy 118.733491 -389.729263) (xy 118.694953 -389.701789) (xy 118.66111 -389.668703)
			(xy 118.632772 -389.630796) (xy 118.621302 -389.610092) (xy 118.621048 -389.60933) (xy 118.608094 -389.586978)
			(xy 118.602721 -389.578527) (xy 118.586829 -389.566366) (xy 118.567493 -389.56121) (xy 118.547656 -389.563846)
			(xy 118.538752 -389.568436) (xy 118.529608 -389.57377) (xy 118.523512 -389.582152) (xy 118.512616 -389.596078)
			(xy 118.486524 -389.619938) (xy 118.456489 -389.638594) (xy 118.423537 -389.65141) (xy 118.38879 -389.657949)
			(xy 118.371112 -389.658352) (xy 118.370604 -389.658352) (xy 118.35184 -389.657845) (xy 118.315031 -389.650525)
			(xy 118.280358 -389.636166) (xy 118.249152 -389.615319) (xy 118.222612 -389.588785) (xy 118.201757 -389.557584)
			(xy 118.187389 -389.522915) (xy 118.18006 -389.486108) (xy 118.179596 -389.467344) (xy 118.180116 -389.448252)
			(xy 118.187674 -389.410824) (xy 118.202499 -389.375636) (xy 118.224003 -389.344083) (xy 118.251333 -389.317417)
			(xy 118.283405 -389.296696) (xy 118.301008 -389.28929) (xy 118.311168 -389.285226) (xy 118.326662 -389.269478)
			(xy 118.355872 -389.186166) (xy 118.359061 -389.175579) (xy 118.357106 -389.153585) (xy 118.352062 -389.143748)
			(xy 118.223792 -388.922006) (xy 118.211854 -388.897876) (xy 118.207093 -388.888317) (xy 118.19129 -388.873981)
			(xy 118.171028 -388.867296) (xy 118.149797 -388.869412) (xy 118.131253 -388.879965) (xy 118.124478 -388.888224)
			(xy 118.113583 -388.902311) (xy 118.087433 -388.926482) (xy 118.05726 -388.945394) (xy 118.024107 -388.958391)
			(xy 117.98912 -388.965025) (xy 117.971316 -388.96544) (xy 117.970808 -388.96544) (xy 117.943122 -388.963408)
			(xy 117.942868 -388.963408) (xy 117.933399 -388.962429) (xy 117.914879 -388.96677) (xy 117.899228 -388.977581)
			(xy 117.893592 -388.985252) (xy 117.84203 -389.060944) (xy 117.837003 -389.069076) (xy 117.832833 -389.087721)
			(xy 117.835774 -389.106598) (xy 117.840252 -389.115046) (xy 117.955822 -389.314944) (xy 117.956076 -389.315452)
			(xy 117.95633 -389.315452) (xy 117.9576 -389.317992) (xy 117.969871 -389.340908) (xy 117.987278 -389.389886)
			(xy 117.996152 -389.441101) (xy 117.996716 -389.46709) (xy 117.996716 -389.467344) (xy 117.996279 -389.491323)
			(xy 117.988775 -389.538691) (xy 117.973957 -389.584304) (xy 117.952191 -389.627039) (xy 117.924011 -389.665846)
			(xy 117.890112 -389.69977) (xy 117.851325 -389.727977) (xy 117.808605 -389.749773) (xy 117.763004 -389.764624)
			(xy 117.715641 -389.772162) (xy 117.691662 -389.772652) (xy 117.691154 -389.772652) (xy 117.667491 -389.772169)
			(xy 117.620732 -389.764867) (xy 117.575658 -389.750444) (xy 117.533345 -389.729245) (xy 117.494807 -389.701776)
			(xy 117.460963 -389.668696) (xy 117.432623 -389.630793) (xy 117.421152 -389.610092) (xy 117.420898 -389.60933)
			(xy 117.407944 -389.586978) (xy 117.40252 -389.578564) (xy 117.386647 -389.566402) (xy 117.367328 -389.561238)
			(xy 117.347503 -389.563856) (xy 117.338602 -389.568436) (xy 117.329458 -389.57377) (xy 117.323362 -389.582152)
			(xy 117.312438 -389.596054) (xy 117.286353 -389.619916) (xy 117.256325 -389.638576) (xy 117.223379 -389.651398)
			(xy 117.188638 -389.657945) (xy 117.170962 -389.658352) (xy 117.170454 -389.658352) (xy 117.151675 -389.657945)
			(xy 117.11484 -389.650616) (xy 117.080139 -389.636248) (xy 117.048904 -389.615393) (xy 117.022333 -389.588849)
			(xy 117.001445 -389.557636) (xy 116.987042 -389.52295) (xy 116.979675 -389.486122) (xy 116.979192 -389.467344)
			(xy 116.979641 -389.448229) (xy 116.98721 -389.410757) (xy 117.002075 -389.375536) (xy 117.023643 -389.343972)
			(xy 117.051054 -389.317324) (xy 117.083213 -389.296655) (xy 117.100858 -389.28929) (xy 117.111018 -389.285226)
			(xy 117.126512 -389.269478) (xy 117.155722 -389.186166) (xy 117.158917 -389.17558) (xy 117.15696 -389.153584)
			(xy 117.151912 -389.143748) (xy 117.023642 -388.922006) (xy 117.011704 -388.897876) (xy 117.006872 -388.888358)
			(xy 116.991089 -388.874028) (xy 116.970848 -388.867339) (xy 116.949635 -388.869443) (xy 116.931102 -388.879976)
			(xy 116.924328 -388.888224) (xy 116.913387 -388.902306) (xy 116.887201 -388.926507) (xy 116.856982 -388.945433)
			(xy 116.823778 -388.958428) (xy 116.78874 -388.965042) (xy 116.770912 -388.96544) (xy 116.770404 -388.96544)
			(xy 116.763524 -388.965438) (xy 116.749794 -388.964547) (xy 116.742972 -388.963662) (xy 116.728494 -388.961376)
			(xy 116.701824 -388.97306) (xy 116.642134 -389.060944) (xy 116.637107 -389.069076) (xy 116.632936 -389.087721)
			(xy 116.635878 -389.106598) (xy 116.640356 -389.115046) (xy 116.755926 -389.314944) (xy 116.75618 -389.315452)
			(xy 116.756434 -389.315452) (xy 116.757704 -389.317992) (xy 116.769975 -389.340908) (xy 116.787382 -389.389886)
			(xy 116.796256 -389.441101) (xy 116.79682 -389.46709) (xy 116.79682 -389.467344) (xy 116.796379 -389.491323)
			(xy 116.788875 -389.538691) (xy 116.774057 -389.584303) (xy 116.752292 -389.627038) (xy 116.724113 -389.665844)
			(xy 116.690213 -389.699768) (xy 116.651427 -389.727975) (xy 116.608708 -389.749772) (xy 116.563107 -389.764623)
			(xy 116.515745 -389.772162) (xy 116.491766 -389.772652) (xy 116.491258 -389.772652) (xy 116.467595 -389.772166)
			(xy 116.420836 -389.764864) (xy 116.375762 -389.750442) (xy 116.33345 -389.729243) (xy 116.294911 -389.701775)
			(xy 116.261067 -389.668695) (xy 116.232727 -389.630793) (xy 116.221256 -389.610092) (xy 116.221002 -389.60933)
			(xy 116.208048 -389.586978) (xy 116.20262 -389.578567) (xy 116.186748 -389.566405) (xy 116.167431 -389.56124)
			(xy 116.147607 -389.563857) (xy 116.138706 -389.568436) (xy 116.129562 -389.57377) (xy 116.123466 -389.582152)
			(xy 116.11254 -389.596052) (xy 116.086455 -389.619914) (xy 116.056428 -389.638574) (xy 116.023483 -389.651397)
			(xy 115.988742 -389.657944) (xy 115.971066 -389.658352) (xy 115.970558 -389.658352) (xy 115.951779 -389.657941)
			(xy 115.914944 -389.650613) (xy 115.880243 -389.636246) (xy 115.849009 -389.615391) (xy 115.822438 -389.588848)
			(xy 115.80155 -389.557635) (xy 115.787146 -389.52295) (xy 115.779779 -389.486122) (xy 115.779296 -389.467344)
			(xy 115.779742 -389.448229) (xy 115.787311 -389.410756) (xy 115.802177 -389.375536) (xy 115.823745 -389.343972)
			(xy 115.851157 -389.317324) (xy 115.883317 -389.296655) (xy 115.900962 -389.28929) (xy 115.911122 -389.285226)
			(xy 115.926616 -389.269478) (xy 115.955826 -389.186166) (xy 115.959021 -389.17558) (xy 115.957063 -389.153584)
			(xy 115.952016 -389.143748) (xy 115.823746 -388.922006) (xy 115.811808 -388.897876) (xy 115.806971 -388.888361)
			(xy 115.791189 -388.874032) (xy 115.77095 -388.867343) (xy 115.749738 -388.869445) (xy 115.731206 -388.879977)
			(xy 115.724432 -388.888224) (xy 115.713489 -388.902304) (xy 115.687303 -388.926505) (xy 115.657085 -388.945432)
			(xy 115.623881 -388.958427) (xy 115.588844 -388.965041) (xy 115.571016 -388.96544) (xy 115.570508 -388.96544)
			(xy 115.563628 -388.965437) (xy 115.549898 -388.964547) (xy 115.543076 -388.963662) (xy 115.528598 -388.961376)
			(xy 115.501928 -388.97306) (xy 115.442238 -389.060944) (xy 115.437211 -389.069076) (xy 115.43304 -389.087721)
			(xy 115.435982 -389.106599) (xy 115.44046 -389.115046) (xy 115.55603 -389.314944) (xy 115.556284 -389.315452)
			(xy 115.556538 -389.315452) (xy 115.557808 -389.317992) (xy 115.57008 -389.340908) (xy 115.587486 -389.389886)
			(xy 115.59636 -389.441101) (xy 115.596924 -389.46709) (xy 115.596924 -389.467344) (xy 115.596479 -389.491323)
			(xy 115.588975 -389.53869) (xy 115.574158 -389.584302) (xy 115.552392 -389.627036) (xy 115.524214 -389.665843)
			(xy 115.490315 -389.699767) (xy 115.451529 -389.727974) (xy 115.408811 -389.749771) (xy 115.36321 -389.764622)
			(xy 115.315849 -389.772161) (xy 115.29187 -389.772652) (xy 115.291362 -389.772652) (xy 115.267699 -389.772163)
			(xy 115.220941 -389.764861) (xy 115.175866 -389.750439) (xy 115.133554 -389.729241) (xy 115.095015 -389.701774)
			(xy 115.061171 -389.668695) (xy 115.032831 -389.630793) (xy 115.02136 -389.610092) (xy 115.021106 -389.60933)
			(xy 115.008152 -389.586978) (xy 115.00272 -389.57857) (xy 114.98685 -389.566408) (xy 114.967534 -389.561242)
			(xy 114.947711 -389.563858) (xy 114.93881 -389.568436) (xy 114.929666 -389.57377) (xy 114.92357 -389.582152)
			(xy 114.912641 -389.59605) (xy 114.886557 -389.619912) (xy 114.856531 -389.638573) (xy 114.823586 -389.651396)
			(xy 114.788846 -389.657944) (xy 114.77117 -389.658352) (xy 114.770662 -389.658352) (xy 114.751884 -389.657938)
			(xy 114.715048 -389.65061) (xy 114.680348 -389.636244) (xy 114.649113 -389.615389) (xy 114.622542 -389.588847)
			(xy 114.601654 -389.557634) (xy 114.58725 -389.522949) (xy 114.579883 -389.486122) (xy 114.5794 -389.467344)
			(xy 114.579843 -389.448229) (xy 114.587413 -389.410756) (xy 114.602279 -389.375535) (xy 114.623848 -389.343971)
			(xy 114.65126 -389.317323) (xy 114.683421 -389.296655) (xy 114.701066 -389.28929) (xy 114.711226 -389.285226)
			(xy 114.72672 -389.269478) (xy 114.75593 -389.186166) (xy 114.759124 -389.17558) (xy 114.757167 -389.153584)
			(xy 114.75212 -389.143748) (xy 114.62385 -388.922006) (xy 114.611912 -388.897876) (xy 114.607069 -388.888364)
			(xy 114.591289 -388.874036) (xy 114.571052 -388.867346) (xy 114.549841 -388.869447) (xy 114.531309 -388.879978)
			(xy 114.524536 -388.888224) (xy 114.513608 -388.902283) (xy 114.487467 -388.926457) (xy 114.457302 -388.945373)
			(xy 114.424156 -388.958377) (xy 114.389176 -388.96502) (xy 114.371374 -388.96544) (xy 114.370866 -388.96544)
			(xy 114.350851 -388.96485) (xy 114.311697 -388.956521) (xy 114.275129 -388.940234) (xy 114.242747 -388.916702)
			(xy 114.215964 -388.886951) (xy 114.195951 -388.852283) (xy 114.183582 -388.814211) (xy 114.179398 -388.7744)
			(xy 98.671418 -388.7744) (xy 98.9838 -389.314944) (xy 98.984054 -389.315452) (xy 98.984308 -389.315452)
			(xy 98.985578 -389.317992) (xy 98.997808 -389.340918) (xy 99.01513 -389.389903) (xy 99.023918 -389.441111)
			(xy 99.02444 -389.46709) (xy 99.02444 -389.467344) (xy 99.023978 -389.491335) (xy 99.016466 -389.538725)
			(xy 99.001635 -389.584357) (xy 98.979849 -389.627107) (xy 98.951644 -389.665924) (xy 98.917715 -389.699852)
			(xy 98.878897 -389.728055) (xy 98.836146 -389.74984) (xy 98.790513 -389.764669) (xy 98.743123 -389.772179)
			(xy 98.719132 -389.772652) (xy 98.695469 -389.772187) (xy 98.648709 -389.764881) (xy 98.603634 -389.750455)
			(xy 98.561321 -389.729253) (xy 98.522783 -389.701782) (xy 98.48894 -389.668699) (xy 98.460601 -389.630794)
			(xy 98.44913 -389.610092) (xy 98.448876 -389.60933) (xy 98.435922 -389.586978) (xy 98.430521 -389.578548)
			(xy 98.414639 -389.566386) (xy 98.395313 -389.561226) (xy 98.375482 -389.563851) (xy 98.36658 -389.568436)
			(xy 98.357436 -389.57377) (xy 98.35134 -389.582152) (xy 98.340428 -389.596064) (xy 98.31434 -389.619925)
			(xy 98.28431 -389.638584) (xy 98.251361 -389.651403) (xy 98.216617 -389.657947) (xy 98.19894 -389.658352)
			(xy 98.198432 -389.658352) (xy 98.179668 -389.657819) (xy 98.142861 -389.650505) (xy 98.108188 -389.63615)
			(xy 98.076982 -389.615307) (xy 98.050441 -389.588777) (xy 98.029586 -389.557579) (xy 98.015217 -389.522912)
			(xy 98.007888 -389.486107) (xy 98.007424 -389.467344) (xy 98.007927 -389.448251) (xy 98.015486 -389.410821)
			(xy 98.030313 -389.375631) (xy 98.051821 -389.344078) (xy 98.079155 -389.317413) (xy 98.111231 -389.296694)
			(xy 98.128836 -389.28929) (xy 98.138996 -389.285226) (xy 98.15449 -389.269478) (xy 98.1837 -389.186166)
			(xy 98.186898 -389.17558) (xy 98.184939 -389.153584) (xy 98.17989 -389.143748) (xy 98.05162 -388.922006)
			(xy 98.039682 -388.897876) (xy 98.034881 -388.88834) (xy 98.019089 -388.874008) (xy 97.998839 -388.867321)
			(xy 97.977618 -388.869429) (xy 97.95908 -388.879971) (xy 97.952306 -388.888224) (xy 97.941395 -388.902298)
			(xy 97.915249 -388.92647) (xy 97.88508 -388.945384) (xy 97.851931 -388.958384) (xy 97.816947 -388.965022)
			(xy 97.799144 -388.96544) (xy 97.798636 -388.96544) (xy 97.77095 -388.963408) (xy 97.770696 -388.963408)
			(xy 97.761226 -388.962452) (xy 97.742709 -388.966782) (xy 97.727058 -388.977585) (xy 97.72142 -388.985252)
			(xy 97.669858 -389.060944) (xy 97.664835 -389.069077) (xy 97.66067 -389.087721) (xy 97.663607 -389.106597)
			(xy 97.66808 -389.115046) (xy 97.78365 -389.314944) (xy 97.783904 -389.315452) (xy 97.784158 -389.315452)
			(xy 97.785428 -389.317992) (xy 97.797701 -389.340907) (xy 97.815106 -389.389885) (xy 97.82398 -389.441101)
			(xy 97.824544 -389.46709) (xy 97.824544 -389.467344) (xy 97.824079 -389.491322) (xy 97.816576 -389.538687)
			(xy 97.80176 -389.584297) (xy 97.779996 -389.62703) (xy 97.75182 -389.665836) (xy 97.717923 -389.69976)
			(xy 97.67914 -389.727967) (xy 97.636425 -389.749765) (xy 97.590827 -389.764618) (xy 97.543468 -389.77216)
			(xy 97.51949 -389.772652) (xy 97.518982 -389.772652) (xy 97.495317 -389.772227) (xy 97.448555 -389.764914)
			(xy 97.40348 -389.75048) (xy 97.361167 -389.729272) (xy 97.322629 -389.701795) (xy 97.288787 -389.668706)
			(xy 97.26045 -389.630797) (xy 97.24898 -389.610092) (xy 97.248726 -389.60933) (xy 97.235772 -389.586978)
			(xy 97.23032 -389.578586) (xy 97.214457 -389.566423) (xy 97.195148 -389.561254) (xy 97.17533 -389.563862)
			(xy 97.16643 -389.568436) (xy 97.157286 -389.57377) (xy 97.15119 -389.582152) (xy 97.14025 -389.59604)
			(xy 97.114169 -389.619904) (xy 97.084146 -389.638566) (xy 97.051203 -389.651391) (xy 97.016465 -389.657942)
			(xy 96.99879 -389.658352) (xy 96.998282 -389.658352) (xy 96.979504 -389.65792) (xy 96.94267 -389.650596)
			(xy 96.907969 -389.636233) (xy 96.876734 -389.615381) (xy 96.850163 -389.588841) (xy 96.829274 -389.55763)
			(xy 96.81487 -389.522947) (xy 96.807503 -389.486121) (xy 96.80702 -389.467344) (xy 96.807451 -389.448228)
			(xy 96.815022 -389.410754) (xy 96.829889 -389.375532) (xy 96.851461 -389.343968) (xy 96.878876 -389.317321)
			(xy 96.91104 -389.296654) (xy 96.928686 -389.28929) (xy 96.938846 -389.285226) (xy 96.95434 -389.269478)
			(xy 96.98355 -389.186166) (xy 96.986742 -389.17558) (xy 96.984786 -389.153585) (xy 96.97974 -389.143748)
			(xy 96.85147 -388.922006) (xy 96.839532 -388.897876) (xy 96.834661 -388.888381) (xy 96.818889 -388.874054)
			(xy 96.79866 -388.867363) (xy 96.777456 -388.869459) (xy 96.758929 -388.879982) (xy 96.752156 -388.888224)
			(xy 96.741199 -388.902293) (xy 96.715017 -388.926495) (xy 96.684802 -388.945423) (xy 96.651602 -388.958421)
			(xy 96.616567 -388.965039) (xy 96.59874 -388.96544) (xy 96.598232 -388.96544) (xy 96.591352 -388.965435)
			(xy 96.577623 -388.964546) (xy 96.5708 -388.963662) (xy 96.556322 -388.961376) (xy 96.529652 -388.97306)
			(xy 96.469962 -389.060944) (xy 96.464938 -389.069077) (xy 96.460773 -389.087721) (xy 96.463711 -389.106597)
			(xy 96.468184 -389.115046) (xy 96.583754 -389.314944) (xy 96.584008 -389.315452) (xy 96.584262 -389.315452)
			(xy 96.585532 -389.317992) (xy 96.597806 -389.340907) (xy 96.615211 -389.389885) (xy 96.624084 -389.441101)
			(xy 96.624648 -389.46709) (xy 96.624648 -389.467344) (xy 96.624179 -389.491322) (xy 96.616676 -389.538687)
			(xy 96.60186 -389.584296) (xy 96.580097 -389.627029) (xy 96.551921 -389.665835) (xy 96.518025 -389.699758)
			(xy 96.479243 -389.727966) (xy 96.436528 -389.749764) (xy 96.39093 -389.764617) (xy 96.343571 -389.772159)
			(xy 96.319594 -389.772652) (xy 96.319086 -389.772652) (xy 96.295421 -389.772224) (xy 96.24866 -389.764911)
			(xy 96.203584 -389.750478) (xy 96.161272 -389.72927) (xy 96.122734 -389.701794) (xy 96.088892 -389.668705)
			(xy 96.060554 -389.630796) (xy 96.049084 -389.610092) (xy 96.04883 -389.60933) (xy 96.035876 -389.586978)
			(xy 96.03042 -389.578589) (xy 96.014558 -389.566426) (xy 95.995251 -389.561256) (xy 95.975434 -389.563863)
			(xy 95.966534 -389.568436) (xy 95.95739 -389.57377) (xy 95.951294 -389.582152) (xy 95.940352 -389.596039)
			(xy 95.914271 -389.619902) (xy 95.884248 -389.638564) (xy 95.851307 -389.65139) (xy 95.816569 -389.657942)
			(xy 95.798894 -389.658352) (xy 95.798386 -389.658352) (xy 95.779608 -389.657916) (xy 95.742774 -389.650593)
			(xy 95.708074 -389.63623) (xy 95.676839 -389.615379) (xy 95.650267 -389.58884) (xy 95.629378 -389.55763)
			(xy 95.614974 -389.522947) (xy 95.607607 -389.486121) (xy 95.607124 -389.467344) (xy 95.607553 -389.448228)
			(xy 95.615123 -389.410753) (xy 95.629991 -389.375531) (xy 95.651563 -389.343967) (xy 95.678979 -389.31732)
			(xy 95.711143 -389.296654) (xy 95.72879 -389.28929) (xy 95.73895 -389.285226) (xy 95.754444 -389.269478)
			(xy 95.783654 -389.186166) (xy 95.786846 -389.17558) (xy 95.784889 -389.153585) (xy 95.779844 -389.143748)
			(xy 95.651574 -388.922006) (xy 95.639636 -388.897876) (xy 95.634759 -388.888384) (xy 95.618989 -388.874059)
			(xy 95.598762 -388.867367) (xy 95.577559 -388.869462) (xy 95.559033 -388.879983) (xy 95.55226 -388.888224)
			(xy 95.541318 -388.902272) (xy 95.51518 -388.926447) (xy 95.485019 -388.945365) (xy 95.451876 -388.958371)
			(xy 95.416899 -388.965017) (xy 95.399098 -388.96544) (xy 95.39859 -388.96544) (xy 95.370904 -388.963408)
			(xy 95.37065 -388.963408) (xy 95.361182 -388.962415) (xy 95.34266 -388.966762) (xy 95.32701 -388.977578)
			(xy 95.321374 -388.985252) (xy 95.269812 -389.060944) (xy 95.264786 -389.069077) (xy 95.260617 -389.087721)
			(xy 95.263558 -389.106598) (xy 95.268034 -389.115046) (xy 95.383604 -389.314944) (xy 95.383858 -389.315452)
			(xy 95.384112 -389.315452) (xy 95.385382 -389.317992) (xy 95.397612 -389.340918) (xy 95.414934 -389.389903)
			(xy 95.423722 -389.441111) (xy 95.424244 -389.46709) (xy 95.424244 -389.467344) (xy 95.423778 -389.491335)
			(xy 95.416267 -389.538724) (xy 95.401435 -389.584356) (xy 95.379649 -389.627106) (xy 95.351445 -389.665923)
			(xy 95.317517 -389.69985) (xy 95.278699 -389.728054) (xy 95.235949 -389.749838) (xy 95.190317 -389.764668)
			(xy 95.142927 -389.772179) (xy 95.118936 -389.772652) (xy 95.095273 -389.772184) (xy 95.048513 -389.764878)
			(xy 95.003438 -389.750453) (xy 94.961126 -389.729251) (xy 94.922587 -389.701781) (xy 94.888744 -389.668698)
			(xy 94.860405 -389.630794) (xy 94.848934 -389.610092) (xy 94.84868 -389.60933) (xy 94.835726 -389.586978)
			(xy 94.830321 -389.578551) (xy 94.81444 -389.566389) (xy 94.795116 -389.561228) (xy 94.775286 -389.563852)
			(xy 94.766384 -389.568436) (xy 94.75724 -389.57377) (xy 94.751144 -389.582152) (xy 94.74023 -389.596062)
			(xy 94.714142 -389.619924) (xy 94.684112 -389.638582) (xy 94.651164 -389.651402) (xy 94.616421 -389.657946)
			(xy 94.598744 -389.658352) (xy 94.598236 -389.658352) (xy 94.579473 -389.657816) (xy 94.542666 -389.650502)
			(xy 94.507993 -389.636148) (xy 94.476786 -389.615306) (xy 94.450245 -389.588776) (xy 94.42939 -389.557578)
			(xy 94.415021 -389.522911) (xy 94.407692 -389.486107) (xy 94.407228 -389.467344) (xy 94.407728 -389.448251)
			(xy 94.415288 -389.41082) (xy 94.430115 -389.37563) (xy 94.451623 -389.344077) (xy 94.478958 -389.317412)
			(xy 94.511035 -389.296693) (xy 94.52864 -389.28929) (xy 94.5388 -389.285226) (xy 94.554294 -389.269478)
			(xy 94.583504 -389.186166) (xy 94.586701 -389.17558) (xy 94.584743 -389.153584) (xy 94.579694 -389.143748)
			(xy 94.451424 -388.922006) (xy 94.439486 -388.897876) (xy 94.434679 -388.888343) (xy 94.418889 -388.874012)
			(xy 94.398641 -388.867324) (xy 94.377421 -388.869432) (xy 94.358884 -388.879972) (xy 94.35211 -388.888224)
			(xy 94.341179 -388.902314) (xy 94.314991 -388.926515) (xy 94.284769 -388.94544) (xy 94.251563 -388.958433)
			(xy 94.216523 -388.965043) (xy 94.198694 -388.96544) (xy 94.198186 -388.96544) (xy 94.191306 -388.96544)
			(xy 94.177576 -388.964548) (xy 94.170754 -388.963662) (xy 94.156276 -388.961376) (xy 94.129606 -388.97306)
			(xy 94.069916 -389.060944) (xy 94.06489 -389.069077) (xy 94.060721 -389.087721) (xy 94.063661 -389.106598)
			(xy 94.068138 -389.115046) (xy 94.183708 -389.314944) (xy 94.183962 -389.315452) (xy 94.184216 -389.315452)
			(xy 94.185486 -389.317992) (xy 94.197717 -389.340917) (xy 94.215038 -389.389902) (xy 94.223826 -389.441111)
			(xy 94.224348 -389.46709) (xy 94.224348 -389.467344) (xy 94.223878 -389.491334) (xy 94.216367 -389.538724)
			(xy 94.201536 -389.584355) (xy 94.17975 -389.627105) (xy 94.151546 -389.665922) (xy 94.117618 -389.699849)
			(xy 94.078802 -389.728052) (xy 94.036051 -389.749837) (xy 93.99042 -389.764668) (xy 93.94303 -389.772178)
			(xy 93.91904 -389.772652) (xy 93.895377 -389.77218) (xy 93.848617 -389.764876) (xy 93.803542 -389.750451)
			(xy 93.76123 -389.72925) (xy 93.722692 -389.70178) (xy 93.688848 -389.668698) (xy 93.660509 -389.630794)
			(xy 93.649038 -389.610092) (xy 93.648784 -389.60933) (xy 93.63583 -389.586978) (xy 93.630421 -389.578554)
			(xy 93.614542 -389.566392) (xy 93.595218 -389.56123) (xy 93.57539 -389.563853) (xy 93.566488 -389.568436)
			(xy 93.557344 -389.57377) (xy 93.551248 -389.582152) (xy 93.540332 -389.59606) (xy 93.514245 -389.619922)
			(xy 93.484215 -389.638581) (xy 93.451268 -389.651401) (xy 93.416525 -389.657946) (xy 93.398848 -389.658352)
			(xy 93.39834 -389.658352) (xy 93.379577 -389.657812) (xy 93.34277 -389.650499) (xy 93.308097 -389.636146)
			(xy 93.27689 -389.615304) (xy 93.250349 -389.588775) (xy 93.229494 -389.557577) (xy 93.215125 -389.522911)
			(xy 93.207796 -389.486107) (xy 93.207332 -389.467344) (xy 93.20783 -389.448251) (xy 93.215389 -389.41082)
			(xy 93.230217 -389.37563) (xy 93.251726 -389.344076) (xy 93.279061 -389.317411) (xy 93.311138 -389.296693)
			(xy 93.328744 -389.28929) (xy 93.338904 -389.285226) (xy 93.354398 -389.269478) (xy 93.383608 -389.186166)
			(xy 93.386805 -389.17558) (xy 93.384847 -389.153584) (xy 93.379798 -389.143748) (xy 93.251528 -388.922006)
			(xy 93.23959 -388.897876) (xy 93.234778 -388.888346) (xy 93.218989 -388.874015) (xy 93.198743 -388.867327)
			(xy 93.177524 -388.869434) (xy 93.158988 -388.879973) (xy 93.152214 -388.888224) (xy 93.141281 -388.902313)
			(xy 93.115093 -388.926513) (xy 93.084872 -388.945438) (xy 93.051666 -388.958432) (xy 93.016627 -388.965043)
			(xy 92.998798 -388.96544) (xy 92.99829 -388.96544) (xy 92.99141 -388.965439) (xy 92.97768 -388.964548)
			(xy 92.970858 -388.963662) (xy 92.95638 -388.961376) (xy 92.92971 -388.97306) (xy 92.87002 -389.060944)
			(xy 92.864994 -389.069077) (xy 92.860824 -389.087721) (xy 92.863765 -389.106598) (xy 92.868242 -389.115046)
			(xy 92.983812 -389.314944) (xy 92.984066 -389.315452) (xy 92.98432 -389.315452) (xy 92.98559 -389.317992)
			(xy 92.997821 -389.340917) (xy 93.015142 -389.389902) (xy 93.02393 -389.441111) (xy 93.024452 -389.46709)
			(xy 93.024452 -389.467344) (xy 93.023978 -389.491334) (xy 93.016467 -389.538723) (xy 93.001636 -389.584354)
			(xy 92.979851 -389.627104) (xy 92.951648 -389.66592) (xy 92.91772 -389.699848) (xy 92.878904 -389.728051)
			(xy 92.836154 -389.749836) (xy 92.790523 -389.764667) (xy 92.743134 -389.772178) (xy 92.719144 -389.772652)
			(xy 92.695481 -389.772177) (xy 92.648721 -389.764873) (xy 92.603647 -389.750449) (xy 92.561334 -389.729248)
			(xy 92.522796 -389.701779) (xy 92.488952 -389.668697) (xy 92.460613 -389.630794) (xy 92.449142 -389.610092)
			(xy 92.448888 -389.60933) (xy 92.435934 -389.586978) (xy 92.43052 -389.578557) (xy 92.414643 -389.566395)
			(xy 92.395321 -389.561232) (xy 92.375494 -389.563854) (xy 92.366592 -389.568436) (xy 92.357448 -389.57377)
			(xy 92.351352 -389.582152) (xy 92.340433 -389.596059) (xy 92.314347 -389.61992) (xy 92.284318 -389.638579)
			(xy 92.251371 -389.6514) (xy 92.216628 -389.657946) (xy 92.198952 -389.658352) (xy 92.198444 -389.658352)
			(xy 92.179681 -389.657809) (xy 92.142874 -389.650496) (xy 92.108201 -389.636143) (xy 92.076995 -389.615302)
			(xy 92.050454 -389.588773) (xy 92.029598 -389.557576) (xy 92.01523 -389.52291) (xy 92.0079 -389.486107)
			(xy 92.007436 -389.467344) (xy 92.007931 -389.44825) (xy 92.015491 -389.410819) (xy 92.030319 -389.375629)
			(xy 92.051828 -389.344075) (xy 92.079164 -389.317411) (xy 92.111242 -389.296693) (xy 92.128848 -389.28929)
			(xy 92.139008 -389.285226) (xy 92.154502 -389.269478) (xy 92.183712 -389.186166) (xy 92.186908 -389.17558)
			(xy 92.18495 -389.153584) (xy 92.179902 -389.143748) (xy 92.051632 -388.922006) (xy 92.039694 -388.897876)
			(xy 92.034876 -388.88835) (xy 92.019089 -388.874019) (xy 91.998844 -388.867331) (xy 91.977627 -388.869437)
			(xy 91.959092 -388.879974) (xy 91.952318 -388.888224) (xy 91.9414 -388.902292) (xy 91.915256 -388.926465)
			(xy 91.885089 -388.94538) (xy 91.851941 -388.958382) (xy 91.816959 -388.965021) (xy 91.799156 -388.96544)
			(xy 91.798648 -388.96544) (xy 91.770962 -388.963408) (xy 91.770708 -388.963408) (xy 91.761238 -388.962461)
			(xy 91.742722 -388.966788) (xy 91.72707 -388.977586) (xy 91.721432 -388.985252) (xy 91.66987 -389.060944)
			(xy 91.664846 -389.069077) (xy 91.66068 -389.087721) (xy 91.663618 -389.106597) (xy 91.668092 -389.115046)
			(xy 91.783662 -389.314944) (xy 91.783916 -389.315452) (xy 91.78417 -389.315452) (xy 91.78544 -389.317992)
			(xy 91.797714 -389.340906) (xy 91.815119 -389.389885) (xy 91.823992 -389.441101) (xy 91.824556 -389.46709)
			(xy 91.824556 -389.467344) (xy 91.824079 -389.491321) (xy 91.816576 -389.538686) (xy 91.801761 -389.584295)
			(xy 91.779998 -389.627027) (xy 91.751823 -389.665832) (xy 91.717928 -389.699755) (xy 91.679147 -389.727963)
			(xy 91.636433 -389.749762) (xy 91.590837 -389.764616) (xy 91.543479 -389.772159) (xy 91.519502 -389.772652)
			(xy 91.518994 -389.772652) (xy 91.495329 -389.772217) (xy 91.448568 -389.764906) (xy 91.403493 -389.750474)
			(xy 91.36118 -389.729267) (xy 91.322642 -389.701792) (xy 91.2888 -389.668704) (xy 91.260462 -389.630796)
			(xy 91.248992 -389.610092) (xy 91.248738 -389.60933) (xy 91.235784 -389.586978) (xy 91.230319 -389.578595)
			(xy 91.214461 -389.566432) (xy 91.195156 -389.56126) (xy 91.175341 -389.563865) (xy 91.166442 -389.568436)
			(xy 91.157298 -389.57377) (xy 91.151202 -389.582152) (xy 91.140255 -389.596035) (xy 91.114176 -389.619898)
			(xy 91.084154 -389.638562) (xy 91.051213 -389.651388) (xy 91.016476 -389.657941) (xy 90.998802 -389.658352)
			(xy 90.998294 -389.658352) (xy 90.979517 -389.657908) (xy 90.942683 -389.650587) (xy 90.907983 -389.636225)
			(xy 90.876747 -389.615376) (xy 90.850176 -389.588837) (xy 90.829287 -389.557628) (xy 90.814883 -389.522946)
			(xy 90.807515 -389.486121) (xy 90.807032 -389.467344) (xy 90.807456 -389.448228) (xy 90.815027 -389.410752)
			(xy 90.829895 -389.37553) (xy 90.851468 -389.343965) (xy 90.878885 -389.317319) (xy 90.911051 -389.296653)
			(xy 90.928698 -389.28929) (xy 90.938858 -389.285226) (xy 90.954352 -389.269478) (xy 90.983562 -389.186166)
			(xy 90.986753 -389.175579) (xy 90.984797 -389.153585) (xy 90.979752 -389.143748) (xy 90.851482 -388.922006)
			(xy 90.839544 -388.897876) (xy 90.834797 -388.888308) (xy 90.81899 -388.873972) (xy 90.798724 -388.867288)
			(xy 90.777489 -388.869406) (xy 90.758943 -388.879963) (xy 90.752168 -388.888224) (xy 90.741204 -388.902287)
			(xy 90.715024 -388.926489) (xy 90.684811 -388.945419) (xy 90.651612 -388.958419) (xy 90.616579 -388.965038)
			(xy 90.598752 -388.96544) (xy 90.598244 -388.96544) (xy 90.591364 -388.965433) (xy 90.577635 -388.964546)
			(xy 90.570812 -388.963662) (xy 90.556334 -388.961376) (xy 90.529664 -388.97306) (xy 90.469974 -389.060944)
			(xy 90.46495 -389.069077) (xy 90.460784 -389.087721) (xy 90.463722 -389.106597) (xy 90.468196 -389.115046)
			(xy 90.583766 -389.314944) (xy 90.58402 -389.315452) (xy 90.584274 -389.315452) (xy 90.585544 -389.317992)
			(xy 90.597819 -389.340906) (xy 90.615223 -389.389885) (xy 90.624096 -389.441101) (xy 90.62466 -389.46709)
			(xy 90.62466 -389.467344) (xy 90.624279 -389.491326) (xy 90.616773 -389.5387) (xy 90.601952 -389.584317)
			(xy 90.580181 -389.627055) (xy 90.551995 -389.665865) (xy 90.518088 -389.69979) (xy 90.479294 -389.727996)
			(xy 90.436567 -389.74979) (xy 90.390957 -389.764635) (xy 90.343588 -389.772166) (xy 90.319606 -389.772652)
			(xy 90.319098 -389.772652) (xy 90.295434 -389.772214) (xy 90.248672 -389.764903) (xy 90.203597 -389.750472)
			(xy 90.161285 -389.729266) (xy 90.122747 -389.701791) (xy 90.088904 -389.668704) (xy 90.060566 -389.630796)
			(xy 90.049096 -389.610092) (xy 90.048842 -389.60933) (xy 90.035888 -389.586978) (xy 90.030419 -389.578598)
			(xy 90.014562 -389.566435) (xy 89.995259 -389.561262) (xy 89.975445 -389.563866) (xy 89.966546 -389.568436)
			(xy 89.957402 -389.57377) (xy 89.951306 -389.582152) (xy 89.940414 -389.59608) (xy 89.91432 -389.61994)
			(xy 89.884285 -389.638596) (xy 89.851332 -389.651411) (xy 89.816584 -389.65795) (xy 89.798906 -389.658352)
			(xy 89.798398 -389.658352) (xy 89.779621 -389.657905) (xy 89.742787 -389.650584) (xy 89.708087 -389.636223)
			(xy 89.676852 -389.615374) (xy 89.65028 -389.588836) (xy 89.629391 -389.557627) (xy 89.614987 -389.522945)
			(xy 89.607619 -389.486121) (xy 89.607136 -389.467344) (xy 89.607557 -389.448227) (xy 89.615128 -389.410752)
			(xy 89.629997 -389.375529) (xy 89.651571 -389.343965) (xy 89.678988 -389.317318) (xy 89.711154 -389.296653)
			(xy 89.728802 -389.28929) (xy 89.738962 -389.285226) (xy 89.754456 -389.269478) (xy 89.783666 -389.186166)
			(xy 89.786856 -389.175579) (xy 89.7849 -389.153585) (xy 89.779856 -389.143748) (xy 89.651586 -388.922006)
			(xy 89.639648 -388.897876) (xy 89.634895 -388.888312) (xy 89.61909 -388.873976) (xy 89.598825 -388.867291)
			(xy 89.577592 -388.869408) (xy 89.559047 -388.879964) (xy 89.552272 -388.888224) (xy 89.54138 -388.902314)
			(xy 89.51523 -388.926485) (xy 89.485056 -388.945396) (xy 89.451902 -388.958393) (xy 89.416915 -388.965025)
			(xy 89.39911 -388.96544) (xy 89.398602 -388.96544) (xy 89.370916 -388.963408) (xy 89.370662 -388.963408)
			(xy 89.361194 -388.962424) (xy 89.342673 -388.966767) (xy 89.327022 -388.97758) (xy 89.321386 -388.985252)
			(xy 89.269824 -389.060944) (xy 89.264798 -389.069077) (xy 89.260628 -389.087721) (xy 89.263569 -389.106598)
			(xy 89.268046 -389.115046) (xy 89.383616 -389.314944) (xy 89.38387 -389.315452) (xy 89.384124 -389.315452)
			(xy 89.385394 -389.317992) (xy 89.397625 -389.340917) (xy 89.414946 -389.389902) (xy 89.423734 -389.441111)
			(xy 89.424256 -389.46709) (xy 89.424256 -389.467344) (xy 89.423778 -389.491334) (xy 89.416267 -389.538723)
			(xy 89.401436 -389.584353) (xy 89.379652 -389.627103) (xy 89.351449 -389.665919) (xy 89.317522 -389.699846)
			(xy 89.278706 -389.72805) (xy 89.235957 -389.749835) (xy 89.190327 -389.764666) (xy 89.142938 -389.772178)
			(xy 89.118948 -389.772652) (xy 89.095285 -389.772174) (xy 89.048526 -389.764871) (xy 89.003451 -389.750447)
			(xy 88.961139 -389.729247) (xy 88.9226 -389.701778) (xy 88.888757 -389.668697) (xy 88.860417 -389.630794)
			(xy 88.848946 -389.610092) (xy 88.848692 -389.60933) (xy 88.835738 -389.586978) (xy 88.83032 -389.57856)
			(xy 88.814445 -389.566398) (xy 88.795124 -389.561234) (xy 88.775298 -389.563855) (xy 88.766396 -389.568436)
			(xy 88.757252 -389.57377) (xy 88.751156 -389.582152) (xy 88.740235 -389.596057) (xy 88.714149 -389.619918)
			(xy 88.684121 -389.638578) (xy 88.651174 -389.651399) (xy 88.616432 -389.657945) (xy 88.598756 -389.658352)
			(xy 88.598248 -389.658352) (xy 88.579482 -389.657835) (xy 88.54267 -389.650522) (xy 88.507991 -389.636168)
			(xy 88.47678 -389.615324) (xy 88.450234 -389.588792) (xy 88.429375 -389.55759) (xy 88.415004 -389.522919)
			(xy 88.407674 -389.48611) (xy 88.40724 -389.467344) (xy 88.407733 -389.44825) (xy 88.415293 -389.410819)
			(xy 88.430121 -389.375628) (xy 88.451631 -389.344075) (xy 88.478967 -389.31741) (xy 88.511046 -389.296693)
			(xy 88.528652 -389.28929) (xy 88.538812 -389.285226) (xy 88.554306 -389.269478) (xy 88.583516 -389.186166)
			(xy 88.586712 -389.17558) (xy 88.584754 -389.153584) (xy 88.579706 -389.143748) (xy 88.451436 -388.922006)
			(xy 88.439498 -388.897876) (xy 88.434675 -388.888353) (xy 88.418889 -388.874023) (xy 88.398646 -388.867334)
			(xy 88.37743 -388.869439) (xy 88.358896 -388.879975) (xy 88.352122 -388.888224) (xy 88.341185 -388.902309)
			(xy 88.314998 -388.92651) (xy 88.284778 -388.945435) (xy 88.251573 -388.95843) (xy 88.216534 -388.965042)
			(xy 88.198706 -388.96544) (xy 88.198198 -388.96544) (xy 88.191318 -388.965438) (xy 88.177588 -388.964548)
			(xy 88.170766 -388.963662) (xy 88.156288 -388.961376) (xy 88.129618 -388.97306) (xy 88.069928 -389.060944)
			(xy 88.064901 -389.069077) (xy 88.060731 -389.087721) (xy 88.063672 -389.106598) (xy 88.06815 -389.115046)
			(xy 88.18372 -389.314944) (xy 88.183974 -389.315452) (xy 88.184228 -389.315452) (xy 88.185498 -389.317992)
			(xy 88.197729 -389.340917) (xy 88.21505 -389.389902) (xy 88.223838 -389.441111) (xy 88.22436 -389.46709)
			(xy 88.22436 -389.467344) (xy 88.224002 -389.491341) (xy 88.216487 -389.538742) (xy 88.20165 -389.584385)
			(xy 88.179855 -389.627144) (xy 88.151639 -389.665968) (xy 88.117698 -389.699899) (xy 88.078866 -389.728103)
			(xy 88.0361 -389.749885) (xy 87.990453 -389.764709) (xy 87.943049 -389.772209) (xy 87.919052 -389.772652)
			(xy 87.895389 -389.772171) (xy 87.84863 -389.764868) (xy 87.803556 -389.750445) (xy 87.761243 -389.729245)
			(xy 87.722705 -389.701777) (xy 87.688861 -389.668696) (xy 87.660521 -389.630793) (xy 87.64905 -389.610092)
			(xy 87.648796 -389.60933) (xy 87.635842 -389.586978) (xy 87.63042 -389.578563) (xy 87.614546 -389.566401)
			(xy 87.595227 -389.561237) (xy 87.575401 -389.563856) (xy 87.5665 -389.568436) (xy 87.557356 -389.57377)
			(xy 87.55126 -389.582152) (xy 87.540337 -389.596055) (xy 87.514252 -389.619917) (xy 87.484224 -389.638577)
			(xy 87.451278 -389.651398) (xy 87.416536 -389.657945) (xy 87.39886 -389.658352) (xy 87.398352 -389.658352)
			(xy 87.379586 -389.657892) (xy 87.342776 -389.650562) (xy 87.308102 -389.636195) (xy 87.276896 -389.61534)
			(xy 87.250357 -389.588801) (xy 87.229503 -389.557594) (xy 87.215136 -389.52292) (xy 87.207808 -389.48611)
			(xy 87.207344 -389.467344) (xy 87.207834 -389.44825) (xy 87.215394 -389.410818) (xy 87.230223 -389.375628)
			(xy 87.251733 -389.344074) (xy 87.27907 -389.31741) (xy 87.311149 -389.296692) (xy 87.328756 -389.28929)
			(xy 87.338916 -389.285226) (xy 87.35441 -389.269478) (xy 87.38362 -389.186166) (xy 87.386815 -389.17558)
			(xy 87.384858 -389.153584) (xy 87.37981 -389.143748) (xy 87.25154 -388.922006) (xy 87.239602 -388.897876)
			(xy 87.234773 -388.888356) (xy 87.218989 -388.874026) (xy 87.198748 -388.867338) (xy 87.177533 -388.869441)
			(xy 87.159 -388.879976) (xy 87.152226 -388.888224) (xy 87.141286 -388.902307) (xy 87.1151 -388.926508)
			(xy 87.084881 -388.945434) (xy 87.051676 -388.958429) (xy 87.016638 -388.965042) (xy 86.99881 -388.96544)
			(xy 86.998302 -388.96544) (xy 86.991422 -388.965438) (xy 86.977692 -388.964547) (xy 86.97087 -388.963662)
			(xy 86.956392 -388.961376) (xy 86.929722 -388.97306) (xy 86.870032 -389.060944) (xy 86.865005 -389.069076)
			(xy 86.860834 -389.087721) (xy 86.863776 -389.106598) (xy 86.868254 -389.115046) (xy 86.983824 -389.314944)
			(xy 86.984078 -389.315452) (xy 86.984332 -389.315452) (xy 86.985602 -389.317992) (xy 86.997834 -389.340917)
			(xy 87.015155 -389.389902) (xy 87.023942 -389.441111) (xy 87.024464 -389.46709) (xy 87.024464 -389.467344)
			(xy 87.024078 -389.491339) (xy 87.016564 -389.538736) (xy 87.001728 -389.584375) (xy 86.979935 -389.62713)
			(xy 86.951722 -389.66595) (xy 86.917783 -389.699879) (xy 86.878955 -389.728081) (xy 86.836193 -389.749861)
			(xy 86.79055 -389.764684) (xy 86.743151 -389.772185) (xy 86.719156 -389.772652) (xy 86.695493 -389.772167)
			(xy 86.648734 -389.764865) (xy 86.60366 -389.750443) (xy 86.561348 -389.729244) (xy 86.522809 -389.701776)
			(xy 86.488965 -389.668695) (xy 86.460625 -389.630793) (xy 86.449154 -389.610092) (xy 86.4489 -389.60933)
			(xy 86.435946 -389.586978) (xy 86.43052 -389.578566) (xy 86.414648 -389.566404) (xy 86.39533 -389.561239)
			(xy 86.375505 -389.563856) (xy 86.366604 -389.568436) (xy 86.35746 -389.57377) (xy 86.351364 -389.582152)
			(xy 86.340439 -389.596053) (xy 86.314354 -389.619915) (xy 86.284327 -389.638575) (xy 86.251381 -389.651397)
			(xy 86.21664 -389.657944) (xy 86.198964 -389.658352) (xy 86.198456 -389.658352) (xy 86.17969 -389.657888)
			(xy 86.14288 -389.650559) (xy 86.108206 -389.636192) (xy 86.077001 -389.615339) (xy 86.050461 -389.588799)
			(xy 86.029608 -389.557594) (xy 86.015241 -389.52292) (xy 86.007912 -389.48611) (xy 86.007448 -389.467344)
			(xy 86.007936 -389.44825) (xy 86.015496 -389.410818) (xy 86.030325 -389.375627) (xy 86.051836 -389.344073)
			(xy 86.079173 -389.317409) (xy 86.111253 -389.296692) (xy 86.12886 -389.28929) (xy 86.13902 -389.285226)
			(xy 86.154514 -389.269478) (xy 86.183724 -389.186166) (xy 86.186919 -389.17558) (xy 86.184961 -389.153584)
			(xy 86.179914 -389.143748) (xy 86.051644 -388.922006) (xy 86.039706 -388.897876) (xy 86.034871 -388.888359)
			(xy 86.019089 -388.87403) (xy 85.998849 -388.867341) (xy 85.977636 -388.869444) (xy 85.959104 -388.879976)
			(xy 85.95233 -388.888224) (xy 85.941405 -388.902286) (xy 85.915263 -388.92646) (xy 85.885097 -388.945375)
			(xy 85.851951 -388.958379) (xy 85.81697 -388.96502) (xy 85.799168 -388.96544) (xy 85.79866 -388.96544)
			(xy 85.770974 -388.963408) (xy 85.77072 -388.963408) (xy 85.761253 -388.962391) (xy 85.742729 -388.966748)
			(xy 85.727078 -388.977574) (xy 85.721444 -388.985252) (xy 85.669882 -389.060944) (xy 85.664857 -389.069077)
			(xy 85.660691 -389.087721) (xy 85.663629 -389.106597) (xy 85.668104 -389.115046) (xy 85.783674 -389.314944)
			(xy 85.783928 -389.315452) (xy 85.784182 -389.315452) (xy 85.785452 -389.317992) (xy 85.797727 -389.340906)
			(xy 85.815131 -389.389885) (xy 85.824004 -389.441101) (xy 85.824568 -389.46709) (xy 85.824568 -389.467344)
			(xy 85.824179 -389.491326) (xy 85.816673 -389.538698) (xy 85.801852 -389.584315) (xy 85.780082 -389.627053)
			(xy 85.751897 -389.665862) (xy 85.717991 -389.699787) (xy 85.679198 -389.727993) (xy 85.636472 -389.749787)
			(xy 85.590864 -389.764633) (xy 85.543495 -389.772165) (xy 85.519514 -389.772652) (xy 85.519006 -389.772652)
			(xy 85.495342 -389.772208) (xy 85.448581 -389.764898) (xy 85.403506 -389.750468) (xy 85.361193 -389.729263)
			(xy 85.322655 -389.701789) (xy 85.288813 -389.668703) (xy 85.260474 -389.630795) (xy 85.249004 -389.610092)
			(xy 85.24875 -389.60933) (xy 85.235796 -389.586978) (xy 85.230421 -389.578529) (xy 85.21453 -389.566367)
			(xy 85.195194 -389.561211) (xy 85.175358 -389.563846) (xy 85.166454 -389.568436) (xy 85.15731 -389.57377)
			(xy 85.151214 -389.582152) (xy 85.140317 -389.596077) (xy 85.114225 -389.619937) (xy 85.084191 -389.638593)
			(xy 85.051239 -389.651409) (xy 85.016492 -389.657949) (xy 84.998814 -389.658352) (xy 84.998306 -389.658352)
			(xy 84.979529 -389.657898) (xy 84.942696 -389.650578) (xy 84.907996 -389.636219) (xy 84.87676 -389.615371)
			(xy 84.850188 -389.588833) (xy 84.829299 -389.557625) (xy 84.814895 -389.522944) (xy 84.807527 -389.48612)
			(xy 84.807044 -389.467344) (xy 84.80746 -389.448227) (xy 84.815032 -389.410751) (xy 84.829901 -389.375528)
			(xy 84.851476 -389.343963) (xy 84.878894 -389.317317) (xy 84.911062 -389.296653) (xy 84.92871 -389.28929)
			(xy 84.93887 -389.285226) (xy 84.954364 -389.269478) (xy 84.983574 -389.186166) (xy 84.986763 -389.175579)
			(xy 84.984808 -389.153585) (xy 84.979764 -389.143748) (xy 84.851494 -388.922006) (xy 84.839556 -388.897876)
			(xy 84.834792 -388.888318) (xy 84.81899 -388.873983) (xy 84.798729 -388.867298) (xy 84.777498 -388.869413)
			(xy 84.758955 -388.879965) (xy 84.75218 -388.888224) (xy 84.741267 -388.902329) (xy 84.715074 -388.926528)
			(xy 84.684848 -388.94545) (xy 84.651637 -388.95844) (xy 84.616594 -388.965046) (xy 84.598764 -388.96544)
			(xy 84.598256 -388.96544) (xy 84.591376 -388.965432) (xy 84.577647 -388.964545) (xy 84.570824 -388.963662)
			(xy 84.556346 -388.961376) (xy 84.529676 -388.97306) (xy 84.469986 -389.060944) (xy 84.464961 -389.069077)
			(xy 84.460794 -389.087721) (xy 84.463733 -389.106598) (xy 84.468208 -389.115046) (xy 84.583778 -389.314944)
			(xy 84.584032 -389.315452) (xy 84.584286 -389.315452) (xy 84.585556 -389.317992) (xy 84.597831 -389.340906)
			(xy 84.615235 -389.389885) (xy 84.624108 -389.441101) (xy 84.624672 -389.46709) (xy 84.624672 -389.467344)
			(xy 84.624279 -389.491326) (xy 84.616773 -389.538698) (xy 84.601953 -389.584314) (xy 84.580183 -389.627052)
			(xy 84.551999 -389.665861) (xy 84.518093 -389.699785) (xy 84.4793 -389.727992) (xy 84.436575 -389.749786)
			(xy 84.390967 -389.764632) (xy 84.343599 -389.772165) (xy 84.319618 -389.772652) (xy 84.31911 -389.772652)
			(xy 84.295446 -389.772205) (xy 84.248685 -389.764896) (xy 84.20361 -389.750466) (xy 84.161298 -389.729261)
			(xy 84.122759 -389.701788) (xy 84.088917 -389.668702) (xy 84.060578 -389.630795) (xy 84.049108 -389.610092)
			(xy 84.048854 -389.60933) (xy 84.0359 -389.586978) (xy 84.030521 -389.578532) (xy 84.014631 -389.56637)
			(xy 83.995297 -389.561214) (xy 83.975462 -389.563847) (xy 83.966558 -389.568436) (xy 83.957414 -389.57377)
			(xy 83.951318 -389.582152) (xy 83.940419 -389.596075) (xy 83.914327 -389.619935) (xy 83.884294 -389.638592)
			(xy 83.851342 -389.651408) (xy 83.816596 -389.657949) (xy 83.798918 -389.658352) (xy 83.79841 -389.658352)
			(xy 83.779633 -389.657894) (xy 83.7428 -389.650575) (xy 83.7081 -389.636216) (xy 83.676865 -389.615369)
			(xy 83.650293 -389.588832) (xy 83.629404 -389.557625) (xy 83.614999 -389.522944) (xy 83.607631 -389.48612)
			(xy 83.607148 -389.467344) (xy 83.607562 -389.448227) (xy 83.615133 -389.410751) (xy 83.630003 -389.375527)
			(xy 83.651578 -389.343962) (xy 83.678997 -389.317316) (xy 83.711166 -389.296652) (xy 83.728814 -389.28929)
			(xy 83.738974 -389.285226) (xy 83.754468 -389.269478) (xy 83.783678 -389.186166) (xy 83.786867 -389.175579)
			(xy 83.784911 -389.153585) (xy 83.779868 -389.143748) (xy 83.651598 -388.922006) (xy 83.63966 -388.897876)
			(xy 83.63489 -388.888322) (xy 83.61909 -388.873987) (xy 83.59883 -388.867301) (xy 83.577601 -388.869416)
			(xy 83.559059 -388.879966) (xy 83.552284 -388.888224) (xy 83.541385 -388.902308) (xy 83.515237 -388.92648)
			(xy 83.485065 -388.945392) (xy 83.451912 -388.95839) (xy 83.416926 -388.965024) (xy 83.399122 -388.96544)
			(xy 83.398614 -388.96544) (xy 83.370928 -388.963408) (xy 83.370674 -388.963408) (xy 83.361205 -388.962434)
			(xy 83.342686 -388.966772) (xy 83.327035 -388.977582) (xy 83.321398 -388.985252) (xy 83.269836 -389.060944)
			(xy 83.264809 -389.069076) (xy 83.260638 -389.087721) (xy 83.26358 -389.106598) (xy 83.268058 -389.115046)
			(xy 83.383628 -389.314944) (xy 83.383882 -389.315452) (xy 83.384136 -389.315452) (xy 83.385406 -389.317992)
			(xy 83.397638 -389.340917) (xy 83.414959 -389.389902) (xy 83.423746 -389.441111) (xy 83.424268 -389.46709)
			(xy 83.424268 -389.467344) (xy 83.423878 -389.491338) (xy 83.416364 -389.538735) (xy 83.401528 -389.584374)
			(xy 83.379736 -389.627129) (xy 83.351523 -389.665949) (xy 83.317585 -389.699878) (xy 83.278757 -389.728079)
			(xy 83.235996 -389.74986) (xy 83.190354 -389.764684) (xy 83.142955 -389.772184) (xy 83.11896 -389.772652)
			(xy 83.095297 -389.772164) (xy 83.048539 -389.764863) (xy 83.003464 -389.75044) (xy 82.961152 -389.729242)
			(xy 82.922613 -389.701775) (xy 82.888769 -389.668695) (xy 82.860429 -389.630793) (xy 82.848958 -389.610092)
			(xy 82.848704 -389.60933) (xy 82.83575 -389.586978) (xy 82.83032 -389.578569) (xy 82.814449 -389.566407)
			(xy 82.795132 -389.561241) (xy 82.775309 -389.563857) (xy 82.766408 -389.568436) (xy 82.757264 -389.57377)
			(xy 82.751168 -389.582152) (xy 82.74024 -389.596051) (xy 82.714156 -389.619913) (xy 82.68413 -389.638574)
			(xy 82.651185 -389.651396) (xy 82.616444 -389.657944) (xy 82.598768 -389.658352) (xy 82.59826 -389.658352)
			(xy 82.579494 -389.657884) (xy 82.542684 -389.650557) (xy 82.508011 -389.63619) (xy 82.476805 -389.615337)
			(xy 82.450265 -389.588798) (xy 82.429412 -389.557593) (xy 82.415045 -389.52292) (xy 82.407716 -389.48611)
			(xy 82.407252 -389.467344) (xy 82.407737 -389.44825) (xy 82.415298 -389.410817) (xy 82.430127 -389.375626)
			(xy 82.451638 -389.344073) (xy 82.478976 -389.317408) (xy 82.511057 -389.296692) (xy 82.528664 -389.28929)
			(xy 82.538824 -389.285226) (xy 82.554318 -389.269478) (xy 82.583528 -389.186166) (xy 82.586722 -389.17558)
			(xy 82.584765 -389.153584) (xy 82.579718 -389.143748) (xy 82.451448 -388.922006) (xy 82.43951 -388.897876)
			(xy 82.43467 -388.888363) (xy 82.418889 -388.874034) (xy 82.398651 -388.867344) (xy 82.37744 -388.869446)
			(xy 82.358907 -388.879977) (xy 82.352134 -388.888224) (xy 82.34119 -388.902303) (xy 82.315005 -388.926504)
			(xy 82.284787 -388.945431) (xy 82.251583 -388.958427) (xy 82.216546 -388.965041) (xy 82.198718 -388.96544)
			(xy 82.19821 -388.96544) (xy 82.19133 -388.965437) (xy 82.1776 -388.964547) (xy 82.170778 -388.963662)
			(xy 82.1563 -388.961376) (xy 82.12963 -388.97306) (xy 82.06994 -389.060944) (xy 82.064913 -389.069076)
			(xy 82.060741 -389.087721) (xy 82.063684 -389.106599) (xy 82.068162 -389.115046) (xy 82.183732 -389.314944)
			(xy 82.183986 -389.315452) (xy 82.18424 -389.315452) (xy 82.18551 -389.317992) (xy 82.197742 -389.340916)
			(xy 82.215063 -389.389902) (xy 82.22385 -389.441111) (xy 82.224372 -389.46709) (xy 82.224372 -389.467344)
			(xy 82.223978 -389.491338) (xy 82.216464 -389.538735) (xy 82.201628 -389.584373) (xy 82.179836 -389.627128)
			(xy 82.151624 -389.665948) (xy 82.117687 -389.699876) (xy 82.078859 -389.728078) (xy 82.036099 -389.749859)
			(xy 81.990457 -389.764683) (xy 81.943058 -389.772184) (xy 81.919064 -389.772652) (xy 81.895401 -389.772161)
			(xy 81.848643 -389.76486) (xy 81.803569 -389.750438) (xy 81.761256 -389.729241) (xy 81.722717 -389.701774)
			(xy 81.688873 -389.668694) (xy 81.660533 -389.630793) (xy 81.649062 -389.610092) (xy 81.648808 -389.60933)
			(xy 81.635854 -389.586978) (xy 81.63042 -389.578572) (xy 81.61455 -389.56641) (xy 81.595235 -389.561243)
			(xy 81.575413 -389.563858) (xy 81.566512 -389.568436) (xy 81.557368 -389.57377) (xy 81.551272 -389.582152)
			(xy 81.540342 -389.596049) (xy 81.514258 -389.619912) (xy 81.484233 -389.638572) (xy 81.451288 -389.651395)
			(xy 81.416548 -389.657944) (xy 81.398872 -389.658352) (xy 81.398364 -389.658352) (xy 81.379598 -389.657881)
			(xy 81.342789 -389.650554) (xy 81.308115 -389.636188) (xy 81.276909 -389.615336) (xy 81.25037 -389.588797)
			(xy 81.229516 -389.557592) (xy 81.215149 -389.522919) (xy 81.20782 -389.48611) (xy 81.207356 -389.467344)
			(xy 81.207839 -389.44825) (xy 81.215399 -389.410817) (xy 81.230229 -389.375626) (xy 81.251741 -389.344072)
			(xy 81.279079 -389.317408) (xy 81.311161 -389.296692) (xy 81.328768 -389.28929) (xy 81.338928 -389.285226)
			(xy 81.354422 -389.269478) (xy 81.383632 -389.186166) (xy 81.386826 -389.17558) (xy 81.384869 -389.153584)
			(xy 81.379822 -389.143748) (xy 81.251552 -388.922006) (xy 81.239614 -388.897876) (xy 81.234768 -388.888366)
			(xy 81.218989 -388.874038) (xy 81.198753 -388.867348) (xy 81.177543 -388.869449) (xy 81.159011 -388.879978)
			(xy 81.152238 -388.888224) (xy 81.141291 -388.902301) (xy 81.115107 -388.926503) (xy 81.084889 -388.94543)
			(xy 81.051687 -388.958426) (xy 81.01665 -388.965041) (xy 80.998822 -388.96544) (xy 80.998314 -388.96544)
			(xy 80.991434 -388.965437) (xy 80.977704 -388.964547) (xy 80.970882 -388.963662) (xy 80.956404 -388.961376)
			(xy 80.929734 -388.97306) (xy 80.870044 -389.060944) (xy 80.865016 -389.069076) (xy 80.860845 -389.087721)
			(xy 80.863787 -389.106599) (xy 80.868266 -389.115046) (xy 80.983836 -389.314944) (xy 80.98409 -389.315452)
			(xy 80.984344 -389.315452) (xy 80.985614 -389.317992) (xy 80.997847 -389.340916) (xy 81.015167 -389.389902)
			(xy 81.023954 -389.441111) (xy 81.024476 -389.46709) (xy 81.024476 -389.467344) (xy 81.024078 -389.491338)
			(xy 81.016564 -389.538734) (xy 81.001729 -389.584372) (xy 80.979937 -389.627127) (xy 80.951725 -389.665946)
			(xy 80.917788 -389.699875) (xy 80.878962 -389.728077) (xy 80.836201 -389.749858) (xy 80.79056 -389.764682)
			(xy 80.743162 -389.772184) (xy 80.719168 -389.772652) (xy 80.695506 -389.772158) (xy 80.648747 -389.764857)
			(xy 80.603673 -389.750436) (xy 80.561361 -389.729239) (xy 80.522822 -389.701773) (xy 80.488978 -389.668694)
			(xy 80.460637 -389.630793) (xy 80.449166 -389.610092) (xy 80.448912 -389.60933) (xy 80.435958 -389.586978)
			(xy 80.43052 -389.578575) (xy 80.414652 -389.566413) (xy 80.395338 -389.561245) (xy 80.375516 -389.563859)
			(xy 80.366616 -389.568436) (xy 80.357472 -389.57377) (xy 80.351376 -389.582152) (xy 80.340444 -389.596047)
			(xy 80.314361 -389.61991) (xy 80.284335 -389.638571) (xy 80.251391 -389.651394) (xy 80.216651 -389.657943)
			(xy 80.198976 -389.658352) (xy 80.198468 -389.658352) (xy 80.179702 -389.657877) (xy 80.142893 -389.650551)
			(xy 80.108219 -389.636186) (xy 80.077013 -389.615334) (xy 80.050474 -389.588796) (xy 80.02962 -389.557591)
			(xy 80.015253 -389.522919) (xy 80.007924 -389.48611) (xy 80.00746 -389.467344) (xy 80.00794 -389.448249)
			(xy 80.015501 -389.410816) (xy 80.030331 -389.375625) (xy 80.051843 -389.344071) (xy 80.079182 -389.317407)
			(xy 80.111264 -389.296691) (xy 80.128872 -389.28929) (xy 80.139032 -389.285226) (xy 80.154526 -389.269478)
			(xy 80.183736 -389.186166) (xy 80.186929 -389.17558) (xy 80.184972 -389.153584) (xy 80.179926 -389.143748)
			(xy 80.051656 -388.922006) (xy 80.039718 -388.897876) (xy 80.034866 -388.888369) (xy 80.019089 -388.874041)
			(xy 79.998854 -388.867351) (xy 79.977646 -388.869451) (xy 79.959115 -388.879979) (xy 79.952342 -388.888224)
			(xy 79.94141 -388.90228) (xy 79.91527 -388.926455) (xy 79.885106 -388.945371) (xy 79.851961 -388.958376)
			(xy 79.816982 -388.965019) (xy 79.79918 -388.96544) (xy 79.798672 -388.96544) (xy 79.778657 -388.96485)
			(xy 79.739501 -388.956522) (xy 79.702933 -388.940236) (xy 79.670549 -388.916704) (xy 79.643765 -388.886953)
			(xy 79.623751 -388.852284) (xy 79.611382 -388.814212) (xy 79.607198 -388.7744) (xy 66.14367 -388.7744)
			(xy 66.456052 -389.314944) (xy 66.456306 -389.315452) (xy 66.45656 -389.315452) (xy 66.45783 -389.317992)
			(xy 66.470064 -389.340916) (xy 66.487383 -389.389902) (xy 66.496171 -389.441111) (xy 66.496692 -389.46709)
			(xy 66.496692 -389.467344) (xy 66.496278 -389.491337) (xy 66.488765 -389.538732) (xy 66.47393 -389.584368)
			(xy 66.45214 -389.627122) (xy 66.42393 -389.665941) (xy 66.389995 -389.699869) (xy 66.351171 -389.728071)
			(xy 66.308412 -389.749853) (xy 66.262774 -389.764679) (xy 66.215377 -389.772183) (xy 66.191384 -389.772652)
			(xy 66.167719 -389.772226) (xy 66.120957 -389.764913) (xy 66.075882 -389.750479) (xy 66.033569 -389.729271)
			(xy 65.995032 -389.701794) (xy 65.961189 -389.668706) (xy 65.932852 -389.630796) (xy 65.921382 -389.610092)
			(xy 65.921128 -389.60933) (xy 65.908174 -389.586978) (xy 65.90272 -389.578587) (xy 65.886857 -389.566425)
			(xy 65.867549 -389.561255) (xy 65.847732 -389.563863) (xy 65.838832 -389.568436) (xy 65.829688 -389.57377)
			(xy 65.823592 -389.582152) (xy 65.812651 -389.59604) (xy 65.78657 -389.619903) (xy 65.756547 -389.638565)
			(xy 65.723605 -389.651391) (xy 65.688867 -389.657942) (xy 65.671192 -389.658352) (xy 65.670684 -389.658352)
			(xy 65.651919 -389.657863) (xy 65.61511 -389.650539) (xy 65.580437 -389.636177) (xy 65.549231 -389.615327)
			(xy 65.522691 -389.588791) (xy 65.501836 -389.557588) (xy 65.487469 -389.522917) (xy 65.48014 -389.486109)
			(xy 65.479676 -389.467344) (xy 65.480146 -389.448249) (xy 65.487708 -389.410815) (xy 65.50254 -389.375622)
			(xy 65.524053 -389.344068) (xy 65.551395 -389.317405) (xy 65.583479 -389.29669) (xy 65.601088 -389.28929)
			(xy 65.611248 -389.285226) (xy 65.626742 -389.269478) (xy 65.655952 -389.186166) (xy 65.659144 -389.17558)
			(xy 65.657187 -389.153585) (xy 65.652142 -389.143748) (xy 65.523872 -388.922006) (xy 65.511934 -388.897876)
			(xy 65.50706 -388.888383) (xy 65.491289 -388.874057) (xy 65.471061 -388.867365) (xy 65.449858 -388.869461)
			(xy 65.431331 -388.879983) (xy 65.424558 -388.888224) (xy 65.413617 -388.902273) (xy 65.387479 -388.926448)
			(xy 65.357317 -388.945365) (xy 65.324175 -388.958372) (xy 65.289197 -388.965018) (xy 65.271396 -388.96544)
			(xy 65.270888 -388.96544) (xy 65.243202 -388.963408) (xy 65.242948 -388.963408) (xy 65.23348 -388.962413)
			(xy 65.214958 -388.966761) (xy 65.199308 -388.977578) (xy 65.193672 -388.985252) (xy 65.14211 -389.060944)
			(xy 65.137084 -389.069077) (xy 65.132915 -389.087721) (xy 65.135855 -389.106598) (xy 65.140332 -389.115046)
			(xy 65.255902 -389.314944) (xy 65.256156 -389.315452) (xy 65.25641 -389.315452) (xy 65.25768 -389.317992)
			(xy 65.269949 -389.340909) (xy 65.287357 -389.389886) (xy 65.296232 -389.441102) (xy 65.296796 -389.46709)
			(xy 65.296796 -389.467344) (xy 65.296379 -389.491324) (xy 65.288874 -389.538694) (xy 65.274055 -389.584308)
			(xy 65.252287 -389.627045) (xy 65.224106 -389.665852) (xy 65.190203 -389.699777) (xy 65.151414 -389.727984)
			(xy 65.108692 -389.749779) (xy 65.063087 -389.764628) (xy 65.015722 -389.772163) (xy 64.991742 -389.772652)
			(xy 64.991234 -389.772652) (xy 64.967571 -389.772185) (xy 64.920811 -389.76488) (xy 64.875736 -389.750454)
			(xy 64.833424 -389.729252) (xy 64.794885 -389.701781) (xy 64.761042 -389.668699) (xy 64.732703 -389.630794)
			(xy 64.721232 -389.610092) (xy 64.720978 -389.60933) (xy 64.708024 -389.586978) (xy 64.702621 -389.57855)
			(xy 64.68674 -389.566388) (xy 64.667414 -389.561227) (xy 64.647584 -389.563852) (xy 64.638682 -389.568436)
			(xy 64.629538 -389.57377) (xy 64.623442 -389.582152) (xy 64.612529 -389.596063) (xy 64.586441 -389.619925)
			(xy 64.556411 -389.638583) (xy 64.523463 -389.651403) (xy 64.488719 -389.657946) (xy 64.471042 -389.658352)
			(xy 64.470534 -389.658352) (xy 64.451758 -389.657872) (xy 64.414926 -389.650558) (xy 64.380226 -389.636203)
			(xy 64.34899 -389.615359) (xy 64.322418 -389.588825) (xy 64.301528 -389.55762) (xy 64.287123 -389.522941)
			(xy 64.279755 -389.486119) (xy 64.279272 -389.467344) (xy 64.27967 -389.448226) (xy 64.287243 -389.410748)
			(xy 64.302116 -389.375523) (xy 64.323694 -389.343958) (xy 64.351116 -389.317313) (xy 64.383288 -389.296651)
			(xy 64.400938 -389.28929) (xy 64.411098 -389.285226) (xy 64.426592 -389.269478) (xy 64.455802 -389.186166)
			(xy 64.459 -389.17558) (xy 64.457041 -389.153584) (xy 64.451992 -389.143748) (xy 64.323722 -388.922006)
			(xy 64.311784 -388.897876) (xy 64.30698 -388.888342) (xy 64.291189 -388.87401) (xy 64.27094 -388.867322)
			(xy 64.24972 -388.869431) (xy 64.231182 -388.879972) (xy 64.224408 -388.888224) (xy 64.213479 -388.902315)
			(xy 64.18729 -388.926516) (xy 64.157068 -388.94544) (xy 64.123861 -388.958433) (xy 64.088821 -388.965043)
			(xy 64.070992 -388.96544) (xy 64.070484 -388.96544) (xy 64.063604 -388.96544) (xy 64.049874 -388.964548)
			(xy 64.043052 -388.963662) (xy 64.028574 -388.961376) (xy 64.001904 -388.97306) (xy 63.942214 -389.060944)
			(xy 63.937188 -389.069077) (xy 63.933019 -389.087721) (xy 63.93596 -389.106598) (xy 63.940436 -389.115046)
			(xy 64.056006 -389.314944) (xy 64.05626 -389.315452) (xy 64.056514 -389.315452) (xy 64.057784 -389.317992)
			(xy 64.070054 -389.340909) (xy 64.087461 -389.389886) (xy 64.096336 -389.441101) (xy 64.0969 -389.46709)
			(xy 64.0969 -389.467344) (xy 64.096479 -389.491324) (xy 64.088974 -389.538694) (xy 64.074156 -389.584307)
			(xy 64.052388 -389.627044) (xy 64.024207 -389.665851) (xy 63.990305 -389.699775) (xy 63.951516 -389.727982)
			(xy 63.908794 -389.749778) (xy 63.86319 -389.764627) (xy 63.815826 -389.772163) (xy 63.791846 -389.772652)
			(xy 63.791338 -389.772652) (xy 63.767675 -389.772182) (xy 63.720915 -389.764877) (xy 63.67584 -389.750452)
			(xy 63.633528 -389.729251) (xy 63.594989 -389.70178) (xy 63.561146 -389.668698) (xy 63.532807 -389.630794)
			(xy 63.521336 -389.610092) (xy 63.521082 -389.60933) (xy 63.508128 -389.586978) (xy 63.502721 -389.578553)
			(xy 63.486841 -389.566391) (xy 63.467517 -389.561229) (xy 63.447688 -389.563853) (xy 63.438786 -389.568436)
			(xy 63.429642 -389.57377) (xy 63.423546 -389.582152) (xy 63.412631 -389.596061) (xy 63.386543 -389.619923)
			(xy 63.356514 -389.638582) (xy 63.323566 -389.651402) (xy 63.288823 -389.657946) (xy 63.271146 -389.658352)
			(xy 63.270638 -389.658352) (xy 63.251862 -389.657869) (xy 63.21503 -389.650555) (xy 63.18033 -389.636201)
			(xy 63.149095 -389.615357) (xy 63.122522 -389.588824) (xy 63.101632 -389.557619) (xy 63.087227 -389.522941)
			(xy 63.079859 -389.486119) (xy 63.079376 -389.467344) (xy 63.079835 -389.44823) (xy 63.087403 -389.410759)
			(xy 63.102267 -389.375539) (xy 63.123833 -389.343975) (xy 63.151241 -389.317327) (xy 63.183399 -389.296657)
			(xy 63.201042 -389.28929) (xy 63.211202 -389.285226) (xy 63.226696 -389.269478) (xy 63.255906 -389.186166)
			(xy 63.259103 -389.17558) (xy 63.257145 -389.153584) (xy 63.252096 -389.143748) (xy 63.123826 -388.922006)
			(xy 63.111888 -388.897876) (xy 63.107079 -388.888345) (xy 63.091289 -388.874013) (xy 63.071042 -388.867326)
			(xy 63.049823 -388.869433) (xy 63.031286 -388.879973) (xy 63.024512 -388.888224) (xy 63.013597 -388.902295)
			(xy 62.987453 -388.926468) (xy 62.957285 -388.945382) (xy 62.924136 -388.958383) (xy 62.889153 -388.965022)
			(xy 62.87135 -388.96544) (xy 62.870842 -388.96544) (xy 62.843156 -388.963408) (xy 62.842902 -388.963408)
			(xy 62.833432 -388.962456) (xy 62.814915 -388.966785) (xy 62.799264 -388.977586) (xy 62.793626 -388.985252)
			(xy 62.742064 -389.060944) (xy 62.73704 -389.069077) (xy 62.732875 -389.087721) (xy 62.735813 -389.106597)
			(xy 62.740286 -389.115046) (xy 62.855856 -389.314944) (xy 62.85611 -389.315452) (xy 62.856364 -389.315452)
			(xy 62.857634 -389.317992) (xy 62.869868 -389.340915) (xy 62.887188 -389.389902) (xy 62.895975 -389.441111)
			(xy 62.896496 -389.46709) (xy 62.896496 -389.467344) (xy 62.896078 -389.491337) (xy 62.888565 -389.538731)
			(xy 62.873731 -389.584367) (xy 62.851941 -389.627121) (xy 62.823731 -389.665939) (xy 62.789797 -389.699868)
			(xy 62.750973 -389.72807) (xy 62.708215 -389.749852) (xy 62.662577 -389.764678) (xy 62.615181 -389.772182)
			(xy 62.591188 -389.772652) (xy 62.567523 -389.772222) (xy 62.520762 -389.76491) (xy 62.475686 -389.750477)
			(xy 62.433374 -389.729269) (xy 62.394836 -389.701793) (xy 62.360994 -389.668705) (xy 62.332656 -389.630796)
			(xy 62.321186 -389.610092) (xy 62.320932 -389.60933) (xy 62.307978 -389.586978) (xy 62.30252 -389.57859)
			(xy 62.286659 -389.566428) (xy 62.267352 -389.561257) (xy 62.247536 -389.563864) (xy 62.238636 -389.568436)
			(xy 62.229492 -389.57377) (xy 62.223396 -389.582152) (xy 62.212453 -389.596038) (xy 62.186372 -389.619901)
			(xy 62.15635 -389.638564) (xy 62.123408 -389.65139) (xy 62.088671 -389.657942) (xy 62.070996 -389.658352)
			(xy 62.070488 -389.658352) (xy 62.051723 -389.657859) (xy 62.014914 -389.650536) (xy 61.980241 -389.636175)
			(xy 61.949035 -389.615326) (xy 61.922495 -389.58879) (xy 61.90164 -389.557587) (xy 61.887273 -389.522916)
			(xy 61.879944 -389.486109) (xy 61.87948 -389.467344) (xy 61.879947 -389.448249) (xy 61.887509 -389.410814)
			(xy 61.902342 -389.375622) (xy 61.923856 -389.344067) (xy 61.951198 -389.317404) (xy 61.983283 -389.29669)
			(xy 62.000892 -389.28929) (xy 62.011052 -389.285226) (xy 62.026546 -389.269478) (xy 62.055756 -389.186166)
			(xy 62.058947 -389.175579) (xy 62.056991 -389.153585) (xy 62.051946 -389.143748) (xy 61.923676 -388.922006)
			(xy 61.911738 -388.897876) (xy 61.906858 -388.888386) (xy 61.891089 -388.87406) (xy 61.870862 -388.867369)
			(xy 61.849661 -388.869464) (xy 61.831135 -388.879984) (xy 61.824362 -388.888224) (xy 61.813402 -388.90229)
			(xy 61.787221 -388.926492) (xy 61.757007 -388.945421) (xy 61.723807 -388.95842) (xy 61.688773 -388.965039)
			(xy 61.670946 -388.96544) (xy 61.670438 -388.96544) (xy 61.663558 -388.965434) (xy 61.649829 -388.964546)
			(xy 61.643006 -388.963662) (xy 61.628528 -388.961376) (xy 61.601858 -388.97306) (xy 61.542168 -389.060944)
			(xy 61.537144 -389.069077) (xy 61.532979 -389.087721) (xy 61.535917 -389.106597) (xy 61.54039 -389.115046)
			(xy 61.65596 -389.314944) (xy 61.656214 -389.315452) (xy 61.656468 -389.315452) (xy 61.657738 -389.317992)
			(xy 61.669973 -389.340915) (xy 61.687292 -389.389902) (xy 61.696079 -389.441111) (xy 61.6966 -389.46709)
			(xy 61.6966 -389.467344) (xy 61.696178 -389.491337) (xy 61.688665 -389.538731) (xy 61.673831 -389.584366)
			(xy 61.652041 -389.627119) (xy 61.623832 -389.665938) (xy 61.589898 -389.699866) (xy 61.551075 -389.728069)
			(xy 61.508318 -389.749851) (xy 61.46268 -389.764677) (xy 61.415285 -389.772182) (xy 61.391292 -389.772652)
			(xy 61.367627 -389.772219) (xy 61.320866 -389.764907) (xy 61.27579 -389.750475) (xy 61.233478 -389.729268)
			(xy 61.19494 -389.701792) (xy 61.161098 -389.668705) (xy 61.13276 -389.630796) (xy 61.12129 -389.610092)
			(xy 61.121036 -389.60933) (xy 61.108082 -389.586978) (xy 61.10262 -389.578593) (xy 61.08676 -389.566431)
			(xy 61.067455 -389.561259) (xy 61.047639 -389.563864) (xy 61.03874 -389.568436) (xy 61.029596 -389.57377)
			(xy 61.0235 -389.582152) (xy 61.012554 -389.596036) (xy 60.986475 -389.619899) (xy 60.956453 -389.638562)
			(xy 60.923512 -389.651389) (xy 60.888774 -389.657941) (xy 60.8711 -389.658352) (xy 60.870592 -389.658352)
			(xy 60.851827 -389.657856) (xy 60.815019 -389.650534) (xy 60.780345 -389.636172) (xy 60.749139 -389.615324)
			(xy 60.722599 -389.588789) (xy 60.701745 -389.557587) (xy 60.687377 -389.522916) (xy 60.680048 -389.486109)
			(xy 60.679584 -389.467344) (xy 60.680049 -389.448248) (xy 60.687611 -389.410814) (xy 60.702444 -389.375621)
			(xy 60.723958 -389.344067) (xy 60.751301 -389.317404) (xy 60.783387 -389.29669) (xy 60.800996 -389.28929)
			(xy 60.811156 -389.285226) (xy 60.82665 -389.269478) (xy 60.85586 -389.186166) (xy 60.859051 -389.175579)
			(xy 60.857095 -389.153585) (xy 60.85205 -389.143748) (xy 60.72378 -388.922006) (xy 60.711842 -388.897876)
			(xy 60.707097 -388.888307) (xy 60.69129 -388.87397) (xy 60.671023 -388.867286) (xy 60.649788 -388.869405)
			(xy 60.631241 -388.879962) (xy 60.624466 -388.888224) (xy 60.613503 -388.902288) (xy 60.587323 -388.92649)
			(xy 60.557109 -388.945419) (xy 60.52391 -388.958419) (xy 60.488877 -388.965038) (xy 60.47105 -388.96544)
			(xy 60.470542 -388.96544) (xy 60.463662 -388.965434) (xy 60.449933 -388.964546) (xy 60.44311 -388.963662)
			(xy 60.428632 -388.961376) (xy 60.401962 -388.97306) (xy 60.342272 -389.060944) (xy 60.337248 -389.069077)
			(xy 60.333082 -389.087721) (xy 60.33602 -389.106597) (xy 60.340494 -389.115046) (xy 60.456064 -389.314944)
			(xy 60.456318 -389.315452) (xy 60.456572 -389.315452) (xy 60.457842 -389.317992) (xy 60.470077 -389.340915)
			(xy 60.487396 -389.389902) (xy 60.496183 -389.441111) (xy 60.496704 -389.46709) (xy 60.496704 -389.467344)
			(xy 60.496278 -389.491337) (xy 60.488765 -389.53873) (xy 60.473931 -389.584365) (xy 60.452142 -389.627118)
			(xy 60.423933 -389.665937) (xy 60.39 -389.699865) (xy 60.351177 -389.728067) (xy 60.308421 -389.74985)
			(xy 60.262783 -389.764676) (xy 60.215389 -389.772182) (xy 60.191396 -389.772652) (xy 60.167731 -389.772216)
			(xy 60.12097 -389.764905) (xy 60.075895 -389.750473) (xy 60.033582 -389.729266) (xy 59.995044 -389.701791)
			(xy 59.961202 -389.668704) (xy 59.932864 -389.630796) (xy 59.921394 -389.610092) (xy 59.92114 -389.60933)
			(xy 59.908186 -389.586978) (xy 59.902719 -389.578596) (xy 59.886862 -389.566434) (xy 59.867558 -389.561261)
			(xy 59.847743 -389.563865) (xy 59.838844 -389.568436) (xy 59.8297 -389.57377) (xy 59.823604 -389.582152)
			(xy 59.812656 -389.596034) (xy 59.786577 -389.619898) (xy 59.756556 -389.638561) (xy 59.723615 -389.651388)
			(xy 59.688878 -389.657941) (xy 59.671204 -389.658352) (xy 59.670696 -389.658352) (xy 59.651931 -389.657852)
			(xy 59.615123 -389.650531) (xy 59.58045 -389.63617) (xy 59.549243 -389.615322) (xy 59.522703 -389.588788)
			(xy 59.501849 -389.557586) (xy 59.487481 -389.522916) (xy 59.480152 -389.486109) (xy 59.479688 -389.467344)
			(xy 59.48015 -389.448248) (xy 59.487713 -389.410813) (xy 59.502546 -389.37562) (xy 59.524061 -389.344066)
			(xy 59.551404 -389.317403) (xy 59.58349 -389.29669) (xy 59.6011 -389.28929) (xy 59.61126 -389.285226)
			(xy 59.626754 -389.269478) (xy 59.655964 -389.186166) (xy 59.659154 -389.175579) (xy 59.657198 -389.153585)
			(xy 59.652154 -389.143748) (xy 59.523884 -388.922006) (xy 59.511946 -388.897876) (xy 59.507196 -388.88831)
			(xy 59.49139 -388.873974) (xy 59.471124 -388.867289) (xy 59.449891 -388.869407) (xy 59.431345 -388.879963)
			(xy 59.42457 -388.888224) (xy 59.413679 -388.902315) (xy 59.387529 -388.926486) (xy 59.357355 -388.945397)
			(xy 59.3242 -388.958393) (xy 59.289213 -388.965025) (xy 59.271408 -388.96544) (xy 59.2709 -388.96544)
			(xy 59.243214 -388.963408) (xy 59.24296 -388.963408) (xy 59.233492 -388.962423) (xy 59.214971 -388.966766)
			(xy 59.19932 -388.97758) (xy 59.193684 -388.985252) (xy 59.142122 -389.060944) (xy 59.137096 -389.069077)
			(xy 59.132926 -389.087721) (xy 59.135867 -389.106598) (xy 59.140344 -389.115046) (xy 59.255914 -389.314944)
			(xy 59.256168 -389.315452) (xy 59.256422 -389.315452) (xy 59.257692 -389.317992) (xy 59.269962 -389.340908)
			(xy 59.287369 -389.389886) (xy 59.296244 -389.441101) (xy 59.296808 -389.46709) (xy 59.296808 -389.467344)
			(xy 59.296379 -389.491324) (xy 59.288874 -389.538693) (xy 59.274056 -389.584306) (xy 59.252289 -389.627041)
			(xy 59.224109 -389.665848) (xy 59.190208 -389.699772) (xy 59.15142 -389.72798) (xy 59.1087 -389.749776)
			(xy 59.063097 -389.764625) (xy 59.015733 -389.772162) (xy 58.991754 -389.772652) (xy 58.991246 -389.772652)
			(xy 58.967583 -389.772176) (xy 58.920824 -389.764872) (xy 58.875749 -389.750448) (xy 58.833437 -389.729248)
			(xy 58.794898 -389.701778) (xy 58.761054 -389.668697) (xy 58.732715 -389.630794) (xy 58.721244 -389.610092)
			(xy 58.72099 -389.60933) (xy 58.708036 -389.586978) (xy 58.70262 -389.578559) (xy 58.686744 -389.566397)
			(xy 58.667423 -389.561233) (xy 58.647596 -389.563854) (xy 58.638694 -389.568436) (xy 58.62955 -389.57377)
			(xy 58.623454 -389.582152) (xy 58.612534 -389.596058) (xy 58.586448 -389.619919) (xy 58.55642 -389.638579)
			(xy 58.523473 -389.6514) (xy 58.48873 -389.657945) (xy 58.471054 -389.658352) (xy 58.470546 -389.658352)
			(xy 58.45177 -389.657861) (xy 58.414938 -389.650549) (xy 58.380239 -389.636196) (xy 58.349003 -389.615354)
			(xy 58.322431 -389.588822) (xy 58.301541 -389.557618) (xy 58.287135 -389.52294) (xy 58.279767 -389.486119)
			(xy 58.279284 -389.467344) (xy 58.279738 -389.448229) (xy 58.287306 -389.410758) (xy 58.302171 -389.375538)
			(xy 58.323738 -389.343974) (xy 58.351147 -389.317326) (xy 58.383306 -389.296656) (xy 58.40095 -389.28929)
			(xy 58.41111 -389.285226) (xy 58.426604 -389.269478) (xy 58.455814 -389.186166) (xy 58.45901 -389.17558)
			(xy 58.457052 -389.153584) (xy 58.452004 -389.143748) (xy 58.323734 -388.922006) (xy 58.311796 -388.897876)
			(xy 58.306975 -388.888351) (xy 58.291189 -388.874021) (xy 58.270945 -388.867332) (xy 58.249729 -388.869438)
			(xy 58.231194 -388.879974) (xy 58.22442 -388.888224) (xy 58.213484 -388.90231) (xy 58.187297 -388.92651)
			(xy 58.157077 -388.945436) (xy 58.123871 -388.95843) (xy 58.088833 -388.965042) (xy 58.071004 -388.96544)
			(xy 58.070496 -388.96544) (xy 58.063616 -388.965439) (xy 58.049886 -388.964548) (xy 58.043064 -388.963662)
			(xy 58.028586 -388.961376) (xy 58.001916 -388.97306) (xy 57.942226 -389.060944) (xy 57.937199 -389.069077)
			(xy 57.933029 -389.087721) (xy 57.935971 -389.106598) (xy 57.940448 -389.115046) (xy 58.056018 -389.314944)
			(xy 58.056272 -389.315452) (xy 58.056526 -389.315452) (xy 58.057796 -389.317992) (xy 58.070067 -389.340908)
			(xy 58.087474 -389.389886) (xy 58.096348 -389.441101) (xy 58.096912 -389.46709) (xy 58.096912 -389.467344)
			(xy 58.096479 -389.491324) (xy 58.088974 -389.538692) (xy 58.074157 -389.584305) (xy 58.05239 -389.62704)
			(xy 58.02421 -389.665847) (xy 57.99031 -389.699771) (xy 57.951523 -389.727978) (xy 57.908803 -389.749775)
			(xy 57.8632 -389.764624) (xy 57.815837 -389.772162) (xy 57.791858 -389.772652) (xy 57.79135 -389.772652)
			(xy 57.767687 -389.772172) (xy 57.720928 -389.764869) (xy 57.675853 -389.750446) (xy 57.633541 -389.729246)
			(xy 57.595002 -389.701777) (xy 57.561159 -389.668696) (xy 57.532819 -389.630793) (xy 57.521348 -389.610092)
			(xy 57.521094 -389.60933) (xy 57.50814 -389.586978) (xy 57.50272 -389.578562) (xy 57.486845 -389.566399)
			(xy 57.467525 -389.561236) (xy 57.447699 -389.563855) (xy 57.438798 -389.568436) (xy 57.429654 -389.57377)
			(xy 57.423558 -389.582152) (xy 57.412636 -389.596056) (xy 57.38655 -389.619918) (xy 57.356523 -389.638577)
			(xy 57.323576 -389.651399) (xy 57.288834 -389.657945) (xy 57.271158 -389.658352) (xy 57.27065 -389.658352)
			(xy 57.251875 -389.657858) (xy 57.215043 -389.650546) (xy 57.180343 -389.636194) (xy 57.149107 -389.615352)
			(xy 57.122535 -389.58882) (xy 57.101645 -389.557617) (xy 57.087239 -389.522939) (xy 57.079871 -389.486119)
			(xy 57.079388 -389.467344) (xy 57.079839 -389.448229) (xy 57.087408 -389.410757) (xy 57.102273 -389.375537)
			(xy 57.12384 -389.343973) (xy 57.151251 -389.317325) (xy 57.18341 -389.296656) (xy 57.201054 -389.28929)
			(xy 57.211214 -389.285226) (xy 57.226708 -389.269478) (xy 57.255918 -389.186166) (xy 57.259114 -389.17558)
			(xy 57.257156 -389.153584) (xy 57.252108 -389.143748) (xy 57.123838 -388.922006) (xy 57.1119 -388.897876)
			(xy 57.107074 -388.888355) (xy 57.091289 -388.874025) (xy 57.071047 -388.867336) (xy 57.049832 -388.86944)
			(xy 57.031298 -388.879975) (xy 57.024524 -388.888224) (xy 57.013602 -388.902289) (xy 56.98746 -388.926462)
			(xy 56.957293 -388.945377) (xy 56.924146 -388.95838) (xy 56.889165 -388.965021) (xy 56.871362 -388.96544)
			(xy 56.870854 -388.96544) (xy 56.843168 -388.963408) (xy 56.842914 -388.963408) (xy 56.833444 -388.962466)
			(xy 56.814928 -388.96679) (xy 56.799276 -388.977587) (xy 56.793638 -388.985252) (xy 56.742076 -389.060944)
			(xy 56.737052 -389.069077) (xy 56.732886 -389.087721) (xy 56.735824 -389.106597) (xy 56.740298 -389.115046)
			(xy 56.855868 -389.314944) (xy 56.856122 -389.315452) (xy 56.856376 -389.315452) (xy 56.857646 -389.317992)
			(xy 56.869881 -389.340915) (xy 56.8872 -389.389902) (xy 56.895987 -389.441111) (xy 56.896508 -389.46709)
			(xy 56.896508 -389.467344) (xy 56.896078 -389.491336) (xy 56.888565 -389.53873) (xy 56.873732 -389.584364)
			(xy 56.851943 -389.627117) (xy 56.823735 -389.665935) (xy 56.789802 -389.699863) (xy 56.750979 -389.728066)
			(xy 56.708224 -389.749849) (xy 56.662587 -389.764676) (xy 56.615192 -389.772181) (xy 56.5912 -389.772652)
			(xy 56.567536 -389.772213) (xy 56.520775 -389.764902) (xy 56.475699 -389.750471) (xy 56.433387 -389.729265)
			(xy 56.394849 -389.70179) (xy 56.361006 -389.668703) (xy 56.332668 -389.630796) (xy 56.321198 -389.610092)
			(xy 56.320944 -389.60933) (xy 56.30799 -389.586978) (xy 56.302519 -389.578599) (xy 56.286663 -389.566437)
			(xy 56.26736 -389.561263) (xy 56.247547 -389.563866) (xy 56.238648 -389.568436) (xy 56.229504 -389.57377)
			(xy 56.223408 -389.582152) (xy 56.212514 -389.596079) (xy 56.186422 -389.619939) (xy 56.156387 -389.638595)
			(xy 56.123434 -389.651411) (xy 56.088686 -389.657949) (xy 56.071008 -389.658352) (xy 56.0705 -389.658352)
			(xy 56.051735 -389.657848) (xy 56.014927 -389.650528) (xy 55.980254 -389.636168) (xy 55.949048 -389.615321)
			(xy 55.922507 -389.588786) (xy 55.901653 -389.557585) (xy 55.887285 -389.522915) (xy 55.879956 -389.486108)
			(xy 55.879492 -389.467344) (xy 55.880015 -389.448252) (xy 55.887573 -389.410824) (xy 55.902397 -389.375636)
			(xy 55.9239 -389.344083) (xy 55.95123 -389.317417) (xy 55.983301 -389.296696) (xy 56.000904 -389.28929)
			(xy 56.011064 -389.285226) (xy 56.026558 -389.269478) (xy 56.055768 -389.186166) (xy 56.058958 -389.175579)
			(xy 56.057002 -389.153585) (xy 56.051958 -389.143748) (xy 55.923688 -388.922006) (xy 55.91175 -388.897876)
			(xy 55.906994 -388.888313) (xy 55.89119 -388.873978) (xy 55.870926 -388.867293) (xy 55.849694 -388.86941)
			(xy 55.831149 -388.879964) (xy 55.824374 -388.888224) (xy 55.813464 -388.902332) (xy 55.78727 -388.92653)
			(xy 55.757044 -388.945453) (xy 55.723832 -388.958441) (xy 55.688789 -388.965046) (xy 55.670958 -388.96544)
			(xy 55.67045 -388.96544) (xy 55.66357 -388.965433) (xy 55.649841 -388.964546) (xy 55.643018 -388.963662)
			(xy 55.62854 -388.961376) (xy 55.60187 -388.97306) (xy 55.54218 -389.060944) (xy 55.537155 -389.069077)
			(xy 55.532989 -389.087721) (xy 55.535928 -389.106597) (xy 55.540402 -389.115046) (xy 55.655972 -389.314944)
			(xy 55.656226 -389.315452) (xy 55.65648 -389.315452) (xy 55.65775 -389.317992) (xy 55.669986 -389.340915)
			(xy 55.687304 -389.389901) (xy 55.696091 -389.441111) (xy 55.696612 -389.46709) (xy 55.696612 -389.467344)
			(xy 55.696178 -389.491336) (xy 55.688665 -389.538729) (xy 55.673832 -389.584363) (xy 55.652044 -389.627116)
			(xy 55.623836 -389.665934) (xy 55.589903 -389.699862) (xy 55.551082 -389.728065) (xy 55.508326 -389.749848)
			(xy 55.46269 -389.764675) (xy 55.415296 -389.772181) (xy 55.391304 -389.772652) (xy 55.36764 -389.772209)
			(xy 55.320879 -389.764899) (xy 55.275803 -389.750469) (xy 55.233491 -389.729263) (xy 55.194953 -389.701789)
			(xy 55.16111 -389.668703) (xy 55.132772 -389.630796) (xy 55.121302 -389.610092) (xy 55.121048 -389.60933)
			(xy 55.108094 -389.586978) (xy 55.102721 -389.578527) (xy 55.086829 -389.566366) (xy 55.067493 -389.56121)
			(xy 55.047656 -389.563846) (xy 55.038752 -389.568436) (xy 55.029608 -389.57377) (xy 55.023512 -389.582152)
			(xy 55.012616 -389.596078) (xy 54.986524 -389.619938) (xy 54.956489 -389.638594) (xy 54.923537 -389.65141)
			(xy 54.88879 -389.657949) (xy 54.871112 -389.658352) (xy 54.870604 -389.658352) (xy 54.85184 -389.657845)
			(xy 54.815031 -389.650525) (xy 54.780358 -389.636166) (xy 54.749152 -389.615319) (xy 54.722612 -389.588785)
			(xy 54.701757 -389.557584) (xy 54.687389 -389.522915) (xy 54.68006 -389.486108) (xy 54.679596 -389.467344)
			(xy 54.680116 -389.448252) (xy 54.687674 -389.410824) (xy 54.702499 -389.375636) (xy 54.724003 -389.344083)
			(xy 54.751333 -389.317417) (xy 54.783405 -389.296696) (xy 54.801008 -389.28929) (xy 54.811168 -389.285226)
			(xy 54.826662 -389.269478) (xy 54.855872 -389.186166) (xy 54.859061 -389.175579) (xy 54.857106 -389.153585)
			(xy 54.852062 -389.143748) (xy 54.723792 -388.922006) (xy 54.711854 -388.897876) (xy 54.707093 -388.888317)
			(xy 54.69129 -388.873981) (xy 54.671028 -388.867296) (xy 54.649797 -388.869412) (xy 54.631253 -388.879965)
			(xy 54.624478 -388.888224) (xy 54.613566 -388.90233) (xy 54.587373 -388.926529) (xy 54.557147 -388.945451)
			(xy 54.523936 -388.95844) (xy 54.488892 -388.965046) (xy 54.471062 -388.96544) (xy 54.470554 -388.96544)
			(xy 54.463674 -388.965432) (xy 54.449945 -388.964546) (xy 54.443122 -388.963662) (xy 54.428644 -388.961376)
			(xy 54.401974 -388.97306) (xy 54.342284 -389.060944) (xy 54.337259 -389.069077) (xy 54.333092 -389.087721)
			(xy 54.336031 -389.106598) (xy 54.340506 -389.115046) (xy 54.456076 -389.314944) (xy 54.45633 -389.315452)
			(xy 54.456584 -389.315452) (xy 54.457854 -389.317992) (xy 54.47009 -389.340915) (xy 54.487408 -389.389901)
			(xy 54.496195 -389.441111) (xy 54.496716 -389.46709) (xy 54.496716 -389.467344) (xy 54.496278 -389.491336)
			(xy 54.488766 -389.538728) (xy 54.473933 -389.584362) (xy 54.452144 -389.627115) (xy 54.423937 -389.665932)
			(xy 54.390005 -389.69986) (xy 54.351184 -389.728063) (xy 54.308429 -389.749846) (xy 54.262793 -389.764674)
			(xy 54.2154 -389.772181) (xy 54.191408 -389.772652) (xy 54.167744 -389.772206) (xy 54.120983 -389.764897)
			(xy 54.075908 -389.750467) (xy 54.033595 -389.729262) (xy 53.995057 -389.701788) (xy 53.961215 -389.668702)
			(xy 53.932876 -389.630795) (xy 53.921406 -389.610092) (xy 53.921152 -389.60933) (xy 53.908198 -389.586978)
			(xy 53.902821 -389.57853) (xy 53.88693 -389.566369) (xy 53.867596 -389.561213) (xy 53.84776 -389.563847)
			(xy 53.838856 -389.568436) (xy 53.829712 -389.57377) (xy 53.823616 -389.582152) (xy 53.812718 -389.596076)
			(xy 53.786626 -389.619936) (xy 53.756592 -389.638592) (xy 53.72364 -389.651409) (xy 53.688894 -389.657949)
			(xy 53.671216 -389.658352) (xy 53.670708 -389.658352) (xy 53.651944 -389.657841) (xy 53.615136 -389.650522)
			(xy 53.580462 -389.636164) (xy 53.549256 -389.615317) (xy 53.522716 -389.588784) (xy 53.501861 -389.557584)
			(xy 53.487493 -389.522914) (xy 53.480164 -389.486108) (xy 53.4797 -389.467344) (xy 53.480218 -389.448252)
			(xy 53.487776 -389.410823) (xy 53.502601 -389.375635) (xy 53.524105 -389.344082) (xy 53.551436 -389.317416)
			(xy 53.583509 -389.296695) (xy 53.601112 -389.28929) (xy 53.611272 -389.285226) (xy 53.626766 -389.269478)
			(xy 53.655976 -389.186166) (xy 53.659165 -389.175579) (xy 53.657209 -389.153585) (xy 53.652166 -389.143748)
			(xy 53.523896 -388.922006) (xy 53.511958 -388.897876) (xy 53.507191 -388.88832) (xy 53.49139 -388.873985)
			(xy 53.471129 -388.867299) (xy 53.4499 -388.869414) (xy 53.431357 -388.879966) (xy 53.424582 -388.888224)
			(xy 53.413685 -388.902309) (xy 53.387536 -388.926481) (xy 53.357363 -388.945393) (xy 53.32421 -388.95839)
			(xy 53.289224 -388.965024) (xy 53.27142 -388.96544) (xy 53.270912 -388.96544) (xy 53.243226 -388.963408)
			(xy 53.242972 -388.963408) (xy 53.233503 -388.962432) (xy 53.214984 -388.966771) (xy 53.199333 -388.977581)
			(xy 53.193696 -388.985252) (xy 53.142134 -389.060944) (xy 53.137107 -389.069076) (xy 53.132936 -389.087721)
			(xy 53.135878 -389.106598) (xy 53.140356 -389.115046) (xy 53.255926 -389.314944) (xy 53.25618 -389.315452)
			(xy 53.256434 -389.315452) (xy 53.257704 -389.317992) (xy 53.269975 -389.340908) (xy 53.287382 -389.389886)
			(xy 53.296256 -389.441101) (xy 53.29682 -389.46709) (xy 53.29682 -389.467344) (xy 53.296379 -389.491323)
			(xy 53.288875 -389.538691) (xy 53.274057 -389.584303) (xy 53.252292 -389.627038) (xy 53.224113 -389.665844)
			(xy 53.190213 -389.699768) (xy 53.151427 -389.727975) (xy 53.108708 -389.749772) (xy 53.063107 -389.764623)
			(xy 53.015745 -389.772162) (xy 52.991766 -389.772652) (xy 52.991258 -389.772652) (xy 52.967595 -389.772166)
			(xy 52.920836 -389.764864) (xy 52.875762 -389.750442) (xy 52.83345 -389.729243) (xy 52.794911 -389.701775)
			(xy 52.761067 -389.668695) (xy 52.732727 -389.630793) (xy 52.721256 -389.610092) (xy 52.721002 -389.60933)
			(xy 52.708048 -389.586978) (xy 52.70262 -389.578567) (xy 52.686748 -389.566405) (xy 52.667431 -389.56124)
			(xy 52.647607 -389.563857) (xy 52.638706 -389.568436) (xy 52.629562 -389.57377) (xy 52.623466 -389.582152)
			(xy 52.61254 -389.596052) (xy 52.586455 -389.619914) (xy 52.556428 -389.638574) (xy 52.523483 -389.651397)
			(xy 52.488742 -389.657944) (xy 52.471066 -389.658352) (xy 52.470558 -389.658352) (xy 52.451779 -389.657941)
			(xy 52.414944 -389.650613) (xy 52.380243 -389.636246) (xy 52.349009 -389.615391) (xy 52.322438 -389.588848)
			(xy 52.30155 -389.557635) (xy 52.287146 -389.52295) (xy 52.279779 -389.486122) (xy 52.279296 -389.467344)
			(xy 52.279742 -389.448229) (xy 52.287311 -389.410756) (xy 52.302177 -389.375536) (xy 52.323745 -389.343972)
			(xy 52.351157 -389.317324) (xy 52.383317 -389.296655) (xy 52.400962 -389.28929) (xy 52.411122 -389.285226)
			(xy 52.426616 -389.269478) (xy 52.455826 -389.186166) (xy 52.459021 -389.17558) (xy 52.457063 -389.153584)
			(xy 52.452016 -389.143748) (xy 52.323746 -388.922006) (xy 52.311808 -388.897876) (xy 52.306971 -388.888361)
			(xy 52.291189 -388.874032) (xy 52.27095 -388.867343) (xy 52.249738 -388.869445) (xy 52.231206 -388.879977)
			(xy 52.224432 -388.888224) (xy 52.213489 -388.902304) (xy 52.187303 -388.926505) (xy 52.157085 -388.945432)
			(xy 52.123881 -388.958427) (xy 52.088844 -388.965041) (xy 52.071016 -388.96544) (xy 52.070508 -388.96544)
			(xy 52.063628 -388.965437) (xy 52.049898 -388.964547) (xy 52.043076 -388.963662) (xy 52.028598 -388.961376)
			(xy 52.001928 -388.97306) (xy 51.942238 -389.060944) (xy 51.937211 -389.069076) (xy 51.93304 -389.087721)
			(xy 51.935982 -389.106599) (xy 51.94046 -389.115046) (xy 52.05603 -389.314944) (xy 52.056284 -389.315452)
			(xy 52.056538 -389.315452) (xy 52.057808 -389.317992) (xy 52.07008 -389.340908) (xy 52.087486 -389.389886)
			(xy 52.09636 -389.441101) (xy 52.096924 -389.46709) (xy 52.096924 -389.467344) (xy 52.096479 -389.491323)
			(xy 52.088975 -389.53869) (xy 52.074158 -389.584302) (xy 52.052392 -389.627036) (xy 52.024214 -389.665843)
			(xy 51.990315 -389.699767) (xy 51.951529 -389.727974) (xy 51.908811 -389.749771) (xy 51.86321 -389.764622)
			(xy 51.815849 -389.772161) (xy 51.79187 -389.772652) (xy 51.791362 -389.772652) (xy 51.767699 -389.772163)
			(xy 51.720941 -389.764861) (xy 51.675866 -389.750439) (xy 51.633554 -389.729241) (xy 51.595015 -389.701774)
			(xy 51.561171 -389.668695) (xy 51.532831 -389.630793) (xy 51.52136 -389.610092) (xy 51.521106 -389.60933)
			(xy 51.508152 -389.586978) (xy 51.50272 -389.57857) (xy 51.48685 -389.566408) (xy 51.467534 -389.561242)
			(xy 51.447711 -389.563858) (xy 51.43881 -389.568436) (xy 51.429666 -389.57377) (xy 51.42357 -389.582152)
			(xy 51.412641 -389.59605) (xy 51.386557 -389.619912) (xy 51.356531 -389.638573) (xy 51.323586 -389.651396)
			(xy 51.288846 -389.657944) (xy 51.27117 -389.658352) (xy 51.270662 -389.658352) (xy 51.251884 -389.657938)
			(xy 51.215048 -389.65061) (xy 51.180348 -389.636244) (xy 51.149113 -389.615389) (xy 51.122542 -389.588847)
			(xy 51.101654 -389.557634) (xy 51.08725 -389.522949) (xy 51.079883 -389.486122) (xy 51.0794 -389.467344)
			(xy 51.079843 -389.448229) (xy 51.087413 -389.410756) (xy 51.102279 -389.375535) (xy 51.123848 -389.343971)
			(xy 51.15126 -389.317323) (xy 51.183421 -389.296655) (xy 51.201066 -389.28929) (xy 51.211226 -389.285226)
			(xy 51.22672 -389.269478) (xy 51.25593 -389.186166) (xy 51.259124 -389.17558) (xy 51.257167 -389.153584)
			(xy 51.25212 -389.143748) (xy 51.12385 -388.922006) (xy 51.111912 -388.897876) (xy 51.107069 -388.888364)
			(xy 51.091289 -388.874036) (xy 51.071052 -388.867346) (xy 51.049841 -388.869447) (xy 51.031309 -388.879978)
			(xy 51.024536 -388.888224) (xy 51.013608 -388.902283) (xy 50.987467 -388.926457) (xy 50.957302 -388.945373)
			(xy 50.924156 -388.958377) (xy 50.889176 -388.96502) (xy 50.871374 -388.96544) (xy 50.870866 -388.96544)
			(xy 50.84318 -388.963408) (xy 50.842926 -388.963408) (xy 50.833459 -388.962396) (xy 50.814935 -388.966751)
			(xy 50.799285 -388.977575) (xy 50.79365 -388.985252) (xy 50.742088 -389.060944) (xy 50.737063 -389.069077)
			(xy 50.732896 -389.087721) (xy 50.735835 -389.106598) (xy 50.74031 -389.115046) (xy 50.85588 -389.314944)
			(xy 50.856134 -389.315452) (xy 50.856388 -389.315452) (xy 50.857658 -389.317992) (xy 50.869894 -389.340914)
			(xy 50.887212 -389.389901) (xy 50.895999 -389.441111) (xy 50.89652 -389.46709) (xy 50.89652 -389.467344)
			(xy 50.896078 -389.491336) (xy 50.888566 -389.538728) (xy 50.873733 -389.584362) (xy 50.851945 -389.627113)
			(xy 50.823738 -389.665931) (xy 50.789807 -389.699859) (xy 50.750986 -389.728062) (xy 50.708232 -389.749845)
			(xy 50.662597 -389.764673) (xy 50.615204 -389.772181) (xy 50.591212 -389.772652) (xy 50.567548 -389.772203)
			(xy 50.520787 -389.764894) (xy 50.475712 -389.750465) (xy 50.4334 -389.72926) (xy 50.394862 -389.701787)
			(xy 50.361019 -389.668702) (xy 50.33268 -389.630795) (xy 50.32121 -389.610092) (xy 50.320956 -389.60933)
			(xy 50.308002 -389.586978) (xy 50.302621 -389.578533) (xy 50.286732 -389.566372) (xy 50.267399 -389.561215)
			(xy 50.247564 -389.563847) (xy 50.23866 -389.568436) (xy 50.229516 -389.57377) (xy 50.22342 -389.582152)
			(xy 50.21252 -389.596074) (xy 50.186428 -389.619934) (xy 50.156395 -389.638591) (xy 50.123444 -389.651408)
			(xy 50.088698 -389.657948) (xy 50.07102 -389.658352) (xy 50.070512 -389.658352) (xy 50.051748 -389.657837)
			(xy 50.01494 -389.650519) (xy 49.980267 -389.636161) (xy 49.94906 -389.615316) (xy 49.92252 -389.588783)
			(xy 49.901665 -389.557583) (xy 49.887297 -389.522914) (xy 49.879968 -389.486108) (xy 49.879504 -389.467344)
			(xy 49.880019 -389.448252) (xy 49.887578 -389.410823) (xy 49.902403 -389.375634) (xy 49.923908 -389.344081)
			(xy 49.951239 -389.317416) (xy 49.983312 -389.296695) (xy 50.000916 -389.28929) (xy 50.011076 -389.285226)
			(xy 50.02657 -389.269478) (xy 50.05578 -389.186166) (xy 50.058968 -389.175579) (xy 50.057013 -389.153585)
			(xy 50.05197 -389.143748) (xy 49.9237 -388.922006) (xy 49.911762 -388.897876) (xy 49.906989 -388.888323)
			(xy 49.89119 -388.873989) (xy 49.870931 -388.867303) (xy 49.849703 -388.869417) (xy 49.831161 -388.879967)
			(xy 49.824386 -388.888224) (xy 49.813469 -388.902326) (xy 49.787277 -388.926525) (xy 49.757052 -388.945448)
			(xy 49.723843 -388.958438) (xy 49.6888 -388.965045) (xy 49.67097 -388.96544) (xy 49.670462 -388.96544)
			(xy 49.663582 -388.965442) (xy 49.649852 -388.964549) (xy 49.64303 -388.963662) (xy 49.628552 -388.961376)
			(xy 49.601882 -388.97306) (xy 49.542192 -389.060944) (xy 49.537167 -389.069077) (xy 49.532999 -389.087721)
			(xy 49.535939 -389.106598) (xy 49.540414 -389.115046) (xy 49.655984 -389.314944) (xy 49.656238 -389.315452)
			(xy 49.656492 -389.315452) (xy 49.657762 -389.317992) (xy 49.669999 -389.340914) (xy 49.687316 -389.389901)
			(xy 49.696103 -389.441111) (xy 49.696624 -389.46709) (xy 49.696624 -389.467344) (xy 49.696178 -389.491336)
			(xy 49.688666 -389.538727) (xy 49.673833 -389.584361) (xy 49.652046 -389.627112) (xy 49.623839 -389.66593)
			(xy 49.589908 -389.699858) (xy 49.551088 -389.72806) (xy 49.508335 -389.749844) (xy 49.4627 -389.764672)
			(xy 49.415308 -389.77218) (xy 49.391316 -389.772652) (xy 49.367652 -389.7722) (xy 49.320892 -389.764892)
			(xy 49.275816 -389.750463) (xy 49.233504 -389.729259) (xy 49.194966 -389.701786) (xy 49.161123 -389.668701)
			(xy 49.132784 -389.630795) (xy 49.121314 -389.610092) (xy 49.12106 -389.60933) (xy 49.108106 -389.586978)
			(xy 49.102721 -389.578536) (xy 49.086833 -389.566375) (xy 49.067502 -389.561217) (xy 49.047667 -389.563848)
			(xy 49.038764 -389.568436) (xy 49.02962 -389.57377) (xy 49.023524 -389.582152) (xy 49.012621 -389.596072)
			(xy 48.986531 -389.619932) (xy 48.956498 -389.63859) (xy 48.923547 -389.651407) (xy 48.888802 -389.657948)
			(xy 48.871124 -389.658352) (xy 48.870616 -389.658352) (xy 48.851852 -389.657834) (xy 48.815044 -389.650516)
			(xy 48.780371 -389.636159) (xy 48.749165 -389.615314) (xy 48.722624 -389.588782) (xy 48.701769 -389.557582)
			(xy 48.687401 -389.522913) (xy 48.680072 -389.486108) (xy 48.679608 -389.467344) (xy 48.680121 -389.448252)
			(xy 48.687679 -389.410822) (xy 48.702505 -389.375634) (xy 48.72401 -389.344081) (xy 48.751342 -389.317415)
			(xy 48.783416 -389.296695) (xy 48.80102 -389.28929) (xy 48.81118 -389.285226) (xy 48.826674 -389.269478)
			(xy 48.855884 -389.186166) (xy 48.859072 -389.175579) (xy 48.857117 -389.153585) (xy 48.852074 -389.143748)
			(xy 48.723804 -388.922006) (xy 48.711866 -388.897876) (xy 48.707088 -388.888326) (xy 48.69129 -388.873993)
			(xy 48.671033 -388.867306) (xy 48.649806 -388.869419) (xy 48.631265 -388.879967) (xy 48.62449 -388.888224)
			(xy 48.613571 -388.902324) (xy 48.58738 -388.926524) (xy 48.557155 -388.945447) (xy 48.523946 -388.958437)
			(xy 48.488904 -388.965045) (xy 48.471074 -388.96544) (xy 48.470566 -388.96544) (xy 48.463686 -388.965442)
			(xy 48.449956 -388.964549) (xy 48.443134 -388.963662) (xy 48.428656 -388.961376) (xy 48.401986 -388.97306)
			(xy 48.342296 -389.060944) (xy 48.337271 -389.069077) (xy 48.333103 -389.087721) (xy 48.336042 -389.106598)
			(xy 48.340518 -389.115046) (xy 48.456088 -389.314944) (xy 48.456342 -389.315452) (xy 48.456596 -389.315452)
			(xy 48.457866 -389.317992) (xy 48.470103 -389.340914) (xy 48.48742 -389.389901) (xy 48.496207 -389.441111)
			(xy 48.496728 -389.46709) (xy 48.496728 -389.467344) (xy 48.496278 -389.491335) (xy 48.488766 -389.538727)
			(xy 48.473934 -389.58436) (xy 48.452147 -389.627111) (xy 48.423941 -389.665928) (xy 48.39001 -389.699856)
			(xy 48.351191 -389.728059) (xy 48.308437 -389.749843) (xy 48.262803 -389.764672) (xy 48.215411 -389.77218)
			(xy 48.19142 -389.772652) (xy 48.167756 -389.772196) (xy 48.120996 -389.764889) (xy 48.075921 -389.750461)
			(xy 48.033608 -389.729257) (xy 47.99507 -389.701785) (xy 47.961227 -389.668701) (xy 47.932888 -389.630795)
			(xy 47.921418 -389.610092) (xy 47.921164 -389.60933) (xy 47.90821 -389.586978) (xy 47.902821 -389.578539)
			(xy 47.886935 -389.566377) (xy 47.867604 -389.561219) (xy 47.847771 -389.563849) (xy 47.838868 -389.568436)
			(xy 47.829724 -389.57377) (xy 47.823628 -389.582152) (xy 47.812723 -389.59607) (xy 47.786633 -389.619931)
			(xy 47.756601 -389.638588) (xy 47.723651 -389.651406) (xy 47.688905 -389.657948) (xy 47.671228 -389.658352)
			(xy 47.67072 -389.658352) (xy 47.651956 -389.65783) (xy 47.615148 -389.650513) (xy 47.580475 -389.636157)
			(xy 47.549269 -389.615312) (xy 47.522728 -389.588781) (xy 47.501873 -389.557581) (xy 47.487505 -389.522913)
			(xy 47.480176 -389.486108) (xy 47.479712 -389.467344) (xy 47.480222 -389.448251) (xy 47.487781 -389.410822)
			(xy 47.502607 -389.375633) (xy 47.524113 -389.34408) (xy 47.551445 -389.317414) (xy 47.58352 -389.296695)
			(xy 47.601124 -389.28929) (xy 47.611284 -389.285226) (xy 47.626778 -389.269478) (xy 47.655988 -389.186166)
			(xy 47.659187 -389.175581) (xy 47.657228 -389.153584) (xy 47.652178 -389.143748) (xy 47.523908 -388.922006)
			(xy 47.51197 -388.897876) (xy 47.507186 -388.88833) (xy 47.49139 -388.873996) (xy 47.471134 -388.86731)
			(xy 47.449909 -388.869422) (xy 47.431368 -388.879968) (xy 47.424594 -388.888224) (xy 47.41369 -388.902303)
			(xy 47.387543 -388.926475) (xy 47.357372 -388.945388) (xy 47.324221 -388.958387) (xy 47.289236 -388.965023)
			(xy 47.271432 -388.96544) (xy 47.270924 -388.96544) (xy 47.250901 -388.964892) (xy 47.21173 -388.95657)
			(xy 47.175144 -388.940286) (xy 47.142745 -388.91675) (xy 47.115947 -388.886992) (xy 47.095923 -388.852312)
			(xy 47.083547 -388.814226) (xy 47.079361 -388.7744) (xy 2.509012 -388.7744) (xy 2.509012 -390.761474)
			(xy 47.264307 -390.761474) (xy 47.268449 -390.726032) (xy 47.280653 -390.692501) (xy 47.300262 -390.662688)
			(xy 47.326217 -390.638201) (xy 47.357119 -390.620359) (xy 47.391303 -390.610125) (xy 47.426926 -390.608051)
			(xy 47.462067 -390.614247) (xy 47.494832 -390.62838) (xy 47.523454 -390.649689) (xy 47.546391 -390.677024)
			(xy 47.562405 -390.708911) (xy 47.570634 -390.743632) (xy 47.571152 -390.761474) (xy 48.464203 -390.761474)
			(xy 48.468345 -390.726032) (xy 48.480549 -390.692501) (xy 48.500158 -390.662688) (xy 48.526113 -390.638201)
			(xy 48.557015 -390.620359) (xy 48.591199 -390.610125) (xy 48.626822 -390.608051) (xy 48.661963 -390.614247)
			(xy 48.694728 -390.62838) (xy 48.72335 -390.649689) (xy 48.746287 -390.677024) (xy 48.762301 -390.708911)
			(xy 48.77053 -390.743632) (xy 48.771048 -390.761474) (xy 49.664353 -390.761474) (xy 49.668495 -390.726032)
			(xy 49.680699 -390.692501) (xy 49.700308 -390.662688) (xy 49.726263 -390.638201) (xy 49.757165 -390.620359)
			(xy 49.791349 -390.610125) (xy 49.826972 -390.608051) (xy 49.862113 -390.614247) (xy 49.894878 -390.62838)
			(xy 49.9235 -390.649689) (xy 49.946437 -390.677024) (xy 49.962451 -390.708911) (xy 49.97068 -390.743632)
			(xy 49.971198 -390.761474) (xy 50.864249 -390.761474) (xy 50.868391 -390.726032) (xy 50.880595 -390.692501)
			(xy 50.900204 -390.662688) (xy 50.926159 -390.638201) (xy 50.957061 -390.620359) (xy 50.991245 -390.610125)
			(xy 51.026868 -390.608051) (xy 51.062009 -390.614247) (xy 51.094774 -390.62838) (xy 51.123396 -390.649689)
			(xy 51.146333 -390.677024) (xy 51.162347 -390.708911) (xy 51.170576 -390.743632) (xy 51.171094 -390.761474)
			(xy 52.064399 -390.761474) (xy 52.068541 -390.726032) (xy 52.080745 -390.692501) (xy 52.100354 -390.662688)
			(xy 52.126309 -390.638201) (xy 52.157211 -390.620359) (xy 52.191395 -390.610125) (xy 52.227018 -390.608051)
			(xy 52.262159 -390.614247) (xy 52.294924 -390.62838) (xy 52.323546 -390.649689) (xy 52.346483 -390.677024)
			(xy 52.362497 -390.708911) (xy 52.370726 -390.743632) (xy 52.371244 -390.761474) (xy 53.264295 -390.761474)
			(xy 53.268437 -390.726032) (xy 53.280641 -390.692501) (xy 53.30025 -390.662688) (xy 53.326205 -390.638201)
			(xy 53.357107 -390.620359) (xy 53.391291 -390.610125) (xy 53.426914 -390.608051) (xy 53.462055 -390.614247)
			(xy 53.49482 -390.62838) (xy 53.523442 -390.649689) (xy 53.546379 -390.677024) (xy 53.562393 -390.708911)
			(xy 53.570622 -390.743632) (xy 53.57114 -390.761474) (xy 54.464445 -390.761474) (xy 54.468587 -390.726032)
			(xy 54.480791 -390.692501) (xy 54.5004 -390.662688) (xy 54.526355 -390.638201) (xy 54.557257 -390.620359)
			(xy 54.591441 -390.610125) (xy 54.627064 -390.608051) (xy 54.662205 -390.614247) (xy 54.69497 -390.62838)
			(xy 54.723592 -390.649689) (xy 54.746529 -390.677024) (xy 54.762543 -390.708911) (xy 54.770772 -390.743632)
			(xy 54.77129 -390.761474) (xy 55.664341 -390.761474) (xy 55.668483 -390.726032) (xy 55.680687 -390.692501)
			(xy 55.700296 -390.662688) (xy 55.726251 -390.638201) (xy 55.757153 -390.620359) (xy 55.791337 -390.610125)
			(xy 55.82696 -390.608051) (xy 55.862101 -390.614247) (xy 55.894866 -390.62838) (xy 55.923488 -390.649689)
			(xy 55.946425 -390.677024) (xy 55.962439 -390.708911) (xy 55.970668 -390.743632) (xy 55.971186 -390.761474)
			(xy 56.864237 -390.761474) (xy 56.868379 -390.726032) (xy 56.880583 -390.692501) (xy 56.900192 -390.662688)
			(xy 56.926147 -390.638201) (xy 56.957049 -390.620359) (xy 56.991233 -390.610125) (xy 57.026856 -390.608051)
			(xy 57.061997 -390.614247) (xy 57.094762 -390.62838) (xy 57.123384 -390.649689) (xy 57.146321 -390.677024)
			(xy 57.162335 -390.708911) (xy 57.170564 -390.743632) (xy 57.171082 -390.761474) (xy 58.064387 -390.761474)
			(xy 58.068529 -390.726032) (xy 58.080733 -390.692501) (xy 58.100342 -390.662688) (xy 58.126297 -390.638201)
			(xy 58.157199 -390.620359) (xy 58.191383 -390.610125) (xy 58.227006 -390.608051) (xy 58.262147 -390.614247)
			(xy 58.294912 -390.62838) (xy 58.323534 -390.649689) (xy 58.346471 -390.677024) (xy 58.362485 -390.708911)
			(xy 58.370714 -390.743632) (xy 58.371232 -390.761474) (xy 59.264283 -390.761474) (xy 59.268425 -390.726032)
			(xy 59.280629 -390.692501) (xy 59.300238 -390.662688) (xy 59.326193 -390.638201) (xy 59.357095 -390.620359)
			(xy 59.391279 -390.610125) (xy 59.426902 -390.608051) (xy 59.462043 -390.614247) (xy 59.494808 -390.62838)
			(xy 59.52343 -390.649689) (xy 59.546367 -390.677024) (xy 59.562381 -390.708911) (xy 59.57061 -390.743632)
			(xy 59.571128 -390.761474) (xy 60.464433 -390.761474) (xy 60.468575 -390.726032) (xy 60.480779 -390.692501)
			(xy 60.500388 -390.662688) (xy 60.526343 -390.638201) (xy 60.557245 -390.620359) (xy 60.591429 -390.610125)
			(xy 60.627052 -390.608051) (xy 60.662193 -390.614247) (xy 60.694958 -390.62838) (xy 60.72358 -390.649689)
			(xy 60.746517 -390.677024) (xy 60.762531 -390.708911) (xy 60.77076 -390.743632) (xy 60.771278 -390.761474)
			(xy 61.664329 -390.761474) (xy 61.668471 -390.726032) (xy 61.680675 -390.692501) (xy 61.700284 -390.662688)
			(xy 61.726239 -390.638201) (xy 61.757141 -390.620359) (xy 61.791325 -390.610125) (xy 61.826948 -390.608051)
			(xy 61.862089 -390.614247) (xy 61.894854 -390.62838) (xy 61.923476 -390.649689) (xy 61.946413 -390.677024)
			(xy 61.962427 -390.708911) (xy 61.970656 -390.743632) (xy 61.971174 -390.761474) (xy 62.864225 -390.761474)
			(xy 62.868367 -390.726032) (xy 62.880571 -390.692501) (xy 62.90018 -390.662688) (xy 62.926135 -390.638201)
			(xy 62.957037 -390.620359) (xy 62.991221 -390.610125) (xy 63.026844 -390.608051) (xy 63.061985 -390.614247)
			(xy 63.09475 -390.62838) (xy 63.123372 -390.649689) (xy 63.146309 -390.677024) (xy 63.162323 -390.708911)
			(xy 63.170552 -390.743632) (xy 63.17107 -390.761474) (xy 64.064375 -390.761474) (xy 64.068517 -390.726032)
			(xy 64.080721 -390.692501) (xy 64.10033 -390.662688) (xy 64.126285 -390.638201) (xy 64.157187 -390.620359)
			(xy 64.191371 -390.610125) (xy 64.226994 -390.608051) (xy 64.262135 -390.614247) (xy 64.2949 -390.62838)
			(xy 64.323522 -390.649689) (xy 64.346459 -390.677024) (xy 64.362473 -390.708911) (xy 64.370702 -390.743632)
			(xy 64.37122 -390.761474) (xy 65.264271 -390.761474) (xy 65.268413 -390.726032) (xy 65.280617 -390.692501)
			(xy 65.300226 -390.662688) (xy 65.326181 -390.638201) (xy 65.357083 -390.620359) (xy 65.391267 -390.610125)
			(xy 65.42689 -390.608051) (xy 65.462031 -390.614247) (xy 65.494796 -390.62838) (xy 65.523418 -390.649689)
			(xy 65.546355 -390.677024) (xy 65.562369 -390.708911) (xy 65.570598 -390.743632) (xy 65.571116 -390.761474)
			(xy 79.792055 -390.761474) (xy 79.796197 -390.726032) (xy 79.808401 -390.692501) (xy 79.82801 -390.662688)
			(xy 79.853965 -390.638201) (xy 79.884867 -390.620359) (xy 79.919051 -390.610125) (xy 79.954674 -390.608051)
			(xy 79.989815 -390.614247) (xy 80.02258 -390.62838) (xy 80.051202 -390.649689) (xy 80.074139 -390.677024)
			(xy 80.090153 -390.708911) (xy 80.098382 -390.743632) (xy 80.0989 -390.761474) (xy 80.991951 -390.761474)
			(xy 80.996093 -390.726032) (xy 81.008297 -390.692501) (xy 81.027906 -390.662688) (xy 81.053861 -390.638201)
			(xy 81.084763 -390.620359) (xy 81.118947 -390.610125) (xy 81.15457 -390.608051) (xy 81.189711 -390.614247)
			(xy 81.222476 -390.62838) (xy 81.251098 -390.649689) (xy 81.274035 -390.677024) (xy 81.290049 -390.708911)
			(xy 81.298278 -390.743632) (xy 81.298796 -390.761474) (xy 82.192101 -390.761474) (xy 82.196243 -390.726032)
			(xy 82.208447 -390.692501) (xy 82.228056 -390.662688) (xy 82.254011 -390.638201) (xy 82.284913 -390.620359)
			(xy 82.319097 -390.610125) (xy 82.35472 -390.608051) (xy 82.389861 -390.614247) (xy 82.422626 -390.62838)
			(xy 82.451248 -390.649689) (xy 82.474185 -390.677024) (xy 82.490199 -390.708911) (xy 82.498428 -390.743632)
			(xy 82.498946 -390.761474) (xy 83.391997 -390.761474) (xy 83.396139 -390.726032) (xy 83.408343 -390.692501)
			(xy 83.427952 -390.662688) (xy 83.453907 -390.638201) (xy 83.484809 -390.620359) (xy 83.518993 -390.610125)
			(xy 83.554616 -390.608051) (xy 83.589757 -390.614247) (xy 83.622522 -390.62838) (xy 83.651144 -390.649689)
			(xy 83.674081 -390.677024) (xy 83.690095 -390.708911) (xy 83.698324 -390.743632) (xy 83.698842 -390.761474)
			(xy 84.592147 -390.761474) (xy 84.596289 -390.726032) (xy 84.608493 -390.692501) (xy 84.628102 -390.662688)
			(xy 84.654057 -390.638201) (xy 84.684959 -390.620359) (xy 84.719143 -390.610125) (xy 84.754766 -390.608051)
			(xy 84.789907 -390.614247) (xy 84.822672 -390.62838) (xy 84.851294 -390.649689) (xy 84.874231 -390.677024)
			(xy 84.890245 -390.708911) (xy 84.898474 -390.743632) (xy 84.898992 -390.761474) (xy 85.792043 -390.761474)
			(xy 85.796185 -390.726032) (xy 85.808389 -390.692501) (xy 85.827998 -390.662688) (xy 85.853953 -390.638201)
			(xy 85.884855 -390.620359) (xy 85.919039 -390.610125) (xy 85.954662 -390.608051) (xy 85.989803 -390.614247)
			(xy 86.022568 -390.62838) (xy 86.05119 -390.649689) (xy 86.074127 -390.677024) (xy 86.090141 -390.708911)
			(xy 86.09837 -390.743632) (xy 86.098888 -390.761474) (xy 86.992193 -390.761474) (xy 86.996335 -390.726032)
			(xy 87.008539 -390.692501) (xy 87.028148 -390.662688) (xy 87.054103 -390.638201) (xy 87.085005 -390.620359)
			(xy 87.119189 -390.610125) (xy 87.154812 -390.608051) (xy 87.189953 -390.614247) (xy 87.222718 -390.62838)
			(xy 87.25134 -390.649689) (xy 87.274277 -390.677024) (xy 87.290291 -390.708911) (xy 87.29852 -390.743632)
			(xy 87.299038 -390.761474) (xy 88.192089 -390.761474) (xy 88.196231 -390.726032) (xy 88.208435 -390.692501)
			(xy 88.228044 -390.662688) (xy 88.253999 -390.638201) (xy 88.284901 -390.620359) (xy 88.319085 -390.610125)
			(xy 88.354708 -390.608051) (xy 88.389849 -390.614247) (xy 88.422614 -390.62838) (xy 88.451236 -390.649689)
			(xy 88.474173 -390.677024) (xy 88.490187 -390.708911) (xy 88.498416 -390.743632) (xy 88.498934 -390.761474)
			(xy 89.391985 -390.761474) (xy 89.396127 -390.726032) (xy 89.408331 -390.692501) (xy 89.42794 -390.662688)
			(xy 89.453895 -390.638201) (xy 89.484797 -390.620359) (xy 89.518981 -390.610125) (xy 89.554604 -390.608051)
			(xy 89.589745 -390.614247) (xy 89.62251 -390.62838) (xy 89.651132 -390.649689) (xy 89.674069 -390.677024)
			(xy 89.690083 -390.708911) (xy 89.698312 -390.743632) (xy 89.69883 -390.761474) (xy 90.592135 -390.761474)
			(xy 90.596277 -390.726032) (xy 90.608481 -390.692501) (xy 90.62809 -390.662688) (xy 90.654045 -390.638201)
			(xy 90.684947 -390.620359) (xy 90.719131 -390.610125) (xy 90.754754 -390.608051) (xy 90.789895 -390.614247)
			(xy 90.82266 -390.62838) (xy 90.851282 -390.649689) (xy 90.874219 -390.677024) (xy 90.890233 -390.708911)
			(xy 90.898462 -390.743632) (xy 90.89898 -390.761474) (xy 91.792031 -390.761474) (xy 91.796173 -390.726032)
			(xy 91.808377 -390.692501) (xy 91.827986 -390.662688) (xy 91.853941 -390.638201) (xy 91.884843 -390.620359)
			(xy 91.919027 -390.610125) (xy 91.95465 -390.608051) (xy 91.989791 -390.614247) (xy 92.022556 -390.62838)
			(xy 92.051178 -390.649689) (xy 92.074115 -390.677024) (xy 92.090129 -390.708911) (xy 92.098358 -390.743632)
			(xy 92.098876 -390.761474) (xy 92.992181 -390.761474) (xy 92.996323 -390.726032) (xy 93.008527 -390.692501)
			(xy 93.028136 -390.662688) (xy 93.054091 -390.638201) (xy 93.084993 -390.620359) (xy 93.119177 -390.610125)
			(xy 93.1548 -390.608051) (xy 93.189941 -390.614247) (xy 93.222706 -390.62838) (xy 93.251328 -390.649689)
			(xy 93.274265 -390.677024) (xy 93.290279 -390.708911) (xy 93.298508 -390.743632) (xy 93.299026 -390.761474)
			(xy 94.192077 -390.761474) (xy 94.196219 -390.726032) (xy 94.208423 -390.692501) (xy 94.228032 -390.662688)
			(xy 94.253987 -390.638201) (xy 94.284889 -390.620359) (xy 94.319073 -390.610125) (xy 94.354696 -390.608051)
			(xy 94.389837 -390.614247) (xy 94.422602 -390.62838) (xy 94.451224 -390.649689) (xy 94.474161 -390.677024)
			(xy 94.490175 -390.708911) (xy 94.498404 -390.743632) (xy 94.498922 -390.761474) (xy 95.391973 -390.761474)
			(xy 95.396115 -390.726032) (xy 95.408319 -390.692501) (xy 95.427928 -390.662688) (xy 95.453883 -390.638201)
			(xy 95.484785 -390.620359) (xy 95.518969 -390.610125) (xy 95.554592 -390.608051) (xy 95.589733 -390.614247)
			(xy 95.622498 -390.62838) (xy 95.65112 -390.649689) (xy 95.674057 -390.677024) (xy 95.690071 -390.708911)
			(xy 95.6983 -390.743632) (xy 95.698818 -390.761474) (xy 96.592123 -390.761474) (xy 96.596265 -390.726032)
			(xy 96.608469 -390.692501) (xy 96.628078 -390.662688) (xy 96.654033 -390.638201) (xy 96.684935 -390.620359)
			(xy 96.719119 -390.610125) (xy 96.754742 -390.608051) (xy 96.789883 -390.614247) (xy 96.822648 -390.62838)
			(xy 96.85127 -390.649689) (xy 96.874207 -390.677024) (xy 96.890221 -390.708911) (xy 96.89845 -390.743632)
			(xy 96.898968 -390.761474) (xy 97.792019 -390.761474) (xy 97.796161 -390.726032) (xy 97.808365 -390.692501)
			(xy 97.827974 -390.662688) (xy 97.853929 -390.638201) (xy 97.884831 -390.620359) (xy 97.919015 -390.610125)
			(xy 97.954638 -390.608051) (xy 97.989779 -390.614247) (xy 98.022544 -390.62838) (xy 98.051166 -390.649689)
			(xy 98.074103 -390.677024) (xy 98.090117 -390.708911) (xy 98.098346 -390.743632) (xy 98.098864 -390.761474)
			(xy 114.364249 -390.761474) (xy 114.368391 -390.726032) (xy 114.380595 -390.692501) (xy 114.400204 -390.662688)
			(xy 114.426159 -390.638201) (xy 114.457061 -390.620359) (xy 114.491245 -390.610125) (xy 114.526868 -390.608051)
			(xy 114.562009 -390.614247) (xy 114.594774 -390.62838) (xy 114.623396 -390.649689) (xy 114.646333 -390.677024)
			(xy 114.662347 -390.708911) (xy 114.670576 -390.743632) (xy 114.671094 -390.761474) (xy 115.564145 -390.761474)
			(xy 115.568287 -390.726032) (xy 115.580491 -390.692501) (xy 115.6001 -390.662688) (xy 115.626055 -390.638201)
			(xy 115.656957 -390.620359) (xy 115.691141 -390.610125) (xy 115.726764 -390.608051) (xy 115.761905 -390.614247)
			(xy 115.79467 -390.62838) (xy 115.823292 -390.649689) (xy 115.846229 -390.677024) (xy 115.862243 -390.708911)
			(xy 115.870472 -390.743632) (xy 115.87099 -390.761474) (xy 116.764295 -390.761474) (xy 116.768437 -390.726032)
			(xy 116.780641 -390.692501) (xy 116.80025 -390.662688) (xy 116.826205 -390.638201) (xy 116.857107 -390.620359)
			(xy 116.891291 -390.610125) (xy 116.926914 -390.608051) (xy 116.962055 -390.614247) (xy 116.99482 -390.62838)
			(xy 117.023442 -390.649689) (xy 117.046379 -390.677024) (xy 117.062393 -390.708911) (xy 117.070622 -390.743632)
			(xy 117.07114 -390.761474) (xy 117.964191 -390.761474) (xy 117.968333 -390.726032) (xy 117.980537 -390.692501)
			(xy 118.000146 -390.662688) (xy 118.026101 -390.638201) (xy 118.057003 -390.620359) (xy 118.091187 -390.610125)
			(xy 118.12681 -390.608051) (xy 118.161951 -390.614247) (xy 118.194716 -390.62838) (xy 118.223338 -390.649689)
			(xy 118.246275 -390.677024) (xy 118.262289 -390.708911) (xy 118.270518 -390.743632) (xy 118.271036 -390.761474)
			(xy 119.164341 -390.761474) (xy 119.168483 -390.726032) (xy 119.180687 -390.692501) (xy 119.200296 -390.662688)
			(xy 119.226251 -390.638201) (xy 119.257153 -390.620359) (xy 119.291337 -390.610125) (xy 119.32696 -390.608051)
			(xy 119.362101 -390.614247) (xy 119.394866 -390.62838) (xy 119.423488 -390.649689) (xy 119.446425 -390.677024)
			(xy 119.462439 -390.708911) (xy 119.470668 -390.743632) (xy 119.471186 -390.761474) (xy 120.364237 -390.761474)
			(xy 120.368379 -390.726032) (xy 120.380583 -390.692501) (xy 120.400192 -390.662688) (xy 120.426147 -390.638201)
			(xy 120.457049 -390.620359) (xy 120.491233 -390.610125) (xy 120.526856 -390.608051) (xy 120.561997 -390.614247)
			(xy 120.594762 -390.62838) (xy 120.623384 -390.649689) (xy 120.646321 -390.677024) (xy 120.662335 -390.708911)
			(xy 120.670564 -390.743632) (xy 120.671082 -390.761474) (xy 121.564387 -390.761474) (xy 121.568529 -390.726032)
			(xy 121.580733 -390.692501) (xy 121.600342 -390.662688) (xy 121.626297 -390.638201) (xy 121.657199 -390.620359)
			(xy 121.691383 -390.610125) (xy 121.727006 -390.608051) (xy 121.762147 -390.614247) (xy 121.794912 -390.62838)
			(xy 121.823534 -390.649689) (xy 121.846471 -390.677024) (xy 121.862485 -390.708911) (xy 121.870714 -390.743632)
			(xy 121.871232 -390.761474) (xy 122.764283 -390.761474) (xy 122.768425 -390.726032) (xy 122.780629 -390.692501)
			(xy 122.800238 -390.662688) (xy 122.826193 -390.638201) (xy 122.857095 -390.620359) (xy 122.891279 -390.610125)
			(xy 122.926902 -390.608051) (xy 122.962043 -390.614247) (xy 122.994808 -390.62838) (xy 123.02343 -390.649689)
			(xy 123.046367 -390.677024) (xy 123.062381 -390.708911) (xy 123.07061 -390.743632) (xy 123.071128 -390.761474)
			(xy 123.964179 -390.761474) (xy 123.968321 -390.726032) (xy 123.980525 -390.692501) (xy 124.000134 -390.662688)
			(xy 124.026089 -390.638201) (xy 124.056991 -390.620359) (xy 124.091175 -390.610125) (xy 124.126798 -390.608051)
			(xy 124.161939 -390.614247) (xy 124.194704 -390.62838) (xy 124.223326 -390.649689) (xy 124.246263 -390.677024)
			(xy 124.262277 -390.708911) (xy 124.270506 -390.743632) (xy 124.271024 -390.761474) (xy 125.164329 -390.761474)
			(xy 125.168471 -390.726032) (xy 125.180675 -390.692501) (xy 125.200284 -390.662688) (xy 125.226239 -390.638201)
			(xy 125.257141 -390.620359) (xy 125.291325 -390.610125) (xy 125.326948 -390.608051) (xy 125.362089 -390.614247)
			(xy 125.394854 -390.62838) (xy 125.423476 -390.649689) (xy 125.446413 -390.677024) (xy 125.462427 -390.708911)
			(xy 125.470656 -390.743632) (xy 125.471174 -390.761474) (xy 126.364225 -390.761474) (xy 126.368367 -390.726032)
			(xy 126.380571 -390.692501) (xy 126.40018 -390.662688) (xy 126.426135 -390.638201) (xy 126.457037 -390.620359)
			(xy 126.491221 -390.610125) (xy 126.526844 -390.608051) (xy 126.561985 -390.614247) (xy 126.59475 -390.62838)
			(xy 126.623372 -390.649689) (xy 126.646309 -390.677024) (xy 126.662323 -390.708911) (xy 126.670552 -390.743632)
			(xy 126.67107 -390.761474) (xy 127.564375 -390.761474) (xy 127.568517 -390.726032) (xy 127.580721 -390.692501)
			(xy 127.60033 -390.662688) (xy 127.626285 -390.638201) (xy 127.657187 -390.620359) (xy 127.691371 -390.610125)
			(xy 127.726994 -390.608051) (xy 127.762135 -390.614247) (xy 127.7949 -390.62838) (xy 127.823522 -390.649689)
			(xy 127.846459 -390.677024) (xy 127.862473 -390.708911) (xy 127.870702 -390.743632) (xy 127.87122 -390.761474)
			(xy 128.764271 -390.761474) (xy 128.768413 -390.726032) (xy 128.780617 -390.692501) (xy 128.800226 -390.662688)
			(xy 128.826181 -390.638201) (xy 128.857083 -390.620359) (xy 128.891267 -390.610125) (xy 128.92689 -390.608051)
			(xy 128.962031 -390.614247) (xy 128.994796 -390.62838) (xy 129.023418 -390.649689) (xy 129.046355 -390.677024)
			(xy 129.062369 -390.708911) (xy 129.070598 -390.743632) (xy 129.071116 -390.761474) (xy 129.964167 -390.761474)
			(xy 129.968309 -390.726032) (xy 129.980513 -390.692501) (xy 130.000122 -390.662688) (xy 130.026077 -390.638201)
			(xy 130.056979 -390.620359) (xy 130.091163 -390.610125) (xy 130.126786 -390.608051) (xy 130.161927 -390.614247)
			(xy 130.194692 -390.62838) (xy 130.223314 -390.649689) (xy 130.246251 -390.677024) (xy 130.262265 -390.708911)
			(xy 130.270494 -390.743632) (xy 130.271012 -390.761474) (xy 131.164317 -390.761474) (xy 131.168459 -390.726032)
			(xy 131.180663 -390.692501) (xy 131.200272 -390.662688) (xy 131.226227 -390.638201) (xy 131.257129 -390.620359)
			(xy 131.291313 -390.610125) (xy 131.326936 -390.608051) (xy 131.362077 -390.614247) (xy 131.394842 -390.62838)
			(xy 131.423464 -390.649689) (xy 131.446401 -390.677024) (xy 131.462415 -390.708911) (xy 131.470644 -390.743632)
			(xy 131.471162 -390.761474) (xy 132.364213 -390.761474) (xy 132.368355 -390.726032) (xy 132.380559 -390.692501)
			(xy 132.400168 -390.662688) (xy 132.426123 -390.638201) (xy 132.457025 -390.620359) (xy 132.491209 -390.610125)
			(xy 132.526832 -390.608051) (xy 132.561973 -390.614247) (xy 132.594738 -390.62838) (xy 132.62336 -390.649689)
			(xy 132.646297 -390.677024) (xy 132.662311 -390.708911) (xy 132.67054 -390.743632) (xy 132.671058 -390.761474)
			(xy 146.891997 -390.761474) (xy 146.896139 -390.726032) (xy 146.908343 -390.692501) (xy 146.927952 -390.662688)
			(xy 146.953907 -390.638201) (xy 146.984809 -390.620359) (xy 147.018993 -390.610125) (xy 147.054616 -390.608051)
			(xy 147.089757 -390.614247) (xy 147.122522 -390.62838) (xy 147.151144 -390.649689) (xy 147.174081 -390.677024)
			(xy 147.190095 -390.708911) (xy 147.198324 -390.743632) (xy 147.198842 -390.761474) (xy 148.091893 -390.761474)
			(xy 148.096035 -390.726032) (xy 148.108239 -390.692501) (xy 148.127848 -390.662688) (xy 148.153803 -390.638201)
			(xy 148.184705 -390.620359) (xy 148.218889 -390.610125) (xy 148.254512 -390.608051) (xy 148.289653 -390.614247)
			(xy 148.322418 -390.62838) (xy 148.35104 -390.649689) (xy 148.373977 -390.677024) (xy 148.389991 -390.708911)
			(xy 148.39822 -390.743632) (xy 148.398738 -390.761474) (xy 149.292043 -390.761474) (xy 149.296185 -390.726032)
			(xy 149.308389 -390.692501) (xy 149.327998 -390.662688) (xy 149.353953 -390.638201) (xy 149.384855 -390.620359)
			(xy 149.419039 -390.610125) (xy 149.454662 -390.608051) (xy 149.489803 -390.614247) (xy 149.522568 -390.62838)
			(xy 149.55119 -390.649689) (xy 149.574127 -390.677024) (xy 149.590141 -390.708911) (xy 149.59837 -390.743632)
			(xy 149.598888 -390.761474) (xy 150.491939 -390.761474) (xy 150.496081 -390.726032) (xy 150.508285 -390.692501)
			(xy 150.527894 -390.662688) (xy 150.553849 -390.638201) (xy 150.584751 -390.620359) (xy 150.618935 -390.610125)
			(xy 150.654558 -390.608051) (xy 150.689699 -390.614247) (xy 150.722464 -390.62838) (xy 150.751086 -390.649689)
			(xy 150.774023 -390.677024) (xy 150.790037 -390.708911) (xy 150.798266 -390.743632) (xy 150.798784 -390.761474)
			(xy 151.692089 -390.761474) (xy 151.696231 -390.726032) (xy 151.708435 -390.692501) (xy 151.728044 -390.662688)
			(xy 151.753999 -390.638201) (xy 151.784901 -390.620359) (xy 151.819085 -390.610125) (xy 151.854708 -390.608051)
			(xy 151.889849 -390.614247) (xy 151.922614 -390.62838) (xy 151.951236 -390.649689) (xy 151.974173 -390.677024)
			(xy 151.990187 -390.708911) (xy 151.998416 -390.743632) (xy 151.998934 -390.761474) (xy 152.891985 -390.761474)
			(xy 152.896127 -390.726032) (xy 152.908331 -390.692501) (xy 152.92794 -390.662688) (xy 152.953895 -390.638201)
			(xy 152.984797 -390.620359) (xy 153.018981 -390.610125) (xy 153.054604 -390.608051) (xy 153.089745 -390.614247)
			(xy 153.12251 -390.62838) (xy 153.151132 -390.649689) (xy 153.174069 -390.677024) (xy 153.190083 -390.708911)
			(xy 153.198312 -390.743632) (xy 153.19883 -390.761474) (xy 154.092135 -390.761474) (xy 154.096277 -390.726032)
			(xy 154.108481 -390.692501) (xy 154.12809 -390.662688) (xy 154.154045 -390.638201) (xy 154.184947 -390.620359)
			(xy 154.219131 -390.610125) (xy 154.254754 -390.608051) (xy 154.289895 -390.614247) (xy 154.32266 -390.62838)
			(xy 154.351282 -390.649689) (xy 154.374219 -390.677024) (xy 154.390233 -390.708911) (xy 154.398462 -390.743632)
			(xy 154.39898 -390.761474) (xy 155.292031 -390.761474) (xy 155.296173 -390.726032) (xy 155.308377 -390.692501)
			(xy 155.327986 -390.662688) (xy 155.353941 -390.638201) (xy 155.384843 -390.620359) (xy 155.419027 -390.610125)
			(xy 155.45465 -390.608051) (xy 155.489791 -390.614247) (xy 155.522556 -390.62838) (xy 155.551178 -390.649689)
			(xy 155.574115 -390.677024) (xy 155.590129 -390.708911) (xy 155.598358 -390.743632) (xy 155.598876 -390.761474)
			(xy 156.491927 -390.761474) (xy 156.496069 -390.726032) (xy 156.508273 -390.692501) (xy 156.527882 -390.662688)
			(xy 156.553837 -390.638201) (xy 156.584739 -390.620359) (xy 156.618923 -390.610125) (xy 156.654546 -390.608051)
			(xy 156.689687 -390.614247) (xy 156.722452 -390.62838) (xy 156.751074 -390.649689) (xy 156.774011 -390.677024)
			(xy 156.790025 -390.708911) (xy 156.798254 -390.743632) (xy 156.798772 -390.761474) (xy 157.692077 -390.761474)
			(xy 157.696219 -390.726032) (xy 157.708423 -390.692501) (xy 157.728032 -390.662688) (xy 157.753987 -390.638201)
			(xy 157.784889 -390.620359) (xy 157.819073 -390.610125) (xy 157.854696 -390.608051) (xy 157.889837 -390.614247)
			(xy 157.922602 -390.62838) (xy 157.951224 -390.649689) (xy 157.974161 -390.677024) (xy 157.990175 -390.708911)
			(xy 157.998404 -390.743632) (xy 157.998922 -390.761474) (xy 158.891973 -390.761474) (xy 158.896115 -390.726032)
			(xy 158.908319 -390.692501) (xy 158.927928 -390.662688) (xy 158.953883 -390.638201) (xy 158.984785 -390.620359)
			(xy 159.018969 -390.610125) (xy 159.054592 -390.608051) (xy 159.089733 -390.614247) (xy 159.122498 -390.62838)
			(xy 159.15112 -390.649689) (xy 159.174057 -390.677024) (xy 159.190071 -390.708911) (xy 159.1983 -390.743632)
			(xy 159.198818 -390.761474) (xy 160.092123 -390.761474) (xy 160.096265 -390.726032) (xy 160.108469 -390.692501)
			(xy 160.128078 -390.662688) (xy 160.154033 -390.638201) (xy 160.184935 -390.620359) (xy 160.219119 -390.610125)
			(xy 160.254742 -390.608051) (xy 160.289883 -390.614247) (xy 160.322648 -390.62838) (xy 160.35127 -390.649689)
			(xy 160.374207 -390.677024) (xy 160.390221 -390.708911) (xy 160.39845 -390.743632) (xy 160.398968 -390.761474)
			(xy 161.292019 -390.761474) (xy 161.296161 -390.726032) (xy 161.308365 -390.692501) (xy 161.327974 -390.662688)
			(xy 161.353929 -390.638201) (xy 161.384831 -390.620359) (xy 161.419015 -390.610125) (xy 161.454638 -390.608051)
			(xy 161.489779 -390.614247) (xy 161.522544 -390.62838) (xy 161.551166 -390.649689) (xy 161.574103 -390.677024)
			(xy 161.590117 -390.708911) (xy 161.598346 -390.743632) (xy 161.598864 -390.761474) (xy 162.491915 -390.761474)
			(xy 162.496057 -390.726032) (xy 162.508261 -390.692501) (xy 162.52787 -390.662688) (xy 162.553825 -390.638201)
			(xy 162.584727 -390.620359) (xy 162.618911 -390.610125) (xy 162.654534 -390.608051) (xy 162.689675 -390.614247)
			(xy 162.72244 -390.62838) (xy 162.751062 -390.649689) (xy 162.773999 -390.677024) (xy 162.790013 -390.708911)
			(xy 162.798242 -390.743632) (xy 162.79876 -390.761474) (xy 163.692065 -390.761474) (xy 163.696207 -390.726032)
			(xy 163.708411 -390.692501) (xy 163.72802 -390.662688) (xy 163.753975 -390.638201) (xy 163.784877 -390.620359)
			(xy 163.819061 -390.610125) (xy 163.854684 -390.608051) (xy 163.889825 -390.614247) (xy 163.92259 -390.62838)
			(xy 163.951212 -390.649689) (xy 163.974149 -390.677024) (xy 163.990163 -390.708911) (xy 163.998392 -390.743632)
			(xy 163.99891 -390.761474) (xy 164.891961 -390.761474) (xy 164.896103 -390.726032) (xy 164.908307 -390.692501)
			(xy 164.927916 -390.662688) (xy 164.953871 -390.638201) (xy 164.984773 -390.620359) (xy 165.018957 -390.610125)
			(xy 165.05458 -390.608051) (xy 165.089721 -390.614247) (xy 165.122486 -390.62838) (xy 165.151108 -390.649689)
			(xy 165.174045 -390.677024) (xy 165.190059 -390.708911) (xy 165.198288 -390.743632) (xy 165.198806 -390.761474)
			(xy 165.198288 -390.779316) (xy 165.190059 -390.814037) (xy 165.174045 -390.845924) (xy 165.151108 -390.873259)
			(xy 165.122486 -390.894568) (xy 165.089721 -390.908701) (xy 165.05458 -390.914897) (xy 165.018957 -390.912823)
			(xy 164.984773 -390.902589) (xy 164.953871 -390.884747) (xy 164.927916 -390.86026) (xy 164.908307 -390.830447)
			(xy 164.896103 -390.796916) (xy 164.891961 -390.761474) (xy 163.99891 -390.761474) (xy 163.998392 -390.779316)
			(xy 163.990163 -390.814037) (xy 163.974149 -390.845924) (xy 163.951212 -390.873259) (xy 163.92259 -390.894568)
			(xy 163.889825 -390.908701) (xy 163.854684 -390.914897) (xy 163.819061 -390.912823) (xy 163.784877 -390.902589)
			(xy 163.753975 -390.884747) (xy 163.72802 -390.86026) (xy 163.708411 -390.830447) (xy 163.696207 -390.796916)
			(xy 163.692065 -390.761474) (xy 162.79876 -390.761474) (xy 162.798242 -390.779316) (xy 162.790013 -390.814037)
			(xy 162.773999 -390.845924) (xy 162.751062 -390.873259) (xy 162.72244 -390.894568) (xy 162.689675 -390.908701)
			(xy 162.654534 -390.914897) (xy 162.618911 -390.912823) (xy 162.584727 -390.902589) (xy 162.553825 -390.884747)
			(xy 162.52787 -390.86026) (xy 162.508261 -390.830447) (xy 162.496057 -390.796916) (xy 162.491915 -390.761474)
			(xy 161.598864 -390.761474) (xy 161.598346 -390.779316) (xy 161.590117 -390.814037) (xy 161.574103 -390.845924)
			(xy 161.551166 -390.873259) (xy 161.522544 -390.894568) (xy 161.489779 -390.908701) (xy 161.454638 -390.914897)
			(xy 161.419015 -390.912823) (xy 161.384831 -390.902589) (xy 161.353929 -390.884747) (xy 161.327974 -390.86026)
			(xy 161.308365 -390.830447) (xy 161.296161 -390.796916) (xy 161.292019 -390.761474) (xy 160.398968 -390.761474)
			(xy 160.39845 -390.779316) (xy 160.390221 -390.814037) (xy 160.374207 -390.845924) (xy 160.35127 -390.873259)
			(xy 160.322648 -390.894568) (xy 160.289883 -390.908701) (xy 160.254742 -390.914897) (xy 160.219119 -390.912823)
			(xy 160.184935 -390.902589) (xy 160.154033 -390.884747) (xy 160.128078 -390.86026) (xy 160.108469 -390.830447)
			(xy 160.096265 -390.796916) (xy 160.092123 -390.761474) (xy 159.198818 -390.761474) (xy 159.1983 -390.779316)
			(xy 159.190071 -390.814037) (xy 159.174057 -390.845924) (xy 159.15112 -390.873259) (xy 159.122498 -390.894568)
			(xy 159.089733 -390.908701) (xy 159.054592 -390.914897) (xy 159.018969 -390.912823) (xy 158.984785 -390.902589)
			(xy 158.953883 -390.884747) (xy 158.927928 -390.86026) (xy 158.908319 -390.830447) (xy 158.896115 -390.796916)
			(xy 158.891973 -390.761474) (xy 157.998922 -390.761474) (xy 157.998404 -390.779316) (xy 157.990175 -390.814037)
			(xy 157.974161 -390.845924) (xy 157.951224 -390.873259) (xy 157.922602 -390.894568) (xy 157.889837 -390.908701)
			(xy 157.854696 -390.914897) (xy 157.819073 -390.912823) (xy 157.784889 -390.902589) (xy 157.753987 -390.884747)
			(xy 157.728032 -390.86026) (xy 157.708423 -390.830447) (xy 157.696219 -390.796916) (xy 157.692077 -390.761474)
			(xy 156.798772 -390.761474) (xy 156.798254 -390.779316) (xy 156.790025 -390.814037) (xy 156.774011 -390.845924)
			(xy 156.751074 -390.873259) (xy 156.722452 -390.894568) (xy 156.689687 -390.908701) (xy 156.654546 -390.914897)
			(xy 156.618923 -390.912823) (xy 156.584739 -390.902589) (xy 156.553837 -390.884747) (xy 156.527882 -390.86026)
			(xy 156.508273 -390.830447) (xy 156.496069 -390.796916) (xy 156.491927 -390.761474) (xy 155.598876 -390.761474)
			(xy 155.598358 -390.779316) (xy 155.590129 -390.814037) (xy 155.574115 -390.845924) (xy 155.551178 -390.873259)
			(xy 155.522556 -390.894568) (xy 155.489791 -390.908701) (xy 155.45465 -390.914897) (xy 155.419027 -390.912823)
			(xy 155.384843 -390.902589) (xy 155.353941 -390.884747) (xy 155.327986 -390.86026) (xy 155.308377 -390.830447)
			(xy 155.296173 -390.796916) (xy 155.292031 -390.761474) (xy 154.39898 -390.761474) (xy 154.398462 -390.779316)
			(xy 154.390233 -390.814037) (xy 154.374219 -390.845924) (xy 154.351282 -390.873259) (xy 154.32266 -390.894568)
			(xy 154.289895 -390.908701) (xy 154.254754 -390.914897) (xy 154.219131 -390.912823) (xy 154.184947 -390.902589)
			(xy 154.154045 -390.884747) (xy 154.12809 -390.86026) (xy 154.108481 -390.830447) (xy 154.096277 -390.796916)
			(xy 154.092135 -390.761474) (xy 153.19883 -390.761474) (xy 153.198312 -390.779316) (xy 153.190083 -390.814037)
			(xy 153.174069 -390.845924) (xy 153.151132 -390.873259) (xy 153.12251 -390.894568) (xy 153.089745 -390.908701)
			(xy 153.054604 -390.914897) (xy 153.018981 -390.912823) (xy 152.984797 -390.902589) (xy 152.953895 -390.884747)
			(xy 152.92794 -390.86026) (xy 152.908331 -390.830447) (xy 152.896127 -390.796916) (xy 152.891985 -390.761474)
			(xy 151.998934 -390.761474) (xy 151.998416 -390.779316) (xy 151.990187 -390.814037) (xy 151.974173 -390.845924)
			(xy 151.951236 -390.873259) (xy 151.922614 -390.894568) (xy 151.889849 -390.908701) (xy 151.854708 -390.914897)
			(xy 151.819085 -390.912823) (xy 151.784901 -390.902589) (xy 151.753999 -390.884747) (xy 151.728044 -390.86026)
			(xy 151.708435 -390.830447) (xy 151.696231 -390.796916) (xy 151.692089 -390.761474) (xy 150.798784 -390.761474)
			(xy 150.798266 -390.779316) (xy 150.790037 -390.814037) (xy 150.774023 -390.845924) (xy 150.751086 -390.873259)
			(xy 150.722464 -390.894568) (xy 150.689699 -390.908701) (xy 150.654558 -390.914897) (xy 150.618935 -390.912823)
			(xy 150.584751 -390.902589) (xy 150.553849 -390.884747) (xy 150.527894 -390.86026) (xy 150.508285 -390.830447)
			(xy 150.496081 -390.796916) (xy 150.491939 -390.761474) (xy 149.598888 -390.761474) (xy 149.59837 -390.779316)
			(xy 149.590141 -390.814037) (xy 149.574127 -390.845924) (xy 149.55119 -390.873259) (xy 149.522568 -390.894568)
			(xy 149.489803 -390.908701) (xy 149.454662 -390.914897) (xy 149.419039 -390.912823) (xy 149.384855 -390.902589)
			(xy 149.353953 -390.884747) (xy 149.327998 -390.86026) (xy 149.308389 -390.830447) (xy 149.296185 -390.796916)
			(xy 149.292043 -390.761474) (xy 148.398738 -390.761474) (xy 148.39822 -390.779316) (xy 148.389991 -390.814037)
			(xy 148.373977 -390.845924) (xy 148.35104 -390.873259) (xy 148.322418 -390.894568) (xy 148.289653 -390.908701)
			(xy 148.254512 -390.914897) (xy 148.218889 -390.912823) (xy 148.184705 -390.902589) (xy 148.153803 -390.884747)
			(xy 148.127848 -390.86026) (xy 148.108239 -390.830447) (xy 148.096035 -390.796916) (xy 148.091893 -390.761474)
			(xy 147.198842 -390.761474) (xy 147.198324 -390.779316) (xy 147.190095 -390.814037) (xy 147.174081 -390.845924)
			(xy 147.151144 -390.873259) (xy 147.122522 -390.894568) (xy 147.089757 -390.908701) (xy 147.054616 -390.914897)
			(xy 147.018993 -390.912823) (xy 146.984809 -390.902589) (xy 146.953907 -390.884747) (xy 146.927952 -390.86026)
			(xy 146.908343 -390.830447) (xy 146.896139 -390.796916) (xy 146.891997 -390.761474) (xy 132.671058 -390.761474)
			(xy 132.67054 -390.779316) (xy 132.662311 -390.814037) (xy 132.646297 -390.845924) (xy 132.62336 -390.873259)
			(xy 132.594738 -390.894568) (xy 132.561973 -390.908701) (xy 132.526832 -390.914897) (xy 132.491209 -390.912823)
			(xy 132.457025 -390.902589) (xy 132.426123 -390.884747) (xy 132.400168 -390.86026) (xy 132.380559 -390.830447)
			(xy 132.368355 -390.796916) (xy 132.364213 -390.761474) (xy 131.471162 -390.761474) (xy 131.470644 -390.779316)
			(xy 131.462415 -390.814037) (xy 131.446401 -390.845924) (xy 131.423464 -390.873259) (xy 131.394842 -390.894568)
			(xy 131.362077 -390.908701) (xy 131.326936 -390.914897) (xy 131.291313 -390.912823) (xy 131.257129 -390.902589)
			(xy 131.226227 -390.884747) (xy 131.200272 -390.86026) (xy 131.180663 -390.830447) (xy 131.168459 -390.796916)
			(xy 131.164317 -390.761474) (xy 130.271012 -390.761474) (xy 130.270494 -390.779316) (xy 130.262265 -390.814037)
			(xy 130.246251 -390.845924) (xy 130.223314 -390.873259) (xy 130.194692 -390.894568) (xy 130.161927 -390.908701)
			(xy 130.126786 -390.914897) (xy 130.091163 -390.912823) (xy 130.056979 -390.902589) (xy 130.026077 -390.884747)
			(xy 130.000122 -390.86026) (xy 129.980513 -390.830447) (xy 129.968309 -390.796916) (xy 129.964167 -390.761474)
			(xy 129.071116 -390.761474) (xy 129.070598 -390.779316) (xy 129.062369 -390.814037) (xy 129.046355 -390.845924)
			(xy 129.023418 -390.873259) (xy 128.994796 -390.894568) (xy 128.962031 -390.908701) (xy 128.92689 -390.914897)
			(xy 128.891267 -390.912823) (xy 128.857083 -390.902589) (xy 128.826181 -390.884747) (xy 128.800226 -390.86026)
			(xy 128.780617 -390.830447) (xy 128.768413 -390.796916) (xy 128.764271 -390.761474) (xy 127.87122 -390.761474)
			(xy 127.870702 -390.779316) (xy 127.862473 -390.814037) (xy 127.846459 -390.845924) (xy 127.823522 -390.873259)
			(xy 127.7949 -390.894568) (xy 127.762135 -390.908701) (xy 127.726994 -390.914897) (xy 127.691371 -390.912823)
			(xy 127.657187 -390.902589) (xy 127.626285 -390.884747) (xy 127.60033 -390.86026) (xy 127.580721 -390.830447)
			(xy 127.568517 -390.796916) (xy 127.564375 -390.761474) (xy 126.67107 -390.761474) (xy 126.670552 -390.779316)
			(xy 126.662323 -390.814037) (xy 126.646309 -390.845924) (xy 126.623372 -390.873259) (xy 126.59475 -390.894568)
			(xy 126.561985 -390.908701) (xy 126.526844 -390.914897) (xy 126.491221 -390.912823) (xy 126.457037 -390.902589)
			(xy 126.426135 -390.884747) (xy 126.40018 -390.86026) (xy 126.380571 -390.830447) (xy 126.368367 -390.796916)
			(xy 126.364225 -390.761474) (xy 125.471174 -390.761474) (xy 125.470656 -390.779316) (xy 125.462427 -390.814037)
			(xy 125.446413 -390.845924) (xy 125.423476 -390.873259) (xy 125.394854 -390.894568) (xy 125.362089 -390.908701)
			(xy 125.326948 -390.914897) (xy 125.291325 -390.912823) (xy 125.257141 -390.902589) (xy 125.226239 -390.884747)
			(xy 125.200284 -390.86026) (xy 125.180675 -390.830447) (xy 125.168471 -390.796916) (xy 125.164329 -390.761474)
			(xy 124.271024 -390.761474) (xy 124.270506 -390.779316) (xy 124.262277 -390.814037) (xy 124.246263 -390.845924)
			(xy 124.223326 -390.873259) (xy 124.194704 -390.894568) (xy 124.161939 -390.908701) (xy 124.126798 -390.914897)
			(xy 124.091175 -390.912823) (xy 124.056991 -390.902589) (xy 124.026089 -390.884747) (xy 124.000134 -390.86026)
			(xy 123.980525 -390.830447) (xy 123.968321 -390.796916) (xy 123.964179 -390.761474) (xy 123.071128 -390.761474)
			(xy 123.07061 -390.779316) (xy 123.062381 -390.814037) (xy 123.046367 -390.845924) (xy 123.02343 -390.873259)
			(xy 122.994808 -390.894568) (xy 122.962043 -390.908701) (xy 122.926902 -390.914897) (xy 122.891279 -390.912823)
			(xy 122.857095 -390.902589) (xy 122.826193 -390.884747) (xy 122.800238 -390.86026) (xy 122.780629 -390.830447)
			(xy 122.768425 -390.796916) (xy 122.764283 -390.761474) (xy 121.871232 -390.761474) (xy 121.870714 -390.779316)
			(xy 121.862485 -390.814037) (xy 121.846471 -390.845924) (xy 121.823534 -390.873259) (xy 121.794912 -390.894568)
			(xy 121.762147 -390.908701) (xy 121.727006 -390.914897) (xy 121.691383 -390.912823) (xy 121.657199 -390.902589)
			(xy 121.626297 -390.884747) (xy 121.600342 -390.86026) (xy 121.580733 -390.830447) (xy 121.568529 -390.796916)
			(xy 121.564387 -390.761474) (xy 120.671082 -390.761474) (xy 120.670564 -390.779316) (xy 120.662335 -390.814037)
			(xy 120.646321 -390.845924) (xy 120.623384 -390.873259) (xy 120.594762 -390.894568) (xy 120.561997 -390.908701)
			(xy 120.526856 -390.914897) (xy 120.491233 -390.912823) (xy 120.457049 -390.902589) (xy 120.426147 -390.884747)
			(xy 120.400192 -390.86026) (xy 120.380583 -390.830447) (xy 120.368379 -390.796916) (xy 120.364237 -390.761474)
			(xy 119.471186 -390.761474) (xy 119.470668 -390.779316) (xy 119.462439 -390.814037) (xy 119.446425 -390.845924)
			(xy 119.423488 -390.873259) (xy 119.394866 -390.894568) (xy 119.362101 -390.908701) (xy 119.32696 -390.914897)
			(xy 119.291337 -390.912823) (xy 119.257153 -390.902589) (xy 119.226251 -390.884747) (xy 119.200296 -390.86026)
			(xy 119.180687 -390.830447) (xy 119.168483 -390.796916) (xy 119.164341 -390.761474) (xy 118.271036 -390.761474)
			(xy 118.270518 -390.779316) (xy 118.262289 -390.814037) (xy 118.246275 -390.845924) (xy 118.223338 -390.873259)
			(xy 118.194716 -390.894568) (xy 118.161951 -390.908701) (xy 118.12681 -390.914897) (xy 118.091187 -390.912823)
			(xy 118.057003 -390.902589) (xy 118.026101 -390.884747) (xy 118.000146 -390.86026) (xy 117.980537 -390.830447)
			(xy 117.968333 -390.796916) (xy 117.964191 -390.761474) (xy 117.07114 -390.761474) (xy 117.070622 -390.779316)
			(xy 117.062393 -390.814037) (xy 117.046379 -390.845924) (xy 117.023442 -390.873259) (xy 116.99482 -390.894568)
			(xy 116.962055 -390.908701) (xy 116.926914 -390.914897) (xy 116.891291 -390.912823) (xy 116.857107 -390.902589)
			(xy 116.826205 -390.884747) (xy 116.80025 -390.86026) (xy 116.780641 -390.830447) (xy 116.768437 -390.796916)
			(xy 116.764295 -390.761474) (xy 115.87099 -390.761474) (xy 115.870472 -390.779316) (xy 115.862243 -390.814037)
			(xy 115.846229 -390.845924) (xy 115.823292 -390.873259) (xy 115.79467 -390.894568) (xy 115.761905 -390.908701)
			(xy 115.726764 -390.914897) (xy 115.691141 -390.912823) (xy 115.656957 -390.902589) (xy 115.626055 -390.884747)
			(xy 115.6001 -390.86026) (xy 115.580491 -390.830447) (xy 115.568287 -390.796916) (xy 115.564145 -390.761474)
			(xy 114.671094 -390.761474) (xy 114.670576 -390.779316) (xy 114.662347 -390.814037) (xy 114.646333 -390.845924)
			(xy 114.623396 -390.873259) (xy 114.594774 -390.894568) (xy 114.562009 -390.908701) (xy 114.526868 -390.914897)
			(xy 114.491245 -390.912823) (xy 114.457061 -390.902589) (xy 114.426159 -390.884747) (xy 114.400204 -390.86026)
			(xy 114.380595 -390.830447) (xy 114.368391 -390.796916) (xy 114.364249 -390.761474) (xy 98.098864 -390.761474)
			(xy 98.098346 -390.779316) (xy 98.090117 -390.814037) (xy 98.074103 -390.845924) (xy 98.051166 -390.873259)
			(xy 98.022544 -390.894568) (xy 97.989779 -390.908701) (xy 97.954638 -390.914897) (xy 97.919015 -390.912823)
			(xy 97.884831 -390.902589) (xy 97.853929 -390.884747) (xy 97.827974 -390.86026) (xy 97.808365 -390.830447)
			(xy 97.796161 -390.796916) (xy 97.792019 -390.761474) (xy 96.898968 -390.761474) (xy 96.89845 -390.779316)
			(xy 96.890221 -390.814037) (xy 96.874207 -390.845924) (xy 96.85127 -390.873259) (xy 96.822648 -390.894568)
			(xy 96.789883 -390.908701) (xy 96.754742 -390.914897) (xy 96.719119 -390.912823) (xy 96.684935 -390.902589)
			(xy 96.654033 -390.884747) (xy 96.628078 -390.86026) (xy 96.608469 -390.830447) (xy 96.596265 -390.796916)
			(xy 96.592123 -390.761474) (xy 95.698818 -390.761474) (xy 95.6983 -390.779316) (xy 95.690071 -390.814037)
			(xy 95.674057 -390.845924) (xy 95.65112 -390.873259) (xy 95.622498 -390.894568) (xy 95.589733 -390.908701)
			(xy 95.554592 -390.914897) (xy 95.518969 -390.912823) (xy 95.484785 -390.902589) (xy 95.453883 -390.884747)
			(xy 95.427928 -390.86026) (xy 95.408319 -390.830447) (xy 95.396115 -390.796916) (xy 95.391973 -390.761474)
			(xy 94.498922 -390.761474) (xy 94.498404 -390.779316) (xy 94.490175 -390.814037) (xy 94.474161 -390.845924)
			(xy 94.451224 -390.873259) (xy 94.422602 -390.894568) (xy 94.389837 -390.908701) (xy 94.354696 -390.914897)
			(xy 94.319073 -390.912823) (xy 94.284889 -390.902589) (xy 94.253987 -390.884747) (xy 94.228032 -390.86026)
			(xy 94.208423 -390.830447) (xy 94.196219 -390.796916) (xy 94.192077 -390.761474) (xy 93.299026 -390.761474)
			(xy 93.298508 -390.779316) (xy 93.290279 -390.814037) (xy 93.274265 -390.845924) (xy 93.251328 -390.873259)
			(xy 93.222706 -390.894568) (xy 93.189941 -390.908701) (xy 93.1548 -390.914897) (xy 93.119177 -390.912823)
			(xy 93.084993 -390.902589) (xy 93.054091 -390.884747) (xy 93.028136 -390.86026) (xy 93.008527 -390.830447)
			(xy 92.996323 -390.796916) (xy 92.992181 -390.761474) (xy 92.098876 -390.761474) (xy 92.098358 -390.779316)
			(xy 92.090129 -390.814037) (xy 92.074115 -390.845924) (xy 92.051178 -390.873259) (xy 92.022556 -390.894568)
			(xy 91.989791 -390.908701) (xy 91.95465 -390.914897) (xy 91.919027 -390.912823) (xy 91.884843 -390.902589)
			(xy 91.853941 -390.884747) (xy 91.827986 -390.86026) (xy 91.808377 -390.830447) (xy 91.796173 -390.796916)
			(xy 91.792031 -390.761474) (xy 90.89898 -390.761474) (xy 90.898462 -390.779316) (xy 90.890233 -390.814037)
			(xy 90.874219 -390.845924) (xy 90.851282 -390.873259) (xy 90.82266 -390.894568) (xy 90.789895 -390.908701)
			(xy 90.754754 -390.914897) (xy 90.719131 -390.912823) (xy 90.684947 -390.902589) (xy 90.654045 -390.884747)
			(xy 90.62809 -390.86026) (xy 90.608481 -390.830447) (xy 90.596277 -390.796916) (xy 90.592135 -390.761474)
			(xy 89.69883 -390.761474) (xy 89.698312 -390.779316) (xy 89.690083 -390.814037) (xy 89.674069 -390.845924)
			(xy 89.651132 -390.873259) (xy 89.62251 -390.894568) (xy 89.589745 -390.908701) (xy 89.554604 -390.914897)
			(xy 89.518981 -390.912823) (xy 89.484797 -390.902589) (xy 89.453895 -390.884747) (xy 89.42794 -390.86026)
			(xy 89.408331 -390.830447) (xy 89.396127 -390.796916) (xy 89.391985 -390.761474) (xy 88.498934 -390.761474)
			(xy 88.498416 -390.779316) (xy 88.490187 -390.814037) (xy 88.474173 -390.845924) (xy 88.451236 -390.873259)
			(xy 88.422614 -390.894568) (xy 88.389849 -390.908701) (xy 88.354708 -390.914897) (xy 88.319085 -390.912823)
			(xy 88.284901 -390.902589) (xy 88.253999 -390.884747) (xy 88.228044 -390.86026) (xy 88.208435 -390.830447)
			(xy 88.196231 -390.796916) (xy 88.192089 -390.761474) (xy 87.299038 -390.761474) (xy 87.29852 -390.779316)
			(xy 87.290291 -390.814037) (xy 87.274277 -390.845924) (xy 87.25134 -390.873259) (xy 87.222718 -390.894568)
			(xy 87.189953 -390.908701) (xy 87.154812 -390.914897) (xy 87.119189 -390.912823) (xy 87.085005 -390.902589)
			(xy 87.054103 -390.884747) (xy 87.028148 -390.86026) (xy 87.008539 -390.830447) (xy 86.996335 -390.796916)
			(xy 86.992193 -390.761474) (xy 86.098888 -390.761474) (xy 86.09837 -390.779316) (xy 86.090141 -390.814037)
			(xy 86.074127 -390.845924) (xy 86.05119 -390.873259) (xy 86.022568 -390.894568) (xy 85.989803 -390.908701)
			(xy 85.954662 -390.914897) (xy 85.919039 -390.912823) (xy 85.884855 -390.902589) (xy 85.853953 -390.884747)
			(xy 85.827998 -390.86026) (xy 85.808389 -390.830447) (xy 85.796185 -390.796916) (xy 85.792043 -390.761474)
			(xy 84.898992 -390.761474) (xy 84.898474 -390.779316) (xy 84.890245 -390.814037) (xy 84.874231 -390.845924)
			(xy 84.851294 -390.873259) (xy 84.822672 -390.894568) (xy 84.789907 -390.908701) (xy 84.754766 -390.914897)
			(xy 84.719143 -390.912823) (xy 84.684959 -390.902589) (xy 84.654057 -390.884747) (xy 84.628102 -390.86026)
			(xy 84.608493 -390.830447) (xy 84.596289 -390.796916) (xy 84.592147 -390.761474) (xy 83.698842 -390.761474)
			(xy 83.698324 -390.779316) (xy 83.690095 -390.814037) (xy 83.674081 -390.845924) (xy 83.651144 -390.873259)
			(xy 83.622522 -390.894568) (xy 83.589757 -390.908701) (xy 83.554616 -390.914897) (xy 83.518993 -390.912823)
			(xy 83.484809 -390.902589) (xy 83.453907 -390.884747) (xy 83.427952 -390.86026) (xy 83.408343 -390.830447)
			(xy 83.396139 -390.796916) (xy 83.391997 -390.761474) (xy 82.498946 -390.761474) (xy 82.498428 -390.779316)
			(xy 82.490199 -390.814037) (xy 82.474185 -390.845924) (xy 82.451248 -390.873259) (xy 82.422626 -390.894568)
			(xy 82.389861 -390.908701) (xy 82.35472 -390.914897) (xy 82.319097 -390.912823) (xy 82.284913 -390.902589)
			(xy 82.254011 -390.884747) (xy 82.228056 -390.86026) (xy 82.208447 -390.830447) (xy 82.196243 -390.796916)
			(xy 82.192101 -390.761474) (xy 81.298796 -390.761474) (xy 81.298278 -390.779316) (xy 81.290049 -390.814037)
			(xy 81.274035 -390.845924) (xy 81.251098 -390.873259) (xy 81.222476 -390.894568) (xy 81.189711 -390.908701)
			(xy 81.15457 -390.914897) (xy 81.118947 -390.912823) (xy 81.084763 -390.902589) (xy 81.053861 -390.884747)
			(xy 81.027906 -390.86026) (xy 81.008297 -390.830447) (xy 80.996093 -390.796916) (xy 80.991951 -390.761474)
			(xy 80.0989 -390.761474) (xy 80.098382 -390.779316) (xy 80.090153 -390.814037) (xy 80.074139 -390.845924)
			(xy 80.051202 -390.873259) (xy 80.02258 -390.894568) (xy 79.989815 -390.908701) (xy 79.954674 -390.914897)
			(xy 79.919051 -390.912823) (xy 79.884867 -390.902589) (xy 79.853965 -390.884747) (xy 79.82801 -390.86026)
			(xy 79.808401 -390.830447) (xy 79.796197 -390.796916) (xy 79.792055 -390.761474) (xy 65.571116 -390.761474)
			(xy 65.570598 -390.779316) (xy 65.562369 -390.814037) (xy 65.546355 -390.845924) (xy 65.523418 -390.873259)
			(xy 65.494796 -390.894568) (xy 65.462031 -390.908701) (xy 65.42689 -390.914897) (xy 65.391267 -390.912823)
			(xy 65.357083 -390.902589) (xy 65.326181 -390.884747) (xy 65.300226 -390.86026) (xy 65.280617 -390.830447)
			(xy 65.268413 -390.796916) (xy 65.264271 -390.761474) (xy 64.37122 -390.761474) (xy 64.370702 -390.779316)
			(xy 64.362473 -390.814037) (xy 64.346459 -390.845924) (xy 64.323522 -390.873259) (xy 64.2949 -390.894568)
			(xy 64.262135 -390.908701) (xy 64.226994 -390.914897) (xy 64.191371 -390.912823) (xy 64.157187 -390.902589)
			(xy 64.126285 -390.884747) (xy 64.10033 -390.86026) (xy 64.080721 -390.830447) (xy 64.068517 -390.796916)
			(xy 64.064375 -390.761474) (xy 63.17107 -390.761474) (xy 63.170552 -390.779316) (xy 63.162323 -390.814037)
			(xy 63.146309 -390.845924) (xy 63.123372 -390.873259) (xy 63.09475 -390.894568) (xy 63.061985 -390.908701)
			(xy 63.026844 -390.914897) (xy 62.991221 -390.912823) (xy 62.957037 -390.902589) (xy 62.926135 -390.884747)
			(xy 62.90018 -390.86026) (xy 62.880571 -390.830447) (xy 62.868367 -390.796916) (xy 62.864225 -390.761474)
			(xy 61.971174 -390.761474) (xy 61.970656 -390.779316) (xy 61.962427 -390.814037) (xy 61.946413 -390.845924)
			(xy 61.923476 -390.873259) (xy 61.894854 -390.894568) (xy 61.862089 -390.908701) (xy 61.826948 -390.914897)
			(xy 61.791325 -390.912823) (xy 61.757141 -390.902589) (xy 61.726239 -390.884747) (xy 61.700284 -390.86026)
			(xy 61.680675 -390.830447) (xy 61.668471 -390.796916) (xy 61.664329 -390.761474) (xy 60.771278 -390.761474)
			(xy 60.77076 -390.779316) (xy 60.762531 -390.814037) (xy 60.746517 -390.845924) (xy 60.72358 -390.873259)
			(xy 60.694958 -390.894568) (xy 60.662193 -390.908701) (xy 60.627052 -390.914897) (xy 60.591429 -390.912823)
			(xy 60.557245 -390.902589) (xy 60.526343 -390.884747) (xy 60.500388 -390.86026) (xy 60.480779 -390.830447)
			(xy 60.468575 -390.796916) (xy 60.464433 -390.761474) (xy 59.571128 -390.761474) (xy 59.57061 -390.779316)
			(xy 59.562381 -390.814037) (xy 59.546367 -390.845924) (xy 59.52343 -390.873259) (xy 59.494808 -390.894568)
			(xy 59.462043 -390.908701) (xy 59.426902 -390.914897) (xy 59.391279 -390.912823) (xy 59.357095 -390.902589)
			(xy 59.326193 -390.884747) (xy 59.300238 -390.86026) (xy 59.280629 -390.830447) (xy 59.268425 -390.796916)
			(xy 59.264283 -390.761474) (xy 58.371232 -390.761474) (xy 58.370714 -390.779316) (xy 58.362485 -390.814037)
			(xy 58.346471 -390.845924) (xy 58.323534 -390.873259) (xy 58.294912 -390.894568) (xy 58.262147 -390.908701)
			(xy 58.227006 -390.914897) (xy 58.191383 -390.912823) (xy 58.157199 -390.902589) (xy 58.126297 -390.884747)
			(xy 58.100342 -390.86026) (xy 58.080733 -390.830447) (xy 58.068529 -390.796916) (xy 58.064387 -390.761474)
			(xy 57.171082 -390.761474) (xy 57.170564 -390.779316) (xy 57.162335 -390.814037) (xy 57.146321 -390.845924)
			(xy 57.123384 -390.873259) (xy 57.094762 -390.894568) (xy 57.061997 -390.908701) (xy 57.026856 -390.914897)
			(xy 56.991233 -390.912823) (xy 56.957049 -390.902589) (xy 56.926147 -390.884747) (xy 56.900192 -390.86026)
			(xy 56.880583 -390.830447) (xy 56.868379 -390.796916) (xy 56.864237 -390.761474) (xy 55.971186 -390.761474)
			(xy 55.970668 -390.779316) (xy 55.962439 -390.814037) (xy 55.946425 -390.845924) (xy 55.923488 -390.873259)
			(xy 55.894866 -390.894568) (xy 55.862101 -390.908701) (xy 55.82696 -390.914897) (xy 55.791337 -390.912823)
			(xy 55.757153 -390.902589) (xy 55.726251 -390.884747) (xy 55.700296 -390.86026) (xy 55.680687 -390.830447)
			(xy 55.668483 -390.796916) (xy 55.664341 -390.761474) (xy 54.77129 -390.761474) (xy 54.770772 -390.779316)
			(xy 54.762543 -390.814037) (xy 54.746529 -390.845924) (xy 54.723592 -390.873259) (xy 54.69497 -390.894568)
			(xy 54.662205 -390.908701) (xy 54.627064 -390.914897) (xy 54.591441 -390.912823) (xy 54.557257 -390.902589)
			(xy 54.526355 -390.884747) (xy 54.5004 -390.86026) (xy 54.480791 -390.830447) (xy 54.468587 -390.796916)
			(xy 54.464445 -390.761474) (xy 53.57114 -390.761474) (xy 53.570622 -390.779316) (xy 53.562393 -390.814037)
			(xy 53.546379 -390.845924) (xy 53.523442 -390.873259) (xy 53.49482 -390.894568) (xy 53.462055 -390.908701)
			(xy 53.426914 -390.914897) (xy 53.391291 -390.912823) (xy 53.357107 -390.902589) (xy 53.326205 -390.884747)
			(xy 53.30025 -390.86026) (xy 53.280641 -390.830447) (xy 53.268437 -390.796916) (xy 53.264295 -390.761474)
			(xy 52.371244 -390.761474) (xy 52.370726 -390.779316) (xy 52.362497 -390.814037) (xy 52.346483 -390.845924)
			(xy 52.323546 -390.873259) (xy 52.294924 -390.894568) (xy 52.262159 -390.908701) (xy 52.227018 -390.914897)
			(xy 52.191395 -390.912823) (xy 52.157211 -390.902589) (xy 52.126309 -390.884747) (xy 52.100354 -390.86026)
			(xy 52.080745 -390.830447) (xy 52.068541 -390.796916) (xy 52.064399 -390.761474) (xy 51.171094 -390.761474)
			(xy 51.170576 -390.779316) (xy 51.162347 -390.814037) (xy 51.146333 -390.845924) (xy 51.123396 -390.873259)
			(xy 51.094774 -390.894568) (xy 51.062009 -390.908701) (xy 51.026868 -390.914897) (xy 50.991245 -390.912823)
			(xy 50.957061 -390.902589) (xy 50.926159 -390.884747) (xy 50.900204 -390.86026) (xy 50.880595 -390.830447)
			(xy 50.868391 -390.796916) (xy 50.864249 -390.761474) (xy 49.971198 -390.761474) (xy 49.97068 -390.779316)
			(xy 49.962451 -390.814037) (xy 49.946437 -390.845924) (xy 49.9235 -390.873259) (xy 49.894878 -390.894568)
			(xy 49.862113 -390.908701) (xy 49.826972 -390.914897) (xy 49.791349 -390.912823) (xy 49.757165 -390.902589)
			(xy 49.726263 -390.884747) (xy 49.700308 -390.86026) (xy 49.680699 -390.830447) (xy 49.668495 -390.796916)
			(xy 49.664353 -390.761474) (xy 48.771048 -390.761474) (xy 48.77053 -390.779316) (xy 48.762301 -390.814037)
			(xy 48.746287 -390.845924) (xy 48.72335 -390.873259) (xy 48.694728 -390.894568) (xy 48.661963 -390.908701)
			(xy 48.626822 -390.914897) (xy 48.591199 -390.912823) (xy 48.557015 -390.902589) (xy 48.526113 -390.884747)
			(xy 48.500158 -390.86026) (xy 48.480549 -390.830447) (xy 48.468345 -390.796916) (xy 48.464203 -390.761474)
			(xy 47.571152 -390.761474) (xy 47.570634 -390.779316) (xy 47.562405 -390.814037) (xy 47.546391 -390.845924)
			(xy 47.523454 -390.873259) (xy 47.494832 -390.894568) (xy 47.462067 -390.908701) (xy 47.426926 -390.914897)
			(xy 47.391303 -390.912823) (xy 47.357119 -390.902589) (xy 47.326217 -390.884747) (xy 47.300262 -390.86026)
			(xy 47.280653 -390.830447) (xy 47.268449 -390.796916) (xy 47.264307 -390.761474) (xy 2.509012 -390.761474)
			(xy 2.509012 -391.319258) (xy 46.990508 -391.319258) (xy 46.990508 -391.243058) (xy 46.990973 -391.227632)
			(xy 46.998356 -391.197677) (xy 47.012693 -391.170359) (xy 47.033152 -391.147266) (xy 47.058542 -391.12974)
			(xy 47.087389 -391.1188) (xy 47.118016 -391.115082) (xy 47.148643 -391.1188) (xy 47.17749 -391.12974)
			(xy 47.20288 -391.147266) (xy 47.223339 -391.170359) (xy 47.237676 -391.197677) (xy 47.245059 -391.227632)
			(xy 47.245524 -391.243058) (xy 47.245524 -391.319258) (xy 48.190404 -391.319258) (xy 48.190404 -391.243058)
			(xy 48.190869 -391.227632) (xy 48.198252 -391.197677) (xy 48.212589 -391.170359) (xy 48.233048 -391.147266)
			(xy 48.258438 -391.12974) (xy 48.287285 -391.1188) (xy 48.317912 -391.115082) (xy 48.348539 -391.1188)
			(xy 48.377386 -391.12974) (xy 48.402776 -391.147266) (xy 48.423235 -391.170359) (xy 48.437572 -391.197677)
			(xy 48.444955 -391.227632) (xy 48.44542 -391.243058) (xy 48.44542 -391.319258) (xy 49.3903 -391.319258)
			(xy 49.3903 -391.243058) (xy 49.390766 -391.227601) (xy 49.398164 -391.197587) (xy 49.41253 -391.170214)
			(xy 49.433029 -391.147076) (xy 49.45847 -391.129515) (xy 49.487374 -391.118553) (xy 49.518062 -391.114827)
			(xy 49.54875 -391.118553) (xy 49.577654 -391.129515) (xy 49.603095 -391.147076) (xy 49.623594 -391.170214)
			(xy 49.63796 -391.197587) (xy 49.645358 -391.227601) (xy 49.645824 -391.243058) (xy 49.645824 -391.319258)
			(xy 50.590196 -391.319258) (xy 50.590196 -391.243058) (xy 50.590662 -391.227601) (xy 50.59806 -391.197587)
			(xy 50.612426 -391.170214) (xy 50.632925 -391.147076) (xy 50.658366 -391.129515) (xy 50.68727 -391.118553)
			(xy 50.717958 -391.114827) (xy 50.748646 -391.118553) (xy 50.77755 -391.129515) (xy 50.802991 -391.147076)
			(xy 50.82349 -391.170214) (xy 50.837856 -391.197587) (xy 50.845254 -391.227601) (xy 50.84572 -391.243058)
			(xy 50.84572 -391.319258) (xy 51.7906 -391.319258) (xy 51.7906 -391.243058) (xy 51.791065 -391.227632)
			(xy 51.798448 -391.197677) (xy 51.812785 -391.170359) (xy 51.833244 -391.147266) (xy 51.858634 -391.12974)
			(xy 51.887481 -391.1188) (xy 51.918108 -391.115082) (xy 51.948735 -391.1188) (xy 51.977582 -391.12974)
			(xy 52.002972 -391.147266) (xy 52.023431 -391.170359) (xy 52.037768 -391.197677) (xy 52.045151 -391.227632)
			(xy 52.045616 -391.243058) (xy 52.045616 -391.319258) (xy 52.990496 -391.319258) (xy 52.990496 -391.243058)
			(xy 52.990961 -391.227632) (xy 52.998344 -391.197677) (xy 53.012681 -391.170359) (xy 53.03314 -391.147266)
			(xy 53.05853 -391.12974) (xy 53.087377 -391.1188) (xy 53.118004 -391.115082) (xy 53.148631 -391.1188)
			(xy 53.177478 -391.12974) (xy 53.202868 -391.147266) (xy 53.223327 -391.170359) (xy 53.237664 -391.197677)
			(xy 53.245047 -391.227632) (xy 53.245512 -391.243058) (xy 53.245512 -391.319258) (xy 54.190392 -391.319258)
			(xy 54.190392 -391.243058) (xy 54.190858 -391.227601) (xy 54.198256 -391.197587) (xy 54.212622 -391.170214)
			(xy 54.233121 -391.147076) (xy 54.258562 -391.129515) (xy 54.287466 -391.118553) (xy 54.318154 -391.114827)
			(xy 54.348842 -391.118553) (xy 54.377746 -391.129515) (xy 54.403187 -391.147076) (xy 54.423686 -391.170214)
			(xy 54.438052 -391.197587) (xy 54.44545 -391.227601) (xy 54.445916 -391.243058) (xy 54.445916 -391.319258)
			(xy 55.390288 -391.319258) (xy 55.390288 -391.243058) (xy 55.390754 -391.227601) (xy 55.398152 -391.197587)
			(xy 55.412518 -391.170214) (xy 55.433017 -391.147076) (xy 55.458458 -391.129515) (xy 55.487362 -391.118553)
			(xy 55.51805 -391.114827) (xy 55.548738 -391.118553) (xy 55.577642 -391.129515) (xy 55.603083 -391.147076)
			(xy 55.623582 -391.170214) (xy 55.637948 -391.197587) (xy 55.645346 -391.227601) (xy 55.645812 -391.243058)
			(xy 55.645812 -391.319258) (xy 56.590184 -391.319258) (xy 56.590184 -391.243058) (xy 56.59065 -391.227601)
			(xy 56.598048 -391.197587) (xy 56.612414 -391.170214) (xy 56.632913 -391.147076) (xy 56.658354 -391.129515)
			(xy 56.687258 -391.118553) (xy 56.717946 -391.114827) (xy 56.748634 -391.118553) (xy 56.777538 -391.129515)
			(xy 56.802979 -391.147076) (xy 56.823478 -391.170214) (xy 56.837844 -391.197587) (xy 56.845242 -391.227601)
			(xy 56.845708 -391.243058) (xy 56.845708 -391.319258) (xy 57.790588 -391.319258) (xy 57.790588 -391.243058)
			(xy 57.791053 -391.227632) (xy 57.798436 -391.197677) (xy 57.812773 -391.170359) (xy 57.833232 -391.147266)
			(xy 57.858622 -391.12974) (xy 57.887469 -391.1188) (xy 57.918096 -391.115082) (xy 57.948723 -391.1188)
			(xy 57.97757 -391.12974) (xy 58.00296 -391.147266) (xy 58.023419 -391.170359) (xy 58.037756 -391.197677)
			(xy 58.045139 -391.227632) (xy 58.045604 -391.243058) (xy 58.045604 -391.319258) (xy 58.990484 -391.319258)
			(xy 58.990484 -391.243058) (xy 58.990949 -391.227632) (xy 58.998332 -391.197677) (xy 59.012669 -391.170359)
			(xy 59.033128 -391.147266) (xy 59.058518 -391.12974) (xy 59.087365 -391.1188) (xy 59.117992 -391.115082)
			(xy 59.148619 -391.1188) (xy 59.177466 -391.12974) (xy 59.202856 -391.147266) (xy 59.223315 -391.170359)
			(xy 59.237652 -391.197677) (xy 59.245035 -391.227632) (xy 59.2455 -391.243058) (xy 59.2455 -391.319258)
			(xy 60.19038 -391.319258) (xy 60.19038 -391.243058) (xy 60.190846 -391.227601) (xy 60.198244 -391.197587)
			(xy 60.21261 -391.170214) (xy 60.233109 -391.147076) (xy 60.25855 -391.129515) (xy 60.287454 -391.118553)
			(xy 60.318142 -391.114827) (xy 60.34883 -391.118553) (xy 60.377734 -391.129515) (xy 60.403175 -391.147076)
			(xy 60.423674 -391.170214) (xy 60.43804 -391.197587) (xy 60.445438 -391.227601) (xy 60.445904 -391.243058)
			(xy 60.445904 -391.319258) (xy 61.390276 -391.319258) (xy 61.390276 -391.243058) (xy 61.390742 -391.227601)
			(xy 61.39814 -391.197587) (xy 61.412506 -391.170214) (xy 61.433005 -391.147076) (xy 61.458446 -391.129515)
			(xy 61.48735 -391.118553) (xy 61.518038 -391.114827) (xy 61.548726 -391.118553) (xy 61.57763 -391.129515)
			(xy 61.603071 -391.147076) (xy 61.62357 -391.170214) (xy 61.637936 -391.197587) (xy 61.645334 -391.227601)
			(xy 61.6458 -391.243058) (xy 61.6458 -391.319258) (xy 62.590172 -391.319258) (xy 62.590172 -391.243058)
			(xy 62.590638 -391.227601) (xy 62.598036 -391.197587) (xy 62.612402 -391.170214) (xy 62.632901 -391.147076)
			(xy 62.658342 -391.129515) (xy 62.687246 -391.118553) (xy 62.717934 -391.114827) (xy 62.748622 -391.118553)
			(xy 62.777526 -391.129515) (xy 62.802967 -391.147076) (xy 62.823466 -391.170214) (xy 62.837832 -391.197587)
			(xy 62.84523 -391.227601) (xy 62.845696 -391.243058) (xy 62.845696 -391.319258) (xy 63.790576 -391.319258)
			(xy 63.790576 -391.243058) (xy 63.791041 -391.227632) (xy 63.798424 -391.197677) (xy 63.812761 -391.170359)
			(xy 63.83322 -391.147266) (xy 63.85861 -391.12974) (xy 63.887457 -391.1188) (xy 63.918084 -391.115082)
			(xy 63.948711 -391.1188) (xy 63.977558 -391.12974) (xy 64.002948 -391.147266) (xy 64.023407 -391.170359)
			(xy 64.037744 -391.197677) (xy 64.045127 -391.227632) (xy 64.045592 -391.243058) (xy 64.045592 -391.319258)
			(xy 64.990472 -391.319258) (xy 64.990472 -391.243058) (xy 64.990937 -391.227632) (xy 64.99832 -391.197677)
			(xy 65.012657 -391.170359) (xy 65.033116 -391.147266) (xy 65.058506 -391.12974) (xy 65.087353 -391.1188)
			(xy 65.11798 -391.115082) (xy 65.148607 -391.1188) (xy 65.177454 -391.12974) (xy 65.202844 -391.147266)
			(xy 65.223303 -391.170359) (xy 65.23764 -391.197677) (xy 65.245023 -391.227632) (xy 65.245488 -391.243058)
			(xy 65.245488 -391.319258) (xy 79.518256 -391.319258) (xy 79.518256 -391.243058) (xy 79.518721 -391.227632)
			(xy 79.526104 -391.197677) (xy 79.540441 -391.170359) (xy 79.5609 -391.147266) (xy 79.58629 -391.12974)
			(xy 79.615137 -391.1188) (xy 79.645764 -391.115082) (xy 79.676391 -391.1188) (xy 79.705238 -391.12974)
			(xy 79.730628 -391.147266) (xy 79.751087 -391.170359) (xy 79.765424 -391.197677) (xy 79.772807 -391.227632)
			(xy 79.773272 -391.243058) (xy 79.773272 -391.319258) (xy 80.718152 -391.319258) (xy 80.718152 -391.243058)
			(xy 80.718617 -391.227632) (xy 80.726 -391.197677) (xy 80.740337 -391.170359) (xy 80.760796 -391.147266)
			(xy 80.786186 -391.12974) (xy 80.815033 -391.1188) (xy 80.84566 -391.115082) (xy 80.876287 -391.1188)
			(xy 80.905134 -391.12974) (xy 80.930524 -391.147266) (xy 80.950983 -391.170359) (xy 80.96532 -391.197677)
			(xy 80.972703 -391.227632) (xy 80.973168 -391.243058) (xy 80.973168 -391.319258) (xy 81.918048 -391.319258)
			(xy 81.918048 -391.243058) (xy 81.918514 -391.227601) (xy 81.925912 -391.197587) (xy 81.940278 -391.170214)
			(xy 81.960777 -391.147076) (xy 81.986218 -391.129515) (xy 82.015122 -391.118553) (xy 82.04581 -391.114827)
			(xy 82.076498 -391.118553) (xy 82.105402 -391.129515) (xy 82.130843 -391.147076) (xy 82.151342 -391.170214)
			(xy 82.165708 -391.197587) (xy 82.173106 -391.227601) (xy 82.173572 -391.243058) (xy 82.173572 -391.319258)
			(xy 83.117944 -391.319258) (xy 83.117944 -391.243058) (xy 83.11841 -391.227601) (xy 83.125808 -391.197587)
			(xy 83.140174 -391.170214) (xy 83.160673 -391.147076) (xy 83.186114 -391.129515) (xy 83.215018 -391.118553)
			(xy 83.245706 -391.114827) (xy 83.276394 -391.118553) (xy 83.305298 -391.129515) (xy 83.330739 -391.147076)
			(xy 83.351238 -391.170214) (xy 83.365604 -391.197587) (xy 83.373002 -391.227601) (xy 83.373468 -391.243058)
			(xy 83.373468 -391.319258) (xy 84.318348 -391.319258) (xy 84.318348 -391.243058) (xy 84.318813 -391.227632)
			(xy 84.326196 -391.197677) (xy 84.340533 -391.170359) (xy 84.360992 -391.147266) (xy 84.386382 -391.12974)
			(xy 84.415229 -391.1188) (xy 84.445856 -391.115082) (xy 84.476483 -391.1188) (xy 84.50533 -391.12974)
			(xy 84.53072 -391.147266) (xy 84.551179 -391.170359) (xy 84.565516 -391.197677) (xy 84.572899 -391.227632)
			(xy 84.573364 -391.243058) (xy 84.573364 -391.319258) (xy 85.518244 -391.319258) (xy 85.518244 -391.243058)
			(xy 85.518709 -391.227632) (xy 85.526092 -391.197677) (xy 85.540429 -391.170359) (xy 85.560888 -391.147266)
			(xy 85.586278 -391.12974) (xy 85.615125 -391.1188) (xy 85.645752 -391.115082) (xy 85.676379 -391.1188)
			(xy 85.705226 -391.12974) (xy 85.730616 -391.147266) (xy 85.751075 -391.170359) (xy 85.765412 -391.197677)
			(xy 85.772795 -391.227632) (xy 85.77326 -391.243058) (xy 85.77326 -391.319258) (xy 86.71814 -391.319258)
			(xy 86.71814 -391.243058) (xy 86.718606 -391.227601) (xy 86.726004 -391.197587) (xy 86.74037 -391.170214)
			(xy 86.760869 -391.147076) (xy 86.78631 -391.129515) (xy 86.815214 -391.118553) (xy 86.845902 -391.114827)
			(xy 86.87659 -391.118553) (xy 86.905494 -391.129515) (xy 86.930935 -391.147076) (xy 86.951434 -391.170214)
			(xy 86.9658 -391.197587) (xy 86.973198 -391.227601) (xy 86.973664 -391.243058) (xy 86.973664 -391.319258)
			(xy 87.918036 -391.319258) (xy 87.918036 -391.243058) (xy 87.918502 -391.227601) (xy 87.9259 -391.197587)
			(xy 87.940266 -391.170214) (xy 87.960765 -391.147076) (xy 87.986206 -391.129515) (xy 88.01511 -391.118553)
			(xy 88.045798 -391.114827) (xy 88.076486 -391.118553) (xy 88.10539 -391.129515) (xy 88.130831 -391.147076)
			(xy 88.15133 -391.170214) (xy 88.165696 -391.197587) (xy 88.173094 -391.227601) (xy 88.17356 -391.243058)
			(xy 88.17356 -391.319258) (xy 89.117932 -391.319258) (xy 89.117932 -391.243058) (xy 89.118398 -391.227601)
			(xy 89.125796 -391.197587) (xy 89.140162 -391.170214) (xy 89.160661 -391.147076) (xy 89.186102 -391.129515)
			(xy 89.215006 -391.118553) (xy 89.245694 -391.114827) (xy 89.276382 -391.118553) (xy 89.305286 -391.129515)
			(xy 89.330727 -391.147076) (xy 89.351226 -391.170214) (xy 89.365592 -391.197587) (xy 89.37299 -391.227601)
			(xy 89.373456 -391.243058) (xy 89.373456 -391.319258) (xy 90.318336 -391.319258) (xy 90.318336 -391.243058)
			(xy 90.318801 -391.227632) (xy 90.326184 -391.197677) (xy 90.340521 -391.170359) (xy 90.36098 -391.147266)
			(xy 90.38637 -391.12974) (xy 90.415217 -391.1188) (xy 90.445844 -391.115082) (xy 90.476471 -391.1188)
			(xy 90.505318 -391.12974) (xy 90.530708 -391.147266) (xy 90.551167 -391.170359) (xy 90.565504 -391.197677)
			(xy 90.572887 -391.227632) (xy 90.573352 -391.243058) (xy 90.573352 -391.319258) (xy 91.518232 -391.319258)
			(xy 91.518232 -391.243058) (xy 91.518697 -391.227632) (xy 91.52608 -391.197677) (xy 91.540417 -391.170359)
			(xy 91.560876 -391.147266) (xy 91.586266 -391.12974) (xy 91.615113 -391.1188) (xy 91.64574 -391.115082)
			(xy 91.676367 -391.1188) (xy 91.705214 -391.12974) (xy 91.730604 -391.147266) (xy 91.751063 -391.170359)
			(xy 91.7654 -391.197677) (xy 91.772783 -391.227632) (xy 91.773248 -391.243058) (xy 91.773248 -391.319258)
			(xy 92.718128 -391.319258) (xy 92.718128 -391.243058) (xy 92.718594 -391.227601) (xy 92.725992 -391.197587)
			(xy 92.740358 -391.170214) (xy 92.760857 -391.147076) (xy 92.786298 -391.129515) (xy 92.815202 -391.118553)
			(xy 92.84589 -391.114827) (xy 92.876578 -391.118553) (xy 92.905482 -391.129515) (xy 92.930923 -391.147076)
			(xy 92.951422 -391.170214) (xy 92.965788 -391.197587) (xy 92.973186 -391.227601) (xy 92.973652 -391.243058)
			(xy 92.973652 -391.319258) (xy 93.918024 -391.319258) (xy 93.918024 -391.243058) (xy 93.91849 -391.227601)
			(xy 93.925888 -391.197587) (xy 93.940254 -391.170214) (xy 93.960753 -391.147076) (xy 93.986194 -391.129515)
			(xy 94.015098 -391.118553) (xy 94.045786 -391.114827) (xy 94.076474 -391.118553) (xy 94.105378 -391.129515)
			(xy 94.130819 -391.147076) (xy 94.151318 -391.170214) (xy 94.165684 -391.197587) (xy 94.173082 -391.227601)
			(xy 94.173548 -391.243058) (xy 94.173548 -391.319258) (xy 95.11792 -391.319258) (xy 95.11792 -391.243058)
			(xy 95.118386 -391.227601) (xy 95.125784 -391.197587) (xy 95.14015 -391.170214) (xy 95.160649 -391.147076)
			(xy 95.18609 -391.129515) (xy 95.214994 -391.118553) (xy 95.245682 -391.114827) (xy 95.27637 -391.118553)
			(xy 95.305274 -391.129515) (xy 95.330715 -391.147076) (xy 95.351214 -391.170214) (xy 95.36558 -391.197587)
			(xy 95.372978 -391.227601) (xy 95.373444 -391.243058) (xy 95.373444 -391.319258) (xy 96.318324 -391.319258)
			(xy 96.318324 -391.243058) (xy 96.318789 -391.227632) (xy 96.326172 -391.197677) (xy 96.340509 -391.170359)
			(xy 96.360968 -391.147266) (xy 96.386358 -391.12974) (xy 96.415205 -391.1188) (xy 96.445832 -391.115082)
			(xy 96.476459 -391.1188) (xy 96.505306 -391.12974) (xy 96.530696 -391.147266) (xy 96.551155 -391.170359)
			(xy 96.565492 -391.197677) (xy 96.572875 -391.227632) (xy 96.57334 -391.243058) (xy 96.57334 -391.319258)
			(xy 97.51822 -391.319258) (xy 97.51822 -391.243058) (xy 97.518685 -391.227632) (xy 97.526068 -391.197677)
			(xy 97.540405 -391.170359) (xy 97.560864 -391.147266) (xy 97.586254 -391.12974) (xy 97.615101 -391.1188)
			(xy 97.645728 -391.115082) (xy 97.676355 -391.1188) (xy 97.705202 -391.12974) (xy 97.730592 -391.147266)
			(xy 97.751051 -391.170359) (xy 97.765388 -391.197677) (xy 97.772771 -391.227632) (xy 97.773236 -391.243058)
			(xy 97.773236 -391.319258) (xy 114.090196 -391.319258) (xy 114.090196 -391.243058) (xy 114.090662 -391.227601)
			(xy 114.09806 -391.197587) (xy 114.112426 -391.170214) (xy 114.132925 -391.147076) (xy 114.158366 -391.129515)
			(xy 114.18727 -391.118553) (xy 114.217958 -391.114827) (xy 114.248646 -391.118553) (xy 114.27755 -391.129515)
			(xy 114.302991 -391.147076) (xy 114.32349 -391.170214) (xy 114.337856 -391.197587) (xy 114.345254 -391.227601)
			(xy 114.34572 -391.243058) (xy 114.34572 -391.319258) (xy 115.290092 -391.319258) (xy 115.290092 -391.243058)
			(xy 115.290558 -391.227601) (xy 115.297956 -391.197587) (xy 115.312322 -391.170214) (xy 115.332821 -391.147076)
			(xy 115.358262 -391.129515) (xy 115.387166 -391.118553) (xy 115.417854 -391.114827) (xy 115.448542 -391.118553)
			(xy 115.477446 -391.129515) (xy 115.502887 -391.147076) (xy 115.523386 -391.170214) (xy 115.537752 -391.197587)
			(xy 115.54515 -391.227601) (xy 115.545616 -391.243058) (xy 115.545616 -391.319258) (xy 116.490496 -391.319258)
			(xy 116.490496 -391.243058) (xy 116.490961 -391.227632) (xy 116.498344 -391.197677) (xy 116.512681 -391.170359)
			(xy 116.53314 -391.147266) (xy 116.55853 -391.12974) (xy 116.587377 -391.1188) (xy 116.618004 -391.115082)
			(xy 116.648631 -391.1188) (xy 116.677478 -391.12974) (xy 116.702868 -391.147266) (xy 116.723327 -391.170359)
			(xy 116.737664 -391.197677) (xy 116.745047 -391.227632) (xy 116.745512 -391.243058) (xy 116.745512 -391.319258)
			(xy 117.690392 -391.319258) (xy 117.690392 -391.243058) (xy 117.690857 -391.227632) (xy 117.69824 -391.197677)
			(xy 117.712577 -391.170359) (xy 117.733036 -391.147266) (xy 117.758426 -391.12974) (xy 117.787273 -391.1188)
			(xy 117.8179 -391.115082) (xy 117.848527 -391.1188) (xy 117.877374 -391.12974) (xy 117.902764 -391.147266)
			(xy 117.923223 -391.170359) (xy 117.93756 -391.197677) (xy 117.944943 -391.227632) (xy 117.945408 -391.243058)
			(xy 117.945408 -391.319258) (xy 118.890288 -391.319258) (xy 118.890288 -391.243058) (xy 118.890754 -391.227601)
			(xy 118.898152 -391.197587) (xy 118.912518 -391.170214) (xy 118.933017 -391.147076) (xy 118.958458 -391.129515)
			(xy 118.987362 -391.118553) (xy 119.01805 -391.114827) (xy 119.048738 -391.118553) (xy 119.077642 -391.129515)
			(xy 119.103083 -391.147076) (xy 119.123582 -391.170214) (xy 119.137948 -391.197587) (xy 119.145346 -391.227601)
			(xy 119.145812 -391.243058) (xy 119.145812 -391.319258) (xy 120.090184 -391.319258) (xy 120.090184 -391.243058)
			(xy 120.09065 -391.227601) (xy 120.098048 -391.197587) (xy 120.112414 -391.170214) (xy 120.132913 -391.147076)
			(xy 120.158354 -391.129515) (xy 120.187258 -391.118553) (xy 120.217946 -391.114827) (xy 120.248634 -391.118553)
			(xy 120.277538 -391.129515) (xy 120.302979 -391.147076) (xy 120.323478 -391.170214) (xy 120.337844 -391.197587)
			(xy 120.345242 -391.227601) (xy 120.345708 -391.243058) (xy 120.345708 -391.319258) (xy 121.290588 -391.319258)
			(xy 121.290588 -391.243058) (xy 121.291053 -391.227632) (xy 121.298436 -391.197677) (xy 121.312773 -391.170359)
			(xy 121.333232 -391.147266) (xy 121.358622 -391.12974) (xy 121.387469 -391.1188) (xy 121.418096 -391.115082)
			(xy 121.448723 -391.1188) (xy 121.47757 -391.12974) (xy 121.50296 -391.147266) (xy 121.523419 -391.170359)
			(xy 121.537756 -391.197677) (xy 121.545139 -391.227632) (xy 121.545604 -391.243058) (xy 121.545604 -391.319258)
			(xy 122.490484 -391.319258) (xy 122.490484 -391.243058) (xy 122.490949 -391.227632) (xy 122.498332 -391.197677)
			(xy 122.512669 -391.170359) (xy 122.533128 -391.147266) (xy 122.558518 -391.12974) (xy 122.587365 -391.1188)
			(xy 122.617992 -391.115082) (xy 122.648619 -391.1188) (xy 122.677466 -391.12974) (xy 122.702856 -391.147266)
			(xy 122.723315 -391.170359) (xy 122.737652 -391.197677) (xy 122.745035 -391.227632) (xy 122.7455 -391.243058)
			(xy 122.7455 -391.319258) (xy 123.69038 -391.319258) (xy 123.69038 -391.243058) (xy 123.690845 -391.227632)
			(xy 123.698228 -391.197677) (xy 123.712565 -391.170359) (xy 123.733024 -391.147266) (xy 123.758414 -391.12974)
			(xy 123.787261 -391.1188) (xy 123.817888 -391.115082) (xy 123.848515 -391.1188) (xy 123.877362 -391.12974)
			(xy 123.902752 -391.147266) (xy 123.923211 -391.170359) (xy 123.937548 -391.197677) (xy 123.944931 -391.227632)
			(xy 123.945396 -391.243058) (xy 123.945396 -391.319258) (xy 124.890276 -391.319258) (xy 124.890276 -391.243058)
			(xy 124.890742 -391.227601) (xy 124.89814 -391.197587) (xy 124.912506 -391.170214) (xy 124.933005 -391.147076)
			(xy 124.958446 -391.129515) (xy 124.98735 -391.118553) (xy 125.018038 -391.114827) (xy 125.048726 -391.118553)
			(xy 125.07763 -391.129515) (xy 125.103071 -391.147076) (xy 125.12357 -391.170214) (xy 125.137936 -391.197587)
			(xy 125.145334 -391.227601) (xy 125.1458 -391.243058) (xy 125.1458 -391.319258) (xy 126.090172 -391.319258)
			(xy 126.090172 -391.243058) (xy 126.090638 -391.227601) (xy 126.098036 -391.197587) (xy 126.112402 -391.170214)
			(xy 126.132901 -391.147076) (xy 126.158342 -391.129515) (xy 126.187246 -391.118553) (xy 126.217934 -391.114827)
			(xy 126.248622 -391.118553) (xy 126.277526 -391.129515) (xy 126.302967 -391.147076) (xy 126.323466 -391.170214)
			(xy 126.337832 -391.197587) (xy 126.34523 -391.227601) (xy 126.345696 -391.243058) (xy 126.345696 -391.319258)
			(xy 127.290576 -391.319258) (xy 127.290576 -391.243058) (xy 127.291041 -391.227632) (xy 127.298424 -391.197677)
			(xy 127.312761 -391.170359) (xy 127.33322 -391.147266) (xy 127.35861 -391.12974) (xy 127.387457 -391.1188)
			(xy 127.418084 -391.115082) (xy 127.448711 -391.1188) (xy 127.477558 -391.12974) (xy 127.502948 -391.147266)
			(xy 127.523407 -391.170359) (xy 127.537744 -391.197677) (xy 127.545127 -391.227632) (xy 127.545592 -391.243058)
			(xy 127.545592 -391.319258) (xy 128.490472 -391.319258) (xy 128.490472 -391.243058) (xy 128.490937 -391.227632)
			(xy 128.49832 -391.197677) (xy 128.512657 -391.170359) (xy 128.533116 -391.147266) (xy 128.558506 -391.12974)
			(xy 128.587353 -391.1188) (xy 128.61798 -391.115082) (xy 128.648607 -391.1188) (xy 128.677454 -391.12974)
			(xy 128.702844 -391.147266) (xy 128.723303 -391.170359) (xy 128.73764 -391.197677) (xy 128.745023 -391.227632)
			(xy 128.745488 -391.243058) (xy 128.745488 -391.319258) (xy 129.690368 -391.319258) (xy 129.690368 -391.243058)
			(xy 129.690833 -391.227632) (xy 129.698216 -391.197677) (xy 129.712553 -391.170359) (xy 129.733012 -391.147266)
			(xy 129.758402 -391.12974) (xy 129.787249 -391.1188) (xy 129.817876 -391.115082) (xy 129.848503 -391.1188)
			(xy 129.87735 -391.12974) (xy 129.90274 -391.147266) (xy 129.923199 -391.170359) (xy 129.937536 -391.197677)
			(xy 129.944919 -391.227632) (xy 129.945384 -391.243058) (xy 129.945384 -391.319258) (xy 130.890264 -391.319258)
			(xy 130.890264 -391.243058) (xy 130.89073 -391.227601) (xy 130.898128 -391.197587) (xy 130.912494 -391.170214)
			(xy 130.932993 -391.147076) (xy 130.958434 -391.129515) (xy 130.987338 -391.118553) (xy 131.018026 -391.114827)
			(xy 131.048714 -391.118553) (xy 131.077618 -391.129515) (xy 131.103059 -391.147076) (xy 131.123558 -391.170214)
			(xy 131.137924 -391.197587) (xy 131.145322 -391.227601) (xy 131.145788 -391.243058) (xy 131.145788 -391.319258)
			(xy 132.09016 -391.319258) (xy 132.09016 -391.243058) (xy 132.090626 -391.227601) (xy 132.098024 -391.197587)
			(xy 132.11239 -391.170214) (xy 132.132889 -391.147076) (xy 132.15833 -391.129515) (xy 132.187234 -391.118553)
			(xy 132.217922 -391.114827) (xy 132.24861 -391.118553) (xy 132.277514 -391.129515) (xy 132.302955 -391.147076)
			(xy 132.323454 -391.170214) (xy 132.33782 -391.197587) (xy 132.345218 -391.227601) (xy 132.345684 -391.243058)
			(xy 132.345684 -391.319258) (xy 146.617944 -391.319258) (xy 146.617944 -391.243058) (xy 146.61841 -391.227601)
			(xy 146.625808 -391.197587) (xy 146.640174 -391.170214) (xy 146.660673 -391.147076) (xy 146.686114 -391.129515)
			(xy 146.715018 -391.118553) (xy 146.745706 -391.114827) (xy 146.776394 -391.118553) (xy 146.805298 -391.129515)
			(xy 146.830739 -391.147076) (xy 146.851238 -391.170214) (xy 146.865604 -391.197587) (xy 146.873002 -391.227601)
			(xy 146.873468 -391.243058) (xy 146.873468 -391.319258) (xy 147.81784 -391.319258) (xy 147.81784 -391.243058)
			(xy 147.818306 -391.227601) (xy 147.825704 -391.197587) (xy 147.84007 -391.170214) (xy 147.860569 -391.147076)
			(xy 147.88601 -391.129515) (xy 147.914914 -391.118553) (xy 147.945602 -391.114827) (xy 147.97629 -391.118553)
			(xy 148.005194 -391.129515) (xy 148.030635 -391.147076) (xy 148.051134 -391.170214) (xy 148.0655 -391.197587)
			(xy 148.072898 -391.227601) (xy 148.073364 -391.243058) (xy 148.073364 -391.319258) (xy 149.018244 -391.319258)
			(xy 149.018244 -391.243058) (xy 149.018709 -391.227632) (xy 149.026092 -391.197677) (xy 149.040429 -391.170359)
			(xy 149.060888 -391.147266) (xy 149.086278 -391.12974) (xy 149.115125 -391.1188) (xy 149.145752 -391.115082)
			(xy 149.176379 -391.1188) (xy 149.205226 -391.12974) (xy 149.230616 -391.147266) (xy 149.251075 -391.170359)
			(xy 149.265412 -391.197677) (xy 149.272795 -391.227632) (xy 149.27326 -391.243058) (xy 149.27326 -391.319258)
			(xy 150.21814 -391.319258) (xy 150.21814 -391.243058) (xy 150.218605 -391.227632) (xy 150.225988 -391.197677)
			(xy 150.240325 -391.170359) (xy 150.260784 -391.147266) (xy 150.286174 -391.12974) (xy 150.315021 -391.1188)
			(xy 150.345648 -391.115082) (xy 150.376275 -391.1188) (xy 150.405122 -391.12974) (xy 150.430512 -391.147266)
			(xy 150.450971 -391.170359) (xy 150.465308 -391.197677) (xy 150.472691 -391.227632) (xy 150.473156 -391.243058)
			(xy 150.473156 -391.319258) (xy 151.418036 -391.319258) (xy 151.418036 -391.243058) (xy 151.418502 -391.227601)
			(xy 151.4259 -391.197587) (xy 151.440266 -391.170214) (xy 151.460765 -391.147076) (xy 151.486206 -391.129515)
			(xy 151.51511 -391.118553) (xy 151.545798 -391.114827) (xy 151.576486 -391.118553) (xy 151.60539 -391.129515)
			(xy 151.630831 -391.147076) (xy 151.65133 -391.170214) (xy 151.665696 -391.197587) (xy 151.673094 -391.227601)
			(xy 151.67356 -391.243058) (xy 151.67356 -391.319258) (xy 152.617932 -391.319258) (xy 152.617932 -391.243058)
			(xy 152.618398 -391.227601) (xy 152.625796 -391.197587) (xy 152.640162 -391.170214) (xy 152.660661 -391.147076)
			(xy 152.686102 -391.129515) (xy 152.715006 -391.118553) (xy 152.745694 -391.114827) (xy 152.776382 -391.118553)
			(xy 152.805286 -391.129515) (xy 152.830727 -391.147076) (xy 152.851226 -391.170214) (xy 152.865592 -391.197587)
			(xy 152.87299 -391.227601) (xy 152.873456 -391.243058) (xy 152.873456 -391.319258) (xy 153.818336 -391.319258)
			(xy 153.818336 -391.243058) (xy 153.818801 -391.227632) (xy 153.826184 -391.197677) (xy 153.840521 -391.170359)
			(xy 153.86098 -391.147266) (xy 153.88637 -391.12974) (xy 153.915217 -391.1188) (xy 153.945844 -391.115082)
			(xy 153.976471 -391.1188) (xy 154.005318 -391.12974) (xy 154.030708 -391.147266) (xy 154.051167 -391.170359)
			(xy 154.065504 -391.197677) (xy 154.072887 -391.227632) (xy 154.073352 -391.243058) (xy 154.073352 -391.319258)
			(xy 155.018232 -391.319258) (xy 155.018232 -391.243058) (xy 155.018697 -391.227632) (xy 155.02608 -391.197677)
			(xy 155.040417 -391.170359) (xy 155.060876 -391.147266) (xy 155.086266 -391.12974) (xy 155.115113 -391.1188)
			(xy 155.14574 -391.115082) (xy 155.176367 -391.1188) (xy 155.205214 -391.12974) (xy 155.230604 -391.147266)
			(xy 155.251063 -391.170359) (xy 155.2654 -391.197677) (xy 155.272783 -391.227632) (xy 155.273248 -391.243058)
			(xy 155.273248 -391.319258) (xy 156.218128 -391.319258) (xy 156.218128 -391.243058) (xy 156.218593 -391.227632)
			(xy 156.225976 -391.197677) (xy 156.240313 -391.170359) (xy 156.260772 -391.147266) (xy 156.286162 -391.12974)
			(xy 156.315009 -391.1188) (xy 156.345636 -391.115082) (xy 156.376263 -391.1188) (xy 156.40511 -391.12974)
			(xy 156.4305 -391.147266) (xy 156.450959 -391.170359) (xy 156.465296 -391.197677) (xy 156.472679 -391.227632)
			(xy 156.473144 -391.243058) (xy 156.473144 -391.319258) (xy 157.418024 -391.319258) (xy 157.418024 -391.243058)
			(xy 157.41849 -391.227601) (xy 157.425888 -391.197587) (xy 157.440254 -391.170214) (xy 157.460753 -391.147076)
			(xy 157.486194 -391.129515) (xy 157.515098 -391.118553) (xy 157.545786 -391.114827) (xy 157.576474 -391.118553)
			(xy 157.605378 -391.129515) (xy 157.630819 -391.147076) (xy 157.651318 -391.170214) (xy 157.665684 -391.197587)
			(xy 157.673082 -391.227601) (xy 157.673548 -391.243058) (xy 157.673548 -391.319258) (xy 158.61792 -391.319258)
			(xy 158.61792 -391.243058) (xy 158.618386 -391.227601) (xy 158.625784 -391.197587) (xy 158.64015 -391.170214)
			(xy 158.660649 -391.147076) (xy 158.68609 -391.129515) (xy 158.714994 -391.118553) (xy 158.745682 -391.114827)
			(xy 158.77637 -391.118553) (xy 158.805274 -391.129515) (xy 158.830715 -391.147076) (xy 158.851214 -391.170214)
			(xy 158.86558 -391.197587) (xy 158.872978 -391.227601) (xy 158.873444 -391.243058) (xy 158.873444 -391.319258)
			(xy 159.818324 -391.319258) (xy 159.818324 -391.243058) (xy 159.818789 -391.227632) (xy 159.826172 -391.197677)
			(xy 159.840509 -391.170359) (xy 159.860968 -391.147266) (xy 159.886358 -391.12974) (xy 159.915205 -391.1188)
			(xy 159.945832 -391.115082) (xy 159.976459 -391.1188) (xy 160.005306 -391.12974) (xy 160.030696 -391.147266)
			(xy 160.051155 -391.170359) (xy 160.065492 -391.197677) (xy 160.072875 -391.227632) (xy 160.07334 -391.243058)
			(xy 160.07334 -391.319258) (xy 161.01822 -391.319258) (xy 161.01822 -391.243058) (xy 161.018685 -391.227632)
			(xy 161.026068 -391.197677) (xy 161.040405 -391.170359) (xy 161.060864 -391.147266) (xy 161.086254 -391.12974)
			(xy 161.115101 -391.1188) (xy 161.145728 -391.115082) (xy 161.176355 -391.1188) (xy 161.205202 -391.12974)
			(xy 161.230592 -391.147266) (xy 161.251051 -391.170359) (xy 161.265388 -391.197677) (xy 161.272771 -391.227632)
			(xy 161.273236 -391.243058) (xy 161.273236 -391.319258) (xy 162.218116 -391.319258) (xy 162.218116 -391.243058)
			(xy 162.218581 -391.227632) (xy 162.225964 -391.197677) (xy 162.240301 -391.170359) (xy 162.26076 -391.147266)
			(xy 162.28615 -391.12974) (xy 162.314997 -391.1188) (xy 162.345624 -391.115082) (xy 162.376251 -391.1188)
			(xy 162.405098 -391.12974) (xy 162.430488 -391.147266) (xy 162.450947 -391.170359) (xy 162.465284 -391.197677)
			(xy 162.472667 -391.227632) (xy 162.473132 -391.243058) (xy 162.473132 -391.319258) (xy 163.418012 -391.319258)
			(xy 163.418012 -391.243058) (xy 163.418478 -391.227601) (xy 163.425876 -391.197587) (xy 163.440242 -391.170214)
			(xy 163.460741 -391.147076) (xy 163.486182 -391.129515) (xy 163.515086 -391.118553) (xy 163.545774 -391.114827)
			(xy 163.576462 -391.118553) (xy 163.605366 -391.129515) (xy 163.630807 -391.147076) (xy 163.651306 -391.170214)
			(xy 163.665672 -391.197587) (xy 163.67307 -391.227601) (xy 163.673536 -391.243058) (xy 163.673536 -391.319258)
			(xy 164.617908 -391.319258) (xy 164.617908 -391.243058) (xy 164.618374 -391.227601) (xy 164.625772 -391.197587)
			(xy 164.640138 -391.170214) (xy 164.660637 -391.147076) (xy 164.686078 -391.129515) (xy 164.714982 -391.118553)
			(xy 164.74567 -391.114827) (xy 164.776358 -391.118553) (xy 164.805262 -391.129515) (xy 164.830703 -391.147076)
			(xy 164.851202 -391.170214) (xy 164.865568 -391.197587) (xy 164.872966 -391.227601) (xy 164.873432 -391.243058)
			(xy 164.873432 -391.319258) (xy 164.872966 -391.334715) (xy 164.865568 -391.364729) (xy 164.851202 -391.392102)
			(xy 164.830703 -391.41524) (xy 164.805262 -391.432801) (xy 164.776358 -391.443763) (xy 164.74567 -391.447489)
			(xy 164.714982 -391.443763) (xy 164.686078 -391.432801) (xy 164.660637 -391.41524) (xy 164.640138 -391.392102)
			(xy 164.625772 -391.364729) (xy 164.618374 -391.334715) (xy 164.617908 -391.319258) (xy 163.673536 -391.319258)
			(xy 163.67307 -391.334715) (xy 163.665672 -391.364729) (xy 163.651306 -391.392102) (xy 163.630807 -391.41524)
			(xy 163.605366 -391.432801) (xy 163.576462 -391.443763) (xy 163.545774 -391.447489) (xy 163.515086 -391.443763)
			(xy 163.486182 -391.432801) (xy 163.460741 -391.41524) (xy 163.440242 -391.392102) (xy 163.425876 -391.364729)
			(xy 163.418478 -391.334715) (xy 163.418012 -391.319258) (xy 162.473132 -391.319258) (xy 162.472667 -391.334684)
			(xy 162.465284 -391.364639) (xy 162.450947 -391.391957) (xy 162.430488 -391.41505) (xy 162.405098 -391.432576)
			(xy 162.376251 -391.443516) (xy 162.345624 -391.447235) (xy 162.314997 -391.443516) (xy 162.28615 -391.432576)
			(xy 162.26076 -391.41505) (xy 162.240301 -391.391957) (xy 162.225964 -391.364639) (xy 162.218581 -391.334684)
			(xy 162.218116 -391.319258) (xy 161.273236 -391.319258) (xy 161.272771 -391.334684) (xy 161.265388 -391.364639)
			(xy 161.251051 -391.391957) (xy 161.230592 -391.41505) (xy 161.205202 -391.432576) (xy 161.176355 -391.443516)
			(xy 161.145728 -391.447235) (xy 161.115101 -391.443516) (xy 161.086254 -391.432576) (xy 161.060864 -391.41505)
			(xy 161.040405 -391.391957) (xy 161.026068 -391.364639) (xy 161.018685 -391.334684) (xy 161.01822 -391.319258)
			(xy 160.07334 -391.319258) (xy 160.072875 -391.334684) (xy 160.065492 -391.364639) (xy 160.051155 -391.391957)
			(xy 160.030696 -391.41505) (xy 160.005306 -391.432576) (xy 159.976459 -391.443516) (xy 159.945832 -391.447235)
			(xy 159.915205 -391.443516) (xy 159.886358 -391.432576) (xy 159.860968 -391.41505) (xy 159.840509 -391.391957)
			(xy 159.826172 -391.364639) (xy 159.818789 -391.334684) (xy 159.818324 -391.319258) (xy 158.873444 -391.319258)
			(xy 158.872978 -391.334715) (xy 158.86558 -391.364729) (xy 158.851214 -391.392102) (xy 158.830715 -391.41524)
			(xy 158.805274 -391.432801) (xy 158.77637 -391.443763) (xy 158.745682 -391.447489) (xy 158.714994 -391.443763)
			(xy 158.68609 -391.432801) (xy 158.660649 -391.41524) (xy 158.64015 -391.392102) (xy 158.625784 -391.364729)
			(xy 158.618386 -391.334715) (xy 158.61792 -391.319258) (xy 157.673548 -391.319258) (xy 157.673082 -391.334715)
			(xy 157.665684 -391.364729) (xy 157.651318 -391.392102) (xy 157.630819 -391.41524) (xy 157.605378 -391.432801)
			(xy 157.576474 -391.443763) (xy 157.545786 -391.447489) (xy 157.515098 -391.443763) (xy 157.486194 -391.432801)
			(xy 157.460753 -391.41524) (xy 157.440254 -391.392102) (xy 157.425888 -391.364729) (xy 157.41849 -391.334715)
			(xy 157.418024 -391.319258) (xy 156.473144 -391.319258) (xy 156.472679 -391.334684) (xy 156.465296 -391.364639)
			(xy 156.450959 -391.391957) (xy 156.4305 -391.41505) (xy 156.40511 -391.432576) (xy 156.376263 -391.443516)
			(xy 156.345636 -391.447235) (xy 156.315009 -391.443516) (xy 156.286162 -391.432576) (xy 156.260772 -391.41505)
			(xy 156.240313 -391.391957) (xy 156.225976 -391.364639) (xy 156.218593 -391.334684) (xy 156.218128 -391.319258)
			(xy 155.273248 -391.319258) (xy 155.272783 -391.334684) (xy 155.2654 -391.364639) (xy 155.251063 -391.391957)
			(xy 155.230604 -391.41505) (xy 155.205214 -391.432576) (xy 155.176367 -391.443516) (xy 155.14574 -391.447235)
			(xy 155.115113 -391.443516) (xy 155.086266 -391.432576) (xy 155.060876 -391.41505) (xy 155.040417 -391.391957)
			(xy 155.02608 -391.364639) (xy 155.018697 -391.334684) (xy 155.018232 -391.319258) (xy 154.073352 -391.319258)
			(xy 154.072887 -391.334684) (xy 154.065504 -391.364639) (xy 154.051167 -391.391957) (xy 154.030708 -391.41505)
			(xy 154.005318 -391.432576) (xy 153.976471 -391.443516) (xy 153.945844 -391.447235) (xy 153.915217 -391.443516)
			(xy 153.88637 -391.432576) (xy 153.86098 -391.41505) (xy 153.840521 -391.391957) (xy 153.826184 -391.364639)
			(xy 153.818801 -391.334684) (xy 153.818336 -391.319258) (xy 152.873456 -391.319258) (xy 152.87299 -391.334715)
			(xy 152.865592 -391.364729) (xy 152.851226 -391.392102) (xy 152.830727 -391.41524) (xy 152.805286 -391.432801)
			(xy 152.776382 -391.443763) (xy 152.745694 -391.447489) (xy 152.715006 -391.443763) (xy 152.686102 -391.432801)
			(xy 152.660661 -391.41524) (xy 152.640162 -391.392102) (xy 152.625796 -391.364729) (xy 152.618398 -391.334715)
			(xy 152.617932 -391.319258) (xy 151.67356 -391.319258) (xy 151.673094 -391.334715) (xy 151.665696 -391.364729)
			(xy 151.65133 -391.392102) (xy 151.630831 -391.41524) (xy 151.60539 -391.432801) (xy 151.576486 -391.443763)
			(xy 151.545798 -391.447489) (xy 151.51511 -391.443763) (xy 151.486206 -391.432801) (xy 151.460765 -391.41524)
			(xy 151.440266 -391.392102) (xy 151.4259 -391.364729) (xy 151.418502 -391.334715) (xy 151.418036 -391.319258)
			(xy 150.473156 -391.319258) (xy 150.472691 -391.334684) (xy 150.465308 -391.364639) (xy 150.450971 -391.391957)
			(xy 150.430512 -391.41505) (xy 150.405122 -391.432576) (xy 150.376275 -391.443516) (xy 150.345648 -391.447235)
			(xy 150.315021 -391.443516) (xy 150.286174 -391.432576) (xy 150.260784 -391.41505) (xy 150.240325 -391.391957)
			(xy 150.225988 -391.364639) (xy 150.218605 -391.334684) (xy 150.21814 -391.319258) (xy 149.27326 -391.319258)
			(xy 149.272795 -391.334684) (xy 149.265412 -391.364639) (xy 149.251075 -391.391957) (xy 149.230616 -391.41505)
			(xy 149.205226 -391.432576) (xy 149.176379 -391.443516) (xy 149.145752 -391.447235) (xy 149.115125 -391.443516)
			(xy 149.086278 -391.432576) (xy 149.060888 -391.41505) (xy 149.040429 -391.391957) (xy 149.026092 -391.364639)
			(xy 149.018709 -391.334684) (xy 149.018244 -391.319258) (xy 148.073364 -391.319258) (xy 148.072898 -391.334715)
			(xy 148.0655 -391.364729) (xy 148.051134 -391.392102) (xy 148.030635 -391.41524) (xy 148.005194 -391.432801)
			(xy 147.97629 -391.443763) (xy 147.945602 -391.447489) (xy 147.914914 -391.443763) (xy 147.88601 -391.432801)
			(xy 147.860569 -391.41524) (xy 147.84007 -391.392102) (xy 147.825704 -391.364729) (xy 147.818306 -391.334715)
			(xy 147.81784 -391.319258) (xy 146.873468 -391.319258) (xy 146.873002 -391.334715) (xy 146.865604 -391.364729)
			(xy 146.851238 -391.392102) (xy 146.830739 -391.41524) (xy 146.805298 -391.432801) (xy 146.776394 -391.443763)
			(xy 146.745706 -391.447489) (xy 146.715018 -391.443763) (xy 146.686114 -391.432801) (xy 146.660673 -391.41524)
			(xy 146.640174 -391.392102) (xy 146.625808 -391.364729) (xy 146.61841 -391.334715) (xy 146.617944 -391.319258)
			(xy 132.345684 -391.319258) (xy 132.345218 -391.334715) (xy 132.33782 -391.364729) (xy 132.323454 -391.392102)
			(xy 132.302955 -391.41524) (xy 132.277514 -391.432801) (xy 132.24861 -391.443763) (xy 132.217922 -391.447489)
			(xy 132.187234 -391.443763) (xy 132.15833 -391.432801) (xy 132.132889 -391.41524) (xy 132.11239 -391.392102)
			(xy 132.098024 -391.364729) (xy 132.090626 -391.334715) (xy 132.09016 -391.319258) (xy 131.145788 -391.319258)
			(xy 131.145322 -391.334715) (xy 131.137924 -391.364729) (xy 131.123558 -391.392102) (xy 131.103059 -391.41524)
			(xy 131.077618 -391.432801) (xy 131.048714 -391.443763) (xy 131.018026 -391.447489) (xy 130.987338 -391.443763)
			(xy 130.958434 -391.432801) (xy 130.932993 -391.41524) (xy 130.912494 -391.392102) (xy 130.898128 -391.364729)
			(xy 130.89073 -391.334715) (xy 130.890264 -391.319258) (xy 129.945384 -391.319258) (xy 129.944919 -391.334684)
			(xy 129.937536 -391.364639) (xy 129.923199 -391.391957) (xy 129.90274 -391.41505) (xy 129.87735 -391.432576)
			(xy 129.848503 -391.443516) (xy 129.817876 -391.447235) (xy 129.787249 -391.443516) (xy 129.758402 -391.432576)
			(xy 129.733012 -391.41505) (xy 129.712553 -391.391957) (xy 129.698216 -391.364639) (xy 129.690833 -391.334684)
			(xy 129.690368 -391.319258) (xy 128.745488 -391.319258) (xy 128.745023 -391.334684) (xy 128.73764 -391.364639)
			(xy 128.723303 -391.391957) (xy 128.702844 -391.41505) (xy 128.677454 -391.432576) (xy 128.648607 -391.443516)
			(xy 128.61798 -391.447235) (xy 128.587353 -391.443516) (xy 128.558506 -391.432576) (xy 128.533116 -391.41505)
			(xy 128.512657 -391.391957) (xy 128.49832 -391.364639) (xy 128.490937 -391.334684) (xy 128.490472 -391.319258)
			(xy 127.545592 -391.319258) (xy 127.545127 -391.334684) (xy 127.537744 -391.364639) (xy 127.523407 -391.391957)
			(xy 127.502948 -391.41505) (xy 127.477558 -391.432576) (xy 127.448711 -391.443516) (xy 127.418084 -391.447235)
			(xy 127.387457 -391.443516) (xy 127.35861 -391.432576) (xy 127.33322 -391.41505) (xy 127.312761 -391.391957)
			(xy 127.298424 -391.364639) (xy 127.291041 -391.334684) (xy 127.290576 -391.319258) (xy 126.345696 -391.319258)
			(xy 126.34523 -391.334715) (xy 126.337832 -391.364729) (xy 126.323466 -391.392102) (xy 126.302967 -391.41524)
			(xy 126.277526 -391.432801) (xy 126.248622 -391.443763) (xy 126.217934 -391.447489) (xy 126.187246 -391.443763)
			(xy 126.158342 -391.432801) (xy 126.132901 -391.41524) (xy 126.112402 -391.392102) (xy 126.098036 -391.364729)
			(xy 126.090638 -391.334715) (xy 126.090172 -391.319258) (xy 125.1458 -391.319258) (xy 125.145334 -391.334715)
			(xy 125.137936 -391.364729) (xy 125.12357 -391.392102) (xy 125.103071 -391.41524) (xy 125.07763 -391.432801)
			(xy 125.048726 -391.443763) (xy 125.018038 -391.447489) (xy 124.98735 -391.443763) (xy 124.958446 -391.432801)
			(xy 124.933005 -391.41524) (xy 124.912506 -391.392102) (xy 124.89814 -391.364729) (xy 124.890742 -391.334715)
			(xy 124.890276 -391.319258) (xy 123.945396 -391.319258) (xy 123.944931 -391.334684) (xy 123.937548 -391.364639)
			(xy 123.923211 -391.391957) (xy 123.902752 -391.41505) (xy 123.877362 -391.432576) (xy 123.848515 -391.443516)
			(xy 123.817888 -391.447235) (xy 123.787261 -391.443516) (xy 123.758414 -391.432576) (xy 123.733024 -391.41505)
			(xy 123.712565 -391.391957) (xy 123.698228 -391.364639) (xy 123.690845 -391.334684) (xy 123.69038 -391.319258)
			(xy 122.7455 -391.319258) (xy 122.745035 -391.334684) (xy 122.737652 -391.364639) (xy 122.723315 -391.391957)
			(xy 122.702856 -391.41505) (xy 122.677466 -391.432576) (xy 122.648619 -391.443516) (xy 122.617992 -391.447235)
			(xy 122.587365 -391.443516) (xy 122.558518 -391.432576) (xy 122.533128 -391.41505) (xy 122.512669 -391.391957)
			(xy 122.498332 -391.364639) (xy 122.490949 -391.334684) (xy 122.490484 -391.319258) (xy 121.545604 -391.319258)
			(xy 121.545139 -391.334684) (xy 121.537756 -391.364639) (xy 121.523419 -391.391957) (xy 121.50296 -391.41505)
			(xy 121.47757 -391.432576) (xy 121.448723 -391.443516) (xy 121.418096 -391.447235) (xy 121.387469 -391.443516)
			(xy 121.358622 -391.432576) (xy 121.333232 -391.41505) (xy 121.312773 -391.391957) (xy 121.298436 -391.364639)
			(xy 121.291053 -391.334684) (xy 121.290588 -391.319258) (xy 120.345708 -391.319258) (xy 120.345242 -391.334715)
			(xy 120.337844 -391.364729) (xy 120.323478 -391.392102) (xy 120.302979 -391.41524) (xy 120.277538 -391.432801)
			(xy 120.248634 -391.443763) (xy 120.217946 -391.447489) (xy 120.187258 -391.443763) (xy 120.158354 -391.432801)
			(xy 120.132913 -391.41524) (xy 120.112414 -391.392102) (xy 120.098048 -391.364729) (xy 120.09065 -391.334715)
			(xy 120.090184 -391.319258) (xy 119.145812 -391.319258) (xy 119.145346 -391.334715) (xy 119.137948 -391.364729)
			(xy 119.123582 -391.392102) (xy 119.103083 -391.41524) (xy 119.077642 -391.432801) (xy 119.048738 -391.443763)
			(xy 119.01805 -391.447489) (xy 118.987362 -391.443763) (xy 118.958458 -391.432801) (xy 118.933017 -391.41524)
			(xy 118.912518 -391.392102) (xy 118.898152 -391.364729) (xy 118.890754 -391.334715) (xy 118.890288 -391.319258)
			(xy 117.945408 -391.319258) (xy 117.944943 -391.334684) (xy 117.93756 -391.364639) (xy 117.923223 -391.391957)
			(xy 117.902764 -391.41505) (xy 117.877374 -391.432576) (xy 117.848527 -391.443516) (xy 117.8179 -391.447235)
			(xy 117.787273 -391.443516) (xy 117.758426 -391.432576) (xy 117.733036 -391.41505) (xy 117.712577 -391.391957)
			(xy 117.69824 -391.364639) (xy 117.690857 -391.334684) (xy 117.690392 -391.319258) (xy 116.745512 -391.319258)
			(xy 116.745047 -391.334684) (xy 116.737664 -391.364639) (xy 116.723327 -391.391957) (xy 116.702868 -391.41505)
			(xy 116.677478 -391.432576) (xy 116.648631 -391.443516) (xy 116.618004 -391.447235) (xy 116.587377 -391.443516)
			(xy 116.55853 -391.432576) (xy 116.53314 -391.41505) (xy 116.512681 -391.391957) (xy 116.498344 -391.364639)
			(xy 116.490961 -391.334684) (xy 116.490496 -391.319258) (xy 115.545616 -391.319258) (xy 115.54515 -391.334715)
			(xy 115.537752 -391.364729) (xy 115.523386 -391.392102) (xy 115.502887 -391.41524) (xy 115.477446 -391.432801)
			(xy 115.448542 -391.443763) (xy 115.417854 -391.447489) (xy 115.387166 -391.443763) (xy 115.358262 -391.432801)
			(xy 115.332821 -391.41524) (xy 115.312322 -391.392102) (xy 115.297956 -391.364729) (xy 115.290558 -391.334715)
			(xy 115.290092 -391.319258) (xy 114.34572 -391.319258) (xy 114.345254 -391.334715) (xy 114.337856 -391.364729)
			(xy 114.32349 -391.392102) (xy 114.302991 -391.41524) (xy 114.27755 -391.432801) (xy 114.248646 -391.443763)
			(xy 114.217958 -391.447489) (xy 114.18727 -391.443763) (xy 114.158366 -391.432801) (xy 114.132925 -391.41524)
			(xy 114.112426 -391.392102) (xy 114.09806 -391.364729) (xy 114.090662 -391.334715) (xy 114.090196 -391.319258)
			(xy 97.773236 -391.319258) (xy 97.772771 -391.334684) (xy 97.765388 -391.364639) (xy 97.751051 -391.391957)
			(xy 97.730592 -391.41505) (xy 97.705202 -391.432576) (xy 97.676355 -391.443516) (xy 97.645728 -391.447235)
			(xy 97.615101 -391.443516) (xy 97.586254 -391.432576) (xy 97.560864 -391.41505) (xy 97.540405 -391.391957)
			(xy 97.526068 -391.364639) (xy 97.518685 -391.334684) (xy 97.51822 -391.319258) (xy 96.57334 -391.319258)
			(xy 96.572875 -391.334684) (xy 96.565492 -391.364639) (xy 96.551155 -391.391957) (xy 96.530696 -391.41505)
			(xy 96.505306 -391.432576) (xy 96.476459 -391.443516) (xy 96.445832 -391.447235) (xy 96.415205 -391.443516)
			(xy 96.386358 -391.432576) (xy 96.360968 -391.41505) (xy 96.340509 -391.391957) (xy 96.326172 -391.364639)
			(xy 96.318789 -391.334684) (xy 96.318324 -391.319258) (xy 95.373444 -391.319258) (xy 95.372978 -391.334715)
			(xy 95.36558 -391.364729) (xy 95.351214 -391.392102) (xy 95.330715 -391.41524) (xy 95.305274 -391.432801)
			(xy 95.27637 -391.443763) (xy 95.245682 -391.447489) (xy 95.214994 -391.443763) (xy 95.18609 -391.432801)
			(xy 95.160649 -391.41524) (xy 95.14015 -391.392102) (xy 95.125784 -391.364729) (xy 95.118386 -391.334715)
			(xy 95.11792 -391.319258) (xy 94.173548 -391.319258) (xy 94.173082 -391.334715) (xy 94.165684 -391.364729)
			(xy 94.151318 -391.392102) (xy 94.130819 -391.41524) (xy 94.105378 -391.432801) (xy 94.076474 -391.443763)
			(xy 94.045786 -391.447489) (xy 94.015098 -391.443763) (xy 93.986194 -391.432801) (xy 93.960753 -391.41524)
			(xy 93.940254 -391.392102) (xy 93.925888 -391.364729) (xy 93.91849 -391.334715) (xy 93.918024 -391.319258)
			(xy 92.973652 -391.319258) (xy 92.973186 -391.334715) (xy 92.965788 -391.364729) (xy 92.951422 -391.392102)
			(xy 92.930923 -391.41524) (xy 92.905482 -391.432801) (xy 92.876578 -391.443763) (xy 92.84589 -391.447489)
			(xy 92.815202 -391.443763) (xy 92.786298 -391.432801) (xy 92.760857 -391.41524) (xy 92.740358 -391.392102)
			(xy 92.725992 -391.364729) (xy 92.718594 -391.334715) (xy 92.718128 -391.319258) (xy 91.773248 -391.319258)
			(xy 91.772783 -391.334684) (xy 91.7654 -391.364639) (xy 91.751063 -391.391957) (xy 91.730604 -391.41505)
			(xy 91.705214 -391.432576) (xy 91.676367 -391.443516) (xy 91.64574 -391.447235) (xy 91.615113 -391.443516)
			(xy 91.586266 -391.432576) (xy 91.560876 -391.41505) (xy 91.540417 -391.391957) (xy 91.52608 -391.364639)
			(xy 91.518697 -391.334684) (xy 91.518232 -391.319258) (xy 90.573352 -391.319258) (xy 90.572887 -391.334684)
			(xy 90.565504 -391.364639) (xy 90.551167 -391.391957) (xy 90.530708 -391.41505) (xy 90.505318 -391.432576)
			(xy 90.476471 -391.443516) (xy 90.445844 -391.447235) (xy 90.415217 -391.443516) (xy 90.38637 -391.432576)
			(xy 90.36098 -391.41505) (xy 90.340521 -391.391957) (xy 90.326184 -391.364639) (xy 90.318801 -391.334684)
			(xy 90.318336 -391.319258) (xy 89.373456 -391.319258) (xy 89.37299 -391.334715) (xy 89.365592 -391.364729)
			(xy 89.351226 -391.392102) (xy 89.330727 -391.41524) (xy 89.305286 -391.432801) (xy 89.276382 -391.443763)
			(xy 89.245694 -391.447489) (xy 89.215006 -391.443763) (xy 89.186102 -391.432801) (xy 89.160661 -391.41524)
			(xy 89.140162 -391.392102) (xy 89.125796 -391.364729) (xy 89.118398 -391.334715) (xy 89.117932 -391.319258)
			(xy 88.17356 -391.319258) (xy 88.173094 -391.334715) (xy 88.165696 -391.364729) (xy 88.15133 -391.392102)
			(xy 88.130831 -391.41524) (xy 88.10539 -391.432801) (xy 88.076486 -391.443763) (xy 88.045798 -391.447489)
			(xy 88.01511 -391.443763) (xy 87.986206 -391.432801) (xy 87.960765 -391.41524) (xy 87.940266 -391.392102)
			(xy 87.9259 -391.364729) (xy 87.918502 -391.334715) (xy 87.918036 -391.319258) (xy 86.973664 -391.319258)
			(xy 86.973198 -391.334715) (xy 86.9658 -391.364729) (xy 86.951434 -391.392102) (xy 86.930935 -391.41524)
			(xy 86.905494 -391.432801) (xy 86.87659 -391.443763) (xy 86.845902 -391.447489) (xy 86.815214 -391.443763)
			(xy 86.78631 -391.432801) (xy 86.760869 -391.41524) (xy 86.74037 -391.392102) (xy 86.726004 -391.364729)
			(xy 86.718606 -391.334715) (xy 86.71814 -391.319258) (xy 85.77326 -391.319258) (xy 85.772795 -391.334684)
			(xy 85.765412 -391.364639) (xy 85.751075 -391.391957) (xy 85.730616 -391.41505) (xy 85.705226 -391.432576)
			(xy 85.676379 -391.443516) (xy 85.645752 -391.447235) (xy 85.615125 -391.443516) (xy 85.586278 -391.432576)
			(xy 85.560888 -391.41505) (xy 85.540429 -391.391957) (xy 85.526092 -391.364639) (xy 85.518709 -391.334684)
			(xy 85.518244 -391.319258) (xy 84.573364 -391.319258) (xy 84.572899 -391.334684) (xy 84.565516 -391.364639)
			(xy 84.551179 -391.391957) (xy 84.53072 -391.41505) (xy 84.50533 -391.432576) (xy 84.476483 -391.443516)
			(xy 84.445856 -391.447235) (xy 84.415229 -391.443516) (xy 84.386382 -391.432576) (xy 84.360992 -391.41505)
			(xy 84.340533 -391.391957) (xy 84.326196 -391.364639) (xy 84.318813 -391.334684) (xy 84.318348 -391.319258)
			(xy 83.373468 -391.319258) (xy 83.373002 -391.334715) (xy 83.365604 -391.364729) (xy 83.351238 -391.392102)
			(xy 83.330739 -391.41524) (xy 83.305298 -391.432801) (xy 83.276394 -391.443763) (xy 83.245706 -391.447489)
			(xy 83.215018 -391.443763) (xy 83.186114 -391.432801) (xy 83.160673 -391.41524) (xy 83.140174 -391.392102)
			(xy 83.125808 -391.364729) (xy 83.11841 -391.334715) (xy 83.117944 -391.319258) (xy 82.173572 -391.319258)
			(xy 82.173106 -391.334715) (xy 82.165708 -391.364729) (xy 82.151342 -391.392102) (xy 82.130843 -391.41524)
			(xy 82.105402 -391.432801) (xy 82.076498 -391.443763) (xy 82.04581 -391.447489) (xy 82.015122 -391.443763)
			(xy 81.986218 -391.432801) (xy 81.960777 -391.41524) (xy 81.940278 -391.392102) (xy 81.925912 -391.364729)
			(xy 81.918514 -391.334715) (xy 81.918048 -391.319258) (xy 80.973168 -391.319258) (xy 80.972703 -391.334684)
			(xy 80.96532 -391.364639) (xy 80.950983 -391.391957) (xy 80.930524 -391.41505) (xy 80.905134 -391.432576)
			(xy 80.876287 -391.443516) (xy 80.84566 -391.447235) (xy 80.815033 -391.443516) (xy 80.786186 -391.432576)
			(xy 80.760796 -391.41505) (xy 80.740337 -391.391957) (xy 80.726 -391.364639) (xy 80.718617 -391.334684)
			(xy 80.718152 -391.319258) (xy 79.773272 -391.319258) (xy 79.772807 -391.334684) (xy 79.765424 -391.364639)
			(xy 79.751087 -391.391957) (xy 79.730628 -391.41505) (xy 79.705238 -391.432576) (xy 79.676391 -391.443516)
			(xy 79.645764 -391.447235) (xy 79.615137 -391.443516) (xy 79.58629 -391.432576) (xy 79.5609 -391.41505)
			(xy 79.540441 -391.391957) (xy 79.526104 -391.364639) (xy 79.518721 -391.334684) (xy 79.518256 -391.319258)
			(xy 65.245488 -391.319258) (xy 65.245023 -391.334684) (xy 65.23764 -391.364639) (xy 65.223303 -391.391957)
			(xy 65.202844 -391.41505) (xy 65.177454 -391.432576) (xy 65.148607 -391.443516) (xy 65.11798 -391.447235)
			(xy 65.087353 -391.443516) (xy 65.058506 -391.432576) (xy 65.033116 -391.41505) (xy 65.012657 -391.391957)
			(xy 64.99832 -391.364639) (xy 64.990937 -391.334684) (xy 64.990472 -391.319258) (xy 64.045592 -391.319258)
			(xy 64.045127 -391.334684) (xy 64.037744 -391.364639) (xy 64.023407 -391.391957) (xy 64.002948 -391.41505)
			(xy 63.977558 -391.432576) (xy 63.948711 -391.443516) (xy 63.918084 -391.447235) (xy 63.887457 -391.443516)
			(xy 63.85861 -391.432576) (xy 63.83322 -391.41505) (xy 63.812761 -391.391957) (xy 63.798424 -391.364639)
			(xy 63.791041 -391.334684) (xy 63.790576 -391.319258) (xy 62.845696 -391.319258) (xy 62.84523 -391.334715)
			(xy 62.837832 -391.364729) (xy 62.823466 -391.392102) (xy 62.802967 -391.41524) (xy 62.777526 -391.432801)
			(xy 62.748622 -391.443763) (xy 62.717934 -391.447489) (xy 62.687246 -391.443763) (xy 62.658342 -391.432801)
			(xy 62.632901 -391.41524) (xy 62.612402 -391.392102) (xy 62.598036 -391.364729) (xy 62.590638 -391.334715)
			(xy 62.590172 -391.319258) (xy 61.6458 -391.319258) (xy 61.645334 -391.334715) (xy 61.637936 -391.364729)
			(xy 61.62357 -391.392102) (xy 61.603071 -391.41524) (xy 61.57763 -391.432801) (xy 61.548726 -391.443763)
			(xy 61.518038 -391.447489) (xy 61.48735 -391.443763) (xy 61.458446 -391.432801) (xy 61.433005 -391.41524)
			(xy 61.412506 -391.392102) (xy 61.39814 -391.364729) (xy 61.390742 -391.334715) (xy 61.390276 -391.319258)
			(xy 60.445904 -391.319258) (xy 60.445438 -391.334715) (xy 60.43804 -391.364729) (xy 60.423674 -391.392102)
			(xy 60.403175 -391.41524) (xy 60.377734 -391.432801) (xy 60.34883 -391.443763) (xy 60.318142 -391.447489)
			(xy 60.287454 -391.443763) (xy 60.25855 -391.432801) (xy 60.233109 -391.41524) (xy 60.21261 -391.392102)
			(xy 60.198244 -391.364729) (xy 60.190846 -391.334715) (xy 60.19038 -391.319258) (xy 59.2455 -391.319258)
			(xy 59.245035 -391.334684) (xy 59.237652 -391.364639) (xy 59.223315 -391.391957) (xy 59.202856 -391.41505)
			(xy 59.177466 -391.432576) (xy 59.148619 -391.443516) (xy 59.117992 -391.447235) (xy 59.087365 -391.443516)
			(xy 59.058518 -391.432576) (xy 59.033128 -391.41505) (xy 59.012669 -391.391957) (xy 58.998332 -391.364639)
			(xy 58.990949 -391.334684) (xy 58.990484 -391.319258) (xy 58.045604 -391.319258) (xy 58.045139 -391.334684)
			(xy 58.037756 -391.364639) (xy 58.023419 -391.391957) (xy 58.00296 -391.41505) (xy 57.97757 -391.432576)
			(xy 57.948723 -391.443516) (xy 57.918096 -391.447235) (xy 57.887469 -391.443516) (xy 57.858622 -391.432576)
			(xy 57.833232 -391.41505) (xy 57.812773 -391.391957) (xy 57.798436 -391.364639) (xy 57.791053 -391.334684)
			(xy 57.790588 -391.319258) (xy 56.845708 -391.319258) (xy 56.845242 -391.334715) (xy 56.837844 -391.364729)
			(xy 56.823478 -391.392102) (xy 56.802979 -391.41524) (xy 56.777538 -391.432801) (xy 56.748634 -391.443763)
			(xy 56.717946 -391.447489) (xy 56.687258 -391.443763) (xy 56.658354 -391.432801) (xy 56.632913 -391.41524)
			(xy 56.612414 -391.392102) (xy 56.598048 -391.364729) (xy 56.59065 -391.334715) (xy 56.590184 -391.319258)
			(xy 55.645812 -391.319258) (xy 55.645346 -391.334715) (xy 55.637948 -391.364729) (xy 55.623582 -391.392102)
			(xy 55.603083 -391.41524) (xy 55.577642 -391.432801) (xy 55.548738 -391.443763) (xy 55.51805 -391.447489)
			(xy 55.487362 -391.443763) (xy 55.458458 -391.432801) (xy 55.433017 -391.41524) (xy 55.412518 -391.392102)
			(xy 55.398152 -391.364729) (xy 55.390754 -391.334715) (xy 55.390288 -391.319258) (xy 54.445916 -391.319258)
			(xy 54.44545 -391.334715) (xy 54.438052 -391.364729) (xy 54.423686 -391.392102) (xy 54.403187 -391.41524)
			(xy 54.377746 -391.432801) (xy 54.348842 -391.443763) (xy 54.318154 -391.447489) (xy 54.287466 -391.443763)
			(xy 54.258562 -391.432801) (xy 54.233121 -391.41524) (xy 54.212622 -391.392102) (xy 54.198256 -391.364729)
			(xy 54.190858 -391.334715) (xy 54.190392 -391.319258) (xy 53.245512 -391.319258) (xy 53.245047 -391.334684)
			(xy 53.237664 -391.364639) (xy 53.223327 -391.391957) (xy 53.202868 -391.41505) (xy 53.177478 -391.432576)
			(xy 53.148631 -391.443516) (xy 53.118004 -391.447235) (xy 53.087377 -391.443516) (xy 53.05853 -391.432576)
			(xy 53.03314 -391.41505) (xy 53.012681 -391.391957) (xy 52.998344 -391.364639) (xy 52.990961 -391.334684)
			(xy 52.990496 -391.319258) (xy 52.045616 -391.319258) (xy 52.045151 -391.334684) (xy 52.037768 -391.364639)
			(xy 52.023431 -391.391957) (xy 52.002972 -391.41505) (xy 51.977582 -391.432576) (xy 51.948735 -391.443516)
			(xy 51.918108 -391.447235) (xy 51.887481 -391.443516) (xy 51.858634 -391.432576) (xy 51.833244 -391.41505)
			(xy 51.812785 -391.391957) (xy 51.798448 -391.364639) (xy 51.791065 -391.334684) (xy 51.7906 -391.319258)
			(xy 50.84572 -391.319258) (xy 50.845254 -391.334715) (xy 50.837856 -391.364729) (xy 50.82349 -391.392102)
			(xy 50.802991 -391.41524) (xy 50.77755 -391.432801) (xy 50.748646 -391.443763) (xy 50.717958 -391.447489)
			(xy 50.68727 -391.443763) (xy 50.658366 -391.432801) (xy 50.632925 -391.41524) (xy 50.612426 -391.392102)
			(xy 50.59806 -391.364729) (xy 50.590662 -391.334715) (xy 50.590196 -391.319258) (xy 49.645824 -391.319258)
			(xy 49.645358 -391.334715) (xy 49.63796 -391.364729) (xy 49.623594 -391.392102) (xy 49.603095 -391.41524)
			(xy 49.577654 -391.432801) (xy 49.54875 -391.443763) (xy 49.518062 -391.447489) (xy 49.487374 -391.443763)
			(xy 49.45847 -391.432801) (xy 49.433029 -391.41524) (xy 49.41253 -391.392102) (xy 49.398164 -391.364729)
			(xy 49.390766 -391.334715) (xy 49.3903 -391.319258) (xy 48.44542 -391.319258) (xy 48.444955 -391.334684)
			(xy 48.437572 -391.364639) (xy 48.423235 -391.391957) (xy 48.402776 -391.41505) (xy 48.377386 -391.432576)
			(xy 48.348539 -391.443516) (xy 48.317912 -391.447235) (xy 48.287285 -391.443516) (xy 48.258438 -391.432576)
			(xy 48.233048 -391.41505) (xy 48.212589 -391.391957) (xy 48.198252 -391.364639) (xy 48.190869 -391.334684)
			(xy 48.190404 -391.319258) (xy 47.245524 -391.319258) (xy 47.245059 -391.334684) (xy 47.237676 -391.364639)
			(xy 47.223339 -391.391957) (xy 47.20288 -391.41505) (xy 47.17749 -391.432576) (xy 47.148643 -391.443516)
			(xy 47.118016 -391.447235) (xy 47.087389 -391.443516) (xy 47.058542 -391.432576) (xy 47.033152 -391.41505)
			(xy 47.012693 -391.391957) (xy 46.998356 -391.364639) (xy 46.990973 -391.334684) (xy 46.990508 -391.319258)
			(xy 2.509012 -391.319258) (xy 2.509012 -393.292838) (xy 47.435008 -393.292838) (xy 47.435008 -392.429238)
			(xy 47.435494 -392.401987) (xy 47.44325 -392.348039) (xy 47.458605 -392.295744) (xy 47.481247 -392.246167)
			(xy 47.510713 -392.200317) (xy 47.546404 -392.159126) (xy 47.587595 -392.123435) (xy 47.633445 -392.093969)
			(xy 47.683022 -392.071327) (xy 47.735317 -392.055972) (xy 47.789265 -392.048216) (xy 47.843767 -392.048216)
			(xy 47.897715 -392.055972) (xy 47.95001 -392.071327) (xy 47.999587 -392.093969) (xy 48.045437 -392.123435)
			(xy 48.086628 -392.159126) (xy 48.122319 -392.200317) (xy 48.151785 -392.246167) (xy 48.174427 -392.295744)
			(xy 48.189782 -392.348039) (xy 48.197538 -392.401987) (xy 48.198024 -392.429238) (xy 48.198024 -393.292838)
			(xy 48.634904 -393.292838) (xy 48.634904 -392.429238) (xy 48.63539 -392.401987) (xy 48.643146 -392.348039)
			(xy 48.658501 -392.295744) (xy 48.681143 -392.246167) (xy 48.710609 -392.200317) (xy 48.7463 -392.159126)
			(xy 48.787491 -392.123435) (xy 48.833341 -392.093969) (xy 48.882918 -392.071327) (xy 48.935213 -392.055972)
			(xy 48.989161 -392.048216) (xy 49.043663 -392.048216) (xy 49.097611 -392.055972) (xy 49.149906 -392.071327)
			(xy 49.199483 -392.093969) (xy 49.245333 -392.123435) (xy 49.286524 -392.159126) (xy 49.322215 -392.200317)
			(xy 49.351681 -392.246167) (xy 49.374323 -392.295744) (xy 49.389678 -392.348039) (xy 49.397434 -392.401987)
			(xy 49.39792 -392.429238) (xy 49.39792 -393.292838) (xy 49.8348 -393.292838) (xy 49.8348 -392.429238)
			(xy 49.835286 -392.401969) (xy 49.843048 -392.347985) (xy 49.858413 -392.295655) (xy 49.88107 -392.246045)
			(xy 49.910556 -392.200164) (xy 49.946271 -392.158947) (xy 49.987488 -392.123232) (xy 50.033369 -392.093746)
			(xy 50.082979 -392.071089) (xy 50.135309 -392.055724) (xy 50.189293 -392.047962) (xy 50.243831 -392.047962)
			(xy 50.297815 -392.055724) (xy 50.350145 -392.071089) (xy 50.399755 -392.093746) (xy 50.445636 -392.123232)
			(xy 50.486853 -392.158947) (xy 50.522568 -392.200164) (xy 50.552054 -392.246045) (xy 50.574711 -392.295655)
			(xy 50.590076 -392.347985) (xy 50.597838 -392.401969) (xy 50.598324 -392.429238) (xy 50.598324 -393.292838)
			(xy 51.034696 -393.292838) (xy 51.034696 -392.429238) (xy 51.035182 -392.401969) (xy 51.042944 -392.347985)
			(xy 51.058309 -392.295655) (xy 51.080966 -392.246045) (xy 51.110452 -392.200164) (xy 51.146167 -392.158947)
			(xy 51.187384 -392.123232) (xy 51.233265 -392.093746) (xy 51.282875 -392.071089) (xy 51.335205 -392.055724)
			(xy 51.389189 -392.047962) (xy 51.443727 -392.047962) (xy 51.497711 -392.055724) (xy 51.550041 -392.071089)
			(xy 51.599651 -392.093746) (xy 51.645532 -392.123232) (xy 51.686749 -392.158947) (xy 51.722464 -392.200164)
			(xy 51.75195 -392.246045) (xy 51.774607 -392.295655) (xy 51.789972 -392.347985) (xy 51.797734 -392.401969)
			(xy 51.79822 -392.429238) (xy 51.79822 -393.292838) (xy 52.2351 -393.292838) (xy 52.2351 -392.429238)
			(xy 52.235586 -392.401987) (xy 52.243342 -392.348039) (xy 52.258697 -392.295744) (xy 52.281339 -392.246167)
			(xy 52.310805 -392.200317) (xy 52.346496 -392.159126) (xy 52.387687 -392.123435) (xy 52.433537 -392.093969)
			(xy 52.483114 -392.071327) (xy 52.535409 -392.055972) (xy 52.589357 -392.048216) (xy 52.643859 -392.048216)
			(xy 52.697807 -392.055972) (xy 52.750102 -392.071327) (xy 52.799679 -392.093969) (xy 52.845529 -392.123435)
			(xy 52.88672 -392.159126) (xy 52.922411 -392.200317) (xy 52.951877 -392.246167) (xy 52.974519 -392.295744)
			(xy 52.989874 -392.348039) (xy 52.99763 -392.401987) (xy 52.998116 -392.429238) (xy 52.998116 -393.292838)
			(xy 53.434996 -393.292838) (xy 53.434996 -392.429238) (xy 53.435482 -392.401987) (xy 53.443238 -392.348039)
			(xy 53.458593 -392.295744) (xy 53.481235 -392.246167) (xy 53.510701 -392.200317) (xy 53.546392 -392.159126)
			(xy 53.587583 -392.123435) (xy 53.633433 -392.093969) (xy 53.68301 -392.071327) (xy 53.735305 -392.055972)
			(xy 53.789253 -392.048216) (xy 53.843755 -392.048216) (xy 53.897703 -392.055972) (xy 53.949998 -392.071327)
			(xy 53.999575 -392.093969) (xy 54.045425 -392.123435) (xy 54.086616 -392.159126) (xy 54.122307 -392.200317)
			(xy 54.151773 -392.246167) (xy 54.174415 -392.295744) (xy 54.18977 -392.348039) (xy 54.197526 -392.401987)
			(xy 54.198012 -392.429238) (xy 54.198012 -393.292838) (xy 54.634892 -393.292838) (xy 54.634892 -392.429238)
			(xy 54.635378 -392.401969) (xy 54.64314 -392.347985) (xy 54.658505 -392.295655) (xy 54.681162 -392.246045)
			(xy 54.710648 -392.200164) (xy 54.746363 -392.158947) (xy 54.78758 -392.123232) (xy 54.833461 -392.093746)
			(xy 54.883071 -392.071089) (xy 54.935401 -392.055724) (xy 54.989385 -392.047962) (xy 55.043923 -392.047962)
			(xy 55.097907 -392.055724) (xy 55.150237 -392.071089) (xy 55.199847 -392.093746) (xy 55.245728 -392.123232)
			(xy 55.286945 -392.158947) (xy 55.32266 -392.200164) (xy 55.352146 -392.246045) (xy 55.374803 -392.295655)
			(xy 55.390168 -392.347985) (xy 55.39793 -392.401969) (xy 55.398416 -392.429238) (xy 55.398416 -393.292838)
			(xy 55.834788 -393.292838) (xy 55.834788 -392.429238) (xy 55.835274 -392.401969) (xy 55.843036 -392.347985)
			(xy 55.858401 -392.295655) (xy 55.881058 -392.246045) (xy 55.910544 -392.200164) (xy 55.946259 -392.158947)
			(xy 55.987476 -392.123232) (xy 56.033357 -392.093746) (xy 56.082967 -392.071089) (xy 56.135297 -392.055724)
			(xy 56.189281 -392.047962) (xy 56.243819 -392.047962) (xy 56.297803 -392.055724) (xy 56.350133 -392.071089)
			(xy 56.399743 -392.093746) (xy 56.445624 -392.123232) (xy 56.486841 -392.158947) (xy 56.522556 -392.200164)
			(xy 56.552042 -392.246045) (xy 56.574699 -392.295655) (xy 56.590064 -392.347985) (xy 56.597826 -392.401969)
			(xy 56.598312 -392.429238) (xy 56.598312 -393.292838) (xy 57.035192 -393.292838) (xy 57.035192 -392.429238)
			(xy 57.035678 -392.401987) (xy 57.043434 -392.348039) (xy 57.058789 -392.295744) (xy 57.081431 -392.246167)
			(xy 57.110897 -392.200317) (xy 57.146588 -392.159126) (xy 57.187779 -392.123435) (xy 57.233629 -392.093969)
			(xy 57.283206 -392.071327) (xy 57.335501 -392.055972) (xy 57.389449 -392.048216) (xy 57.443951 -392.048216)
			(xy 57.497899 -392.055972) (xy 57.550194 -392.071327) (xy 57.599771 -392.093969) (xy 57.645621 -392.123435)
			(xy 57.686812 -392.159126) (xy 57.722503 -392.200317) (xy 57.751969 -392.246167) (xy 57.774611 -392.295744)
			(xy 57.789966 -392.348039) (xy 57.797722 -392.401987) (xy 57.798208 -392.429238) (xy 57.798208 -393.292838)
			(xy 58.235088 -393.292838) (xy 58.235088 -392.429238) (xy 58.235574 -392.401987) (xy 58.24333 -392.348039)
			(xy 58.258685 -392.295744) (xy 58.281327 -392.246167) (xy 58.310793 -392.200317) (xy 58.346484 -392.159126)
			(xy 58.387675 -392.123435) (xy 58.433525 -392.093969) (xy 58.483102 -392.071327) (xy 58.535397 -392.055972)
			(xy 58.589345 -392.048216) (xy 58.643847 -392.048216) (xy 58.697795 -392.055972) (xy 58.75009 -392.071327)
			(xy 58.799667 -392.093969) (xy 58.845517 -392.123435) (xy 58.886708 -392.159126) (xy 58.922399 -392.200317)
			(xy 58.951865 -392.246167) (xy 58.974507 -392.295744) (xy 58.989862 -392.348039) (xy 58.997618 -392.401987)
			(xy 58.998104 -392.429238) (xy 58.998104 -393.292838) (xy 59.434984 -393.292838) (xy 59.434984 -392.429238)
			(xy 59.43547 -392.401969) (xy 59.443232 -392.347985) (xy 59.458597 -392.295655) (xy 59.481254 -392.246045)
			(xy 59.51074 -392.200164) (xy 59.546455 -392.158947) (xy 59.587672 -392.123232) (xy 59.633553 -392.093746)
			(xy 59.683163 -392.071089) (xy 59.735493 -392.055724) (xy 59.789477 -392.047962) (xy 59.844015 -392.047962)
			(xy 59.897999 -392.055724) (xy 59.950329 -392.071089) (xy 59.999939 -392.093746) (xy 60.04582 -392.123232)
			(xy 60.087037 -392.158947) (xy 60.122752 -392.200164) (xy 60.152238 -392.246045) (xy 60.174895 -392.295655)
			(xy 60.19026 -392.347985) (xy 60.198022 -392.401969) (xy 60.198508 -392.429238) (xy 60.198508 -393.292838)
			(xy 60.63488 -393.292838) (xy 60.63488 -392.429238) (xy 60.635366 -392.401969) (xy 60.643128 -392.347985)
			(xy 60.658493 -392.295655) (xy 60.68115 -392.246045) (xy 60.710636 -392.200164) (xy 60.746351 -392.158947)
			(xy 60.787568 -392.123232) (xy 60.833449 -392.093746) (xy 60.883059 -392.071089) (xy 60.935389 -392.055724)
			(xy 60.989373 -392.047962) (xy 61.043911 -392.047962) (xy 61.097895 -392.055724) (xy 61.150225 -392.071089)
			(xy 61.199835 -392.093746) (xy 61.245716 -392.123232) (xy 61.286933 -392.158947) (xy 61.322648 -392.200164)
			(xy 61.352134 -392.246045) (xy 61.374791 -392.295655) (xy 61.390156 -392.347985) (xy 61.397918 -392.401969)
			(xy 61.398404 -392.429238) (xy 61.398404 -393.292838) (xy 61.834776 -393.292838) (xy 61.834776 -392.429238)
			(xy 61.835262 -392.401969) (xy 61.843024 -392.347985) (xy 61.858389 -392.295655) (xy 61.881046 -392.246045)
			(xy 61.910532 -392.200164) (xy 61.946247 -392.158947) (xy 61.987464 -392.123232) (xy 62.033345 -392.093746)
			(xy 62.082955 -392.071089) (xy 62.135285 -392.055724) (xy 62.189269 -392.047962) (xy 62.243807 -392.047962)
			(xy 62.297791 -392.055724) (xy 62.350121 -392.071089) (xy 62.399731 -392.093746) (xy 62.445612 -392.123232)
			(xy 62.486829 -392.158947) (xy 62.522544 -392.200164) (xy 62.55203 -392.246045) (xy 62.574687 -392.295655)
			(xy 62.590052 -392.347985) (xy 62.597814 -392.401969) (xy 62.5983 -392.429238) (xy 62.5983 -393.292838)
			(xy 63.034672 -393.292838) (xy 63.034672 -392.429238) (xy 63.035158 -392.401969) (xy 63.04292 -392.347985)
			(xy 63.058285 -392.295655) (xy 63.080942 -392.246045) (xy 63.110428 -392.200164) (xy 63.146143 -392.158947)
			(xy 63.18736 -392.123232) (xy 63.233241 -392.093746) (xy 63.282851 -392.071089) (xy 63.335181 -392.055724)
			(xy 63.389165 -392.047962) (xy 63.443703 -392.047962) (xy 63.497687 -392.055724) (xy 63.550017 -392.071089)
			(xy 63.599627 -392.093746) (xy 63.645508 -392.123232) (xy 63.686725 -392.158947) (xy 63.72244 -392.200164)
			(xy 63.751926 -392.246045) (xy 63.774583 -392.295655) (xy 63.789948 -392.347985) (xy 63.79771 -392.401969)
			(xy 63.798196 -392.429238) (xy 63.798196 -393.292838) (xy 64.235076 -393.292838) (xy 64.235076 -392.429238)
			(xy 64.235562 -392.401987) (xy 64.243318 -392.348039) (xy 64.258673 -392.295744) (xy 64.281315 -392.246167)
			(xy 64.310781 -392.200317) (xy 64.346472 -392.159126) (xy 64.387663 -392.123435) (xy 64.433513 -392.093969)
			(xy 64.48309 -392.071327) (xy 64.535385 -392.055972) (xy 64.589333 -392.048216) (xy 64.643835 -392.048216)
			(xy 64.697783 -392.055972) (xy 64.750078 -392.071327) (xy 64.799655 -392.093969) (xy 64.845505 -392.123435)
			(xy 64.886696 -392.159126) (xy 64.922387 -392.200317) (xy 64.951853 -392.246167) (xy 64.974495 -392.295744)
			(xy 64.98985 -392.348039) (xy 64.997606 -392.401987) (xy 64.998092 -392.429238) (xy 64.998092 -393.292838)
			(xy 65.434972 -393.292838) (xy 65.434972 -392.429238) (xy 65.435458 -392.401987) (xy 65.443214 -392.348039)
			(xy 65.458569 -392.295744) (xy 65.481211 -392.246167) (xy 65.510677 -392.200317) (xy 65.546368 -392.159126)
			(xy 65.587559 -392.123435) (xy 65.633409 -392.093969) (xy 65.682986 -392.071327) (xy 65.735281 -392.055972)
			(xy 65.789229 -392.048216) (xy 65.843731 -392.048216) (xy 65.897679 -392.055972) (xy 65.949974 -392.071327)
			(xy 65.999551 -392.093969) (xy 66.045401 -392.123435) (xy 66.086592 -392.159126) (xy 66.122283 -392.200317)
			(xy 66.151749 -392.246167) (xy 66.174391 -392.295744) (xy 66.189746 -392.348039) (xy 66.197502 -392.401987)
			(xy 66.197988 -392.429238) (xy 66.197988 -393.292838) (xy 79.962756 -393.292838) (xy 79.962756 -392.429238)
			(xy 79.963242 -392.401987) (xy 79.970998 -392.348039) (xy 79.986353 -392.295744) (xy 80.008995 -392.246167)
			(xy 80.038461 -392.200317) (xy 80.074152 -392.159126) (xy 80.115343 -392.123435) (xy 80.161193 -392.093969)
			(xy 80.21077 -392.071327) (xy 80.263065 -392.055972) (xy 80.317013 -392.048216) (xy 80.371515 -392.048216)
			(xy 80.425463 -392.055972) (xy 80.477758 -392.071327) (xy 80.527335 -392.093969) (xy 80.573185 -392.123435)
			(xy 80.614376 -392.159126) (xy 80.650067 -392.200317) (xy 80.679533 -392.246167) (xy 80.702175 -392.295744)
			(xy 80.71753 -392.348039) (xy 80.725286 -392.401987) (xy 80.725772 -392.429238) (xy 80.725772 -393.292838)
			(xy 81.162652 -393.292838) (xy 81.162652 -392.429238) (xy 81.163138 -392.401987) (xy 81.170894 -392.348039)
			(xy 81.186249 -392.295744) (xy 81.208891 -392.246167) (xy 81.238357 -392.200317) (xy 81.274048 -392.159126)
			(xy 81.315239 -392.123435) (xy 81.361089 -392.093969) (xy 81.410666 -392.071327) (xy 81.462961 -392.055972)
			(xy 81.516909 -392.048216) (xy 81.571411 -392.048216) (xy 81.625359 -392.055972) (xy 81.677654 -392.071327)
			(xy 81.727231 -392.093969) (xy 81.773081 -392.123435) (xy 81.814272 -392.159126) (xy 81.849963 -392.200317)
			(xy 81.879429 -392.246167) (xy 81.902071 -392.295744) (xy 81.917426 -392.348039) (xy 81.925182 -392.401987)
			(xy 81.925668 -392.429238) (xy 81.925668 -393.292838) (xy 82.362548 -393.292838) (xy 82.362548 -392.429238)
			(xy 82.363034 -392.401969) (xy 82.370796 -392.347985) (xy 82.386161 -392.295655) (xy 82.408818 -392.246045)
			(xy 82.438304 -392.200164) (xy 82.474019 -392.158947) (xy 82.515236 -392.123232) (xy 82.561117 -392.093746)
			(xy 82.610727 -392.071089) (xy 82.663057 -392.055724) (xy 82.717041 -392.047962) (xy 82.771579 -392.047962)
			(xy 82.825563 -392.055724) (xy 82.877893 -392.071089) (xy 82.927503 -392.093746) (xy 82.973384 -392.123232)
			(xy 83.014601 -392.158947) (xy 83.050316 -392.200164) (xy 83.079802 -392.246045) (xy 83.102459 -392.295655)
			(xy 83.117824 -392.347985) (xy 83.125586 -392.401969) (xy 83.126072 -392.429238) (xy 83.126072 -393.292838)
			(xy 83.562444 -393.292838) (xy 83.562444 -392.429238) (xy 83.56293 -392.401969) (xy 83.570692 -392.347985)
			(xy 83.586057 -392.295655) (xy 83.608714 -392.246045) (xy 83.6382 -392.200164) (xy 83.673915 -392.158947)
			(xy 83.715132 -392.123232) (xy 83.761013 -392.093746) (xy 83.810623 -392.071089) (xy 83.862953 -392.055724)
			(xy 83.916937 -392.047962) (xy 83.971475 -392.047962) (xy 84.025459 -392.055724) (xy 84.077789 -392.071089)
			(xy 84.127399 -392.093746) (xy 84.17328 -392.123232) (xy 84.214497 -392.158947) (xy 84.250212 -392.200164)
			(xy 84.279698 -392.246045) (xy 84.302355 -392.295655) (xy 84.31772 -392.347985) (xy 84.325482 -392.401969)
			(xy 84.325968 -392.429238) (xy 84.325968 -393.292838) (xy 84.762848 -393.292838) (xy 84.762848 -392.429238)
			(xy 84.763334 -392.401987) (xy 84.77109 -392.348039) (xy 84.786445 -392.295744) (xy 84.809087 -392.246167)
			(xy 84.838553 -392.200317) (xy 84.874244 -392.159126) (xy 84.915435 -392.123435) (xy 84.961285 -392.093969)
			(xy 85.010862 -392.071327) (xy 85.063157 -392.055972) (xy 85.117105 -392.048216) (xy 85.171607 -392.048216)
			(xy 85.225555 -392.055972) (xy 85.27785 -392.071327) (xy 85.327427 -392.093969) (xy 85.373277 -392.123435)
			(xy 85.414468 -392.159126) (xy 85.450159 -392.200317) (xy 85.479625 -392.246167) (xy 85.502267 -392.295744)
			(xy 85.517622 -392.348039) (xy 85.525378 -392.401987) (xy 85.525864 -392.429238) (xy 85.525864 -393.292838)
			(xy 85.962744 -393.292838) (xy 85.962744 -392.429238) (xy 85.96323 -392.401987) (xy 85.970986 -392.348039)
			(xy 85.986341 -392.295744) (xy 86.008983 -392.246167) (xy 86.038449 -392.200317) (xy 86.07414 -392.159126)
			(xy 86.115331 -392.123435) (xy 86.161181 -392.093969) (xy 86.210758 -392.071327) (xy 86.263053 -392.055972)
			(xy 86.317001 -392.048216) (xy 86.371503 -392.048216) (xy 86.425451 -392.055972) (xy 86.477746 -392.071327)
			(xy 86.527323 -392.093969) (xy 86.573173 -392.123435) (xy 86.614364 -392.159126) (xy 86.650055 -392.200317)
			(xy 86.679521 -392.246167) (xy 86.702163 -392.295744) (xy 86.717518 -392.348039) (xy 86.725274 -392.401987)
			(xy 86.72576 -392.429238) (xy 86.72576 -393.292838) (xy 87.16264 -393.292838) (xy 87.16264 -392.429238)
			(xy 87.163126 -392.401969) (xy 87.170888 -392.347985) (xy 87.186253 -392.295655) (xy 87.20891 -392.246045)
			(xy 87.238396 -392.200164) (xy 87.274111 -392.158947) (xy 87.315328 -392.123232) (xy 87.361209 -392.093746)
			(xy 87.410819 -392.071089) (xy 87.463149 -392.055724) (xy 87.517133 -392.047962) (xy 87.571671 -392.047962)
			(xy 87.625655 -392.055724) (xy 87.677985 -392.071089) (xy 87.727595 -392.093746) (xy 87.773476 -392.123232)
			(xy 87.814693 -392.158947) (xy 87.850408 -392.200164) (xy 87.879894 -392.246045) (xy 87.902551 -392.295655)
			(xy 87.917916 -392.347985) (xy 87.925678 -392.401969) (xy 87.926164 -392.429238) (xy 87.926164 -393.292838)
			(xy 88.362536 -393.292838) (xy 88.362536 -392.429238) (xy 88.363022 -392.401969) (xy 88.370784 -392.347985)
			(xy 88.386149 -392.295655) (xy 88.408806 -392.246045) (xy 88.438292 -392.200164) (xy 88.474007 -392.158947)
			(xy 88.515224 -392.123232) (xy 88.561105 -392.093746) (xy 88.610715 -392.071089) (xy 88.663045 -392.055724)
			(xy 88.717029 -392.047962) (xy 88.771567 -392.047962) (xy 88.825551 -392.055724) (xy 88.877881 -392.071089)
			(xy 88.927491 -392.093746) (xy 88.973372 -392.123232) (xy 89.014589 -392.158947) (xy 89.050304 -392.200164)
			(xy 89.07979 -392.246045) (xy 89.102447 -392.295655) (xy 89.117812 -392.347985) (xy 89.125574 -392.401969)
			(xy 89.12606 -392.429238) (xy 89.12606 -393.292838) (xy 89.56294 -393.292838) (xy 89.56294 -392.429238)
			(xy 89.563426 -392.401987) (xy 89.571182 -392.348039) (xy 89.586537 -392.295744) (xy 89.609179 -392.246167)
			(xy 89.638645 -392.200317) (xy 89.674336 -392.159126) (xy 89.715527 -392.123435) (xy 89.761377 -392.093969)
			(xy 89.810954 -392.071327) (xy 89.863249 -392.055972) (xy 89.917197 -392.048216) (xy 89.971699 -392.048216)
			(xy 90.025647 -392.055972) (xy 90.077942 -392.071327) (xy 90.127519 -392.093969) (xy 90.173369 -392.123435)
			(xy 90.21456 -392.159126) (xy 90.250251 -392.200317) (xy 90.279717 -392.246167) (xy 90.302359 -392.295744)
			(xy 90.317714 -392.348039) (xy 90.32547 -392.401987) (xy 90.325956 -392.429238) (xy 90.325956 -393.292838)
			(xy 90.762836 -393.292838) (xy 90.762836 -392.429238) (xy 90.763322 -392.401987) (xy 90.771078 -392.348039)
			(xy 90.786433 -392.295744) (xy 90.809075 -392.246167) (xy 90.838541 -392.200317) (xy 90.874232 -392.159126)
			(xy 90.915423 -392.123435) (xy 90.961273 -392.093969) (xy 91.01085 -392.071327) (xy 91.063145 -392.055972)
			(xy 91.117093 -392.048216) (xy 91.171595 -392.048216) (xy 91.225543 -392.055972) (xy 91.277838 -392.071327)
			(xy 91.327415 -392.093969) (xy 91.373265 -392.123435) (xy 91.414456 -392.159126) (xy 91.450147 -392.200317)
			(xy 91.479613 -392.246167) (xy 91.502255 -392.295744) (xy 91.51761 -392.348039) (xy 91.525366 -392.401987)
			(xy 91.525852 -392.429238) (xy 91.525852 -393.292838) (xy 91.962732 -393.292838) (xy 91.962732 -392.429238)
			(xy 91.963218 -392.401969) (xy 91.97098 -392.347985) (xy 91.986345 -392.295655) (xy 92.009002 -392.246045)
			(xy 92.038488 -392.200164) (xy 92.074203 -392.158947) (xy 92.11542 -392.123232) (xy 92.161301 -392.093746)
			(xy 92.210911 -392.071089) (xy 92.263241 -392.055724) (xy 92.317225 -392.047962) (xy 92.371763 -392.047962)
			(xy 92.425747 -392.055724) (xy 92.478077 -392.071089) (xy 92.527687 -392.093746) (xy 92.573568 -392.123232)
			(xy 92.614785 -392.158947) (xy 92.6505 -392.200164) (xy 92.679986 -392.246045) (xy 92.702643 -392.295655)
			(xy 92.718008 -392.347985) (xy 92.72577 -392.401969) (xy 92.726256 -392.429238) (xy 92.726256 -393.292838)
			(xy 93.162628 -393.292838) (xy 93.162628 -392.429238) (xy 93.163114 -392.401969) (xy 93.170876 -392.347985)
			(xy 93.186241 -392.295655) (xy 93.208898 -392.246045) (xy 93.238384 -392.200164) (xy 93.274099 -392.158947)
			(xy 93.315316 -392.123232) (xy 93.361197 -392.093746) (xy 93.410807 -392.071089) (xy 93.463137 -392.055724)
			(xy 93.517121 -392.047962) (xy 93.571659 -392.047962) (xy 93.625643 -392.055724) (xy 93.677973 -392.071089)
			(xy 93.727583 -392.093746) (xy 93.773464 -392.123232) (xy 93.814681 -392.158947) (xy 93.850396 -392.200164)
			(xy 93.879882 -392.246045) (xy 93.902539 -392.295655) (xy 93.917904 -392.347985) (xy 93.925666 -392.401969)
			(xy 93.926152 -392.429238) (xy 93.926152 -393.292838) (xy 94.362524 -393.292838) (xy 94.362524 -392.429238)
			(xy 94.36301 -392.401969) (xy 94.370772 -392.347985) (xy 94.386137 -392.295655) (xy 94.408794 -392.246045)
			(xy 94.43828 -392.200164) (xy 94.473995 -392.158947) (xy 94.515212 -392.123232) (xy 94.561093 -392.093746)
			(xy 94.610703 -392.071089) (xy 94.663033 -392.055724) (xy 94.717017 -392.047962) (xy 94.771555 -392.047962)
			(xy 94.825539 -392.055724) (xy 94.877869 -392.071089) (xy 94.927479 -392.093746) (xy 94.97336 -392.123232)
			(xy 95.014577 -392.158947) (xy 95.050292 -392.200164) (xy 95.079778 -392.246045) (xy 95.102435 -392.295655)
			(xy 95.1178 -392.347985) (xy 95.125562 -392.401969) (xy 95.126048 -392.429238) (xy 95.126048 -393.292838)
			(xy 95.56242 -393.292838) (xy 95.56242 -392.429238) (xy 95.562906 -392.401969) (xy 95.570668 -392.347985)
			(xy 95.586033 -392.295655) (xy 95.60869 -392.246045) (xy 95.638176 -392.200164) (xy 95.673891 -392.158947)
			(xy 95.715108 -392.123232) (xy 95.760989 -392.093746) (xy 95.810599 -392.071089) (xy 95.862929 -392.055724)
			(xy 95.916913 -392.047962) (xy 95.971451 -392.047962) (xy 96.025435 -392.055724) (xy 96.077765 -392.071089)
			(xy 96.127375 -392.093746) (xy 96.173256 -392.123232) (xy 96.214473 -392.158947) (xy 96.250188 -392.200164)
			(xy 96.279674 -392.246045) (xy 96.302331 -392.295655) (xy 96.317696 -392.347985) (xy 96.325458 -392.401969)
			(xy 96.325944 -392.429238) (xy 96.325944 -393.292838) (xy 96.762824 -393.292838) (xy 96.762824 -392.429238)
			(xy 96.76331 -392.401987) (xy 96.771066 -392.348039) (xy 96.786421 -392.295744) (xy 96.809063 -392.246167)
			(xy 96.838529 -392.200317) (xy 96.87422 -392.159126) (xy 96.915411 -392.123435) (xy 96.961261 -392.093969)
			(xy 97.010838 -392.071327) (xy 97.063133 -392.055972) (xy 97.117081 -392.048216) (xy 97.171583 -392.048216)
			(xy 97.225531 -392.055972) (xy 97.277826 -392.071327) (xy 97.327403 -392.093969) (xy 97.373253 -392.123435)
			(xy 97.414444 -392.159126) (xy 97.450135 -392.200317) (xy 97.479601 -392.246167) (xy 97.502243 -392.295744)
			(xy 97.517598 -392.348039) (xy 97.525354 -392.401987) (xy 97.52584 -392.429238) (xy 97.52584 -393.292838)
			(xy 97.96272 -393.292838) (xy 97.96272 -392.429238) (xy 97.963206 -392.401987) (xy 97.970962 -392.348039)
			(xy 97.986317 -392.295744) (xy 98.008959 -392.246167) (xy 98.038425 -392.200317) (xy 98.074116 -392.159126)
			(xy 98.115307 -392.123435) (xy 98.161157 -392.093969) (xy 98.210734 -392.071327) (xy 98.263029 -392.055972)
			(xy 98.316977 -392.048216) (xy 98.371479 -392.048216) (xy 98.425427 -392.055972) (xy 98.477722 -392.071327)
			(xy 98.527299 -392.093969) (xy 98.573149 -392.123435) (xy 98.61434 -392.159126) (xy 98.650031 -392.200317)
			(xy 98.679497 -392.246167) (xy 98.702139 -392.295744) (xy 98.717494 -392.348039) (xy 98.72525 -392.401987)
			(xy 98.725736 -392.429238) (xy 98.725736 -393.292838) (xy 114.534696 -393.292838) (xy 114.534696 -392.429238)
			(xy 114.535182 -392.401969) (xy 114.542944 -392.347985) (xy 114.558309 -392.295655) (xy 114.580966 -392.246045)
			(xy 114.610452 -392.200164) (xy 114.646167 -392.158947) (xy 114.687384 -392.123232) (xy 114.733265 -392.093746)
			(xy 114.782875 -392.071089) (xy 114.835205 -392.055724) (xy 114.889189 -392.047962) (xy 114.943727 -392.047962)
			(xy 114.997711 -392.055724) (xy 115.050041 -392.071089) (xy 115.099651 -392.093746) (xy 115.145532 -392.123232)
			(xy 115.186749 -392.158947) (xy 115.222464 -392.200164) (xy 115.25195 -392.246045) (xy 115.274607 -392.295655)
			(xy 115.289972 -392.347985) (xy 115.297734 -392.401969) (xy 115.29822 -392.429238) (xy 115.29822 -393.292838)
			(xy 115.734592 -393.292838) (xy 115.734592 -392.429238) (xy 115.735078 -392.401969) (xy 115.74284 -392.347985)
			(xy 115.758205 -392.295655) (xy 115.780862 -392.246045) (xy 115.810348 -392.200164) (xy 115.846063 -392.158947)
			(xy 115.88728 -392.123232) (xy 115.933161 -392.093746) (xy 115.982771 -392.071089) (xy 116.035101 -392.055724)
			(xy 116.089085 -392.047962) (xy 116.143623 -392.047962) (xy 116.197607 -392.055724) (xy 116.249937 -392.071089)
			(xy 116.299547 -392.093746) (xy 116.345428 -392.123232) (xy 116.386645 -392.158947) (xy 116.42236 -392.200164)
			(xy 116.451846 -392.246045) (xy 116.474503 -392.295655) (xy 116.489868 -392.347985) (xy 116.49763 -392.401969)
			(xy 116.498116 -392.429238) (xy 116.498116 -393.292838) (xy 116.934996 -393.292838) (xy 116.934996 -392.429238)
			(xy 116.935482 -392.401987) (xy 116.943238 -392.348039) (xy 116.958593 -392.295744) (xy 116.981235 -392.246167)
			(xy 117.010701 -392.200317) (xy 117.046392 -392.159126) (xy 117.087583 -392.123435) (xy 117.133433 -392.093969)
			(xy 117.18301 -392.071327) (xy 117.235305 -392.055972) (xy 117.289253 -392.048216) (xy 117.343755 -392.048216)
			(xy 117.397703 -392.055972) (xy 117.449998 -392.071327) (xy 117.499575 -392.093969) (xy 117.545425 -392.123435)
			(xy 117.586616 -392.159126) (xy 117.622307 -392.200317) (xy 117.651773 -392.246167) (xy 117.674415 -392.295744)
			(xy 117.68977 -392.348039) (xy 117.697526 -392.401987) (xy 117.698012 -392.429238) (xy 117.698012 -393.292838)
			(xy 118.134892 -393.292838) (xy 118.134892 -392.429238) (xy 118.135378 -392.401987) (xy 118.143134 -392.348039)
			(xy 118.158489 -392.295744) (xy 118.181131 -392.246167) (xy 118.210597 -392.200317) (xy 118.246288 -392.159126)
			(xy 118.287479 -392.123435) (xy 118.333329 -392.093969) (xy 118.382906 -392.071327) (xy 118.435201 -392.055972)
			(xy 118.489149 -392.048216) (xy 118.543651 -392.048216) (xy 118.597599 -392.055972) (xy 118.649894 -392.071327)
			(xy 118.699471 -392.093969) (xy 118.745321 -392.123435) (xy 118.786512 -392.159126) (xy 118.822203 -392.200317)
			(xy 118.851669 -392.246167) (xy 118.874311 -392.295744) (xy 118.889666 -392.348039) (xy 118.897422 -392.401987)
			(xy 118.897908 -392.429238) (xy 118.897908 -393.292838) (xy 119.334788 -393.292838) (xy 119.334788 -392.429238)
			(xy 119.335274 -392.401969) (xy 119.343036 -392.347985) (xy 119.358401 -392.295655) (xy 119.381058 -392.246045)
			(xy 119.410544 -392.200164) (xy 119.446259 -392.158947) (xy 119.487476 -392.123232) (xy 119.533357 -392.093746)
			(xy 119.582967 -392.071089) (xy 119.635297 -392.055724) (xy 119.689281 -392.047962) (xy 119.743819 -392.047962)
			(xy 119.797803 -392.055724) (xy 119.850133 -392.071089) (xy 119.899743 -392.093746) (xy 119.945624 -392.123232)
			(xy 119.986841 -392.158947) (xy 120.022556 -392.200164) (xy 120.052042 -392.246045) (xy 120.074699 -392.295655)
			(xy 120.090064 -392.347985) (xy 120.097826 -392.401969) (xy 120.098312 -392.429238) (xy 120.098312 -393.292838)
			(xy 120.534684 -393.292838) (xy 120.534684 -392.429238) (xy 120.53517 -392.401969) (xy 120.542932 -392.347985)
			(xy 120.558297 -392.295655) (xy 120.580954 -392.246045) (xy 120.61044 -392.200164) (xy 120.646155 -392.158947)
			(xy 120.687372 -392.123232) (xy 120.733253 -392.093746) (xy 120.782863 -392.071089) (xy 120.835193 -392.055724)
			(xy 120.889177 -392.047962) (xy 120.943715 -392.047962) (xy 120.997699 -392.055724) (xy 121.050029 -392.071089)
			(xy 121.099639 -392.093746) (xy 121.14552 -392.123232) (xy 121.186737 -392.158947) (xy 121.222452 -392.200164)
			(xy 121.251938 -392.246045) (xy 121.274595 -392.295655) (xy 121.28996 -392.347985) (xy 121.297722 -392.401969)
			(xy 121.298208 -392.429238) (xy 121.298208 -393.292838) (xy 121.735088 -393.292838) (xy 121.735088 -392.429238)
			(xy 121.735574 -392.401987) (xy 121.74333 -392.348039) (xy 121.758685 -392.295744) (xy 121.781327 -392.246167)
			(xy 121.810793 -392.200317) (xy 121.846484 -392.159126) (xy 121.887675 -392.123435) (xy 121.933525 -392.093969)
			(xy 121.983102 -392.071327) (xy 122.035397 -392.055972) (xy 122.089345 -392.048216) (xy 122.143847 -392.048216)
			(xy 122.197795 -392.055972) (xy 122.25009 -392.071327) (xy 122.299667 -392.093969) (xy 122.345517 -392.123435)
			(xy 122.386708 -392.159126) (xy 122.422399 -392.200317) (xy 122.451865 -392.246167) (xy 122.474507 -392.295744)
			(xy 122.489862 -392.348039) (xy 122.497618 -392.401987) (xy 122.498104 -392.429238) (xy 122.498104 -393.292838)
			(xy 122.934984 -393.292838) (xy 122.934984 -392.429238) (xy 122.93547 -392.401987) (xy 122.943226 -392.348039)
			(xy 122.958581 -392.295744) (xy 122.981223 -392.246167) (xy 123.010689 -392.200317) (xy 123.04638 -392.159126)
			(xy 123.087571 -392.123435) (xy 123.133421 -392.093969) (xy 123.182998 -392.071327) (xy 123.235293 -392.055972)
			(xy 123.289241 -392.048216) (xy 123.343743 -392.048216) (xy 123.397691 -392.055972) (xy 123.449986 -392.071327)
			(xy 123.499563 -392.093969) (xy 123.545413 -392.123435) (xy 123.586604 -392.159126) (xy 123.622295 -392.200317)
			(xy 123.651761 -392.246167) (xy 123.674403 -392.295744) (xy 123.689758 -392.348039) (xy 123.697514 -392.401987)
			(xy 123.698 -392.429238) (xy 123.698 -393.292838) (xy 124.13488 -393.292838) (xy 124.13488 -392.429238)
			(xy 124.135366 -392.401969) (xy 124.143128 -392.347985) (xy 124.158493 -392.295655) (xy 124.18115 -392.246045)
			(xy 124.210636 -392.200164) (xy 124.246351 -392.158947) (xy 124.287568 -392.123232) (xy 124.333449 -392.093746)
			(xy 124.383059 -392.071089) (xy 124.435389 -392.055724) (xy 124.489373 -392.047962) (xy 124.543911 -392.047962)
			(xy 124.597895 -392.055724) (xy 124.650225 -392.071089) (xy 124.699835 -392.093746) (xy 124.745716 -392.123232)
			(xy 124.786933 -392.158947) (xy 124.822648 -392.200164) (xy 124.852134 -392.246045) (xy 124.874791 -392.295655)
			(xy 124.890156 -392.347985) (xy 124.897918 -392.401969) (xy 124.898404 -392.429238) (xy 124.898404 -393.292838)
			(xy 125.334776 -393.292838) (xy 125.334776 -392.429238) (xy 125.335262 -392.401969) (xy 125.343024 -392.347985)
			(xy 125.358389 -392.295655) (xy 125.381046 -392.246045) (xy 125.410532 -392.200164) (xy 125.446247 -392.158947)
			(xy 125.487464 -392.123232) (xy 125.533345 -392.093746) (xy 125.582955 -392.071089) (xy 125.635285 -392.055724)
			(xy 125.689269 -392.047962) (xy 125.743807 -392.047962) (xy 125.797791 -392.055724) (xy 125.850121 -392.071089)
			(xy 125.899731 -392.093746) (xy 125.945612 -392.123232) (xy 125.986829 -392.158947) (xy 126.022544 -392.200164)
			(xy 126.05203 -392.246045) (xy 126.074687 -392.295655) (xy 126.090052 -392.347985) (xy 126.097814 -392.401969)
			(xy 126.0983 -392.429238) (xy 126.0983 -393.292838) (xy 126.53518 -393.292838) (xy 126.53518 -392.429238)
			(xy 126.535666 -392.401987) (xy 126.543422 -392.348039) (xy 126.558777 -392.295744) (xy 126.581419 -392.246167)
			(xy 126.610885 -392.200317) (xy 126.646576 -392.159126) (xy 126.687767 -392.123435) (xy 126.733617 -392.093969)
			(xy 126.783194 -392.071327) (xy 126.835489 -392.055972) (xy 126.889437 -392.048216) (xy 126.943939 -392.048216)
			(xy 126.997887 -392.055972) (xy 127.050182 -392.071327) (xy 127.099759 -392.093969) (xy 127.145609 -392.123435)
			(xy 127.1868 -392.159126) (xy 127.222491 -392.200317) (xy 127.251957 -392.246167) (xy 127.274599 -392.295744)
			(xy 127.289954 -392.348039) (xy 127.29771 -392.401987) (xy 127.298196 -392.429238) (xy 127.298196 -393.292838)
			(xy 127.735076 -393.292838) (xy 127.735076 -392.429238) (xy 127.735562 -392.401987) (xy 127.743318 -392.348039)
			(xy 127.758673 -392.295744) (xy 127.781315 -392.246167) (xy 127.810781 -392.200317) (xy 127.846472 -392.159126)
			(xy 127.887663 -392.123435) (xy 127.933513 -392.093969) (xy 127.98309 -392.071327) (xy 128.035385 -392.055972)
			(xy 128.089333 -392.048216) (xy 128.143835 -392.048216) (xy 128.197783 -392.055972) (xy 128.250078 -392.071327)
			(xy 128.299655 -392.093969) (xy 128.345505 -392.123435) (xy 128.386696 -392.159126) (xy 128.422387 -392.200317)
			(xy 128.451853 -392.246167) (xy 128.474495 -392.295744) (xy 128.48985 -392.348039) (xy 128.497606 -392.401987)
			(xy 128.498092 -392.429238) (xy 128.498092 -393.292838) (xy 128.934972 -393.292838) (xy 128.934972 -392.429238)
			(xy 128.935458 -392.401987) (xy 128.943214 -392.348039) (xy 128.958569 -392.295744) (xy 128.981211 -392.246167)
			(xy 129.010677 -392.200317) (xy 129.046368 -392.159126) (xy 129.087559 -392.123435) (xy 129.133409 -392.093969)
			(xy 129.182986 -392.071327) (xy 129.235281 -392.055972) (xy 129.289229 -392.048216) (xy 129.343731 -392.048216)
			(xy 129.397679 -392.055972) (xy 129.449974 -392.071327) (xy 129.499551 -392.093969) (xy 129.545401 -392.123435)
			(xy 129.586592 -392.159126) (xy 129.622283 -392.200317) (xy 129.651749 -392.246167) (xy 129.674391 -392.295744)
			(xy 129.689746 -392.348039) (xy 129.697502 -392.401987) (xy 129.697988 -392.429238) (xy 129.697988 -393.292838)
			(xy 130.134868 -393.292838) (xy 130.134868 -392.429238) (xy 130.135354 -392.401987) (xy 130.14311 -392.348039)
			(xy 130.158465 -392.295744) (xy 130.181107 -392.246167) (xy 130.210573 -392.200317) (xy 130.246264 -392.159126)
			(xy 130.287455 -392.123435) (xy 130.333305 -392.093969) (xy 130.382882 -392.071327) (xy 130.435177 -392.055972)
			(xy 130.489125 -392.048216) (xy 130.543627 -392.048216) (xy 130.597575 -392.055972) (xy 130.64987 -392.071327)
			(xy 130.699447 -392.093969) (xy 130.745297 -392.123435) (xy 130.786488 -392.159126) (xy 130.822179 -392.200317)
			(xy 130.851645 -392.246167) (xy 130.874287 -392.295744) (xy 130.889642 -392.348039) (xy 130.897398 -392.401987)
			(xy 130.897884 -392.429238) (xy 130.897884 -393.292838) (xy 131.334764 -393.292838) (xy 131.334764 -392.429238)
			(xy 131.33525 -392.401969) (xy 131.343012 -392.347985) (xy 131.358377 -392.295655) (xy 131.381034 -392.246045)
			(xy 131.41052 -392.200164) (xy 131.446235 -392.158947) (xy 131.487452 -392.123232) (xy 131.533333 -392.093746)
			(xy 131.582943 -392.071089) (xy 131.635273 -392.055724) (xy 131.689257 -392.047962) (xy 131.743795 -392.047962)
			(xy 131.797779 -392.055724) (xy 131.850109 -392.071089) (xy 131.899719 -392.093746) (xy 131.9456 -392.123232)
			(xy 131.986817 -392.158947) (xy 132.022532 -392.200164) (xy 132.052018 -392.246045) (xy 132.074675 -392.295655)
			(xy 132.09004 -392.347985) (xy 132.097802 -392.401969) (xy 132.098288 -392.429238) (xy 132.098288 -393.292838)
			(xy 132.53466 -393.292838) (xy 132.53466 -392.429238) (xy 132.535146 -392.401969) (xy 132.542908 -392.347985)
			(xy 132.558273 -392.295655) (xy 132.58093 -392.246045) (xy 132.610416 -392.200164) (xy 132.646131 -392.158947)
			(xy 132.687348 -392.123232) (xy 132.733229 -392.093746) (xy 132.782839 -392.071089) (xy 132.835169 -392.055724)
			(xy 132.889153 -392.047962) (xy 132.943691 -392.047962) (xy 132.997675 -392.055724) (xy 133.050005 -392.071089)
			(xy 133.099615 -392.093746) (xy 133.145496 -392.123232) (xy 133.186713 -392.158947) (xy 133.222428 -392.200164)
			(xy 133.251914 -392.246045) (xy 133.274571 -392.295655) (xy 133.289936 -392.347985) (xy 133.297698 -392.401969)
			(xy 133.298184 -392.429238) (xy 133.298184 -393.292838) (xy 147.062444 -393.292838) (xy 147.062444 -392.429238)
			(xy 147.06293 -392.401969) (xy 147.070692 -392.347985) (xy 147.086057 -392.295655) (xy 147.108714 -392.246045)
			(xy 147.1382 -392.200164) (xy 147.173915 -392.158947) (xy 147.215132 -392.123232) (xy 147.261013 -392.093746)
			(xy 147.310623 -392.071089) (xy 147.362953 -392.055724) (xy 147.416937 -392.047962) (xy 147.471475 -392.047962)
			(xy 147.525459 -392.055724) (xy 147.577789 -392.071089) (xy 147.627399 -392.093746) (xy 147.67328 -392.123232)
			(xy 147.714497 -392.158947) (xy 147.750212 -392.200164) (xy 147.779698 -392.246045) (xy 147.802355 -392.295655)
			(xy 147.81772 -392.347985) (xy 147.825482 -392.401969) (xy 147.825968 -392.429238) (xy 147.825968 -393.292838)
			(xy 148.26234 -393.292838) (xy 148.26234 -392.429238) (xy 148.262826 -392.401969) (xy 148.270588 -392.347985)
			(xy 148.285953 -392.295655) (xy 148.30861 -392.246045) (xy 148.338096 -392.200164) (xy 148.373811 -392.158947)
			(xy 148.415028 -392.123232) (xy 148.460909 -392.093746) (xy 148.510519 -392.071089) (xy 148.562849 -392.055724)
			(xy 148.616833 -392.047962) (xy 148.671371 -392.047962) (xy 148.725355 -392.055724) (xy 148.777685 -392.071089)
			(xy 148.827295 -392.093746) (xy 148.873176 -392.123232) (xy 148.914393 -392.158947) (xy 148.950108 -392.200164)
			(xy 148.979594 -392.246045) (xy 149.002251 -392.295655) (xy 149.017616 -392.347985) (xy 149.025378 -392.401969)
			(xy 149.025864 -392.429238) (xy 149.025864 -393.292838) (xy 149.462744 -393.292838) (xy 149.462744 -392.429238)
			(xy 149.46323 -392.401987) (xy 149.470986 -392.348039) (xy 149.486341 -392.295744) (xy 149.508983 -392.246167)
			(xy 149.538449 -392.200317) (xy 149.57414 -392.159126) (xy 149.615331 -392.123435) (xy 149.661181 -392.093969)
			(xy 149.710758 -392.071327) (xy 149.763053 -392.055972) (xy 149.817001 -392.048216) (xy 149.871503 -392.048216)
			(xy 149.925451 -392.055972) (xy 149.977746 -392.071327) (xy 150.027323 -392.093969) (xy 150.073173 -392.123435)
			(xy 150.114364 -392.159126) (xy 150.150055 -392.200317) (xy 150.179521 -392.246167) (xy 150.202163 -392.295744)
			(xy 150.217518 -392.348039) (xy 150.225274 -392.401987) (xy 150.22576 -392.429238) (xy 150.22576 -393.292838)
			(xy 150.66264 -393.292838) (xy 150.66264 -392.429238) (xy 150.663126 -392.401987) (xy 150.670882 -392.348039)
			(xy 150.686237 -392.295744) (xy 150.708879 -392.246167) (xy 150.738345 -392.200317) (xy 150.774036 -392.159126)
			(xy 150.815227 -392.123435) (xy 150.861077 -392.093969) (xy 150.910654 -392.071327) (xy 150.962949 -392.055972)
			(xy 151.016897 -392.048216) (xy 151.071399 -392.048216) (xy 151.125347 -392.055972) (xy 151.177642 -392.071327)
			(xy 151.227219 -392.093969) (xy 151.273069 -392.123435) (xy 151.31426 -392.159126) (xy 151.349951 -392.200317)
			(xy 151.379417 -392.246167) (xy 151.402059 -392.295744) (xy 151.417414 -392.348039) (xy 151.42517 -392.401987)
			(xy 151.425656 -392.429238) (xy 151.425656 -393.292838) (xy 151.862536 -393.292838) (xy 151.862536 -392.429238)
			(xy 151.863022 -392.401969) (xy 151.870784 -392.347985) (xy 151.886149 -392.295655) (xy 151.908806 -392.246045)
			(xy 151.938292 -392.200164) (xy 151.974007 -392.158947) (xy 152.015224 -392.123232) (xy 152.061105 -392.093746)
			(xy 152.110715 -392.071089) (xy 152.163045 -392.055724) (xy 152.217029 -392.047962) (xy 152.271567 -392.047962)
			(xy 152.325551 -392.055724) (xy 152.377881 -392.071089) (xy 152.427491 -392.093746) (xy 152.473372 -392.123232)
			(xy 152.514589 -392.158947) (xy 152.550304 -392.200164) (xy 152.57979 -392.246045) (xy 152.602447 -392.295655)
			(xy 152.617812 -392.347985) (xy 152.625574 -392.401969) (xy 152.62606 -392.429238) (xy 152.62606 -393.292838)
			(xy 153.062432 -393.292838) (xy 153.062432 -392.429238) (xy 153.062918 -392.401969) (xy 153.07068 -392.347985)
			(xy 153.086045 -392.295655) (xy 153.108702 -392.246045) (xy 153.138188 -392.200164) (xy 153.173903 -392.158947)
			(xy 153.21512 -392.123232) (xy 153.261001 -392.093746) (xy 153.310611 -392.071089) (xy 153.362941 -392.055724)
			(xy 153.416925 -392.047962) (xy 153.471463 -392.047962) (xy 153.525447 -392.055724) (xy 153.577777 -392.071089)
			(xy 153.627387 -392.093746) (xy 153.673268 -392.123232) (xy 153.714485 -392.158947) (xy 153.7502 -392.200164)
			(xy 153.779686 -392.246045) (xy 153.802343 -392.295655) (xy 153.817708 -392.347985) (xy 153.82547 -392.401969)
			(xy 153.825956 -392.429238) (xy 153.825956 -393.292838) (xy 154.262836 -393.292838) (xy 154.262836 -392.429238)
			(xy 154.263322 -392.401987) (xy 154.271078 -392.348039) (xy 154.286433 -392.295744) (xy 154.309075 -392.246167)
			(xy 154.338541 -392.200317) (xy 154.374232 -392.159126) (xy 154.415423 -392.123435) (xy 154.461273 -392.093969)
			(xy 154.51085 -392.071327) (xy 154.563145 -392.055972) (xy 154.617093 -392.048216) (xy 154.671595 -392.048216)
			(xy 154.725543 -392.055972) (xy 154.777838 -392.071327) (xy 154.827415 -392.093969) (xy 154.873265 -392.123435)
			(xy 154.914456 -392.159126) (xy 154.950147 -392.200317) (xy 154.979613 -392.246167) (xy 155.002255 -392.295744)
			(xy 155.01761 -392.348039) (xy 155.025366 -392.401987) (xy 155.025852 -392.429238) (xy 155.025852 -393.292838)
			(xy 155.462732 -393.292838) (xy 155.462732 -392.429238) (xy 155.463218 -392.401987) (xy 155.470974 -392.348039)
			(xy 155.486329 -392.295744) (xy 155.508971 -392.246167) (xy 155.538437 -392.200317) (xy 155.574128 -392.159126)
			(xy 155.615319 -392.123435) (xy 155.661169 -392.093969) (xy 155.710746 -392.071327) (xy 155.763041 -392.055972)
			(xy 155.816989 -392.048216) (xy 155.871491 -392.048216) (xy 155.925439 -392.055972) (xy 155.977734 -392.071327)
			(xy 156.027311 -392.093969) (xy 156.073161 -392.123435) (xy 156.114352 -392.159126) (xy 156.150043 -392.200317)
			(xy 156.179509 -392.246167) (xy 156.202151 -392.295744) (xy 156.217506 -392.348039) (xy 156.225262 -392.401987)
			(xy 156.225748 -392.429238) (xy 156.225748 -393.292838) (xy 156.662628 -393.292838) (xy 156.662628 -392.429238)
			(xy 156.663114 -392.401969) (xy 156.670876 -392.347985) (xy 156.686241 -392.295655) (xy 156.708898 -392.246045)
			(xy 156.738384 -392.200164) (xy 156.774099 -392.158947) (xy 156.815316 -392.123232) (xy 156.861197 -392.093746)
			(xy 156.910807 -392.071089) (xy 156.963137 -392.055724) (xy 157.017121 -392.047962) (xy 157.071659 -392.047962)
			(xy 157.125643 -392.055724) (xy 157.177973 -392.071089) (xy 157.227583 -392.093746) (xy 157.273464 -392.123232)
			(xy 157.314681 -392.158947) (xy 157.350396 -392.200164) (xy 157.379882 -392.246045) (xy 157.402539 -392.295655)
			(xy 157.417904 -392.347985) (xy 157.425666 -392.401969) (xy 157.426152 -392.429238) (xy 157.426152 -393.292838)
			(xy 157.862524 -393.292838) (xy 157.862524 -392.429238) (xy 157.86301 -392.401969) (xy 157.870772 -392.347985)
			(xy 157.886137 -392.295655) (xy 157.908794 -392.246045) (xy 157.93828 -392.200164) (xy 157.973995 -392.158947)
			(xy 158.015212 -392.123232) (xy 158.061093 -392.093746) (xy 158.110703 -392.071089) (xy 158.163033 -392.055724)
			(xy 158.217017 -392.047962) (xy 158.271555 -392.047962) (xy 158.325539 -392.055724) (xy 158.377869 -392.071089)
			(xy 158.427479 -392.093746) (xy 158.47336 -392.123232) (xy 158.514577 -392.158947) (xy 158.550292 -392.200164)
			(xy 158.579778 -392.246045) (xy 158.602435 -392.295655) (xy 158.6178 -392.347985) (xy 158.625562 -392.401969)
			(xy 158.626048 -392.429238) (xy 158.626048 -393.292838) (xy 159.062928 -393.292838) (xy 159.062928 -392.429238)
			(xy 159.063414 -392.401987) (xy 159.07117 -392.348039) (xy 159.086525 -392.295744) (xy 159.109167 -392.246167)
			(xy 159.138633 -392.200317) (xy 159.174324 -392.159126) (xy 159.215515 -392.123435) (xy 159.261365 -392.093969)
			(xy 159.310942 -392.071327) (xy 159.363237 -392.055972) (xy 159.417185 -392.048216) (xy 159.471687 -392.048216)
			(xy 159.525635 -392.055972) (xy 159.57793 -392.071327) (xy 159.627507 -392.093969) (xy 159.673357 -392.123435)
			(xy 159.714548 -392.159126) (xy 159.750239 -392.200317) (xy 159.779705 -392.246167) (xy 159.802347 -392.295744)
			(xy 159.817702 -392.348039) (xy 159.825458 -392.401987) (xy 159.825944 -392.429238) (xy 159.825944 -393.292838)
			(xy 160.262824 -393.292838) (xy 160.262824 -392.429238) (xy 160.26331 -392.401987) (xy 160.271066 -392.348039)
			(xy 160.286421 -392.295744) (xy 160.309063 -392.246167) (xy 160.338529 -392.200317) (xy 160.37422 -392.159126)
			(xy 160.415411 -392.123435) (xy 160.461261 -392.093969) (xy 160.510838 -392.071327) (xy 160.563133 -392.055972)
			(xy 160.617081 -392.048216) (xy 160.671583 -392.048216) (xy 160.725531 -392.055972) (xy 160.777826 -392.071327)
			(xy 160.827403 -392.093969) (xy 160.873253 -392.123435) (xy 160.914444 -392.159126) (xy 160.950135 -392.200317)
			(xy 160.979601 -392.246167) (xy 161.002243 -392.295744) (xy 161.017598 -392.348039) (xy 161.025354 -392.401987)
			(xy 161.02584 -392.429238) (xy 161.02584 -393.292838) (xy 161.46272 -393.292838) (xy 161.46272 -392.429238)
			(xy 161.463206 -392.401987) (xy 161.470962 -392.348039) (xy 161.486317 -392.295744) (xy 161.508959 -392.246167)
			(xy 161.538425 -392.200317) (xy 161.574116 -392.159126) (xy 161.615307 -392.123435) (xy 161.661157 -392.093969)
			(xy 161.710734 -392.071327) (xy 161.763029 -392.055972) (xy 161.816977 -392.048216) (xy 161.871479 -392.048216)
			(xy 161.925427 -392.055972) (xy 161.977722 -392.071327) (xy 162.027299 -392.093969) (xy 162.073149 -392.123435)
			(xy 162.11434 -392.159126) (xy 162.150031 -392.200317) (xy 162.179497 -392.246167) (xy 162.202139 -392.295744)
			(xy 162.217494 -392.348039) (xy 162.22525 -392.401987) (xy 162.225736 -392.429238) (xy 162.225736 -393.292838)
			(xy 162.662616 -393.292838) (xy 162.662616 -392.429238) (xy 162.663102 -392.401987) (xy 162.670858 -392.348039)
			(xy 162.686213 -392.295744) (xy 162.708855 -392.246167) (xy 162.738321 -392.200317) (xy 162.774012 -392.159126)
			(xy 162.815203 -392.123435) (xy 162.861053 -392.093969) (xy 162.91063 -392.071327) (xy 162.962925 -392.055972)
			(xy 163.016873 -392.048216) (xy 163.071375 -392.048216) (xy 163.125323 -392.055972) (xy 163.177618 -392.071327)
			(xy 163.227195 -392.093969) (xy 163.273045 -392.123435) (xy 163.314236 -392.159126) (xy 163.349927 -392.200317)
			(xy 163.379393 -392.246167) (xy 163.402035 -392.295744) (xy 163.41739 -392.348039) (xy 163.425146 -392.401987)
			(xy 163.425632 -392.429238) (xy 163.425632 -393.292838) (xy 163.862512 -393.292838) (xy 163.862512 -392.429238)
			(xy 163.862998 -392.401969) (xy 163.87076 -392.347985) (xy 163.886125 -392.295655) (xy 163.908782 -392.246045)
			(xy 163.938268 -392.200164) (xy 163.973983 -392.158947) (xy 164.0152 -392.123232) (xy 164.061081 -392.093746)
			(xy 164.110691 -392.071089) (xy 164.163021 -392.055724) (xy 164.217005 -392.047962) (xy 164.271543 -392.047962)
			(xy 164.325527 -392.055724) (xy 164.377857 -392.071089) (xy 164.427467 -392.093746) (xy 164.473348 -392.123232)
			(xy 164.514565 -392.158947) (xy 164.55028 -392.200164) (xy 164.579766 -392.246045) (xy 164.602423 -392.295655)
			(xy 164.617788 -392.347985) (xy 164.62555 -392.401969) (xy 164.626036 -392.429238) (xy 164.626036 -393.292838)
			(xy 165.062408 -393.292838) (xy 165.062408 -392.429238) (xy 165.062894 -392.401969) (xy 165.070656 -392.347985)
			(xy 165.086021 -392.295655) (xy 165.108678 -392.246045) (xy 165.138164 -392.200164) (xy 165.173879 -392.158947)
			(xy 165.215096 -392.123232) (xy 165.260977 -392.093746) (xy 165.310587 -392.071089) (xy 165.362917 -392.055724)
			(xy 165.416901 -392.047962) (xy 165.471439 -392.047962) (xy 165.525423 -392.055724) (xy 165.577753 -392.071089)
			(xy 165.627363 -392.093746) (xy 165.673244 -392.123232) (xy 165.714461 -392.158947) (xy 165.750176 -392.200164)
			(xy 165.779662 -392.246045) (xy 165.802319 -392.295655) (xy 165.817684 -392.347985) (xy 165.825446 -392.401969)
			(xy 165.825932 -392.429238) (xy 165.825932 -393.292838) (xy 165.825446 -393.320107) (xy 165.817684 -393.374091)
			(xy 165.802319 -393.426421) (xy 165.779662 -393.476031) (xy 165.750176 -393.521912) (xy 165.714461 -393.563129)
			(xy 165.673244 -393.598844) (xy 165.627363 -393.62833) (xy 165.577753 -393.650987) (xy 165.525423 -393.666352)
			(xy 165.471439 -393.674114) (xy 165.416901 -393.674114) (xy 165.362917 -393.666352) (xy 165.310587 -393.650987)
			(xy 165.260977 -393.62833) (xy 165.215096 -393.598844) (xy 165.173879 -393.563129) (xy 165.138164 -393.521912)
			(xy 165.108678 -393.476031) (xy 165.086021 -393.426421) (xy 165.070656 -393.374091) (xy 165.062894 -393.320107)
			(xy 165.062408 -393.292838) (xy 164.626036 -393.292838) (xy 164.62555 -393.320107) (xy 164.617788 -393.374091)
			(xy 164.602423 -393.426421) (xy 164.579766 -393.476031) (xy 164.55028 -393.521912) (xy 164.514565 -393.563129)
			(xy 164.473348 -393.598844) (xy 164.427467 -393.62833) (xy 164.377857 -393.650987) (xy 164.325527 -393.666352)
			(xy 164.271543 -393.674114) (xy 164.217005 -393.674114) (xy 164.163021 -393.666352) (xy 164.110691 -393.650987)
			(xy 164.061081 -393.62833) (xy 164.0152 -393.598844) (xy 163.973983 -393.563129) (xy 163.938268 -393.521912)
			(xy 163.908782 -393.476031) (xy 163.886125 -393.426421) (xy 163.87076 -393.374091) (xy 163.862998 -393.320107)
			(xy 163.862512 -393.292838) (xy 163.425632 -393.292838) (xy 163.425146 -393.320089) (xy 163.41739 -393.374037)
			(xy 163.402035 -393.426332) (xy 163.379393 -393.475909) (xy 163.349927 -393.521759) (xy 163.314236 -393.56295)
			(xy 163.273045 -393.598641) (xy 163.227195 -393.628107) (xy 163.177618 -393.650749) (xy 163.125323 -393.666104)
			(xy 163.071375 -393.67386) (xy 163.016873 -393.67386) (xy 162.962925 -393.666104) (xy 162.91063 -393.650749)
			(xy 162.861053 -393.628107) (xy 162.815203 -393.598641) (xy 162.774012 -393.56295) (xy 162.738321 -393.521759)
			(xy 162.708855 -393.475909) (xy 162.686213 -393.426332) (xy 162.670858 -393.374037) (xy 162.663102 -393.320089)
			(xy 162.662616 -393.292838) (xy 162.225736 -393.292838) (xy 162.22525 -393.320089) (xy 162.217494 -393.374037)
			(xy 162.202139 -393.426332) (xy 162.179497 -393.475909) (xy 162.150031 -393.521759) (xy 162.11434 -393.56295)
			(xy 162.073149 -393.598641) (xy 162.027299 -393.628107) (xy 161.977722 -393.650749) (xy 161.925427 -393.666104)
			(xy 161.871479 -393.67386) (xy 161.816977 -393.67386) (xy 161.763029 -393.666104) (xy 161.710734 -393.650749)
			(xy 161.661157 -393.628107) (xy 161.615307 -393.598641) (xy 161.574116 -393.56295) (xy 161.538425 -393.521759)
			(xy 161.508959 -393.475909) (xy 161.486317 -393.426332) (xy 161.470962 -393.374037) (xy 161.463206 -393.320089)
			(xy 161.46272 -393.292838) (xy 161.02584 -393.292838) (xy 161.025354 -393.320089) (xy 161.017598 -393.374037)
			(xy 161.002243 -393.426332) (xy 160.979601 -393.475909) (xy 160.950135 -393.521759) (xy 160.914444 -393.56295)
			(xy 160.873253 -393.598641) (xy 160.827403 -393.628107) (xy 160.777826 -393.650749) (xy 160.725531 -393.666104)
			(xy 160.671583 -393.67386) (xy 160.617081 -393.67386) (xy 160.563133 -393.666104) (xy 160.510838 -393.650749)
			(xy 160.461261 -393.628107) (xy 160.415411 -393.598641) (xy 160.37422 -393.56295) (xy 160.338529 -393.521759)
			(xy 160.309063 -393.475909) (xy 160.286421 -393.426332) (xy 160.271066 -393.374037) (xy 160.26331 -393.320089)
			(xy 160.262824 -393.292838) (xy 159.825944 -393.292838) (xy 159.825458 -393.320089) (xy 159.817702 -393.374037)
			(xy 159.802347 -393.426332) (xy 159.779705 -393.475909) (xy 159.750239 -393.521759) (xy 159.714548 -393.56295)
			(xy 159.673357 -393.598641) (xy 159.627507 -393.628107) (xy 159.57793 -393.650749) (xy 159.525635 -393.666104)
			(xy 159.471687 -393.67386) (xy 159.417185 -393.67386) (xy 159.363237 -393.666104) (xy 159.310942 -393.650749)
			(xy 159.261365 -393.628107) (xy 159.215515 -393.598641) (xy 159.174324 -393.56295) (xy 159.138633 -393.521759)
			(xy 159.109167 -393.475909) (xy 159.086525 -393.426332) (xy 159.07117 -393.374037) (xy 159.063414 -393.320089)
			(xy 159.062928 -393.292838) (xy 158.626048 -393.292838) (xy 158.625562 -393.320107) (xy 158.6178 -393.374091)
			(xy 158.602435 -393.426421) (xy 158.579778 -393.476031) (xy 158.550292 -393.521912) (xy 158.514577 -393.563129)
			(xy 158.47336 -393.598844) (xy 158.427479 -393.62833) (xy 158.377869 -393.650987) (xy 158.325539 -393.666352)
			(xy 158.271555 -393.674114) (xy 158.217017 -393.674114) (xy 158.163033 -393.666352) (xy 158.110703 -393.650987)
			(xy 158.061093 -393.62833) (xy 158.015212 -393.598844) (xy 157.973995 -393.563129) (xy 157.93828 -393.521912)
			(xy 157.908794 -393.476031) (xy 157.886137 -393.426421) (xy 157.870772 -393.374091) (xy 157.86301 -393.320107)
			(xy 157.862524 -393.292838) (xy 157.426152 -393.292838) (xy 157.425666 -393.320107) (xy 157.417904 -393.374091)
			(xy 157.402539 -393.426421) (xy 157.379882 -393.476031) (xy 157.350396 -393.521912) (xy 157.314681 -393.563129)
			(xy 157.273464 -393.598844) (xy 157.227583 -393.62833) (xy 157.177973 -393.650987) (xy 157.125643 -393.666352)
			(xy 157.071659 -393.674114) (xy 157.017121 -393.674114) (xy 156.963137 -393.666352) (xy 156.910807 -393.650987)
			(xy 156.861197 -393.62833) (xy 156.815316 -393.598844) (xy 156.774099 -393.563129) (xy 156.738384 -393.521912)
			(xy 156.708898 -393.476031) (xy 156.686241 -393.426421) (xy 156.670876 -393.374091) (xy 156.663114 -393.320107)
			(xy 156.662628 -393.292838) (xy 156.225748 -393.292838) (xy 156.225262 -393.320089) (xy 156.217506 -393.374037)
			(xy 156.202151 -393.426332) (xy 156.179509 -393.475909) (xy 156.150043 -393.521759) (xy 156.114352 -393.56295)
			(xy 156.073161 -393.598641) (xy 156.027311 -393.628107) (xy 155.977734 -393.650749) (xy 155.925439 -393.666104)
			(xy 155.871491 -393.67386) (xy 155.816989 -393.67386) (xy 155.763041 -393.666104) (xy 155.710746 -393.650749)
			(xy 155.661169 -393.628107) (xy 155.615319 -393.598641) (xy 155.574128 -393.56295) (xy 155.538437 -393.521759)
			(xy 155.508971 -393.475909) (xy 155.486329 -393.426332) (xy 155.470974 -393.374037) (xy 155.463218 -393.320089)
			(xy 155.462732 -393.292838) (xy 155.025852 -393.292838) (xy 155.025366 -393.320089) (xy 155.01761 -393.374037)
			(xy 155.002255 -393.426332) (xy 154.979613 -393.475909) (xy 154.950147 -393.521759) (xy 154.914456 -393.56295)
			(xy 154.873265 -393.598641) (xy 154.827415 -393.628107) (xy 154.777838 -393.650749) (xy 154.725543 -393.666104)
			(xy 154.671595 -393.67386) (xy 154.617093 -393.67386) (xy 154.563145 -393.666104) (xy 154.51085 -393.650749)
			(xy 154.461273 -393.628107) (xy 154.415423 -393.598641) (xy 154.374232 -393.56295) (xy 154.338541 -393.521759)
			(xy 154.309075 -393.475909) (xy 154.286433 -393.426332) (xy 154.271078 -393.374037) (xy 154.263322 -393.320089)
			(xy 154.262836 -393.292838) (xy 153.825956 -393.292838) (xy 153.82547 -393.320107) (xy 153.817708 -393.374091)
			(xy 153.802343 -393.426421) (xy 153.779686 -393.476031) (xy 153.7502 -393.521912) (xy 153.714485 -393.563129)
			(xy 153.673268 -393.598844) (xy 153.627387 -393.62833) (xy 153.577777 -393.650987) (xy 153.525447 -393.666352)
			(xy 153.471463 -393.674114) (xy 153.416925 -393.674114) (xy 153.362941 -393.666352) (xy 153.310611 -393.650987)
			(xy 153.261001 -393.62833) (xy 153.21512 -393.598844) (xy 153.173903 -393.563129) (xy 153.138188 -393.521912)
			(xy 153.108702 -393.476031) (xy 153.086045 -393.426421) (xy 153.07068 -393.374091) (xy 153.062918 -393.320107)
			(xy 153.062432 -393.292838) (xy 152.62606 -393.292838) (xy 152.625574 -393.320107) (xy 152.617812 -393.374091)
			(xy 152.602447 -393.426421) (xy 152.57979 -393.476031) (xy 152.550304 -393.521912) (xy 152.514589 -393.563129)
			(xy 152.473372 -393.598844) (xy 152.427491 -393.62833) (xy 152.377881 -393.650987) (xy 152.325551 -393.666352)
			(xy 152.271567 -393.674114) (xy 152.217029 -393.674114) (xy 152.163045 -393.666352) (xy 152.110715 -393.650987)
			(xy 152.061105 -393.62833) (xy 152.015224 -393.598844) (xy 151.974007 -393.563129) (xy 151.938292 -393.521912)
			(xy 151.908806 -393.476031) (xy 151.886149 -393.426421) (xy 151.870784 -393.374091) (xy 151.863022 -393.320107)
			(xy 151.862536 -393.292838) (xy 151.425656 -393.292838) (xy 151.42517 -393.320089) (xy 151.417414 -393.374037)
			(xy 151.402059 -393.426332) (xy 151.379417 -393.475909) (xy 151.349951 -393.521759) (xy 151.31426 -393.56295)
			(xy 151.273069 -393.598641) (xy 151.227219 -393.628107) (xy 151.177642 -393.650749) (xy 151.125347 -393.666104)
			(xy 151.071399 -393.67386) (xy 151.016897 -393.67386) (xy 150.962949 -393.666104) (xy 150.910654 -393.650749)
			(xy 150.861077 -393.628107) (xy 150.815227 -393.598641) (xy 150.774036 -393.56295) (xy 150.738345 -393.521759)
			(xy 150.708879 -393.475909) (xy 150.686237 -393.426332) (xy 150.670882 -393.374037) (xy 150.663126 -393.320089)
			(xy 150.66264 -393.292838) (xy 150.22576 -393.292838) (xy 150.225274 -393.320089) (xy 150.217518 -393.374037)
			(xy 150.202163 -393.426332) (xy 150.179521 -393.475909) (xy 150.150055 -393.521759) (xy 150.114364 -393.56295)
			(xy 150.073173 -393.598641) (xy 150.027323 -393.628107) (xy 149.977746 -393.650749) (xy 149.925451 -393.666104)
			(xy 149.871503 -393.67386) (xy 149.817001 -393.67386) (xy 149.763053 -393.666104) (xy 149.710758 -393.650749)
			(xy 149.661181 -393.628107) (xy 149.615331 -393.598641) (xy 149.57414 -393.56295) (xy 149.538449 -393.521759)
			(xy 149.508983 -393.475909) (xy 149.486341 -393.426332) (xy 149.470986 -393.374037) (xy 149.46323 -393.320089)
			(xy 149.462744 -393.292838) (xy 149.025864 -393.292838) (xy 149.025378 -393.320107) (xy 149.017616 -393.374091)
			(xy 149.002251 -393.426421) (xy 148.979594 -393.476031) (xy 148.950108 -393.521912) (xy 148.914393 -393.563129)
			(xy 148.873176 -393.598844) (xy 148.827295 -393.62833) (xy 148.777685 -393.650987) (xy 148.725355 -393.666352)
			(xy 148.671371 -393.674114) (xy 148.616833 -393.674114) (xy 148.562849 -393.666352) (xy 148.510519 -393.650987)
			(xy 148.460909 -393.62833) (xy 148.415028 -393.598844) (xy 148.373811 -393.563129) (xy 148.338096 -393.521912)
			(xy 148.30861 -393.476031) (xy 148.285953 -393.426421) (xy 148.270588 -393.374091) (xy 148.262826 -393.320107)
			(xy 148.26234 -393.292838) (xy 147.825968 -393.292838) (xy 147.825482 -393.320107) (xy 147.81772 -393.374091)
			(xy 147.802355 -393.426421) (xy 147.779698 -393.476031) (xy 147.750212 -393.521912) (xy 147.714497 -393.563129)
			(xy 147.67328 -393.598844) (xy 147.627399 -393.62833) (xy 147.577789 -393.650987) (xy 147.525459 -393.666352)
			(xy 147.471475 -393.674114) (xy 147.416937 -393.674114) (xy 147.362953 -393.666352) (xy 147.310623 -393.650987)
			(xy 147.261013 -393.62833) (xy 147.215132 -393.598844) (xy 147.173915 -393.563129) (xy 147.1382 -393.521912)
			(xy 147.108714 -393.476031) (xy 147.086057 -393.426421) (xy 147.070692 -393.374091) (xy 147.06293 -393.320107)
			(xy 147.062444 -393.292838) (xy 133.298184 -393.292838) (xy 133.297698 -393.320107) (xy 133.289936 -393.374091)
			(xy 133.274571 -393.426421) (xy 133.251914 -393.476031) (xy 133.222428 -393.521912) (xy 133.186713 -393.563129)
			(xy 133.145496 -393.598844) (xy 133.099615 -393.62833) (xy 133.050005 -393.650987) (xy 132.997675 -393.666352)
			(xy 132.943691 -393.674114) (xy 132.889153 -393.674114) (xy 132.835169 -393.666352) (xy 132.782839 -393.650987)
			(xy 132.733229 -393.62833) (xy 132.687348 -393.598844) (xy 132.646131 -393.563129) (xy 132.610416 -393.521912)
			(xy 132.58093 -393.476031) (xy 132.558273 -393.426421) (xy 132.542908 -393.374091) (xy 132.535146 -393.320107)
			(xy 132.53466 -393.292838) (xy 132.098288 -393.292838) (xy 132.097802 -393.320107) (xy 132.09004 -393.374091)
			(xy 132.074675 -393.426421) (xy 132.052018 -393.476031) (xy 132.022532 -393.521912) (xy 131.986817 -393.563129)
			(xy 131.9456 -393.598844) (xy 131.899719 -393.62833) (xy 131.850109 -393.650987) (xy 131.797779 -393.666352)
			(xy 131.743795 -393.674114) (xy 131.689257 -393.674114) (xy 131.635273 -393.666352) (xy 131.582943 -393.650987)
			(xy 131.533333 -393.62833) (xy 131.487452 -393.598844) (xy 131.446235 -393.563129) (xy 131.41052 -393.521912)
			(xy 131.381034 -393.476031) (xy 131.358377 -393.426421) (xy 131.343012 -393.374091) (xy 131.33525 -393.320107)
			(xy 131.334764 -393.292838) (xy 130.897884 -393.292838) (xy 130.897398 -393.320089) (xy 130.889642 -393.374037)
			(xy 130.874287 -393.426332) (xy 130.851645 -393.475909) (xy 130.822179 -393.521759) (xy 130.786488 -393.56295)
			(xy 130.745297 -393.598641) (xy 130.699447 -393.628107) (xy 130.64987 -393.650749) (xy 130.597575 -393.666104)
			(xy 130.543627 -393.67386) (xy 130.489125 -393.67386) (xy 130.435177 -393.666104) (xy 130.382882 -393.650749)
			(xy 130.333305 -393.628107) (xy 130.287455 -393.598641) (xy 130.246264 -393.56295) (xy 130.210573 -393.521759)
			(xy 130.181107 -393.475909) (xy 130.158465 -393.426332) (xy 130.14311 -393.374037) (xy 130.135354 -393.320089)
			(xy 130.134868 -393.292838) (xy 129.697988 -393.292838) (xy 129.697502 -393.320089) (xy 129.689746 -393.374037)
			(xy 129.674391 -393.426332) (xy 129.651749 -393.475909) (xy 129.622283 -393.521759) (xy 129.586592 -393.56295)
			(xy 129.545401 -393.598641) (xy 129.499551 -393.628107) (xy 129.449974 -393.650749) (xy 129.397679 -393.666104)
			(xy 129.343731 -393.67386) (xy 129.289229 -393.67386) (xy 129.235281 -393.666104) (xy 129.182986 -393.650749)
			(xy 129.133409 -393.628107) (xy 129.087559 -393.598641) (xy 129.046368 -393.56295) (xy 129.010677 -393.521759)
			(xy 128.981211 -393.475909) (xy 128.958569 -393.426332) (xy 128.943214 -393.374037) (xy 128.935458 -393.320089)
			(xy 128.934972 -393.292838) (xy 128.498092 -393.292838) (xy 128.497606 -393.320089) (xy 128.48985 -393.374037)
			(xy 128.474495 -393.426332) (xy 128.451853 -393.475909) (xy 128.422387 -393.521759) (xy 128.386696 -393.56295)
			(xy 128.345505 -393.598641) (xy 128.299655 -393.628107) (xy 128.250078 -393.650749) (xy 128.197783 -393.666104)
			(xy 128.143835 -393.67386) (xy 128.089333 -393.67386) (xy 128.035385 -393.666104) (xy 127.98309 -393.650749)
			(xy 127.933513 -393.628107) (xy 127.887663 -393.598641) (xy 127.846472 -393.56295) (xy 127.810781 -393.521759)
			(xy 127.781315 -393.475909) (xy 127.758673 -393.426332) (xy 127.743318 -393.374037) (xy 127.735562 -393.320089)
			(xy 127.735076 -393.292838) (xy 127.298196 -393.292838) (xy 127.29771 -393.320089) (xy 127.289954 -393.374037)
			(xy 127.274599 -393.426332) (xy 127.251957 -393.475909) (xy 127.222491 -393.521759) (xy 127.1868 -393.56295)
			(xy 127.145609 -393.598641) (xy 127.099759 -393.628107) (xy 127.050182 -393.650749) (xy 126.997887 -393.666104)
			(xy 126.943939 -393.67386) (xy 126.889437 -393.67386) (xy 126.835489 -393.666104) (xy 126.783194 -393.650749)
			(xy 126.733617 -393.628107) (xy 126.687767 -393.598641) (xy 126.646576 -393.56295) (xy 126.610885 -393.521759)
			(xy 126.581419 -393.475909) (xy 126.558777 -393.426332) (xy 126.543422 -393.374037) (xy 126.535666 -393.320089)
			(xy 126.53518 -393.292838) (xy 126.0983 -393.292838) (xy 126.097814 -393.320107) (xy 126.090052 -393.374091)
			(xy 126.074687 -393.426421) (xy 126.05203 -393.476031) (xy 126.022544 -393.521912) (xy 125.986829 -393.563129)
			(xy 125.945612 -393.598844) (xy 125.899731 -393.62833) (xy 125.850121 -393.650987) (xy 125.797791 -393.666352)
			(xy 125.743807 -393.674114) (xy 125.689269 -393.674114) (xy 125.635285 -393.666352) (xy 125.582955 -393.650987)
			(xy 125.533345 -393.62833) (xy 125.487464 -393.598844) (xy 125.446247 -393.563129) (xy 125.410532 -393.521912)
			(xy 125.381046 -393.476031) (xy 125.358389 -393.426421) (xy 125.343024 -393.374091) (xy 125.335262 -393.320107)
			(xy 125.334776 -393.292838) (xy 124.898404 -393.292838) (xy 124.897918 -393.320107) (xy 124.890156 -393.374091)
			(xy 124.874791 -393.426421) (xy 124.852134 -393.476031) (xy 124.822648 -393.521912) (xy 124.786933 -393.563129)
			(xy 124.745716 -393.598844) (xy 124.699835 -393.62833) (xy 124.650225 -393.650987) (xy 124.597895 -393.666352)
			(xy 124.543911 -393.674114) (xy 124.489373 -393.674114) (xy 124.435389 -393.666352) (xy 124.383059 -393.650987)
			(xy 124.333449 -393.62833) (xy 124.287568 -393.598844) (xy 124.246351 -393.563129) (xy 124.210636 -393.521912)
			(xy 124.18115 -393.476031) (xy 124.158493 -393.426421) (xy 124.143128 -393.374091) (xy 124.135366 -393.320107)
			(xy 124.13488 -393.292838) (xy 123.698 -393.292838) (xy 123.697514 -393.320089) (xy 123.689758 -393.374037)
			(xy 123.674403 -393.426332) (xy 123.651761 -393.475909) (xy 123.622295 -393.521759) (xy 123.586604 -393.56295)
			(xy 123.545413 -393.598641) (xy 123.499563 -393.628107) (xy 123.449986 -393.650749) (xy 123.397691 -393.666104)
			(xy 123.343743 -393.67386) (xy 123.289241 -393.67386) (xy 123.235293 -393.666104) (xy 123.182998 -393.650749)
			(xy 123.133421 -393.628107) (xy 123.087571 -393.598641) (xy 123.04638 -393.56295) (xy 123.010689 -393.521759)
			(xy 122.981223 -393.475909) (xy 122.958581 -393.426332) (xy 122.943226 -393.374037) (xy 122.93547 -393.320089)
			(xy 122.934984 -393.292838) (xy 122.498104 -393.292838) (xy 122.497618 -393.320089) (xy 122.489862 -393.374037)
			(xy 122.474507 -393.426332) (xy 122.451865 -393.475909) (xy 122.422399 -393.521759) (xy 122.386708 -393.56295)
			(xy 122.345517 -393.598641) (xy 122.299667 -393.628107) (xy 122.25009 -393.650749) (xy 122.197795 -393.666104)
			(xy 122.143847 -393.67386) (xy 122.089345 -393.67386) (xy 122.035397 -393.666104) (xy 121.983102 -393.650749)
			(xy 121.933525 -393.628107) (xy 121.887675 -393.598641) (xy 121.846484 -393.56295) (xy 121.810793 -393.521759)
			(xy 121.781327 -393.475909) (xy 121.758685 -393.426332) (xy 121.74333 -393.374037) (xy 121.735574 -393.320089)
			(xy 121.735088 -393.292838) (xy 121.298208 -393.292838) (xy 121.297722 -393.320107) (xy 121.28996 -393.374091)
			(xy 121.274595 -393.426421) (xy 121.251938 -393.476031) (xy 121.222452 -393.521912) (xy 121.186737 -393.563129)
			(xy 121.14552 -393.598844) (xy 121.099639 -393.62833) (xy 121.050029 -393.650987) (xy 120.997699 -393.666352)
			(xy 120.943715 -393.674114) (xy 120.889177 -393.674114) (xy 120.835193 -393.666352) (xy 120.782863 -393.650987)
			(xy 120.733253 -393.62833) (xy 120.687372 -393.598844) (xy 120.646155 -393.563129) (xy 120.61044 -393.521912)
			(xy 120.580954 -393.476031) (xy 120.558297 -393.426421) (xy 120.542932 -393.374091) (xy 120.53517 -393.320107)
			(xy 120.534684 -393.292838) (xy 120.098312 -393.292838) (xy 120.097826 -393.320107) (xy 120.090064 -393.374091)
			(xy 120.074699 -393.426421) (xy 120.052042 -393.476031) (xy 120.022556 -393.521912) (xy 119.986841 -393.563129)
			(xy 119.945624 -393.598844) (xy 119.899743 -393.62833) (xy 119.850133 -393.650987) (xy 119.797803 -393.666352)
			(xy 119.743819 -393.674114) (xy 119.689281 -393.674114) (xy 119.635297 -393.666352) (xy 119.582967 -393.650987)
			(xy 119.533357 -393.62833) (xy 119.487476 -393.598844) (xy 119.446259 -393.563129) (xy 119.410544 -393.521912)
			(xy 119.381058 -393.476031) (xy 119.358401 -393.426421) (xy 119.343036 -393.374091) (xy 119.335274 -393.320107)
			(xy 119.334788 -393.292838) (xy 118.897908 -393.292838) (xy 118.897422 -393.320089) (xy 118.889666 -393.374037)
			(xy 118.874311 -393.426332) (xy 118.851669 -393.475909) (xy 118.822203 -393.521759) (xy 118.786512 -393.56295)
			(xy 118.745321 -393.598641) (xy 118.699471 -393.628107) (xy 118.649894 -393.650749) (xy 118.597599 -393.666104)
			(xy 118.543651 -393.67386) (xy 118.489149 -393.67386) (xy 118.435201 -393.666104) (xy 118.382906 -393.650749)
			(xy 118.333329 -393.628107) (xy 118.287479 -393.598641) (xy 118.246288 -393.56295) (xy 118.210597 -393.521759)
			(xy 118.181131 -393.475909) (xy 118.158489 -393.426332) (xy 118.143134 -393.374037) (xy 118.135378 -393.320089)
			(xy 118.134892 -393.292838) (xy 117.698012 -393.292838) (xy 117.697526 -393.320089) (xy 117.68977 -393.374037)
			(xy 117.674415 -393.426332) (xy 117.651773 -393.475909) (xy 117.622307 -393.521759) (xy 117.586616 -393.56295)
			(xy 117.545425 -393.598641) (xy 117.499575 -393.628107) (xy 117.449998 -393.650749) (xy 117.397703 -393.666104)
			(xy 117.343755 -393.67386) (xy 117.289253 -393.67386) (xy 117.235305 -393.666104) (xy 117.18301 -393.650749)
			(xy 117.133433 -393.628107) (xy 117.087583 -393.598641) (xy 117.046392 -393.56295) (xy 117.010701 -393.521759)
			(xy 116.981235 -393.475909) (xy 116.958593 -393.426332) (xy 116.943238 -393.374037) (xy 116.935482 -393.320089)
			(xy 116.934996 -393.292838) (xy 116.498116 -393.292838) (xy 116.49763 -393.320107) (xy 116.489868 -393.374091)
			(xy 116.474503 -393.426421) (xy 116.451846 -393.476031) (xy 116.42236 -393.521912) (xy 116.386645 -393.563129)
			(xy 116.345428 -393.598844) (xy 116.299547 -393.62833) (xy 116.249937 -393.650987) (xy 116.197607 -393.666352)
			(xy 116.143623 -393.674114) (xy 116.089085 -393.674114) (xy 116.035101 -393.666352) (xy 115.982771 -393.650987)
			(xy 115.933161 -393.62833) (xy 115.88728 -393.598844) (xy 115.846063 -393.563129) (xy 115.810348 -393.521912)
			(xy 115.780862 -393.476031) (xy 115.758205 -393.426421) (xy 115.74284 -393.374091) (xy 115.735078 -393.320107)
			(xy 115.734592 -393.292838) (xy 115.29822 -393.292838) (xy 115.297734 -393.320107) (xy 115.289972 -393.374091)
			(xy 115.274607 -393.426421) (xy 115.25195 -393.476031) (xy 115.222464 -393.521912) (xy 115.186749 -393.563129)
			(xy 115.145532 -393.598844) (xy 115.099651 -393.62833) (xy 115.050041 -393.650987) (xy 114.997711 -393.666352)
			(xy 114.943727 -393.674114) (xy 114.889189 -393.674114) (xy 114.835205 -393.666352) (xy 114.782875 -393.650987)
			(xy 114.733265 -393.62833) (xy 114.687384 -393.598844) (xy 114.646167 -393.563129) (xy 114.610452 -393.521912)
			(xy 114.580966 -393.476031) (xy 114.558309 -393.426421) (xy 114.542944 -393.374091) (xy 114.535182 -393.320107)
			(xy 114.534696 -393.292838) (xy 98.725736 -393.292838) (xy 98.72525 -393.320089) (xy 98.717494 -393.374037)
			(xy 98.702139 -393.426332) (xy 98.679497 -393.475909) (xy 98.650031 -393.521759) (xy 98.61434 -393.56295)
			(xy 98.573149 -393.598641) (xy 98.527299 -393.628107) (xy 98.477722 -393.650749) (xy 98.425427 -393.666104)
			(xy 98.371479 -393.67386) (xy 98.316977 -393.67386) (xy 98.263029 -393.666104) (xy 98.210734 -393.650749)
			(xy 98.161157 -393.628107) (xy 98.115307 -393.598641) (xy 98.074116 -393.56295) (xy 98.038425 -393.521759)
			(xy 98.008959 -393.475909) (xy 97.986317 -393.426332) (xy 97.970962 -393.374037) (xy 97.963206 -393.320089)
			(xy 97.96272 -393.292838) (xy 97.52584 -393.292838) (xy 97.525354 -393.320089) (xy 97.517598 -393.374037)
			(xy 97.502243 -393.426332) (xy 97.479601 -393.475909) (xy 97.450135 -393.521759) (xy 97.414444 -393.56295)
			(xy 97.373253 -393.598641) (xy 97.327403 -393.628107) (xy 97.277826 -393.650749) (xy 97.225531 -393.666104)
			(xy 97.171583 -393.67386) (xy 97.117081 -393.67386) (xy 97.063133 -393.666104) (xy 97.010838 -393.650749)
			(xy 96.961261 -393.628107) (xy 96.915411 -393.598641) (xy 96.87422 -393.56295) (xy 96.838529 -393.521759)
			(xy 96.809063 -393.475909) (xy 96.786421 -393.426332) (xy 96.771066 -393.374037) (xy 96.76331 -393.320089)
			(xy 96.762824 -393.292838) (xy 96.325944 -393.292838) (xy 96.325458 -393.320107) (xy 96.317696 -393.374091)
			(xy 96.302331 -393.426421) (xy 96.279674 -393.476031) (xy 96.250188 -393.521912) (xy 96.214473 -393.563129)
			(xy 96.173256 -393.598844) (xy 96.127375 -393.62833) (xy 96.077765 -393.650987) (xy 96.025435 -393.666352)
			(xy 95.971451 -393.674114) (xy 95.916913 -393.674114) (xy 95.862929 -393.666352) (xy 95.810599 -393.650987)
			(xy 95.760989 -393.62833) (xy 95.715108 -393.598844) (xy 95.673891 -393.563129) (xy 95.638176 -393.521912)
			(xy 95.60869 -393.476031) (xy 95.586033 -393.426421) (xy 95.570668 -393.374091) (xy 95.562906 -393.320107)
			(xy 95.56242 -393.292838) (xy 95.126048 -393.292838) (xy 95.125562 -393.320107) (xy 95.1178 -393.374091)
			(xy 95.102435 -393.426421) (xy 95.079778 -393.476031) (xy 95.050292 -393.521912) (xy 95.014577 -393.563129)
			(xy 94.97336 -393.598844) (xy 94.927479 -393.62833) (xy 94.877869 -393.650987) (xy 94.825539 -393.666352)
			(xy 94.771555 -393.674114) (xy 94.717017 -393.674114) (xy 94.663033 -393.666352) (xy 94.610703 -393.650987)
			(xy 94.561093 -393.62833) (xy 94.515212 -393.598844) (xy 94.473995 -393.563129) (xy 94.43828 -393.521912)
			(xy 94.408794 -393.476031) (xy 94.386137 -393.426421) (xy 94.370772 -393.374091) (xy 94.36301 -393.320107)
			(xy 94.362524 -393.292838) (xy 93.926152 -393.292838) (xy 93.925666 -393.320107) (xy 93.917904 -393.374091)
			(xy 93.902539 -393.426421) (xy 93.879882 -393.476031) (xy 93.850396 -393.521912) (xy 93.814681 -393.563129)
			(xy 93.773464 -393.598844) (xy 93.727583 -393.62833) (xy 93.677973 -393.650987) (xy 93.625643 -393.666352)
			(xy 93.571659 -393.674114) (xy 93.517121 -393.674114) (xy 93.463137 -393.666352) (xy 93.410807 -393.650987)
			(xy 93.361197 -393.62833) (xy 93.315316 -393.598844) (xy 93.274099 -393.563129) (xy 93.238384 -393.521912)
			(xy 93.208898 -393.476031) (xy 93.186241 -393.426421) (xy 93.170876 -393.374091) (xy 93.163114 -393.320107)
			(xy 93.162628 -393.292838) (xy 92.726256 -393.292838) (xy 92.72577 -393.320107) (xy 92.718008 -393.374091)
			(xy 92.702643 -393.426421) (xy 92.679986 -393.476031) (xy 92.6505 -393.521912) (xy 92.614785 -393.563129)
			(xy 92.573568 -393.598844) (xy 92.527687 -393.62833) (xy 92.478077 -393.650987) (xy 92.425747 -393.666352)
			(xy 92.371763 -393.674114) (xy 92.317225 -393.674114) (xy 92.263241 -393.666352) (xy 92.210911 -393.650987)
			(xy 92.161301 -393.62833) (xy 92.11542 -393.598844) (xy 92.074203 -393.563129) (xy 92.038488 -393.521912)
			(xy 92.009002 -393.476031) (xy 91.986345 -393.426421) (xy 91.97098 -393.374091) (xy 91.963218 -393.320107)
			(xy 91.962732 -393.292838) (xy 91.525852 -393.292838) (xy 91.525366 -393.320089) (xy 91.51761 -393.374037)
			(xy 91.502255 -393.426332) (xy 91.479613 -393.475909) (xy 91.450147 -393.521759) (xy 91.414456 -393.56295)
			(xy 91.373265 -393.598641) (xy 91.327415 -393.628107) (xy 91.277838 -393.650749) (xy 91.225543 -393.666104)
			(xy 91.171595 -393.67386) (xy 91.117093 -393.67386) (xy 91.063145 -393.666104) (xy 91.01085 -393.650749)
			(xy 90.961273 -393.628107) (xy 90.915423 -393.598641) (xy 90.874232 -393.56295) (xy 90.838541 -393.521759)
			(xy 90.809075 -393.475909) (xy 90.786433 -393.426332) (xy 90.771078 -393.374037) (xy 90.763322 -393.320089)
			(xy 90.762836 -393.292838) (xy 90.325956 -393.292838) (xy 90.32547 -393.320089) (xy 90.317714 -393.374037)
			(xy 90.302359 -393.426332) (xy 90.279717 -393.475909) (xy 90.250251 -393.521759) (xy 90.21456 -393.56295)
			(xy 90.173369 -393.598641) (xy 90.127519 -393.628107) (xy 90.077942 -393.650749) (xy 90.025647 -393.666104)
			(xy 89.971699 -393.67386) (xy 89.917197 -393.67386) (xy 89.863249 -393.666104) (xy 89.810954 -393.650749)
			(xy 89.761377 -393.628107) (xy 89.715527 -393.598641) (xy 89.674336 -393.56295) (xy 89.638645 -393.521759)
			(xy 89.609179 -393.475909) (xy 89.586537 -393.426332) (xy 89.571182 -393.374037) (xy 89.563426 -393.320089)
			(xy 89.56294 -393.292838) (xy 89.12606 -393.292838) (xy 89.125574 -393.320107) (xy 89.117812 -393.374091)
			(xy 89.102447 -393.426421) (xy 89.07979 -393.476031) (xy 89.050304 -393.521912) (xy 89.014589 -393.563129)
			(xy 88.973372 -393.598844) (xy 88.927491 -393.62833) (xy 88.877881 -393.650987) (xy 88.825551 -393.666352)
			(xy 88.771567 -393.674114) (xy 88.717029 -393.674114) (xy 88.663045 -393.666352) (xy 88.610715 -393.650987)
			(xy 88.561105 -393.62833) (xy 88.515224 -393.598844) (xy 88.474007 -393.563129) (xy 88.438292 -393.521912)
			(xy 88.408806 -393.476031) (xy 88.386149 -393.426421) (xy 88.370784 -393.374091) (xy 88.363022 -393.320107)
			(xy 88.362536 -393.292838) (xy 87.926164 -393.292838) (xy 87.925678 -393.320107) (xy 87.917916 -393.374091)
			(xy 87.902551 -393.426421) (xy 87.879894 -393.476031) (xy 87.850408 -393.521912) (xy 87.814693 -393.563129)
			(xy 87.773476 -393.598844) (xy 87.727595 -393.62833) (xy 87.677985 -393.650987) (xy 87.625655 -393.666352)
			(xy 87.571671 -393.674114) (xy 87.517133 -393.674114) (xy 87.463149 -393.666352) (xy 87.410819 -393.650987)
			(xy 87.361209 -393.62833) (xy 87.315328 -393.598844) (xy 87.274111 -393.563129) (xy 87.238396 -393.521912)
			(xy 87.20891 -393.476031) (xy 87.186253 -393.426421) (xy 87.170888 -393.374091) (xy 87.163126 -393.320107)
			(xy 87.16264 -393.292838) (xy 86.72576 -393.292838) (xy 86.725274 -393.320089) (xy 86.717518 -393.374037)
			(xy 86.702163 -393.426332) (xy 86.679521 -393.475909) (xy 86.650055 -393.521759) (xy 86.614364 -393.56295)
			(xy 86.573173 -393.598641) (xy 86.527323 -393.628107) (xy 86.477746 -393.650749) (xy 86.425451 -393.666104)
			(xy 86.371503 -393.67386) (xy 86.317001 -393.67386) (xy 86.263053 -393.666104) (xy 86.210758 -393.650749)
			(xy 86.161181 -393.628107) (xy 86.115331 -393.598641) (xy 86.07414 -393.56295) (xy 86.038449 -393.521759)
			(xy 86.008983 -393.475909) (xy 85.986341 -393.426332) (xy 85.970986 -393.374037) (xy 85.96323 -393.320089)
			(xy 85.962744 -393.292838) (xy 85.525864 -393.292838) (xy 85.525378 -393.320089) (xy 85.517622 -393.374037)
			(xy 85.502267 -393.426332) (xy 85.479625 -393.475909) (xy 85.450159 -393.521759) (xy 85.414468 -393.56295)
			(xy 85.373277 -393.598641) (xy 85.327427 -393.628107) (xy 85.27785 -393.650749) (xy 85.225555 -393.666104)
			(xy 85.171607 -393.67386) (xy 85.117105 -393.67386) (xy 85.063157 -393.666104) (xy 85.010862 -393.650749)
			(xy 84.961285 -393.628107) (xy 84.915435 -393.598641) (xy 84.874244 -393.56295) (xy 84.838553 -393.521759)
			(xy 84.809087 -393.475909) (xy 84.786445 -393.426332) (xy 84.77109 -393.374037) (xy 84.763334 -393.320089)
			(xy 84.762848 -393.292838) (xy 84.325968 -393.292838) (xy 84.325482 -393.320107) (xy 84.31772 -393.374091)
			(xy 84.302355 -393.426421) (xy 84.279698 -393.476031) (xy 84.250212 -393.521912) (xy 84.214497 -393.563129)
			(xy 84.17328 -393.598844) (xy 84.127399 -393.62833) (xy 84.077789 -393.650987) (xy 84.025459 -393.666352)
			(xy 83.971475 -393.674114) (xy 83.916937 -393.674114) (xy 83.862953 -393.666352) (xy 83.810623 -393.650987)
			(xy 83.761013 -393.62833) (xy 83.715132 -393.598844) (xy 83.673915 -393.563129) (xy 83.6382 -393.521912)
			(xy 83.608714 -393.476031) (xy 83.586057 -393.426421) (xy 83.570692 -393.374091) (xy 83.56293 -393.320107)
			(xy 83.562444 -393.292838) (xy 83.126072 -393.292838) (xy 83.125586 -393.320107) (xy 83.117824 -393.374091)
			(xy 83.102459 -393.426421) (xy 83.079802 -393.476031) (xy 83.050316 -393.521912) (xy 83.014601 -393.563129)
			(xy 82.973384 -393.598844) (xy 82.927503 -393.62833) (xy 82.877893 -393.650987) (xy 82.825563 -393.666352)
			(xy 82.771579 -393.674114) (xy 82.717041 -393.674114) (xy 82.663057 -393.666352) (xy 82.610727 -393.650987)
			(xy 82.561117 -393.62833) (xy 82.515236 -393.598844) (xy 82.474019 -393.563129) (xy 82.438304 -393.521912)
			(xy 82.408818 -393.476031) (xy 82.386161 -393.426421) (xy 82.370796 -393.374091) (xy 82.363034 -393.320107)
			(xy 82.362548 -393.292838) (xy 81.925668 -393.292838) (xy 81.925182 -393.320089) (xy 81.917426 -393.374037)
			(xy 81.902071 -393.426332) (xy 81.879429 -393.475909) (xy 81.849963 -393.521759) (xy 81.814272 -393.56295)
			(xy 81.773081 -393.598641) (xy 81.727231 -393.628107) (xy 81.677654 -393.650749) (xy 81.625359 -393.666104)
			(xy 81.571411 -393.67386) (xy 81.516909 -393.67386) (xy 81.462961 -393.666104) (xy 81.410666 -393.650749)
			(xy 81.361089 -393.628107) (xy 81.315239 -393.598641) (xy 81.274048 -393.56295) (xy 81.238357 -393.521759)
			(xy 81.208891 -393.475909) (xy 81.186249 -393.426332) (xy 81.170894 -393.374037) (xy 81.163138 -393.320089)
			(xy 81.162652 -393.292838) (xy 80.725772 -393.292838) (xy 80.725286 -393.320089) (xy 80.71753 -393.374037)
			(xy 80.702175 -393.426332) (xy 80.679533 -393.475909) (xy 80.650067 -393.521759) (xy 80.614376 -393.56295)
			(xy 80.573185 -393.598641) (xy 80.527335 -393.628107) (xy 80.477758 -393.650749) (xy 80.425463 -393.666104)
			(xy 80.371515 -393.67386) (xy 80.317013 -393.67386) (xy 80.263065 -393.666104) (xy 80.21077 -393.650749)
			(xy 80.161193 -393.628107) (xy 80.115343 -393.598641) (xy 80.074152 -393.56295) (xy 80.038461 -393.521759)
			(xy 80.008995 -393.475909) (xy 79.986353 -393.426332) (xy 79.970998 -393.374037) (xy 79.963242 -393.320089)
			(xy 79.962756 -393.292838) (xy 66.197988 -393.292838) (xy 66.197502 -393.320089) (xy 66.189746 -393.374037)
			(xy 66.174391 -393.426332) (xy 66.151749 -393.475909) (xy 66.122283 -393.521759) (xy 66.086592 -393.56295)
			(xy 66.045401 -393.598641) (xy 65.999551 -393.628107) (xy 65.949974 -393.650749) (xy 65.897679 -393.666104)
			(xy 65.843731 -393.67386) (xy 65.789229 -393.67386) (xy 65.735281 -393.666104) (xy 65.682986 -393.650749)
			(xy 65.633409 -393.628107) (xy 65.587559 -393.598641) (xy 65.546368 -393.56295) (xy 65.510677 -393.521759)
			(xy 65.481211 -393.475909) (xy 65.458569 -393.426332) (xy 65.443214 -393.374037) (xy 65.435458 -393.320089)
			(xy 65.434972 -393.292838) (xy 64.998092 -393.292838) (xy 64.997606 -393.320089) (xy 64.98985 -393.374037)
			(xy 64.974495 -393.426332) (xy 64.951853 -393.475909) (xy 64.922387 -393.521759) (xy 64.886696 -393.56295)
			(xy 64.845505 -393.598641) (xy 64.799655 -393.628107) (xy 64.750078 -393.650749) (xy 64.697783 -393.666104)
			(xy 64.643835 -393.67386) (xy 64.589333 -393.67386) (xy 64.535385 -393.666104) (xy 64.48309 -393.650749)
			(xy 64.433513 -393.628107) (xy 64.387663 -393.598641) (xy 64.346472 -393.56295) (xy 64.310781 -393.521759)
			(xy 64.281315 -393.475909) (xy 64.258673 -393.426332) (xy 64.243318 -393.374037) (xy 64.235562 -393.320089)
			(xy 64.235076 -393.292838) (xy 63.798196 -393.292838) (xy 63.79771 -393.320107) (xy 63.789948 -393.374091)
			(xy 63.774583 -393.426421) (xy 63.751926 -393.476031) (xy 63.72244 -393.521912) (xy 63.686725 -393.563129)
			(xy 63.645508 -393.598844) (xy 63.599627 -393.62833) (xy 63.550017 -393.650987) (xy 63.497687 -393.666352)
			(xy 63.443703 -393.674114) (xy 63.389165 -393.674114) (xy 63.335181 -393.666352) (xy 63.282851 -393.650987)
			(xy 63.233241 -393.62833) (xy 63.18736 -393.598844) (xy 63.146143 -393.563129) (xy 63.110428 -393.521912)
			(xy 63.080942 -393.476031) (xy 63.058285 -393.426421) (xy 63.04292 -393.374091) (xy 63.035158 -393.320107)
			(xy 63.034672 -393.292838) (xy 62.5983 -393.292838) (xy 62.597814 -393.320107) (xy 62.590052 -393.374091)
			(xy 62.574687 -393.426421) (xy 62.55203 -393.476031) (xy 62.522544 -393.521912) (xy 62.486829 -393.563129)
			(xy 62.445612 -393.598844) (xy 62.399731 -393.62833) (xy 62.350121 -393.650987) (xy 62.297791 -393.666352)
			(xy 62.243807 -393.674114) (xy 62.189269 -393.674114) (xy 62.135285 -393.666352) (xy 62.082955 -393.650987)
			(xy 62.033345 -393.62833) (xy 61.987464 -393.598844) (xy 61.946247 -393.563129) (xy 61.910532 -393.521912)
			(xy 61.881046 -393.476031) (xy 61.858389 -393.426421) (xy 61.843024 -393.374091) (xy 61.835262 -393.320107)
			(xy 61.834776 -393.292838) (xy 61.398404 -393.292838) (xy 61.397918 -393.320107) (xy 61.390156 -393.374091)
			(xy 61.374791 -393.426421) (xy 61.352134 -393.476031) (xy 61.322648 -393.521912) (xy 61.286933 -393.563129)
			(xy 61.245716 -393.598844) (xy 61.199835 -393.62833) (xy 61.150225 -393.650987) (xy 61.097895 -393.666352)
			(xy 61.043911 -393.674114) (xy 60.989373 -393.674114) (xy 60.935389 -393.666352) (xy 60.883059 -393.650987)
			(xy 60.833449 -393.62833) (xy 60.787568 -393.598844) (xy 60.746351 -393.563129) (xy 60.710636 -393.521912)
			(xy 60.68115 -393.476031) (xy 60.658493 -393.426421) (xy 60.643128 -393.374091) (xy 60.635366 -393.320107)
			(xy 60.63488 -393.292838) (xy 60.198508 -393.292838) (xy 60.198022 -393.320107) (xy 60.19026 -393.374091)
			(xy 60.174895 -393.426421) (xy 60.152238 -393.476031) (xy 60.122752 -393.521912) (xy 60.087037 -393.563129)
			(xy 60.04582 -393.598844) (xy 59.999939 -393.62833) (xy 59.950329 -393.650987) (xy 59.897999 -393.666352)
			(xy 59.844015 -393.674114) (xy 59.789477 -393.674114) (xy 59.735493 -393.666352) (xy 59.683163 -393.650987)
			(xy 59.633553 -393.62833) (xy 59.587672 -393.598844) (xy 59.546455 -393.563129) (xy 59.51074 -393.521912)
			(xy 59.481254 -393.476031) (xy 59.458597 -393.426421) (xy 59.443232 -393.374091) (xy 59.43547 -393.320107)
			(xy 59.434984 -393.292838) (xy 58.998104 -393.292838) (xy 58.997618 -393.320089) (xy 58.989862 -393.374037)
			(xy 58.974507 -393.426332) (xy 58.951865 -393.475909) (xy 58.922399 -393.521759) (xy 58.886708 -393.56295)
			(xy 58.845517 -393.598641) (xy 58.799667 -393.628107) (xy 58.75009 -393.650749) (xy 58.697795 -393.666104)
			(xy 58.643847 -393.67386) (xy 58.589345 -393.67386) (xy 58.535397 -393.666104) (xy 58.483102 -393.650749)
			(xy 58.433525 -393.628107) (xy 58.387675 -393.598641) (xy 58.346484 -393.56295) (xy 58.310793 -393.521759)
			(xy 58.281327 -393.475909) (xy 58.258685 -393.426332) (xy 58.24333 -393.374037) (xy 58.235574 -393.320089)
			(xy 58.235088 -393.292838) (xy 57.798208 -393.292838) (xy 57.797722 -393.320089) (xy 57.789966 -393.374037)
			(xy 57.774611 -393.426332) (xy 57.751969 -393.475909) (xy 57.722503 -393.521759) (xy 57.686812 -393.56295)
			(xy 57.645621 -393.598641) (xy 57.599771 -393.628107) (xy 57.550194 -393.650749) (xy 57.497899 -393.666104)
			(xy 57.443951 -393.67386) (xy 57.389449 -393.67386) (xy 57.335501 -393.666104) (xy 57.283206 -393.650749)
			(xy 57.233629 -393.628107) (xy 57.187779 -393.598641) (xy 57.146588 -393.56295) (xy 57.110897 -393.521759)
			(xy 57.081431 -393.475909) (xy 57.058789 -393.426332) (xy 57.043434 -393.374037) (xy 57.035678 -393.320089)
			(xy 57.035192 -393.292838) (xy 56.598312 -393.292838) (xy 56.597826 -393.320107) (xy 56.590064 -393.374091)
			(xy 56.574699 -393.426421) (xy 56.552042 -393.476031) (xy 56.522556 -393.521912) (xy 56.486841 -393.563129)
			(xy 56.445624 -393.598844) (xy 56.399743 -393.62833) (xy 56.350133 -393.650987) (xy 56.297803 -393.666352)
			(xy 56.243819 -393.674114) (xy 56.189281 -393.674114) (xy 56.135297 -393.666352) (xy 56.082967 -393.650987)
			(xy 56.033357 -393.62833) (xy 55.987476 -393.598844) (xy 55.946259 -393.563129) (xy 55.910544 -393.521912)
			(xy 55.881058 -393.476031) (xy 55.858401 -393.426421) (xy 55.843036 -393.374091) (xy 55.835274 -393.320107)
			(xy 55.834788 -393.292838) (xy 55.398416 -393.292838) (xy 55.39793 -393.320107) (xy 55.390168 -393.374091)
			(xy 55.374803 -393.426421) (xy 55.352146 -393.476031) (xy 55.32266 -393.521912) (xy 55.286945 -393.563129)
			(xy 55.245728 -393.598844) (xy 55.199847 -393.62833) (xy 55.150237 -393.650987) (xy 55.097907 -393.666352)
			(xy 55.043923 -393.674114) (xy 54.989385 -393.674114) (xy 54.935401 -393.666352) (xy 54.883071 -393.650987)
			(xy 54.833461 -393.62833) (xy 54.78758 -393.598844) (xy 54.746363 -393.563129) (xy 54.710648 -393.521912)
			(xy 54.681162 -393.476031) (xy 54.658505 -393.426421) (xy 54.64314 -393.374091) (xy 54.635378 -393.320107)
			(xy 54.634892 -393.292838) (xy 54.198012 -393.292838) (xy 54.197526 -393.320089) (xy 54.18977 -393.374037)
			(xy 54.174415 -393.426332) (xy 54.151773 -393.475909) (xy 54.122307 -393.521759) (xy 54.086616 -393.56295)
			(xy 54.045425 -393.598641) (xy 53.999575 -393.628107) (xy 53.949998 -393.650749) (xy 53.897703 -393.666104)
			(xy 53.843755 -393.67386) (xy 53.789253 -393.67386) (xy 53.735305 -393.666104) (xy 53.68301 -393.650749)
			(xy 53.633433 -393.628107) (xy 53.587583 -393.598641) (xy 53.546392 -393.56295) (xy 53.510701 -393.521759)
			(xy 53.481235 -393.475909) (xy 53.458593 -393.426332) (xy 53.443238 -393.374037) (xy 53.435482 -393.320089)
			(xy 53.434996 -393.292838) (xy 52.998116 -393.292838) (xy 52.99763 -393.320089) (xy 52.989874 -393.374037)
			(xy 52.974519 -393.426332) (xy 52.951877 -393.475909) (xy 52.922411 -393.521759) (xy 52.88672 -393.56295)
			(xy 52.845529 -393.598641) (xy 52.799679 -393.628107) (xy 52.750102 -393.650749) (xy 52.697807 -393.666104)
			(xy 52.643859 -393.67386) (xy 52.589357 -393.67386) (xy 52.535409 -393.666104) (xy 52.483114 -393.650749)
			(xy 52.433537 -393.628107) (xy 52.387687 -393.598641) (xy 52.346496 -393.56295) (xy 52.310805 -393.521759)
			(xy 52.281339 -393.475909) (xy 52.258697 -393.426332) (xy 52.243342 -393.374037) (xy 52.235586 -393.320089)
			(xy 52.2351 -393.292838) (xy 51.79822 -393.292838) (xy 51.797734 -393.320107) (xy 51.789972 -393.374091)
			(xy 51.774607 -393.426421) (xy 51.75195 -393.476031) (xy 51.722464 -393.521912) (xy 51.686749 -393.563129)
			(xy 51.645532 -393.598844) (xy 51.599651 -393.62833) (xy 51.550041 -393.650987) (xy 51.497711 -393.666352)
			(xy 51.443727 -393.674114) (xy 51.389189 -393.674114) (xy 51.335205 -393.666352) (xy 51.282875 -393.650987)
			(xy 51.233265 -393.62833) (xy 51.187384 -393.598844) (xy 51.146167 -393.563129) (xy 51.110452 -393.521912)
			(xy 51.080966 -393.476031) (xy 51.058309 -393.426421) (xy 51.042944 -393.374091) (xy 51.035182 -393.320107)
			(xy 51.034696 -393.292838) (xy 50.598324 -393.292838) (xy 50.597838 -393.320107) (xy 50.590076 -393.374091)
			(xy 50.574711 -393.426421) (xy 50.552054 -393.476031) (xy 50.522568 -393.521912) (xy 50.486853 -393.563129)
			(xy 50.445636 -393.598844) (xy 50.399755 -393.62833) (xy 50.350145 -393.650987) (xy 50.297815 -393.666352)
			(xy 50.243831 -393.674114) (xy 50.189293 -393.674114) (xy 50.135309 -393.666352) (xy 50.082979 -393.650987)
			(xy 50.033369 -393.62833) (xy 49.987488 -393.598844) (xy 49.946271 -393.563129) (xy 49.910556 -393.521912)
			(xy 49.88107 -393.476031) (xy 49.858413 -393.426421) (xy 49.843048 -393.374091) (xy 49.835286 -393.320107)
			(xy 49.8348 -393.292838) (xy 49.39792 -393.292838) (xy 49.397434 -393.320089) (xy 49.389678 -393.374037)
			(xy 49.374323 -393.426332) (xy 49.351681 -393.475909) (xy 49.322215 -393.521759) (xy 49.286524 -393.56295)
			(xy 49.245333 -393.598641) (xy 49.199483 -393.628107) (xy 49.149906 -393.650749) (xy 49.097611 -393.666104)
			(xy 49.043663 -393.67386) (xy 48.989161 -393.67386) (xy 48.935213 -393.666104) (xy 48.882918 -393.650749)
			(xy 48.833341 -393.628107) (xy 48.787491 -393.598641) (xy 48.7463 -393.56295) (xy 48.710609 -393.521759)
			(xy 48.681143 -393.475909) (xy 48.658501 -393.426332) (xy 48.643146 -393.374037) (xy 48.63539 -393.320089)
			(xy 48.634904 -393.292838) (xy 48.198024 -393.292838) (xy 48.197538 -393.320089) (xy 48.189782 -393.374037)
			(xy 48.174427 -393.426332) (xy 48.151785 -393.475909) (xy 48.122319 -393.521759) (xy 48.086628 -393.56295)
			(xy 48.045437 -393.598641) (xy 47.999587 -393.628107) (xy 47.95001 -393.650749) (xy 47.897715 -393.666104)
			(xy 47.843767 -393.67386) (xy 47.789265 -393.67386) (xy 47.735317 -393.666104) (xy 47.683022 -393.650749)
			(xy 47.633445 -393.628107) (xy 47.587595 -393.598641) (xy 47.546404 -393.56295) (xy 47.510713 -393.521759)
			(xy 47.481247 -393.475909) (xy 47.458605 -393.426332) (xy 47.44325 -393.374037) (xy 47.435494 -393.320089)
			(xy 47.435008 -393.292838) (xy 2.509012 -393.292838) (xy 2.509012 -400.50847) (xy 103.485188 -400.50847)
			(xy 103.485723 -400.479553) (xy 103.494444 -400.422381) (xy 103.511697 -400.367182) (xy 103.537085 -400.315219)
			(xy 103.570027 -400.267685) (xy 103.609768 -400.225669) (xy 103.632254 -400.20748) (xy 103.641069 -400.199881)
			(xy 103.651246 -400.178974) (xy 103.651812 -400.167348) (xy 103.651812 -400.087592) (xy 103.651259 -400.075962)
			(xy 103.64108 -400.055053) (xy 103.632254 -400.04746) (xy 103.609742 -400.029303) (xy 103.57001 -399.987275)
			(xy 103.537076 -399.939733) (xy 103.511693 -399.887765) (xy 103.494443 -399.832562) (xy 103.48572 -399.775388)
			(xy 103.485188 -399.74647) (xy 103.485674 -399.719201) (xy 103.493436 -399.665217) (xy 103.508801 -399.612887)
			(xy 103.531458 -399.563277) (xy 103.560944 -399.517396) (xy 103.596659 -399.476179) (xy 103.637876 -399.440464)
			(xy 103.683757 -399.410978) (xy 103.733367 -399.388321) (xy 103.785697 -399.372956) (xy 103.839681 -399.365194)
			(xy 103.894219 -399.365194) (xy 103.948203 -399.372956) (xy 104.000533 -399.388321) (xy 104.050143 -399.410978)
			(xy 104.096024 -399.440464) (xy 104.137241 -399.476179) (xy 104.172956 -399.517396) (xy 104.202442 -399.563277)
			(xy 104.225099 -399.612887) (xy 104.240464 -399.665217) (xy 104.248226 -399.719201) (xy 104.248712 -399.74647)
			(xy 104.248206 -399.775388) (xy 104.239479 -399.832561) (xy 104.222221 -399.887762) (xy 104.196827 -399.939724)
			(xy 104.16388 -399.987257) (xy 104.124134 -400.029272) (xy 104.101646 -400.04746) (xy 104.092858 -400.055085)
			(xy 104.082666 -400.075972) (xy 104.082088 -400.087592) (xy 104.082088 -400.167348) (xy 104.082618 -400.178981)
			(xy 104.092814 -400.19989) (xy 104.101646 -400.20748) (xy 104.124129 -400.225671) (xy 104.163863 -400.267692)
			(xy 104.1968 -400.315227) (xy 104.222188 -400.367188) (xy 104.239445 -400.422385) (xy 104.248176 -400.479554)
			(xy 104.248712 -400.50847) (xy 104.248226 -400.535739) (xy 104.240464 -400.589723) (xy 104.225099 -400.642053)
			(xy 104.202442 -400.691663) (xy 104.172956 -400.737544) (xy 104.137241 -400.778761) (xy 104.096024 -400.814476)
			(xy 104.050143 -400.843962) (xy 104.000533 -400.866619) (xy 103.948203 -400.881984) (xy 103.894219 -400.889746)
			(xy 103.839681 -400.889746) (xy 103.785697 -400.881984) (xy 103.733367 -400.866619) (xy 103.683757 -400.843962)
			(xy 103.637876 -400.814476) (xy 103.596659 -400.778761) (xy 103.560944 -400.737544) (xy 103.531458 -400.691663)
			(xy 103.508801 -400.642053) (xy 103.493436 -400.589723) (xy 103.485674 -400.535739) (xy 103.485188 -400.50847)
			(xy 2.509012 -400.50847) (xy 2.509012 -403.371812) (xy 2.5095 -403.425034) (xy 2.517117 -403.531207)
			(xy 2.532283 -403.636566) (xy 2.554922 -403.740575) (xy 2.584919 -403.842706) (xy 2.622121 -403.942439)
			(xy 2.666338 -404.039266) (xy 2.717346 -404.132693) (xy 2.774884 -404.222247) (xy 2.838661 -404.307471)
			(xy 2.908351 -404.387931) (xy 2.945638 -404.425912) (xy 3.30962 -404.789894) (xy 37.568898 -404.789894)
			(xy 37.57287 -404.611651) (xy 37.584778 -404.433762) (xy 37.604599 -404.25658) (xy 37.632293 -404.080456)
			(xy 37.667805 -403.905741) (xy 37.711065 -403.732782) (xy 37.761987 -403.561921) (xy 37.82047 -403.393499)
			(xy 37.886397 -403.227849) (xy 37.959638 -403.0653) (xy 38.040048 -402.906175) (xy 38.127466 -402.75079)
			(xy 38.221719 -402.599454) (xy 38.32262 -402.452466) (xy 38.429969 -402.310119) (xy 38.543552 -402.172696)
			(xy 38.663145 -402.040469) (xy 38.788509 -401.9137) (xy 38.919396 -401.792642) (xy 39.055545 -401.677535)
			(xy 39.196687 -401.568607) (xy 39.342542 -401.466075) (xy 39.492819 -401.370141) (xy 39.64722 -401.280998)
			(xy 39.805439 -401.198821) (xy 39.967162 -401.123773) (xy 40.132067 -401.056005) (xy 40.299828 -400.995649)
			(xy 40.470111 -400.942827) (xy 40.642578 -400.897643) (xy 40.816886 -400.860186) (xy 40.99269 -400.830532)
			(xy 41.16964 -400.808739) (xy 41.347386 -400.794849) (xy 41.525573 -400.788892) (xy 41.70385 -400.790878)
			(xy 41.881861 -400.800804) (xy 42.059253 -400.81865) (xy 42.235673 -400.84438) (xy 42.410773 -400.877944)
			(xy 42.584204 -400.919274) (xy 42.755621 -400.96829) (xy 42.924684 -401.024892) (xy 43.091059 -401.08897)
			(xy 43.254413 -401.160396) (xy 43.414424 -401.239028) (xy 43.570773 -401.324709) (xy 43.72315 -401.417271)
			(xy 43.871253 -401.516528) (xy 44.014787 -401.622285) (xy 44.153467 -401.73433) (xy 44.287018 -401.852442)
			(xy 44.415175 -401.976386) (xy 44.537684 -402.105916) (xy 44.654301 -402.240775) (xy 44.764794 -402.380695)
			(xy 44.868945 -402.525398) (xy 44.966547 -402.674597) (xy 45.057405 -402.827996) (xy 45.141339 -402.98529)
			(xy 45.218184 -403.146166) (xy 45.287785 -403.310307) (xy 45.350006 -403.477384) (xy 45.404722 -403.647068)
			(xy 45.451824 -403.819021) (xy 45.49122 -403.992901) (xy 45.522831 -404.168364) (xy 45.546595 -404.34506)
			(xy 45.559703 -404.491748) (xy 47.413198 -404.491748) (xy 47.413198 -404.437252) (xy 47.420953 -404.38331)
			(xy 47.436306 -404.331021) (xy 47.458943 -404.281449) (xy 47.488404 -404.235603) (xy 47.52409 -404.194416)
			(xy 47.565274 -404.158726) (xy 47.611117 -404.12926) (xy 47.660687 -404.106618) (xy 47.712975 -404.091261)
			(xy 47.766916 -404.083501) (xy 47.794164 -404.083012) (xy 48.657764 -404.083012) (xy 48.68502 -404.083432)
			(xy 48.738978 -404.091186) (xy 48.791283 -404.106539) (xy 48.84087 -404.129181) (xy 48.88673 -404.15865)
			(xy 48.927929 -404.194345) (xy 48.963629 -404.235541) (xy 48.993102 -404.281398) (xy 49.015748 -404.330984)
			(xy 49.031107 -404.383287) (xy 49.038865 -404.437244) (xy 49.038865 -404.491752) (xy 50.476375 -404.491752)
			(xy 50.476375 -404.437248) (xy 50.484132 -404.3833) (xy 50.499487 -404.331005) (xy 50.522129 -404.281427)
			(xy 50.551596 -404.235576) (xy 50.587288 -404.194385) (xy 50.628479 -404.158693) (xy 50.67433 -404.129227)
			(xy 50.723908 -404.106586) (xy 50.776204 -404.091231) (xy 50.830152 -404.083475) (xy 50.857404 -404.083012)
			(xy 51.721004 -404.083012) (xy 51.748256 -404.083458) (xy 51.802207 -404.091215) (xy 51.854504 -404.106572)
			(xy 51.904083 -404.129214) (xy 51.949935 -404.158682) (xy 51.991127 -404.194376) (xy 52.02682 -404.235568)
			(xy 52.056288 -404.281421) (xy 52.07893 -404.331) (xy 52.094285 -404.383297) (xy 52.102042 -404.437248)
			(xy 52.102042 -404.491752) (xy 52.102042 -404.491753) (xy 53.539575 -404.491753) (xy 53.539575 -404.437247)
			(xy 53.547333 -404.383295) (xy 53.562691 -404.330996) (xy 53.585335 -404.281416) (xy 53.614806 -404.235563)
			(xy 53.650502 -404.194371) (xy 53.691698 -404.158679) (xy 53.737554 -404.129214) (xy 53.787137 -404.106575)
			(xy 53.839438 -404.091224) (xy 53.893391 -404.083472) (xy 53.920644 -404.083012) (xy 54.784244 -404.083012)
			(xy 54.811495 -404.083461) (xy 54.86544 -404.091223) (xy 54.917733 -404.106583) (xy 54.967307 -404.129227)
			(xy 55.013154 -404.158696) (xy 55.054341 -404.19439) (xy 55.09003 -404.235581) (xy 55.119494 -404.281432)
			(xy 55.142133 -404.331009) (xy 55.157487 -404.383303) (xy 55.165242 -404.437249) (xy 55.165242 -404.491749)
			(xy 56.602898 -404.491749) (xy 56.602898 -404.437251) (xy 56.610654 -404.383308) (xy 56.626007 -404.331017)
			(xy 56.648646 -404.281443) (xy 56.678109 -404.235596) (xy 56.713797 -404.194409) (xy 56.754983 -404.158719)
			(xy 56.800829 -404.129254) (xy 56.850402 -404.106613) (xy 56.902692 -404.091257) (xy 56.956635 -404.083499)
			(xy 56.983884 -404.083012) (xy 57.847484 -404.083012) (xy 57.874739 -404.083434) (xy 57.928695 -404.091189)
			(xy 57.980997 -404.106545) (xy 58.030582 -404.129188) (xy 58.07644 -404.158657) (xy 58.117636 -404.194352)
			(xy 58.153334 -404.235548) (xy 58.182805 -404.281404) (xy 58.20545 -404.330988) (xy 58.220807 -404.38329)
			(xy 58.228565 -404.437245) (xy 58.228565 -404.491753) (xy 59.666075 -404.491753) (xy 59.666075 -404.437247)
			(xy 59.673833 -404.383297) (xy 59.689189 -404.331) (xy 59.711832 -404.281421) (xy 59.741301 -404.235569)
			(xy 59.776995 -404.194378) (xy 59.818188 -404.158686) (xy 59.864042 -404.129221) (xy 59.913623 -404.106581)
			(xy 59.965921 -404.091227) (xy 60.019871 -404.083474) (xy 60.047124 -404.083012) (xy 60.910724 -404.083012)
			(xy 60.937976 -404.083459) (xy 60.991924 -404.091219) (xy 61.044218 -404.106577) (xy 61.093795 -404.129221)
			(xy 61.139645 -404.158689) (xy 61.180834 -404.194383) (xy 61.216525 -404.235575) (xy 61.245991 -404.281426)
			(xy 61.268631 -404.331004) (xy 61.283986 -404.3833) (xy 61.291742 -404.437248) (xy 61.291742 -404.491748)
			(xy 62.729398 -404.491748) (xy 62.729398 -404.437252) (xy 62.737153 -404.38331) (xy 62.752506 -404.331021)
			(xy 62.775143 -404.281449) (xy 62.804604 -404.235603) (xy 62.84029 -404.194416) (xy 62.881474 -404.158726)
			(xy 62.927317 -404.12926) (xy 62.976887 -404.106618) (xy 63.029175 -404.091261) (xy 63.083116 -404.083501)
			(xy 63.110364 -404.083012) (xy 63.973964 -404.083012) (xy 64.00122 -404.083432) (xy 64.055178 -404.091186)
			(xy 64.107483 -404.106539) (xy 64.15707 -404.129181) (xy 64.20293 -404.15865) (xy 64.244129 -404.194345)
			(xy 64.279829 -404.235541) (xy 64.309302 -404.281398) (xy 64.331948 -404.330984) (xy 64.347307 -404.383287)
			(xy 64.355065 -404.437244) (xy 64.355065 -404.491752) (xy 65.792575 -404.491752) (xy 65.792575 -404.437248)
			(xy 65.800332 -404.3833) (xy 65.815687 -404.331005) (xy 65.838329 -404.281427) (xy 65.867796 -404.235576)
			(xy 65.903488 -404.194385) (xy 65.944679 -404.158693) (xy 65.99053 -404.129227) (xy 66.040108 -404.106586)
			(xy 66.092404 -404.091231) (xy 66.146352 -404.083475) (xy 66.173604 -404.083012) (xy 67.037204 -404.083012)
			(xy 67.064456 -404.083458) (xy 67.118407 -404.091215) (xy 67.170704 -404.106572) (xy 67.220283 -404.129214)
			(xy 67.266135 -404.158682) (xy 67.307327 -404.194376) (xy 67.34302 -404.235568) (xy 67.372488 -404.281421)
			(xy 67.39513 -404.331) (xy 67.410485 -404.383297) (xy 67.418242 -404.437248) (xy 67.418242 -404.491752)
			(xy 67.418242 -404.491753) (xy 68.855775 -404.491753) (xy 68.855775 -404.437247) (xy 68.863533 -404.383295)
			(xy 68.878891 -404.330996) (xy 68.901535 -404.281416) (xy 68.931006 -404.235563) (xy 68.966702 -404.194371)
			(xy 69.007898 -404.158679) (xy 69.053754 -404.129214) (xy 69.103337 -404.106575) (xy 69.155638 -404.091224)
			(xy 69.209591 -404.083472) (xy 69.236844 -404.083012) (xy 70.100444 -404.083012) (xy 70.127695 -404.083461)
			(xy 70.18164 -404.091223) (xy 70.233933 -404.106583) (xy 70.283507 -404.129227) (xy 70.329354 -404.158696)
			(xy 70.370541 -404.19439) (xy 70.40623 -404.235581) (xy 70.435694 -404.281432) (xy 70.458333 -404.331009)
			(xy 70.473687 -404.383303) (xy 70.481442 -404.437249) (xy 70.481442 -404.491749) (xy 71.919098 -404.491749)
			(xy 71.919098 -404.437251) (xy 71.926854 -404.383308) (xy 71.942207 -404.331017) (xy 71.964846 -404.281443)
			(xy 71.994309 -404.235596) (xy 72.029997 -404.194409) (xy 72.071183 -404.158719) (xy 72.117029 -404.129254)
			(xy 72.166602 -404.106613) (xy 72.218892 -404.091257) (xy 72.272835 -404.083499) (xy 72.300084 -404.083012)
			(xy 73.163684 -404.083012) (xy 73.190939 -404.083434) (xy 73.244895 -404.091189) (xy 73.297197 -404.106545)
			(xy 73.346782 -404.129188) (xy 73.39264 -404.158657) (xy 73.433836 -404.194352) (xy 73.469534 -404.235548)
			(xy 73.499005 -404.281404) (xy 73.52165 -404.330988) (xy 73.537007 -404.38329) (xy 73.544765 -404.437245)
			(xy 73.544765 -404.491753) (xy 74.982275 -404.491753) (xy 74.982275 -404.437247) (xy 74.990033 -404.383297)
			(xy 75.005389 -404.331) (xy 75.028032 -404.281421) (xy 75.057501 -404.235569) (xy 75.093195 -404.194378)
			(xy 75.134388 -404.158686) (xy 75.180242 -404.129221) (xy 75.229823 -404.106581) (xy 75.282121 -404.091227)
			(xy 75.336071 -404.083474) (xy 75.363324 -404.083012) (xy 76.226924 -404.083012) (xy 76.254176 -404.083459)
			(xy 76.308124 -404.091219) (xy 76.360418 -404.106577) (xy 76.409995 -404.129221) (xy 76.455845 -404.158689)
			(xy 76.497034 -404.194383) (xy 76.532725 -404.235575) (xy 76.562191 -404.281426) (xy 76.584831 -404.331004)
			(xy 76.600186 -404.3833) (xy 76.607942 -404.437248) (xy 76.607942 -404.491748) (xy 78.045598 -404.491748)
			(xy 78.045598 -404.437252) (xy 78.053353 -404.38331) (xy 78.068706 -404.331021) (xy 78.091343 -404.281449)
			(xy 78.120804 -404.235603) (xy 78.15649 -404.194416) (xy 78.197674 -404.158726) (xy 78.243517 -404.12926)
			(xy 78.293087 -404.106618) (xy 78.345375 -404.091261) (xy 78.399316 -404.083501) (xy 78.426564 -404.083012)
			(xy 79.290164 -404.083012) (xy 79.31742 -404.083432) (xy 79.371378 -404.091186) (xy 79.423683 -404.106539)
			(xy 79.47327 -404.129181) (xy 79.51913 -404.15865) (xy 79.560329 -404.194345) (xy 79.596029 -404.235541)
			(xy 79.625502 -404.281398) (xy 79.648148 -404.330984) (xy 79.663507 -404.383287) (xy 79.671265 -404.437244)
			(xy 79.671265 -404.491752) (xy 81.108775 -404.491752) (xy 81.108775 -404.437248) (xy 81.116532 -404.3833)
			(xy 81.131887 -404.331005) (xy 81.154529 -404.281427) (xy 81.183996 -404.235576) (xy 81.219688 -404.194385)
			(xy 81.260879 -404.158693) (xy 81.30673 -404.129227) (xy 81.356308 -404.106586) (xy 81.408604 -404.091231)
			(xy 81.462552 -404.083475) (xy 81.489804 -404.083012) (xy 82.353404 -404.083012) (xy 82.380656 -404.083458)
			(xy 82.434607 -404.091215) (xy 82.486904 -404.106572) (xy 82.536483 -404.129214) (xy 82.582335 -404.158682)
			(xy 82.623527 -404.194376) (xy 82.65922 -404.235568) (xy 82.688688 -404.281421) (xy 82.71133 -404.331)
			(xy 82.726685 -404.383297) (xy 82.734442 -404.437248) (xy 82.734442 -404.491752) (xy 82.734442 -404.491753)
			(xy 84.171975 -404.491753) (xy 84.171975 -404.437247) (xy 84.179733 -404.383295) (xy 84.195091 -404.330996)
			(xy 84.217735 -404.281416) (xy 84.247206 -404.235563) (xy 84.282902 -404.194371) (xy 84.324098 -404.158679)
			(xy 84.369954 -404.129214) (xy 84.419537 -404.106575) (xy 84.471838 -404.091224) (xy 84.525791 -404.083472)
			(xy 84.553044 -404.083012) (xy 85.416644 -404.083012) (xy 85.443895 -404.083461) (xy 85.49784 -404.091223)
			(xy 85.550133 -404.106583) (xy 85.599707 -404.129227) (xy 85.645554 -404.158696) (xy 85.686741 -404.19439)
			(xy 85.72243 -404.235581) (xy 85.751894 -404.281432) (xy 85.774533 -404.331009) (xy 85.789887 -404.383303)
			(xy 85.797642 -404.437249) (xy 85.797642 -404.491749) (xy 87.235298 -404.491749) (xy 87.235298 -404.437251)
			(xy 87.243054 -404.383308) (xy 87.258407 -404.331017) (xy 87.281046 -404.281443) (xy 87.310509 -404.235596)
			(xy 87.346197 -404.194409) (xy 87.387383 -404.158719) (xy 87.433229 -404.129254) (xy 87.482802 -404.106613)
			(xy 87.535092 -404.091257) (xy 87.589035 -404.083499) (xy 87.616284 -404.083012) (xy 88.479884 -404.083012)
			(xy 88.507139 -404.083434) (xy 88.561095 -404.091189) (xy 88.613397 -404.106545) (xy 88.662982 -404.129188)
			(xy 88.70884 -404.158657) (xy 88.750036 -404.194352) (xy 88.785734 -404.235548) (xy 88.815205 -404.281404)
			(xy 88.83785 -404.330988) (xy 88.853207 -404.38329) (xy 88.860965 -404.437245) (xy 88.860965 -404.491753)
			(xy 90.298475 -404.491753) (xy 90.298475 -404.437247) (xy 90.306233 -404.383297) (xy 90.321589 -404.331)
			(xy 90.344232 -404.281421) (xy 90.373701 -404.235569) (xy 90.409395 -404.194378) (xy 90.450588 -404.158686)
			(xy 90.496442 -404.129221) (xy 90.546023 -404.106581) (xy 90.598321 -404.091227) (xy 90.652271 -404.083474)
			(xy 90.679524 -404.083012) (xy 91.543124 -404.083012) (xy 91.570376 -404.083459) (xy 91.624324 -404.091219)
			(xy 91.676618 -404.106577) (xy 91.726195 -404.129221) (xy 91.772045 -404.158689) (xy 91.813234 -404.194383)
			(xy 91.848925 -404.235575) (xy 91.878391 -404.281426) (xy 91.901031 -404.331004) (xy 91.916386 -404.3833)
			(xy 91.924142 -404.437248) (xy 91.924142 -404.491748) (xy 93.361798 -404.491748) (xy 93.361798 -404.437252)
			(xy 93.369553 -404.38331) (xy 93.384906 -404.331021) (xy 93.407543 -404.281449) (xy 93.437004 -404.235603)
			(xy 93.47269 -404.194416) (xy 93.513874 -404.158726) (xy 93.559717 -404.12926) (xy 93.609287 -404.106618)
			(xy 93.661575 -404.091261) (xy 93.715516 -404.083501) (xy 93.742764 -404.083012) (xy 94.606364 -404.083012)
			(xy 94.63362 -404.083432) (xy 94.687578 -404.091186) (xy 94.739883 -404.106539) (xy 94.78947 -404.129181)
			(xy 94.83533 -404.15865) (xy 94.876529 -404.194345) (xy 94.912229 -404.235541) (xy 94.941702 -404.281398)
			(xy 94.964348 -404.330984) (xy 94.979707 -404.383287) (xy 94.987465 -404.437244) (xy 94.987465 -404.491752)
			(xy 114.513075 -404.491752) (xy 114.513075 -404.437248) (xy 114.520832 -404.3833) (xy 114.536188 -404.331004)
			(xy 114.558829 -404.281426) (xy 114.588296 -404.235575) (xy 114.623989 -404.194384) (xy 114.66518 -404.158693)
			(xy 114.711031 -404.129226) (xy 114.76061 -404.106585) (xy 114.812906 -404.091231) (xy 114.866854 -404.083475)
			(xy 114.894106 -404.083012) (xy 115.757706 -404.083012) (xy 115.784958 -404.083458) (xy 115.838908 -404.091216)
			(xy 115.891205 -404.106572) (xy 115.940784 -404.129215) (xy 115.986636 -404.158683) (xy 116.027828 -404.194376)
			(xy 116.063521 -404.235569) (xy 116.092988 -404.281421) (xy 116.11563 -404.331001) (xy 116.130985 -404.383298)
			(xy 116.138742 -404.437248) (xy 116.138742 -404.491752) (xy 116.138742 -404.491754) (xy 117.576275 -404.491754)
			(xy 117.576275 -404.437246) (xy 117.584033 -404.383294) (xy 117.599391 -404.330996) (xy 117.622035 -404.281415)
			(xy 117.651506 -404.235562) (xy 117.687203 -404.19437) (xy 117.728399 -404.158679) (xy 117.774255 -404.129213)
			(xy 117.823839 -404.106575) (xy 117.876139 -404.091223) (xy 117.930092 -404.083472) (xy 117.957346 -404.083012)
			(xy 118.820946 -404.083012) (xy 118.848197 -404.083461) (xy 118.902142 -404.091223) (xy 118.954434 -404.106583)
			(xy 119.004008 -404.129228) (xy 119.049855 -404.158697) (xy 119.091042 -404.194391) (xy 119.12673 -404.235582)
			(xy 119.156194 -404.281432) (xy 119.178833 -404.331009) (xy 119.194187 -404.383303) (xy 119.201942 -404.437249)
			(xy 119.201942 -404.491749) (xy 120.639598 -404.491749) (xy 120.639598 -404.437251) (xy 120.647354 -404.383307)
			(xy 120.662708 -404.331016) (xy 120.685346 -404.281443) (xy 120.71481 -404.235596) (xy 120.750498 -404.194408)
			(xy 120.791684 -404.158718) (xy 120.83753 -404.129253) (xy 120.887103 -404.106612) (xy 120.939394 -404.091257)
			(xy 120.993337 -404.083499) (xy 121.020586 -404.083012) (xy 121.884186 -404.083012) (xy 121.911441 -404.083434)
			(xy 121.965396 -404.09119) (xy 122.017699 -404.106545) (xy 122.067283 -404.129188) (xy 122.113141 -404.158657)
			(xy 122.154337 -404.194353) (xy 122.190034 -404.235548) (xy 122.219505 -404.281405) (xy 122.24215 -404.330988)
			(xy 122.257507 -404.38329) (xy 122.265265 -404.437245) (xy 122.265265 -404.491753) (xy 123.702775 -404.491753)
			(xy 123.702775 -404.437247) (xy 123.710533 -404.383297) (xy 123.725889 -404.331) (xy 123.748532 -404.281421)
			(xy 123.778001 -404.235569) (xy 123.813696 -404.194377) (xy 123.854889 -404.158686) (xy 123.900743 -404.12922)
			(xy 123.950324 -404.10658) (xy 124.002622 -404.091227) (xy 124.056573 -404.083474) (xy 124.083826 -404.083012)
			(xy 124.947426 -404.083012) (xy 124.974677 -404.08346) (xy 125.028625 -404.09122) (xy 125.08092 -404.106578)
			(xy 125.130496 -404.129222) (xy 125.176346 -404.15869) (xy 125.217535 -404.194383) (xy 125.253226 -404.235575)
			(xy 125.282691 -404.281427) (xy 125.305331 -404.331005) (xy 125.320686 -404.3833) (xy 125.328442 -404.437249)
			(xy 125.328442 -404.491748) (xy 126.766098 -404.491748) (xy 126.766098 -404.437252) (xy 126.773853 -404.38331)
			(xy 126.789206 -404.331021) (xy 126.811843 -404.281448) (xy 126.841305 -404.235602) (xy 126.876991 -404.194415)
			(xy 126.918175 -404.158725) (xy 126.964018 -404.12926) (xy 127.013589 -404.106618) (xy 127.065877 -404.091261)
			(xy 127.119818 -404.083501) (xy 127.147066 -404.083012) (xy 128.010666 -404.083012) (xy 128.037922 -404.083433)
			(xy 128.091879 -404.091186) (xy 128.144184 -404.10654) (xy 128.193771 -404.129182) (xy 128.239631 -404.15865)
			(xy 128.28083 -404.194346) (xy 128.316529 -404.235542) (xy 128.346002 -404.281399) (xy 128.368648 -404.330984)
			(xy 128.384007 -404.383287) (xy 128.391765 -404.437244) (xy 128.391765 -404.491752) (xy 129.829275 -404.491752)
			(xy 129.829275 -404.437248) (xy 129.837032 -404.3833) (xy 129.852388 -404.331004) (xy 129.875029 -404.281426)
			(xy 129.904496 -404.235575) (xy 129.940189 -404.194384) (xy 129.98138 -404.158693) (xy 130.027231 -404.129226)
			(xy 130.07681 -404.106585) (xy 130.129106 -404.091231) (xy 130.183054 -404.083475) (xy 130.210306 -404.083012)
			(xy 131.073906 -404.083012) (xy 131.101158 -404.083458) (xy 131.155108 -404.091216) (xy 131.207405 -404.106572)
			(xy 131.256984 -404.129215) (xy 131.302836 -404.158683) (xy 131.344028 -404.194376) (xy 131.379721 -404.235569)
			(xy 131.409188 -404.281421) (xy 131.43183 -404.331001) (xy 131.447185 -404.383298) (xy 131.454942 -404.437248)
			(xy 131.454942 -404.491752) (xy 131.454942 -404.491754) (xy 132.892475 -404.491754) (xy 132.892475 -404.437246)
			(xy 132.900233 -404.383294) (xy 132.915591 -404.330996) (xy 132.938235 -404.281415) (xy 132.967706 -404.235562)
			(xy 133.003403 -404.19437) (xy 133.044599 -404.158679) (xy 133.090455 -404.129213) (xy 133.140039 -404.106575)
			(xy 133.192339 -404.091223) (xy 133.246292 -404.083472) (xy 133.273546 -404.083012) (xy 134.137146 -404.083012)
			(xy 134.164397 -404.083461) (xy 134.218342 -404.091223) (xy 134.270634 -404.106583) (xy 134.320208 -404.129228)
			(xy 134.366055 -404.158697) (xy 134.407242 -404.194391) (xy 134.44293 -404.235582) (xy 134.472394 -404.281432)
			(xy 134.495033 -404.331009) (xy 134.510387 -404.383303) (xy 134.518142 -404.437249) (xy 134.518142 -404.491749)
			(xy 135.955798 -404.491749) (xy 135.955798 -404.437251) (xy 135.963554 -404.383307) (xy 135.978908 -404.331016)
			(xy 136.001546 -404.281443) (xy 136.03101 -404.235596) (xy 136.066698 -404.194408) (xy 136.107884 -404.158718)
			(xy 136.15373 -404.129253) (xy 136.203303 -404.106612) (xy 136.255594 -404.091257) (xy 136.309537 -404.083499)
			(xy 136.336786 -404.083012) (xy 137.200386 -404.083012) (xy 137.227641 -404.083434) (xy 137.281596 -404.09119)
			(xy 137.333899 -404.106545) (xy 137.383483 -404.129188) (xy 137.429341 -404.158657) (xy 137.470537 -404.194353)
			(xy 137.506234 -404.235548) (xy 137.535705 -404.281405) (xy 137.55835 -404.330988) (xy 137.573707 -404.38329)
			(xy 137.581465 -404.437245) (xy 137.581465 -404.491753) (xy 139.018975 -404.491753) (xy 139.018975 -404.437247)
			(xy 139.026733 -404.383297) (xy 139.042089 -404.331) (xy 139.064732 -404.281421) (xy 139.094201 -404.235569)
			(xy 139.129896 -404.194377) (xy 139.171089 -404.158686) (xy 139.216943 -404.12922) (xy 139.266524 -404.10658)
			(xy 139.318822 -404.091227) (xy 139.372773 -404.083474) (xy 139.400026 -404.083012) (xy 140.263626 -404.083012)
			(xy 140.290877 -404.08346) (xy 140.344825 -404.09122) (xy 140.39712 -404.106578) (xy 140.446696 -404.129222)
			(xy 140.492546 -404.15869) (xy 140.533735 -404.194383) (xy 140.569426 -404.235575) (xy 140.598891 -404.281427)
			(xy 140.621531 -404.331005) (xy 140.636886 -404.3833) (xy 140.644642 -404.437249) (xy 140.644642 -404.491748)
			(xy 142.082298 -404.491748) (xy 142.082298 -404.437252) (xy 142.090053 -404.38331) (xy 142.105406 -404.331021)
			(xy 142.128043 -404.281448) (xy 142.157505 -404.235602) (xy 142.193191 -404.194415) (xy 142.234375 -404.158725)
			(xy 142.280218 -404.12926) (xy 142.329789 -404.106618) (xy 142.382077 -404.091261) (xy 142.436018 -404.083501)
			(xy 142.463266 -404.083012) (xy 143.326866 -404.083012) (xy 143.354122 -404.083433) (xy 143.408079 -404.091186)
			(xy 143.460384 -404.10654) (xy 143.509971 -404.129182) (xy 143.555831 -404.15865) (xy 143.59703 -404.194346)
			(xy 143.632729 -404.235542) (xy 143.662202 -404.281399) (xy 143.684848 -404.330984) (xy 143.700207 -404.383287)
			(xy 143.707965 -404.437244) (xy 143.707965 -404.491752) (xy 145.145475 -404.491752) (xy 145.145475 -404.437248)
			(xy 145.153232 -404.3833) (xy 145.168588 -404.331004) (xy 145.191229 -404.281426) (xy 145.220696 -404.235575)
			(xy 145.256389 -404.194384) (xy 145.29758 -404.158693) (xy 145.343431 -404.129226) (xy 145.39301 -404.106585)
			(xy 145.445306 -404.091231) (xy 145.499254 -404.083475) (xy 145.526506 -404.083012) (xy 146.390106 -404.083012)
			(xy 146.417358 -404.083458) (xy 146.471308 -404.091216) (xy 146.523605 -404.106572) (xy 146.573184 -404.129215)
			(xy 146.619036 -404.158683) (xy 146.660228 -404.194376) (xy 146.695921 -404.235569) (xy 146.725388 -404.281421)
			(xy 146.74803 -404.331001) (xy 146.763385 -404.383298) (xy 146.771142 -404.437248) (xy 146.771142 -404.491752)
			(xy 146.771142 -404.491754) (xy 148.208675 -404.491754) (xy 148.208675 -404.437246) (xy 148.216433 -404.383294)
			(xy 148.231791 -404.330996) (xy 148.254435 -404.281415) (xy 148.283906 -404.235562) (xy 148.319603 -404.19437)
			(xy 148.360799 -404.158679) (xy 148.406655 -404.129213) (xy 148.456239 -404.106575) (xy 148.508539 -404.091223)
			(xy 148.562492 -404.083472) (xy 148.589746 -404.083012) (xy 149.453346 -404.083012) (xy 149.480597 -404.083461)
			(xy 149.534542 -404.091223) (xy 149.586834 -404.106583) (xy 149.636408 -404.129228) (xy 149.682255 -404.158697)
			(xy 149.723442 -404.194391) (xy 149.75913 -404.235582) (xy 149.788594 -404.281432) (xy 149.811233 -404.331009)
			(xy 149.826587 -404.383303) (xy 149.834342 -404.437249) (xy 149.834342 -404.491749) (xy 151.271998 -404.491749)
			(xy 151.271998 -404.437251) (xy 151.279754 -404.383307) (xy 151.295108 -404.331016) (xy 151.317746 -404.281443)
			(xy 151.34721 -404.235596) (xy 151.382898 -404.194408) (xy 151.424084 -404.158718) (xy 151.46993 -404.129253)
			(xy 151.519503 -404.106612) (xy 151.571794 -404.091257) (xy 151.625737 -404.083499) (xy 151.652986 -404.083012)
			(xy 152.516586 -404.083012) (xy 152.543841 -404.083434) (xy 152.597796 -404.09119) (xy 152.650099 -404.106545)
			(xy 152.699683 -404.129188) (xy 152.745541 -404.158657) (xy 152.786737 -404.194353) (xy 152.822434 -404.235548)
			(xy 152.851905 -404.281405) (xy 152.87455 -404.330988) (xy 152.889907 -404.38329) (xy 152.897665 -404.437245)
			(xy 152.897665 -404.491753) (xy 154.335175 -404.491753) (xy 154.335175 -404.437247) (xy 154.342933 -404.383297)
			(xy 154.358289 -404.331) (xy 154.380932 -404.281421) (xy 154.410401 -404.235569) (xy 154.446096 -404.194377)
			(xy 154.487289 -404.158686) (xy 154.533143 -404.12922) (xy 154.582724 -404.10658) (xy 154.635022 -404.091227)
			(xy 154.688973 -404.083474) (xy 154.716226 -404.083012) (xy 155.579826 -404.083012) (xy 155.607077 -404.08346)
			(xy 155.661025 -404.09122) (xy 155.71332 -404.106578) (xy 155.762896 -404.129222) (xy 155.808746 -404.15869)
			(xy 155.849935 -404.194383) (xy 155.885626 -404.235575) (xy 155.915091 -404.281427) (xy 155.937731 -404.331005)
			(xy 155.953086 -404.3833) (xy 155.960842 -404.437249) (xy 155.960842 -404.491748) (xy 157.398498 -404.491748)
			(xy 157.398498 -404.437252) (xy 157.406253 -404.38331) (xy 157.421606 -404.331021) (xy 157.444243 -404.281448)
			(xy 157.473705 -404.235602) (xy 157.509391 -404.194415) (xy 157.550575 -404.158725) (xy 157.596418 -404.12926)
			(xy 157.645989 -404.106618) (xy 157.698277 -404.091261) (xy 157.752218 -404.083501) (xy 157.779466 -404.083012)
			(xy 158.643066 -404.083012) (xy 158.670322 -404.083433) (xy 158.724279 -404.091186) (xy 158.776584 -404.10654)
			(xy 158.826171 -404.129182) (xy 158.872031 -404.15865) (xy 158.91323 -404.194346) (xy 158.948929 -404.235542)
			(xy 158.978402 -404.281399) (xy 159.001048 -404.330984) (xy 159.016407 -404.383287) (xy 159.024165 -404.437244)
			(xy 159.024165 -404.491752) (xy 160.461675 -404.491752) (xy 160.461675 -404.437248) (xy 160.469432 -404.3833)
			(xy 160.484788 -404.331004) (xy 160.507429 -404.281426) (xy 160.536896 -404.235575) (xy 160.572589 -404.194384)
			(xy 160.61378 -404.158693) (xy 160.659631 -404.129226) (xy 160.70921 -404.106585) (xy 160.761506 -404.091231)
			(xy 160.815454 -404.083475) (xy 160.842706 -404.083012) (xy 161.706306 -404.083012) (xy 161.733558 -404.083458)
			(xy 161.787508 -404.091216) (xy 161.839805 -404.106572) (xy 161.889384 -404.129215) (xy 161.935236 -404.158683)
			(xy 161.976428 -404.194376) (xy 162.012121 -404.235569) (xy 162.041588 -404.281421) (xy 162.06423 -404.331001)
			(xy 162.079585 -404.383298) (xy 162.087342 -404.437248) (xy 162.087342 -404.491752) (xy 162.079585 -404.545702)
			(xy 162.06423 -404.597999) (xy 162.041588 -404.647579) (xy 162.012121 -404.693431) (xy 161.976428 -404.734624)
			(xy 161.935236 -404.770317) (xy 161.904774 -404.789894) (xy 166.998662 -404.789894) (xy 167.002634 -404.611651)
			(xy 167.014542 -404.433762) (xy 167.034363 -404.25658) (xy 167.062057 -404.080456) (xy 167.097569 -403.905741)
			(xy 167.140829 -403.732782) (xy 167.191751 -403.561921) (xy 167.250234 -403.393499) (xy 167.316161 -403.227849)
			(xy 167.389402 -403.0653) (xy 167.469812 -402.906175) (xy 167.55723 -402.75079) (xy 167.651483 -402.599454)
			(xy 167.752384 -402.452466) (xy 167.859733 -402.310119) (xy 167.973316 -402.172696) (xy 168.092909 -402.040469)
			(xy 168.218273 -401.9137) (xy 168.34916 -401.792642) (xy 168.485309 -401.677535) (xy 168.626451 -401.568607)
			(xy 168.772306 -401.466075) (xy 168.922583 -401.370141) (xy 169.076984 -401.280998) (xy 169.235203 -401.198821)
			(xy 169.396926 -401.123773) (xy 169.561831 -401.056005) (xy 169.729592 -400.995649) (xy 169.899875 -400.942827)
			(xy 170.072342 -400.897643) (xy 170.24665 -400.860186) (xy 170.422454 -400.830532) (xy 170.599404 -400.808739)
			(xy 170.77715 -400.794849) (xy 170.955337 -400.788892) (xy 171.133614 -400.790878) (xy 171.311625 -400.800804)
			(xy 171.489017 -400.81865) (xy 171.665437 -400.84438) (xy 171.840537 -400.877944) (xy 172.013968 -400.919274)
			(xy 172.185385 -400.96829) (xy 172.354448 -401.024892) (xy 172.520823 -401.08897) (xy 172.684177 -401.160396)
			(xy 172.844188 -401.239028) (xy 173.000537 -401.324709) (xy 173.152914 -401.417271) (xy 173.301017 -401.516528)
			(xy 173.444551 -401.622285) (xy 173.583231 -401.73433) (xy 173.716782 -401.852442) (xy 173.844939 -401.976386)
			(xy 173.967448 -402.105916) (xy 174.084065 -402.240775) (xy 174.194558 -402.380695) (xy 174.298709 -402.525398)
			(xy 174.396311 -402.674597) (xy 174.487169 -402.827996) (xy 174.571103 -402.98529) (xy 174.647948 -403.146166)
			(xy 174.717549 -403.310307) (xy 174.77977 -403.477384) (xy 174.834486 -403.647068) (xy 174.881588 -403.819021)
			(xy 174.920984 -403.992901) (xy 174.952595 -404.168364) (xy 174.976359 -404.34506) (xy 174.992227 -404.52264)
			(xy 175.000169 -404.70075) (xy 175.000666 -404.789894) (xy 175.000169 -404.879038) (xy 174.992227 -405.057148)
			(xy 174.976359 -405.234728) (xy 174.952595 -405.411424) (xy 174.920984 -405.586887) (xy 174.881588 -405.760767)
			(xy 174.834486 -405.93272) (xy 174.77977 -406.102404) (xy 174.717549 -406.269481) (xy 174.647948 -406.433622)
			(xy 174.571103 -406.594498) (xy 174.487169 -406.751792) (xy 174.396311 -406.905191) (xy 174.298709 -407.05439)
			(xy 174.194558 -407.199093) (xy 174.084065 -407.339013) (xy 173.967448 -407.473872) (xy 173.844939 -407.603402)
			(xy 173.716782 -407.727346) (xy 173.583231 -407.845458) (xy 173.444551 -407.957503) (xy 173.301017 -408.06326)
			(xy 173.152914 -408.162517) (xy 173.000537 -408.255079) (xy 172.844188 -408.34076) (xy 172.684177 -408.419392)
			(xy 172.520823 -408.490818) (xy 172.354448 -408.554896) (xy 172.185385 -408.611498) (xy 172.013968 -408.660514)
			(xy 171.840537 -408.701844) (xy 171.665437 -408.735408) (xy 171.489017 -408.761138) (xy 171.311625 -408.778984)
			(xy 171.133614 -408.78891) (xy 170.955337 -408.790896) (xy 170.77715 -408.784939) (xy 170.599404 -408.771049)
			(xy 170.422454 -408.749256) (xy 170.24665 -408.719602) (xy 170.072342 -408.682145) (xy 169.899875 -408.636961)
			(xy 169.729592 -408.584139) (xy 169.561831 -408.523783) (xy 169.396926 -408.456015) (xy 169.235203 -408.380967)
			(xy 169.076984 -408.29879) (xy 168.922583 -408.209647) (xy 168.772306 -408.113713) (xy 168.626451 -408.011181)
			(xy 168.485309 -407.902253) (xy 168.34916 -407.787146) (xy 168.218273 -407.666088) (xy 168.092909 -407.539319)
			(xy 167.973316 -407.407092) (xy 167.859733 -407.269669) (xy 167.752384 -407.127322) (xy 167.651483 -406.980334)
			(xy 167.55723 -406.828998) (xy 167.469812 -406.673613) (xy 167.389402 -406.514488) (xy 167.316161 -406.351939)
			(xy 167.250234 -406.186289) (xy 167.191751 -406.017867) (xy 167.140829 -405.847006) (xy 167.097569 -405.674047)
			(xy 167.062057 -405.499332) (xy 167.034363 -405.323208) (xy 167.014542 -405.146026) (xy 167.002634 -404.968137)
			(xy 166.998662 -404.789894) (xy 161.904774 -404.789894) (xy 161.889384 -404.799785) (xy 161.839805 -404.822428)
			(xy 161.787508 -404.837784) (xy 161.733558 -404.845542) (xy 161.706306 -404.846028) (xy 160.842706 -404.846028)
			(xy 160.815454 -404.845525) (xy 160.761506 -404.837769) (xy 160.70921 -404.822415) (xy 160.659631 -404.799774)
			(xy 160.61378 -404.770307) (xy 160.572589 -404.734616) (xy 160.536896 -404.693425) (xy 160.507429 -404.647574)
			(xy 160.484788 -404.597996) (xy 160.469432 -404.5457) (xy 160.461675 -404.491752) (xy 159.024165 -404.491752)
			(xy 159.024165 -404.491756) (xy 159.016407 -404.545713) (xy 159.001048 -404.598016) (xy 158.978402 -404.647601)
			(xy 158.948929 -404.693458) (xy 158.91323 -404.734654) (xy 158.872031 -404.77035) (xy 158.826171 -404.799818)
			(xy 158.776584 -404.82246) (xy 158.724279 -404.837814) (xy 158.670322 -404.845567) (xy 158.643066 -404.846028)
			(xy 157.779466 -404.846028) (xy 157.752218 -404.845499) (xy 157.698277 -404.837739) (xy 157.645989 -404.822382)
			(xy 157.596418 -404.79974) (xy 157.550575 -404.770275) (xy 157.509391 -404.734585) (xy 157.473705 -404.693398)
			(xy 157.444243 -404.647552) (xy 157.421606 -404.597979) (xy 157.406253 -404.54569) (xy 157.398498 -404.491748)
			(xy 155.960842 -404.491748) (xy 155.960842 -404.491751) (xy 155.953086 -404.5457) (xy 155.937731 -404.597995)
			(xy 155.915091 -404.647573) (xy 155.885626 -404.693425) (xy 155.849935 -404.734617) (xy 155.808746 -404.77031)
			(xy 155.762896 -404.799778) (xy 155.71332 -404.822422) (xy 155.661025 -404.83778) (xy 155.607077 -404.84554)
			(xy 155.579826 -404.846028) (xy 154.716226 -404.846028) (xy 154.688973 -404.845526) (xy 154.635022 -404.837773)
			(xy 154.582724 -404.82242) (xy 154.533143 -404.79978) (xy 154.487289 -404.770314) (xy 154.446096 -404.734623)
			(xy 154.410401 -404.693431) (xy 154.380932 -404.647579) (xy 154.358289 -404.598) (xy 154.342933 -404.545703)
			(xy 154.335175 -404.491753) (xy 152.897665 -404.491753) (xy 152.897665 -404.491755) (xy 152.889907 -404.54571)
			(xy 152.87455 -404.598012) (xy 152.851905 -404.647595) (xy 152.822434 -404.693452) (xy 152.786737 -404.734647)
			(xy 152.745541 -404.770343) (xy 152.699683 -404.799812) (xy 152.650099 -404.822455) (xy 152.597796 -404.83781)
			(xy 152.543841 -404.845566) (xy 152.516586 -404.846028) (xy 151.652986 -404.846028) (xy 151.625737 -404.845501)
			(xy 151.571794 -404.837743) (xy 151.519503 -404.822388) (xy 151.46993 -404.799747) (xy 151.424084 -404.770282)
			(xy 151.382898 -404.734592) (xy 151.34721 -404.693404) (xy 151.317746 -404.647557) (xy 151.295108 -404.597984)
			(xy 151.279754 -404.545693) (xy 151.271998 -404.491749) (xy 149.834342 -404.491749) (xy 149.834342 -404.491751)
			(xy 149.826587 -404.545697) (xy 149.811233 -404.597991) (xy 149.788594 -404.647568) (xy 149.75913 -404.693418)
			(xy 149.723442 -404.734609) (xy 149.682255 -404.770303) (xy 149.636408 -404.799772) (xy 149.586834 -404.822417)
			(xy 149.534542 -404.837777) (xy 149.480597 -404.845539) (xy 149.453346 -404.846028) (xy 148.589746 -404.846028)
			(xy 148.562492 -404.845528) (xy 148.508539 -404.837777) (xy 148.456239 -404.822425) (xy 148.406655 -404.799787)
			(xy 148.360799 -404.770321) (xy 148.319603 -404.73463) (xy 148.283906 -404.693438) (xy 148.254435 -404.647585)
			(xy 148.231791 -404.598004) (xy 148.216433 -404.545706) (xy 148.208675 -404.491754) (xy 146.771142 -404.491754)
			(xy 146.763385 -404.545702) (xy 146.74803 -404.597999) (xy 146.725388 -404.647579) (xy 146.695921 -404.693431)
			(xy 146.660228 -404.734624) (xy 146.619036 -404.770317) (xy 146.573184 -404.799785) (xy 146.523605 -404.822428)
			(xy 146.471308 -404.837784) (xy 146.417358 -404.845542) (xy 146.390106 -404.846028) (xy 145.526506 -404.846028)
			(xy 145.499254 -404.845525) (xy 145.445306 -404.837769) (xy 145.39301 -404.822415) (xy 145.343431 -404.799774)
			(xy 145.29758 -404.770307) (xy 145.256389 -404.734616) (xy 145.220696 -404.693425) (xy 145.191229 -404.647574)
			(xy 145.168588 -404.597996) (xy 145.153232 -404.5457) (xy 145.145475 -404.491752) (xy 143.707965 -404.491752)
			(xy 143.707965 -404.491756) (xy 143.700207 -404.545713) (xy 143.684848 -404.598016) (xy 143.662202 -404.647601)
			(xy 143.632729 -404.693458) (xy 143.59703 -404.734654) (xy 143.555831 -404.77035) (xy 143.509971 -404.799818)
			(xy 143.460384 -404.82246) (xy 143.408079 -404.837814) (xy 143.354122 -404.845567) (xy 143.326866 -404.846028)
			(xy 142.463266 -404.846028) (xy 142.436018 -404.845499) (xy 142.382077 -404.837739) (xy 142.329789 -404.822382)
			(xy 142.280218 -404.79974) (xy 142.234375 -404.770275) (xy 142.193191 -404.734585) (xy 142.157505 -404.693398)
			(xy 142.128043 -404.647552) (xy 142.105406 -404.597979) (xy 142.090053 -404.54569) (xy 142.082298 -404.491748)
			(xy 140.644642 -404.491748) (xy 140.644642 -404.491751) (xy 140.636886 -404.5457) (xy 140.621531 -404.597995)
			(xy 140.598891 -404.647573) (xy 140.569426 -404.693425) (xy 140.533735 -404.734617) (xy 140.492546 -404.77031)
			(xy 140.446696 -404.799778) (xy 140.39712 -404.822422) (xy 140.344825 -404.83778) (xy 140.290877 -404.84554)
			(xy 140.263626 -404.846028) (xy 139.400026 -404.846028) (xy 139.372773 -404.845526) (xy 139.318822 -404.837773)
			(xy 139.266524 -404.82242) (xy 139.216943 -404.79978) (xy 139.171089 -404.770314) (xy 139.129896 -404.734623)
			(xy 139.094201 -404.693431) (xy 139.064732 -404.647579) (xy 139.042089 -404.598) (xy 139.026733 -404.545703)
			(xy 139.018975 -404.491753) (xy 137.581465 -404.491753) (xy 137.581465 -404.491755) (xy 137.573707 -404.54571)
			(xy 137.55835 -404.598012) (xy 137.535705 -404.647595) (xy 137.506234 -404.693452) (xy 137.470537 -404.734647)
			(xy 137.429341 -404.770343) (xy 137.383483 -404.799812) (xy 137.333899 -404.822455) (xy 137.281596 -404.83781)
			(xy 137.227641 -404.845566) (xy 137.200386 -404.846028) (xy 136.336786 -404.846028) (xy 136.309537 -404.845501)
			(xy 136.255594 -404.837743) (xy 136.203303 -404.822388) (xy 136.15373 -404.799747) (xy 136.107884 -404.770282)
			(xy 136.066698 -404.734592) (xy 136.03101 -404.693404) (xy 136.001546 -404.647557) (xy 135.978908 -404.597984)
			(xy 135.963554 -404.545693) (xy 135.955798 -404.491749) (xy 134.518142 -404.491749) (xy 134.518142 -404.491751)
			(xy 134.510387 -404.545697) (xy 134.495033 -404.597991) (xy 134.472394 -404.647568) (xy 134.44293 -404.693418)
			(xy 134.407242 -404.734609) (xy 134.366055 -404.770303) (xy 134.320208 -404.799772) (xy 134.270634 -404.822417)
			(xy 134.218342 -404.837777) (xy 134.164397 -404.845539) (xy 134.137146 -404.846028) (xy 133.273546 -404.846028)
			(xy 133.246292 -404.845528) (xy 133.192339 -404.837777) (xy 133.140039 -404.822425) (xy 133.090455 -404.799787)
			(xy 133.044599 -404.770321) (xy 133.003403 -404.73463) (xy 132.967706 -404.693438) (xy 132.938235 -404.647585)
			(xy 132.915591 -404.598004) (xy 132.900233 -404.545706) (xy 132.892475 -404.491754) (xy 131.454942 -404.491754)
			(xy 131.447185 -404.545702) (xy 131.43183 -404.597999) (xy 131.409188 -404.647579) (xy 131.379721 -404.693431)
			(xy 131.344028 -404.734624) (xy 131.302836 -404.770317) (xy 131.256984 -404.799785) (xy 131.207405 -404.822428)
			(xy 131.155108 -404.837784) (xy 131.101158 -404.845542) (xy 131.073906 -404.846028) (xy 130.210306 -404.846028)
			(xy 130.183054 -404.845525) (xy 130.129106 -404.837769) (xy 130.07681 -404.822415) (xy 130.027231 -404.799774)
			(xy 129.98138 -404.770307) (xy 129.940189 -404.734616) (xy 129.904496 -404.693425) (xy 129.875029 -404.647574)
			(xy 129.852388 -404.597996) (xy 129.837032 -404.5457) (xy 129.829275 -404.491752) (xy 128.391765 -404.491752)
			(xy 128.391765 -404.491756) (xy 128.384007 -404.545713) (xy 128.368648 -404.598016) (xy 128.346002 -404.647601)
			(xy 128.316529 -404.693458) (xy 128.28083 -404.734654) (xy 128.239631 -404.77035) (xy 128.193771 -404.799818)
			(xy 128.144184 -404.82246) (xy 128.091879 -404.837814) (xy 128.037922 -404.845567) (xy 128.010666 -404.846028)
			(xy 127.147066 -404.846028) (xy 127.119818 -404.845499) (xy 127.065877 -404.837739) (xy 127.013589 -404.822382)
			(xy 126.964018 -404.79974) (xy 126.918175 -404.770275) (xy 126.876991 -404.734585) (xy 126.841305 -404.693398)
			(xy 126.811843 -404.647552) (xy 126.789206 -404.597979) (xy 126.773853 -404.54569) (xy 126.766098 -404.491748)
			(xy 125.328442 -404.491748) (xy 125.328442 -404.491751) (xy 125.320686 -404.5457) (xy 125.305331 -404.597995)
			(xy 125.282691 -404.647573) (xy 125.253226 -404.693425) (xy 125.217535 -404.734617) (xy 125.176346 -404.77031)
			(xy 125.130496 -404.799778) (xy 125.08092 -404.822422) (xy 125.028625 -404.83778) (xy 124.974677 -404.84554)
			(xy 124.947426 -404.846028) (xy 124.083826 -404.846028) (xy 124.056573 -404.845526) (xy 124.002622 -404.837773)
			(xy 123.950324 -404.82242) (xy 123.900743 -404.79978) (xy 123.854889 -404.770314) (xy 123.813696 -404.734623)
			(xy 123.778001 -404.693431) (xy 123.748532 -404.647579) (xy 123.725889 -404.598) (xy 123.710533 -404.545703)
			(xy 123.702775 -404.491753) (xy 122.265265 -404.491753) (xy 122.265265 -404.491755) (xy 122.257507 -404.54571)
			(xy 122.24215 -404.598012) (xy 122.219505 -404.647595) (xy 122.190034 -404.693452) (xy 122.154337 -404.734647)
			(xy 122.113141 -404.770343) (xy 122.067283 -404.799812) (xy 122.017699 -404.822455) (xy 121.965396 -404.83781)
			(xy 121.911441 -404.845566) (xy 121.884186 -404.846028) (xy 121.020586 -404.846028) (xy 120.993337 -404.845501)
			(xy 120.939394 -404.837743) (xy 120.887103 -404.822388) (xy 120.83753 -404.799747) (xy 120.791684 -404.770282)
			(xy 120.750498 -404.734592) (xy 120.71481 -404.693404) (xy 120.685346 -404.647557) (xy 120.662708 -404.597984)
			(xy 120.647354 -404.545693) (xy 120.639598 -404.491749) (xy 119.201942 -404.491749) (xy 119.201942 -404.491751)
			(xy 119.194187 -404.545697) (xy 119.178833 -404.597991) (xy 119.156194 -404.647568) (xy 119.12673 -404.693418)
			(xy 119.091042 -404.734609) (xy 119.049855 -404.770303) (xy 119.004008 -404.799772) (xy 118.954434 -404.822417)
			(xy 118.902142 -404.837777) (xy 118.848197 -404.845539) (xy 118.820946 -404.846028) (xy 117.957346 -404.846028)
			(xy 117.930092 -404.845528) (xy 117.876139 -404.837777) (xy 117.823839 -404.822425) (xy 117.774255 -404.799787)
			(xy 117.728399 -404.770321) (xy 117.687203 -404.73463) (xy 117.651506 -404.693438) (xy 117.622035 -404.647585)
			(xy 117.599391 -404.598004) (xy 117.584033 -404.545706) (xy 117.576275 -404.491754) (xy 116.138742 -404.491754)
			(xy 116.130985 -404.545702) (xy 116.11563 -404.597999) (xy 116.092988 -404.647579) (xy 116.063521 -404.693431)
			(xy 116.027828 -404.734624) (xy 115.986636 -404.770317) (xy 115.940784 -404.799785) (xy 115.891205 -404.822428)
			(xy 115.838908 -404.837784) (xy 115.784958 -404.845542) (xy 115.757706 -404.846028) (xy 114.894106 -404.846028)
			(xy 114.866854 -404.845525) (xy 114.812906 -404.837769) (xy 114.76061 -404.822415) (xy 114.711031 -404.799774)
			(xy 114.66518 -404.770307) (xy 114.623989 -404.734616) (xy 114.588296 -404.693425) (xy 114.558829 -404.647574)
			(xy 114.536188 -404.597996) (xy 114.520832 -404.5457) (xy 114.513075 -404.491752) (xy 94.987465 -404.491752)
			(xy 94.987465 -404.491756) (xy 94.979707 -404.545713) (xy 94.964348 -404.598016) (xy 94.941702 -404.647602)
			(xy 94.912229 -404.693459) (xy 94.876529 -404.734655) (xy 94.83533 -404.77035) (xy 94.78947 -404.799819)
			(xy 94.739883 -404.822461) (xy 94.687578 -404.837814) (xy 94.63362 -404.845568) (xy 94.606364 -404.846028)
			(xy 93.742764 -404.846028) (xy 93.715516 -404.845499) (xy 93.661575 -404.837739) (xy 93.609287 -404.822382)
			(xy 93.559717 -404.79974) (xy 93.513874 -404.770274) (xy 93.47269 -404.734584) (xy 93.437004 -404.693397)
			(xy 93.407543 -404.647551) (xy 93.384906 -404.597979) (xy 93.369553 -404.54569) (xy 93.361798 -404.491748)
			(xy 91.924142 -404.491748) (xy 91.924142 -404.491752) (xy 91.916386 -404.5457) (xy 91.901031 -404.597996)
			(xy 91.878391 -404.647574) (xy 91.848925 -404.693425) (xy 91.813234 -404.734617) (xy 91.772045 -404.770311)
			(xy 91.726195 -404.799779) (xy 91.676618 -404.822423) (xy 91.624324 -404.837781) (xy 91.570376 -404.845541)
			(xy 91.543124 -404.846028) (xy 90.679524 -404.846028) (xy 90.652271 -404.845526) (xy 90.598321 -404.837773)
			(xy 90.546023 -404.822419) (xy 90.496442 -404.799779) (xy 90.450588 -404.770314) (xy 90.409395 -404.734622)
			(xy 90.373701 -404.693431) (xy 90.344232 -404.647579) (xy 90.321589 -404.598) (xy 90.306233 -404.545703)
			(xy 90.298475 -404.491753) (xy 88.860965 -404.491753) (xy 88.860965 -404.491755) (xy 88.853207 -404.54571)
			(xy 88.83785 -404.598012) (xy 88.815205 -404.647596) (xy 88.785734 -404.693452) (xy 88.750036 -404.734648)
			(xy 88.70884 -404.770343) (xy 88.662982 -404.799812) (xy 88.613397 -404.822455) (xy 88.561095 -404.837811)
			(xy 88.507139 -404.845566) (xy 88.479884 -404.846028) (xy 87.616284 -404.846028) (xy 87.589035 -404.845501)
			(xy 87.535092 -404.837743) (xy 87.482802 -404.822387) (xy 87.433229 -404.799746) (xy 87.387383 -404.770281)
			(xy 87.346197 -404.734591) (xy 87.310509 -404.693404) (xy 87.281046 -404.647557) (xy 87.258407 -404.597983)
			(xy 87.243054 -404.545692) (xy 87.235298 -404.491749) (xy 85.797642 -404.491749) (xy 85.797642 -404.491751)
			(xy 85.789887 -404.545697) (xy 85.774533 -404.597991) (xy 85.751894 -404.647568) (xy 85.72243 -404.693419)
			(xy 85.686741 -404.73461) (xy 85.645554 -404.770304) (xy 85.599707 -404.799773) (xy 85.550133 -404.822417)
			(xy 85.49784 -404.837777) (xy 85.443895 -404.845539) (xy 85.416644 -404.846028) (xy 84.553044 -404.846028)
			(xy 84.525791 -404.845528) (xy 84.471838 -404.837776) (xy 84.419537 -404.822425) (xy 84.369954 -404.799786)
			(xy 84.324098 -404.770321) (xy 84.282902 -404.734629) (xy 84.247206 -404.693437) (xy 84.217735 -404.647584)
			(xy 84.195091 -404.598004) (xy 84.179733 -404.545705) (xy 84.171975 -404.491753) (xy 82.734442 -404.491753)
			(xy 82.726685 -404.545703) (xy 82.71133 -404.598) (xy 82.688688 -404.647579) (xy 82.65922 -404.693432)
			(xy 82.623527 -404.734624) (xy 82.582335 -404.770318) (xy 82.536483 -404.799786) (xy 82.486904 -404.822428)
			(xy 82.434607 -404.837785) (xy 82.380656 -404.845542) (xy 82.353404 -404.846028) (xy 81.489804 -404.846028)
			(xy 81.462552 -404.845525) (xy 81.408604 -404.837769) (xy 81.356308 -404.822414) (xy 81.30673 -404.799773)
			(xy 81.260879 -404.770307) (xy 81.219688 -404.734615) (xy 81.183996 -404.693424) (xy 81.154529 -404.647573)
			(xy 81.131887 -404.597995) (xy 81.116532 -404.5457) (xy 81.108775 -404.491752) (xy 79.671265 -404.491752)
			(xy 79.671265 -404.491756) (xy 79.663507 -404.545713) (xy 79.648148 -404.598016) (xy 79.625502 -404.647602)
			(xy 79.596029 -404.693459) (xy 79.560329 -404.734655) (xy 79.51913 -404.77035) (xy 79.47327 -404.799819)
			(xy 79.423683 -404.822461) (xy 79.371378 -404.837814) (xy 79.31742 -404.845568) (xy 79.290164 -404.846028)
			(xy 78.426564 -404.846028) (xy 78.399316 -404.845499) (xy 78.345375 -404.837739) (xy 78.293087 -404.822382)
			(xy 78.243517 -404.79974) (xy 78.197674 -404.770274) (xy 78.15649 -404.734584) (xy 78.120804 -404.693397)
			(xy 78.091343 -404.647551) (xy 78.068706 -404.597979) (xy 78.053353 -404.54569) (xy 78.045598 -404.491748)
			(xy 76.607942 -404.491748) (xy 76.607942 -404.491752) (xy 76.600186 -404.5457) (xy 76.584831 -404.597996)
			(xy 76.562191 -404.647574) (xy 76.532725 -404.693425) (xy 76.497034 -404.734617) (xy 76.455845 -404.770311)
			(xy 76.409995 -404.799779) (xy 76.360418 -404.822423) (xy 76.308124 -404.837781) (xy 76.254176 -404.845541)
			(xy 76.226924 -404.846028) (xy 75.363324 -404.846028) (xy 75.336071 -404.845526) (xy 75.282121 -404.837773)
			(xy 75.229823 -404.822419) (xy 75.180242 -404.799779) (xy 75.134388 -404.770314) (xy 75.093195 -404.734622)
			(xy 75.057501 -404.693431) (xy 75.028032 -404.647579) (xy 75.005389 -404.598) (xy 74.990033 -404.545703)
			(xy 74.982275 -404.491753) (xy 73.544765 -404.491753) (xy 73.544765 -404.491755) (xy 73.537007 -404.54571)
			(xy 73.52165 -404.598012) (xy 73.499005 -404.647596) (xy 73.469534 -404.693452) (xy 73.433836 -404.734648)
			(xy 73.39264 -404.770343) (xy 73.346782 -404.799812) (xy 73.297197 -404.822455) (xy 73.244895 -404.837811)
			(xy 73.190939 -404.845566) (xy 73.163684 -404.846028) (xy 72.300084 -404.846028) (xy 72.272835 -404.845501)
			(xy 72.218892 -404.837743) (xy 72.166602 -404.822387) (xy 72.117029 -404.799746) (xy 72.071183 -404.770281)
			(xy 72.029997 -404.734591) (xy 71.994309 -404.693404) (xy 71.964846 -404.647557) (xy 71.942207 -404.597983)
			(xy 71.926854 -404.545692) (xy 71.919098 -404.491749) (xy 70.481442 -404.491749) (xy 70.481442 -404.491751)
			(xy 70.473687 -404.545697) (xy 70.458333 -404.597991) (xy 70.435694 -404.647568) (xy 70.40623 -404.693419)
			(xy 70.370541 -404.73461) (xy 70.329354 -404.770304) (xy 70.283507 -404.799773) (xy 70.233933 -404.822417)
			(xy 70.18164 -404.837777) (xy 70.127695 -404.845539) (xy 70.100444 -404.846028) (xy 69.236844 -404.846028)
			(xy 69.209591 -404.845528) (xy 69.155638 -404.837776) (xy 69.103337 -404.822425) (xy 69.053754 -404.799786)
			(xy 69.007898 -404.770321) (xy 68.966702 -404.734629) (xy 68.931006 -404.693437) (xy 68.901535 -404.647584)
			(xy 68.878891 -404.598004) (xy 68.863533 -404.545705) (xy 68.855775 -404.491753) (xy 67.418242 -404.491753)
			(xy 67.410485 -404.545703) (xy 67.39513 -404.598) (xy 67.372488 -404.647579) (xy 67.34302 -404.693432)
			(xy 67.307327 -404.734624) (xy 67.266135 -404.770318) (xy 67.220283 -404.799786) (xy 67.170704 -404.822428)
			(xy 67.118407 -404.837785) (xy 67.064456 -404.845542) (xy 67.037204 -404.846028) (xy 66.173604 -404.846028)
			(xy 66.146352 -404.845525) (xy 66.092404 -404.837769) (xy 66.040108 -404.822414) (xy 65.99053 -404.799773)
			(xy 65.944679 -404.770307) (xy 65.903488 -404.734615) (xy 65.867796 -404.693424) (xy 65.838329 -404.647573)
			(xy 65.815687 -404.597995) (xy 65.800332 -404.5457) (xy 65.792575 -404.491752) (xy 64.355065 -404.491752)
			(xy 64.355065 -404.491756) (xy 64.347307 -404.545713) (xy 64.331948 -404.598016) (xy 64.309302 -404.647602)
			(xy 64.279829 -404.693459) (xy 64.244129 -404.734655) (xy 64.20293 -404.77035) (xy 64.15707 -404.799819)
			(xy 64.107483 -404.822461) (xy 64.055178 -404.837814) (xy 64.00122 -404.845568) (xy 63.973964 -404.846028)
			(xy 63.110364 -404.846028) (xy 63.083116 -404.845499) (xy 63.029175 -404.837739) (xy 62.976887 -404.822382)
			(xy 62.927317 -404.79974) (xy 62.881474 -404.770274) (xy 62.84029 -404.734584) (xy 62.804604 -404.693397)
			(xy 62.775143 -404.647551) (xy 62.752506 -404.597979) (xy 62.737153 -404.54569) (xy 62.729398 -404.491748)
			(xy 61.291742 -404.491748) (xy 61.291742 -404.491752) (xy 61.283986 -404.5457) (xy 61.268631 -404.597996)
			(xy 61.245991 -404.647574) (xy 61.216525 -404.693425) (xy 61.180834 -404.734617) (xy 61.139645 -404.770311)
			(xy 61.093795 -404.799779) (xy 61.044218 -404.822423) (xy 60.991924 -404.837781) (xy 60.937976 -404.845541)
			(xy 60.910724 -404.846028) (xy 60.047124 -404.846028) (xy 60.019871 -404.845526) (xy 59.965921 -404.837773)
			(xy 59.913623 -404.822419) (xy 59.864042 -404.799779) (xy 59.818188 -404.770314) (xy 59.776995 -404.734622)
			(xy 59.741301 -404.693431) (xy 59.711832 -404.647579) (xy 59.689189 -404.598) (xy 59.673833 -404.545703)
			(xy 59.666075 -404.491753) (xy 58.228565 -404.491753) (xy 58.228565 -404.491755) (xy 58.220807 -404.54571)
			(xy 58.20545 -404.598012) (xy 58.182805 -404.647596) (xy 58.153334 -404.693452) (xy 58.117636 -404.734648)
			(xy 58.07644 -404.770343) (xy 58.030582 -404.799812) (xy 57.980997 -404.822455) (xy 57.928695 -404.837811)
			(xy 57.874739 -404.845566) (xy 57.847484 -404.846028) (xy 56.983884 -404.846028) (xy 56.956635 -404.845501)
			(xy 56.902692 -404.837743) (xy 56.850402 -404.822387) (xy 56.800829 -404.799746) (xy 56.754983 -404.770281)
			(xy 56.713797 -404.734591) (xy 56.678109 -404.693404) (xy 56.648646 -404.647557) (xy 56.626007 -404.597983)
			(xy 56.610654 -404.545692) (xy 56.602898 -404.491749) (xy 55.165242 -404.491749) (xy 55.165242 -404.491751)
			(xy 55.157487 -404.545697) (xy 55.142133 -404.597991) (xy 55.119494 -404.647568) (xy 55.09003 -404.693419)
			(xy 55.054341 -404.73461) (xy 55.013154 -404.770304) (xy 54.967307 -404.799773) (xy 54.917733 -404.822417)
			(xy 54.86544 -404.837777) (xy 54.811495 -404.845539) (xy 54.784244 -404.846028) (xy 53.920644 -404.846028)
			(xy 53.893391 -404.845528) (xy 53.839438 -404.837776) (xy 53.787137 -404.822425) (xy 53.737554 -404.799786)
			(xy 53.691698 -404.770321) (xy 53.650502 -404.734629) (xy 53.614806 -404.693437) (xy 53.585335 -404.647584)
			(xy 53.562691 -404.598004) (xy 53.547333 -404.545705) (xy 53.539575 -404.491753) (xy 52.102042 -404.491753)
			(xy 52.094285 -404.545703) (xy 52.07893 -404.598) (xy 52.056288 -404.647579) (xy 52.02682 -404.693432)
			(xy 51.991127 -404.734624) (xy 51.949935 -404.770318) (xy 51.904083 -404.799786) (xy 51.854504 -404.822428)
			(xy 51.802207 -404.837785) (xy 51.748256 -404.845542) (xy 51.721004 -404.846028) (xy 50.857404 -404.846028)
			(xy 50.830152 -404.845525) (xy 50.776204 -404.837769) (xy 50.723908 -404.822414) (xy 50.67433 -404.799773)
			(xy 50.628479 -404.770307) (xy 50.587288 -404.734615) (xy 50.551596 -404.693424) (xy 50.522129 -404.647573)
			(xy 50.499487 -404.597995) (xy 50.484132 -404.5457) (xy 50.476375 -404.491752) (xy 49.038865 -404.491752)
			(xy 49.038865 -404.491756) (xy 49.031107 -404.545713) (xy 49.015748 -404.598016) (xy 48.993102 -404.647602)
			(xy 48.963629 -404.693459) (xy 48.927929 -404.734655) (xy 48.88673 -404.77035) (xy 48.84087 -404.799819)
			(xy 48.791283 -404.822461) (xy 48.738978 -404.837814) (xy 48.68502 -404.845568) (xy 48.657764 -404.846028)
			(xy 47.794164 -404.846028) (xy 47.766916 -404.845499) (xy 47.712975 -404.837739) (xy 47.660687 -404.822382)
			(xy 47.611117 -404.79974) (xy 47.565274 -404.770274) (xy 47.52409 -404.734584) (xy 47.488404 -404.693397)
			(xy 47.458943 -404.647551) (xy 47.436306 -404.597979) (xy 47.420953 -404.54569) (xy 47.413198 -404.491748)
			(xy 45.559703 -404.491748) (xy 45.562463 -404.52264) (xy 45.570405 -404.70075) (xy 45.570902 -404.789894)
			(xy 45.570405 -404.879038) (xy 45.562463 -405.057148) (xy 45.546595 -405.234728) (xy 45.522831 -405.411424)
			(xy 45.49122 -405.586887) (xy 45.479552 -405.638385) (xy 104.009796 -405.638385) (xy 104.013672 -405.584006)
			(xy 104.025246 -405.530732) (xy 104.044281 -405.479646) (xy 104.070391 -405.431789) (xy 104.103044 -405.388132)
			(xy 104.121966 -405.368506) (xy 104.732582 -404.757636) (xy 104.75423 -404.736857) (xy 104.802784 -404.701606)
			(xy 104.856253 -404.67438) (xy 104.91332 -404.655848) (xy 104.972583 -404.646465) (xy 105.002584 -404.645876)
			(xy 105.029856 -404.646316) (xy 105.083846 -404.654077) (xy 105.136181 -404.669444) (xy 105.185797 -404.692102)
			(xy 105.231683 -404.721592) (xy 105.272904 -404.757312) (xy 105.308622 -404.798535) (xy 105.338108 -404.844422)
			(xy 105.360764 -404.894039) (xy 105.376127 -404.946376) (xy 105.383885 -405.000366) (xy 105.384346 -405.027638)
			(xy 105.383744 -405.057639) (xy 105.374371 -405.116904) (xy 105.355845 -405.173974) (xy 105.328623 -405.227445)
			(xy 105.29971 -405.267273) (xy 106.824184 -405.267273) (xy 106.824184 -405.212727) (xy 106.831947 -405.158735)
			(xy 106.847315 -405.106398) (xy 106.869976 -405.05678) (xy 106.899467 -405.010893) (xy 106.935189 -404.969671)
			(xy 106.976414 -404.933951) (xy 107.022303 -404.904463) (xy 107.071922 -404.881806) (xy 107.12426 -404.866441)
			(xy 107.178252 -404.858682) (xy 107.205526 -404.85822) (xy 108.069126 -404.85822) (xy 108.096393 -404.858744)
			(xy 108.150371 -404.866508) (xy 108.202695 -404.881875) (xy 108.2523 -404.904532) (xy 108.298175 -404.934017)
			(xy 108.339388 -404.969731) (xy 108.375098 -405.010946) (xy 108.404581 -405.056823) (xy 108.427234 -405.106429)
			(xy 108.442597 -405.158754) (xy 108.450358 -405.212733) (xy 108.450358 -405.267267) (xy 108.442597 -405.321246)
			(xy 108.427234 -405.373571) (xy 108.404581 -405.423177) (xy 108.375098 -405.469054) (xy 108.339388 -405.510269)
			(xy 108.298175 -405.545983) (xy 108.2523 -405.575468) (xy 108.202695 -405.598125) (xy 108.150371 -405.613492)
			(xy 108.096393 -405.621256) (xy 108.069126 -405.621744) (xy 107.205526 -405.621744) (xy 107.178252 -405.621318)
			(xy 107.12426 -405.613559) (xy 107.071922 -405.598194) (xy 107.022303 -405.575537) (xy 106.976414 -405.546049)
			(xy 106.935189 -405.510329) (xy 106.899467 -405.469107) (xy 106.869976 -405.42322) (xy 106.847315 -405.373602)
			(xy 106.831947 -405.321265) (xy 106.824184 -405.267273) (xy 105.29971 -405.267273) (xy 105.293374 -405.276001)
			(xy 105.272586 -405.29764) (xy 104.661716 -405.908256) (xy 104.642167 -405.927256) (xy 104.598511 -405.959909)
			(xy 104.550654 -405.986019) (xy 104.499568 -406.005054) (xy 104.446294 -406.016628) (xy 104.391915 -406.020504)
			(xy 104.337538 -406.016603) (xy 104.284269 -406.005006) (xy 104.233192 -405.985949) (xy 104.185346 -405.959818)
			(xy 104.141704 -405.927145) (xy 104.103155 -405.888596) (xy 104.070482 -405.844954) (xy 104.044351 -405.797108)
			(xy 104.025294 -405.746031) (xy 104.013697 -405.692762) (xy 104.009796 -405.638385) (xy 45.479552 -405.638385)
			(xy 45.451824 -405.760767) (xy 45.404722 -405.93272) (xy 45.350006 -406.102404) (xy 45.287785 -406.269481)
			(xy 45.218184 -406.433622) (xy 45.141339 -406.594498) (xy 45.057405 -406.751792) (xy 44.966547 -406.905191)
			(xy 44.883756 -407.031749) (xy 48.944798 -407.031749) (xy 48.944798 -406.977251) (xy 48.952554 -406.923308)
			(xy 48.967907 -406.871017) (xy 48.990546 -406.821443) (xy 49.020009 -406.775596) (xy 49.055697 -406.734409)
			(xy 49.096883 -406.698719) (xy 49.142729 -406.669254) (xy 49.192302 -406.646613) (xy 49.244592 -406.631257)
			(xy 49.298535 -406.623499) (xy 49.325784 -406.623012) (xy 50.189384 -406.623012) (xy 50.216639 -406.623434)
			(xy 50.270595 -406.631189) (xy 50.322897 -406.646545) (xy 50.372482 -406.669188) (xy 50.41834 -406.698657)
			(xy 50.459536 -406.734352) (xy 50.495234 -406.775548) (xy 50.524705 -406.821404) (xy 50.54735 -406.870988)
			(xy 50.562707 -406.92329) (xy 50.570465 -406.977245) (xy 50.570465 -407.031753) (xy 52.007975 -407.031753)
			(xy 52.007975 -406.977247) (xy 52.015733 -406.923297) (xy 52.031089 -406.871) (xy 52.053732 -406.821421)
			(xy 52.083201 -406.775569) (xy 52.118895 -406.734378) (xy 52.160088 -406.698686) (xy 52.205942 -406.669221)
			(xy 52.255523 -406.646581) (xy 52.307821 -406.631227) (xy 52.361771 -406.623474) (xy 52.389024 -406.623012)
			(xy 53.252624 -406.623012) (xy 53.279876 -406.623459) (xy 53.333824 -406.631219) (xy 53.386118 -406.646577)
			(xy 53.435695 -406.669221) (xy 53.481545 -406.698689) (xy 53.522734 -406.734383) (xy 53.558425 -406.775575)
			(xy 53.587891 -406.821426) (xy 53.610531 -406.871004) (xy 53.625886 -406.9233) (xy 53.633642 -406.977248)
			(xy 53.633642 -407.031748) (xy 55.071298 -407.031748) (xy 55.071298 -406.977252) (xy 55.079053 -406.92331)
			(xy 55.094406 -406.871021) (xy 55.117043 -406.821449) (xy 55.146504 -406.775603) (xy 55.18219 -406.734416)
			(xy 55.223374 -406.698726) (xy 55.269217 -406.66926) (xy 55.318787 -406.646618) (xy 55.371075 -406.631261)
			(xy 55.425016 -406.623501) (xy 55.452264 -406.623012) (xy 56.315864 -406.623012) (xy 56.34312 -406.623432)
			(xy 56.397078 -406.631186) (xy 56.449383 -406.646539) (xy 56.49897 -406.669181) (xy 56.54483 -406.69865)
			(xy 56.586029 -406.734345) (xy 56.621729 -406.775541) (xy 56.651202 -406.821398) (xy 56.673848 -406.870984)
			(xy 56.689207 -406.923287) (xy 56.696965 -406.977244) (xy 56.696965 -407.031752) (xy 58.134475 -407.031752)
			(xy 58.134475 -406.977248) (xy 58.142232 -406.9233) (xy 58.157587 -406.871005) (xy 58.180229 -406.821427)
			(xy 58.209696 -406.775576) (xy 58.245388 -406.734385) (xy 58.286579 -406.698693) (xy 58.33243 -406.669227)
			(xy 58.382008 -406.646586) (xy 58.434304 -406.631231) (xy 58.488252 -406.623475) (xy 58.515504 -406.623012)
			(xy 59.379104 -406.623012) (xy 59.406356 -406.623458) (xy 59.460307 -406.631215) (xy 59.512604 -406.646572)
			(xy 59.562183 -406.669214) (xy 59.608035 -406.698682) (xy 59.649227 -406.734376) (xy 59.68492 -406.775568)
			(xy 59.714388 -406.821421) (xy 59.73703 -406.871) (xy 59.752385 -406.923297) (xy 59.760142 -406.977248)
			(xy 59.760142 -407.031752) (xy 59.760142 -407.031753) (xy 61.197675 -407.031753) (xy 61.197675 -406.977247)
			(xy 61.205433 -406.923295) (xy 61.220791 -406.870996) (xy 61.243435 -406.821416) (xy 61.272906 -406.775563)
			(xy 61.308602 -406.734371) (xy 61.349798 -406.698679) (xy 61.395654 -406.669214) (xy 61.445237 -406.646575)
			(xy 61.497538 -406.631224) (xy 61.551491 -406.623472) (xy 61.578744 -406.623012) (xy 62.442344 -406.623012)
			(xy 62.469595 -406.623461) (xy 62.52354 -406.631223) (xy 62.575833 -406.646583) (xy 62.625407 -406.669227)
			(xy 62.671254 -406.698696) (xy 62.712441 -406.73439) (xy 62.74813 -406.775581) (xy 62.777594 -406.821432)
			(xy 62.800233 -406.871009) (xy 62.815587 -406.923303) (xy 62.823342 -406.977249) (xy 62.823342 -407.031749)
			(xy 64.260998 -407.031749) (xy 64.260998 -406.977251) (xy 64.268754 -406.923308) (xy 64.284107 -406.871017)
			(xy 64.306746 -406.821443) (xy 64.336209 -406.775596) (xy 64.371897 -406.734409) (xy 64.413083 -406.698719)
			(xy 64.458929 -406.669254) (xy 64.508502 -406.646613) (xy 64.560792 -406.631257) (xy 64.614735 -406.623499)
			(xy 64.641984 -406.623012) (xy 65.505584 -406.623012) (xy 65.532839 -406.623434) (xy 65.586795 -406.631189)
			(xy 65.639097 -406.646545) (xy 65.688682 -406.669188) (xy 65.73454 -406.698657) (xy 65.775736 -406.734352)
			(xy 65.811434 -406.775548) (xy 65.840905 -406.821404) (xy 65.86355 -406.870988) (xy 65.878907 -406.92329)
			(xy 65.886665 -406.977245) (xy 65.886665 -407.031753) (xy 67.324175 -407.031753) (xy 67.324175 -406.977247)
			(xy 67.331933 -406.923297) (xy 67.347289 -406.871) (xy 67.369932 -406.821421) (xy 67.399401 -406.775569)
			(xy 67.435095 -406.734378) (xy 67.476288 -406.698686) (xy 67.522142 -406.669221) (xy 67.571723 -406.646581)
			(xy 67.624021 -406.631227) (xy 67.677971 -406.623474) (xy 67.705224 -406.623012) (xy 68.568824 -406.623012)
			(xy 68.596076 -406.623459) (xy 68.650024 -406.631219) (xy 68.702318 -406.646577) (xy 68.751895 -406.669221)
			(xy 68.797745 -406.698689) (xy 68.838934 -406.734383) (xy 68.874625 -406.775575) (xy 68.904091 -406.821426)
			(xy 68.926731 -406.871004) (xy 68.942086 -406.9233) (xy 68.949842 -406.977248) (xy 68.949842 -407.031748)
			(xy 70.387498 -407.031748) (xy 70.387498 -406.977252) (xy 70.395253 -406.92331) (xy 70.410606 -406.871021)
			(xy 70.433243 -406.821449) (xy 70.462704 -406.775603) (xy 70.49839 -406.734416) (xy 70.539574 -406.698726)
			(xy 70.585417 -406.66926) (xy 70.634987 -406.646618) (xy 70.687275 -406.631261) (xy 70.741216 -406.623501)
			(xy 70.768464 -406.623012) (xy 71.632064 -406.623012) (xy 71.65932 -406.623432) (xy 71.713278 -406.631186)
			(xy 71.765583 -406.646539) (xy 71.81517 -406.669181) (xy 71.86103 -406.69865) (xy 71.902229 -406.734345)
			(xy 71.937929 -406.775541) (xy 71.967402 -406.821398) (xy 71.990048 -406.870984) (xy 72.005407 -406.923287)
			(xy 72.013165 -406.977244) (xy 72.013165 -407.031752) (xy 73.450675 -407.031752) (xy 73.450675 -406.977248)
			(xy 73.458432 -406.9233) (xy 73.473787 -406.871005) (xy 73.496429 -406.821427) (xy 73.525896 -406.775576)
			(xy 73.561588 -406.734385) (xy 73.602779 -406.698693) (xy 73.64863 -406.669227) (xy 73.698208 -406.646586)
			(xy 73.750504 -406.631231) (xy 73.804452 -406.623475) (xy 73.831704 -406.623012) (xy 74.695304 -406.623012)
			(xy 74.722556 -406.623458) (xy 74.776507 -406.631215) (xy 74.828804 -406.646572) (xy 74.878383 -406.669214)
			(xy 74.924235 -406.698682) (xy 74.965427 -406.734376) (xy 75.00112 -406.775568) (xy 75.030588 -406.821421)
			(xy 75.05323 -406.871) (xy 75.068585 -406.923297) (xy 75.076342 -406.977248) (xy 75.076342 -407.031752)
			(xy 75.076342 -407.031753) (xy 76.513875 -407.031753) (xy 76.513875 -406.977247) (xy 76.521633 -406.923295)
			(xy 76.536991 -406.870996) (xy 76.559635 -406.821416) (xy 76.589106 -406.775563) (xy 76.624802 -406.734371)
			(xy 76.665998 -406.698679) (xy 76.711854 -406.669214) (xy 76.761437 -406.646575) (xy 76.813738 -406.631224)
			(xy 76.867691 -406.623472) (xy 76.894944 -406.623012) (xy 77.758544 -406.623012) (xy 77.785795 -406.623461)
			(xy 77.83974 -406.631223) (xy 77.892033 -406.646583) (xy 77.941607 -406.669227) (xy 77.987454 -406.698696)
			(xy 78.028641 -406.73439) (xy 78.06433 -406.775581) (xy 78.093794 -406.821432) (xy 78.116433 -406.871009)
			(xy 78.131787 -406.923303) (xy 78.139542 -406.977249) (xy 78.139542 -407.031749) (xy 79.577198 -407.031749)
			(xy 79.577198 -406.977251) (xy 79.584954 -406.923308) (xy 79.600307 -406.871017) (xy 79.622946 -406.821443)
			(xy 79.652409 -406.775596) (xy 79.688097 -406.734409) (xy 79.729283 -406.698719) (xy 79.775129 -406.669254)
			(xy 79.824702 -406.646613) (xy 79.876992 -406.631257) (xy 79.930935 -406.623499) (xy 79.958184 -406.623012)
			(xy 80.821784 -406.623012) (xy 80.849039 -406.623434) (xy 80.902995 -406.631189) (xy 80.955297 -406.646545)
			(xy 81.004882 -406.669188) (xy 81.05074 -406.698657) (xy 81.091936 -406.734352) (xy 81.127634 -406.775548)
			(xy 81.157105 -406.821404) (xy 81.17975 -406.870988) (xy 81.195107 -406.92329) (xy 81.202865 -406.977245)
			(xy 81.202865 -407.031753) (xy 82.640375 -407.031753) (xy 82.640375 -406.977247) (xy 82.648133 -406.923297)
			(xy 82.663489 -406.871) (xy 82.686132 -406.821421) (xy 82.715601 -406.775569) (xy 82.751295 -406.734378)
			(xy 82.792488 -406.698686) (xy 82.838342 -406.669221) (xy 82.887923 -406.646581) (xy 82.940221 -406.631227)
			(xy 82.994171 -406.623474) (xy 83.021424 -406.623012) (xy 83.885024 -406.623012) (xy 83.912276 -406.623459)
			(xy 83.966224 -406.631219) (xy 84.018518 -406.646577) (xy 84.068095 -406.669221) (xy 84.113945 -406.698689)
			(xy 84.155134 -406.734383) (xy 84.190825 -406.775575) (xy 84.220291 -406.821426) (xy 84.242931 -406.871004)
			(xy 84.258286 -406.9233) (xy 84.266042 -406.977248) (xy 84.266042 -407.031748) (xy 85.703698 -407.031748)
			(xy 85.703698 -406.977252) (xy 85.711453 -406.92331) (xy 85.726806 -406.871021) (xy 85.749443 -406.821449)
			(xy 85.778904 -406.775603) (xy 85.81459 -406.734416) (xy 85.855774 -406.698726) (xy 85.901617 -406.66926)
			(xy 85.951187 -406.646618) (xy 86.003475 -406.631261) (xy 86.057416 -406.623501) (xy 86.084664 -406.623012)
			(xy 86.948264 -406.623012) (xy 86.97552 -406.623432) (xy 87.029478 -406.631186) (xy 87.081783 -406.646539)
			(xy 87.13137 -406.669181) (xy 87.17723 -406.69865) (xy 87.218429 -406.734345) (xy 87.254129 -406.775541)
			(xy 87.283602 -406.821398) (xy 87.306248 -406.870984) (xy 87.321607 -406.923287) (xy 87.329365 -406.977244)
			(xy 87.329365 -407.031752) (xy 88.766875 -407.031752) (xy 88.766875 -406.977248) (xy 88.774632 -406.9233)
			(xy 88.789987 -406.871005) (xy 88.812629 -406.821427) (xy 88.842096 -406.775576) (xy 88.877788 -406.734385)
			(xy 88.918979 -406.698693) (xy 88.96483 -406.669227) (xy 89.014408 -406.646586) (xy 89.066704 -406.631231)
			(xy 89.120652 -406.623475) (xy 89.147904 -406.623012) (xy 90.011504 -406.623012) (xy 90.038756 -406.623458)
			(xy 90.092707 -406.631215) (xy 90.145004 -406.646572) (xy 90.194583 -406.669214) (xy 90.240435 -406.698682)
			(xy 90.281627 -406.734376) (xy 90.31732 -406.775568) (xy 90.346788 -406.821421) (xy 90.36943 -406.871)
			(xy 90.384785 -406.923297) (xy 90.392542 -406.977248) (xy 90.392542 -407.031752) (xy 90.392542 -407.031753)
			(xy 91.830075 -407.031753) (xy 91.830075 -406.977247) (xy 91.837833 -406.923295) (xy 91.853191 -406.870996)
			(xy 91.875835 -406.821416) (xy 91.905306 -406.775563) (xy 91.941002 -406.734371) (xy 91.982198 -406.698679)
			(xy 92.028054 -406.669214) (xy 92.077637 -406.646575) (xy 92.129938 -406.631224) (xy 92.183891 -406.623472)
			(xy 92.211144 -406.623012) (xy 93.074744 -406.623012) (xy 93.101995 -406.623461) (xy 93.15594 -406.631223)
			(xy 93.208233 -406.646583) (xy 93.257807 -406.669227) (xy 93.303654 -406.698696) (xy 93.344841 -406.73439)
			(xy 93.38053 -406.775581) (xy 93.409994 -406.821432) (xy 93.432633 -406.871009) (xy 93.447987 -406.923303)
			(xy 93.455742 -406.977249) (xy 93.455742 -407.031749) (xy 94.893398 -407.031749) (xy 94.893398 -406.977251)
			(xy 94.901154 -406.923308) (xy 94.916507 -406.871017) (xy 94.939146 -406.821443) (xy 94.968609 -406.775596)
			(xy 95.004297 -406.734409) (xy 95.045483 -406.698719) (xy 95.091329 -406.669254) (xy 95.140902 -406.646613)
			(xy 95.193192 -406.631257) (xy 95.247135 -406.623499) (xy 95.274384 -406.623012) (xy 96.137984 -406.623012)
			(xy 96.165239 -406.623434) (xy 96.219195 -406.631189) (xy 96.271497 -406.646545) (xy 96.321082 -406.669188)
			(xy 96.36694 -406.698657) (xy 96.408136 -406.734352) (xy 96.443834 -406.775548) (xy 96.473305 -406.821404)
			(xy 96.49595 -406.870988) (xy 96.511307 -406.92329) (xy 96.519065 -406.977245) (xy 96.519065 -407.031753)
			(xy 116.044675 -407.031753) (xy 116.044675 -406.977247) (xy 116.052433 -406.923297) (xy 116.067789 -406.871)
			(xy 116.090432 -406.821421) (xy 116.119901 -406.775569) (xy 116.155596 -406.734377) (xy 116.196789 -406.698686)
			(xy 116.242643 -406.66922) (xy 116.292224 -406.64658) (xy 116.344522 -406.631227) (xy 116.398473 -406.623474)
			(xy 116.425726 -406.623012) (xy 117.289326 -406.623012) (xy 117.316577 -406.62346) (xy 117.370525 -406.63122)
			(xy 117.42282 -406.646578) (xy 117.472396 -406.669222) (xy 117.518246 -406.69869) (xy 117.559435 -406.734383)
			(xy 117.595126 -406.775575) (xy 117.624591 -406.821427) (xy 117.647231 -406.871005) (xy 117.662586 -406.9233)
			(xy 117.670342 -406.977249) (xy 117.670342 -407.031748) (xy 119.107998 -407.031748) (xy 119.107998 -406.977252)
			(xy 119.115753 -406.92331) (xy 119.131106 -406.871021) (xy 119.153743 -406.821448) (xy 119.183205 -406.775602)
			(xy 119.218891 -406.734415) (xy 119.260075 -406.698725) (xy 119.305918 -406.66926) (xy 119.355489 -406.646618)
			(xy 119.407777 -406.631261) (xy 119.461718 -406.623501) (xy 119.488966 -406.623012) (xy 120.352566 -406.623012)
			(xy 120.379822 -406.623433) (xy 120.433779 -406.631186) (xy 120.486084 -406.64654) (xy 120.535671 -406.669182)
			(xy 120.581531 -406.69865) (xy 120.62273 -406.734346) (xy 120.658429 -406.775542) (xy 120.687902 -406.821399)
			(xy 120.710548 -406.870984) (xy 120.725907 -406.923287) (xy 120.733665 -406.977244) (xy 120.733665 -407.031752)
			(xy 122.171175 -407.031752) (xy 122.171175 -406.977248) (xy 122.178932 -406.9233) (xy 122.194288 -406.871004)
			(xy 122.216929 -406.821426) (xy 122.246396 -406.775575) (xy 122.282089 -406.734384) (xy 122.32328 -406.698693)
			(xy 122.369131 -406.669226) (xy 122.41871 -406.646585) (xy 122.471006 -406.631231) (xy 122.524954 -406.623475)
			(xy 122.552206 -406.623012) (xy 123.415806 -406.623012) (xy 123.443058 -406.623458) (xy 123.497008 -406.631216)
			(xy 123.549305 -406.646572) (xy 123.598884 -406.669215) (xy 123.644736 -406.698683) (xy 123.685928 -406.734376)
			(xy 123.721621 -406.775569) (xy 123.751088 -406.821421) (xy 123.77373 -406.871001) (xy 123.789085 -406.923298)
			(xy 123.796842 -406.977248) (xy 123.796842 -407.031752) (xy 123.796842 -407.031754) (xy 125.234375 -407.031754)
			(xy 125.234375 -406.977246) (xy 125.242133 -406.923294) (xy 125.257491 -406.870996) (xy 125.280135 -406.821415)
			(xy 125.309606 -406.775562) (xy 125.345303 -406.73437) (xy 125.386499 -406.698679) (xy 125.432355 -406.669213)
			(xy 125.481939 -406.646575) (xy 125.534239 -406.631223) (xy 125.588192 -406.623472) (xy 125.615446 -406.623012)
			(xy 126.479046 -406.623012) (xy 126.506297 -406.623461) (xy 126.560242 -406.631223) (xy 126.612534 -406.646583)
			(xy 126.662108 -406.669228) (xy 126.707955 -406.698697) (xy 126.749142 -406.734391) (xy 126.78483 -406.775582)
			(xy 126.814294 -406.821432) (xy 126.836933 -406.871009) (xy 126.852287 -406.923303) (xy 126.860042 -406.977249)
			(xy 126.860042 -407.031749) (xy 128.297698 -407.031749) (xy 128.297698 -406.977251) (xy 128.305454 -406.923307)
			(xy 128.320808 -406.871016) (xy 128.343446 -406.821443) (xy 128.37291 -406.775596) (xy 128.408598 -406.734408)
			(xy 128.449784 -406.698718) (xy 128.49563 -406.669253) (xy 128.545203 -406.646612) (xy 128.597494 -406.631257)
			(xy 128.651437 -406.623499) (xy 128.678686 -406.623012) (xy 129.542286 -406.623012) (xy 129.569541 -406.623434)
			(xy 129.623496 -406.63119) (xy 129.675799 -406.646545) (xy 129.725383 -406.669188) (xy 129.771241 -406.698657)
			(xy 129.812437 -406.734353) (xy 129.848134 -406.775548) (xy 129.877605 -406.821405) (xy 129.90025 -406.870988)
			(xy 129.915607 -406.92329) (xy 129.923365 -406.977245) (xy 129.923365 -407.031753) (xy 131.360875 -407.031753)
			(xy 131.360875 -406.977247) (xy 131.368633 -406.923297) (xy 131.383989 -406.871) (xy 131.406632 -406.821421)
			(xy 131.436101 -406.775569) (xy 131.471796 -406.734377) (xy 131.512989 -406.698686) (xy 131.558843 -406.66922)
			(xy 131.608424 -406.64658) (xy 131.660722 -406.631227) (xy 131.714673 -406.623474) (xy 131.741926 -406.623012)
			(xy 132.605526 -406.623012) (xy 132.632777 -406.62346) (xy 132.686725 -406.63122) (xy 132.73902 -406.646578)
			(xy 132.788596 -406.669222) (xy 132.834446 -406.69869) (xy 132.875635 -406.734383) (xy 132.911326 -406.775575)
			(xy 132.940791 -406.821427) (xy 132.963431 -406.871005) (xy 132.978786 -406.9233) (xy 132.986542 -406.977249)
			(xy 132.986542 -407.031748) (xy 134.424198 -407.031748) (xy 134.424198 -406.977252) (xy 134.431953 -406.92331)
			(xy 134.447306 -406.871021) (xy 134.469943 -406.821448) (xy 134.499405 -406.775602) (xy 134.535091 -406.734415)
			(xy 134.576275 -406.698725) (xy 134.622118 -406.66926) (xy 134.671689 -406.646618) (xy 134.723977 -406.631261)
			(xy 134.777918 -406.623501) (xy 134.805166 -406.623012) (xy 135.668766 -406.623012) (xy 135.696022 -406.623433)
			(xy 135.749979 -406.631186) (xy 135.802284 -406.64654) (xy 135.851871 -406.669182) (xy 135.897731 -406.69865)
			(xy 135.93893 -406.734346) (xy 135.974629 -406.775542) (xy 136.004102 -406.821399) (xy 136.026748 -406.870984)
			(xy 136.042107 -406.923287) (xy 136.049865 -406.977244) (xy 136.049865 -407.031752) (xy 137.487375 -407.031752)
			(xy 137.487375 -406.977248) (xy 137.495132 -406.9233) (xy 137.510488 -406.871004) (xy 137.533129 -406.821426)
			(xy 137.562596 -406.775575) (xy 137.598289 -406.734384) (xy 137.63948 -406.698693) (xy 137.685331 -406.669226)
			(xy 137.73491 -406.646585) (xy 137.787206 -406.631231) (xy 137.841154 -406.623475) (xy 137.868406 -406.623012)
			(xy 138.732006 -406.623012) (xy 138.759258 -406.623458) (xy 138.813208 -406.631216) (xy 138.865505 -406.646572)
			(xy 138.915084 -406.669215) (xy 138.960936 -406.698683) (xy 139.002128 -406.734376) (xy 139.037821 -406.775569)
			(xy 139.067288 -406.821421) (xy 139.08993 -406.871001) (xy 139.105285 -406.923298) (xy 139.113042 -406.977248)
			(xy 139.113042 -407.031752) (xy 139.113042 -407.031754) (xy 140.550575 -407.031754) (xy 140.550575 -406.977246)
			(xy 140.558333 -406.923294) (xy 140.573691 -406.870996) (xy 140.596335 -406.821415) (xy 140.625806 -406.775562)
			(xy 140.661503 -406.73437) (xy 140.702699 -406.698679) (xy 140.748555 -406.669213) (xy 140.798139 -406.646575)
			(xy 140.850439 -406.631223) (xy 140.904392 -406.623472) (xy 140.931646 -406.623012) (xy 141.795246 -406.623012)
			(xy 141.822497 -406.623461) (xy 141.876442 -406.631223) (xy 141.928734 -406.646583) (xy 141.978308 -406.669228)
			(xy 142.024155 -406.698697) (xy 142.065342 -406.734391) (xy 142.10103 -406.775582) (xy 142.130494 -406.821432)
			(xy 142.153133 -406.871009) (xy 142.168487 -406.923303) (xy 142.176242 -406.977249) (xy 142.176242 -407.031749)
			(xy 143.613898 -407.031749) (xy 143.613898 -406.977251) (xy 143.621654 -406.923307) (xy 143.637008 -406.871016)
			(xy 143.659646 -406.821443) (xy 143.68911 -406.775596) (xy 143.724798 -406.734408) (xy 143.765984 -406.698718)
			(xy 143.81183 -406.669253) (xy 143.861403 -406.646612) (xy 143.913694 -406.631257) (xy 143.967637 -406.623499)
			(xy 143.994886 -406.623012) (xy 144.858486 -406.623012) (xy 144.885741 -406.623434) (xy 144.939696 -406.63119)
			(xy 144.991999 -406.646545) (xy 145.041583 -406.669188) (xy 145.087441 -406.698657) (xy 145.128637 -406.734353)
			(xy 145.164334 -406.775548) (xy 145.193805 -406.821405) (xy 145.21645 -406.870988) (xy 145.231807 -406.92329)
			(xy 145.239565 -406.977245) (xy 145.239565 -407.031753) (xy 146.677075 -407.031753) (xy 146.677075 -406.977247)
			(xy 146.684833 -406.923297) (xy 146.700189 -406.871) (xy 146.722832 -406.821421) (xy 146.752301 -406.775569)
			(xy 146.787996 -406.734377) (xy 146.829189 -406.698686) (xy 146.875043 -406.66922) (xy 146.924624 -406.64658)
			(xy 146.976922 -406.631227) (xy 147.030873 -406.623474) (xy 147.058126 -406.623012) (xy 147.921726 -406.623012)
			(xy 147.948977 -406.62346) (xy 148.002925 -406.63122) (xy 148.05522 -406.646578) (xy 148.104796 -406.669222)
			(xy 148.150646 -406.69869) (xy 148.191835 -406.734383) (xy 148.227526 -406.775575) (xy 148.256991 -406.821427)
			(xy 148.279631 -406.871005) (xy 148.294986 -406.9233) (xy 148.302742 -406.977249) (xy 148.302742 -407.031748)
			(xy 149.740398 -407.031748) (xy 149.740398 -406.977252) (xy 149.748153 -406.92331) (xy 149.763506 -406.871021)
			(xy 149.786143 -406.821448) (xy 149.815605 -406.775602) (xy 149.851291 -406.734415) (xy 149.892475 -406.698725)
			(xy 149.938318 -406.66926) (xy 149.987889 -406.646618) (xy 150.040177 -406.631261) (xy 150.094118 -406.623501)
			(xy 150.121366 -406.623012) (xy 150.984966 -406.623012) (xy 151.012222 -406.623433) (xy 151.066179 -406.631186)
			(xy 151.118484 -406.64654) (xy 151.168071 -406.669182) (xy 151.213931 -406.69865) (xy 151.25513 -406.734346)
			(xy 151.290829 -406.775542) (xy 151.320302 -406.821399) (xy 151.342948 -406.870984) (xy 151.358307 -406.923287)
			(xy 151.366065 -406.977244) (xy 151.366065 -407.031752) (xy 152.803575 -407.031752) (xy 152.803575 -406.977248)
			(xy 152.811332 -406.9233) (xy 152.826688 -406.871004) (xy 152.849329 -406.821426) (xy 152.878796 -406.775575)
			(xy 152.914489 -406.734384) (xy 152.95568 -406.698693) (xy 153.001531 -406.669226) (xy 153.05111 -406.646585)
			(xy 153.103406 -406.631231) (xy 153.157354 -406.623475) (xy 153.184606 -406.623012) (xy 154.048206 -406.623012)
			(xy 154.075458 -406.623458) (xy 154.129408 -406.631216) (xy 154.181705 -406.646572) (xy 154.231284 -406.669215)
			(xy 154.277136 -406.698683) (xy 154.318328 -406.734376) (xy 154.354021 -406.775569) (xy 154.383488 -406.821421)
			(xy 154.40613 -406.871001) (xy 154.421485 -406.923298) (xy 154.429242 -406.977248) (xy 154.429242 -407.031752)
			(xy 154.429242 -407.031754) (xy 155.866775 -407.031754) (xy 155.866775 -406.977246) (xy 155.874533 -406.923294)
			(xy 155.889891 -406.870996) (xy 155.912535 -406.821415) (xy 155.942006 -406.775562) (xy 155.977703 -406.73437)
			(xy 156.018899 -406.698679) (xy 156.064755 -406.669213) (xy 156.114339 -406.646575) (xy 156.166639 -406.631223)
			(xy 156.220592 -406.623472) (xy 156.247846 -406.623012) (xy 157.111446 -406.623012) (xy 157.138697 -406.623461)
			(xy 157.192642 -406.631223) (xy 157.244934 -406.646583) (xy 157.294508 -406.669228) (xy 157.340355 -406.698697)
			(xy 157.381542 -406.734391) (xy 157.41723 -406.775582) (xy 157.446694 -406.821432) (xy 157.469333 -406.871009)
			(xy 157.484687 -406.923303) (xy 157.492442 -406.977249) (xy 157.492442 -407.031749) (xy 158.930098 -407.031749)
			(xy 158.930098 -406.977251) (xy 158.937854 -406.923307) (xy 158.953208 -406.871016) (xy 158.975846 -406.821443)
			(xy 159.00531 -406.775596) (xy 159.040998 -406.734408) (xy 159.082184 -406.698718) (xy 159.12803 -406.669253)
			(xy 159.177603 -406.646612) (xy 159.229894 -406.631257) (xy 159.283837 -406.623499) (xy 159.311086 -406.623012)
			(xy 160.174686 -406.623012) (xy 160.201941 -406.623434) (xy 160.255896 -406.63119) (xy 160.308199 -406.646545)
			(xy 160.357783 -406.669188) (xy 160.403641 -406.698657) (xy 160.444837 -406.734353) (xy 160.480534 -406.775548)
			(xy 160.510005 -406.821405) (xy 160.53265 -406.870988) (xy 160.548007 -406.92329) (xy 160.555765 -406.977245)
			(xy 160.555765 -407.031753) (xy 161.993275 -407.031753) (xy 161.993275 -406.977247) (xy 162.001033 -406.923297)
			(xy 162.016389 -406.871) (xy 162.039032 -406.821421) (xy 162.068501 -406.775569) (xy 162.104196 -406.734377)
			(xy 162.145389 -406.698686) (xy 162.191243 -406.66922) (xy 162.240824 -406.64658) (xy 162.293122 -406.631227)
			(xy 162.347073 -406.623474) (xy 162.374326 -406.623012) (xy 163.237926 -406.623012) (xy 163.265177 -406.62346)
			(xy 163.319125 -406.63122) (xy 163.37142 -406.646578) (xy 163.420996 -406.669222) (xy 163.466846 -406.69869)
			(xy 163.508035 -406.734383) (xy 163.543726 -406.775575) (xy 163.573191 -406.821427) (xy 163.595831 -406.871005)
			(xy 163.611186 -406.9233) (xy 163.618942 -406.977249) (xy 163.618942 -407.031751) (xy 163.611186 -407.0857)
			(xy 163.595831 -407.137995) (xy 163.573191 -407.187573) (xy 163.543726 -407.233425) (xy 163.508035 -407.274617)
			(xy 163.466846 -407.31031) (xy 163.420996 -407.339778) (xy 163.37142 -407.362422) (xy 163.319125 -407.37778)
			(xy 163.265177 -407.38554) (xy 163.237926 -407.386028) (xy 162.374326 -407.386028) (xy 162.347073 -407.385526)
			(xy 162.293122 -407.377773) (xy 162.240824 -407.36242) (xy 162.191243 -407.33978) (xy 162.145389 -407.310314)
			(xy 162.104196 -407.274623) (xy 162.068501 -407.233431) (xy 162.039032 -407.187579) (xy 162.016389 -407.138)
			(xy 162.001033 -407.085703) (xy 161.993275 -407.031753) (xy 160.555765 -407.031753) (xy 160.555765 -407.031755)
			(xy 160.548007 -407.08571) (xy 160.53265 -407.138012) (xy 160.510005 -407.187595) (xy 160.480534 -407.233452)
			(xy 160.444837 -407.274647) (xy 160.403641 -407.310343) (xy 160.357783 -407.339812) (xy 160.308199 -407.362455)
			(xy 160.255896 -407.37781) (xy 160.201941 -407.385566) (xy 160.174686 -407.386028) (xy 159.311086 -407.386028)
			(xy 159.283837 -407.385501) (xy 159.229894 -407.377743) (xy 159.177603 -407.362388) (xy 159.12803 -407.339747)
			(xy 159.082184 -407.310282) (xy 159.040998 -407.274592) (xy 159.00531 -407.233404) (xy 158.975846 -407.187557)
			(xy 158.953208 -407.137984) (xy 158.937854 -407.085693) (xy 158.930098 -407.031749) (xy 157.492442 -407.031749)
			(xy 157.492442 -407.031751) (xy 157.484687 -407.085697) (xy 157.469333 -407.137991) (xy 157.446694 -407.187568)
			(xy 157.41723 -407.233418) (xy 157.381542 -407.274609) (xy 157.340355 -407.310303) (xy 157.294508 -407.339772)
			(xy 157.244934 -407.362417) (xy 157.192642 -407.377777) (xy 157.138697 -407.385539) (xy 157.111446 -407.386028)
			(xy 156.247846 -407.386028) (xy 156.220592 -407.385528) (xy 156.166639 -407.377777) (xy 156.114339 -407.362425)
			(xy 156.064755 -407.339787) (xy 156.018899 -407.310321) (xy 155.977703 -407.27463) (xy 155.942006 -407.233438)
			(xy 155.912535 -407.187585) (xy 155.889891 -407.138004) (xy 155.874533 -407.085706) (xy 155.866775 -407.031754)
			(xy 154.429242 -407.031754) (xy 154.421485 -407.085702) (xy 154.40613 -407.137999) (xy 154.383488 -407.187579)
			(xy 154.354021 -407.233431) (xy 154.318328 -407.274624) (xy 154.277136 -407.310317) (xy 154.231284 -407.339785)
			(xy 154.181705 -407.362428) (xy 154.129408 -407.377784) (xy 154.075458 -407.385542) (xy 154.048206 -407.386028)
			(xy 153.184606 -407.386028) (xy 153.157354 -407.385525) (xy 153.103406 -407.377769) (xy 153.05111 -407.362415)
			(xy 153.001531 -407.339774) (xy 152.95568 -407.310307) (xy 152.914489 -407.274616) (xy 152.878796 -407.233425)
			(xy 152.849329 -407.187574) (xy 152.826688 -407.137996) (xy 152.811332 -407.0857) (xy 152.803575 -407.031752)
			(xy 151.366065 -407.031752) (xy 151.366065 -407.031756) (xy 151.358307 -407.085713) (xy 151.342948 -407.138016)
			(xy 151.320302 -407.187601) (xy 151.290829 -407.233458) (xy 151.25513 -407.274654) (xy 151.213931 -407.31035)
			(xy 151.168071 -407.339818) (xy 151.118484 -407.36246) (xy 151.066179 -407.377814) (xy 151.012222 -407.385567)
			(xy 150.984966 -407.386028) (xy 150.121366 -407.386028) (xy 150.094118 -407.385499) (xy 150.040177 -407.377739)
			(xy 149.987889 -407.362382) (xy 149.938318 -407.33974) (xy 149.892475 -407.310275) (xy 149.851291 -407.274585)
			(xy 149.815605 -407.233398) (xy 149.786143 -407.187552) (xy 149.763506 -407.137979) (xy 149.748153 -407.08569)
			(xy 149.740398 -407.031748) (xy 148.302742 -407.031748) (xy 148.302742 -407.031751) (xy 148.294986 -407.0857)
			(xy 148.279631 -407.137995) (xy 148.256991 -407.187573) (xy 148.227526 -407.233425) (xy 148.191835 -407.274617)
			(xy 148.150646 -407.31031) (xy 148.104796 -407.339778) (xy 148.05522 -407.362422) (xy 148.002925 -407.37778)
			(xy 147.948977 -407.38554) (xy 147.921726 -407.386028) (xy 147.058126 -407.386028) (xy 147.030873 -407.385526)
			(xy 146.976922 -407.377773) (xy 146.924624 -407.36242) (xy 146.875043 -407.33978) (xy 146.829189 -407.310314)
			(xy 146.787996 -407.274623) (xy 146.752301 -407.233431) (xy 146.722832 -407.187579) (xy 146.700189 -407.138)
			(xy 146.684833 -407.085703) (xy 146.677075 -407.031753) (xy 145.239565 -407.031753) (xy 145.239565 -407.031755)
			(xy 145.231807 -407.08571) (xy 145.21645 -407.138012) (xy 145.193805 -407.187595) (xy 145.164334 -407.233452)
			(xy 145.128637 -407.274647) (xy 145.087441 -407.310343) (xy 145.041583 -407.339812) (xy 144.991999 -407.362455)
			(xy 144.939696 -407.37781) (xy 144.885741 -407.385566) (xy 144.858486 -407.386028) (xy 143.994886 -407.386028)
			(xy 143.967637 -407.385501) (xy 143.913694 -407.377743) (xy 143.861403 -407.362388) (xy 143.81183 -407.339747)
			(xy 143.765984 -407.310282) (xy 143.724798 -407.274592) (xy 143.68911 -407.233404) (xy 143.659646 -407.187557)
			(xy 143.637008 -407.137984) (xy 143.621654 -407.085693) (xy 143.613898 -407.031749) (xy 142.176242 -407.031749)
			(xy 142.176242 -407.031751) (xy 142.168487 -407.085697) (xy 142.153133 -407.137991) (xy 142.130494 -407.187568)
			(xy 142.10103 -407.233418) (xy 142.065342 -407.274609) (xy 142.024155 -407.310303) (xy 141.978308 -407.339772)
			(xy 141.928734 -407.362417) (xy 141.876442 -407.377777) (xy 141.822497 -407.385539) (xy 141.795246 -407.386028)
			(xy 140.931646 -407.386028) (xy 140.904392 -407.385528) (xy 140.850439 -407.377777) (xy 140.798139 -407.362425)
			(xy 140.748555 -407.339787) (xy 140.702699 -407.310321) (xy 140.661503 -407.27463) (xy 140.625806 -407.233438)
			(xy 140.596335 -407.187585) (xy 140.573691 -407.138004) (xy 140.558333 -407.085706) (xy 140.550575 -407.031754)
			(xy 139.113042 -407.031754) (xy 139.105285 -407.085702) (xy 139.08993 -407.137999) (xy 139.067288 -407.187579)
			(xy 139.037821 -407.233431) (xy 139.002128 -407.274624) (xy 138.960936 -407.310317) (xy 138.915084 -407.339785)
			(xy 138.865505 -407.362428) (xy 138.813208 -407.377784) (xy 138.759258 -407.385542) (xy 138.732006 -407.386028)
			(xy 137.868406 -407.386028) (xy 137.841154 -407.385525) (xy 137.787206 -407.377769) (xy 137.73491 -407.362415)
			(xy 137.685331 -407.339774) (xy 137.63948 -407.310307) (xy 137.598289 -407.274616) (xy 137.562596 -407.233425)
			(xy 137.533129 -407.187574) (xy 137.510488 -407.137996) (xy 137.495132 -407.0857) (xy 137.487375 -407.031752)
			(xy 136.049865 -407.031752) (xy 136.049865 -407.031756) (xy 136.042107 -407.085713) (xy 136.026748 -407.138016)
			(xy 136.004102 -407.187601) (xy 135.974629 -407.233458) (xy 135.93893 -407.274654) (xy 135.897731 -407.31035)
			(xy 135.851871 -407.339818) (xy 135.802284 -407.36246) (xy 135.749979 -407.377814) (xy 135.696022 -407.385567)
			(xy 135.668766 -407.386028) (xy 134.805166 -407.386028) (xy 134.777918 -407.385499) (xy 134.723977 -407.377739)
			(xy 134.671689 -407.362382) (xy 134.622118 -407.33974) (xy 134.576275 -407.310275) (xy 134.535091 -407.274585)
			(xy 134.499405 -407.233398) (xy 134.469943 -407.187552) (xy 134.447306 -407.137979) (xy 134.431953 -407.08569)
			(xy 134.424198 -407.031748) (xy 132.986542 -407.031748) (xy 132.986542 -407.031751) (xy 132.978786 -407.0857)
			(xy 132.963431 -407.137995) (xy 132.940791 -407.187573) (xy 132.911326 -407.233425) (xy 132.875635 -407.274617)
			(xy 132.834446 -407.31031) (xy 132.788596 -407.339778) (xy 132.73902 -407.362422) (xy 132.686725 -407.37778)
			(xy 132.632777 -407.38554) (xy 132.605526 -407.386028) (xy 131.741926 -407.386028) (xy 131.714673 -407.385526)
			(xy 131.660722 -407.377773) (xy 131.608424 -407.36242) (xy 131.558843 -407.33978) (xy 131.512989 -407.310314)
			(xy 131.471796 -407.274623) (xy 131.436101 -407.233431) (xy 131.406632 -407.187579) (xy 131.383989 -407.138)
			(xy 131.368633 -407.085703) (xy 131.360875 -407.031753) (xy 129.923365 -407.031753) (xy 129.923365 -407.031755)
			(xy 129.915607 -407.08571) (xy 129.90025 -407.138012) (xy 129.877605 -407.187595) (xy 129.848134 -407.233452)
			(xy 129.812437 -407.274647) (xy 129.771241 -407.310343) (xy 129.725383 -407.339812) (xy 129.675799 -407.362455)
			(xy 129.623496 -407.37781) (xy 129.569541 -407.385566) (xy 129.542286 -407.386028) (xy 128.678686 -407.386028)
			(xy 128.651437 -407.385501) (xy 128.597494 -407.377743) (xy 128.545203 -407.362388) (xy 128.49563 -407.339747)
			(xy 128.449784 -407.310282) (xy 128.408598 -407.274592) (xy 128.37291 -407.233404) (xy 128.343446 -407.187557)
			(xy 128.320808 -407.137984) (xy 128.305454 -407.085693) (xy 128.297698 -407.031749) (xy 126.860042 -407.031749)
			(xy 126.860042 -407.031751) (xy 126.852287 -407.085697) (xy 126.836933 -407.137991) (xy 126.814294 -407.187568)
			(xy 126.78483 -407.233418) (xy 126.749142 -407.274609) (xy 126.707955 -407.310303) (xy 126.662108 -407.339772)
			(xy 126.612534 -407.362417) (xy 126.560242 -407.377777) (xy 126.506297 -407.385539) (xy 126.479046 -407.386028)
			(xy 125.615446 -407.386028) (xy 125.588192 -407.385528) (xy 125.534239 -407.377777) (xy 125.481939 -407.362425)
			(xy 125.432355 -407.339787) (xy 125.386499 -407.310321) (xy 125.345303 -407.27463) (xy 125.309606 -407.233438)
			(xy 125.280135 -407.187585) (xy 125.257491 -407.138004) (xy 125.242133 -407.085706) (xy 125.234375 -407.031754)
			(xy 123.796842 -407.031754) (xy 123.789085 -407.085702) (xy 123.77373 -407.137999) (xy 123.751088 -407.187579)
			(xy 123.721621 -407.233431) (xy 123.685928 -407.274624) (xy 123.644736 -407.310317) (xy 123.598884 -407.339785)
			(xy 123.549305 -407.362428) (xy 123.497008 -407.377784) (xy 123.443058 -407.385542) (xy 123.415806 -407.386028)
			(xy 122.552206 -407.386028) (xy 122.524954 -407.385525) (xy 122.471006 -407.377769) (xy 122.41871 -407.362415)
			(xy 122.369131 -407.339774) (xy 122.32328 -407.310307) (xy 122.282089 -407.274616) (xy 122.246396 -407.233425)
			(xy 122.216929 -407.187574) (xy 122.194288 -407.137996) (xy 122.178932 -407.0857) (xy 122.171175 -407.031752)
			(xy 120.733665 -407.031752) (xy 120.733665 -407.031756) (xy 120.725907 -407.085713) (xy 120.710548 -407.138016)
			(xy 120.687902 -407.187601) (xy 120.658429 -407.233458) (xy 120.62273 -407.274654) (xy 120.581531 -407.31035)
			(xy 120.535671 -407.339818) (xy 120.486084 -407.36246) (xy 120.433779 -407.377814) (xy 120.379822 -407.385567)
			(xy 120.352566 -407.386028) (xy 119.488966 -407.386028) (xy 119.461718 -407.385499) (xy 119.407777 -407.377739)
			(xy 119.355489 -407.362382) (xy 119.305918 -407.33974) (xy 119.260075 -407.310275) (xy 119.218891 -407.274585)
			(xy 119.183205 -407.233398) (xy 119.153743 -407.187552) (xy 119.131106 -407.137979) (xy 119.115753 -407.08569)
			(xy 119.107998 -407.031748) (xy 117.670342 -407.031748) (xy 117.670342 -407.031751) (xy 117.662586 -407.0857)
			(xy 117.647231 -407.137995) (xy 117.624591 -407.187573) (xy 117.595126 -407.233425) (xy 117.559435 -407.274617)
			(xy 117.518246 -407.31031) (xy 117.472396 -407.339778) (xy 117.42282 -407.362422) (xy 117.370525 -407.37778)
			(xy 117.316577 -407.38554) (xy 117.289326 -407.386028) (xy 116.425726 -407.386028) (xy 116.398473 -407.385526)
			(xy 116.344522 -407.377773) (xy 116.292224 -407.36242) (xy 116.242643 -407.33978) (xy 116.196789 -407.310314)
			(xy 116.155596 -407.274623) (xy 116.119901 -407.233431) (xy 116.090432 -407.187579) (xy 116.067789 -407.138)
			(xy 116.052433 -407.085703) (xy 116.044675 -407.031753) (xy 96.519065 -407.031753) (xy 96.519065 -407.031755)
			(xy 96.511307 -407.08571) (xy 96.49595 -407.138012) (xy 96.473305 -407.187596) (xy 96.443834 -407.233452)
			(xy 96.408136 -407.274648) (xy 96.36694 -407.310343) (xy 96.321082 -407.339812) (xy 96.271497 -407.362455)
			(xy 96.219195 -407.377811) (xy 96.165239 -407.385566) (xy 96.137984 -407.386028) (xy 95.274384 -407.386028)
			(xy 95.247135 -407.385501) (xy 95.193192 -407.377743) (xy 95.140902 -407.362387) (xy 95.091329 -407.339746)
			(xy 95.045483 -407.310281) (xy 95.004297 -407.274591) (xy 94.968609 -407.233404) (xy 94.939146 -407.187557)
			(xy 94.916507 -407.137983) (xy 94.901154 -407.085692) (xy 94.893398 -407.031749) (xy 93.455742 -407.031749)
			(xy 93.455742 -407.031751) (xy 93.447987 -407.085697) (xy 93.432633 -407.137991) (xy 93.409994 -407.187568)
			(xy 93.38053 -407.233419) (xy 93.344841 -407.27461) (xy 93.303654 -407.310304) (xy 93.257807 -407.339773)
			(xy 93.208233 -407.362417) (xy 93.15594 -407.377777) (xy 93.101995 -407.385539) (xy 93.074744 -407.386028)
			(xy 92.211144 -407.386028) (xy 92.183891 -407.385528) (xy 92.129938 -407.377776) (xy 92.077637 -407.362425)
			(xy 92.028054 -407.339786) (xy 91.982198 -407.310321) (xy 91.941002 -407.274629) (xy 91.905306 -407.233437)
			(xy 91.875835 -407.187584) (xy 91.853191 -407.138004) (xy 91.837833 -407.085705) (xy 91.830075 -407.031753)
			(xy 90.392542 -407.031753) (xy 90.384785 -407.085703) (xy 90.36943 -407.138) (xy 90.346788 -407.187579)
			(xy 90.31732 -407.233432) (xy 90.281627 -407.274624) (xy 90.240435 -407.310318) (xy 90.194583 -407.339786)
			(xy 90.145004 -407.362428) (xy 90.092707 -407.377785) (xy 90.038756 -407.385542) (xy 90.011504 -407.386028)
			(xy 89.147904 -407.386028) (xy 89.120652 -407.385525) (xy 89.066704 -407.377769) (xy 89.014408 -407.362414)
			(xy 88.96483 -407.339773) (xy 88.918979 -407.310307) (xy 88.877788 -407.274615) (xy 88.842096 -407.233424)
			(xy 88.812629 -407.187573) (xy 88.789987 -407.137995) (xy 88.774632 -407.0857) (xy 88.766875 -407.031752)
			(xy 87.329365 -407.031752) (xy 87.329365 -407.031756) (xy 87.321607 -407.085713) (xy 87.306248 -407.138016)
			(xy 87.283602 -407.187602) (xy 87.254129 -407.233459) (xy 87.218429 -407.274655) (xy 87.17723 -407.31035)
			(xy 87.13137 -407.339819) (xy 87.081783 -407.362461) (xy 87.029478 -407.377814) (xy 86.97552 -407.385568)
			(xy 86.948264 -407.386028) (xy 86.084664 -407.386028) (xy 86.057416 -407.385499) (xy 86.003475 -407.377739)
			(xy 85.951187 -407.362382) (xy 85.901617 -407.33974) (xy 85.855774 -407.310274) (xy 85.81459 -407.274584)
			(xy 85.778904 -407.233397) (xy 85.749443 -407.187551) (xy 85.726806 -407.137979) (xy 85.711453 -407.08569)
			(xy 85.703698 -407.031748) (xy 84.266042 -407.031748) (xy 84.266042 -407.031752) (xy 84.258286 -407.0857)
			(xy 84.242931 -407.137996) (xy 84.220291 -407.187574) (xy 84.190825 -407.233425) (xy 84.155134 -407.274617)
			(xy 84.113945 -407.310311) (xy 84.068095 -407.339779) (xy 84.018518 -407.362423) (xy 83.966224 -407.377781)
			(xy 83.912276 -407.385541) (xy 83.885024 -407.386028) (xy 83.021424 -407.386028) (xy 82.994171 -407.385526)
			(xy 82.940221 -407.377773) (xy 82.887923 -407.362419) (xy 82.838342 -407.339779) (xy 82.792488 -407.310314)
			(xy 82.751295 -407.274622) (xy 82.715601 -407.233431) (xy 82.686132 -407.187579) (xy 82.663489 -407.138)
			(xy 82.648133 -407.085703) (xy 82.640375 -407.031753) (xy 81.202865 -407.031753) (xy 81.202865 -407.031755)
			(xy 81.195107 -407.08571) (xy 81.17975 -407.138012) (xy 81.157105 -407.187596) (xy 81.127634 -407.233452)
			(xy 81.091936 -407.274648) (xy 81.05074 -407.310343) (xy 81.004882 -407.339812) (xy 80.955297 -407.362455)
			(xy 80.902995 -407.377811) (xy 80.849039 -407.385566) (xy 80.821784 -407.386028) (xy 79.958184 -407.386028)
			(xy 79.930935 -407.385501) (xy 79.876992 -407.377743) (xy 79.824702 -407.362387) (xy 79.775129 -407.339746)
			(xy 79.729283 -407.310281) (xy 79.688097 -407.274591) (xy 79.652409 -407.233404) (xy 79.622946 -407.187557)
			(xy 79.600307 -407.137983) (xy 79.584954 -407.085692) (xy 79.577198 -407.031749) (xy 78.139542 -407.031749)
			(xy 78.139542 -407.031751) (xy 78.131787 -407.085697) (xy 78.116433 -407.137991) (xy 78.093794 -407.187568)
			(xy 78.06433 -407.233419) (xy 78.028641 -407.27461) (xy 77.987454 -407.310304) (xy 77.941607 -407.339773)
			(xy 77.892033 -407.362417) (xy 77.83974 -407.377777) (xy 77.785795 -407.385539) (xy 77.758544 -407.386028)
			(xy 76.894944 -407.386028) (xy 76.867691 -407.385528) (xy 76.813738 -407.377776) (xy 76.761437 -407.362425)
			(xy 76.711854 -407.339786) (xy 76.665998 -407.310321) (xy 76.624802 -407.274629) (xy 76.589106 -407.233437)
			(xy 76.559635 -407.187584) (xy 76.536991 -407.138004) (xy 76.521633 -407.085705) (xy 76.513875 -407.031753)
			(xy 75.076342 -407.031753) (xy 75.068585 -407.085703) (xy 75.05323 -407.138) (xy 75.030588 -407.187579)
			(xy 75.00112 -407.233432) (xy 74.965427 -407.274624) (xy 74.924235 -407.310318) (xy 74.878383 -407.339786)
			(xy 74.828804 -407.362428) (xy 74.776507 -407.377785) (xy 74.722556 -407.385542) (xy 74.695304 -407.386028)
			(xy 73.831704 -407.386028) (xy 73.804452 -407.385525) (xy 73.750504 -407.377769) (xy 73.698208 -407.362414)
			(xy 73.64863 -407.339773) (xy 73.602779 -407.310307) (xy 73.561588 -407.274615) (xy 73.525896 -407.233424)
			(xy 73.496429 -407.187573) (xy 73.473787 -407.137995) (xy 73.458432 -407.0857) (xy 73.450675 -407.031752)
			(xy 72.013165 -407.031752) (xy 72.013165 -407.031756) (xy 72.005407 -407.085713) (xy 71.990048 -407.138016)
			(xy 71.967402 -407.187602) (xy 71.937929 -407.233459) (xy 71.902229 -407.274655) (xy 71.86103 -407.31035)
			(xy 71.81517 -407.339819) (xy 71.765583 -407.362461) (xy 71.713278 -407.377814) (xy 71.65932 -407.385568)
			(xy 71.632064 -407.386028) (xy 70.768464 -407.386028) (xy 70.741216 -407.385499) (xy 70.687275 -407.377739)
			(xy 70.634987 -407.362382) (xy 70.585417 -407.33974) (xy 70.539574 -407.310274) (xy 70.49839 -407.274584)
			(xy 70.462704 -407.233397) (xy 70.433243 -407.187551) (xy 70.410606 -407.137979) (xy 70.395253 -407.08569)
			(xy 70.387498 -407.031748) (xy 68.949842 -407.031748) (xy 68.949842 -407.031752) (xy 68.942086 -407.0857)
			(xy 68.926731 -407.137996) (xy 68.904091 -407.187574) (xy 68.874625 -407.233425) (xy 68.838934 -407.274617)
			(xy 68.797745 -407.310311) (xy 68.751895 -407.339779) (xy 68.702318 -407.362423) (xy 68.650024 -407.377781)
			(xy 68.596076 -407.385541) (xy 68.568824 -407.386028) (xy 67.705224 -407.386028) (xy 67.677971 -407.385526)
			(xy 67.624021 -407.377773) (xy 67.571723 -407.362419) (xy 67.522142 -407.339779) (xy 67.476288 -407.310314)
			(xy 67.435095 -407.274622) (xy 67.399401 -407.233431) (xy 67.369932 -407.187579) (xy 67.347289 -407.138)
			(xy 67.331933 -407.085703) (xy 67.324175 -407.031753) (xy 65.886665 -407.031753) (xy 65.886665 -407.031755)
			(xy 65.878907 -407.08571) (xy 65.86355 -407.138012) (xy 65.840905 -407.187596) (xy 65.811434 -407.233452)
			(xy 65.775736 -407.274648) (xy 65.73454 -407.310343) (xy 65.688682 -407.339812) (xy 65.639097 -407.362455)
			(xy 65.586795 -407.377811) (xy 65.532839 -407.385566) (xy 65.505584 -407.386028) (xy 64.641984 -407.386028)
			(xy 64.614735 -407.385501) (xy 64.560792 -407.377743) (xy 64.508502 -407.362387) (xy 64.458929 -407.339746)
			(xy 64.413083 -407.310281) (xy 64.371897 -407.274591) (xy 64.336209 -407.233404) (xy 64.306746 -407.187557)
			(xy 64.284107 -407.137983) (xy 64.268754 -407.085692) (xy 64.260998 -407.031749) (xy 62.823342 -407.031749)
			(xy 62.823342 -407.031751) (xy 62.815587 -407.085697) (xy 62.800233 -407.137991) (xy 62.777594 -407.187568)
			(xy 62.74813 -407.233419) (xy 62.712441 -407.27461) (xy 62.671254 -407.310304) (xy 62.625407 -407.339773)
			(xy 62.575833 -407.362417) (xy 62.52354 -407.377777) (xy 62.469595 -407.385539) (xy 62.442344 -407.386028)
			(xy 61.578744 -407.386028) (xy 61.551491 -407.385528) (xy 61.497538 -407.377776) (xy 61.445237 -407.362425)
			(xy 61.395654 -407.339786) (xy 61.349798 -407.310321) (xy 61.308602 -407.274629) (xy 61.272906 -407.233437)
			(xy 61.243435 -407.187584) (xy 61.220791 -407.138004) (xy 61.205433 -407.085705) (xy 61.197675 -407.031753)
			(xy 59.760142 -407.031753) (xy 59.752385 -407.085703) (xy 59.73703 -407.138) (xy 59.714388 -407.187579)
			(xy 59.68492 -407.233432) (xy 59.649227 -407.274624) (xy 59.608035 -407.310318) (xy 59.562183 -407.339786)
			(xy 59.512604 -407.362428) (xy 59.460307 -407.377785) (xy 59.406356 -407.385542) (xy 59.379104 -407.386028)
			(xy 58.515504 -407.386028) (xy 58.488252 -407.385525) (xy 58.434304 -407.377769) (xy 58.382008 -407.362414)
			(xy 58.33243 -407.339773) (xy 58.286579 -407.310307) (xy 58.245388 -407.274615) (xy 58.209696 -407.233424)
			(xy 58.180229 -407.187573) (xy 58.157587 -407.137995) (xy 58.142232 -407.0857) (xy 58.134475 -407.031752)
			(xy 56.696965 -407.031752) (xy 56.696965 -407.031756) (xy 56.689207 -407.085713) (xy 56.673848 -407.138016)
			(xy 56.651202 -407.187602) (xy 56.621729 -407.233459) (xy 56.586029 -407.274655) (xy 56.54483 -407.31035)
			(xy 56.49897 -407.339819) (xy 56.449383 -407.362461) (xy 56.397078 -407.377814) (xy 56.34312 -407.385568)
			(xy 56.315864 -407.386028) (xy 55.452264 -407.386028) (xy 55.425016 -407.385499) (xy 55.371075 -407.377739)
			(xy 55.318787 -407.362382) (xy 55.269217 -407.33974) (xy 55.223374 -407.310274) (xy 55.18219 -407.274584)
			(xy 55.146504 -407.233397) (xy 55.117043 -407.187551) (xy 55.094406 -407.137979) (xy 55.079053 -407.08569)
			(xy 55.071298 -407.031748) (xy 53.633642 -407.031748) (xy 53.633642 -407.031752) (xy 53.625886 -407.0857)
			(xy 53.610531 -407.137996) (xy 53.587891 -407.187574) (xy 53.558425 -407.233425) (xy 53.522734 -407.274617)
			(xy 53.481545 -407.310311) (xy 53.435695 -407.339779) (xy 53.386118 -407.362423) (xy 53.333824 -407.377781)
			(xy 53.279876 -407.385541) (xy 53.252624 -407.386028) (xy 52.389024 -407.386028) (xy 52.361771 -407.385526)
			(xy 52.307821 -407.377773) (xy 52.255523 -407.362419) (xy 52.205942 -407.339779) (xy 52.160088 -407.310314)
			(xy 52.118895 -407.274622) (xy 52.083201 -407.233431) (xy 52.053732 -407.187579) (xy 52.031089 -407.138)
			(xy 52.015733 -407.085703) (xy 52.007975 -407.031753) (xy 50.570465 -407.031753) (xy 50.570465 -407.031755)
			(xy 50.562707 -407.08571) (xy 50.54735 -407.138012) (xy 50.524705 -407.187596) (xy 50.495234 -407.233452)
			(xy 50.459536 -407.274648) (xy 50.41834 -407.310343) (xy 50.372482 -407.339812) (xy 50.322897 -407.362455)
			(xy 50.270595 -407.377811) (xy 50.216639 -407.385566) (xy 50.189384 -407.386028) (xy 49.325784 -407.386028)
			(xy 49.298535 -407.385501) (xy 49.244592 -407.377743) (xy 49.192302 -407.362387) (xy 49.142729 -407.339746)
			(xy 49.096883 -407.310281) (xy 49.055697 -407.274591) (xy 49.020009 -407.233404) (xy 48.990546 -407.187557)
			(xy 48.967907 -407.137983) (xy 48.952554 -407.085692) (xy 48.944798 -407.031749) (xy 44.883756 -407.031749)
			(xy 44.868945 -407.05439) (xy 44.764794 -407.199093) (xy 44.654301 -407.339013) (xy 44.537684 -407.473872)
			(xy 44.415175 -407.603402) (xy 44.287018 -407.727346) (xy 44.153467 -407.845458) (xy 44.014787 -407.957503)
			(xy 43.871253 -408.06326) (xy 43.72315 -408.162517) (xy 43.570773 -408.255079) (xy 43.414424 -408.34076)
			(xy 43.254413 -408.419392) (xy 43.091059 -408.490818) (xy 42.924684 -408.554896) (xy 42.755621 -408.611498)
			(xy 42.584204 -408.660514) (xy 42.410773 -408.701844) (xy 42.235673 -408.735408) (xy 42.059253 -408.761138)
			(xy 41.881861 -408.778984) (xy 41.70385 -408.78891) (xy 41.525573 -408.790896) (xy 41.347386 -408.784939)
			(xy 41.16964 -408.771049) (xy 40.99269 -408.749256) (xy 40.816886 -408.719602) (xy 40.642578 -408.682145)
			(xy 40.470111 -408.636961) (xy 40.299828 -408.584139) (xy 40.132067 -408.523783) (xy 39.967162 -408.456015)
			(xy 39.805439 -408.380967) (xy 39.64722 -408.29879) (xy 39.492819 -408.209647) (xy 39.342542 -408.113713)
			(xy 39.196687 -408.011181) (xy 39.055545 -407.902253) (xy 38.919396 -407.787146) (xy 38.788509 -407.666088)
			(xy 38.663145 -407.539319) (xy 38.543552 -407.407092) (xy 38.429969 -407.269669) (xy 38.32262 -407.127322)
			(xy 38.221719 -406.980334) (xy 38.127466 -406.828998) (xy 38.040048 -406.673613) (xy 37.959638 -406.514488)
			(xy 37.886397 -406.351939) (xy 37.82047 -406.186289) (xy 37.761987 -406.017867) (xy 37.711065 -405.847006)
			(xy 37.667805 -405.674047) (xy 37.632293 -405.499332) (xy 37.604599 -405.323208) (xy 37.584778 -405.146026)
			(xy 37.57287 -404.968137) (xy 37.568898 -404.789894) (xy 3.30962 -404.789894) (xy 6.274054 -407.754328)
			(xy 6.323479 -407.804444) (xy 6.417291 -407.909404) (xy 6.50507 -408.019459) (xy 6.58654 -408.134261)
			(xy 6.661445 -408.253452) (xy 6.72955 -408.376654) (xy 6.79064 -408.503481) (xy 6.844523 -408.633534)
			(xy 6.891029 -408.766403) (xy 6.918074 -408.860244) (xy 47.576232 -408.860244) (xy 47.576232 -408.174444)
			(xy 47.576698 -408.162393) (xy 47.584122 -408.139463) (xy 47.59826 -408.119944) (xy 47.617732 -408.10574)
			(xy 47.640637 -408.098239) (xy 47.652686 -408.097736) (xy 47.847758 -408.097736) (xy 47.858863 -408.098111)
			(xy 47.880155 -408.104439) (xy 47.889668 -408.110182) (xy 48.183292 -408.302714) (xy 48.192669 -408.30843)
			(xy 48.213685 -408.314762) (xy 48.235634 -408.314832) (xy 48.25669 -408.308634) (xy 48.266096 -408.302968)
			(xy 48.56226 -408.110182) (xy 48.57177 -408.104434) (xy 48.593064 -408.098108) (xy 48.60417 -408.097736)
			(xy 48.798734 -408.097736) (xy 48.810825 -408.098178) (xy 48.833826 -408.105644) (xy 48.853405 -408.119837)
			(xy 48.867655 -408.139375) (xy 48.875186 -408.162354) (xy 48.875696 -408.174444) (xy 48.875696 -408.860244)
			(xy 50.639472 -408.860244) (xy 50.639472 -408.174444) (xy 50.639997 -408.162399) (xy 50.647414 -408.139479)
			(xy 50.661539 -408.119965) (xy 50.680994 -408.105759) (xy 50.703883 -408.098247) (xy 50.715926 -408.097736)
			(xy 50.910998 -408.097736) (xy 50.922101 -408.098136) (xy 50.943393 -408.104447) (xy 50.952908 -408.110182)
			(xy 51.246532 -408.302714) (xy 51.25589 -408.308464) (xy 51.276915 -408.314789) (xy 51.29887 -408.314849)
			(xy 51.31993 -408.30864) (xy 51.329336 -408.302968) (xy 51.6255 -408.110182) (xy 51.635003 -408.104419)
			(xy 51.656302 -408.098103) (xy 51.66741 -408.097736) (xy 51.861974 -408.097736) (xy 51.874062 -408.098229)
			(xy 51.897061 -408.105679) (xy 51.916641 -408.119858) (xy 51.930892 -408.139386) (xy 51.938426 -408.162358)
			(xy 51.938936 -408.174444) (xy 51.938936 -408.860244) (xy 53.702712 -408.860244) (xy 53.702712 -408.174444)
			(xy 53.703198 -408.162395) (xy 53.71062 -408.139469) (xy 53.724753 -408.119951) (xy 53.74422 -408.105747)
			(xy 53.767119 -408.098242) (xy 53.779166 -408.097736) (xy 53.974238 -408.097736) (xy 53.985343 -408.098119)
			(xy 54.006635 -408.104441) (xy 54.016148 -408.110182) (xy 54.309772 -408.302714) (xy 54.319158 -408.308413)
			(xy 54.34017 -408.314749) (xy 54.362116 -408.314824) (xy 54.38317 -408.308632) (xy 54.392576 -408.302968)
			(xy 54.68874 -408.110182) (xy 54.698254 -408.104441) (xy 54.719545 -408.098111) (xy 54.73065 -408.097736)
			(xy 54.925214 -408.097736) (xy 54.937304 -408.098195) (xy 54.960304 -408.105655) (xy 54.979884 -408.119844)
			(xy 54.994134 -408.139379) (xy 55.001666 -408.162356) (xy 55.002176 -408.174444) (xy 55.002176 -408.860244)
			(xy 56.765952 -408.860244) (xy 56.765952 -408.174444) (xy 56.766496 -408.162401) (xy 56.773911 -408.139485)
			(xy 56.788032 -408.119972) (xy 56.807482 -408.105766) (xy 56.830365 -408.09825) (xy 56.842406 -408.097736)
			(xy 57.037478 -408.097736) (xy 57.048584 -408.098103) (xy 57.069876 -408.104436) (xy 57.079388 -408.110182)
			(xy 57.373012 -408.302714) (xy 57.382379 -408.308447) (xy 57.4034 -408.314775) (xy 57.425352 -408.314841)
			(xy 57.44641 -408.308637) (xy 57.455816 -408.302968) (xy 57.75198 -408.110182) (xy 57.761486 -408.104426)
			(xy 57.782783 -408.098106) (xy 57.79389 -408.097736) (xy 57.988454 -408.097736) (xy 58.000541 -408.098246)
			(xy 58.023539 -408.10569) (xy 58.04312 -408.119865) (xy 58.057372 -408.13939) (xy 58.064906 -408.162359)
			(xy 58.065416 -408.174444) (xy 58.065416 -408.860244) (xy 59.829192 -408.860244) (xy 59.829192 -408.174444)
			(xy 59.829697 -408.162397) (xy 59.837117 -408.139474) (xy 59.851246 -408.119958) (xy 59.870707 -408.105753)
			(xy 59.893601 -408.098244) (xy 59.905646 -408.097736) (xy 60.100718 -408.097736) (xy 60.111822 -408.098127)
			(xy 60.133114 -408.104444) (xy 60.142628 -408.110182) (xy 60.436252 -408.302714) (xy 60.4456 -408.308481)
			(xy 60.46663 -408.314802) (xy 60.488589 -408.314858) (xy 60.50965 -408.308643) (xy 60.519056 -408.302968)
			(xy 60.81522 -408.110182) (xy 60.824738 -408.104449) (xy 60.846026 -408.098114) (xy 60.85713 -408.097736)
			(xy 61.051694 -408.097736) (xy 61.063783 -408.098213) (xy 61.086783 -408.105667) (xy 61.106362 -408.119851)
			(xy 61.120613 -408.139383) (xy 61.128146 -408.162357) (xy 61.128656 -408.174444) (xy 61.128656 -408.860244)
			(xy 62.892432 -408.860244) (xy 62.892432 -408.174444) (xy 62.892898 -408.162393) (xy 62.900322 -408.139463)
			(xy 62.91446 -408.119944) (xy 62.933932 -408.10574) (xy 62.956837 -408.098239) (xy 62.968886 -408.097736)
			(xy 63.163958 -408.097736) (xy 63.175063 -408.098111) (xy 63.196355 -408.104439) (xy 63.205868 -408.110182)
			(xy 63.499492 -408.302714) (xy 63.508869 -408.30843) (xy 63.529885 -408.314762) (xy 63.551834 -408.314832)
			(xy 63.57289 -408.308634) (xy 63.582296 -408.302968) (xy 63.87846 -408.110182) (xy 63.88797 -408.104434)
			(xy 63.909264 -408.098108) (xy 63.92037 -408.097736) (xy 64.114934 -408.097736) (xy 64.127025 -408.098178)
			(xy 64.150026 -408.105644) (xy 64.169605 -408.119837) (xy 64.183855 -408.139375) (xy 64.191386 -408.162354)
			(xy 64.191896 -408.174444) (xy 64.191896 -408.860244) (xy 65.955672 -408.860244) (xy 65.955672 -408.174444)
			(xy 65.956197 -408.162399) (xy 65.963614 -408.139479) (xy 65.977739 -408.119965) (xy 65.997194 -408.105759)
			(xy 66.020083 -408.098247) (xy 66.032126 -408.097736) (xy 66.227198 -408.097736) (xy 66.238301 -408.098136)
			(xy 66.259593 -408.104447) (xy 66.269108 -408.110182) (xy 66.562732 -408.302714) (xy 66.57209 -408.308464)
			(xy 66.593115 -408.314789) (xy 66.61507 -408.314849) (xy 66.63613 -408.30864) (xy 66.645536 -408.302968)
			(xy 66.9417 -408.110182) (xy 66.951203 -408.104419) (xy 66.972502 -408.098103) (xy 66.98361 -408.097736)
			(xy 67.178174 -408.097736) (xy 67.190262 -408.098229) (xy 67.213261 -408.105679) (xy 67.232841 -408.119858)
			(xy 67.247092 -408.139386) (xy 67.254626 -408.162358) (xy 67.255136 -408.174444) (xy 67.255136 -408.860244)
			(xy 69.018912 -408.860244) (xy 69.018912 -408.174444) (xy 69.019398 -408.162395) (xy 69.02682 -408.139469)
			(xy 69.040953 -408.119951) (xy 69.06042 -408.105747) (xy 69.083319 -408.098242) (xy 69.095366 -408.097736)
			(xy 69.290438 -408.097736) (xy 69.301543 -408.098119) (xy 69.322835 -408.104441) (xy 69.332348 -408.110182)
			(xy 69.625972 -408.302714) (xy 69.635358 -408.308413) (xy 69.65637 -408.314749) (xy 69.678316 -408.314824)
			(xy 69.69937 -408.308632) (xy 69.708776 -408.302968) (xy 70.00494 -408.110182) (xy 70.014454 -408.104441)
			(xy 70.035745 -408.098111) (xy 70.04685 -408.097736) (xy 70.241414 -408.097736) (xy 70.253504 -408.098195)
			(xy 70.276504 -408.105655) (xy 70.296084 -408.119844) (xy 70.310334 -408.139379) (xy 70.317866 -408.162356)
			(xy 70.318376 -408.174444) (xy 70.318376 -408.860244) (xy 72.082152 -408.860244) (xy 72.082152 -408.174444)
			(xy 72.082696 -408.162401) (xy 72.090111 -408.139485) (xy 72.104232 -408.119972) (xy 72.123682 -408.105766)
			(xy 72.146565 -408.09825) (xy 72.158606 -408.097736) (xy 72.353678 -408.097736) (xy 72.364784 -408.098103)
			(xy 72.386076 -408.104436) (xy 72.395588 -408.110182) (xy 72.689212 -408.302714) (xy 72.698579 -408.308447)
			(xy 72.7196 -408.314775) (xy 72.741552 -408.314841) (xy 72.76261 -408.308637) (xy 72.772016 -408.302968)
			(xy 73.06818 -408.110182) (xy 73.077686 -408.104426) (xy 73.098983 -408.098106) (xy 73.11009 -408.097736)
			(xy 73.304654 -408.097736) (xy 73.316741 -408.098246) (xy 73.339739 -408.10569) (xy 73.35932 -408.119865)
			(xy 73.373572 -408.13939) (xy 73.381106 -408.162359) (xy 73.381616 -408.174444) (xy 73.381616 -408.860244)
			(xy 75.145392 -408.860244) (xy 75.145392 -408.174444) (xy 75.145897 -408.162397) (xy 75.153317 -408.139474)
			(xy 75.167446 -408.119958) (xy 75.186907 -408.105753) (xy 75.209801 -408.098244) (xy 75.221846 -408.097736)
			(xy 75.416918 -408.097736) (xy 75.428022 -408.098127) (xy 75.449314 -408.104444) (xy 75.458828 -408.110182)
			(xy 75.752452 -408.302714) (xy 75.7618 -408.308481) (xy 75.78283 -408.314802) (xy 75.804789 -408.314858)
			(xy 75.82585 -408.308643) (xy 75.835256 -408.302968) (xy 76.13142 -408.110182) (xy 76.140938 -408.104449)
			(xy 76.162226 -408.098114) (xy 76.17333 -408.097736) (xy 76.367894 -408.097736) (xy 76.379983 -408.098213)
			(xy 76.402983 -408.105667) (xy 76.422562 -408.119851) (xy 76.436813 -408.139383) (xy 76.444346 -408.162357)
			(xy 76.444856 -408.174444) (xy 76.444856 -408.860244) (xy 78.208632 -408.860244) (xy 78.208632 -408.174444)
			(xy 78.209098 -408.162393) (xy 78.216522 -408.139463) (xy 78.23066 -408.119944) (xy 78.250132 -408.10574)
			(xy 78.273037 -408.098239) (xy 78.285086 -408.097736) (xy 78.480158 -408.097736) (xy 78.491263 -408.098111)
			(xy 78.512555 -408.104439) (xy 78.522068 -408.110182) (xy 78.815692 -408.302714) (xy 78.825069 -408.30843)
			(xy 78.846085 -408.314762) (xy 78.868034 -408.314832) (xy 78.88909 -408.308634) (xy 78.898496 -408.302968)
			(xy 79.19466 -408.110182) (xy 79.20417 -408.104434) (xy 79.225464 -408.098108) (xy 79.23657 -408.097736)
			(xy 79.431134 -408.097736) (xy 79.443225 -408.098178) (xy 79.466226 -408.105644) (xy 79.485805 -408.119837)
			(xy 79.500055 -408.139375) (xy 79.507586 -408.162354) (xy 79.508096 -408.174444) (xy 79.508096 -408.860244)
			(xy 81.271872 -408.860244) (xy 81.271872 -408.174444) (xy 81.272397 -408.162399) (xy 81.279814 -408.139479)
			(xy 81.293939 -408.119965) (xy 81.313394 -408.105759) (xy 81.336283 -408.098247) (xy 81.348326 -408.097736)
			(xy 81.543398 -408.097736) (xy 81.554501 -408.098136) (xy 81.575793 -408.104447) (xy 81.585308 -408.110182)
			(xy 81.878932 -408.302714) (xy 81.88829 -408.308464) (xy 81.909315 -408.314789) (xy 81.93127 -408.314849)
			(xy 81.95233 -408.30864) (xy 81.961736 -408.302968) (xy 82.2579 -408.110182) (xy 82.267403 -408.104419)
			(xy 82.288702 -408.098103) (xy 82.29981 -408.097736) (xy 82.494374 -408.097736) (xy 82.506462 -408.098229)
			(xy 82.529461 -408.105679) (xy 82.549041 -408.119858) (xy 82.563292 -408.139386) (xy 82.570826 -408.162358)
			(xy 82.571336 -408.174444) (xy 82.571336 -408.860244) (xy 84.335112 -408.860244) (xy 84.335112 -408.174444)
			(xy 84.335598 -408.162395) (xy 84.34302 -408.139469) (xy 84.357153 -408.119951) (xy 84.37662 -408.105747)
			(xy 84.399519 -408.098242) (xy 84.411566 -408.097736) (xy 84.606638 -408.097736) (xy 84.617743 -408.098119)
			(xy 84.639035 -408.104441) (xy 84.648548 -408.110182) (xy 84.942172 -408.302714) (xy 84.951558 -408.308413)
			(xy 84.97257 -408.314749) (xy 84.994516 -408.314824) (xy 85.01557 -408.308632) (xy 85.024976 -408.302968)
			(xy 85.32114 -408.110182) (xy 85.330654 -408.104441) (xy 85.351945 -408.098111) (xy 85.36305 -408.097736)
			(xy 85.557614 -408.097736) (xy 85.569704 -408.098195) (xy 85.592704 -408.105655) (xy 85.612284 -408.119844)
			(xy 85.626534 -408.139379) (xy 85.634066 -408.162356) (xy 85.634576 -408.174444) (xy 85.634576 -408.860244)
			(xy 87.398352 -408.860244) (xy 87.398352 -408.174444) (xy 87.398896 -408.162401) (xy 87.406311 -408.139485)
			(xy 87.420432 -408.119972) (xy 87.439882 -408.105766) (xy 87.462765 -408.09825) (xy 87.474806 -408.097736)
			(xy 87.669878 -408.097736) (xy 87.680984 -408.098103) (xy 87.702276 -408.104436) (xy 87.711788 -408.110182)
			(xy 88.005412 -408.302714) (xy 88.014779 -408.308447) (xy 88.0358 -408.314775) (xy 88.057752 -408.314841)
			(xy 88.07881 -408.308637) (xy 88.088216 -408.302968) (xy 88.38438 -408.110182) (xy 88.393886 -408.104426)
			(xy 88.415183 -408.098106) (xy 88.42629 -408.097736) (xy 88.620854 -408.097736) (xy 88.632941 -408.098246)
			(xy 88.655939 -408.10569) (xy 88.67552 -408.119865) (xy 88.689772 -408.13939) (xy 88.697306 -408.162359)
			(xy 88.697816 -408.174444) (xy 88.697816 -408.860244) (xy 90.461592 -408.860244) (xy 90.461592 -408.174444)
			(xy 90.462097 -408.162397) (xy 90.469517 -408.139474) (xy 90.483646 -408.119958) (xy 90.503107 -408.105753)
			(xy 90.526001 -408.098244) (xy 90.538046 -408.097736) (xy 90.733118 -408.097736) (xy 90.744222 -408.098127)
			(xy 90.765514 -408.104444) (xy 90.775028 -408.110182) (xy 91.068652 -408.302714) (xy 91.078 -408.308481)
			(xy 91.09903 -408.314802) (xy 91.120989 -408.314858) (xy 91.14205 -408.308643) (xy 91.151456 -408.302968)
			(xy 91.44762 -408.110182) (xy 91.457138 -408.104449) (xy 91.478426 -408.098114) (xy 91.48953 -408.097736)
			(xy 91.684094 -408.097736) (xy 91.696183 -408.098213) (xy 91.719183 -408.105667) (xy 91.738762 -408.119851)
			(xy 91.753013 -408.139383) (xy 91.760546 -408.162357) (xy 91.761056 -408.174444) (xy 91.761056 -408.860244)
			(xy 93.524832 -408.860244) (xy 93.524832 -408.174444) (xy 93.525298 -408.162393) (xy 93.532722 -408.139463)
			(xy 93.54686 -408.119944) (xy 93.566332 -408.10574) (xy 93.589237 -408.098239) (xy 93.601286 -408.097736)
			(xy 93.796358 -408.097736) (xy 93.807463 -408.098111) (xy 93.828755 -408.104439) (xy 93.838268 -408.110182)
			(xy 94.131892 -408.302714) (xy 94.141269 -408.30843) (xy 94.162285 -408.314762) (xy 94.184234 -408.314832)
			(xy 94.20529 -408.308634) (xy 94.214696 -408.302968) (xy 94.51086 -408.110182) (xy 94.52037 -408.104434)
			(xy 94.541664 -408.098108) (xy 94.55277 -408.097736) (xy 94.747334 -408.097736) (xy 94.759425 -408.098178)
			(xy 94.782426 -408.105644) (xy 94.802005 -408.119837) (xy 94.816255 -408.139375) (xy 94.823786 -408.162354)
			(xy 94.824296 -408.174444) (xy 94.824296 -408.860244) (xy 94.823878 -408.872297) (xy 94.816432 -408.895225)
			(xy 94.802281 -408.91474) (xy 94.782802 -408.928942) (xy 94.759894 -408.936446) (xy 94.747842 -408.936952)
			(xy 94.55277 -408.936952) (xy 94.541662 -408.936589) (xy 94.520366 -408.930265) (xy 94.51086 -408.924506)
			(xy 94.215966 -408.731974) (xy 94.206579 -408.726271) (xy 94.185541 -408.719998) (xy 94.163587 -408.719998)
			(xy 94.142549 -408.726271) (xy 94.133162 -408.731974) (xy 93.839538 -408.924506) (xy 93.830027 -408.930254)
			(xy 93.808734 -408.93658) (xy 93.797628 -408.936952) (xy 93.601794 -408.936952) (xy 93.589703 -408.936497)
			(xy 93.566701 -408.929038) (xy 93.547121 -408.914849) (xy 93.532871 -408.895312) (xy 93.52534 -408.872333)
			(xy 93.524832 -408.860244) (xy 91.761056 -408.860244) (xy 91.760579 -408.872291) (xy 91.753141 -408.895209)
			(xy 91.739002 -408.914719) (xy 91.71954 -408.928923) (xy 91.696647 -408.936438) (xy 91.684602 -408.936952)
			(xy 91.48953 -408.936952) (xy 91.478421 -408.936605) (xy 91.457124 -408.93027) (xy 91.44762 -408.924506)
			(xy 91.152726 -408.731974) (xy 91.143339 -408.726271) (xy 91.122301 -408.719998) (xy 91.100347 -408.719998)
			(xy 91.079309 -408.726271) (xy 91.069922 -408.731974) (xy 90.776298 -408.924506) (xy 90.766795 -408.930269)
			(xy 90.745496 -408.936585) (xy 90.734388 -408.936952) (xy 90.538554 -408.936952) (xy 90.526461 -408.936532)
			(xy 90.503458 -408.929061) (xy 90.483878 -408.914863) (xy 90.469629 -408.89532) (xy 90.4621 -408.872335)
			(xy 90.461592 -408.860244) (xy 88.697816 -408.860244) (xy 88.697378 -408.872295) (xy 88.689935 -408.895219)
			(xy 88.675788 -408.914733) (xy 88.656315 -408.928935) (xy 88.633412 -408.936443) (xy 88.621362 -408.936952)
			(xy 88.42629 -408.936952) (xy 88.415183 -408.936581) (xy 88.393886 -408.930262) (xy 88.38438 -408.924506)
			(xy 88.089486 -408.731974) (xy 88.080099 -408.726271) (xy 88.059061 -408.719998) (xy 88.037107 -408.719998)
			(xy 88.016069 -408.726271) (xy 88.006682 -408.731974) (xy 87.713058 -408.924506) (xy 87.703543 -408.930247)
			(xy 87.682253 -408.936577) (xy 87.671148 -408.936952) (xy 87.475314 -408.936952) (xy 87.463224 -408.93648)
			(xy 87.440223 -408.929027) (xy 87.420642 -408.914841) (xy 87.406391 -408.895308) (xy 87.39886 -408.872332)
			(xy 87.398352 -408.860244) (xy 85.634576 -408.860244) (xy 85.634177 -408.872299) (xy 85.626729 -408.89523)
			(xy 85.612574 -408.914747) (xy 85.593089 -408.928948) (xy 85.570176 -408.936449) (xy 85.558122 -408.936952)
			(xy 85.36305 -408.936952) (xy 85.351941 -408.936597) (xy 85.330645 -408.930267) (xy 85.32114 -408.924506)
			(xy 85.026246 -408.731974) (xy 85.016859 -408.726271) (xy 84.995821 -408.719998) (xy 84.973867 -408.719998)
			(xy 84.952829 -408.726271) (xy 84.943442 -408.731974) (xy 84.649818 -408.924506) (xy 84.640311 -408.930261)
			(xy 84.619015 -408.936583) (xy 84.607908 -408.936952) (xy 84.412074 -408.936952) (xy 84.399982 -408.936515)
			(xy 84.376979 -408.92905) (xy 84.357399 -408.914856) (xy 84.34315 -408.895316) (xy 84.33562 -408.872334)
			(xy 84.335112 -408.860244) (xy 82.571336 -408.860244) (xy 82.570878 -408.872293) (xy 82.563438 -408.895214)
			(xy 82.549295 -408.914726) (xy 82.529827 -408.928929) (xy 82.506929 -408.936441) (xy 82.494882 -408.936952)
			(xy 82.29981 -408.936952) (xy 82.288703 -408.936572) (xy 82.267407 -408.930259) (xy 82.2579 -408.924506)
			(xy 81.963006 -408.731974) (xy 81.953619 -408.726271) (xy 81.932581 -408.719998) (xy 81.910627 -408.719998)
			(xy 81.889589 -408.726271) (xy 81.880202 -408.731974) (xy 81.586578 -408.924506) (xy 81.577059 -408.930239)
			(xy 81.555772 -408.936574) (xy 81.544668 -408.936952) (xy 81.348834 -408.936952) (xy 81.336745 -408.936464)
			(xy 81.313745 -408.929015) (xy 81.294163 -408.914834) (xy 81.279912 -408.895305) (xy 81.272381 -408.872331)
			(xy 81.271872 -408.860244) (xy 79.508096 -408.860244) (xy 79.507678 -408.872297) (xy 79.500232 -408.895225)
			(xy 79.486081 -408.91474) (xy 79.466602 -408.928942) (xy 79.443694 -408.936446) (xy 79.431642 -408.936952)
			(xy 79.23657 -408.936952) (xy 79.225462 -408.936589) (xy 79.204166 -408.930265) (xy 79.19466 -408.924506)
			(xy 78.899766 -408.731974) (xy 78.890379 -408.726271) (xy 78.869341 -408.719998) (xy 78.847387 -408.719998)
			(xy 78.826349 -408.726271) (xy 78.816962 -408.731974) (xy 78.523338 -408.924506) (xy 78.513827 -408.930254)
			(xy 78.492534 -408.93658) (xy 78.481428 -408.936952) (xy 78.285594 -408.936952) (xy 78.273503 -408.936497)
			(xy 78.250501 -408.929038) (xy 78.230921 -408.914849) (xy 78.216671 -408.895312) (xy 78.20914 -408.872333)
			(xy 78.208632 -408.860244) (xy 76.444856 -408.860244) (xy 76.444379 -408.872291) (xy 76.436941 -408.895209)
			(xy 76.422802 -408.914719) (xy 76.40334 -408.928923) (xy 76.380447 -408.936438) (xy 76.368402 -408.936952)
			(xy 76.17333 -408.936952) (xy 76.162221 -408.936605) (xy 76.140924 -408.93027) (xy 76.13142 -408.924506)
			(xy 75.836526 -408.731974) (xy 75.827139 -408.726271) (xy 75.806101 -408.719998) (xy 75.784147 -408.719998)
			(xy 75.763109 -408.726271) (xy 75.753722 -408.731974) (xy 75.460098 -408.924506) (xy 75.450595 -408.930269)
			(xy 75.429296 -408.936585) (xy 75.418188 -408.936952) (xy 75.222354 -408.936952) (xy 75.210261 -408.936532)
			(xy 75.187258 -408.929061) (xy 75.167678 -408.914863) (xy 75.153429 -408.89532) (xy 75.1459 -408.872335)
			(xy 75.145392 -408.860244) (xy 73.381616 -408.860244) (xy 73.381178 -408.872295) (xy 73.373735 -408.895219)
			(xy 73.359588 -408.914733) (xy 73.340115 -408.928935) (xy 73.317212 -408.936443) (xy 73.305162 -408.936952)
			(xy 73.11009 -408.936952) (xy 73.098983 -408.936581) (xy 73.077686 -408.930262) (xy 73.06818 -408.924506)
			(xy 72.773286 -408.731974) (xy 72.763899 -408.726271) (xy 72.742861 -408.719998) (xy 72.720907 -408.719998)
			(xy 72.699869 -408.726271) (xy 72.690482 -408.731974) (xy 72.396858 -408.924506) (xy 72.387343 -408.930247)
			(xy 72.366053 -408.936577) (xy 72.354948 -408.936952) (xy 72.159114 -408.936952) (xy 72.147024 -408.93648)
			(xy 72.124023 -408.929027) (xy 72.104442 -408.914841) (xy 72.090191 -408.895308) (xy 72.08266 -408.872332)
			(xy 72.082152 -408.860244) (xy 70.318376 -408.860244) (xy 70.317977 -408.872299) (xy 70.310529 -408.89523)
			(xy 70.296374 -408.914747) (xy 70.276889 -408.928948) (xy 70.253976 -408.936449) (xy 70.241922 -408.936952)
			(xy 70.04685 -408.936952) (xy 70.035741 -408.936597) (xy 70.014445 -408.930267) (xy 70.00494 -408.924506)
			(xy 69.710046 -408.731974) (xy 69.700659 -408.726271) (xy 69.679621 -408.719998) (xy 69.657667 -408.719998)
			(xy 69.636629 -408.726271) (xy 69.627242 -408.731974) (xy 69.333618 -408.924506) (xy 69.324111 -408.930261)
			(xy 69.302815 -408.936583) (xy 69.291708 -408.936952) (xy 69.095874 -408.936952) (xy 69.083782 -408.936515)
			(xy 69.060779 -408.92905) (xy 69.041199 -408.914856) (xy 69.02695 -408.895316) (xy 69.01942 -408.872334)
			(xy 69.018912 -408.860244) (xy 67.255136 -408.860244) (xy 67.254678 -408.872293) (xy 67.247238 -408.895214)
			(xy 67.233095 -408.914726) (xy 67.213627 -408.928929) (xy 67.190729 -408.936441) (xy 67.178682 -408.936952)
			(xy 66.98361 -408.936952) (xy 66.972503 -408.936572) (xy 66.951207 -408.930259) (xy 66.9417 -408.924506)
			(xy 66.646806 -408.731974) (xy 66.637419 -408.726271) (xy 66.616381 -408.719998) (xy 66.594427 -408.719998)
			(xy 66.573389 -408.726271) (xy 66.564002 -408.731974) (xy 66.270378 -408.924506) (xy 66.260859 -408.930239)
			(xy 66.239572 -408.936574) (xy 66.228468 -408.936952) (xy 66.032634 -408.936952) (xy 66.020545 -408.936464)
			(xy 65.997545 -408.929015) (xy 65.977963 -408.914834) (xy 65.963712 -408.895305) (xy 65.956181 -408.872331)
			(xy 65.955672 -408.860244) (xy 64.191896 -408.860244) (xy 64.191478 -408.872297) (xy 64.184032 -408.895225)
			(xy 64.169881 -408.91474) (xy 64.150402 -408.928942) (xy 64.127494 -408.936446) (xy 64.115442 -408.936952)
			(xy 63.92037 -408.936952) (xy 63.909262 -408.936589) (xy 63.887966 -408.930265) (xy 63.87846 -408.924506)
			(xy 63.583566 -408.731974) (xy 63.574179 -408.726271) (xy 63.553141 -408.719998) (xy 63.531187 -408.719998)
			(xy 63.510149 -408.726271) (xy 63.500762 -408.731974) (xy 63.207138 -408.924506) (xy 63.197627 -408.930254)
			(xy 63.176334 -408.93658) (xy 63.165228 -408.936952) (xy 62.969394 -408.936952) (xy 62.957303 -408.936497)
			(xy 62.934301 -408.929038) (xy 62.914721 -408.914849) (xy 62.900471 -408.895312) (xy 62.89294 -408.872333)
			(xy 62.892432 -408.860244) (xy 61.128656 -408.860244) (xy 61.128179 -408.872291) (xy 61.120741 -408.895209)
			(xy 61.106602 -408.914719) (xy 61.08714 -408.928923) (xy 61.064247 -408.936438) (xy 61.052202 -408.936952)
			(xy 60.85713 -408.936952) (xy 60.846021 -408.936605) (xy 60.824724 -408.93027) (xy 60.81522 -408.924506)
			(xy 60.520326 -408.731974) (xy 60.510939 -408.726271) (xy 60.489901 -408.719998) (xy 60.467947 -408.719998)
			(xy 60.446909 -408.726271) (xy 60.437522 -408.731974) (xy 60.143898 -408.924506) (xy 60.134395 -408.930269)
			(xy 60.113096 -408.936585) (xy 60.101988 -408.936952) (xy 59.906154 -408.936952) (xy 59.894061 -408.936532)
			(xy 59.871058 -408.929061) (xy 59.851478 -408.914863) (xy 59.837229 -408.89532) (xy 59.8297 -408.872335)
			(xy 59.829192 -408.860244) (xy 58.065416 -408.860244) (xy 58.064978 -408.872295) (xy 58.057535 -408.895219)
			(xy 58.043388 -408.914733) (xy 58.023915 -408.928935) (xy 58.001012 -408.936443) (xy 57.988962 -408.936952)
			(xy 57.79389 -408.936952) (xy 57.782783 -408.936581) (xy 57.761486 -408.930262) (xy 57.75198 -408.924506)
			(xy 57.457086 -408.731974) (xy 57.447699 -408.726271) (xy 57.426661 -408.719998) (xy 57.404707 -408.719998)
			(xy 57.383669 -408.726271) (xy 57.374282 -408.731974) (xy 57.080658 -408.924506) (xy 57.071143 -408.930247)
			(xy 57.049853 -408.936577) (xy 57.038748 -408.936952) (xy 56.842914 -408.936952) (xy 56.830824 -408.93648)
			(xy 56.807823 -408.929027) (xy 56.788242 -408.914841) (xy 56.773991 -408.895308) (xy 56.76646 -408.872332)
			(xy 56.765952 -408.860244) (xy 55.002176 -408.860244) (xy 55.001777 -408.872299) (xy 54.994329 -408.89523)
			(xy 54.980174 -408.914747) (xy 54.960689 -408.928948) (xy 54.937776 -408.936449) (xy 54.925722 -408.936952)
			(xy 54.73065 -408.936952) (xy 54.719541 -408.936597) (xy 54.698245 -408.930267) (xy 54.68874 -408.924506)
			(xy 54.393846 -408.731974) (xy 54.384459 -408.726271) (xy 54.363421 -408.719998) (xy 54.341467 -408.719998)
			(xy 54.320429 -408.726271) (xy 54.311042 -408.731974) (xy 54.017418 -408.924506) (xy 54.007911 -408.930261)
			(xy 53.986615 -408.936583) (xy 53.975508 -408.936952) (xy 53.779674 -408.936952) (xy 53.767582 -408.936515)
			(xy 53.744579 -408.92905) (xy 53.724999 -408.914856) (xy 53.71075 -408.895316) (xy 53.70322 -408.872334)
			(xy 53.702712 -408.860244) (xy 51.938936 -408.860244) (xy 51.938478 -408.872293) (xy 51.931038 -408.895214)
			(xy 51.916895 -408.914726) (xy 51.897427 -408.928929) (xy 51.874529 -408.936441) (xy 51.862482 -408.936952)
			(xy 51.66741 -408.936952) (xy 51.656303 -408.936572) (xy 51.635007 -408.930259) (xy 51.6255 -408.924506)
			(xy 51.330606 -408.731974) (xy 51.321219 -408.726271) (xy 51.300181 -408.719998) (xy 51.278227 -408.719998)
			(xy 51.257189 -408.726271) (xy 51.247802 -408.731974) (xy 50.954178 -408.924506) (xy 50.944659 -408.930239)
			(xy 50.923372 -408.936574) (xy 50.912268 -408.936952) (xy 50.716434 -408.936952) (xy 50.704345 -408.936464)
			(xy 50.681345 -408.929015) (xy 50.661763 -408.914834) (xy 50.647512 -408.895305) (xy 50.639981 -408.872331)
			(xy 50.639472 -408.860244) (xy 48.875696 -408.860244) (xy 48.875278 -408.872297) (xy 48.867832 -408.895225)
			(xy 48.853681 -408.91474) (xy 48.834202 -408.928942) (xy 48.811294 -408.936446) (xy 48.799242 -408.936952)
			(xy 48.60417 -408.936952) (xy 48.593062 -408.936589) (xy 48.571766 -408.930265) (xy 48.56226 -408.924506)
			(xy 48.267366 -408.731974) (xy 48.257979 -408.726271) (xy 48.236941 -408.719998) (xy 48.214987 -408.719998)
			(xy 48.193949 -408.726271) (xy 48.184562 -408.731974) (xy 47.890938 -408.924506) (xy 47.881427 -408.930254)
			(xy 47.860134 -408.93658) (xy 47.849028 -408.936952) (xy 47.653194 -408.936952) (xy 47.641103 -408.936497)
			(xy 47.618101 -408.929038) (xy 47.598521 -408.914849) (xy 47.584271 -408.895312) (xy 47.57674 -408.872333)
			(xy 47.576232 -408.860244) (xy 6.918074 -408.860244) (xy 6.930013 -408.901671) (xy 6.961351 -409.038912)
			(xy 6.984945 -409.177694) (xy 7.00072 -409.31758) (xy 7.008628 -409.458131) (xy 7.00913 -409.528518)
			(xy 7.00913 -409.563824) (xy 102.192836 -409.563824) (xy 102.192836 -408.700224) (xy 102.193322 -408.672955)
			(xy 102.201084 -408.618971) (xy 102.216449 -408.566641) (xy 102.239106 -408.517031) (xy 102.268592 -408.47115)
			(xy 102.304307 -408.429933) (xy 102.345524 -408.394218) (xy 102.391405 -408.364732) (xy 102.441015 -408.342075)
			(xy 102.493345 -408.32671) (xy 102.547329 -408.318948) (xy 102.601867 -408.318948) (xy 102.655851 -408.32671)
			(xy 102.708181 -408.342075) (xy 102.757791 -408.364732) (xy 102.803672 -408.394218) (xy 102.844889 -408.429933)
			(xy 102.880604 -408.47115) (xy 102.91009 -408.517031) (xy 102.932747 -408.566641) (xy 102.948112 -408.618971)
			(xy 102.955874 -408.672955) (xy 102.95636 -408.700224) (xy 102.95636 -409.563824) (xy 102.955874 -409.591093)
			(xy 102.948112 -409.645077) (xy 102.932747 -409.697407) (xy 102.91009 -409.747017) (xy 102.880604 -409.792898)
			(xy 102.844889 -409.834115) (xy 102.803672 -409.86983) (xy 102.757791 -409.899316) (xy 102.748244 -409.903676)
			(xy 110.559596 -409.903676) (xy 110.559596 -409.040076) (xy 110.560082 -409.012825) (xy 110.567838 -408.958877)
			(xy 110.583193 -408.906582) (xy 110.605835 -408.857005) (xy 110.635301 -408.811155) (xy 110.670992 -408.769964)
			(xy 110.712183 -408.734273) (xy 110.758033 -408.704807) (xy 110.80761 -408.682165) (xy 110.859905 -408.66681)
			(xy 110.913853 -408.659054) (xy 110.968355 -408.659054) (xy 111.022303 -408.66681) (xy 111.074598 -408.682165)
			(xy 111.124175 -408.704807) (xy 111.170025 -408.734273) (xy 111.211216 -408.769964) (xy 111.246907 -408.811155)
			(xy 111.276373 -408.857005) (xy 111.277852 -408.860244) (xy 114.676428 -408.860244) (xy 114.676428 -408.174444)
			(xy 114.676851 -408.16236) (xy 114.68431 -408.139373) (xy 114.698513 -408.119818) (xy 114.718065 -408.105614)
			(xy 114.741052 -408.098152) (xy 114.753136 -408.097736) (xy 114.9477 -408.097736) (xy 114.958803 -408.098135)
			(xy 114.980095 -408.104446) (xy 114.98961 -408.110182) (xy 115.283234 -408.302714) (xy 115.292591 -408.308465)
			(xy 115.313616 -408.31479) (xy 115.335572 -408.31485) (xy 115.356632 -408.30864) (xy 115.366038 -408.302968)
			(xy 115.662202 -408.110182) (xy 115.671704 -408.104418) (xy 115.693004 -408.098103) (xy 115.704112 -408.097736)
			(xy 115.898676 -408.097736) (xy 115.910762 -408.098134) (xy 115.933751 -408.1056) (xy 115.953306 -408.119809)
			(xy 115.967509 -408.139367) (xy 115.974969 -408.162358) (xy 115.975384 -408.174444) (xy 115.975384 -408.860244)
			(xy 117.739668 -408.860244) (xy 117.739668 -408.174444) (xy 117.74015 -408.162366) (xy 117.747602 -408.139389)
			(xy 117.761791 -408.11984) (xy 117.781328 -408.105633) (xy 117.804298 -408.09816) (xy 117.816376 -408.097736)
			(xy 118.01094 -408.097736) (xy 118.022045 -408.098118) (xy 118.043337 -408.104441) (xy 118.05285 -408.110182)
			(xy 118.346474 -408.302714) (xy 118.355859 -408.308414) (xy 118.376871 -408.31475) (xy 118.398818 -408.314825)
			(xy 118.419872 -408.308632) (xy 118.429278 -408.302968) (xy 118.725442 -408.110182) (xy 118.734956 -408.10444)
			(xy 118.756247 -408.098111) (xy 118.767352 -408.097736) (xy 118.961916 -408.097736) (xy 118.974004 -408.0981)
			(xy 118.996995 -408.105577) (xy 119.016549 -408.119794) (xy 119.030751 -408.139359) (xy 119.03821 -408.162356)
			(xy 119.038624 -408.174444) (xy 119.038624 -408.860244) (xy 120.802908 -408.860244) (xy 120.802908 -408.174444)
			(xy 120.80335 -408.162362) (xy 120.810808 -408.139378) (xy 120.825006 -408.119826) (xy 120.844553 -408.105621)
			(xy 120.867534 -408.098155) (xy 120.879616 -408.097736) (xy 121.07418 -408.097736) (xy 121.085286 -408.098103)
			(xy 121.106578 -408.104436) (xy 121.11609 -408.110182) (xy 121.409714 -408.302714) (xy 121.41908 -408.308448)
			(xy 121.440101 -408.314777) (xy 121.462054 -408.314842) (xy 121.483112 -408.308638) (xy 121.492518 -408.302968)
			(xy 121.788682 -408.110182) (xy 121.798188 -408.104426) (xy 121.819485 -408.098105) (xy 121.830592 -408.097736)
			(xy 122.025156 -408.097736) (xy 122.037241 -408.098151) (xy 122.06023 -408.105612) (xy 122.079784 -408.119816)
			(xy 122.093988 -408.13937) (xy 122.101449 -408.162359) (xy 122.101864 -408.174444) (xy 122.101864 -408.860244)
			(xy 123.866148 -408.860244) (xy 123.866148 -408.174444) (xy 123.866701 -408.162376) (xy 123.874146 -408.139418)
			(xy 123.888321 -408.119884) (xy 123.907839 -408.105686) (xy 123.930789 -408.098215) (xy 123.942856 -408.097736)
			(xy 124.13742 -408.097736) (xy 124.148524 -408.098126) (xy 124.169816 -408.104443) (xy 124.17933 -408.110182)
			(xy 124.472954 -408.302714) (xy 124.482349 -408.308397) (xy 124.503356 -408.314736) (xy 124.525299 -408.314816)
			(xy 124.546352 -408.308629) (xy 124.555758 -408.302968) (xy 124.851922 -408.110182) (xy 124.86144 -408.104448)
			(xy 124.882727 -408.098114) (xy 124.893832 -408.097736) (xy 125.088396 -408.097736) (xy 125.100483 -408.098116)
			(xy 125.123473 -408.105588) (xy 125.143027 -408.119801) (xy 125.15723 -408.139363) (xy 125.16469 -408.162357)
			(xy 125.165104 -408.174444) (xy 125.165104 -408.860244) (xy 126.929388 -408.860244) (xy 126.929388 -408.174444)
			(xy 126.92985 -408.162364) (xy 126.937305 -408.139383) (xy 126.951499 -408.119833) (xy 126.97104 -408.105627)
			(xy 126.994016 -408.098158) (xy 127.006096 -408.097736) (xy 127.20066 -408.097736) (xy 127.211765 -408.09811)
			(xy 127.233057 -408.104438) (xy 127.24257 -408.110182) (xy 127.536194 -408.302714) (xy 127.54557 -408.308431)
			(xy 127.566586 -408.314763) (xy 127.588536 -408.314833) (xy 127.609592 -408.308635) (xy 127.618998 -408.302968)
			(xy 127.915162 -408.110182) (xy 127.924672 -408.104433) (xy 127.945966 -408.098108) (xy 127.957072 -408.097736)
			(xy 128.151636 -408.097736) (xy 128.163725 -408.098083) (xy 128.186716 -408.105565) (xy 128.20627 -408.119787)
			(xy 128.220471 -408.139355) (xy 128.22793 -408.162355) (xy 128.228344 -408.174444) (xy 128.228344 -408.860244)
			(xy 129.992628 -408.860244) (xy 129.992628 -408.174444) (xy 129.993051 -408.16236) (xy 130.00051 -408.139373)
			(xy 130.014713 -408.119818) (xy 130.034265 -408.105614) (xy 130.057252 -408.098152) (xy 130.069336 -408.097736)
			(xy 130.2639 -408.097736) (xy 130.275003 -408.098135) (xy 130.296295 -408.104446) (xy 130.30581 -408.110182)
			(xy 130.599434 -408.302714) (xy 130.608791 -408.308465) (xy 130.629816 -408.31479) (xy 130.651772 -408.31485)
			(xy 130.672832 -408.30864) (xy 130.682238 -408.302968) (xy 130.978402 -408.110182) (xy 130.987904 -408.104418)
			(xy 131.009204 -408.098103) (xy 131.020312 -408.097736) (xy 131.214876 -408.097736) (xy 131.226962 -408.098134)
			(xy 131.249951 -408.1056) (xy 131.269506 -408.119809) (xy 131.283709 -408.139367) (xy 131.291169 -408.162358)
			(xy 131.291584 -408.174444) (xy 131.291584 -408.860244) (xy 133.055868 -408.860244) (xy 133.055868 -408.174444)
			(xy 133.05635 -408.162366) (xy 133.063802 -408.139389) (xy 133.077991 -408.11984) (xy 133.097528 -408.105633)
			(xy 133.120498 -408.09816) (xy 133.132576 -408.097736) (xy 133.32714 -408.097736) (xy 133.338245 -408.098118)
			(xy 133.359537 -408.104441) (xy 133.36905 -408.110182) (xy 133.662674 -408.302714) (xy 133.672059 -408.308414)
			(xy 133.693071 -408.31475) (xy 133.715018 -408.314825) (xy 133.736072 -408.308632) (xy 133.745478 -408.302968)
			(xy 134.041642 -408.110182) (xy 134.051156 -408.10444) (xy 134.072447 -408.098111) (xy 134.083552 -408.097736)
			(xy 134.278116 -408.097736) (xy 134.290204 -408.0981) (xy 134.313195 -408.105577) (xy 134.332749 -408.119794)
			(xy 134.346951 -408.139359) (xy 134.35441 -408.162356) (xy 134.354824 -408.174444) (xy 134.354824 -408.860244)
			(xy 136.119108 -408.860244) (xy 136.119108 -408.174444) (xy 136.11955 -408.162362) (xy 136.127008 -408.139378)
			(xy 136.141206 -408.119826) (xy 136.160753 -408.105621) (xy 136.183734 -408.098155) (xy 136.195816 -408.097736)
			(xy 136.39038 -408.097736) (xy 136.401486 -408.098103) (xy 136.422778 -408.104436) (xy 136.43229 -408.110182)
			(xy 136.725914 -408.302714) (xy 136.73528 -408.308448) (xy 136.756301 -408.314777) (xy 136.778254 -408.314842)
			(xy 136.799312 -408.308638) (xy 136.808718 -408.302968) (xy 137.104882 -408.110182) (xy 137.114388 -408.104426)
			(xy 137.135685 -408.098105) (xy 137.146792 -408.097736) (xy 137.341356 -408.097736) (xy 137.353441 -408.098151)
			(xy 137.37643 -408.105612) (xy 137.395984 -408.119816) (xy 137.410188 -408.13937) (xy 137.417649 -408.162359)
			(xy 137.418064 -408.174444) (xy 137.418064 -408.860244) (xy 139.182348 -408.860244) (xy 139.182348 -408.174444)
			(xy 139.182901 -408.162376) (xy 139.190346 -408.139418) (xy 139.204521 -408.119884) (xy 139.224039 -408.105686)
			(xy 139.246989 -408.098215) (xy 139.259056 -408.097736) (xy 139.45362 -408.097736) (xy 139.464724 -408.098126)
			(xy 139.486016 -408.104443) (xy 139.49553 -408.110182) (xy 139.789154 -408.302714) (xy 139.798549 -408.308397)
			(xy 139.819556 -408.314736) (xy 139.841499 -408.314816) (xy 139.862552 -408.308629) (xy 139.871958 -408.302968)
			(xy 140.168122 -408.110182) (xy 140.17764 -408.104448) (xy 140.198927 -408.098114) (xy 140.210032 -408.097736)
			(xy 140.404596 -408.097736) (xy 140.416683 -408.098116) (xy 140.439673 -408.105588) (xy 140.459227 -408.119801)
			(xy 140.47343 -408.139363) (xy 140.48089 -408.162357) (xy 140.481304 -408.174444) (xy 140.481304 -408.860244)
			(xy 142.245588 -408.860244) (xy 142.245588 -408.174444) (xy 142.24605 -408.162364) (xy 142.253505 -408.139383)
			(xy 142.267699 -408.119833) (xy 142.28724 -408.105627) (xy 142.310216 -408.098158) (xy 142.322296 -408.097736)
			(xy 142.51686 -408.097736) (xy 142.527965 -408.09811) (xy 142.549257 -408.104438) (xy 142.55877 -408.110182)
			(xy 142.852394 -408.302714) (xy 142.86177 -408.308431) (xy 142.882786 -408.314763) (xy 142.904736 -408.314833)
			(xy 142.925792 -408.308635) (xy 142.935198 -408.302968) (xy 143.231362 -408.110182) (xy 143.240872 -408.104433)
			(xy 143.262166 -408.098108) (xy 143.273272 -408.097736) (xy 143.467836 -408.097736) (xy 143.479925 -408.098083)
			(xy 143.502916 -408.105565) (xy 143.52247 -408.119787) (xy 143.536671 -408.139355) (xy 143.54413 -408.162355)
			(xy 143.544544 -408.174444) (xy 143.544544 -408.860244) (xy 145.308828 -408.860244) (xy 145.308828 -408.174444)
			(xy 145.309251 -408.16236) (xy 145.31671 -408.139373) (xy 145.330913 -408.119818) (xy 145.350465 -408.105614)
			(xy 145.373452 -408.098152) (xy 145.385536 -408.097736) (xy 145.5801 -408.097736) (xy 145.591203 -408.098135)
			(xy 145.612495 -408.104446) (xy 145.62201 -408.110182) (xy 145.915634 -408.302714) (xy 145.924991 -408.308465)
			(xy 145.946016 -408.31479) (xy 145.967972 -408.31485) (xy 145.989032 -408.30864) (xy 145.998438 -408.302968)
			(xy 146.294602 -408.110182) (xy 146.304104 -408.104418) (xy 146.325404 -408.098103) (xy 146.336512 -408.097736)
			(xy 146.531076 -408.097736) (xy 146.543162 -408.098134) (xy 146.566151 -408.1056) (xy 146.585706 -408.119809)
			(xy 146.599909 -408.139367) (xy 146.607369 -408.162358) (xy 146.607784 -408.174444) (xy 146.607784 -408.860244)
			(xy 148.372068 -408.860244) (xy 148.372068 -408.174444) (xy 148.37255 -408.162366) (xy 148.380002 -408.139389)
			(xy 148.394191 -408.11984) (xy 148.413728 -408.105633) (xy 148.436698 -408.09816) (xy 148.448776 -408.097736)
			(xy 148.64334 -408.097736) (xy 148.654445 -408.098118) (xy 148.675737 -408.104441) (xy 148.68525 -408.110182)
			(xy 148.978874 -408.302714) (xy 148.988259 -408.308414) (xy 149.009271 -408.31475) (xy 149.031218 -408.314825)
			(xy 149.052272 -408.308632) (xy 149.061678 -408.302968) (xy 149.357842 -408.110182) (xy 149.367356 -408.10444)
			(xy 149.388647 -408.098111) (xy 149.399752 -408.097736) (xy 149.594316 -408.097736) (xy 149.606404 -408.0981)
			(xy 149.629395 -408.105577) (xy 149.648949 -408.119794) (xy 149.663151 -408.139359) (xy 149.67061 -408.162356)
			(xy 149.671024 -408.174444) (xy 149.671024 -408.860244) (xy 151.435308 -408.860244) (xy 151.435308 -408.174444)
			(xy 151.43575 -408.162362) (xy 151.443208 -408.139378) (xy 151.457406 -408.119826) (xy 151.476953 -408.105621)
			(xy 151.499934 -408.098155) (xy 151.512016 -408.097736) (xy 151.70658 -408.097736) (xy 151.717686 -408.098103)
			(xy 151.738978 -408.104436) (xy 151.74849 -408.110182) (xy 152.042114 -408.302714) (xy 152.05148 -408.308448)
			(xy 152.072501 -408.314777) (xy 152.094454 -408.314842) (xy 152.115512 -408.308638) (xy 152.124918 -408.302968)
			(xy 152.421082 -408.110182) (xy 152.430588 -408.104426) (xy 152.451885 -408.098105) (xy 152.462992 -408.097736)
			(xy 152.657556 -408.097736) (xy 152.669641 -408.098151) (xy 152.69263 -408.105612) (xy 152.712184 -408.119816)
			(xy 152.726388 -408.13937) (xy 152.733849 -408.162359) (xy 152.734264 -408.174444) (xy 152.734264 -408.860244)
			(xy 154.498548 -408.860244) (xy 154.498548 -408.174444) (xy 154.499101 -408.162376) (xy 154.506546 -408.139418)
			(xy 154.520721 -408.119884) (xy 154.540239 -408.105686) (xy 154.563189 -408.098215) (xy 154.575256 -408.097736)
			(xy 154.76982 -408.097736) (xy 154.780924 -408.098126) (xy 154.802216 -408.104443) (xy 154.81173 -408.110182)
			(xy 155.105354 -408.302714) (xy 155.114685 -408.308442) (xy 155.135645 -408.314749) (xy 155.157532 -408.314811)
			(xy 155.178527 -408.308622) (xy 155.187904 -408.302968) (xy 155.188158 -408.302968) (xy 155.484322 -408.110182)
			(xy 155.49384 -408.104448) (xy 155.515127 -408.098114) (xy 155.526232 -408.097736) (xy 155.720796 -408.097736)
			(xy 155.732883 -408.098116) (xy 155.755873 -408.105588) (xy 155.775427 -408.119801) (xy 155.78963 -408.139363)
			(xy 155.79709 -408.162357) (xy 155.797504 -408.174444) (xy 155.797504 -408.860244) (xy 157.561788 -408.860244)
			(xy 157.561788 -408.174444) (xy 157.56225 -408.162364) (xy 157.569705 -408.139383) (xy 157.583899 -408.119833)
			(xy 157.60344 -408.105627) (xy 157.626416 -408.098158) (xy 157.638496 -408.097736) (xy 157.83306 -408.097736)
			(xy 157.844165 -408.09811) (xy 157.865457 -408.104438) (xy 157.87497 -408.110182) (xy 158.168594 -408.302714)
			(xy 158.177953 -408.308391) (xy 158.198899 -408.31471) (xy 158.220778 -408.314786) (xy 158.241767 -408.308614)
			(xy 158.251144 -408.302968) (xy 158.251398 -408.302968) (xy 158.547562 -408.110182) (xy 158.557072 -408.104433)
			(xy 158.578366 -408.098108) (xy 158.589472 -408.097736) (xy 158.784036 -408.097736) (xy 158.796125 -408.098083)
			(xy 158.819116 -408.105565) (xy 158.83867 -408.119787) (xy 158.852871 -408.139355) (xy 158.86033 -408.162355)
			(xy 158.860744 -408.174444) (xy 158.860744 -408.860244) (xy 160.625028 -408.860244) (xy 160.625028 -408.174444)
			(xy 160.625451 -408.16236) (xy 160.63291 -408.139373) (xy 160.647113 -408.119818) (xy 160.666665 -408.105614)
			(xy 160.689652 -408.098152) (xy 160.701736 -408.097736) (xy 160.8963 -408.097736) (xy 160.907403 -408.098135)
			(xy 160.928695 -408.104446) (xy 160.93821 -408.110182) (xy 161.231834 -408.302714) (xy 161.241175 -408.308425)
			(xy 161.26213 -408.314736) (xy 161.284014 -408.314803) (xy 161.305007 -408.308619) (xy 161.314384 -408.302968)
			(xy 161.314638 -408.302968) (xy 161.610802 -408.110182) (xy 161.620304 -408.104418) (xy 161.641604 -408.098103)
			(xy 161.652712 -408.097736) (xy 161.847276 -408.097736) (xy 161.859362 -408.098134) (xy 161.882351 -408.1056)
			(xy 161.901906 -408.119809) (xy 161.916109 -408.139367) (xy 161.923569 -408.162358) (xy 161.923984 -408.174444)
			(xy 161.923984 -408.860244) (xy 161.923573 -408.872323) (xy 161.916096 -408.895296) (xy 161.901886 -408.914834)
			(xy 161.882335 -408.929027) (xy 161.859356 -408.936484) (xy 161.847276 -408.936952) (xy 161.652712 -408.936952)
			(xy 161.641605 -408.936571) (xy 161.620309 -408.930259) (xy 161.610802 -408.924506) (xy 161.315908 -408.731974)
			(xy 161.306555 -408.726274) (xy 161.28558 -408.72) (xy 161.263686 -408.72) (xy 161.242711 -408.726274)
			(xy 161.233358 -408.731974) (xy 161.233104 -408.731974) (xy 160.93948 -408.924506) (xy 160.929961 -408.930239)
			(xy 160.908674 -408.936574) (xy 160.89757 -408.936952) (xy 160.701736 -408.936952) (xy 160.689668 -408.936406)
			(xy 160.666709 -408.928959) (xy 160.647175 -408.914782) (xy 160.632978 -408.895263) (xy 160.625507 -408.872312)
			(xy 160.625028 -408.860244) (xy 158.860744 -408.860244) (xy 158.860274 -408.872317) (xy 158.852804 -408.89528)
			(xy 158.838607 -408.914813) (xy 158.819073 -408.929007) (xy 158.796109 -408.936475) (xy 158.784036 -408.936952)
			(xy 158.589472 -408.936952) (xy 158.578364 -408.936588) (xy 158.557068 -408.930264) (xy 158.547562 -408.924506)
			(xy 158.252668 -408.731974) (xy 158.243315 -408.726274) (xy 158.22234 -408.72) (xy 158.200446 -408.72)
			(xy 158.179471 -408.726274) (xy 158.170118 -408.731974) (xy 158.169864 -408.731974) (xy 157.87624 -408.924506)
			(xy 157.866729 -408.930253) (xy 157.845436 -408.936579) (xy 157.83433 -408.936952) (xy 157.638496 -408.936952)
			(xy 157.626426 -408.93644) (xy 157.603466 -408.928982) (xy 157.583933 -408.914796) (xy 157.569737 -408.89527)
			(xy 157.562267 -408.872314) (xy 157.561788 -408.860244) (xy 155.797504 -408.860244) (xy 155.797073 -408.872321)
			(xy 155.789598 -408.895291) (xy 155.775393 -408.914827) (xy 155.755848 -408.92902) (xy 155.732874 -408.936481)
			(xy 155.720796 -408.936952) (xy 155.526232 -408.936952) (xy 155.515123 -408.936604) (xy 155.493827 -408.930269)
			(xy 155.484322 -408.924506) (xy 155.189428 -408.731974) (xy 155.180075 -408.726274) (xy 155.1591 -408.72)
			(xy 155.137206 -408.72) (xy 155.116231 -408.726274) (xy 155.106878 -408.731974) (xy 155.106624 -408.731974)
			(xy 154.813 -408.924506) (xy 154.803497 -408.930268) (xy 154.782198 -408.936585) (xy 154.77109 -408.936952)
			(xy 154.575256 -408.936952) (xy 154.563184 -408.936474) (xy 154.540222 -408.929005) (xy 154.52069 -408.91481)
			(xy 154.506495 -408.895278) (xy 154.499026 -408.872316) (xy 154.498548 -408.860244) (xy 152.734264 -408.860244)
			(xy 152.733873 -408.872325) (xy 152.726393 -408.895301) (xy 152.712179 -408.914842) (xy 152.692622 -408.929033)
			(xy 152.669638 -408.936487) (xy 152.657556 -408.936952) (xy 152.462992 -408.936952) (xy 152.451885 -408.93658)
			(xy 152.430588 -408.930262) (xy 152.421082 -408.924506) (xy 152.126188 -408.731974) (xy 152.116801 -408.726271)
			(xy 152.095763 -408.719998) (xy 152.073809 -408.719998) (xy 152.052771 -408.726271) (xy 152.043384 -408.731974)
			(xy 151.74976 -408.924506) (xy 151.740245 -408.930246) (xy 151.718955 -408.936577) (xy 151.70785 -408.936952)
			(xy 151.512016 -408.936952) (xy 151.499947 -408.936423) (xy 151.476987 -408.92897) (xy 151.457454 -408.914789)
			(xy 151.443257 -408.895266) (xy 151.435787 -408.872313) (xy 151.435308 -408.860244) (xy 149.671024 -408.860244)
			(xy 149.670574 -408.872319) (xy 149.663101 -408.895285) (xy 149.6489 -408.91482) (xy 149.62936 -408.929014)
			(xy 149.606391 -408.936478) (xy 149.594316 -408.936952) (xy 149.399752 -408.936952) (xy 149.388643 -408.936596)
			(xy 149.367347 -408.930267) (xy 149.357842 -408.924506) (xy 149.062948 -408.731974) (xy 149.053561 -408.726271)
			(xy 149.032523 -408.719998) (xy 149.010569 -408.719998) (xy 148.989531 -408.726271) (xy 148.980144 -408.731974)
			(xy 148.68652 -408.924506) (xy 148.677013 -408.930261) (xy 148.655717 -408.936582) (xy 148.64461 -408.936952)
			(xy 148.448776 -408.936952) (xy 148.436705 -408.936457) (xy 148.413744 -408.928993) (xy 148.394211 -408.914803)
			(xy 148.380016 -408.895274) (xy 148.372546 -408.872315) (xy 148.372068 -408.860244) (xy 146.607784 -408.860244)
			(xy 146.607373 -408.872323) (xy 146.599896 -408.895296) (xy 146.585686 -408.914834) (xy 146.566135 -408.929027)
			(xy 146.543156 -408.936484) (xy 146.531076 -408.936952) (xy 146.336512 -408.936952) (xy 146.325405 -408.936571)
			(xy 146.304109 -408.930259) (xy 146.294602 -408.924506) (xy 145.999708 -408.731974) (xy 145.990321 -408.726271)
			(xy 145.969283 -408.719998) (xy 145.947329 -408.719998) (xy 145.926291 -408.726271) (xy 145.916904 -408.731974)
			(xy 145.62328 -408.924506) (xy 145.613761 -408.930239) (xy 145.592474 -408.936574) (xy 145.58137 -408.936952)
			(xy 145.385536 -408.936952) (xy 145.373468 -408.936406) (xy 145.350509 -408.928959) (xy 145.330975 -408.914782)
			(xy 145.316778 -408.895263) (xy 145.309307 -408.872312) (xy 145.308828 -408.860244) (xy 143.544544 -408.860244)
			(xy 143.544074 -408.872317) (xy 143.536604 -408.89528) (xy 143.522407 -408.914813) (xy 143.502873 -408.929007)
			(xy 143.479909 -408.936475) (xy 143.467836 -408.936952) (xy 143.273272 -408.936952) (xy 143.262164 -408.936588)
			(xy 143.240868 -408.930264) (xy 143.231362 -408.924506) (xy 142.936468 -408.731974) (xy 142.927081 -408.726271)
			(xy 142.906043 -408.719998) (xy 142.884089 -408.719998) (xy 142.863051 -408.726271) (xy 142.853664 -408.731974)
			(xy 142.56004 -408.924506) (xy 142.550529 -408.930253) (xy 142.529236 -408.936579) (xy 142.51813 -408.936952)
			(xy 142.322296 -408.936952) (xy 142.310226 -408.93644) (xy 142.287266 -408.928982) (xy 142.267733 -408.914796)
			(xy 142.253537 -408.89527) (xy 142.246067 -408.872314) (xy 142.245588 -408.860244) (xy 140.481304 -408.860244)
			(xy 140.480873 -408.872321) (xy 140.473398 -408.895291) (xy 140.459193 -408.914827) (xy 140.439648 -408.92902)
			(xy 140.416674 -408.936481) (xy 140.404596 -408.936952) (xy 140.210032 -408.936952) (xy 140.198923 -408.936604)
			(xy 140.177627 -408.930269) (xy 140.168122 -408.924506) (xy 139.873228 -408.731974) (xy 139.863841 -408.726271)
			(xy 139.842803 -408.719998) (xy 139.820849 -408.719998) (xy 139.799811 -408.726271) (xy 139.790424 -408.731974)
			(xy 139.4968 -408.924506) (xy 139.487297 -408.930268) (xy 139.465998 -408.936585) (xy 139.45489 -408.936952)
			(xy 139.259056 -408.936952) (xy 139.246984 -408.936474) (xy 139.224022 -408.929005) (xy 139.20449 -408.91481)
			(xy 139.190295 -408.895278) (xy 139.182826 -408.872316) (xy 139.182348 -408.860244) (xy 137.418064 -408.860244)
			(xy 137.417673 -408.872325) (xy 137.410193 -408.895301) (xy 137.395979 -408.914842) (xy 137.376422 -408.929033)
			(xy 137.353438 -408.936487) (xy 137.341356 -408.936952) (xy 137.146792 -408.936952) (xy 137.135685 -408.93658)
			(xy 137.114388 -408.930262) (xy 137.104882 -408.924506) (xy 136.809988 -408.731974) (xy 136.800601 -408.726271)
			(xy 136.779563 -408.719998) (xy 136.757609 -408.719998) (xy 136.736571 -408.726271) (xy 136.727184 -408.731974)
			(xy 136.43356 -408.924506) (xy 136.424045 -408.930246) (xy 136.402755 -408.936577) (xy 136.39165 -408.936952)
			(xy 136.195816 -408.936952) (xy 136.183747 -408.936423) (xy 136.160787 -408.92897) (xy 136.141254 -408.914789)
			(xy 136.127057 -408.895266) (xy 136.119587 -408.872313) (xy 136.119108 -408.860244) (xy 134.354824 -408.860244)
			(xy 134.354374 -408.872319) (xy 134.346901 -408.895285) (xy 134.3327 -408.91482) (xy 134.31316 -408.929014)
			(xy 134.290191 -408.936478) (xy 134.278116 -408.936952) (xy 134.083552 -408.936952) (xy 134.072443 -408.936596)
			(xy 134.051147 -408.930267) (xy 134.041642 -408.924506) (xy 133.746748 -408.731974) (xy 133.737361 -408.726271)
			(xy 133.716323 -408.719998) (xy 133.694369 -408.719998) (xy 133.673331 -408.726271) (xy 133.663944 -408.731974)
			(xy 133.37032 -408.924506) (xy 133.360813 -408.930261) (xy 133.339517 -408.936582) (xy 133.32841 -408.936952)
			(xy 133.132576 -408.936952) (xy 133.120505 -408.936457) (xy 133.097544 -408.928993) (xy 133.078011 -408.914803)
			(xy 133.063816 -408.895274) (xy 133.056346 -408.872315) (xy 133.055868 -408.860244) (xy 131.291584 -408.860244)
			(xy 131.291173 -408.872323) (xy 131.283696 -408.895296) (xy 131.269486 -408.914834) (xy 131.249935 -408.929027)
			(xy 131.226956 -408.936484) (xy 131.214876 -408.936952) (xy 131.020312 -408.936952) (xy 131.009205 -408.936571)
			(xy 130.987909 -408.930259) (xy 130.978402 -408.924506) (xy 130.683508 -408.731974) (xy 130.674121 -408.726271)
			(xy 130.653083 -408.719998) (xy 130.631129 -408.719998) (xy 130.610091 -408.726271) (xy 130.600704 -408.731974)
			(xy 130.30708 -408.924506) (xy 130.297561 -408.930239) (xy 130.276274 -408.936574) (xy 130.26517 -408.936952)
			(xy 130.069336 -408.936952) (xy 130.057268 -408.936406) (xy 130.034309 -408.928959) (xy 130.014775 -408.914782)
			(xy 130.000578 -408.895263) (xy 129.993107 -408.872312) (xy 129.992628 -408.860244) (xy 128.228344 -408.860244)
			(xy 128.227874 -408.872317) (xy 128.220404 -408.89528) (xy 128.206207 -408.914813) (xy 128.186673 -408.929007)
			(xy 128.163709 -408.936475) (xy 128.151636 -408.936952) (xy 127.957072 -408.936952) (xy 127.945964 -408.936588)
			(xy 127.924668 -408.930264) (xy 127.915162 -408.924506) (xy 127.620268 -408.731974) (xy 127.610881 -408.726271)
			(xy 127.589843 -408.719998) (xy 127.567889 -408.719998) (xy 127.546851 -408.726271) (xy 127.537464 -408.731974)
			(xy 127.24384 -408.924506) (xy 127.234329 -408.930253) (xy 127.213036 -408.936579) (xy 127.20193 -408.936952)
			(xy 127.006096 -408.936952) (xy 126.994026 -408.93644) (xy 126.971066 -408.928982) (xy 126.951533 -408.914796)
			(xy 126.937337 -408.89527) (xy 126.929867 -408.872314) (xy 126.929388 -408.860244) (xy 125.165104 -408.860244)
			(xy 125.164673 -408.872321) (xy 125.157198 -408.895291) (xy 125.142993 -408.914827) (xy 125.123448 -408.92902)
			(xy 125.100474 -408.936481) (xy 125.088396 -408.936952) (xy 124.893832 -408.936952) (xy 124.882723 -408.936604)
			(xy 124.861427 -408.930269) (xy 124.851922 -408.924506) (xy 124.557028 -408.731974) (xy 124.547641 -408.726271)
			(xy 124.526603 -408.719998) (xy 124.504649 -408.719998) (xy 124.483611 -408.726271) (xy 124.474224 -408.731974)
			(xy 124.1806 -408.924506) (xy 124.171097 -408.930268) (xy 124.149798 -408.936585) (xy 124.13869 -408.936952)
			(xy 123.942856 -408.936952) (xy 123.930784 -408.936474) (xy 123.907822 -408.929005) (xy 123.88829 -408.91481)
			(xy 123.874095 -408.895278) (xy 123.866626 -408.872316) (xy 123.866148 -408.860244) (xy 122.101864 -408.860244)
			(xy 122.101473 -408.872325) (xy 122.093993 -408.895301) (xy 122.079779 -408.914842) (xy 122.060222 -408.929033)
			(xy 122.037238 -408.936487) (xy 122.025156 -408.936952) (xy 121.830592 -408.936952) (xy 121.819485 -408.93658)
			(xy 121.798188 -408.930262) (xy 121.788682 -408.924506) (xy 121.493788 -408.731974) (xy 121.484401 -408.726271)
			(xy 121.463363 -408.719998) (xy 121.441409 -408.719998) (xy 121.420371 -408.726271) (xy 121.410984 -408.731974)
			(xy 121.11736 -408.924506) (xy 121.107845 -408.930246) (xy 121.086555 -408.936577) (xy 121.07545 -408.936952)
			(xy 120.879616 -408.936952) (xy 120.867547 -408.936423) (xy 120.844587 -408.92897) (xy 120.825054 -408.914789)
			(xy 120.810857 -408.895266) (xy 120.803387 -408.872313) (xy 120.802908 -408.860244) (xy 119.038624 -408.860244)
			(xy 119.038174 -408.872319) (xy 119.030701 -408.895285) (xy 119.0165 -408.91482) (xy 118.99696 -408.929014)
			(xy 118.973991 -408.936478) (xy 118.961916 -408.936952) (xy 118.767352 -408.936952) (xy 118.756243 -408.936596)
			(xy 118.734947 -408.930267) (xy 118.725442 -408.924506) (xy 118.430548 -408.731974) (xy 118.421161 -408.726271)
			(xy 118.400123 -408.719998) (xy 118.378169 -408.719998) (xy 118.357131 -408.726271) (xy 118.347744 -408.731974)
			(xy 118.05412 -408.924506) (xy 118.044613 -408.930261) (xy 118.023317 -408.936582) (xy 118.01221 -408.936952)
			(xy 117.816376 -408.936952) (xy 117.804305 -408.936457) (xy 117.781344 -408.928993) (xy 117.761811 -408.914803)
			(xy 117.747616 -408.895274) (xy 117.740146 -408.872315) (xy 117.739668 -408.860244) (xy 115.975384 -408.860244)
			(xy 115.974973 -408.872323) (xy 115.967496 -408.895296) (xy 115.953286 -408.914834) (xy 115.933735 -408.929027)
			(xy 115.910756 -408.936484) (xy 115.898676 -408.936952) (xy 115.704112 -408.936952) (xy 115.693005 -408.936571)
			(xy 115.671709 -408.930259) (xy 115.662202 -408.924506) (xy 115.367308 -408.731974) (xy 115.357921 -408.726271)
			(xy 115.336883 -408.719998) (xy 115.314929 -408.719998) (xy 115.293891 -408.726271) (xy 115.284504 -408.731974)
			(xy 114.99088 -408.924506) (xy 114.981361 -408.930239) (xy 114.960074 -408.936574) (xy 114.94897 -408.936952)
			(xy 114.753136 -408.936952) (xy 114.741068 -408.936406) (xy 114.718109 -408.928959) (xy 114.698575 -408.914782)
			(xy 114.684378 -408.895263) (xy 114.676907 -408.872312) (xy 114.676428 -408.860244) (xy 111.277852 -408.860244)
			(xy 111.299015 -408.906582) (xy 111.31437 -408.958877) (xy 111.322126 -409.012825) (xy 111.322612 -409.040076)
			(xy 111.322612 -409.903676) (xy 111.322126 -409.930927) (xy 111.31437 -409.984875) (xy 111.299015 -410.03717)
			(xy 111.28975 -410.057456) (xy 116.044623 -410.057456) (xy 116.044623 -410.002944) (xy 116.052381 -409.948986)
			(xy 116.06774 -409.896681) (xy 116.090386 -409.847095) (xy 116.119859 -409.801237) (xy 116.155559 -409.76004)
			(xy 116.196758 -409.724344) (xy 116.242618 -409.694874) (xy 116.292206 -409.672231) (xy 116.344511 -409.656876)
			(xy 116.39847 -409.649121) (xy 116.425726 -409.64866) (xy 117.289326 -409.64866) (xy 117.316574 -409.649212)
			(xy 117.370514 -409.656971) (xy 117.422801 -409.672327) (xy 117.472371 -409.694968) (xy 117.518214 -409.724432)
			(xy 117.559398 -409.760121) (xy 117.595084 -409.801307) (xy 117.624545 -409.847152) (xy 117.647182 -409.896723)
			(xy 117.662535 -409.949011) (xy 117.67029 -410.002952) (xy 117.67029 -410.057448) (xy 117.670289 -410.057452)
			(xy 119.107946 -410.057452) (xy 119.107946 -410.002948) (xy 119.115702 -409.948999) (xy 119.131057 -409.896702)
			(xy 119.153697 -409.847123) (xy 119.183163 -409.801271) (xy 119.218854 -409.760078) (xy 119.260043 -409.724383)
			(xy 119.305893 -409.694914) (xy 119.35547 -409.672269) (xy 119.407765 -409.656909) (xy 119.461714 -409.649148)
			(xy 119.488966 -409.64866) (xy 120.352566 -409.64866) (xy 120.379818 -409.649185) (xy 120.433768 -409.656937)
			(xy 120.486066 -409.672289) (xy 120.535646 -409.694928) (xy 120.5815 -409.724392) (xy 120.622693 -409.760083)
			(xy 120.658387 -409.801273) (xy 120.687856 -409.847124) (xy 120.710499 -409.896702) (xy 120.725855 -409.948999)
			(xy 120.733613 -410.002948) (xy 120.733613 -410.057452) (xy 120.733613 -410.057455) (xy 122.171123 -410.057455)
			(xy 122.171123 -410.002945) (xy 122.178881 -409.948989) (xy 122.194238 -409.896686) (xy 122.216883 -409.847101)
			(xy 122.246354 -409.801244) (xy 122.282052 -409.760047) (xy 122.323249 -409.724351) (xy 122.369106 -409.69488)
			(xy 122.418691 -409.672236) (xy 122.470994 -409.656879) (xy 122.524951 -409.649123) (xy 122.552206 -409.64866)
			(xy 123.415806 -409.64866) (xy 123.443055 -409.649211) (xy 123.496997 -409.656967) (xy 123.549287 -409.672321)
			(xy 123.598859 -409.694961) (xy 123.644705 -409.724425) (xy 123.685891 -409.760113) (xy 123.721579 -409.8013)
			(xy 123.751042 -409.847146) (xy 123.773681 -409.896719) (xy 123.789034 -409.949009) (xy 123.79679 -410.002951)
			(xy 123.79679 -410.057449) (xy 123.796789 -410.057457) (xy 125.234323 -410.057457) (xy 125.234323 -410.002943)
			(xy 125.242082 -409.948983) (xy 125.257442 -409.896677) (xy 125.280089 -409.84709) (xy 125.309564 -409.801231)
			(xy 125.345266 -409.760033) (xy 125.386467 -409.724337) (xy 125.43233 -409.694867) (xy 125.48192 -409.672225)
			(xy 125.534228 -409.656872) (xy 125.588189 -409.64912) (xy 125.615446 -409.64866) (xy 126.479046 -409.64866)
			(xy 126.506293 -409.649213) (xy 126.560231 -409.656975) (xy 126.612516 -409.672332) (xy 126.662083 -409.694974)
			(xy 126.707924 -409.724439) (xy 126.749105 -409.760128) (xy 126.784788 -409.801313) (xy 126.814248 -409.847157)
			(xy 126.836884 -409.896727) (xy 126.852235 -409.949014) (xy 126.85999 -410.002953) (xy 126.85999 -410.057447)
			(xy 126.859989 -410.057453) (xy 128.297646 -410.057453) (xy 128.297646 -410.002947) (xy 128.305403 -409.948996)
			(xy 128.320758 -409.896698) (xy 128.3434 -409.847118) (xy 128.372868 -409.801264) (xy 128.408561 -409.760071)
			(xy 128.449753 -409.724376) (xy 128.495605 -409.694907) (xy 128.545185 -409.672263) (xy 128.597482 -409.656906)
			(xy 128.651433 -409.649147) (xy 128.678686 -409.64866) (xy 129.542286 -409.64866) (xy 129.569537 -409.649186)
			(xy 129.623485 -409.656941) (xy 129.67578 -409.672295) (xy 129.725358 -409.694934) (xy 129.771209 -409.724399)
			(xy 129.8124 -409.76009) (xy 129.848092 -409.80128) (xy 129.877559 -409.84713) (xy 129.900201 -409.896707)
			(xy 129.915556 -409.949001) (xy 129.923313 -410.002949) (xy 129.923313 -410.057451) (xy 129.923312 -410.057456)
			(xy 131.360823 -410.057456) (xy 131.360823 -410.002944) (xy 131.368581 -409.948986) (xy 131.38394 -409.896681)
			(xy 131.406586 -409.847095) (xy 131.436059 -409.801237) (xy 131.471759 -409.76004) (xy 131.512958 -409.724344)
			(xy 131.558818 -409.694874) (xy 131.608406 -409.672231) (xy 131.660711 -409.656876) (xy 131.71467 -409.649121)
			(xy 131.741926 -409.64866) (xy 132.605526 -409.64866) (xy 132.632774 -409.649212) (xy 132.686714 -409.656971)
			(xy 132.739001 -409.672327) (xy 132.788571 -409.694968) (xy 132.834414 -409.724432) (xy 132.875598 -409.760121)
			(xy 132.911284 -409.801307) (xy 132.940745 -409.847152) (xy 132.963382 -409.896723) (xy 132.978735 -409.949011)
			(xy 132.98649 -410.002952) (xy 132.98649 -410.057448) (xy 132.986489 -410.057452) (xy 134.424146 -410.057452)
			(xy 134.424146 -410.002948) (xy 134.431902 -409.948999) (xy 134.447257 -409.896702) (xy 134.469897 -409.847123)
			(xy 134.499363 -409.801271) (xy 134.535054 -409.760078) (xy 134.576243 -409.724383) (xy 134.622093 -409.694914)
			(xy 134.67167 -409.672269) (xy 134.723965 -409.656909) (xy 134.777914 -409.649148) (xy 134.805166 -409.64866)
			(xy 135.668766 -409.64866) (xy 135.696018 -409.649185) (xy 135.749968 -409.656937) (xy 135.802266 -409.672289)
			(xy 135.851846 -409.694928) (xy 135.8977 -409.724392) (xy 135.938893 -409.760083) (xy 135.974587 -409.801273)
			(xy 136.004056 -409.847124) (xy 136.026699 -409.896702) (xy 136.042055 -409.948999) (xy 136.049813 -410.002948)
			(xy 136.049813 -410.057452) (xy 136.049813 -410.057455) (xy 137.487323 -410.057455) (xy 137.487323 -410.002945)
			(xy 137.495081 -409.948989) (xy 137.510438 -409.896686) (xy 137.533083 -409.847101) (xy 137.562554 -409.801244)
			(xy 137.598252 -409.760047) (xy 137.639449 -409.724351) (xy 137.685306 -409.69488) (xy 137.734891 -409.672236)
			(xy 137.787194 -409.656879) (xy 137.841151 -409.649123) (xy 137.868406 -409.64866) (xy 138.732006 -409.64866)
			(xy 138.759255 -409.649211) (xy 138.813197 -409.656967) (xy 138.865487 -409.672321) (xy 138.915059 -409.694961)
			(xy 138.960905 -409.724425) (xy 139.002091 -409.760113) (xy 139.037779 -409.8013) (xy 139.067242 -409.847146)
			(xy 139.089881 -409.896719) (xy 139.105234 -409.949009) (xy 139.11299 -410.002951) (xy 139.11299 -410.057449)
			(xy 139.112989 -410.057457) (xy 140.550523 -410.057457) (xy 140.550523 -410.002943) (xy 140.558282 -409.948983)
			(xy 140.573642 -409.896677) (xy 140.596289 -409.84709) (xy 140.625764 -409.801231) (xy 140.661466 -409.760033)
			(xy 140.702667 -409.724337) (xy 140.74853 -409.694867) (xy 140.79812 -409.672225) (xy 140.850428 -409.656872)
			(xy 140.904389 -409.64912) (xy 140.931646 -409.64866) (xy 141.795246 -409.64866) (xy 141.822493 -409.649213)
			(xy 141.876431 -409.656975) (xy 141.928716 -409.672332) (xy 141.978283 -409.694974) (xy 142.024124 -409.724439)
			(xy 142.065305 -409.760128) (xy 142.100988 -409.801313) (xy 142.130448 -409.847157) (xy 142.153084 -409.896727)
			(xy 142.168435 -409.949014) (xy 142.17619 -410.002953) (xy 142.17619 -410.057447) (xy 142.176189 -410.057453)
			(xy 143.613846 -410.057453) (xy 143.613846 -410.002947) (xy 143.621603 -409.948996) (xy 143.636958 -409.896698)
			(xy 143.6596 -409.847118) (xy 143.689068 -409.801264) (xy 143.724761 -409.760071) (xy 143.765953 -409.724376)
			(xy 143.811805 -409.694907) (xy 143.861385 -409.672263) (xy 143.913682 -409.656906) (xy 143.967633 -409.649147)
			(xy 143.994886 -409.64866) (xy 144.858486 -409.64866) (xy 144.885737 -409.649186) (xy 144.939685 -409.656941)
			(xy 144.99198 -409.672295) (xy 145.041558 -409.694934) (xy 145.087409 -409.724399) (xy 145.1286 -409.76009)
			(xy 145.164292 -409.80128) (xy 145.193759 -409.84713) (xy 145.216401 -409.896707) (xy 145.231756 -409.949001)
			(xy 145.239513 -410.002949) (xy 145.239513 -410.057451) (xy 145.239512 -410.057456) (xy 146.677023 -410.057456)
			(xy 146.677023 -410.002944) (xy 146.684781 -409.948986) (xy 146.70014 -409.896681) (xy 146.722786 -409.847095)
			(xy 146.752259 -409.801237) (xy 146.787959 -409.76004) (xy 146.829158 -409.724344) (xy 146.875018 -409.694874)
			(xy 146.924606 -409.672231) (xy 146.976911 -409.656876) (xy 147.03087 -409.649121) (xy 147.058126 -409.64866)
			(xy 147.921726 -409.64866) (xy 147.948974 -409.649212) (xy 148.002914 -409.656971) (xy 148.055201 -409.672327)
			(xy 148.104771 -409.694968) (xy 148.150614 -409.724432) (xy 148.191798 -409.760121) (xy 148.227484 -409.801307)
			(xy 148.256945 -409.847152) (xy 148.279582 -409.896723) (xy 148.294935 -409.949011) (xy 148.30269 -410.002952)
			(xy 148.30269 -410.057448) (xy 148.302689 -410.057452) (xy 149.740346 -410.057452) (xy 149.740346 -410.002948)
			(xy 149.748102 -409.948999) (xy 149.763457 -409.896702) (xy 149.786097 -409.847123) (xy 149.815563 -409.801271)
			(xy 149.851254 -409.760078) (xy 149.892443 -409.724383) (xy 149.938293 -409.694914) (xy 149.98787 -409.672269)
			(xy 150.040165 -409.656909) (xy 150.094114 -409.649148) (xy 150.121366 -409.64866) (xy 150.984966 -409.64866)
			(xy 151.012218 -409.649185) (xy 151.066168 -409.656937) (xy 151.118466 -409.672289) (xy 151.168046 -409.694928)
			(xy 151.2139 -409.724392) (xy 151.255093 -409.760083) (xy 151.290787 -409.801273) (xy 151.320256 -409.847124)
			(xy 151.342899 -409.896702) (xy 151.358255 -409.948999) (xy 151.366013 -410.002948) (xy 151.366013 -410.057452)
			(xy 151.366013 -410.057455) (xy 152.803523 -410.057455) (xy 152.803523 -410.002945) (xy 152.811281 -409.948989)
			(xy 152.826638 -409.896686) (xy 152.849283 -409.847101) (xy 152.878754 -409.801244) (xy 152.914452 -409.760047)
			(xy 152.955649 -409.724351) (xy 153.001506 -409.69488) (xy 153.051091 -409.672236) (xy 153.103394 -409.656879)
			(xy 153.157351 -409.649123) (xy 153.184606 -409.64866) (xy 154.048206 -409.64866) (xy 154.075455 -409.649211)
			(xy 154.129397 -409.656967) (xy 154.181687 -409.672321) (xy 154.231259 -409.694961) (xy 154.277105 -409.724425)
			(xy 154.318291 -409.760113) (xy 154.353979 -409.8013) (xy 154.383442 -409.847146) (xy 154.406081 -409.896719)
			(xy 154.421434 -409.949009) (xy 154.42919 -410.002951) (xy 154.42919 -410.057449) (xy 154.429189 -410.057457)
			(xy 155.866723 -410.057457) (xy 155.866723 -410.002943) (xy 155.874482 -409.948983) (xy 155.889842 -409.896677)
			(xy 155.912489 -409.84709) (xy 155.941964 -409.801231) (xy 155.977666 -409.760033) (xy 156.018867 -409.724337)
			(xy 156.06473 -409.694867) (xy 156.11432 -409.672225) (xy 156.166628 -409.656872) (xy 156.220589 -409.64912)
			(xy 156.247846 -409.64866) (xy 157.111446 -409.64866) (xy 157.138693 -409.649213) (xy 157.192631 -409.656975)
			(xy 157.244916 -409.672332) (xy 157.294483 -409.694974) (xy 157.340324 -409.724439) (xy 157.381505 -409.760128)
			(xy 157.417188 -409.801313) (xy 157.446648 -409.847157) (xy 157.469284 -409.896727) (xy 157.484635 -409.949014)
			(xy 157.49239 -410.002953) (xy 157.49239 -410.057447) (xy 157.492389 -410.057453) (xy 158.930046 -410.057453)
			(xy 158.930046 -410.002947) (xy 158.937803 -409.948996) (xy 158.953158 -409.896698) (xy 158.9758 -409.847118)
			(xy 159.005268 -409.801264) (xy 159.040961 -409.760071) (xy 159.082153 -409.724376) (xy 159.128005 -409.694907)
			(xy 159.177585 -409.672263) (xy 159.229882 -409.656906) (xy 159.283833 -409.649147) (xy 159.311086 -409.64866)
			(xy 160.174686 -409.64866) (xy 160.201937 -409.649186) (xy 160.255885 -409.656941) (xy 160.30818 -409.672295)
			(xy 160.357758 -409.694934) (xy 160.403609 -409.724399) (xy 160.4448 -409.76009) (xy 160.480492 -409.80128)
			(xy 160.509959 -409.84713) (xy 160.532601 -409.896707) (xy 160.547956 -409.949001) (xy 160.555713 -410.002949)
			(xy 160.555713 -410.057451) (xy 160.555712 -410.057456) (xy 161.993223 -410.057456) (xy 161.993223 -410.002944)
			(xy 162.000981 -409.948986) (xy 162.01634 -409.896681) (xy 162.038986 -409.847095) (xy 162.068459 -409.801237)
			(xy 162.104159 -409.76004) (xy 162.145358 -409.724344) (xy 162.191218 -409.694874) (xy 162.240806 -409.672231)
			(xy 162.293111 -409.656876) (xy 162.34707 -409.649121) (xy 162.374326 -409.64866) (xy 163.237926 -409.64866)
			(xy 163.265174 -409.649212) (xy 163.319114 -409.656971) (xy 163.371401 -409.672327) (xy 163.420971 -409.694968)
			(xy 163.466814 -409.724432) (xy 163.507998 -409.760121) (xy 163.543684 -409.801307) (xy 163.573145 -409.847152)
			(xy 163.595782 -409.896723) (xy 163.611135 -409.949011) (xy 163.61889 -410.002952) (xy 163.61889 -410.057448)
			(xy 163.611135 -410.111389) (xy 163.595782 -410.163677) (xy 163.573145 -410.213248) (xy 163.543684 -410.259093)
			(xy 163.507998 -410.300279) (xy 163.466814 -410.335968) (xy 163.420971 -410.365432) (xy 163.371401 -410.388073)
			(xy 163.319114 -410.403429) (xy 163.265174 -410.411188) (xy 163.237926 -410.411676) (xy 162.374326 -410.411676)
			(xy 162.34707 -410.411279) (xy 162.293111 -410.403524) (xy 162.240806 -410.388169) (xy 162.191218 -410.365526)
			(xy 162.145358 -410.336056) (xy 162.104159 -410.30036) (xy 162.068459 -410.259163) (xy 162.038986 -410.213305)
			(xy 162.01634 -410.163719) (xy 162.000981 -410.111414) (xy 161.993223 -410.057456) (xy 160.555712 -410.057456)
			(xy 160.547956 -410.111399) (xy 160.532601 -410.163693) (xy 160.509959 -410.21327) (xy 160.480492 -410.25912)
			(xy 160.4448 -410.30031) (xy 160.403609 -410.336001) (xy 160.357758 -410.365466) (xy 160.30818 -410.388105)
			(xy 160.255885 -410.403459) (xy 160.201937 -410.411214) (xy 160.174686 -410.411676) (xy 159.311086 -410.411676)
			(xy 159.283833 -410.411253) (xy 159.229882 -410.403494) (xy 159.177585 -410.388137) (xy 159.128005 -410.365493)
			(xy 159.082153 -410.336024) (xy 159.040961 -410.300329) (xy 159.005268 -410.259136) (xy 158.9758 -410.213282)
			(xy 158.953158 -410.163702) (xy 158.937803 -410.111404) (xy 158.930046 -410.057453) (xy 157.492389 -410.057453)
			(xy 157.484635 -410.111386) (xy 157.469284 -410.163673) (xy 157.446648 -410.213243) (xy 157.417188 -410.259087)
			(xy 157.381505 -410.300272) (xy 157.340324 -410.335961) (xy 157.294483 -410.365426) (xy 157.244916 -410.388068)
			(xy 157.192631 -410.403425) (xy 157.138693 -410.411187) (xy 157.111446 -410.411676) (xy 156.247846 -410.411676)
			(xy 156.220589 -410.41128) (xy 156.166628 -410.403528) (xy 156.11432 -410.388175) (xy 156.06473 -410.365533)
			(xy 156.018867 -410.336063) (xy 155.977666 -410.300367) (xy 155.941964 -410.259169) (xy 155.912489 -410.21331)
			(xy 155.889842 -410.163723) (xy 155.874482 -410.111417) (xy 155.866723 -410.057457) (xy 154.429189 -410.057457)
			(xy 154.421434 -410.111391) (xy 154.406081 -410.163681) (xy 154.383442 -410.213254) (xy 154.353979 -410.2591)
			(xy 154.318291 -410.300287) (xy 154.277105 -410.335975) (xy 154.231259 -410.365439) (xy 154.181687 -410.388079)
			(xy 154.129397 -410.403433) (xy 154.075455 -410.411189) (xy 154.048206 -410.411676) (xy 153.184606 -410.411676)
			(xy 153.157351 -410.411277) (xy 153.103394 -410.403521) (xy 153.051091 -410.388164) (xy 153.001506 -410.36552)
			(xy 152.955649 -410.336049) (xy 152.914452 -410.300353) (xy 152.878754 -410.259156) (xy 152.849283 -410.213299)
			(xy 152.826638 -410.163714) (xy 152.811281 -410.111411) (xy 152.803523 -410.057455) (xy 151.366013 -410.057455)
			(xy 151.358255 -410.111402) (xy 151.342899 -410.163698) (xy 151.320256 -410.213276) (xy 151.290787 -410.259127)
			(xy 151.255093 -410.300317) (xy 151.2139 -410.336008) (xy 151.168046 -410.365472) (xy 151.118466 -410.388111)
			(xy 151.066168 -410.403463) (xy 151.012218 -410.411215) (xy 150.984966 -410.411676) (xy 150.121366 -410.411676)
			(xy 150.094114 -410.411252) (xy 150.040165 -410.403491) (xy 149.98787 -410.388131) (xy 149.938293 -410.365486)
			(xy 149.892443 -410.336017) (xy 149.851254 -410.300322) (xy 149.815563 -410.259129) (xy 149.786097 -410.213277)
			(xy 149.763457 -410.163698) (xy 149.748102 -410.111401) (xy 149.740346 -410.057452) (xy 148.302689 -410.057452)
			(xy 148.294935 -410.111389) (xy 148.279582 -410.163677) (xy 148.256945 -410.213248) (xy 148.227484 -410.259093)
			(xy 148.191798 -410.300279) (xy 148.150614 -410.335968) (xy 148.104771 -410.365432) (xy 148.055201 -410.388073)
			(xy 148.002914 -410.403429) (xy 147.948974 -410.411188) (xy 147.921726 -410.411676) (xy 147.058126 -410.411676)
			(xy 147.03087 -410.411279) (xy 146.976911 -410.403524) (xy 146.924606 -410.388169) (xy 146.875018 -410.365526)
			(xy 146.829158 -410.336056) (xy 146.787959 -410.30036) (xy 146.752259 -410.259163) (xy 146.722786 -410.213305)
			(xy 146.70014 -410.163719) (xy 146.684781 -410.111414) (xy 146.677023 -410.057456) (xy 145.239512 -410.057456)
			(xy 145.231756 -410.111399) (xy 145.216401 -410.163693) (xy 145.193759 -410.21327) (xy 145.164292 -410.25912)
			(xy 145.1286 -410.30031) (xy 145.087409 -410.336001) (xy 145.041558 -410.365466) (xy 144.99198 -410.388105)
			(xy 144.939685 -410.403459) (xy 144.885737 -410.411214) (xy 144.858486 -410.411676) (xy 143.994886 -410.411676)
			(xy 143.967633 -410.411253) (xy 143.913682 -410.403494) (xy 143.861385 -410.388137) (xy 143.811805 -410.365493)
			(xy 143.765953 -410.336024) (xy 143.724761 -410.300329) (xy 143.689068 -410.259136) (xy 143.6596 -410.213282)
			(xy 143.636958 -410.163702) (xy 143.621603 -410.111404) (xy 143.613846 -410.057453) (xy 142.176189 -410.057453)
			(xy 142.168435 -410.111386) (xy 142.153084 -410.163673) (xy 142.130448 -410.213243) (xy 142.100988 -410.259087)
			(xy 142.065305 -410.300272) (xy 142.024124 -410.335961) (xy 141.978283 -410.365426) (xy 141.928716 -410.388068)
			(xy 141.876431 -410.403425) (xy 141.822493 -410.411187) (xy 141.795246 -410.411676) (xy 140.931646 -410.411676)
			(xy 140.904389 -410.41128) (xy 140.850428 -410.403528) (xy 140.79812 -410.388175) (xy 140.74853 -410.365533)
			(xy 140.702667 -410.336063) (xy 140.661466 -410.300367) (xy 140.625764 -410.259169) (xy 140.596289 -410.21331)
			(xy 140.573642 -410.163723) (xy 140.558282 -410.111417) (xy 140.550523 -410.057457) (xy 139.112989 -410.057457)
			(xy 139.105234 -410.111391) (xy 139.089881 -410.163681) (xy 139.067242 -410.213254) (xy 139.037779 -410.2591)
			(xy 139.002091 -410.300287) (xy 138.960905 -410.335975) (xy 138.915059 -410.365439) (xy 138.865487 -410.388079)
			(xy 138.813197 -410.403433) (xy 138.759255 -410.411189) (xy 138.732006 -410.411676) (xy 137.868406 -410.411676)
			(xy 137.841151 -410.411277) (xy 137.787194 -410.403521) (xy 137.734891 -410.388164) (xy 137.685306 -410.36552)
			(xy 137.639449 -410.336049) (xy 137.598252 -410.300353) (xy 137.562554 -410.259156) (xy 137.533083 -410.213299)
			(xy 137.510438 -410.163714) (xy 137.495081 -410.111411) (xy 137.487323 -410.057455) (xy 136.049813 -410.057455)
			(xy 136.042055 -410.111402) (xy 136.026699 -410.163698) (xy 136.004056 -410.213276) (xy 135.974587 -410.259127)
			(xy 135.938893 -410.300317) (xy 135.8977 -410.336008) (xy 135.851846 -410.365472) (xy 135.802266 -410.388111)
			(xy 135.749968 -410.403463) (xy 135.696018 -410.411215) (xy 135.668766 -410.411676) (xy 134.805166 -410.411676)
			(xy 134.777914 -410.411252) (xy 134.723965 -410.403491) (xy 134.67167 -410.388131) (xy 134.622093 -410.365486)
			(xy 134.576243 -410.336017) (xy 134.535054 -410.300322) (xy 134.499363 -410.259129) (xy 134.469897 -410.213277)
			(xy 134.447257 -410.163698) (xy 134.431902 -410.111401) (xy 134.424146 -410.057452) (xy 132.986489 -410.057452)
			(xy 132.978735 -410.111389) (xy 132.963382 -410.163677) (xy 132.940745 -410.213248) (xy 132.911284 -410.259093)
			(xy 132.875598 -410.300279) (xy 132.834414 -410.335968) (xy 132.788571 -410.365432) (xy 132.739001 -410.388073)
			(xy 132.686714 -410.403429) (xy 132.632774 -410.411188) (xy 132.605526 -410.411676) (xy 131.741926 -410.411676)
			(xy 131.71467 -410.411279) (xy 131.660711 -410.403524) (xy 131.608406 -410.388169) (xy 131.558818 -410.365526)
			(xy 131.512958 -410.336056) (xy 131.471759 -410.30036) (xy 131.436059 -410.259163) (xy 131.406586 -410.213305)
			(xy 131.38394 -410.163719) (xy 131.368581 -410.111414) (xy 131.360823 -410.057456) (xy 129.923312 -410.057456)
			(xy 129.915556 -410.111399) (xy 129.900201 -410.163693) (xy 129.877559 -410.21327) (xy 129.848092 -410.25912)
			(xy 129.8124 -410.30031) (xy 129.771209 -410.336001) (xy 129.725358 -410.365466) (xy 129.67578 -410.388105)
			(xy 129.623485 -410.403459) (xy 129.569537 -410.411214) (xy 129.542286 -410.411676) (xy 128.678686 -410.411676)
			(xy 128.651433 -410.411253) (xy 128.597482 -410.403494) (xy 128.545185 -410.388137) (xy 128.495605 -410.365493)
			(xy 128.449753 -410.336024) (xy 128.408561 -410.300329) (xy 128.372868 -410.259136) (xy 128.3434 -410.213282)
			(xy 128.320758 -410.163702) (xy 128.305403 -410.111404) (xy 128.297646 -410.057453) (xy 126.859989 -410.057453)
			(xy 126.852235 -410.111386) (xy 126.836884 -410.163673) (xy 126.814248 -410.213243) (xy 126.784788 -410.259087)
			(xy 126.749105 -410.300272) (xy 126.707924 -410.335961) (xy 126.662083 -410.365426) (xy 126.612516 -410.388068)
			(xy 126.560231 -410.403425) (xy 126.506293 -410.411187) (xy 126.479046 -410.411676) (xy 125.615446 -410.411676)
			(xy 125.588189 -410.41128) (xy 125.534228 -410.403528) (xy 125.48192 -410.388175) (xy 125.43233 -410.365533)
			(xy 125.386467 -410.336063) (xy 125.345266 -410.300367) (xy 125.309564 -410.259169) (xy 125.280089 -410.21331)
			(xy 125.257442 -410.163723) (xy 125.242082 -410.111417) (xy 125.234323 -410.057457) (xy 123.796789 -410.057457)
			(xy 123.789034 -410.111391) (xy 123.773681 -410.163681) (xy 123.751042 -410.213254) (xy 123.721579 -410.2591)
			(xy 123.685891 -410.300287) (xy 123.644705 -410.335975) (xy 123.598859 -410.365439) (xy 123.549287 -410.388079)
			(xy 123.496997 -410.403433) (xy 123.443055 -410.411189) (xy 123.415806 -410.411676) (xy 122.552206 -410.411676)
			(xy 122.524951 -410.411277) (xy 122.470994 -410.403521) (xy 122.418691 -410.388164) (xy 122.369106 -410.36552)
			(xy 122.323249 -410.336049) (xy 122.282052 -410.300353) (xy 122.246354 -410.259156) (xy 122.216883 -410.213299)
			(xy 122.194238 -410.163714) (xy 122.178881 -410.111411) (xy 122.171123 -410.057455) (xy 120.733613 -410.057455)
			(xy 120.725855 -410.111402) (xy 120.710499 -410.163698) (xy 120.687856 -410.213276) (xy 120.658387 -410.259127)
			(xy 120.622693 -410.300317) (xy 120.5815 -410.336008) (xy 120.535646 -410.365472) (xy 120.486066 -410.388111)
			(xy 120.433768 -410.403463) (xy 120.379818 -410.411215) (xy 120.352566 -410.411676) (xy 119.488966 -410.411676)
			(xy 119.461714 -410.411252) (xy 119.407765 -410.403491) (xy 119.35547 -410.388131) (xy 119.305893 -410.365486)
			(xy 119.260043 -410.336017) (xy 119.218854 -410.300322) (xy 119.183163 -410.259129) (xy 119.153697 -410.213277)
			(xy 119.131057 -410.163698) (xy 119.115702 -410.111401) (xy 119.107946 -410.057452) (xy 117.670289 -410.057452)
			(xy 117.662535 -410.111389) (xy 117.647182 -410.163677) (xy 117.624545 -410.213248) (xy 117.595084 -410.259093)
			(xy 117.559398 -410.300279) (xy 117.518214 -410.335968) (xy 117.472371 -410.365432) (xy 117.422801 -410.388073)
			(xy 117.370514 -410.403429) (xy 117.316574 -410.411188) (xy 117.289326 -410.411676) (xy 116.425726 -410.411676)
			(xy 116.39847 -410.411279) (xy 116.344511 -410.403524) (xy 116.292206 -410.388169) (xy 116.242618 -410.365526)
			(xy 116.196758 -410.336056) (xy 116.155559 -410.30036) (xy 116.119859 -410.259163) (xy 116.090386 -410.213305)
			(xy 116.06774 -410.163719) (xy 116.052381 -410.111414) (xy 116.044623 -410.057456) (xy 111.28975 -410.057456)
			(xy 111.276373 -410.086747) (xy 111.246907 -410.132597) (xy 111.211216 -410.173788) (xy 111.170025 -410.209479)
			(xy 111.124175 -410.238945) (xy 111.074598 -410.261587) (xy 111.022303 -410.276942) (xy 110.968355 -410.284698)
			(xy 110.913853 -410.284698) (xy 110.859905 -410.276942) (xy 110.80761 -410.261587) (xy 110.758033 -410.238945)
			(xy 110.712183 -410.209479) (xy 110.670992 -410.173788) (xy 110.635301 -410.132597) (xy 110.605835 -410.086747)
			(xy 110.583193 -410.03717) (xy 110.567838 -409.984875) (xy 110.560082 -409.930927) (xy 110.559596 -409.903676)
			(xy 102.748244 -409.903676) (xy 102.708181 -409.921973) (xy 102.655851 -409.937338) (xy 102.601867 -409.9451)
			(xy 102.547329 -409.9451) (xy 102.493345 -409.937338) (xy 102.441015 -409.921973) (xy 102.391405 -409.899316)
			(xy 102.345524 -409.86983) (xy 102.304307 -409.834115) (xy 102.268592 -409.792898) (xy 102.239106 -409.747017)
			(xy 102.216449 -409.697407) (xy 102.201084 -409.645077) (xy 102.193322 -409.591093) (xy 102.192836 -409.563824)
			(xy 7.00913 -409.563824) (xy 7.00913 -410.057453) (xy 48.944746 -410.057453) (xy 48.944746 -410.002947)
			(xy 48.952503 -409.948996) (xy 48.967858 -409.896698) (xy 48.9905 -409.847118) (xy 49.019967 -409.801265)
			(xy 49.05566 -409.760071) (xy 49.096852 -409.724377) (xy 49.142704 -409.694908) (xy 49.192283 -409.672264)
			(xy 49.244581 -409.656906) (xy 49.298531 -409.649147) (xy 49.325784 -409.64866) (xy 50.189384 -409.64866)
			(xy 50.216635 -409.649186) (xy 50.270583 -409.656941) (xy 50.322879 -409.672294) (xy 50.372457 -409.694934)
			(xy 50.418308 -409.724399) (xy 50.459499 -409.760089) (xy 50.495192 -409.801279) (xy 50.524659 -409.847129)
			(xy 50.5473 -409.896706) (xy 50.562656 -409.949001) (xy 50.570413 -410.002949) (xy 50.570413 -410.057451)
			(xy 50.570412 -410.057456) (xy 52.007923 -410.057456) (xy 52.007923 -410.002944) (xy 52.015681 -409.948986)
			(xy 52.03104 -409.896682) (xy 52.053686 -409.847096) (xy 52.083159 -409.801238) (xy 52.118858 -409.760041)
			(xy 52.160057 -409.724344) (xy 52.205917 -409.694874) (xy 52.255504 -409.672231) (xy 52.30781 -409.656876)
			(xy 52.361768 -409.649121) (xy 52.389024 -409.64866) (xy 53.252624 -409.64866) (xy 53.279872 -409.649212)
			(xy 53.333812 -409.65697) (xy 53.3861 -409.672326) (xy 53.43567 -409.694967) (xy 53.481513 -409.724431)
			(xy 53.522697 -409.76012) (xy 53.558383 -409.801306) (xy 53.587845 -409.847151) (xy 53.610482 -409.896723)
			(xy 53.625835 -409.949011) (xy 53.63359 -410.002952) (xy 53.63359 -410.057448) (xy 53.633589 -410.057452)
			(xy 55.071246 -410.057452) (xy 55.071246 -410.002948) (xy 55.079002 -409.948999) (xy 55.094357 -409.896703)
			(xy 55.116997 -409.847124) (xy 55.146462 -409.801271) (xy 55.182153 -409.760079) (xy 55.223342 -409.724384)
			(xy 55.269192 -409.694914) (xy 55.318769 -409.672269) (xy 55.371064 -409.65691) (xy 55.425012 -409.649148)
			(xy 55.452264 -409.64866) (xy 56.315864 -409.64866) (xy 56.343116 -409.649185) (xy 56.397067 -409.656937)
			(xy 56.449364 -409.672289) (xy 56.498945 -409.694927) (xy 56.544799 -409.724392) (xy 56.585992 -409.760082)
			(xy 56.621687 -409.801273) (xy 56.651156 -409.847124) (xy 56.673799 -409.896702) (xy 56.689155 -409.948998)
			(xy 56.696913 -410.002948) (xy 56.696913 -410.057452) (xy 56.696913 -410.057455) (xy 58.134423 -410.057455)
			(xy 58.134423 -410.002945) (xy 58.142181 -409.948989) (xy 58.157538 -409.896686) (xy 58.180183 -409.847102)
			(xy 58.209654 -409.801244) (xy 58.245351 -409.760048) (xy 58.286548 -409.724351) (xy 58.332405 -409.694881)
			(xy 58.38199 -409.672237) (xy 58.434293 -409.65688) (xy 58.488249 -409.649123) (xy 58.515504 -409.64866)
			(xy 59.379104 -409.64866) (xy 59.406353 -409.64921) (xy 59.460295 -409.656967) (xy 59.512585 -409.672321)
			(xy 59.562158 -409.69496) (xy 59.608004 -409.724424) (xy 59.64919 -409.760113) (xy 59.684878 -409.801299)
			(xy 59.714342 -409.847146) (xy 59.73698 -409.896718) (xy 59.752334 -409.949008) (xy 59.76009 -410.002951)
			(xy 59.76009 -410.057449) (xy 59.760089 -410.057457) (xy 61.197623 -410.057457) (xy 61.197623 -410.002943)
			(xy 61.205382 -409.948983) (xy 61.220741 -409.896678) (xy 61.243389 -409.84709) (xy 61.272864 -409.801231)
			(xy 61.308565 -409.760034) (xy 61.349767 -409.724337) (xy 61.395629 -409.694868) (xy 61.445219 -409.672226)
			(xy 61.497527 -409.656872) (xy 61.551487 -409.64912) (xy 61.578744 -409.64866) (xy 62.442344 -409.64866)
			(xy 62.469591 -409.649213) (xy 62.523529 -409.656974) (xy 62.575814 -409.672332) (xy 62.625382 -409.694973)
			(xy 62.671223 -409.724438) (xy 62.712404 -409.760127) (xy 62.748088 -409.801313) (xy 62.777548 -409.847157)
			(xy 62.800184 -409.896727) (xy 62.815535 -409.949014) (xy 62.82329 -410.002953) (xy 62.82329 -410.057447)
			(xy 62.823289 -410.057453) (xy 64.260946 -410.057453) (xy 64.260946 -410.002947) (xy 64.268703 -409.948996)
			(xy 64.284058 -409.896698) (xy 64.3067 -409.847118) (xy 64.336167 -409.801265) (xy 64.37186 -409.760071)
			(xy 64.413052 -409.724377) (xy 64.458904 -409.694908) (xy 64.508483 -409.672264) (xy 64.560781 -409.656906)
			(xy 64.614731 -409.649147) (xy 64.641984 -409.64866) (xy 65.505584 -409.64866) (xy 65.532835 -409.649186)
			(xy 65.586783 -409.656941) (xy 65.639079 -409.672294) (xy 65.688657 -409.694934) (xy 65.734508 -409.724399)
			(xy 65.775699 -409.760089) (xy 65.811392 -409.801279) (xy 65.840859 -409.847129) (xy 65.8635 -409.896706)
			(xy 65.878856 -409.949001) (xy 65.886613 -410.002949) (xy 65.886613 -410.057451) (xy 65.886612 -410.057456)
			(xy 67.324123 -410.057456) (xy 67.324123 -410.002944) (xy 67.331881 -409.948986) (xy 67.34724 -409.896682)
			(xy 67.369886 -409.847096) (xy 67.399359 -409.801238) (xy 67.435058 -409.760041) (xy 67.476257 -409.724344)
			(xy 67.522117 -409.694874) (xy 67.571704 -409.672231) (xy 67.62401 -409.656876) (xy 67.677968 -409.649121)
			(xy 67.705224 -409.64866) (xy 68.568824 -409.64866) (xy 68.596072 -409.649212) (xy 68.650012 -409.65697)
			(xy 68.7023 -409.672326) (xy 68.75187 -409.694967) (xy 68.797713 -409.724431) (xy 68.838897 -409.76012)
			(xy 68.874583 -409.801306) (xy 68.904045 -409.847151) (xy 68.926682 -409.896723) (xy 68.942035 -409.949011)
			(xy 68.94979 -410.002952) (xy 68.94979 -410.057448) (xy 68.949789 -410.057452) (xy 70.387446 -410.057452)
			(xy 70.387446 -410.002948) (xy 70.395202 -409.948999) (xy 70.410557 -409.896703) (xy 70.433197 -409.847124)
			(xy 70.462662 -409.801271) (xy 70.498353 -409.760079) (xy 70.539542 -409.724384) (xy 70.585392 -409.694914)
			(xy 70.634969 -409.672269) (xy 70.687264 -409.65691) (xy 70.741212 -409.649148) (xy 70.768464 -409.64866)
			(xy 71.632064 -409.64866) (xy 71.659316 -409.649185) (xy 71.713267 -409.656937) (xy 71.765564 -409.672289)
			(xy 71.815145 -409.694927) (xy 71.860999 -409.724392) (xy 71.902192 -409.760082) (xy 71.937887 -409.801273)
			(xy 71.967356 -409.847124) (xy 71.989999 -409.896702) (xy 72.005355 -409.948998) (xy 72.013113 -410.002948)
			(xy 72.013113 -410.057452) (xy 72.013113 -410.057455) (xy 73.450623 -410.057455) (xy 73.450623 -410.002945)
			(xy 73.458381 -409.948989) (xy 73.473738 -409.896686) (xy 73.496383 -409.847102) (xy 73.525854 -409.801244)
			(xy 73.561551 -409.760048) (xy 73.602748 -409.724351) (xy 73.648605 -409.694881) (xy 73.69819 -409.672237)
			(xy 73.750493 -409.65688) (xy 73.804449 -409.649123) (xy 73.831704 -409.64866) (xy 74.695304 -409.64866)
			(xy 74.722553 -409.64921) (xy 74.776495 -409.656967) (xy 74.828785 -409.672321) (xy 74.878358 -409.69496)
			(xy 74.924204 -409.724424) (xy 74.96539 -409.760113) (xy 75.001078 -409.801299) (xy 75.030542 -409.847146)
			(xy 75.05318 -409.896718) (xy 75.068534 -409.949008) (xy 75.07629 -410.002951) (xy 75.07629 -410.057449)
			(xy 75.076289 -410.057457) (xy 76.513823 -410.057457) (xy 76.513823 -410.002943) (xy 76.521582 -409.948983)
			(xy 76.536941 -409.896678) (xy 76.559589 -409.84709) (xy 76.589064 -409.801231) (xy 76.624765 -409.760034)
			(xy 76.665967 -409.724337) (xy 76.711829 -409.694868) (xy 76.761419 -409.672226) (xy 76.813727 -409.656872)
			(xy 76.867687 -409.64912) (xy 76.894944 -409.64866) (xy 77.758544 -409.64866) (xy 77.785791 -409.649213)
			(xy 77.839729 -409.656974) (xy 77.892014 -409.672332) (xy 77.941582 -409.694973) (xy 77.987423 -409.724438)
			(xy 78.028604 -409.760127) (xy 78.064288 -409.801313) (xy 78.093748 -409.847157) (xy 78.116384 -409.896727)
			(xy 78.131735 -409.949014) (xy 78.13949 -410.002953) (xy 78.13949 -410.057447) (xy 78.139489 -410.057453)
			(xy 79.577146 -410.057453) (xy 79.577146 -410.002947) (xy 79.584903 -409.948996) (xy 79.600258 -409.896698)
			(xy 79.6229 -409.847118) (xy 79.652367 -409.801265) (xy 79.68806 -409.760071) (xy 79.729252 -409.724377)
			(xy 79.775104 -409.694908) (xy 79.824683 -409.672264) (xy 79.876981 -409.656906) (xy 79.930931 -409.649147)
			(xy 79.958184 -409.64866) (xy 80.821784 -409.64866) (xy 80.849035 -409.649186) (xy 80.902983 -409.656941)
			(xy 80.955279 -409.672294) (xy 81.004857 -409.694934) (xy 81.050708 -409.724399) (xy 81.091899 -409.760089)
			(xy 81.127592 -409.801279) (xy 81.157059 -409.847129) (xy 81.1797 -409.896706) (xy 81.195056 -409.949001)
			(xy 81.202813 -410.002949) (xy 81.202813 -410.057451) (xy 81.202812 -410.057456) (xy 82.640323 -410.057456)
			(xy 82.640323 -410.002944) (xy 82.648081 -409.948986) (xy 82.66344 -409.896682) (xy 82.686086 -409.847096)
			(xy 82.715559 -409.801238) (xy 82.751258 -409.760041) (xy 82.792457 -409.724344) (xy 82.838317 -409.694874)
			(xy 82.887904 -409.672231) (xy 82.94021 -409.656876) (xy 82.994168 -409.649121) (xy 83.021424 -409.64866)
			(xy 83.885024 -409.64866) (xy 83.912272 -409.649212) (xy 83.966212 -409.65697) (xy 84.0185 -409.672326)
			(xy 84.06807 -409.694967) (xy 84.113913 -409.724431) (xy 84.155097 -409.76012) (xy 84.190783 -409.801306)
			(xy 84.220245 -409.847151) (xy 84.242882 -409.896723) (xy 84.258235 -409.949011) (xy 84.26599 -410.002952)
			(xy 84.26599 -410.057448) (xy 84.265989 -410.057452) (xy 85.703646 -410.057452) (xy 85.703646 -410.002948)
			(xy 85.711402 -409.948999) (xy 85.726757 -409.896703) (xy 85.749397 -409.847124) (xy 85.778862 -409.801271)
			(xy 85.814553 -409.760079) (xy 85.855742 -409.724384) (xy 85.901592 -409.694914) (xy 85.951169 -409.672269)
			(xy 86.003464 -409.65691) (xy 86.057412 -409.649148) (xy 86.084664 -409.64866) (xy 86.948264 -409.64866)
			(xy 86.975516 -409.649185) (xy 87.029467 -409.656937) (xy 87.081764 -409.672289) (xy 87.131345 -409.694927)
			(xy 87.177199 -409.724392) (xy 87.218392 -409.760082) (xy 87.254087 -409.801273) (xy 87.283556 -409.847124)
			(xy 87.306199 -409.896702) (xy 87.321555 -409.948998) (xy 87.329313 -410.002948) (xy 87.329313 -410.057452)
			(xy 87.329313 -410.057455) (xy 88.766823 -410.057455) (xy 88.766823 -410.002945) (xy 88.774581 -409.948989)
			(xy 88.789938 -409.896686) (xy 88.812583 -409.847102) (xy 88.842054 -409.801244) (xy 88.877751 -409.760048)
			(xy 88.918948 -409.724351) (xy 88.964805 -409.694881) (xy 89.01439 -409.672237) (xy 89.066693 -409.65688)
			(xy 89.120649 -409.649123) (xy 89.147904 -409.64866) (xy 90.011504 -409.64866) (xy 90.038753 -409.64921)
			(xy 90.092695 -409.656967) (xy 90.144985 -409.672321) (xy 90.194558 -409.69496) (xy 90.240404 -409.724424)
			(xy 90.28159 -409.760113) (xy 90.317278 -409.801299) (xy 90.346742 -409.847146) (xy 90.36938 -409.896718)
			(xy 90.384734 -409.949008) (xy 90.39249 -410.002951) (xy 90.39249 -410.057449) (xy 90.392489 -410.057457)
			(xy 91.830023 -410.057457) (xy 91.830023 -410.002943) (xy 91.837782 -409.948983) (xy 91.853141 -409.896678)
			(xy 91.875789 -409.84709) (xy 91.905264 -409.801231) (xy 91.940965 -409.760034) (xy 91.982167 -409.724337)
			(xy 92.028029 -409.694868) (xy 92.077619 -409.672226) (xy 92.129927 -409.656872) (xy 92.183887 -409.64912)
			(xy 92.211144 -409.64866) (xy 93.074744 -409.64866) (xy 93.101991 -409.649213) (xy 93.155929 -409.656974)
			(xy 93.208214 -409.672332) (xy 93.257782 -409.694973) (xy 93.303623 -409.724438) (xy 93.344804 -409.760127)
			(xy 93.380488 -409.801313) (xy 93.409948 -409.847157) (xy 93.432584 -409.896727) (xy 93.447935 -409.949014)
			(xy 93.45569 -410.002953) (xy 93.45569 -410.057447) (xy 93.455689 -410.057453) (xy 94.893346 -410.057453)
			(xy 94.893346 -410.002947) (xy 94.901103 -409.948996) (xy 94.916458 -409.896698) (xy 94.9391 -409.847118)
			(xy 94.968567 -409.801265) (xy 95.00426 -409.760071) (xy 95.045452 -409.724377) (xy 95.091304 -409.694908)
			(xy 95.140883 -409.672264) (xy 95.193181 -409.656906) (xy 95.247131 -409.649147) (xy 95.274384 -409.64866)
			(xy 96.137984 -409.64866) (xy 96.165235 -409.649186) (xy 96.219183 -409.656941) (xy 96.271479 -409.672294)
			(xy 96.321057 -409.694934) (xy 96.366908 -409.724399) (xy 96.408099 -409.760089) (xy 96.443792 -409.801279)
			(xy 96.473259 -409.847129) (xy 96.4959 -409.896706) (xy 96.511256 -409.949001) (xy 96.519013 -410.002949)
			(xy 96.519013 -410.057451) (xy 96.511256 -410.111399) (xy 96.4959 -410.163694) (xy 96.473259 -410.213271)
			(xy 96.443792 -410.259121) (xy 96.408099 -410.300311) (xy 96.366908 -410.336001) (xy 96.321057 -410.365466)
			(xy 96.271479 -410.388106) (xy 96.219183 -410.403459) (xy 96.165235 -410.411214) (xy 96.137984 -410.411676)
			(xy 95.274384 -410.411676) (xy 95.247131 -410.411253) (xy 95.193181 -410.403494) (xy 95.140883 -410.388136)
			(xy 95.091304 -410.365492) (xy 95.045452 -410.336023) (xy 95.00426 -410.300329) (xy 94.968567 -410.259135)
			(xy 94.9391 -410.213282) (xy 94.916458 -410.163702) (xy 94.901103 -410.111404) (xy 94.893346 -410.057453)
			(xy 93.455689 -410.057453) (xy 93.447935 -410.111386) (xy 93.432584 -410.163673) (xy 93.409948 -410.213243)
			(xy 93.380488 -410.259087) (xy 93.344804 -410.300273) (xy 93.303623 -410.335962) (xy 93.257782 -410.365427)
			(xy 93.208214 -410.388068) (xy 93.155929 -410.403426) (xy 93.101991 -410.411187) (xy 93.074744 -410.411676)
			(xy 92.211144 -410.411676) (xy 92.183887 -410.41128) (xy 92.129927 -410.403528) (xy 92.077619 -410.388174)
			(xy 92.028029 -410.365532) (xy 91.982167 -410.336063) (xy 91.940965 -410.300366) (xy 91.905264 -410.259169)
			(xy 91.875789 -410.21331) (xy 91.853141 -410.163722) (xy 91.837782 -410.111417) (xy 91.830023 -410.057457)
			(xy 90.392489 -410.057457) (xy 90.384734 -410.111392) (xy 90.36938 -410.163682) (xy 90.346742 -410.213254)
			(xy 90.317278 -410.259101) (xy 90.28159 -410.300287) (xy 90.240404 -410.335976) (xy 90.194558 -410.36544)
			(xy 90.144985 -410.388079) (xy 90.092695 -410.403433) (xy 90.038753 -410.41119) (xy 90.011504 -410.411676)
			(xy 89.147904 -410.411676) (xy 89.120649 -410.411277) (xy 89.066693 -410.40352) (xy 89.01439 -410.388163)
			(xy 88.964805 -410.365519) (xy 88.918948 -410.336049) (xy 88.877751 -410.300352) (xy 88.842054 -410.259156)
			(xy 88.812583 -410.213298) (xy 88.789938 -410.163714) (xy 88.774581 -410.111411) (xy 88.766823 -410.057455)
			(xy 87.329313 -410.057455) (xy 87.321555 -410.111402) (xy 87.306199 -410.163698) (xy 87.283556 -410.213276)
			(xy 87.254087 -410.259127) (xy 87.218392 -410.300318) (xy 87.177199 -410.336008) (xy 87.131345 -410.365473)
			(xy 87.081764 -410.388111) (xy 87.029467 -410.403463) (xy 86.975516 -410.411215) (xy 86.948264 -410.411676)
			(xy 86.084664 -410.411676) (xy 86.057412 -410.411252) (xy 86.003464 -410.40349) (xy 85.951169 -410.388131)
			(xy 85.901592 -410.365486) (xy 85.855742 -410.336016) (xy 85.814553 -410.300321) (xy 85.778862 -410.259129)
			(xy 85.749397 -410.213276) (xy 85.726757 -410.163697) (xy 85.711402 -410.111401) (xy 85.703646 -410.057452)
			(xy 84.265989 -410.057452) (xy 84.258235 -410.111389) (xy 84.242882 -410.163677) (xy 84.220245 -410.213249)
			(xy 84.190783 -410.259094) (xy 84.155097 -410.30028) (xy 84.113913 -410.335969) (xy 84.06807 -410.365433)
			(xy 84.0185 -410.388074) (xy 83.966212 -410.40343) (xy 83.912272 -410.411188) (xy 83.885024 -410.411676)
			(xy 83.021424 -410.411676) (xy 82.994168 -410.411279) (xy 82.94021 -410.403524) (xy 82.887904 -410.388169)
			(xy 82.838317 -410.365526) (xy 82.792457 -410.336056) (xy 82.751258 -410.300359) (xy 82.715559 -410.259162)
			(xy 82.686086 -410.213304) (xy 82.66344 -410.163718) (xy 82.648081 -410.111414) (xy 82.640323 -410.057456)
			(xy 81.202812 -410.057456) (xy 81.195056 -410.111399) (xy 81.1797 -410.163694) (xy 81.157059 -410.213271)
			(xy 81.127592 -410.259121) (xy 81.091899 -410.300311) (xy 81.050708 -410.336001) (xy 81.004857 -410.365466)
			(xy 80.955279 -410.388106) (xy 80.902983 -410.403459) (xy 80.849035 -410.411214) (xy 80.821784 -410.411676)
			(xy 79.958184 -410.411676) (xy 79.930931 -410.411253) (xy 79.876981 -410.403494) (xy 79.824683 -410.388136)
			(xy 79.775104 -410.365492) (xy 79.729252 -410.336023) (xy 79.68806 -410.300329) (xy 79.652367 -410.259135)
			(xy 79.6229 -410.213282) (xy 79.600258 -410.163702) (xy 79.584903 -410.111404) (xy 79.577146 -410.057453)
			(xy 78.139489 -410.057453) (xy 78.131735 -410.111386) (xy 78.116384 -410.163673) (xy 78.093748 -410.213243)
			(xy 78.064288 -410.259087) (xy 78.028604 -410.300273) (xy 77.987423 -410.335962) (xy 77.941582 -410.365427)
			(xy 77.892014 -410.388068) (xy 77.839729 -410.403426) (xy 77.785791 -410.411187) (xy 77.758544 -410.411676)
			(xy 76.894944 -410.411676) (xy 76.867687 -410.41128) (xy 76.813727 -410.403528) (xy 76.761419 -410.388174)
			(xy 76.711829 -410.365532) (xy 76.665967 -410.336063) (xy 76.624765 -410.300366) (xy 76.589064 -410.259169)
			(xy 76.559589 -410.21331) (xy 76.536941 -410.163722) (xy 76.521582 -410.111417) (xy 76.513823 -410.057457)
			(xy 75.076289 -410.057457) (xy 75.068534 -410.111392) (xy 75.05318 -410.163682) (xy 75.030542 -410.213254)
			(xy 75.001078 -410.259101) (xy 74.96539 -410.300287) (xy 74.924204 -410.335976) (xy 74.878358 -410.36544)
			(xy 74.828785 -410.388079) (xy 74.776495 -410.403433) (xy 74.722553 -410.41119) (xy 74.695304 -410.411676)
			(xy 73.831704 -410.411676) (xy 73.804449 -410.411277) (xy 73.750493 -410.40352) (xy 73.69819 -410.388163)
			(xy 73.648605 -410.365519) (xy 73.602748 -410.336049) (xy 73.561551 -410.300352) (xy 73.525854 -410.259156)
			(xy 73.496383 -410.213298) (xy 73.473738 -410.163714) (xy 73.458381 -410.111411) (xy 73.450623 -410.057455)
			(xy 72.013113 -410.057455) (xy 72.005355 -410.111402) (xy 71.989999 -410.163698) (xy 71.967356 -410.213276)
			(xy 71.937887 -410.259127) (xy 71.902192 -410.300318) (xy 71.860999 -410.336008) (xy 71.815145 -410.365473)
			(xy 71.765564 -410.388111) (xy 71.713267 -410.403463) (xy 71.659316 -410.411215) (xy 71.632064 -410.411676)
			(xy 70.768464 -410.411676) (xy 70.741212 -410.411252) (xy 70.687264 -410.40349) (xy 70.634969 -410.388131)
			(xy 70.585392 -410.365486) (xy 70.539542 -410.336016) (xy 70.498353 -410.300321) (xy 70.462662 -410.259129)
			(xy 70.433197 -410.213276) (xy 70.410557 -410.163697) (xy 70.395202 -410.111401) (xy 70.387446 -410.057452)
			(xy 68.949789 -410.057452) (xy 68.942035 -410.111389) (xy 68.926682 -410.163677) (xy 68.904045 -410.213249)
			(xy 68.874583 -410.259094) (xy 68.838897 -410.30028) (xy 68.797713 -410.335969) (xy 68.75187 -410.365433)
			(xy 68.7023 -410.388074) (xy 68.650012 -410.40343) (xy 68.596072 -410.411188) (xy 68.568824 -410.411676)
			(xy 67.705224 -410.411676) (xy 67.677968 -410.411279) (xy 67.62401 -410.403524) (xy 67.571704 -410.388169)
			(xy 67.522117 -410.365526) (xy 67.476257 -410.336056) (xy 67.435058 -410.300359) (xy 67.399359 -410.259162)
			(xy 67.369886 -410.213304) (xy 67.34724 -410.163718) (xy 67.331881 -410.111414) (xy 67.324123 -410.057456)
			(xy 65.886612 -410.057456) (xy 65.878856 -410.111399) (xy 65.8635 -410.163694) (xy 65.840859 -410.213271)
			(xy 65.811392 -410.259121) (xy 65.775699 -410.300311) (xy 65.734508 -410.336001) (xy 65.688657 -410.365466)
			(xy 65.639079 -410.388106) (xy 65.586783 -410.403459) (xy 65.532835 -410.411214) (xy 65.505584 -410.411676)
			(xy 64.641984 -410.411676) (xy 64.614731 -410.411253) (xy 64.560781 -410.403494) (xy 64.508483 -410.388136)
			(xy 64.458904 -410.365492) (xy 64.413052 -410.336023) (xy 64.37186 -410.300329) (xy 64.336167 -410.259135)
			(xy 64.3067 -410.213282) (xy 64.284058 -410.163702) (xy 64.268703 -410.111404) (xy 64.260946 -410.057453)
			(xy 62.823289 -410.057453) (xy 62.815535 -410.111386) (xy 62.800184 -410.163673) (xy 62.777548 -410.213243)
			(xy 62.748088 -410.259087) (xy 62.712404 -410.300273) (xy 62.671223 -410.335962) (xy 62.625382 -410.365427)
			(xy 62.575814 -410.388068) (xy 62.523529 -410.403426) (xy 62.469591 -410.411187) (xy 62.442344 -410.411676)
			(xy 61.578744 -410.411676) (xy 61.551487 -410.41128) (xy 61.497527 -410.403528) (xy 61.445219 -410.388174)
			(xy 61.395629 -410.365532) (xy 61.349767 -410.336063) (xy 61.308565 -410.300366) (xy 61.272864 -410.259169)
			(xy 61.243389 -410.21331) (xy 61.220741 -410.163722) (xy 61.205382 -410.111417) (xy 61.197623 -410.057457)
			(xy 59.760089 -410.057457) (xy 59.752334 -410.111392) (xy 59.73698 -410.163682) (xy 59.714342 -410.213254)
			(xy 59.684878 -410.259101) (xy 59.64919 -410.300287) (xy 59.608004 -410.335976) (xy 59.562158 -410.36544)
			(xy 59.512585 -410.388079) (xy 59.460295 -410.403433) (xy 59.406353 -410.41119) (xy 59.379104 -410.411676)
			(xy 58.515504 -410.411676) (xy 58.488249 -410.411277) (xy 58.434293 -410.40352) (xy 58.38199 -410.388163)
			(xy 58.332405 -410.365519) (xy 58.286548 -410.336049) (xy 58.245351 -410.300352) (xy 58.209654 -410.259156)
			(xy 58.180183 -410.213298) (xy 58.157538 -410.163714) (xy 58.142181 -410.111411) (xy 58.134423 -410.057455)
			(xy 56.696913 -410.057455) (xy 56.689155 -410.111402) (xy 56.673799 -410.163698) (xy 56.651156 -410.213276)
			(xy 56.621687 -410.259127) (xy 56.585992 -410.300318) (xy 56.544799 -410.336008) (xy 56.498945 -410.365473)
			(xy 56.449364 -410.388111) (xy 56.397067 -410.403463) (xy 56.343116 -410.411215) (xy 56.315864 -410.411676)
			(xy 55.452264 -410.411676) (xy 55.425012 -410.411252) (xy 55.371064 -410.40349) (xy 55.318769 -410.388131)
			(xy 55.269192 -410.365486) (xy 55.223342 -410.336016) (xy 55.182153 -410.300321) (xy 55.146462 -410.259129)
			(xy 55.116997 -410.213276) (xy 55.094357 -410.163697) (xy 55.079002 -410.111401) (xy 55.071246 -410.057452)
			(xy 53.633589 -410.057452) (xy 53.625835 -410.111389) (xy 53.610482 -410.163677) (xy 53.587845 -410.213249)
			(xy 53.558383 -410.259094) (xy 53.522697 -410.30028) (xy 53.481513 -410.335969) (xy 53.43567 -410.365433)
			(xy 53.3861 -410.388074) (xy 53.333812 -410.40343) (xy 53.279872 -410.411188) (xy 53.252624 -410.411676)
			(xy 52.389024 -410.411676) (xy 52.361768 -410.411279) (xy 52.30781 -410.403524) (xy 52.255504 -410.388169)
			(xy 52.205917 -410.365526) (xy 52.160057 -410.336056) (xy 52.118858 -410.300359) (xy 52.083159 -410.259162)
			(xy 52.053686 -410.213304) (xy 52.03104 -410.163718) (xy 52.015681 -410.111414) (xy 52.007923 -410.057456)
			(xy 50.570412 -410.057456) (xy 50.562656 -410.111399) (xy 50.5473 -410.163694) (xy 50.524659 -410.213271)
			(xy 50.495192 -410.259121) (xy 50.459499 -410.300311) (xy 50.418308 -410.336001) (xy 50.372457 -410.365466)
			(xy 50.322879 -410.388106) (xy 50.270583 -410.403459) (xy 50.216635 -410.411214) (xy 50.189384 -410.411676)
			(xy 49.325784 -410.411676) (xy 49.298531 -410.411253) (xy 49.244581 -410.403494) (xy 49.192283 -410.388136)
			(xy 49.142704 -410.365492) (xy 49.096852 -410.336023) (xy 49.05566 -410.300329) (xy 49.019967 -410.259135)
			(xy 48.9905 -410.213282) (xy 48.967858 -410.163702) (xy 48.952503 -410.111404) (xy 48.944746 -410.057453)
			(xy 7.00913 -410.057453) (xy 7.00913 -410.708348) (xy 183.940958 -410.708348) (xy 183.940958 -400.09572)
			(xy 183.941483 -400.070772) (xy 183.94929 -400.021491) (xy 183.964701 -399.974034) (xy 183.987336 -399.929568)
			(xy 184.01664 -399.889183) (xy 184.033922 -399.871184) (xy 184.239408 -399.665698) (xy 184.257395 -399.648399)
			(xy 184.297773 -399.619076) (xy 184.342241 -399.59643) (xy 184.389704 -399.581018) (xy 184.438993 -399.57322)
			(xy 184.463944 -399.572734) (xy 188.119004 -399.572734) (xy 188.143952 -399.57325) (xy 188.193234 -399.581061)
			(xy 188.24069 -399.596474) (xy 188.285156 -399.619111) (xy 188.32554 -399.648416) (xy 188.34354 -399.665698)
			(xy 188.528452 -399.85061) (xy 188.545762 -399.868588) (xy 188.575091 -399.908966) (xy 188.597741 -399.953436)
			(xy 188.613156 -400.000901) (xy 188.620956 -400.050193) (xy 188.621416 -400.075146) (xy 188.621416 -402.753322)
			(xy 188.621826 -402.763393) (xy 188.629557 -402.781991) (xy 188.636402 -402.78939) (xy 191.190372 -405.34336)
			(xy 191.197792 -405.350175) (xy 191.216376 -405.35791) (xy 191.22644 -405.358346) (xy 195.26631 -405.358346)
			(xy 195.276382 -405.35794) (xy 195.29498 -405.350207) (xy 195.302378 -405.34336) (xy 197.179184 -403.466554)
			(xy 197.185991 -403.459128) (xy 197.193731 -403.440549) (xy 197.19417 -403.430486) (xy 197.19417 -400.104356)
			(xy 197.194651 -400.079406) (xy 197.202469 -400.030123) (xy 197.217889 -399.982665) (xy 197.240534 -399.9382)
			(xy 197.269848 -399.897818) (xy 197.287134 -399.87982) (xy 197.53961 -399.627344) (xy 197.557604 -399.610052)
			(xy 197.597979 -399.580727) (xy 197.642445 -399.558078) (xy 197.689907 -399.542665) (xy 197.739195 -399.534866)
			(xy 197.764146 -399.53438) (xy 201.33818 -399.53438) (xy 201.363128 -399.534898) (xy 201.41241 -399.542706)
			(xy 201.459867 -399.558118) (xy 201.504334 -399.580755) (xy 201.544717 -399.610061) (xy 201.562716 -399.627344)
			(xy 201.823066 -399.887694) (xy 201.840352 -399.905693) (xy 201.869678 -399.946068) (xy 201.892327 -399.990532)
			(xy 201.907742 -400.037992) (xy 201.915543 -400.08728) (xy 201.91603 -400.11223) (xy 201.91603 -403.422612)
			(xy 201.916441 -403.432683) (xy 201.924171 -403.451281) (xy 201.931016 -403.45868) (xy 202.036172 -403.563836)
			(xy 202.053479 -403.581816) (xy 202.082802 -403.622195) (xy 202.105447 -403.666665) (xy 202.120857 -403.714129)
			(xy 202.128652 -403.76342) (xy 202.129136 -403.788372) (xy 202.129136 -406.516078) (xy 202.129564 -406.526147)
			(xy 202.137282 -406.544745) (xy 202.144122 -406.552146) (xy 203.391008 -407.799032) (xy 203.39839 -407.805645)
			(xy 203.416673 -407.813238) (xy 203.426568 -407.813764) (xy 203.457048 -407.814018) (xy 203.466471 -407.813752)
			(xy 203.484091 -407.807093) (xy 203.491338 -407.801064) (xy 203.512428 -407.782761) (xy 203.558955 -407.751881)
			(xy 203.609485 -407.728114) (xy 203.662941 -407.711966) (xy 203.71818 -407.703783) (xy 203.7461 -407.703274)
			(xy 203.772675 -407.703742) (xy 203.825312 -407.711107) (xy 203.876417 -407.72571) (xy 203.924999 -407.747267)
			(xy 203.970118 -407.77536) (xy 204.010899 -407.809446) (xy 204.046552 -407.848864) (xy 204.076387 -407.89285)
			(xy 204.099826 -407.940552) (xy 204.108558 -407.965656) (xy 204.112315 -407.97567) (xy 204.126611 -407.991551)
			(xy 204.146134 -408.00024) (xy 204.156818 -408.000708) (xy 205.795372 -408.000708) (xy 205.805443 -408.000292)
			(xy 205.824042 -407.992567) (xy 205.83144 -407.985722) (xy 207.658716 -406.158446) (xy 207.66553 -406.151026)
			(xy 207.673264 -406.132442) (xy 207.673702 -406.122378) (xy 207.673702 -403.722586) (xy 207.674193 -403.697637)
			(xy 207.682006 -403.648353) (xy 207.697424 -403.600896) (xy 207.720068 -403.55643) (xy 207.74938 -403.516048)
			(xy 207.766666 -403.49805) (xy 207.847184 -403.417532) (xy 207.854 -403.410113) (xy 207.861735 -403.391528)
			(xy 207.86217 -403.381464) (xy 207.86217 -400.079464) (xy 207.862656 -400.054515) (xy 207.870472 -400.005231)
			(xy 207.885892 -399.957774) (xy 207.908536 -399.913308) (xy 207.937848 -399.872926) (xy 207.955134 -399.854928)
			(xy 208.201514 -399.608548) (xy 208.21949 -399.591236) (xy 208.259869 -399.561908) (xy 208.304339 -399.539258)
			(xy 208.351805 -399.523843) (xy 208.401097 -399.516044) (xy 208.42605 -399.515584) (xy 211.971128 -399.515584)
			(xy 211.996077 -399.516071) (xy 212.045361 -399.523886) (xy 212.092818 -399.539306) (xy 212.137284 -399.561949)
			(xy 212.177666 -399.591262) (xy 212.195664 -399.608548) (xy 212.507576 -399.92046) (xy 212.524847 -399.938473)
			(xy 212.554175 -399.978843) (xy 212.576826 -400.023305) (xy 212.592245 -400.070762) (xy 212.600051 -400.120047)
			(xy 212.60054 -400.144996) (xy 212.60054 -403.480016) (xy 212.600947 -403.490088) (xy 212.608679 -403.508686)
			(xy 212.615526 -403.516084) (xy 212.638894 -403.539452) (xy 212.656213 -403.557421) (xy 212.685533 -403.597804)
			(xy 212.708176 -403.642276) (xy 212.723583 -403.689743) (xy 212.731376 -403.739036) (xy 212.731858 -403.763988)
			(xy 212.731858 -406.258014) (xy 212.732261 -406.268086) (xy 212.739995 -406.286685) (xy 212.746844 -406.294082)
			(xy 214.186008 -407.733246) (xy 214.193923 -407.74035) (xy 214.21371 -407.748063) (xy 214.234927 -407.747127)
			(xy 214.244682 -407.742898) (xy 214.271123 -407.730432) (xy 214.326854 -407.712801) (xy 214.38462 -407.703855)
			(xy 214.413846 -407.703274) (xy 214.4141 -407.703274) (xy 214.441972 -407.70378) (xy 214.497125 -407.71188)
			(xy 214.550512 -407.727922) (xy 214.600994 -407.751564) (xy 214.647498 -407.782303) (xy 214.689031 -407.819484)
			(xy 214.72471 -407.862315) (xy 214.753774 -407.909883) (xy 214.775604 -407.961175) (xy 214.783162 -407.988008)
			(xy 214.78748 -408.004772) (xy 214.814912 -408.025854) (xy 216.38895 -408.025854) (xy 216.399018 -408.025415)
			(xy 216.417617 -408.017705) (xy 216.425018 -408.010868) (xy 218.335098 -406.100788) (xy 218.341936 -406.093386)
			(xy 218.349657 -406.074788) (xy 218.350084 -406.06472) (xy 218.350084 -403.755606) (xy 218.350592 -403.730657)
			(xy 218.358403 -403.681375) (xy 218.373817 -403.633918) (xy 218.396456 -403.589452) (xy 218.425764 -403.549069)
			(xy 218.443048 -403.53107) (xy 218.50731 -403.466808) (xy 218.51414 -403.4594) (xy 218.521865 -403.440807)
			(xy 218.522296 -403.43074) (xy 218.522296 -400.095974) (xy 218.522781 -400.071024) (xy 218.530596 -400.021741)
			(xy 218.546016 -399.974283) (xy 218.56866 -399.929817) (xy 218.597974 -399.889436) (xy 218.61526 -399.871438)
			(xy 218.820746 -399.665952) (xy 218.838709 -399.648625) (xy 218.879091 -399.619299) (xy 218.923564 -399.596652)
			(xy 218.971033 -399.581241) (xy 219.020328 -399.573446) (xy 219.045282 -399.572988) (xy 222.709232 -399.572988)
			(xy 222.734182 -399.573471) (xy 222.783465 -399.581288) (xy 222.830923 -399.596707) (xy 222.875388 -399.619352)
			(xy 222.91577 -399.648666) (xy 222.933768 -399.665952) (xy 223.130618 -399.862802) (xy 223.147917 -399.880789)
			(xy 223.177239 -399.921168) (xy 223.199885 -399.965636) (xy 223.215297 -400.013098) (xy 223.223096 -400.062387)
			(xy 223.223582 -400.087338) (xy 223.223582 -403.455124) (xy 223.223973 -403.465198) (xy 223.231716 -403.483796)
			(xy 223.238568 -403.491192) (xy 223.323658 -403.576282) (xy 223.340937 -403.594288) (xy 223.370264 -403.63466)
			(xy 223.392915 -403.679123) (xy 223.408331 -403.726582) (xy 223.416134 -403.775868) (xy 223.416622 -403.800818)
			(xy 223.416622 -406.262078) (xy 223.417053 -406.272147) (xy 223.424769 -406.290745) (xy 223.431608 -406.298146)
			(xy 224.874328 -407.740866) (xy 224.905824 -407.7462) (xy 224.920302 -407.739342) (xy 224.945735 -407.727945)
			(xy 224.999097 -407.71187) (xy 225.054234 -407.703754) (xy 225.0821 -407.703274) (xy 225.111289 -407.703848)
			(xy 225.168987 -407.712721) (xy 225.224657 -407.730289) (xy 225.276997 -407.756142) (xy 225.324782 -407.789675)
			(xy 225.366893 -407.830104) (xy 225.402346 -407.876481) (xy 225.430312 -407.927723) (xy 225.440748 -407.954988)
			(xy 225.444773 -407.964592) (xy 225.459011 -407.979756) (xy 225.4781 -407.988017) (xy 225.4885 -407.988516)
			(xy 227.066094 -407.988516) (xy 227.076166 -407.98811) (xy 227.094765 -407.980378) (xy 227.102162 -407.97353)
			(xy 228.999288 -406.076404) (xy 229.006117 -406.068995) (xy 229.013844 -406.050403) (xy 229.014274 -406.040336)
			(xy 229.014274 -403.768052) (xy 229.014751 -403.743102) (xy 229.02257 -403.693818) (xy 229.037991 -403.646361)
			(xy 229.060637 -403.601896) (xy 229.089951 -403.561514) (xy 229.107238 -403.543516) (xy 229.183692 -403.467062)
			(xy 229.19054 -403.459668) (xy 229.198255 -403.441064) (xy 229.198678 -403.430994) (xy 229.198678 -400.11223)
			(xy 229.199203 -400.087282) (xy 229.20701 -400.038) (xy 229.22242 -399.990544) (xy 229.245055 -399.946077)
			(xy 229.27436 -399.905693) (xy 229.291642 -399.887694) (xy 229.521766 -399.65757) (xy 229.539767 -399.640284)
			(xy 229.580139 -399.610952) (xy 229.624602 -399.588297) (xy 229.672062 -399.572876) (xy 229.721351 -399.56507)
			(xy 229.746302 -399.564606) (xy 233.352594 -399.564606) (xy 233.377543 -399.565108) (xy 233.426826 -399.572919)
			(xy 233.474284 -399.588334) (xy 233.51875 -399.610975) (xy 233.559132 -399.640285) (xy 233.57713 -399.65757)
			(xy 233.798872 -399.879312) (xy 233.816168 -399.897302) (xy 233.845492 -399.937679) (xy 233.868139 -399.982146)
			(xy 233.883552 -400.029608) (xy 233.89135 -400.078897) (xy 233.891836 -400.103848) (xy 233.891836 -403.52091)
			(xy 233.892247 -403.530981) (xy 233.899977 -403.549579) (xy 233.906822 -403.556978) (xy 234.044998 -403.695154)
			(xy 234.062318 -403.713122) (xy 234.091638 -403.753505) (xy 234.114281 -403.797978) (xy 234.129687 -403.845445)
			(xy 234.13748 -403.894737) (xy 234.137962 -403.91969) (xy 234.137962 -404.702518) (xy 234.138361 -404.712591)
			(xy 234.146098 -404.731189) (xy 234.152948 -404.738586) (xy 234.63885 -405.224488) (xy 234.646275 -405.231297)
			(xy 234.664855 -405.239035) (xy 234.674918 -405.239474) (xy 238.514382 -405.239474) (xy 238.524405 -405.239065)
			(xy 238.542927 -405.231396) (xy 238.557101 -405.21722) (xy 238.564767 -405.198697) (xy 238.565182 -405.188674)
			(xy 238.565182 -394.001498) (xy 238.565686 -393.976549) (xy 238.573497 -393.927266) (xy 238.588912 -393.879809)
			(xy 238.611553 -393.835343) (xy 238.640862 -393.79496) (xy 238.658146 -393.776962) (xy 238.727234 -393.707874)
			(xy 238.733961 -393.700496) (xy 238.741558 -393.682047) (xy 238.741546 -393.662096) (xy 238.733929 -393.643656)
			(xy 238.727234 -393.636246) (xy 238.579914 -393.488672) (xy 238.553014 -393.461125) (xy 238.504928 -393.400988)
			(xy 238.463885 -393.33584) (xy 238.430403 -393.266502) (xy 238.404904 -393.193848) (xy 238.387709 -393.118794)
			(xy 238.379036 -393.042285) (xy 238.378492 -393.003786) (xy 238.378492 -384.337306) (xy 238.379215 -384.306679)
			(xy 238.390978 -384.246564) (xy 238.40186 -384.217926) (xy 238.457994 -384.079496) (xy 238.466633 -384.059188)
			(xy 238.488684 -384.020961) (xy 238.515818 -383.986157) (xy 238.5314 -383.97053) (xy 238.583216 -383.920746)
			(xy 238.583724 -383.920238) (xy 239.05718 -383.446782) (xy 239.084743 -383.419899) (xy 239.144878 -383.371812)
			(xy 239.210023 -383.330768) (xy 239.279359 -383.297284) (xy 239.35201 -383.271782) (xy 239.427061 -383.254584)
			(xy 239.503568 -383.245906) (xy 239.542066 -383.24536) (xy 273.481546 -383.24536) (xy 273.512174 -383.24607)
			(xy 273.572289 -383.257841) (xy 273.600926 -383.268728) (xy 273.739356 -383.324862) (xy 273.759667 -383.333494)
			(xy 273.797892 -383.355549) (xy 273.832695 -383.382685) (xy 273.848322 -383.398268) (xy 273.898106 -383.450084)
			(xy 273.898614 -383.450592) (xy 274.11807 -383.670048) (xy 274.141946 -383.69494) (xy 274.148804 -383.70256)
			(xy 274.167854 -383.71145) (xy 274.251674 -383.713482) (xy 274.262067 -383.713236) (xy 274.281342 -383.705512)
			(xy 274.289012 -383.698496) (xy 274.649184 -383.338324) (xy 274.667186 -383.321041) (xy 274.70756 -383.291715)
			(xy 274.752024 -383.269066) (xy 274.799483 -383.25365) (xy 274.84877 -383.245848) (xy 274.87372 -383.24536)
			(xy 280.202132 -383.24536) (xy 280.227081 -383.245851) (xy 280.276364 -383.253667) (xy 280.323821 -383.269085)
			(xy 280.368287 -383.291728) (xy 280.40867 -383.321039) (xy 280.426668 -383.338324) (xy 281.135836 -384.047492)
			(xy 281.153135 -384.065481) (xy 281.182465 -384.105856) (xy 281.205118 -384.150322) (xy 281.220536 -384.197785)
			(xy 281.228338 -384.247076) (xy 281.2288 -384.272028) (xy 281.2288 -384.869944) (xy 287.06878 -384.869944)
			(xy 287.072752 -384.691701) (xy 287.08466 -384.513812) (xy 287.104481 -384.33663) (xy 287.132175 -384.160506)
			(xy 287.167687 -383.985791) (xy 287.210947 -383.812832) (xy 287.261869 -383.641971) (xy 287.320352 -383.473549)
			(xy 287.386279 -383.307899) (xy 287.45952 -383.14535) (xy 287.53993 -382.986225) (xy 287.627348 -382.83084)
			(xy 287.721601 -382.679504) (xy 287.822502 -382.532516) (xy 287.929851 -382.390169) (xy 288.043434 -382.252746)
			(xy 288.163027 -382.120519) (xy 288.288391 -381.99375) (xy 288.419278 -381.872692) (xy 288.555427 -381.757585)
			(xy 288.696569 -381.648657) (xy 288.842424 -381.546125) (xy 288.992701 -381.450191) (xy 289.147102 -381.361048)
			(xy 289.305321 -381.278871) (xy 289.467044 -381.203823) (xy 289.631949 -381.136055) (xy 289.79971 -381.075699)
			(xy 289.969993 -381.022877) (xy 290.14246 -380.977693) (xy 290.316768 -380.940236) (xy 290.492572 -380.910582)
			(xy 290.669522 -380.888789) (xy 290.847268 -380.874899) (xy 291.025455 -380.868942) (xy 291.203732 -380.870928)
			(xy 291.381743 -380.880854) (xy 291.559135 -380.8987) (xy 291.735555 -380.92443) (xy 291.910655 -380.957994)
			(xy 292.084086 -380.999324) (xy 292.255503 -381.04834) (xy 292.424566 -381.104942) (xy 292.590941 -381.16902)
			(xy 292.754295 -381.240446) (xy 292.914306 -381.319078) (xy 293.070655 -381.404759) (xy 293.223032 -381.497321)
			(xy 293.371135 -381.596578) (xy 293.514669 -381.702335) (xy 293.58726 -381.760984) (xy 298.797472 -381.760984)
			(xy 298.797472 -381.07493) (xy 298.797934 -381.062839) (xy 298.805386 -381.039834) (xy 298.819573 -381.020251)
			(xy 298.83911 -381.006) (xy 298.86209 -380.998473) (xy 298.87418 -380.997968) (xy 299.068744 -380.997968)
			(xy 299.07987 -380.998377) (xy 299.101167 -381.004839) (xy 299.110654 -381.010668) (xy 299.404278 -381.2032)
			(xy 299.413661 -381.208904) (xy 299.434674 -381.21524) (xy 299.456621 -381.215314) (xy 299.477676 -381.209119)
			(xy 299.487082 -381.203454) (xy 299.783246 -381.010668) (xy 299.792735 -381.00485) (xy 299.814033 -380.998408)
			(xy 299.825156 -380.997968) (xy 300.01972 -380.997968) (xy 300.031793 -380.998447) (xy 300.054757 -381.005912)
			(xy 300.074291 -381.020106) (xy 300.088486 -381.03964) (xy 300.095952 -381.062603) (xy 300.096428 -381.074676)
			(xy 300.096428 -381.76073) (xy 300.096419 -381.760984) (xy 305.604672 -381.760984) (xy 305.604672 -381.07493)
			(xy 305.605134 -381.062839) (xy 305.612586 -381.039834) (xy 305.626773 -381.020251) (xy 305.64631 -381.006)
			(xy 305.66929 -380.998473) (xy 305.68138 -380.997968) (xy 305.875944 -380.997968) (xy 305.88707 -380.998377)
			(xy 305.908367 -381.004839) (xy 305.917854 -381.010668) (xy 306.211478 -381.2032) (xy 306.220861 -381.208904)
			(xy 306.241874 -381.21524) (xy 306.263821 -381.215314) (xy 306.284876 -381.209119) (xy 306.294282 -381.203454)
			(xy 306.590446 -381.010668) (xy 306.599935 -381.00485) (xy 306.621233 -380.998408) (xy 306.632356 -380.997968)
			(xy 306.82692 -380.997968) (xy 306.838993 -380.998447) (xy 306.861957 -381.005912) (xy 306.881491 -381.020106)
			(xy 306.895686 -381.03964) (xy 306.903152 -381.062603) (xy 306.903628 -381.074676) (xy 306.903628 -381.76073)
			(xy 306.903619 -381.760984) (xy 312.411872 -381.760984) (xy 312.411872 -381.07493) (xy 312.412334 -381.062839)
			(xy 312.419786 -381.039834) (xy 312.433973 -381.020251) (xy 312.45351 -381.006) (xy 312.47649 -380.998473)
			(xy 312.48858 -380.997968) (xy 312.683144 -380.997968) (xy 312.69427 -380.998377) (xy 312.715567 -381.004839)
			(xy 312.725054 -381.010668) (xy 313.018678 -381.2032) (xy 313.028061 -381.208904) (xy 313.049074 -381.21524)
			(xy 313.071021 -381.215314) (xy 313.092076 -381.209119) (xy 313.101482 -381.203454) (xy 313.397646 -381.010668)
			(xy 313.407135 -381.00485) (xy 313.428433 -380.998408) (xy 313.439556 -380.997968) (xy 313.63412 -380.997968)
			(xy 313.646193 -380.998447) (xy 313.669157 -381.005912) (xy 313.688691 -381.020106) (xy 313.702886 -381.03964)
			(xy 313.710352 -381.062603) (xy 313.710828 -381.074676) (xy 313.710828 -381.76073) (xy 313.710819 -381.760984)
			(xy 319.219072 -381.760984) (xy 319.219072 -381.07493) (xy 319.219534 -381.062839) (xy 319.226986 -381.039834)
			(xy 319.241173 -381.020251) (xy 319.26071 -381.006) (xy 319.28369 -380.998473) (xy 319.29578 -380.997968)
			(xy 319.490344 -380.997968) (xy 319.50147 -380.998377) (xy 319.522767 -381.004839) (xy 319.532254 -381.010668)
			(xy 319.825878 -381.2032) (xy 319.835261 -381.208904) (xy 319.856274 -381.21524) (xy 319.878221 -381.215314)
			(xy 319.899276 -381.209119) (xy 319.908682 -381.203454) (xy 320.204846 -381.010668) (xy 320.214335 -381.00485)
			(xy 320.235633 -380.998408) (xy 320.246756 -380.997968) (xy 320.44132 -380.997968) (xy 320.453393 -380.998447)
			(xy 320.476357 -381.005912) (xy 320.495891 -381.020106) (xy 320.510086 -381.03964) (xy 320.517552 -381.062603)
			(xy 320.518028 -381.074676) (xy 320.518028 -381.76073) (xy 320.518019 -381.760984) (xy 331.32522 -381.760984)
			(xy 331.32522 -381.07493) (xy 331.325733 -381.062844) (xy 331.333179 -381.039848) (xy 331.347354 -381.020269)
			(xy 331.366877 -381.006017) (xy 331.389844 -380.99848) (xy 331.401928 -380.997968) (xy 331.596492 -380.997968)
			(xy 331.607616 -380.998398) (xy 331.628913 -381.004846) (xy 331.638402 -381.010668) (xy 331.932026 -381.2032)
			(xy 331.941386 -381.208946) (xy 331.96241 -381.215273) (xy 331.984365 -381.215335) (xy 332.005424 -381.209126)
			(xy 332.01483 -381.203454) (xy 332.310994 -381.010668) (xy 332.320494 -381.004869) (xy 332.341784 -380.998415)
			(xy 332.352904 -380.997968) (xy 332.547468 -380.997968) (xy 332.559547 -380.99844) (xy 332.582524 -381.005895)
			(xy 332.602073 -381.020087) (xy 332.616279 -381.039626) (xy 332.623752 -381.062598) (xy 332.624176 -381.074676)
			(xy 332.624176 -381.76073) (xy 332.624166 -381.760984) (xy 338.13242 -381.760984) (xy 338.13242 -381.07493)
			(xy 338.132933 -381.062844) (xy 338.140379 -381.039848) (xy 338.154554 -381.020269) (xy 338.174077 -381.006017)
			(xy 338.197044 -380.99848) (xy 338.209128 -380.997968) (xy 338.403692 -380.997968) (xy 338.414816 -380.998398)
			(xy 338.436113 -381.004846) (xy 338.445602 -381.010668) (xy 338.739226 -381.2032) (xy 338.748586 -381.208946)
			(xy 338.76961 -381.215273) (xy 338.791565 -381.215335) (xy 338.812624 -381.209126) (xy 338.82203 -381.203454)
			(xy 339.118194 -381.010668) (xy 339.127694 -381.004869) (xy 339.148984 -380.998415) (xy 339.160104 -380.997968)
			(xy 339.354668 -380.997968) (xy 339.366747 -380.99844) (xy 339.389724 -381.005895) (xy 339.409273 -381.020087)
			(xy 339.423479 -381.039626) (xy 339.430952 -381.062598) (xy 339.431376 -381.074676) (xy 339.431376 -381.76073)
			(xy 339.431366 -381.760984) (xy 344.93962 -381.760984) (xy 344.93962 -381.07493) (xy 344.940133 -381.062844)
			(xy 344.947579 -381.039848) (xy 344.961754 -381.020269) (xy 344.981277 -381.006017) (xy 345.004244 -380.99848)
			(xy 345.016328 -380.997968) (xy 345.210892 -380.997968) (xy 345.222016 -380.998398) (xy 345.243313 -381.004846)
			(xy 345.252802 -381.010668) (xy 345.546426 -381.2032) (xy 345.555786 -381.208946) (xy 345.57681 -381.215273)
			(xy 345.598765 -381.215335) (xy 345.619824 -381.209126) (xy 345.62923 -381.203454) (xy 345.925394 -381.010668)
			(xy 345.934894 -381.004869) (xy 345.956184 -380.998415) (xy 345.967304 -380.997968) (xy 346.161868 -380.997968)
			(xy 346.173947 -380.99844) (xy 346.196924 -381.005895) (xy 346.216473 -381.020087) (xy 346.230679 -381.039626)
			(xy 346.238152 -381.062598) (xy 346.238576 -381.074676) (xy 346.238576 -381.76073) (xy 346.238566 -381.760984)
			(xy 351.74682 -381.760984) (xy 351.74682 -381.07493) (xy 351.747333 -381.062844) (xy 351.754779 -381.039848)
			(xy 351.768954 -381.020269) (xy 351.788477 -381.006017) (xy 351.811444 -380.99848) (xy 351.823528 -380.997968)
			(xy 352.018092 -380.997968) (xy 352.029216 -380.998398) (xy 352.050513 -381.004846) (xy 352.060002 -381.010668)
			(xy 352.353626 -381.2032) (xy 352.362986 -381.208946) (xy 352.38401 -381.215273) (xy 352.405965 -381.215335)
			(xy 352.427024 -381.209126) (xy 352.43643 -381.203454) (xy 352.732594 -381.010668) (xy 352.742094 -381.004869)
			(xy 352.763384 -380.998415) (xy 352.774504 -380.997968) (xy 352.969068 -380.997968) (xy 352.981147 -380.99844)
			(xy 353.004124 -381.005895) (xy 353.023673 -381.020087) (xy 353.037879 -381.039626) (xy 353.045352 -381.062598)
			(xy 353.045776 -381.074676) (xy 353.045776 -381.76073) (xy 365.89716 -381.76073) (xy 365.89716 -381.07493)
			(xy 365.897586 -381.062807) (xy 365.905072 -381.039745) (xy 365.919322 -381.020128) (xy 365.938938 -381.005876)
			(xy 365.961999 -380.998387) (xy 365.974122 -380.997968) (xy 366.168686 -380.997968) (xy 366.17981 -380.998401)
			(xy 366.201107 -381.004847) (xy 366.210596 -381.010668) (xy 366.50422 -381.2032) (xy 366.513583 -381.20894)
			(xy 366.534605 -381.215269) (xy 366.55656 -381.215332) (xy 366.577618 -381.209125) (xy 366.587024 -381.203454)
			(xy 366.883188 -381.010668) (xy 366.892689 -381.004871) (xy 366.913978 -380.998415) (xy 366.925098 -380.997968)
			(xy 367.119662 -380.997968) (xy 367.131786 -380.998393) (xy 367.154849 -381.005878) (xy 367.174467 -381.020127)
			(xy 367.188718 -381.039744) (xy 367.196206 -381.062806) (xy 367.196624 -381.07493) (xy 367.196624 -381.76073)
			(xy 372.70436 -381.76073) (xy 372.70436 -381.07493) (xy 372.704786 -381.062807) (xy 372.712272 -381.039745)
			(xy 372.726522 -381.020128) (xy 372.746138 -381.005876) (xy 372.769199 -380.998387) (xy 372.781322 -380.997968)
			(xy 372.975886 -380.997968) (xy 372.98701 -380.998401) (xy 373.008307 -381.004847) (xy 373.017796 -381.010668)
			(xy 373.31142 -381.2032) (xy 373.320783 -381.20894) (xy 373.341805 -381.215269) (xy 373.36376 -381.215332)
			(xy 373.384818 -381.209125) (xy 373.394224 -381.203454) (xy 373.690388 -381.010668) (xy 373.699889 -381.004871)
			(xy 373.721178 -380.998415) (xy 373.732298 -380.997968) (xy 373.926862 -380.997968) (xy 373.938986 -380.998393)
			(xy 373.962049 -381.005878) (xy 373.981667 -381.020127) (xy 373.995918 -381.039744) (xy 374.003406 -381.062806)
			(xy 374.003824 -381.07493) (xy 374.003824 -381.76073) (xy 379.51156 -381.76073) (xy 379.51156 -381.07493)
			(xy 379.511986 -381.062807) (xy 379.519472 -381.039745) (xy 379.533722 -381.020128) (xy 379.553338 -381.005876)
			(xy 379.576399 -380.998387) (xy 379.588522 -380.997968) (xy 379.783086 -380.997968) (xy 379.79421 -380.998401)
			(xy 379.815507 -381.004847) (xy 379.824996 -381.010668) (xy 380.11862 -381.2032) (xy 380.127983 -381.20894)
			(xy 380.149005 -381.215269) (xy 380.17096 -381.215332) (xy 380.192018 -381.209125) (xy 380.201424 -381.203454)
			(xy 380.497588 -381.010668) (xy 380.507089 -381.004871) (xy 380.528378 -380.998415) (xy 380.539498 -380.997968)
			(xy 380.734062 -380.997968) (xy 380.746186 -380.998393) (xy 380.769249 -381.005878) (xy 380.788867 -381.020127)
			(xy 380.803118 -381.039744) (xy 380.810606 -381.062806) (xy 380.811024 -381.07493) (xy 380.811024 -381.76073)
			(xy 386.31876 -381.76073) (xy 386.31876 -381.07493) (xy 386.319186 -381.062807) (xy 386.326672 -381.039745)
			(xy 386.340922 -381.020128) (xy 386.360538 -381.005876) (xy 386.383599 -380.998387) (xy 386.395722 -380.997968)
			(xy 386.590286 -380.997968) (xy 386.60141 -380.998401) (xy 386.622707 -381.004847) (xy 386.632196 -381.010668)
			(xy 386.92582 -381.2032) (xy 386.935183 -381.20894) (xy 386.956205 -381.215269) (xy 386.97816 -381.215332)
			(xy 386.999218 -381.209125) (xy 387.008624 -381.203454) (xy 387.304788 -381.010668) (xy 387.314289 -381.004871)
			(xy 387.335578 -380.998415) (xy 387.346698 -380.997968) (xy 387.541262 -380.997968) (xy 387.553386 -380.998393)
			(xy 387.576449 -381.005878) (xy 387.596067 -381.020127) (xy 387.610318 -381.039744) (xy 387.617806 -381.062806)
			(xy 387.618224 -381.07493) (xy 387.618224 -381.76073) (xy 398.424908 -381.76073) (xy 398.424908 -381.07493)
			(xy 398.425437 -381.06282) (xy 398.432912 -381.039783) (xy 398.44714 -381.020183) (xy 398.466729 -381.00594)
			(xy 398.48976 -380.998446) (xy 398.50187 -380.997968) (xy 398.696434 -380.997968) (xy 398.70756 -380.998381)
			(xy 398.728857 -381.00484) (xy 398.738344 -381.010668) (xy 399.031968 -381.2032) (xy 399.041356 -381.208896)
			(xy 399.062366 -381.215234) (xy 399.084312 -381.21531) (xy 399.105366 -381.209117) (xy 399.114772 -381.203454)
			(xy 399.410936 -381.010668) (xy 399.420427 -381.004854) (xy 399.441724 -380.998409) (xy 399.452846 -380.997968)
			(xy 399.64741 -380.997968) (xy 399.659536 -380.998352) (xy 399.6826 -381.005851) (xy 399.702218 -381.020111)
			(xy 399.716468 -381.039735) (xy 399.723954 -381.062804) (xy 399.724372 -381.07493) (xy 399.724372 -381.76073)
			(xy 405.232108 -381.76073) (xy 405.232108 -381.07493) (xy 405.232637 -381.06282) (xy 405.240112 -381.039783)
			(xy 405.25434 -381.020183) (xy 405.273929 -381.00594) (xy 405.29696 -380.998446) (xy 405.30907 -380.997968)
			(xy 405.503634 -380.997968) (xy 405.51476 -380.998381) (xy 405.536057 -381.00484) (xy 405.545544 -381.010668)
			(xy 405.839168 -381.2032) (xy 405.848556 -381.208896) (xy 405.869566 -381.215234) (xy 405.891512 -381.21531)
			(xy 405.912566 -381.209117) (xy 405.921972 -381.203454) (xy 406.218136 -381.010668) (xy 406.227627 -381.004854)
			(xy 406.248924 -380.998409) (xy 406.260046 -380.997968) (xy 406.45461 -380.997968) (xy 406.466736 -380.998352)
			(xy 406.4898 -381.005851) (xy 406.509418 -381.020111) (xy 406.523668 -381.039735) (xy 406.531154 -381.062804)
			(xy 406.531572 -381.07493) (xy 406.531572 -381.76073) (xy 412.039308 -381.76073) (xy 412.039308 -381.07493)
			(xy 412.039837 -381.06282) (xy 412.047312 -381.039783) (xy 412.06154 -381.020183) (xy 412.081129 -381.00594)
			(xy 412.10416 -380.998446) (xy 412.11627 -380.997968) (xy 412.310834 -380.997968) (xy 412.32196 -380.998381)
			(xy 412.343257 -381.00484) (xy 412.352744 -381.010668) (xy 412.646368 -381.2032) (xy 412.655756 -381.208896)
			(xy 412.676766 -381.215234) (xy 412.698712 -381.21531) (xy 412.719766 -381.209117) (xy 412.729172 -381.203454)
			(xy 413.025336 -381.010668) (xy 413.034827 -381.004854) (xy 413.056124 -380.998409) (xy 413.067246 -380.997968)
			(xy 413.26181 -380.997968) (xy 413.273936 -380.998352) (xy 413.297 -381.005851) (xy 413.316618 -381.020111)
			(xy 413.330868 -381.039735) (xy 413.338354 -381.062804) (xy 413.338772 -381.07493) (xy 413.338772 -381.76073)
			(xy 418.846508 -381.76073) (xy 418.846508 -381.07493) (xy 418.847037 -381.06282) (xy 418.854512 -381.039783)
			(xy 418.86874 -381.020183) (xy 418.888329 -381.00594) (xy 418.91136 -380.998446) (xy 418.92347 -380.997968)
			(xy 419.118034 -380.997968) (xy 419.12916 -380.998381) (xy 419.150457 -381.00484) (xy 419.159944 -381.010668)
			(xy 419.453568 -381.2032) (xy 419.462956 -381.208896) (xy 419.483966 -381.215234) (xy 419.505912 -381.21531)
			(xy 419.526966 -381.209117) (xy 419.536372 -381.203454) (xy 419.832536 -381.010668) (xy 419.842027 -381.004854)
			(xy 419.863324 -380.998409) (xy 419.874446 -380.997968) (xy 420.06901 -380.997968) (xy 420.081136 -380.998352)
			(xy 420.1042 -381.005851) (xy 420.123818 -381.020111) (xy 420.138068 -381.039735) (xy 420.145554 -381.062804)
			(xy 420.145972 -381.07493) (xy 420.145972 -381.76073) (xy 420.145514 -381.772845) (xy 420.13802 -381.795888)
			(xy 420.123774 -381.815488) (xy 420.10417 -381.829729) (xy 420.081125 -381.837217) (xy 420.06901 -381.837692)
			(xy 419.874446 -381.837692) (xy 419.86332 -381.837278) (xy 419.842024 -381.830818) (xy 419.832536 -381.824992)
			(xy 419.537642 -381.63246) (xy 419.528255 -381.626757) (xy 419.507217 -381.620484) (xy 419.485263 -381.620484)
			(xy 419.464225 -381.626757) (xy 419.454838 -381.63246) (xy 419.161214 -381.824992) (xy 419.151711 -381.830784)
			(xy 419.130424 -381.837243) (xy 419.119304 -381.837692) (xy 418.92347 -381.837692) (xy 418.911357 -381.837214)
			(xy 418.888318 -381.829723) (xy 418.868719 -381.815481) (xy 418.854477 -381.795882) (xy 418.846986 -381.772843)
			(xy 418.846508 -381.76073) (xy 413.338772 -381.76073) (xy 413.338314 -381.772845) (xy 413.33082 -381.795888)
			(xy 413.316574 -381.815488) (xy 413.29697 -381.829729) (xy 413.273925 -381.837217) (xy 413.26181 -381.837692)
			(xy 413.067246 -381.837692) (xy 413.05612 -381.837278) (xy 413.034824 -381.830818) (xy 413.025336 -381.824992)
			(xy 412.730442 -381.63246) (xy 412.721055 -381.626757) (xy 412.700017 -381.620484) (xy 412.678063 -381.620484)
			(xy 412.657025 -381.626757) (xy 412.647638 -381.63246) (xy 412.354014 -381.824992) (xy 412.344511 -381.830784)
			(xy 412.323224 -381.837243) (xy 412.312104 -381.837692) (xy 412.11627 -381.837692) (xy 412.104157 -381.837214)
			(xy 412.081118 -381.829723) (xy 412.061519 -381.815481) (xy 412.047277 -381.795882) (xy 412.039786 -381.772843)
			(xy 412.039308 -381.76073) (xy 406.531572 -381.76073) (xy 406.531114 -381.772845) (xy 406.52362 -381.795888)
			(xy 406.509374 -381.815488) (xy 406.48977 -381.829729) (xy 406.466725 -381.837217) (xy 406.45461 -381.837692)
			(xy 406.260046 -381.837692) (xy 406.24892 -381.837278) (xy 406.227624 -381.830818) (xy 406.218136 -381.824992)
			(xy 405.923242 -381.63246) (xy 405.913855 -381.626757) (xy 405.892817 -381.620484) (xy 405.870863 -381.620484)
			(xy 405.849825 -381.626757) (xy 405.840438 -381.63246) (xy 405.546814 -381.824992) (xy 405.537311 -381.830784)
			(xy 405.516024 -381.837243) (xy 405.504904 -381.837692) (xy 405.30907 -381.837692) (xy 405.296957 -381.837214)
			(xy 405.273918 -381.829723) (xy 405.254319 -381.815481) (xy 405.240077 -381.795882) (xy 405.232586 -381.772843)
			(xy 405.232108 -381.76073) (xy 399.724372 -381.76073) (xy 399.723914 -381.772845) (xy 399.71642 -381.795888)
			(xy 399.702174 -381.815488) (xy 399.68257 -381.829729) (xy 399.659525 -381.837217) (xy 399.64741 -381.837692)
			(xy 399.452846 -381.837692) (xy 399.44172 -381.837278) (xy 399.420424 -381.830818) (xy 399.410936 -381.824992)
			(xy 399.116042 -381.63246) (xy 399.106655 -381.626757) (xy 399.085617 -381.620484) (xy 399.063663 -381.620484)
			(xy 399.042625 -381.626757) (xy 399.033238 -381.63246) (xy 398.739614 -381.824992) (xy 398.730111 -381.830784)
			(xy 398.708824 -381.837243) (xy 398.697704 -381.837692) (xy 398.50187 -381.837692) (xy 398.489757 -381.837214)
			(xy 398.466718 -381.829723) (xy 398.447119 -381.815481) (xy 398.432877 -381.795882) (xy 398.425386 -381.772843)
			(xy 398.424908 -381.76073) (xy 387.618224 -381.76073) (xy 387.617865 -381.772858) (xy 387.61036 -381.795924)
			(xy 387.596094 -381.815542) (xy 387.576463 -381.829791) (xy 387.553391 -381.837276) (xy 387.541262 -381.837692)
			(xy 387.346698 -381.837692) (xy 387.335574 -381.837257) (xy 387.314277 -381.830812) (xy 387.304788 -381.824992)
			(xy 387.009894 -381.63246) (xy 387.000507 -381.626757) (xy 386.979469 -381.620484) (xy 386.957515 -381.620484)
			(xy 386.936477 -381.626757) (xy 386.92709 -381.63246) (xy 386.633466 -381.824992) (xy 386.623972 -381.830802)
			(xy 386.602678 -381.83725) (xy 386.591556 -381.837692) (xy 386.395722 -381.837692) (xy 386.383612 -381.83717)
			(xy 386.360574 -381.829692) (xy 386.340975 -381.815462) (xy 386.326731 -381.795872) (xy 386.319238 -381.77284)
			(xy 386.31876 -381.76073) (xy 380.811024 -381.76073) (xy 380.810665 -381.772858) (xy 380.80316 -381.795924)
			(xy 380.788894 -381.815542) (xy 380.769263 -381.829791) (xy 380.746191 -381.837276) (xy 380.734062 -381.837692)
			(xy 380.539498 -381.837692) (xy 380.528374 -381.837257) (xy 380.507077 -381.830812) (xy 380.497588 -381.824992)
			(xy 380.202694 -381.63246) (xy 380.193307 -381.626757) (xy 380.172269 -381.620484) (xy 380.150315 -381.620484)
			(xy 380.129277 -381.626757) (xy 380.11989 -381.63246) (xy 379.826266 -381.824992) (xy 379.816772 -381.830802)
			(xy 379.795478 -381.83725) (xy 379.784356 -381.837692) (xy 379.588522 -381.837692) (xy 379.576412 -381.83717)
			(xy 379.553374 -381.829692) (xy 379.533775 -381.815462) (xy 379.519531 -381.795872) (xy 379.512038 -381.77284)
			(xy 379.51156 -381.76073) (xy 374.003824 -381.76073) (xy 374.003465 -381.772858) (xy 373.99596 -381.795924)
			(xy 373.981694 -381.815542) (xy 373.962063 -381.829791) (xy 373.938991 -381.837276) (xy 373.926862 -381.837692)
			(xy 373.732298 -381.837692) (xy 373.721174 -381.837257) (xy 373.699877 -381.830812) (xy 373.690388 -381.824992)
			(xy 373.395494 -381.63246) (xy 373.386107 -381.626757) (xy 373.365069 -381.620484) (xy 373.343115 -381.620484)
			(xy 373.322077 -381.626757) (xy 373.31269 -381.63246) (xy 373.019066 -381.824992) (xy 373.009572 -381.830802)
			(xy 372.988278 -381.83725) (xy 372.977156 -381.837692) (xy 372.781322 -381.837692) (xy 372.769212 -381.83717)
			(xy 372.746174 -381.829692) (xy 372.726575 -381.815462) (xy 372.712331 -381.795872) (xy 372.704838 -381.77284)
			(xy 372.70436 -381.76073) (xy 367.196624 -381.76073) (xy 367.196265 -381.772858) (xy 367.18876 -381.795924)
			(xy 367.174494 -381.815542) (xy 367.154863 -381.829791) (xy 367.131791 -381.837276) (xy 367.119662 -381.837692)
			(xy 366.925098 -381.837692) (xy 366.913974 -381.837257) (xy 366.892677 -381.830812) (xy 366.883188 -381.824992)
			(xy 366.588294 -381.63246) (xy 366.578907 -381.626757) (xy 366.557869 -381.620484) (xy 366.535915 -381.620484)
			(xy 366.514877 -381.626757) (xy 366.50549 -381.63246) (xy 366.211866 -381.824992) (xy 366.202372 -381.830802)
			(xy 366.181078 -381.83725) (xy 366.169956 -381.837692) (xy 365.974122 -381.837692) (xy 365.962012 -381.83717)
			(xy 365.938974 -381.829692) (xy 365.919375 -381.815462) (xy 365.905131 -381.795872) (xy 365.897638 -381.77284)
			(xy 365.89716 -381.76073) (xy 353.045776 -381.76073) (xy 353.045319 -381.77282) (xy 353.037856 -381.795819)
			(xy 353.023666 -381.815397) (xy 353.004132 -381.829647) (xy 352.981156 -381.837181) (xy 352.969068 -381.837692)
			(xy 352.774504 -381.837692) (xy 352.76338 -381.837255) (xy 352.742084 -381.830811) (xy 352.732594 -381.824992)
			(xy 352.4377 -381.63246) (xy 352.428313 -381.626757) (xy 352.407275 -381.620484) (xy 352.385321 -381.620484)
			(xy 352.364283 -381.626757) (xy 352.354896 -381.63246) (xy 352.061272 -381.824992) (xy 352.051777 -381.8308)
			(xy 352.030484 -381.837249) (xy 352.019362 -381.837692) (xy 351.823528 -381.837692) (xy 351.811445 -381.837263)
			(xy 351.788461 -381.829801) (xy 351.768909 -381.8156) (xy 351.754704 -381.79605) (xy 351.747239 -381.773067)
			(xy 351.74682 -381.760984) (xy 346.238566 -381.760984) (xy 346.238119 -381.77282) (xy 346.230656 -381.795819)
			(xy 346.216466 -381.815397) (xy 346.196932 -381.829647) (xy 346.173956 -381.837181) (xy 346.161868 -381.837692)
			(xy 345.967304 -381.837692) (xy 345.95618 -381.837255) (xy 345.934884 -381.830811) (xy 345.925394 -381.824992)
			(xy 345.6305 -381.63246) (xy 345.621113 -381.626757) (xy 345.600075 -381.620484) (xy 345.578121 -381.620484)
			(xy 345.557083 -381.626757) (xy 345.547696 -381.63246) (xy 345.254072 -381.824992) (xy 345.244577 -381.8308)
			(xy 345.223284 -381.837249) (xy 345.212162 -381.837692) (xy 345.016328 -381.837692) (xy 345.004245 -381.837263)
			(xy 344.981261 -381.829801) (xy 344.961709 -381.8156) (xy 344.947504 -381.79605) (xy 344.940039 -381.773067)
			(xy 344.93962 -381.760984) (xy 339.431366 -381.760984) (xy 339.430919 -381.77282) (xy 339.423456 -381.795819)
			(xy 339.409266 -381.815397) (xy 339.389732 -381.829647) (xy 339.366756 -381.837181) (xy 339.354668 -381.837692)
			(xy 339.160104 -381.837692) (xy 339.14898 -381.837255) (xy 339.127684 -381.830811) (xy 339.118194 -381.824992)
			(xy 338.8233 -381.63246) (xy 338.813913 -381.626757) (xy 338.792875 -381.620484) (xy 338.770921 -381.620484)
			(xy 338.749883 -381.626757) (xy 338.740496 -381.63246) (xy 338.446872 -381.824992) (xy 338.437377 -381.8308)
			(xy 338.416084 -381.837249) (xy 338.404962 -381.837692) (xy 338.209128 -381.837692) (xy 338.197045 -381.837263)
			(xy 338.174061 -381.829801) (xy 338.154509 -381.8156) (xy 338.140304 -381.79605) (xy 338.132839 -381.773067)
			(xy 338.13242 -381.760984) (xy 332.624166 -381.760984) (xy 332.623719 -381.77282) (xy 332.616256 -381.795819)
			(xy 332.602066 -381.815397) (xy 332.582532 -381.829647) (xy 332.559556 -381.837181) (xy 332.547468 -381.837692)
			(xy 332.352904 -381.837692) (xy 332.34178 -381.837255) (xy 332.320484 -381.830811) (xy 332.310994 -381.824992)
			(xy 332.0161 -381.63246) (xy 332.006713 -381.626757) (xy 331.985675 -381.620484) (xy 331.963721 -381.620484)
			(xy 331.942683 -381.626757) (xy 331.933296 -381.63246) (xy 331.639672 -381.824992) (xy 331.630177 -381.8308)
			(xy 331.608884 -381.837249) (xy 331.597762 -381.837692) (xy 331.401928 -381.837692) (xy 331.389845 -381.837263)
			(xy 331.366861 -381.829801) (xy 331.347309 -381.8156) (xy 331.333104 -381.79605) (xy 331.325639 -381.773067)
			(xy 331.32522 -381.760984) (xy 320.518019 -381.760984) (xy 320.517618 -381.772824) (xy 320.510149 -381.795831)
			(xy 320.495949 -381.815414) (xy 320.476402 -381.829662) (xy 320.453413 -381.837188) (xy 320.44132 -381.837692)
			(xy 320.246756 -381.837692) (xy 320.235631 -381.837274) (xy 320.214334 -381.830817) (xy 320.204846 -381.824992)
			(xy 319.909952 -381.63246) (xy 319.900565 -381.626757) (xy 319.879527 -381.620484) (xy 319.857573 -381.620484)
			(xy 319.836535 -381.626757) (xy 319.827148 -381.63246) (xy 319.533524 -381.824992) (xy 319.524019 -381.83078)
			(xy 319.502733 -381.837242) (xy 319.491614 -381.837692) (xy 319.29578 -381.837692) (xy 319.283703 -381.837252)
			(xy 319.260732 -381.829782) (xy 319.241194 -381.81558) (xy 319.227001 -381.796035) (xy 319.219542 -381.773061)
			(xy 319.219072 -381.760984) (xy 313.710819 -381.760984) (xy 313.710418 -381.772824) (xy 313.702949 -381.795831)
			(xy 313.688749 -381.815414) (xy 313.669202 -381.829662) (xy 313.646213 -381.837188) (xy 313.63412 -381.837692)
			(xy 313.439556 -381.837692) (xy 313.428431 -381.837274) (xy 313.407134 -381.830817) (xy 313.397646 -381.824992)
			(xy 313.102752 -381.63246) (xy 313.093365 -381.626757) (xy 313.072327 -381.620484) (xy 313.050373 -381.620484)
			(xy 313.029335 -381.626757) (xy 313.019948 -381.63246) (xy 312.726324 -381.824992) (xy 312.716819 -381.83078)
			(xy 312.695533 -381.837242) (xy 312.684414 -381.837692) (xy 312.48858 -381.837692) (xy 312.476503 -381.837252)
			(xy 312.453532 -381.829782) (xy 312.433994 -381.81558) (xy 312.419801 -381.796035) (xy 312.412342 -381.773061)
			(xy 312.411872 -381.760984) (xy 306.903619 -381.760984) (xy 306.903218 -381.772824) (xy 306.895749 -381.795831)
			(xy 306.881549 -381.815414) (xy 306.862002 -381.829662) (xy 306.839013 -381.837188) (xy 306.82692 -381.837692)
			(xy 306.632356 -381.837692) (xy 306.621231 -381.837274) (xy 306.599934 -381.830817) (xy 306.590446 -381.824992)
			(xy 306.295552 -381.63246) (xy 306.286165 -381.626757) (xy 306.265127 -381.620484) (xy 306.243173 -381.620484)
			(xy 306.222135 -381.626757) (xy 306.212748 -381.63246) (xy 305.919124 -381.824992) (xy 305.909619 -381.83078)
			(xy 305.888333 -381.837242) (xy 305.877214 -381.837692) (xy 305.68138 -381.837692) (xy 305.669303 -381.837252)
			(xy 305.646332 -381.829782) (xy 305.626794 -381.81558) (xy 305.612601 -381.796035) (xy 305.605142 -381.773061)
			(xy 305.604672 -381.760984) (xy 300.096419 -381.760984) (xy 300.096018 -381.772824) (xy 300.088549 -381.795831)
			(xy 300.074349 -381.815414) (xy 300.054802 -381.829662) (xy 300.031813 -381.837188) (xy 300.01972 -381.837692)
			(xy 299.825156 -381.837692) (xy 299.814031 -381.837274) (xy 299.792734 -381.830817) (xy 299.783246 -381.824992)
			(xy 299.488352 -381.63246) (xy 299.478965 -381.626757) (xy 299.457927 -381.620484) (xy 299.435973 -381.620484)
			(xy 299.414935 -381.626757) (xy 299.405548 -381.63246) (xy 299.111924 -381.824992) (xy 299.102419 -381.83078)
			(xy 299.081133 -381.837242) (xy 299.070014 -381.837692) (xy 298.87418 -381.837692) (xy 298.862103 -381.837252)
			(xy 298.839132 -381.829782) (xy 298.819594 -381.81558) (xy 298.805401 -381.796035) (xy 298.797942 -381.773061)
			(xy 298.797472 -381.760984) (xy 293.58726 -381.760984) (xy 293.653349 -381.81438) (xy 293.7869 -381.932492)
			(xy 293.915057 -382.056436) (xy 294.037566 -382.185966) (xy 294.154183 -382.320825) (xy 294.194727 -382.372167)
			(xy 303.739054 -382.372167) (xy 303.739054 -382.317633) (xy 303.746815 -382.263654) (xy 303.762179 -382.211329)
			(xy 303.784833 -382.161723) (xy 303.814317 -382.115846) (xy 303.850029 -382.074631) (xy 303.891242 -382.038919)
			(xy 303.937119 -382.009435) (xy 303.986725 -381.986781) (xy 304.03905 -381.971416) (xy 304.093029 -381.963655)
			(xy 304.120296 -381.963168) (xy 304.983896 -381.963168) (xy 305.011169 -381.963571) (xy 305.065161 -381.971334)
			(xy 305.117498 -381.986701) (xy 305.167116 -382.00936) (xy 305.213003 -382.03885) (xy 305.254227 -382.07457)
			(xy 305.289948 -382.115793) (xy 305.319438 -382.161681) (xy 305.342098 -382.211298) (xy 305.357466 -382.263635)
			(xy 305.365228 -382.317627) (xy 305.365228 -382.372167) (xy 310.546254 -382.372167) (xy 310.546254 -382.317633)
			(xy 310.554015 -382.263654) (xy 310.569379 -382.211329) (xy 310.592033 -382.161723) (xy 310.621517 -382.115846)
			(xy 310.657229 -382.074631) (xy 310.698442 -382.038919) (xy 310.744319 -382.009435) (xy 310.793925 -381.986781)
			(xy 310.84625 -381.971416) (xy 310.900229 -381.963655) (xy 310.927496 -381.963168) (xy 311.791096 -381.963168)
			(xy 311.818369 -381.963571) (xy 311.872361 -381.971334) (xy 311.924698 -381.986701) (xy 311.974316 -382.00936)
			(xy 312.020203 -382.03885) (xy 312.061427 -382.07457) (xy 312.097148 -382.115793) (xy 312.126638 -382.161681)
			(xy 312.149298 -382.211298) (xy 312.164666 -382.263635) (xy 312.172428 -382.317627) (xy 312.172428 -382.372167)
			(xy 317.353454 -382.372167) (xy 317.353454 -382.317633) (xy 317.361215 -382.263654) (xy 317.376579 -382.211329)
			(xy 317.399233 -382.161723) (xy 317.428717 -382.115846) (xy 317.464429 -382.074631) (xy 317.505642 -382.038919)
			(xy 317.551519 -382.009435) (xy 317.601125 -381.986781) (xy 317.65345 -381.971416) (xy 317.707429 -381.963655)
			(xy 317.734696 -381.963168) (xy 318.598296 -381.963168) (xy 318.625569 -381.963571) (xy 318.679561 -381.971334)
			(xy 318.731898 -381.986701) (xy 318.781516 -382.00936) (xy 318.827403 -382.03885) (xy 318.868627 -382.07457)
			(xy 318.904348 -382.115793) (xy 318.933838 -382.161681) (xy 318.956498 -382.211298) (xy 318.971866 -382.263635)
			(xy 318.979628 -382.317627) (xy 318.979628 -382.372171) (xy 336.266732 -382.372171) (xy 336.266732 -382.317629)
			(xy 336.274494 -382.263643) (xy 336.289861 -382.211311) (xy 336.312521 -382.161698) (xy 336.34201 -382.115816)
			(xy 336.377729 -382.074598) (xy 336.418951 -382.038884) (xy 336.464837 -382.009399) (xy 336.514452 -381.986746)
			(xy 336.566786 -381.971385) (xy 336.620773 -381.963628) (xy 336.648044 -381.963168) (xy 337.511644 -381.963168)
			(xy 337.538913 -381.963598) (xy 337.592897 -381.971365) (xy 337.645225 -381.986735) (xy 337.694833 -382.009396)
			(xy 337.740712 -382.038885) (xy 337.781928 -382.074603) (xy 337.817641 -382.115823) (xy 337.847125 -382.161705)
			(xy 337.86978 -382.211316) (xy 337.885144 -382.263647) (xy 337.892906 -382.31763) (xy 337.892906 -382.37217)
			(xy 337.892906 -382.372171) (xy 343.073932 -382.372171) (xy 343.073932 -382.317629) (xy 343.081694 -382.263643)
			(xy 343.097061 -382.211311) (xy 343.119721 -382.161698) (xy 343.14921 -382.115816) (xy 343.184929 -382.074598)
			(xy 343.226151 -382.038884) (xy 343.272037 -382.009399) (xy 343.321652 -381.986746) (xy 343.373986 -381.971385)
			(xy 343.427973 -381.963628) (xy 343.455244 -381.963168) (xy 344.318844 -381.963168) (xy 344.346113 -381.963598)
			(xy 344.400097 -381.971365) (xy 344.452425 -381.986735) (xy 344.502033 -382.009396) (xy 344.547912 -382.038885)
			(xy 344.589128 -382.074603) (xy 344.624841 -382.115823) (xy 344.654325 -382.161705) (xy 344.67698 -382.211316)
			(xy 344.692344 -382.263647) (xy 344.700106 -382.31763) (xy 344.700106 -382.37217) (xy 344.700106 -382.372171)
			(xy 349.881132 -382.372171) (xy 349.881132 -382.317629) (xy 349.888894 -382.263643) (xy 349.904261 -382.211311)
			(xy 349.926921 -382.161698) (xy 349.95641 -382.115816) (xy 349.992129 -382.074598) (xy 350.033351 -382.038884)
			(xy 350.079237 -382.009399) (xy 350.128852 -381.986746) (xy 350.181186 -381.971385) (xy 350.235173 -381.963628)
			(xy 350.262444 -381.963168) (xy 351.126044 -381.963168) (xy 351.153313 -381.963598) (xy 351.207297 -381.971365)
			(xy 351.259625 -381.986735) (xy 351.309233 -382.009396) (xy 351.355112 -382.038885) (xy 351.396328 -382.074603)
			(xy 351.432041 -382.115823) (xy 351.461525 -382.161705) (xy 351.48418 -382.211316) (xy 351.499544 -382.263647)
			(xy 351.507306 -382.31763) (xy 351.507306 -382.372167) (xy 370.839254 -382.372167) (xy 370.839254 -382.317633)
			(xy 370.847015 -382.263654) (xy 370.862379 -382.21133) (xy 370.885033 -382.161724) (xy 370.914516 -382.115847)
			(xy 370.950227 -382.074633) (xy 370.991441 -382.03892) (xy 371.037317 -382.009437) (xy 371.086922 -381.986782)
			(xy 371.139247 -381.971417) (xy 371.193225 -381.963655) (xy 371.220492 -381.963168) (xy 372.084092 -381.963168)
			(xy 372.111366 -381.963571) (xy 372.165357 -381.971333) (xy 372.217695 -381.9867) (xy 372.267313 -382.009359)
			(xy 372.313202 -382.038848) (xy 372.354426 -382.074568) (xy 372.390147 -382.115792) (xy 372.419638 -382.16168)
			(xy 372.442298 -382.211297) (xy 372.457665 -382.263635) (xy 372.465428 -382.317626) (xy 372.465428 -382.372167)
			(xy 377.646454 -382.372167) (xy 377.646454 -382.317633) (xy 377.654215 -382.263654) (xy 377.669579 -382.21133)
			(xy 377.692233 -382.161724) (xy 377.721716 -382.115847) (xy 377.757427 -382.074633) (xy 377.798641 -382.03892)
			(xy 377.844517 -382.009437) (xy 377.894122 -381.986782) (xy 377.946447 -381.971417) (xy 378.000425 -381.963655)
			(xy 378.027692 -381.963168) (xy 378.891292 -381.963168) (xy 378.918566 -381.963571) (xy 378.972557 -381.971333)
			(xy 379.024895 -381.9867) (xy 379.074513 -382.009359) (xy 379.120402 -382.038848) (xy 379.161626 -382.074568)
			(xy 379.197347 -382.115792) (xy 379.226838 -382.16168) (xy 379.249498 -382.211297) (xy 379.264865 -382.263635)
			(xy 379.272628 -382.317626) (xy 379.272628 -382.372167) (xy 384.453654 -382.372167) (xy 384.453654 -382.317633)
			(xy 384.461415 -382.263654) (xy 384.476779 -382.21133) (xy 384.499433 -382.161724) (xy 384.528916 -382.115847)
			(xy 384.564627 -382.074633) (xy 384.605841 -382.03892) (xy 384.651717 -382.009437) (xy 384.701322 -381.986782)
			(xy 384.753647 -381.971417) (xy 384.807625 -381.963655) (xy 384.834892 -381.963168) (xy 385.698492 -381.963168)
			(xy 385.725766 -381.963571) (xy 385.779757 -381.971333) (xy 385.832095 -381.9867) (xy 385.881713 -382.009359)
			(xy 385.927602 -382.038848) (xy 385.968826 -382.074568) (xy 386.004547 -382.115792) (xy 386.034038 -382.16168)
			(xy 386.056698 -382.211297) (xy 386.072065 -382.263635) (xy 386.079828 -382.317626) (xy 386.079828 -382.372171)
			(xy 403.366932 -382.372171) (xy 403.366932 -382.317629) (xy 403.374694 -382.263643) (xy 403.390061 -382.211311)
			(xy 403.41272 -382.161699) (xy 403.442209 -382.115817) (xy 403.477928 -382.0746) (xy 403.51915 -382.038885)
			(xy 403.565035 -382.009401) (xy 403.614649 -381.986747) (xy 403.666982 -381.971386) (xy 403.720969 -381.963629)
			(xy 403.74824 -381.963168) (xy 404.61184 -381.963168) (xy 404.63911 -381.963597) (xy 404.693093 -381.971364)
			(xy 404.745422 -381.986734) (xy 404.795031 -382.009394) (xy 404.840911 -382.038884) (xy 404.882127 -382.074602)
			(xy 404.91784 -382.115822) (xy 404.947325 -382.161704) (xy 404.96998 -382.211316) (xy 404.985344 -382.263646)
			(xy 404.993106 -382.31763) (xy 404.993106 -382.37217) (xy 404.993106 -382.372171) (xy 410.174132 -382.372171)
			(xy 410.174132 -382.317629) (xy 410.181894 -382.263643) (xy 410.197261 -382.211311) (xy 410.21992 -382.161699)
			(xy 410.249409 -382.115817) (xy 410.285128 -382.0746) (xy 410.32635 -382.038885) (xy 410.372235 -382.009401)
			(xy 410.421849 -381.986747) (xy 410.474182 -381.971386) (xy 410.528169 -381.963629) (xy 410.55544 -381.963168)
			(xy 411.41904 -381.963168) (xy 411.44631 -381.963597) (xy 411.500293 -381.971364) (xy 411.552622 -381.986734)
			(xy 411.602231 -382.009394) (xy 411.648111 -382.038884) (xy 411.689327 -382.074602) (xy 411.72504 -382.115822)
			(xy 411.754525 -382.161704) (xy 411.77718 -382.211316) (xy 411.792544 -382.263646) (xy 411.800306 -382.31763)
			(xy 411.800306 -382.37217) (xy 411.800306 -382.372171) (xy 416.981332 -382.372171) (xy 416.981332 -382.317629)
			(xy 416.989094 -382.263643) (xy 417.004461 -382.211311) (xy 417.02712 -382.161699) (xy 417.056609 -382.115817)
			(xy 417.092328 -382.0746) (xy 417.13355 -382.038885) (xy 417.179435 -382.009401) (xy 417.229049 -381.986747)
			(xy 417.281382 -381.971386) (xy 417.335369 -381.963629) (xy 417.36264 -381.963168) (xy 418.22624 -381.963168)
			(xy 418.25351 -381.963597) (xy 418.307493 -381.971364) (xy 418.359822 -381.986734) (xy 418.409431 -382.009394)
			(xy 418.455311 -382.038884) (xy 418.496527 -382.074602) (xy 418.53224 -382.115822) (xy 418.561725 -382.161704)
			(xy 418.58438 -382.211316) (xy 418.599744 -382.263646) (xy 418.607506 -382.31763) (xy 418.607506 -382.37217)
			(xy 418.599744 -382.426154) (xy 418.58438 -382.478484) (xy 418.561725 -382.528096) (xy 418.53224 -382.573978)
			(xy 418.496527 -382.615198) (xy 418.455311 -382.650916) (xy 418.409431 -382.680406) (xy 418.359822 -382.703066)
			(xy 418.307493 -382.718436) (xy 418.25351 -382.726203) (xy 418.22624 -382.726692) (xy 417.36264 -382.726692)
			(xy 417.335369 -382.726171) (xy 417.281382 -382.718414) (xy 417.229049 -382.703053) (xy 417.179435 -382.680399)
			(xy 417.13355 -382.650915) (xy 417.092328 -382.6152) (xy 417.056609 -382.573983) (xy 417.02712 -382.528101)
			(xy 417.004461 -382.478489) (xy 416.989094 -382.426157) (xy 416.981332 -382.372171) (xy 411.800306 -382.372171)
			(xy 411.792544 -382.426154) (xy 411.77718 -382.478484) (xy 411.754525 -382.528096) (xy 411.72504 -382.573978)
			(xy 411.689327 -382.615198) (xy 411.648111 -382.650916) (xy 411.602231 -382.680406) (xy 411.552622 -382.703066)
			(xy 411.500293 -382.718436) (xy 411.44631 -382.726203) (xy 411.41904 -382.726692) (xy 410.55544 -382.726692)
			(xy 410.528169 -382.726171) (xy 410.474182 -382.718414) (xy 410.421849 -382.703053) (xy 410.372235 -382.680399)
			(xy 410.32635 -382.650915) (xy 410.285128 -382.6152) (xy 410.249409 -382.573983) (xy 410.21992 -382.528101)
			(xy 410.197261 -382.478489) (xy 410.181894 -382.426157) (xy 410.174132 -382.372171) (xy 404.993106 -382.372171)
			(xy 404.985344 -382.426154) (xy 404.96998 -382.478484) (xy 404.947325 -382.528096) (xy 404.91784 -382.573978)
			(xy 404.882127 -382.615198) (xy 404.840911 -382.650916) (xy 404.795031 -382.680406) (xy 404.745422 -382.703066)
			(xy 404.693093 -382.718436) (xy 404.63911 -382.726203) (xy 404.61184 -382.726692) (xy 403.74824 -382.726692)
			(xy 403.720969 -382.726171) (xy 403.666982 -382.718414) (xy 403.614649 -382.703053) (xy 403.565035 -382.680399)
			(xy 403.51915 -382.650915) (xy 403.477928 -382.6152) (xy 403.442209 -382.573983) (xy 403.41272 -382.528101)
			(xy 403.390061 -382.478489) (xy 403.374694 -382.426157) (xy 403.366932 -382.372171) (xy 386.079828 -382.372171)
			(xy 386.079828 -382.372174) (xy 386.072065 -382.426165) (xy 386.056698 -382.478503) (xy 386.034038 -382.52812)
			(xy 386.004547 -382.574008) (xy 385.968826 -382.615232) (xy 385.927602 -382.650952) (xy 385.881713 -382.680441)
			(xy 385.832095 -382.7031) (xy 385.779757 -382.718467) (xy 385.725766 -382.726229) (xy 385.698492 -382.726692)
			(xy 384.834892 -382.726692) (xy 384.807625 -382.726145) (xy 384.753647 -382.718383) (xy 384.701322 -382.703018)
			(xy 384.651717 -382.680363) (xy 384.605841 -382.65088) (xy 384.564627 -382.615167) (xy 384.528916 -382.573953)
			(xy 384.499433 -382.528076) (xy 384.476779 -382.47847) (xy 384.461415 -382.426146) (xy 384.453654 -382.372167)
			(xy 379.272628 -382.372167) (xy 379.272628 -382.372174) (xy 379.264865 -382.426165) (xy 379.249498 -382.478503)
			(xy 379.226838 -382.52812) (xy 379.197347 -382.574008) (xy 379.161626 -382.615232) (xy 379.120402 -382.650952)
			(xy 379.074513 -382.680441) (xy 379.024895 -382.7031) (xy 378.972557 -382.718467) (xy 378.918566 -382.726229)
			(xy 378.891292 -382.726692) (xy 378.027692 -382.726692) (xy 378.000425 -382.726145) (xy 377.946447 -382.718383)
			(xy 377.894122 -382.703018) (xy 377.844517 -382.680363) (xy 377.798641 -382.65088) (xy 377.757427 -382.615167)
			(xy 377.721716 -382.573953) (xy 377.692233 -382.528076) (xy 377.669579 -382.47847) (xy 377.654215 -382.426146)
			(xy 377.646454 -382.372167) (xy 372.465428 -382.372167) (xy 372.465428 -382.372174) (xy 372.457665 -382.426165)
			(xy 372.442298 -382.478503) (xy 372.419638 -382.52812) (xy 372.390147 -382.574008) (xy 372.354426 -382.615232)
			(xy 372.313202 -382.650952) (xy 372.267313 -382.680441) (xy 372.217695 -382.7031) (xy 372.165357 -382.718467)
			(xy 372.111366 -382.726229) (xy 372.084092 -382.726692) (xy 371.220492 -382.726692) (xy 371.193225 -382.726145)
			(xy 371.139247 -382.718383) (xy 371.086922 -382.703018) (xy 371.037317 -382.680363) (xy 370.991441 -382.65088)
			(xy 370.950227 -382.615167) (xy 370.914516 -382.573953) (xy 370.885033 -382.528076) (xy 370.862379 -382.47847)
			(xy 370.847015 -382.426146) (xy 370.839254 -382.372167) (xy 351.507306 -382.372167) (xy 351.507306 -382.37217)
			(xy 351.499544 -382.426153) (xy 351.48418 -382.478484) (xy 351.461525 -382.528095) (xy 351.432041 -382.573977)
			(xy 351.396328 -382.615197) (xy 351.355112 -382.650915) (xy 351.309233 -382.680404) (xy 351.259625 -382.703065)
			(xy 351.207297 -382.718435) (xy 351.153313 -382.726202) (xy 351.126044 -382.726692) (xy 350.262444 -382.726692)
			(xy 350.235173 -382.726172) (xy 350.181186 -382.718415) (xy 350.128852 -382.703054) (xy 350.079237 -382.680401)
			(xy 350.033351 -382.650916) (xy 349.992129 -382.615202) (xy 349.95641 -382.573984) (xy 349.926921 -382.528102)
			(xy 349.904261 -382.478489) (xy 349.888894 -382.426157) (xy 349.881132 -382.372171) (xy 344.700106 -382.372171)
			(xy 344.692344 -382.426153) (xy 344.67698 -382.478484) (xy 344.654325 -382.528095) (xy 344.624841 -382.573977)
			(xy 344.589128 -382.615197) (xy 344.547912 -382.650915) (xy 344.502033 -382.680404) (xy 344.452425 -382.703065)
			(xy 344.400097 -382.718435) (xy 344.346113 -382.726202) (xy 344.318844 -382.726692) (xy 343.455244 -382.726692)
			(xy 343.427973 -382.726172) (xy 343.373986 -382.718415) (xy 343.321652 -382.703054) (xy 343.272037 -382.680401)
			(xy 343.226151 -382.650916) (xy 343.184929 -382.615202) (xy 343.14921 -382.573984) (xy 343.119721 -382.528102)
			(xy 343.097061 -382.478489) (xy 343.081694 -382.426157) (xy 343.073932 -382.372171) (xy 337.892906 -382.372171)
			(xy 337.885144 -382.426153) (xy 337.86978 -382.478484) (xy 337.847125 -382.528095) (xy 337.817641 -382.573977)
			(xy 337.781928 -382.615197) (xy 337.740712 -382.650915) (xy 337.694833 -382.680404) (xy 337.645225 -382.703065)
			(xy 337.592897 -382.718435) (xy 337.538913 -382.726202) (xy 337.511644 -382.726692) (xy 336.648044 -382.726692)
			(xy 336.620773 -382.726172) (xy 336.566786 -382.718415) (xy 336.514452 -382.703054) (xy 336.464837 -382.680401)
			(xy 336.418951 -382.650916) (xy 336.377729 -382.615202) (xy 336.34201 -382.573984) (xy 336.312521 -382.528102)
			(xy 336.289861 -382.478489) (xy 336.274494 -382.426157) (xy 336.266732 -382.372171) (xy 318.979628 -382.372171)
			(xy 318.979628 -382.372173) (xy 318.971866 -382.426165) (xy 318.956498 -382.478502) (xy 318.933838 -382.528119)
			(xy 318.904348 -382.574007) (xy 318.868627 -382.61523) (xy 318.827403 -382.65095) (xy 318.781516 -382.68044)
			(xy 318.731898 -382.703099) (xy 318.679561 -382.718466) (xy 318.625569 -382.726229) (xy 318.598296 -382.726692)
			(xy 317.734696 -382.726692) (xy 317.707429 -382.726145) (xy 317.65345 -382.718384) (xy 317.601125 -382.703019)
			(xy 317.551519 -382.680365) (xy 317.505642 -382.650881) (xy 317.464429 -382.615169) (xy 317.428717 -382.573954)
			(xy 317.399233 -382.528077) (xy 317.376579 -382.478471) (xy 317.361215 -382.426146) (xy 317.353454 -382.372167)
			(xy 312.172428 -382.372167) (xy 312.172428 -382.372173) (xy 312.164666 -382.426165) (xy 312.149298 -382.478502)
			(xy 312.126638 -382.528119) (xy 312.097148 -382.574007) (xy 312.061427 -382.61523) (xy 312.020203 -382.65095)
			(xy 311.974316 -382.68044) (xy 311.924698 -382.703099) (xy 311.872361 -382.718466) (xy 311.818369 -382.726229)
			(xy 311.791096 -382.726692) (xy 310.927496 -382.726692) (xy 310.900229 -382.726145) (xy 310.84625 -382.718384)
			(xy 310.793925 -382.703019) (xy 310.744319 -382.680365) (xy 310.698442 -382.650881) (xy 310.657229 -382.615169)
			(xy 310.621517 -382.573954) (xy 310.592033 -382.528077) (xy 310.569379 -382.478471) (xy 310.554015 -382.426146)
			(xy 310.546254 -382.372167) (xy 305.365228 -382.372167) (xy 305.365228 -382.372173) (xy 305.357466 -382.426165)
			(xy 305.342098 -382.478502) (xy 305.319438 -382.528119) (xy 305.289948 -382.574007) (xy 305.254227 -382.61523)
			(xy 305.213003 -382.65095) (xy 305.167116 -382.68044) (xy 305.117498 -382.703099) (xy 305.065161 -382.718466)
			(xy 305.011169 -382.726229) (xy 304.983896 -382.726692) (xy 304.120296 -382.726692) (xy 304.093029 -382.726145)
			(xy 304.03905 -382.718384) (xy 303.986725 -382.703019) (xy 303.937119 -382.680365) (xy 303.891242 -382.650881)
			(xy 303.850029 -382.615169) (xy 303.814317 -382.573954) (xy 303.784833 -382.528077) (xy 303.762179 -382.478471)
			(xy 303.746815 -382.426146) (xy 303.739054 -382.372167) (xy 294.194727 -382.372167) (xy 294.264676 -382.460745)
			(xy 294.368827 -382.605448) (xy 294.466429 -382.754647) (xy 294.557287 -382.908046) (xy 294.641221 -383.06534)
			(xy 294.718066 -383.226216) (xy 294.787667 -383.390357) (xy 294.849888 -383.557434) (xy 294.904604 -383.727118)
			(xy 294.951706 -383.899071) (xy 294.991102 -384.072951) (xy 295.022713 -384.248414) (xy 295.046477 -384.42511)
			(xy 295.062345 -384.60269) (xy 295.070287 -384.7808) (xy 295.070784 -384.869944) (xy 295.070287 -384.959088)
			(xy 295.062345 -385.137198) (xy 295.055495 -385.21386) (xy 297.048936 -385.21386) (xy 297.048936 -384.35026)
			(xy 297.049422 -384.323009) (xy 297.057178 -384.269061) (xy 297.072533 -384.216766) (xy 297.095175 -384.167189)
			(xy 297.124641 -384.121339) (xy 297.160332 -384.080148) (xy 297.201523 -384.044457) (xy 297.247373 -384.014991)
			(xy 297.29695 -383.992349) (xy 297.349245 -383.976994) (xy 297.403193 -383.969238) (xy 297.457695 -383.969238)
			(xy 297.511643 -383.976994) (xy 297.563938 -383.992349) (xy 297.613515 -384.014991) (xy 297.659365 -384.044457)
			(xy 297.700556 -384.080148) (xy 297.736247 -384.121339) (xy 297.765713 -384.167189) (xy 297.788355 -384.216766)
			(xy 297.80371 -384.269061) (xy 297.811466 -384.323009) (xy 297.811952 -384.35026) (xy 297.811952 -385.21386)
			(xy 297.811466 -385.241111) (xy 297.80371 -385.295059) (xy 297.788355 -385.347354) (xy 297.784941 -385.35483)
			(xy 298.547536 -385.35483) (xy 298.547536 -385.160266) (xy 298.547954 -385.149141) (xy 298.554411 -385.127844)
			(xy 298.560236 -385.118356) (xy 298.752768 -384.823462) (xy 298.758503 -384.814094) (xy 298.764768 -384.793046)
			(xy 298.764758 -384.771087) (xy 298.758475 -384.750045) (xy 298.752768 -384.740658) (xy 298.560236 -384.447034)
			(xy 298.554417 -384.437545) (xy 298.547974 -384.416247) (xy 298.547536 -384.405124) (xy 298.547536 -384.20929)
			(xy 298.548003 -384.197175) (xy 298.555493 -384.174132) (xy 298.569736 -384.154531) (xy 298.589339 -384.140289)
			(xy 298.612383 -384.132802) (xy 298.624498 -384.132328) (xy 299.310298 -384.132328) (xy 299.322411 -384.132813)
			(xy 299.345453 -384.140299) (xy 299.365054 -384.154538) (xy 299.379296 -384.174136) (xy 299.386785 -384.197177)
			(xy 299.38726 -384.20929) (xy 299.38726 -384.224784) (xy 303.902872 -384.224784) (xy 303.902872 -383.53873)
			(xy 303.903334 -383.526639) (xy 303.910786 -383.503634) (xy 303.924973 -383.484051) (xy 303.94451 -383.4698)
			(xy 303.96749 -383.462273) (xy 303.97958 -383.461768) (xy 304.174144 -383.461768) (xy 304.18527 -383.462177)
			(xy 304.206567 -383.468639) (xy 304.216054 -383.474468) (xy 304.509678 -383.667) (xy 304.519061 -383.672704)
			(xy 304.540074 -383.67904) (xy 304.562021 -383.679114) (xy 304.583076 -383.672919) (xy 304.592482 -383.667254)
			(xy 304.888646 -383.474468) (xy 304.898135 -383.46865) (xy 304.919433 -383.462208) (xy 304.930556 -383.461768)
			(xy 305.12512 -383.461768) (xy 305.137193 -383.462247) (xy 305.160157 -383.469712) (xy 305.179691 -383.483906)
			(xy 305.193886 -383.50344) (xy 305.201352 -383.526403) (xy 305.201828 -383.538476) (xy 305.201828 -384.22453)
			(xy 305.201819 -384.224784) (xy 310.710072 -384.224784) (xy 310.710072 -383.53873) (xy 310.710534 -383.526639)
			(xy 310.717986 -383.503634) (xy 310.732173 -383.484051) (xy 310.75171 -383.4698) (xy 310.77469 -383.462273)
			(xy 310.78678 -383.461768) (xy 310.981344 -383.461768) (xy 310.99247 -383.462177) (xy 311.013767 -383.468639)
			(xy 311.023254 -383.474468) (xy 311.316878 -383.667) (xy 311.326261 -383.672704) (xy 311.347274 -383.67904)
			(xy 311.369221 -383.679114) (xy 311.390276 -383.672919) (xy 311.399682 -383.667254) (xy 311.695846 -383.474468)
			(xy 311.705335 -383.46865) (xy 311.726633 -383.462208) (xy 311.737756 -383.461768) (xy 311.93232 -383.461768)
			(xy 311.944393 -383.462247) (xy 311.967357 -383.469712) (xy 311.986891 -383.483906) (xy 312.001086 -383.50344)
			(xy 312.008552 -383.526403) (xy 312.009028 -383.538476) (xy 312.009028 -384.22453) (xy 312.009019 -384.224784)
			(xy 317.517272 -384.224784) (xy 317.517272 -383.53873) (xy 317.517734 -383.526639) (xy 317.525186 -383.503634)
			(xy 317.539373 -383.484051) (xy 317.55891 -383.4698) (xy 317.58189 -383.462273) (xy 317.59398 -383.461768)
			(xy 317.788544 -383.461768) (xy 317.79967 -383.462177) (xy 317.820967 -383.468639) (xy 317.830454 -383.474468)
			(xy 318.124078 -383.667) (xy 318.133461 -383.672704) (xy 318.154474 -383.67904) (xy 318.176421 -383.679114)
			(xy 318.197476 -383.672919) (xy 318.206882 -383.667254) (xy 318.503046 -383.474468) (xy 318.512535 -383.46865)
			(xy 318.533833 -383.462208) (xy 318.544956 -383.461768) (xy 318.73952 -383.461768) (xy 318.751593 -383.462247)
			(xy 318.774557 -383.469712) (xy 318.794091 -383.483906) (xy 318.808286 -383.50344) (xy 318.815752 -383.526403)
			(xy 318.816228 -383.538476) (xy 318.816228 -384.22453) (xy 318.815818 -384.236624) (xy 318.808349 -384.259631)
			(xy 318.794149 -384.279214) (xy 318.774602 -384.293462) (xy 318.751613 -384.300988) (xy 318.73952 -384.301492)
			(xy 318.544956 -384.301492) (xy 318.533831 -384.301074) (xy 318.512534 -384.294617) (xy 318.503046 -384.288792)
			(xy 318.208152 -384.09626) (xy 318.198765 -384.090557) (xy 318.177727 -384.084284) (xy 318.155773 -384.084284)
			(xy 318.134735 -384.090557) (xy 318.125348 -384.09626) (xy 317.831724 -384.288792) (xy 317.822219 -384.29458)
			(xy 317.800933 -384.301042) (xy 317.789814 -384.301492) (xy 317.59398 -384.301492) (xy 317.581903 -384.301052)
			(xy 317.558932 -384.293582) (xy 317.539394 -384.27938) (xy 317.525201 -384.259835) (xy 317.517742 -384.236861)
			(xy 317.517272 -384.224784) (xy 312.009019 -384.224784) (xy 312.008618 -384.236624) (xy 312.001149 -384.259631)
			(xy 311.986949 -384.279214) (xy 311.967402 -384.293462) (xy 311.944413 -384.300988) (xy 311.93232 -384.301492)
			(xy 311.737756 -384.301492) (xy 311.726631 -384.301074) (xy 311.705334 -384.294617) (xy 311.695846 -384.288792)
			(xy 311.400952 -384.09626) (xy 311.391565 -384.090557) (xy 311.370527 -384.084284) (xy 311.348573 -384.084284)
			(xy 311.327535 -384.090557) (xy 311.318148 -384.09626) (xy 311.024524 -384.288792) (xy 311.015019 -384.29458)
			(xy 310.993733 -384.301042) (xy 310.982614 -384.301492) (xy 310.78678 -384.301492) (xy 310.774703 -384.301052)
			(xy 310.751732 -384.293582) (xy 310.732194 -384.27938) (xy 310.718001 -384.259835) (xy 310.710542 -384.236861)
			(xy 310.710072 -384.224784) (xy 305.201819 -384.224784) (xy 305.201418 -384.236624) (xy 305.193949 -384.259631)
			(xy 305.179749 -384.279214) (xy 305.160202 -384.293462) (xy 305.137213 -384.300988) (xy 305.12512 -384.301492)
			(xy 304.930556 -384.301492) (xy 304.919431 -384.301074) (xy 304.898134 -384.294617) (xy 304.888646 -384.288792)
			(xy 304.593752 -384.09626) (xy 304.584365 -384.090557) (xy 304.563327 -384.084284) (xy 304.541373 -384.084284)
			(xy 304.520335 -384.090557) (xy 304.510948 -384.09626) (xy 304.217324 -384.288792) (xy 304.207819 -384.29458)
			(xy 304.186533 -384.301042) (xy 304.175414 -384.301492) (xy 303.97958 -384.301492) (xy 303.967503 -384.301052)
			(xy 303.944532 -384.293582) (xy 303.924994 -384.27938) (xy 303.910801 -384.259835) (xy 303.903342 -384.236861)
			(xy 303.902872 -384.224784) (xy 299.38726 -384.224784) (xy 299.38726 -384.403854) (xy 299.386851 -384.41498)
			(xy 299.380388 -384.436277) (xy 299.37456 -384.445764) (xy 299.182028 -384.739388) (xy 299.176313 -384.748766)
			(xy 299.169977 -384.769781) (xy 299.169906 -384.791731) (xy 299.176106 -384.812787) (xy 299.181774 -384.822192)
			(xy 299.37456 -385.118356) (xy 299.380375 -385.127847) (xy 299.386821 -385.149143) (xy 299.38726 -385.160266)
			(xy 299.38726 -385.35483) (xy 299.386814 -385.366946) (xy 299.379318 -385.389991) (xy 299.36507 -385.409592)
			(xy 299.345462 -385.423833) (xy 299.322415 -385.431319) (xy 299.310298 -385.431792) (xy 298.624498 -385.431792)
			(xy 298.612386 -385.43129) (xy 298.589348 -385.423806) (xy 298.569749 -385.409571) (xy 298.555507 -385.389977)
			(xy 298.548014 -385.366941) (xy 298.547536 -385.35483) (xy 297.784941 -385.35483) (xy 297.765713 -385.396931)
			(xy 297.736247 -385.442781) (xy 297.704173 -385.479798) (xy 325.321168 -385.479798) (xy 325.321168 -385.285234)
			(xy 325.321568 -385.274107) (xy 325.328036 -385.25281) (xy 325.333868 -385.243324) (xy 325.5264 -384.94843)
			(xy 325.532082 -384.939031) (xy 325.538364 -384.917999) (xy 325.538371 -384.896048) (xy 325.532101 -384.875012)
			(xy 325.5264 -384.865626) (xy 325.333868 -384.572002) (xy 325.328068 -384.562503) (xy 325.321614 -384.541213)
			(xy 325.321168 -384.530092) (xy 325.321168 -384.334258) (xy 325.321576 -384.322138) (xy 325.329079 -384.299089)
			(xy 325.343336 -384.279485) (xy 325.362953 -384.265246) (xy 325.38601 -384.257765) (xy 325.39813 -384.257296)
			(xy 326.08393 -384.257296) (xy 326.096042 -384.257785) (xy 326.119079 -384.265276) (xy 326.138677 -384.279515)
			(xy 326.152919 -384.29911) (xy 326.160413 -384.322146) (xy 326.160892 -384.334258) (xy 326.160892 -384.528822)
			(xy 326.160465 -384.539946) (xy 326.154014 -384.561243) (xy 326.148192 -384.570732) (xy 325.95566 -384.864356)
			(xy 325.949976 -384.87375) (xy 325.94364 -384.894758) (xy 325.943561 -384.916701) (xy 325.949746 -384.937754)
			(xy 325.955406 -384.94716) (xy 326.148192 -385.243324) (xy 326.153998 -385.25282) (xy 326.160449 -385.274113)
			(xy 326.160892 -385.285234) (xy 326.160892 -385.338828) (xy 326.895968 -385.338828) (xy 326.895968 -384.475228)
			(xy 326.896454 -384.447977) (xy 326.90421 -384.394029) (xy 326.919565 -384.341734) (xy 326.942207 -384.292157)
			(xy 326.971673 -384.246307) (xy 327.007364 -384.205116) (xy 327.048555 -384.169425) (xy 327.094405 -384.139959)
			(xy 327.143982 -384.117317) (xy 327.196277 -384.101962) (xy 327.250225 -384.094206) (xy 327.304727 -384.094206)
			(xy 327.358675 -384.101962) (xy 327.41097 -384.117317) (xy 327.460547 -384.139959) (xy 327.506397 -384.169425)
			(xy 327.547588 -384.205116) (xy 327.583279 -384.246307) (xy 327.612745 -384.292157) (xy 327.635387 -384.341734)
			(xy 327.650742 -384.394029) (xy 327.658498 -384.447977) (xy 327.658984 -384.475228) (xy 327.658984 -385.21386)
			(xy 329.576684 -385.21386) (xy 329.576684 -384.35026) (xy 329.57717 -384.323009) (xy 329.584926 -384.269061)
			(xy 329.600281 -384.216766) (xy 329.622923 -384.167189) (xy 329.652389 -384.121339) (xy 329.68808 -384.080148)
			(xy 329.729271 -384.044457) (xy 329.775121 -384.014991) (xy 329.824698 -383.992349) (xy 329.876993 -383.976994)
			(xy 329.930941 -383.969238) (xy 329.985443 -383.969238) (xy 330.039391 -383.976994) (xy 330.091686 -383.992349)
			(xy 330.141263 -384.014991) (xy 330.187113 -384.044457) (xy 330.228304 -384.080148) (xy 330.263995 -384.121339)
			(xy 330.293461 -384.167189) (xy 330.316103 -384.216766) (xy 330.331458 -384.269061) (xy 330.339214 -384.323009)
			(xy 330.3397 -384.35026) (xy 330.3397 -385.21386) (xy 330.339214 -385.241111) (xy 330.331458 -385.295059)
			(xy 330.316103 -385.347354) (xy 330.312689 -385.35483) (xy 331.075284 -385.35483) (xy 331.075284 -385.160266)
			(xy 331.075695 -385.14914) (xy 331.082156 -385.127843) (xy 331.087984 -385.118356) (xy 331.280516 -384.823462)
			(xy 331.286255 -384.814095) (xy 331.292524 -384.793047) (xy 331.292514 -384.771086) (xy 331.286227 -384.750044)
			(xy 331.280516 -384.740658) (xy 331.087984 -384.447034) (xy 331.082161 -384.437548) (xy 331.075721 -384.416247)
			(xy 331.075284 -384.405124) (xy 331.075284 -384.20929) (xy 331.075652 -384.197162) (xy 331.083153 -384.174095)
			(xy 331.097416 -384.154476) (xy 331.117045 -384.140227) (xy 331.140118 -384.132744) (xy 331.152246 -384.132328)
			(xy 331.838046 -384.132328) (xy 331.850162 -384.132772) (xy 331.873205 -384.140271) (xy 331.892805 -384.154521)
			(xy 331.907045 -384.174127) (xy 331.914533 -384.197174) (xy 331.915008 -384.20929) (xy 331.915008 -384.224784)
			(xy 336.43062 -384.224784) (xy 336.43062 -383.53873) (xy 336.431133 -383.526644) (xy 336.438579 -383.503648)
			(xy 336.452754 -383.484069) (xy 336.472277 -383.469817) (xy 336.495244 -383.46228) (xy 336.507328 -383.461768)
			(xy 336.701892 -383.461768) (xy 336.713016 -383.462198) (xy 336.734313 -383.468646) (xy 336.743802 -383.474468)
			(xy 337.037426 -383.667) (xy 337.046786 -383.672746) (xy 337.06781 -383.679073) (xy 337.089765 -383.679135)
			(xy 337.110824 -383.672926) (xy 337.12023 -383.667254) (xy 337.416394 -383.474468) (xy 337.425894 -383.468669)
			(xy 337.447184 -383.462215) (xy 337.458304 -383.461768) (xy 337.652868 -383.461768) (xy 337.664947 -383.46224)
			(xy 337.687924 -383.469695) (xy 337.707473 -383.483887) (xy 337.721679 -383.503426) (xy 337.729152 -383.526398)
			(xy 337.729576 -383.538476) (xy 337.729576 -384.22453) (xy 337.729566 -384.224784) (xy 343.23782 -384.224784)
			(xy 343.23782 -383.53873) (xy 343.238333 -383.526644) (xy 343.245779 -383.503648) (xy 343.259954 -383.484069)
			(xy 343.279477 -383.469817) (xy 343.302444 -383.46228) (xy 343.314528 -383.461768) (xy 343.509092 -383.461768)
			(xy 343.520216 -383.462198) (xy 343.541513 -383.468646) (xy 343.551002 -383.474468) (xy 343.844626 -383.667)
			(xy 343.853986 -383.672746) (xy 343.87501 -383.679073) (xy 343.896965 -383.679135) (xy 343.918024 -383.672926)
			(xy 343.92743 -383.667254) (xy 344.223594 -383.474468) (xy 344.233094 -383.468669) (xy 344.254384 -383.462215)
			(xy 344.265504 -383.461768) (xy 344.460068 -383.461768) (xy 344.472147 -383.46224) (xy 344.495124 -383.469695)
			(xy 344.514673 -383.483887) (xy 344.528879 -383.503426) (xy 344.536352 -383.526398) (xy 344.536776 -383.538476)
			(xy 344.536776 -384.22453) (xy 344.536766 -384.224784) (xy 350.04502 -384.224784) (xy 350.04502 -383.53873)
			(xy 350.045533 -383.526644) (xy 350.052979 -383.503648) (xy 350.067154 -383.484069) (xy 350.086677 -383.469817)
			(xy 350.109644 -383.46228) (xy 350.121728 -383.461768) (xy 350.316292 -383.461768) (xy 350.327416 -383.462198)
			(xy 350.348713 -383.468646) (xy 350.358202 -383.474468) (xy 350.651826 -383.667) (xy 350.661186 -383.672746)
			(xy 350.68221 -383.679073) (xy 350.704165 -383.679135) (xy 350.725224 -383.672926) (xy 350.73463 -383.667254)
			(xy 351.030794 -383.474468) (xy 351.040294 -383.468669) (xy 351.061584 -383.462215) (xy 351.072704 -383.461768)
			(xy 351.267268 -383.461768) (xy 351.279347 -383.46224) (xy 351.302324 -383.469695) (xy 351.321873 -383.483887)
			(xy 351.336079 -383.503426) (xy 351.343552 -383.526398) (xy 351.343976 -383.538476) (xy 351.343976 -384.22453)
			(xy 351.343519 -384.23662) (xy 351.336056 -384.259619) (xy 351.321866 -384.279197) (xy 351.302332 -384.293447)
			(xy 351.279356 -384.300981) (xy 351.267268 -384.301492) (xy 351.072704 -384.301492) (xy 351.06158 -384.301055)
			(xy 351.040284 -384.294611) (xy 351.030794 -384.288792) (xy 350.7359 -384.09626) (xy 350.726513 -384.090557)
			(xy 350.705475 -384.084284) (xy 350.683521 -384.084284) (xy 350.662483 -384.090557) (xy 350.653096 -384.09626)
			(xy 350.359472 -384.288792) (xy 350.349977 -384.2946) (xy 350.328684 -384.301049) (xy 350.317562 -384.301492)
			(xy 350.121728 -384.301492) (xy 350.109645 -384.301063) (xy 350.086661 -384.293601) (xy 350.067109 -384.2794)
			(xy 350.052904 -384.25985) (xy 350.045439 -384.236867) (xy 350.04502 -384.224784) (xy 344.536766 -384.224784)
			(xy 344.536319 -384.23662) (xy 344.528856 -384.259619) (xy 344.514666 -384.279197) (xy 344.495132 -384.293447)
			(xy 344.472156 -384.300981) (xy 344.460068 -384.301492) (xy 344.265504 -384.301492) (xy 344.25438 -384.301055)
			(xy 344.233084 -384.294611) (xy 344.223594 -384.288792) (xy 343.9287 -384.09626) (xy 343.919313 -384.090557)
			(xy 343.898275 -384.084284) (xy 343.876321 -384.084284) (xy 343.855283 -384.090557) (xy 343.845896 -384.09626)
			(xy 343.552272 -384.288792) (xy 343.542777 -384.2946) (xy 343.521484 -384.301049) (xy 343.510362 -384.301492)
			(xy 343.314528 -384.301492) (xy 343.302445 -384.301063) (xy 343.279461 -384.293601) (xy 343.259909 -384.2794)
			(xy 343.245704 -384.25985) (xy 343.238239 -384.236867) (xy 343.23782 -384.224784) (xy 337.729566 -384.224784)
			(xy 337.729119 -384.23662) (xy 337.721656 -384.259619) (xy 337.707466 -384.279197) (xy 337.687932 -384.293447)
			(xy 337.664956 -384.300981) (xy 337.652868 -384.301492) (xy 337.458304 -384.301492) (xy 337.44718 -384.301055)
			(xy 337.425884 -384.294611) (xy 337.416394 -384.288792) (xy 337.1215 -384.09626) (xy 337.112113 -384.090557)
			(xy 337.091075 -384.084284) (xy 337.069121 -384.084284) (xy 337.048083 -384.090557) (xy 337.038696 -384.09626)
			(xy 336.745072 -384.288792) (xy 336.735577 -384.2946) (xy 336.714284 -384.301049) (xy 336.703162 -384.301492)
			(xy 336.507328 -384.301492) (xy 336.495245 -384.301063) (xy 336.472261 -384.293601) (xy 336.452709 -384.2794)
			(xy 336.438504 -384.25985) (xy 336.431039 -384.236867) (xy 336.43062 -384.224784) (xy 331.915008 -384.224784)
			(xy 331.915008 -384.403854) (xy 331.914592 -384.414979) (xy 331.908133 -384.436276) (xy 331.902308 -384.445764)
			(xy 331.709776 -384.739388) (xy 331.704064 -384.748767) (xy 331.697732 -384.769782) (xy 331.697661 -384.79173)
			(xy 331.703857 -384.812786) (xy 331.709522 -384.822192) (xy 331.902308 -385.118356) (xy 331.908127 -385.127845)
			(xy 331.914569 -385.149143) (xy 331.915008 -385.160266) (xy 331.915008 -385.35483) (xy 331.914515 -385.366942)
			(xy 331.907025 -385.389978) (xy 331.892787 -385.409575) (xy 331.873192 -385.423817) (xy 331.850157 -385.431312)
			(xy 331.838046 -385.431792) (xy 331.152246 -385.431792) (xy 331.140129 -385.431301) (xy 331.117076 -385.423825)
			(xy 331.097463 -385.409591) (xy 331.083209 -385.389992) (xy 331.07571 -385.366947) (xy 331.075284 -385.35483)
			(xy 330.312689 -385.35483) (xy 330.293461 -385.396931) (xy 330.263995 -385.442781) (xy 330.231921 -385.479798)
			(xy 357.848916 -385.479798) (xy 357.848916 -385.285234) (xy 357.849324 -385.274108) (xy 357.855788 -385.252811)
			(xy 357.861616 -385.243324) (xy 358.054148 -384.94843) (xy 358.059827 -384.93903) (xy 358.066106 -384.917998)
			(xy 358.066112 -384.896049) (xy 358.059847 -384.875012) (xy 358.054148 -384.865626) (xy 357.861616 -384.572002)
			(xy 357.85582 -384.562501) (xy 357.849363 -384.541212) (xy 357.848916 -384.530092) (xy 357.848916 -384.334258)
			(xy 357.849376 -384.322143) (xy 357.856872 -384.299103) (xy 357.871118 -384.279503) (xy 357.89072 -384.265263)
			(xy 357.913763 -384.257772) (xy 357.925878 -384.257296) (xy 358.611678 -384.257296) (xy 358.623787 -384.25783)
			(xy 358.646823 -384.265306) (xy 358.666421 -384.279533) (xy 358.680665 -384.29912) (xy 358.68816 -384.322149)
			(xy 358.68864 -384.334258) (xy 358.68864 -384.528822) (xy 358.688221 -384.539947) (xy 358.681766 -384.561244)
			(xy 358.67594 -384.570732) (xy 358.483408 -384.864356) (xy 358.477722 -384.873749) (xy 358.471381 -384.894757)
			(xy 358.471302 -384.916701) (xy 358.477492 -384.937755) (xy 358.483154 -384.94716) (xy 358.67594 -385.243324)
			(xy 358.68175 -385.252817) (xy 358.688198 -385.274112) (xy 358.68864 -385.285234) (xy 358.68864 -385.338828)
			(xy 359.423716 -385.338828) (xy 359.423716 -384.475228) (xy 359.424202 -384.447977) (xy 359.431958 -384.394029)
			(xy 359.447313 -384.341734) (xy 359.469955 -384.292157) (xy 359.499421 -384.246307) (xy 359.535112 -384.205116)
			(xy 359.576303 -384.169425) (xy 359.622153 -384.139959) (xy 359.67173 -384.117317) (xy 359.724025 -384.101962)
			(xy 359.777973 -384.094206) (xy 359.832475 -384.094206) (xy 359.886423 -384.101962) (xy 359.938718 -384.117317)
			(xy 359.988295 -384.139959) (xy 360.034145 -384.169425) (xy 360.075336 -384.205116) (xy 360.111027 -384.246307)
			(xy 360.140493 -384.292157) (xy 360.163135 -384.341734) (xy 360.17849 -384.394029) (xy 360.186246 -384.447977)
			(xy 360.186732 -384.475228) (xy 360.186732 -385.21386) (xy 364.149132 -385.21386) (xy 364.149132 -384.35026)
			(xy 364.149618 -384.323009) (xy 364.157374 -384.269061) (xy 364.172729 -384.216766) (xy 364.195371 -384.167189)
			(xy 364.224837 -384.121339) (xy 364.260528 -384.080148) (xy 364.301719 -384.044457) (xy 364.347569 -384.014991)
			(xy 364.397146 -383.992349) (xy 364.449441 -383.976994) (xy 364.503389 -383.969238) (xy 364.557891 -383.969238)
			(xy 364.611839 -383.976994) (xy 364.664134 -383.992349) (xy 364.713711 -384.014991) (xy 364.759561 -384.044457)
			(xy 364.800752 -384.080148) (xy 364.836443 -384.121339) (xy 364.865909 -384.167189) (xy 364.888551 -384.216766)
			(xy 364.903906 -384.269061) (xy 364.911662 -384.323009) (xy 364.912148 -384.35026) (xy 364.912148 -385.21386)
			(xy 364.911662 -385.241111) (xy 364.903906 -385.295059) (xy 364.888551 -385.347354) (xy 364.885021 -385.355084)
			(xy 365.647732 -385.355084) (xy 365.647732 -385.160266) (xy 365.648096 -385.149158) (xy 365.65442 -385.127862)
			(xy 365.660178 -385.118356) (xy 365.85271 -384.823462) (xy 365.858449 -384.814095) (xy 365.864719 -384.793047)
			(xy 365.864709 -384.771086) (xy 365.858421 -384.750044) (xy 365.85271 -384.740658) (xy 365.660178 -384.447034)
			(xy 365.654427 -384.437525) (xy 365.648104 -384.416231) (xy 365.647732 -384.405124) (xy 365.647732 -384.20929)
			(xy 365.648199 -384.197201) (xy 365.655657 -384.174201) (xy 365.669844 -384.154622) (xy 365.689377 -384.140372)
			(xy 365.712352 -384.132839) (xy 365.72444 -384.132328) (xy 366.41024 -384.132328) (xy 366.42232 -384.132731)
			(xy 366.445295 -384.140208) (xy 366.464834 -384.15442) (xy 366.479026 -384.173973) (xy 366.486481 -384.196955)
			(xy 366.486948 -384.209036) (xy 366.486948 -384.22453) (xy 371.00256 -384.22453) (xy 371.00256 -383.53873)
			(xy 371.002986 -383.526607) (xy 371.010472 -383.503545) (xy 371.024722 -383.483928) (xy 371.044338 -383.469676)
			(xy 371.067399 -383.462187) (xy 371.079522 -383.461768) (xy 371.274086 -383.461768) (xy 371.28521 -383.462201)
			(xy 371.306507 -383.468647) (xy 371.315996 -383.474468) (xy 371.60962 -383.667) (xy 371.618983 -383.67274)
			(xy 371.640005 -383.679069) (xy 371.66196 -383.679132) (xy 371.683018 -383.672925) (xy 371.692424 -383.667254)
			(xy 371.988588 -383.474468) (xy 371.998089 -383.468671) (xy 372.019378 -383.462215) (xy 372.030498 -383.461768)
			(xy 372.225062 -383.461768) (xy 372.237186 -383.462193) (xy 372.260249 -383.469678) (xy 372.279867 -383.483927)
			(xy 372.294118 -383.503544) (xy 372.301606 -383.526606) (xy 372.302024 -383.53873) (xy 372.302024 -384.22453)
			(xy 377.80976 -384.22453) (xy 377.80976 -383.53873) (xy 377.810186 -383.526607) (xy 377.817672 -383.503545)
			(xy 377.831922 -383.483928) (xy 377.851538 -383.469676) (xy 377.874599 -383.462187) (xy 377.886722 -383.461768)
			(xy 378.081286 -383.461768) (xy 378.09241 -383.462201) (xy 378.113707 -383.468647) (xy 378.123196 -383.474468)
			(xy 378.41682 -383.667) (xy 378.426183 -383.67274) (xy 378.447205 -383.679069) (xy 378.46916 -383.679132)
			(xy 378.490218 -383.672925) (xy 378.499624 -383.667254) (xy 378.795788 -383.474468) (xy 378.805289 -383.468671)
			(xy 378.826578 -383.462215) (xy 378.837698 -383.461768) (xy 379.032262 -383.461768) (xy 379.044386 -383.462193)
			(xy 379.067449 -383.469678) (xy 379.087067 -383.483927) (xy 379.101318 -383.503544) (xy 379.108806 -383.526606)
			(xy 379.109224 -383.53873) (xy 379.109224 -384.22453) (xy 384.61696 -384.22453) (xy 384.61696 -383.53873)
			(xy 384.617386 -383.526607) (xy 384.624872 -383.503545) (xy 384.639122 -383.483928) (xy 384.658738 -383.469676)
			(xy 384.681799 -383.462187) (xy 384.693922 -383.461768) (xy 384.888486 -383.461768) (xy 384.89961 -383.462201)
			(xy 384.920907 -383.468647) (xy 384.930396 -383.474468) (xy 385.22402 -383.667) (xy 385.233383 -383.67274)
			(xy 385.254405 -383.679069) (xy 385.27636 -383.679132) (xy 385.297418 -383.672925) (xy 385.306824 -383.667254)
			(xy 385.602988 -383.474468) (xy 385.612489 -383.468671) (xy 385.633778 -383.462215) (xy 385.644898 -383.461768)
			(xy 385.839462 -383.461768) (xy 385.851586 -383.462193) (xy 385.874649 -383.469678) (xy 385.894267 -383.483927)
			(xy 385.908518 -383.503544) (xy 385.916006 -383.526606) (xy 385.916424 -383.53873) (xy 385.916424 -384.22453)
			(xy 385.916065 -384.236658) (xy 385.90856 -384.259724) (xy 385.894294 -384.279342) (xy 385.874663 -384.293591)
			(xy 385.851591 -384.301076) (xy 385.839462 -384.301492) (xy 385.644898 -384.301492) (xy 385.633774 -384.301057)
			(xy 385.612477 -384.294612) (xy 385.602988 -384.288792) (xy 385.308094 -384.09626) (xy 385.298707 -384.090557)
			(xy 385.277669 -384.084284) (xy 385.255715 -384.084284) (xy 385.234677 -384.090557) (xy 385.22529 -384.09626)
			(xy 384.931666 -384.288792) (xy 384.922172 -384.294602) (xy 384.900878 -384.30105) (xy 384.889756 -384.301492)
			(xy 384.693922 -384.301492) (xy 384.681812 -384.30097) (xy 384.658774 -384.293492) (xy 384.639175 -384.279262)
			(xy 384.624931 -384.259672) (xy 384.617438 -384.23664) (xy 384.61696 -384.22453) (xy 379.109224 -384.22453)
			(xy 379.108865 -384.236658) (xy 379.10136 -384.259724) (xy 379.087094 -384.279342) (xy 379.067463 -384.293591)
			(xy 379.044391 -384.301076) (xy 379.032262 -384.301492) (xy 378.837698 -384.301492) (xy 378.826574 -384.301057)
			(xy 378.805277 -384.294612) (xy 378.795788 -384.288792) (xy 378.500894 -384.09626) (xy 378.491507 -384.090557)
			(xy 378.470469 -384.084284) (xy 378.448515 -384.084284) (xy 378.427477 -384.090557) (xy 378.41809 -384.09626)
			(xy 378.124466 -384.288792) (xy 378.114972 -384.294602) (xy 378.093678 -384.30105) (xy 378.082556 -384.301492)
			(xy 377.886722 -384.301492) (xy 377.874612 -384.30097) (xy 377.851574 -384.293492) (xy 377.831975 -384.279262)
			(xy 377.817731 -384.259672) (xy 377.810238 -384.23664) (xy 377.80976 -384.22453) (xy 372.302024 -384.22453)
			(xy 372.301665 -384.236658) (xy 372.29416 -384.259724) (xy 372.279894 -384.279342) (xy 372.260263 -384.293591)
			(xy 372.237191 -384.301076) (xy 372.225062 -384.301492) (xy 372.030498 -384.301492) (xy 372.019374 -384.301057)
			(xy 371.998077 -384.294612) (xy 371.988588 -384.288792) (xy 371.693694 -384.09626) (xy 371.684307 -384.090557)
			(xy 371.663269 -384.084284) (xy 371.641315 -384.084284) (xy 371.620277 -384.090557) (xy 371.61089 -384.09626)
			(xy 371.317266 -384.288792) (xy 371.307772 -384.294602) (xy 371.286478 -384.30105) (xy 371.275356 -384.301492)
			(xy 371.079522 -384.301492) (xy 371.067412 -384.30097) (xy 371.044374 -384.293492) (xy 371.024775 -384.279262)
			(xy 371.010531 -384.259672) (xy 371.003038 -384.23664) (xy 371.00256 -384.22453) (xy 366.486948 -384.22453)
			(xy 366.486948 -384.403854) (xy 366.486574 -384.414959) (xy 366.480246 -384.436252) (xy 366.474502 -384.445764)
			(xy 366.28197 -384.739388) (xy 366.276259 -384.748767) (xy 366.269927 -384.769782) (xy 366.269856 -384.79173)
			(xy 366.276051 -384.812786) (xy 366.281716 -384.822192) (xy 366.474502 -385.118356) (xy 366.480248 -385.127868)
			(xy 366.486575 -385.14916) (xy 366.486948 -385.160266) (xy 366.486948 -385.35483) (xy 366.486518 -385.366922)
			(xy 366.479052 -385.389926) (xy 366.464856 -385.409506) (xy 366.445314 -385.423756) (xy 366.422331 -385.431285)
			(xy 366.41024 -385.431792) (xy 365.72444 -385.431792) (xy 365.712358 -385.431353) (xy 365.689374 -385.423895)
			(xy 365.669821 -385.409696) (xy 365.655616 -385.390148) (xy 365.648151 -385.367166) (xy 365.647732 -385.355084)
			(xy 364.885021 -385.355084) (xy 364.865909 -385.396931) (xy 364.836443 -385.442781) (xy 364.804149 -385.480052)
			(xy 392.421364 -385.480052) (xy 392.421364 -385.285234) (xy 392.42171 -385.274125) (xy 392.428046 -385.252828)
			(xy 392.43381 -385.243324) (xy 392.626342 -384.94843) (xy 392.632021 -384.93903) (xy 392.638301 -384.917998)
			(xy 392.638307 -384.896048) (xy 392.632041 -384.875012) (xy 392.626342 -384.865626) (xy 392.43381 -384.572002)
			(xy 392.42805 -384.562498) (xy 392.421731 -384.5412) (xy 392.421364 -384.530092) (xy 392.421364 -384.334258)
			(xy 392.421772 -384.322164) (xy 392.429243 -384.299158) (xy 392.443444 -384.279576) (xy 392.462991 -384.265328)
			(xy 392.485979 -384.257802) (xy 392.498072 -384.257296) (xy 393.183872 -384.257296) (xy 393.195954 -384.257737)
			(xy 393.218936 -384.265197) (xy 393.238487 -384.279396) (xy 393.252692 -384.298942) (xy 393.26016 -384.321922)
			(xy 393.26058 -384.334004) (xy 393.26058 -384.528822) (xy 393.260188 -384.539926) (xy 393.253872 -384.561218)
			(xy 393.248134 -384.570732) (xy 393.055602 -384.864356) (xy 393.049916 -384.873749) (xy 393.043576 -384.894757)
			(xy 393.043497 -384.916701) (xy 393.049686 -384.937754) (xy 393.055348 -384.94716) (xy 393.248134 -385.243324)
			(xy 393.25387 -385.252841) (xy 393.260203 -385.274129) (xy 393.26058 -385.285234) (xy 393.26058 -385.338828)
			(xy 393.996164 -385.338828) (xy 393.996164 -384.475228) (xy 393.99665 -384.447977) (xy 394.004406 -384.394029)
			(xy 394.019761 -384.341734) (xy 394.042403 -384.292157) (xy 394.071869 -384.246307) (xy 394.10756 -384.205116)
			(xy 394.148751 -384.169425) (xy 394.194601 -384.139959) (xy 394.244178 -384.117317) (xy 394.296473 -384.101962)
			(xy 394.350421 -384.094206) (xy 394.404923 -384.094206) (xy 394.458871 -384.101962) (xy 394.511166 -384.117317)
			(xy 394.560743 -384.139959) (xy 394.606593 -384.169425) (xy 394.647784 -384.205116) (xy 394.683475 -384.246307)
			(xy 394.712941 -384.292157) (xy 394.735583 -384.341734) (xy 394.750938 -384.394029) (xy 394.758694 -384.447977)
			(xy 394.75918 -384.475228) (xy 394.75918 -385.21386) (xy 396.67688 -385.21386) (xy 396.67688 -384.35026)
			(xy 396.677366 -384.323009) (xy 396.685122 -384.269061) (xy 396.700477 -384.216766) (xy 396.723119 -384.167189)
			(xy 396.752585 -384.121339) (xy 396.788276 -384.080148) (xy 396.829467 -384.044457) (xy 396.875317 -384.014991)
			(xy 396.924894 -383.992349) (xy 396.977189 -383.976994) (xy 397.031137 -383.969238) (xy 397.085639 -383.969238)
			(xy 397.139587 -383.976994) (xy 397.191882 -383.992349) (xy 397.241459 -384.014991) (xy 397.287309 -384.044457)
			(xy 397.3285 -384.080148) (xy 397.364191 -384.121339) (xy 397.393657 -384.167189) (xy 397.416299 -384.216766)
			(xy 397.431654 -384.269061) (xy 397.43941 -384.323009) (xy 397.439896 -384.35026) (xy 397.439896 -385.21386)
			(xy 397.43941 -385.241111) (xy 397.431654 -385.295059) (xy 397.416299 -385.347354) (xy 397.412769 -385.355084)
			(xy 398.17548 -385.355084) (xy 398.17548 -385.160266) (xy 398.175852 -385.149159) (xy 398.182171 -385.127863)
			(xy 398.187926 -385.118356) (xy 398.380458 -384.823462) (xy 398.386194 -384.814094) (xy 398.392459 -384.793047)
			(xy 398.39245 -384.771087) (xy 398.386166 -384.750045) (xy 398.380458 -384.740658) (xy 398.187926 -384.447034)
			(xy 398.182179 -384.437523) (xy 398.175852 -384.41623) (xy 398.17548 -384.405124) (xy 398.17548 -384.20929)
			(xy 398.1759 -384.197196) (xy 398.183364 -384.174188) (xy 398.197561 -384.154605) (xy 398.217107 -384.140356)
			(xy 398.240095 -384.132832) (xy 398.252188 -384.132328) (xy 398.937988 -384.132328) (xy 398.950074 -384.132724)
			(xy 398.973062 -384.140192) (xy 398.992616 -384.154402) (xy 399.006819 -384.17396) (xy 399.01428 -384.19695)
			(xy 399.014696 -384.209036) (xy 399.014696 -384.22453) (xy 403.530308 -384.22453) (xy 403.530308 -383.53873)
			(xy 403.530837 -383.52662) (xy 403.538312 -383.503583) (xy 403.55254 -383.483983) (xy 403.572129 -383.46974)
			(xy 403.59516 -383.462246) (xy 403.60727 -383.461768) (xy 403.801834 -383.461768) (xy 403.81296 -383.462181)
			(xy 403.834257 -383.46864) (xy 403.843744 -383.474468) (xy 404.137368 -383.667) (xy 404.146756 -383.672696)
			(xy 404.167766 -383.679034) (xy 404.189712 -383.67911) (xy 404.210766 -383.672917) (xy 404.220172 -383.667254)
			(xy 404.516336 -383.474468) (xy 404.525827 -383.468654) (xy 404.547124 -383.462209) (xy 404.558246 -383.461768)
			(xy 404.75281 -383.461768) (xy 404.764936 -383.462152) (xy 404.788 -383.469651) (xy 404.807618 -383.483911)
			(xy 404.821868 -383.503535) (xy 404.829354 -383.526604) (xy 404.829772 -383.53873) (xy 404.829772 -384.22453)
			(xy 410.337508 -384.22453) (xy 410.337508 -383.53873) (xy 410.338037 -383.52662) (xy 410.345512 -383.503583)
			(xy 410.35974 -383.483983) (xy 410.379329 -383.46974) (xy 410.40236 -383.462246) (xy 410.41447 -383.461768)
			(xy 410.609034 -383.461768) (xy 410.62016 -383.462181) (xy 410.641457 -383.46864) (xy 410.650944 -383.474468)
			(xy 410.944568 -383.667) (xy 410.953956 -383.672696) (xy 410.974966 -383.679034) (xy 410.996912 -383.67911)
			(xy 411.017966 -383.672917) (xy 411.027372 -383.667254) (xy 411.323536 -383.474468) (xy 411.333027 -383.468654)
			(xy 411.354324 -383.462209) (xy 411.365446 -383.461768) (xy 411.56001 -383.461768) (xy 411.572136 -383.462152)
			(xy 411.5952 -383.469651) (xy 411.614818 -383.483911) (xy 411.629068 -383.503535) (xy 411.636554 -383.526604)
			(xy 411.636972 -383.53873) (xy 411.636972 -384.22453) (xy 417.144708 -384.22453) (xy 417.144708 -383.53873)
			(xy 417.145237 -383.52662) (xy 417.152712 -383.503583) (xy 417.16694 -383.483983) (xy 417.186529 -383.46974)
			(xy 417.20956 -383.462246) (xy 417.22167 -383.461768) (xy 417.416234 -383.461768) (xy 417.42736 -383.462181)
			(xy 417.448657 -383.46864) (xy 417.458144 -383.474468) (xy 417.751768 -383.667) (xy 417.761156 -383.672696)
			(xy 417.782166 -383.679034) (xy 417.804112 -383.67911) (xy 417.825166 -383.672917) (xy 417.834572 -383.667254)
			(xy 418.130736 -383.474468) (xy 418.140227 -383.468654) (xy 418.161524 -383.462209) (xy 418.172646 -383.461768)
			(xy 418.36721 -383.461768) (xy 418.379336 -383.462152) (xy 418.4024 -383.469651) (xy 418.422018 -383.483911)
			(xy 418.436268 -383.503535) (xy 418.443754 -383.526604) (xy 418.444172 -383.53873) (xy 418.444172 -384.22453)
			(xy 418.443714 -384.236645) (xy 418.43622 -384.259688) (xy 418.421974 -384.279288) (xy 418.40237 -384.293529)
			(xy 418.379325 -384.301017) (xy 418.36721 -384.301492) (xy 418.172646 -384.301492) (xy 418.16152 -384.301078)
			(xy 418.140224 -384.294618) (xy 418.130736 -384.288792) (xy 417.835842 -384.09626) (xy 417.826455 -384.090557)
			(xy 417.805417 -384.084284) (xy 417.783463 -384.084284) (xy 417.762425 -384.090557) (xy 417.753038 -384.09626)
			(xy 417.459414 -384.288792) (xy 417.449911 -384.294584) (xy 417.428624 -384.301043) (xy 417.417504 -384.301492)
			(xy 417.22167 -384.301492) (xy 417.209557 -384.301014) (xy 417.186518 -384.293523) (xy 417.166919 -384.279281)
			(xy 417.152677 -384.259682) (xy 417.145186 -384.236643) (xy 417.144708 -384.22453) (xy 411.636972 -384.22453)
			(xy 411.636514 -384.236645) (xy 411.62902 -384.259688) (xy 411.614774 -384.279288) (xy 411.59517 -384.293529)
			(xy 411.572125 -384.301017) (xy 411.56001 -384.301492) (xy 411.365446 -384.301492) (xy 411.35432 -384.301078)
			(xy 411.333024 -384.294618) (xy 411.323536 -384.288792) (xy 411.028642 -384.09626) (xy 411.019255 -384.090557)
			(xy 410.998217 -384.084284) (xy 410.976263 -384.084284) (xy 410.955225 -384.090557) (xy 410.945838 -384.09626)
			(xy 410.652214 -384.288792) (xy 410.642711 -384.294584) (xy 410.621424 -384.301043) (xy 410.610304 -384.301492)
			(xy 410.41447 -384.301492) (xy 410.402357 -384.301014) (xy 410.379318 -384.293523) (xy 410.359719 -384.279281)
			(xy 410.345477 -384.259682) (xy 410.337986 -384.236643) (xy 410.337508 -384.22453) (xy 404.829772 -384.22453)
			(xy 404.829314 -384.236645) (xy 404.82182 -384.259688) (xy 404.807574 -384.279288) (xy 404.78797 -384.293529)
			(xy 404.764925 -384.301017) (xy 404.75281 -384.301492) (xy 404.558246 -384.301492) (xy 404.54712 -384.301078)
			(xy 404.525824 -384.294618) (xy 404.516336 -384.288792) (xy 404.221442 -384.09626) (xy 404.212055 -384.090557)
			(xy 404.191017 -384.084284) (xy 404.169063 -384.084284) (xy 404.148025 -384.090557) (xy 404.138638 -384.09626)
			(xy 403.845014 -384.288792) (xy 403.835511 -384.294584) (xy 403.814224 -384.301043) (xy 403.803104 -384.301492)
			(xy 403.60727 -384.301492) (xy 403.595157 -384.301014) (xy 403.572118 -384.293523) (xy 403.552519 -384.279281)
			(xy 403.538277 -384.259682) (xy 403.530786 -384.236643) (xy 403.530308 -384.22453) (xy 399.014696 -384.22453)
			(xy 399.014696 -384.403854) (xy 399.014314 -384.414959) (xy 399.007991 -384.43625) (xy 399.00225 -384.445764)
			(xy 398.809718 -384.739388) (xy 398.804004 -384.748766) (xy 398.797668 -384.769781) (xy 398.797597 -384.791731)
			(xy 398.803796 -384.812787) (xy 398.809464 -384.822192) (xy 399.00225 -385.118356) (xy 399.008 -385.127866)
			(xy 399.014324 -385.14916) (xy 399.014696 -385.160266) (xy 399.014696 -385.35483) (xy 399.014219 -385.366918)
			(xy 399.006758 -385.389913) (xy 398.992573 -385.409489) (xy 398.973044 -385.42374) (xy 398.950074 -385.431278)
			(xy 398.937988 -385.431792) (xy 398.252188 -385.431792) (xy 398.240103 -385.431397) (xy 398.217117 -385.423925)
			(xy 398.197566 -385.409714) (xy 398.183363 -385.390158) (xy 398.175898 -385.367169) (xy 398.17548 -385.355084)
			(xy 397.412769 -385.355084) (xy 397.393657 -385.396931) (xy 397.364191 -385.442781) (xy 397.331897 -385.480052)
			(xy 424.949112 -385.480052) (xy 424.949112 -385.285234) (xy 424.949466 -385.274125) (xy 424.955797 -385.252829)
			(xy 424.961558 -385.243324) (xy 425.15409 -384.94843) (xy 425.159766 -384.939029) (xy 425.166041 -384.917997)
			(xy 425.166048 -384.896049) (xy 425.159786 -384.875013) (xy 425.15409 -384.865626) (xy 424.961558 -384.572002)
			(xy 424.955794 -384.5625) (xy 424.949479 -384.5412) (xy 424.949112 -384.530092) (xy 424.949112 -384.334258)
			(xy 424.949571 -384.322169) (xy 424.957036 -384.299172) (xy 424.971226 -384.279595) (xy 424.990758 -384.265345)
			(xy 425.013733 -384.257809) (xy 425.02582 -384.257296) (xy 425.71162 -384.257296) (xy 425.723696 -384.257747)
			(xy 425.746664 -384.265216) (xy 425.766201 -384.279416) (xy 425.780395 -384.298957) (xy 425.787856 -384.321928)
			(xy 425.788328 -384.334004) (xy 425.788328 -384.528822) (xy 425.787929 -384.539925) (xy 425.781617 -384.561217)
			(xy 425.775882 -384.570732) (xy 425.58335 -384.864356) (xy 425.577661 -384.873748) (xy 425.571317 -384.894757)
			(xy 425.571238 -384.916702) (xy 425.577431 -384.937756) (xy 425.583096 -384.94716) (xy 425.775882 -385.243324)
			(xy 425.781614 -385.252843) (xy 425.78795 -385.27413) (xy 425.788328 -385.285234) (xy 425.788328 -385.338828)
			(xy 426.523912 -385.338828) (xy 426.523912 -384.475228) (xy 426.524398 -384.447977) (xy 426.532154 -384.394029)
			(xy 426.547509 -384.341734) (xy 426.570151 -384.292157) (xy 426.599617 -384.246307) (xy 426.635308 -384.205116)
			(xy 426.676499 -384.169425) (xy 426.722349 -384.139959) (xy 426.771926 -384.117317) (xy 426.824221 -384.101962)
			(xy 426.878169 -384.094206) (xy 426.932671 -384.094206) (xy 426.986619 -384.101962) (xy 427.038914 -384.117317)
			(xy 427.088491 -384.139959) (xy 427.134341 -384.169425) (xy 427.175532 -384.205116) (xy 427.211223 -384.246307)
			(xy 427.240689 -384.292157) (xy 427.263331 -384.341734) (xy 427.278686 -384.394029) (xy 427.286442 -384.447977)
			(xy 427.286928 -384.475228) (xy 427.286928 -384.869944) (xy 429.498772 -384.869944) (xy 429.502744 -384.691701)
			(xy 429.514652 -384.513812) (xy 429.534473 -384.33663) (xy 429.562167 -384.160506) (xy 429.597679 -383.985791)
			(xy 429.640939 -383.812832) (xy 429.691861 -383.641971) (xy 429.750344 -383.473549) (xy 429.816271 -383.307899)
			(xy 429.889512 -383.14535) (xy 429.969922 -382.986225) (xy 430.05734 -382.83084) (xy 430.151593 -382.679504)
			(xy 430.252494 -382.532516) (xy 430.359843 -382.390169) (xy 430.473426 -382.252746) (xy 430.593019 -382.120519)
			(xy 430.718383 -381.99375) (xy 430.84927 -381.872692) (xy 430.985419 -381.757585) (xy 431.126561 -381.648657)
			(xy 431.272416 -381.546125) (xy 431.422693 -381.450191) (xy 431.577094 -381.361048) (xy 431.735313 -381.278871)
			(xy 431.897036 -381.203823) (xy 432.061941 -381.136055) (xy 432.229702 -381.075699) (xy 432.399985 -381.022877)
			(xy 432.572452 -380.977693) (xy 432.74676 -380.940236) (xy 432.922564 -380.910582) (xy 433.099514 -380.888789)
			(xy 433.27726 -380.874899) (xy 433.455447 -380.868942) (xy 433.633724 -380.870928) (xy 433.811735 -380.880854)
			(xy 433.989127 -380.8987) (xy 434.165547 -380.92443) (xy 434.340647 -380.957994) (xy 434.514078 -380.999324)
			(xy 434.685495 -381.04834) (xy 434.854558 -381.104942) (xy 435.020933 -381.16902) (xy 435.184287 -381.240446)
			(xy 435.344298 -381.319078) (xy 435.500647 -381.404759) (xy 435.653024 -381.497321) (xy 435.801127 -381.596578)
			(xy 435.944661 -381.702335) (xy 436.083341 -381.81438) (xy 436.216892 -381.932492) (xy 436.345049 -382.056436)
			(xy 436.467558 -382.185966) (xy 436.584175 -382.320825) (xy 436.694668 -382.460745) (xy 436.798819 -382.605448)
			(xy 436.896421 -382.754647) (xy 436.987279 -382.908046) (xy 437.071213 -383.06534) (xy 437.148058 -383.226216)
			(xy 437.217659 -383.390357) (xy 437.27988 -383.557434) (xy 437.334596 -383.727118) (xy 437.381698 -383.899071)
			(xy 437.421094 -384.072951) (xy 437.452705 -384.248414) (xy 437.476469 -384.42511) (xy 437.492337 -384.60269)
			(xy 437.500279 -384.7808) (xy 437.500776 -384.869944) (xy 437.500279 -384.959088) (xy 437.492337 -385.137198)
			(xy 437.476469 -385.314778) (xy 437.452705 -385.491474) (xy 437.421094 -385.666937) (xy 437.381698 -385.840817)
			(xy 437.334596 -386.01277) (xy 437.27988 -386.182454) (xy 437.217659 -386.349531) (xy 437.148058 -386.513672)
			(xy 437.071213 -386.674548) (xy 436.987279 -386.831842) (xy 436.896421 -386.985241) (xy 436.798819 -387.13444)
			(xy 436.694668 -387.279143) (xy 436.584175 -387.419063) (xy 436.467558 -387.553922) (xy 436.345049 -387.683452)
			(xy 436.216892 -387.807396) (xy 436.083341 -387.925508) (xy 435.944661 -388.037553) (xy 435.801127 -388.14331)
			(xy 435.653024 -388.242567) (xy 435.500647 -388.335129) (xy 435.344298 -388.42081) (xy 435.184287 -388.499442)
			(xy 435.020933 -388.570868) (xy 434.854558 -388.634946) (xy 434.685495 -388.691548) (xy 434.514078 -388.740564)
			(xy 434.340647 -388.781894) (xy 434.165547 -388.815458) (xy 433.989127 -388.841188) (xy 433.811735 -388.859034)
			(xy 433.633724 -388.86896) (xy 433.455447 -388.870946) (xy 433.27726 -388.864989) (xy 433.099514 -388.851099)
			(xy 432.922564 -388.829306) (xy 432.74676 -388.799652) (xy 432.572452 -388.762195) (xy 432.399985 -388.717011)
			(xy 432.229702 -388.664189) (xy 432.061941 -388.603833) (xy 431.897036 -388.536065) (xy 431.735313 -388.461017)
			(xy 431.577094 -388.37884) (xy 431.422693 -388.289697) (xy 431.272416 -388.193763) (xy 431.126561 -388.091231)
			(xy 430.985419 -387.982303) (xy 430.84927 -387.867196) (xy 430.718383 -387.746138) (xy 430.593019 -387.619369)
			(xy 430.473426 -387.487142) (xy 430.359843 -387.349719) (xy 430.252494 -387.207372) (xy 430.151593 -387.060384)
			(xy 430.05734 -386.909048) (xy 429.969922 -386.753663) (xy 429.889512 -386.594538) (xy 429.816271 -386.431989)
			(xy 429.750344 -386.266339) (xy 429.691861 -386.097917) (xy 429.640939 -385.927056) (xy 429.597679 -385.754097)
			(xy 429.562167 -385.579382) (xy 429.534473 -385.403258) (xy 429.514652 -385.226076) (xy 429.502744 -385.048187)
			(xy 429.498772 -384.869944) (xy 427.286928 -384.869944) (xy 427.286928 -385.338828) (xy 427.286442 -385.366079)
			(xy 427.278686 -385.420027) (xy 427.263331 -385.472322) (xy 427.240689 -385.521899) (xy 427.211223 -385.567749)
			(xy 427.175532 -385.60894) (xy 427.134341 -385.644631) (xy 427.088491 -385.674097) (xy 427.038914 -385.696739)
			(xy 426.986619 -385.712094) (xy 426.932671 -385.71985) (xy 426.878169 -385.71985) (xy 426.824221 -385.712094)
			(xy 426.771926 -385.696739) (xy 426.722349 -385.674097) (xy 426.676499 -385.644631) (xy 426.635308 -385.60894)
			(xy 426.599617 -385.567749) (xy 426.570151 -385.521899) (xy 426.547509 -385.472322) (xy 426.532154 -385.420027)
			(xy 426.524398 -385.366079) (xy 426.523912 -385.338828) (xy 425.788328 -385.338828) (xy 425.788328 -385.479798)
			(xy 425.78789 -385.491891) (xy 425.78043 -385.514896) (xy 425.766237 -385.534479) (xy 425.746695 -385.548729)
			(xy 425.723711 -385.556255) (xy 425.71162 -385.55676) (xy 425.02582 -385.55676) (xy 425.013734 -385.556369)
			(xy 424.990743 -385.548902) (xy 424.971189 -385.534691) (xy 424.956986 -385.515131) (xy 424.949526 -385.492139)
			(xy 424.949112 -385.480052) (xy 397.331897 -385.480052) (xy 397.3285 -385.483972) (xy 397.287309 -385.519663)
			(xy 397.241459 -385.549129) (xy 397.191882 -385.571771) (xy 397.139587 -385.587126) (xy 397.085639 -385.594882)
			(xy 397.031137 -385.594882) (xy 396.977189 -385.587126) (xy 396.924894 -385.571771) (xy 396.875317 -385.549129)
			(xy 396.829467 -385.519663) (xy 396.788276 -385.483972) (xy 396.752585 -385.442781) (xy 396.723119 -385.396931)
			(xy 396.700477 -385.347354) (xy 396.685122 -385.295059) (xy 396.677366 -385.241111) (xy 396.67688 -385.21386)
			(xy 394.75918 -385.21386) (xy 394.75918 -385.338828) (xy 394.758694 -385.366079) (xy 394.750938 -385.420027)
			(xy 394.735583 -385.472322) (xy 394.712941 -385.521899) (xy 394.683475 -385.567749) (xy 394.647784 -385.60894)
			(xy 394.606593 -385.644631) (xy 394.560743 -385.674097) (xy 394.511166 -385.696739) (xy 394.458871 -385.712094)
			(xy 394.404923 -385.71985) (xy 394.350421 -385.71985) (xy 394.296473 -385.712094) (xy 394.244178 -385.696739)
			(xy 394.194601 -385.674097) (xy 394.148751 -385.644631) (xy 394.10756 -385.60894) (xy 394.071869 -385.567749)
			(xy 394.042403 -385.521899) (xy 394.019761 -385.472322) (xy 394.004406 -385.420027) (xy 393.99665 -385.366079)
			(xy 393.996164 -385.338828) (xy 393.26058 -385.338828) (xy 393.26058 -385.479798) (xy 393.260091 -385.491885)
			(xy 393.252637 -385.514883) (xy 393.238456 -385.534461) (xy 393.218928 -385.548712) (xy 393.195958 -385.556248)
			(xy 393.183872 -385.55676) (xy 392.498072 -385.55676) (xy 392.485983 -385.556411) (xy 392.462991 -385.548929)
			(xy 392.443437 -385.534709) (xy 392.429236 -385.515141) (xy 392.421778 -385.492141) (xy 392.421364 -385.480052)
			(xy 364.804149 -385.480052) (xy 364.800752 -385.483972) (xy 364.759561 -385.519663) (xy 364.713711 -385.549129)
			(xy 364.664134 -385.571771) (xy 364.611839 -385.587126) (xy 364.557891 -385.594882) (xy 364.503389 -385.594882)
			(xy 364.449441 -385.587126) (xy 364.397146 -385.571771) (xy 364.347569 -385.549129) (xy 364.301719 -385.519663)
			(xy 364.260528 -385.483972) (xy 364.224837 -385.442781) (xy 364.195371 -385.396931) (xy 364.172729 -385.347354)
			(xy 364.157374 -385.295059) (xy 364.149618 -385.241111) (xy 364.149132 -385.21386) (xy 360.186732 -385.21386)
			(xy 360.186732 -385.338828) (xy 360.186246 -385.366079) (xy 360.17849 -385.420027) (xy 360.163135 -385.472322)
			(xy 360.140493 -385.521899) (xy 360.111027 -385.567749) (xy 360.075336 -385.60894) (xy 360.034145 -385.644631)
			(xy 359.988295 -385.674097) (xy 359.938718 -385.696739) (xy 359.886423 -385.712094) (xy 359.832475 -385.71985)
			(xy 359.777973 -385.71985) (xy 359.724025 -385.712094) (xy 359.67173 -385.696739) (xy 359.622153 -385.674097)
			(xy 359.576303 -385.644631) (xy 359.535112 -385.60894) (xy 359.499421 -385.567749) (xy 359.469955 -385.521899)
			(xy 359.447313 -385.472322) (xy 359.431958 -385.420027) (xy 359.424202 -385.366079) (xy 359.423716 -385.338828)
			(xy 358.68864 -385.338828) (xy 358.68864 -385.479798) (xy 358.688238 -385.491923) (xy 358.680744 -385.514985)
			(xy 358.666488 -385.534602) (xy 358.646867 -385.548853) (xy 358.623803 -385.556341) (xy 358.611678 -385.55676)
			(xy 357.925878 -385.55676) (xy 357.913762 -385.556307) (xy 357.890718 -385.548814) (xy 357.871116 -385.534567)
			(xy 357.856875 -385.514961) (xy 357.849389 -385.491914) (xy 357.848916 -385.479798) (xy 330.231921 -385.479798)
			(xy 330.228304 -385.483972) (xy 330.187113 -385.519663) (xy 330.141263 -385.549129) (xy 330.091686 -385.571771)
			(xy 330.039391 -385.587126) (xy 329.985443 -385.594882) (xy 329.930941 -385.594882) (xy 329.876993 -385.587126)
			(xy 329.824698 -385.571771) (xy 329.775121 -385.549129) (xy 329.729271 -385.519663) (xy 329.68808 -385.483972)
			(xy 329.652389 -385.442781) (xy 329.622923 -385.396931) (xy 329.600281 -385.347354) (xy 329.584926 -385.295059)
			(xy 329.57717 -385.241111) (xy 329.576684 -385.21386) (xy 327.658984 -385.21386) (xy 327.658984 -385.338828)
			(xy 327.658498 -385.366079) (xy 327.650742 -385.420027) (xy 327.635387 -385.472322) (xy 327.612745 -385.521899)
			(xy 327.583279 -385.567749) (xy 327.547588 -385.60894) (xy 327.506397 -385.644631) (xy 327.460547 -385.674097)
			(xy 327.41097 -385.696739) (xy 327.358675 -385.712094) (xy 327.304727 -385.71985) (xy 327.250225 -385.71985)
			(xy 327.196277 -385.712094) (xy 327.143982 -385.696739) (xy 327.094405 -385.674097) (xy 327.048555 -385.644631)
			(xy 327.007364 -385.60894) (xy 326.971673 -385.567749) (xy 326.942207 -385.521899) (xy 326.919565 -385.472322)
			(xy 326.90421 -385.420027) (xy 326.896454 -385.366079) (xy 326.895968 -385.338828) (xy 326.160892 -385.338828)
			(xy 326.160892 -385.479798) (xy 326.160387 -385.491909) (xy 326.152904 -385.514947) (xy 326.138669 -385.534547)
			(xy 326.119076 -385.548789) (xy 326.096041 -385.556282) (xy 326.08393 -385.55676) (xy 325.39813 -385.55676)
			(xy 325.386009 -385.556315) (xy 325.36295 -385.54883) (xy 325.343335 -385.534585) (xy 325.329083 -385.514975)
			(xy 325.32159 -385.491919) (xy 325.321168 -385.479798) (xy 297.704173 -385.479798) (xy 297.700556 -385.483972)
			(xy 297.659365 -385.519663) (xy 297.613515 -385.549129) (xy 297.563938 -385.571771) (xy 297.511643 -385.587126)
			(xy 297.457695 -385.594882) (xy 297.403193 -385.594882) (xy 297.349245 -385.587126) (xy 297.29695 -385.571771)
			(xy 297.247373 -385.549129) (xy 297.201523 -385.519663) (xy 297.160332 -385.483972) (xy 297.124641 -385.442781)
			(xy 297.095175 -385.396931) (xy 297.072533 -385.347354) (xy 297.057178 -385.295059) (xy 297.049422 -385.241111)
			(xy 297.048936 -385.21386) (xy 295.055495 -385.21386) (xy 295.046477 -385.314778) (xy 295.022713 -385.491474)
			(xy 294.991102 -385.666937) (xy 294.951706 -385.840817) (xy 294.904604 -386.01277) (xy 294.849888 -386.182454)
			(xy 294.787667 -386.349531) (xy 294.718066 -386.513672) (xy 294.641221 -386.674548) (xy 294.557287 -386.831842)
			(xy 294.466429 -386.985241) (xy 294.368827 -387.13444) (xy 294.264676 -387.279143) (xy 294.154183 -387.419063)
			(xy 294.037566 -387.553922) (xy 293.915057 -387.683452) (xy 293.7869 -387.807396) (xy 293.653349 -387.925508)
			(xy 293.514669 -388.037553) (xy 293.371135 -388.14331) (xy 293.223032 -388.242567) (xy 293.070655 -388.335129)
			(xy 292.914306 -388.42081) (xy 292.754295 -388.499442) (xy 292.590941 -388.570868) (xy 292.424566 -388.634946)
			(xy 292.255503 -388.691548) (xy 292.084086 -388.740564) (xy 291.910655 -388.781894) (xy 291.735555 -388.815458)
			(xy 291.559135 -388.841188) (xy 291.381743 -388.859034) (xy 291.203732 -388.86896) (xy 291.025455 -388.870946)
			(xy 290.847268 -388.864989) (xy 290.669522 -388.851099) (xy 290.492572 -388.829306) (xy 290.316768 -388.799652)
			(xy 290.14246 -388.762195) (xy 289.969993 -388.717011) (xy 289.79971 -388.664189) (xy 289.631949 -388.603833)
			(xy 289.467044 -388.536065) (xy 289.305321 -388.461017) (xy 289.147102 -388.37884) (xy 288.992701 -388.289697)
			(xy 288.842424 -388.193763) (xy 288.696569 -388.091231) (xy 288.555427 -387.982303) (xy 288.419278 -387.867196)
			(xy 288.288391 -387.746138) (xy 288.163027 -387.619369) (xy 288.043434 -387.487142) (xy 287.929851 -387.349719)
			(xy 287.822502 -387.207372) (xy 287.721601 -387.060384) (xy 287.627348 -386.909048) (xy 287.53993 -386.753663)
			(xy 287.45952 -386.594538) (xy 287.386279 -386.431989) (xy 287.320352 -386.266339) (xy 287.261869 -386.097917)
			(xy 287.210947 -385.927056) (xy 287.167687 -385.754097) (xy 287.132175 -385.579382) (xy 287.104481 -385.403258)
			(xy 287.08466 -385.226076) (xy 287.072752 -385.048187) (xy 287.06878 -384.869944) (xy 281.2288 -384.869944)
			(xy 281.2288 -387.375146) (xy 281.245056 -387.400292) (xy 281.258772 -387.406388) (xy 281.283524 -387.41805)
			(xy 281.329666 -387.447457) (xy 281.371135 -387.483154) (xy 281.407078 -387.524408) (xy 281.43676 -387.570374)
			(xy 281.45957 -387.620109) (xy 281.475042 -387.672592) (xy 281.482858 -387.726748) (xy 281.482857 -387.781464)
			(xy 281.47504 -387.835619) (xy 281.459566 -387.888102) (xy 281.436754 -387.937836) (xy 281.407071 -387.983801)
			(xy 281.371126 -388.025055) (xy 281.329657 -388.06075) (xy 281.283514 -388.090155) (xy 281.258772 -388.10184)
			(xy 281.245056 -388.107936) (xy 281.2288 -388.133082) (xy 281.2288 -388.883398) (xy 325.321168 -388.883398)
			(xy 325.321168 -388.688834) (xy 325.321568 -388.677707) (xy 325.328036 -388.65641) (xy 325.333868 -388.646924)
			(xy 325.5264 -388.35203) (xy 325.532082 -388.342631) (xy 325.538364 -388.321599) (xy 325.538371 -388.299648)
			(xy 325.532101 -388.278612) (xy 325.5264 -388.269226) (xy 325.333868 -387.975602) (xy 325.328068 -387.966103)
			(xy 325.321614 -387.944813) (xy 325.321168 -387.933692) (xy 325.321168 -387.737858) (xy 325.321576 -387.725738)
			(xy 325.329079 -387.702689) (xy 325.343336 -387.683085) (xy 325.362953 -387.668846) (xy 325.38601 -387.661365)
			(xy 325.39813 -387.660896) (xy 326.08393 -387.660896) (xy 326.096042 -387.661385) (xy 326.119079 -387.668876)
			(xy 326.138677 -387.683115) (xy 326.152919 -387.70271) (xy 326.160413 -387.725746) (xy 326.160892 -387.737858)
			(xy 326.160892 -387.932422) (xy 326.160465 -387.943546) (xy 326.154014 -387.964843) (xy 326.148192 -387.974332)
			(xy 325.95566 -388.267956) (xy 325.949976 -388.27735) (xy 325.94364 -388.298358) (xy 325.943561 -388.320301)
			(xy 325.949746 -388.341354) (xy 325.955406 -388.35076) (xy 326.148192 -388.646924) (xy 326.153998 -388.65642)
			(xy 326.160449 -388.677713) (xy 326.160892 -388.688834) (xy 326.160892 -388.742428) (xy 326.895968 -388.742428)
			(xy 326.895968 -387.878828) (xy 326.896454 -387.851577) (xy 326.90421 -387.797629) (xy 326.919565 -387.745334)
			(xy 326.942207 -387.695757) (xy 326.971673 -387.649907) (xy 327.007364 -387.608716) (xy 327.048555 -387.573025)
			(xy 327.094405 -387.543559) (xy 327.143982 -387.520917) (xy 327.196277 -387.505562) (xy 327.250225 -387.497806)
			(xy 327.304727 -387.497806) (xy 327.358675 -387.505562) (xy 327.41097 -387.520917) (xy 327.460547 -387.543559)
			(xy 327.506397 -387.573025) (xy 327.547588 -387.608716) (xy 327.583279 -387.649907) (xy 327.612745 -387.695757)
			(xy 327.635387 -387.745334) (xy 327.650742 -387.797629) (xy 327.658498 -387.851577) (xy 327.658984 -387.878828)
			(xy 327.658984 -388.742428) (xy 327.658498 -388.769679) (xy 327.650742 -388.823627) (xy 327.635387 -388.875922)
			(xy 327.631973 -388.883398) (xy 357.848916 -388.883398) (xy 357.848916 -388.688834) (xy 357.849324 -388.677708)
			(xy 357.855788 -388.656411) (xy 357.861616 -388.646924) (xy 358.054148 -388.35203) (xy 358.059827 -388.34263)
			(xy 358.066106 -388.321598) (xy 358.066112 -388.299649) (xy 358.059847 -388.278612) (xy 358.054148 -388.269226)
			(xy 357.861616 -387.975602) (xy 357.85582 -387.966101) (xy 357.849363 -387.944812) (xy 357.848916 -387.933692)
			(xy 357.848916 -387.737858) (xy 357.849376 -387.725743) (xy 357.856872 -387.702703) (xy 357.871118 -387.683103)
			(xy 357.89072 -387.668863) (xy 357.913763 -387.661372) (xy 357.925878 -387.660896) (xy 358.611678 -387.660896)
			(xy 358.623787 -387.66143) (xy 358.646823 -387.668906) (xy 358.666421 -387.683133) (xy 358.680665 -387.70272)
			(xy 358.68816 -387.725749) (xy 358.68864 -387.737858) (xy 358.68864 -387.932422) (xy 358.688221 -387.943547)
			(xy 358.681766 -387.964844) (xy 358.67594 -387.974332) (xy 358.483408 -388.267956) (xy 358.477722 -388.277349)
			(xy 358.471381 -388.298357) (xy 358.471302 -388.320301) (xy 358.477492 -388.341355) (xy 358.483154 -388.35076)
			(xy 358.67594 -388.646924) (xy 358.68175 -388.656417) (xy 358.688198 -388.677712) (xy 358.68864 -388.688834)
			(xy 358.68864 -388.742428) (xy 359.423716 -388.742428) (xy 359.423716 -387.878828) (xy 359.424202 -387.851577)
			(xy 359.431958 -387.797629) (xy 359.447313 -387.745334) (xy 359.469955 -387.695757) (xy 359.499421 -387.649907)
			(xy 359.535112 -387.608716) (xy 359.576303 -387.573025) (xy 359.622153 -387.543559) (xy 359.67173 -387.520917)
			(xy 359.724025 -387.505562) (xy 359.777973 -387.497806) (xy 359.832475 -387.497806) (xy 359.886423 -387.505562)
			(xy 359.938718 -387.520917) (xy 359.988295 -387.543559) (xy 360.034145 -387.573025) (xy 360.075336 -387.608716)
			(xy 360.111027 -387.649907) (xy 360.140493 -387.695757) (xy 360.163135 -387.745334) (xy 360.17849 -387.797629)
			(xy 360.186246 -387.851577) (xy 360.186732 -387.878828) (xy 360.186732 -388.742428) (xy 360.186246 -388.769679)
			(xy 360.17849 -388.823627) (xy 360.163135 -388.875922) (xy 360.159605 -388.883652) (xy 392.421364 -388.883652)
			(xy 392.421364 -388.688834) (xy 392.42171 -388.677725) (xy 392.428046 -388.656428) (xy 392.43381 -388.646924)
			(xy 392.626342 -388.35203) (xy 392.632021 -388.34263) (xy 392.638301 -388.321598) (xy 392.638307 -388.299648)
			(xy 392.632041 -388.278612) (xy 392.626342 -388.269226) (xy 392.43381 -387.975602) (xy 392.42805 -387.966098)
			(xy 392.421731 -387.9448) (xy 392.421364 -387.933692) (xy 392.421364 -387.737858) (xy 392.421772 -387.725764)
			(xy 392.429243 -387.702758) (xy 392.443444 -387.683176) (xy 392.462991 -387.668928) (xy 392.485979 -387.661402)
			(xy 392.498072 -387.660896) (xy 393.183872 -387.660896) (xy 393.195954 -387.661337) (xy 393.218936 -387.668797)
			(xy 393.238487 -387.682996) (xy 393.252692 -387.702542) (xy 393.26016 -387.725522) (xy 393.26058 -387.737604)
			(xy 393.26058 -387.932422) (xy 393.260188 -387.943526) (xy 393.253872 -387.964818) (xy 393.248134 -387.974332)
			(xy 393.055602 -388.267956) (xy 393.049916 -388.277349) (xy 393.043576 -388.298357) (xy 393.043497 -388.320301)
			(xy 393.049686 -388.341354) (xy 393.055348 -388.35076) (xy 393.248134 -388.646924) (xy 393.25387 -388.656441)
			(xy 393.260203 -388.677729) (xy 393.26058 -388.688834) (xy 393.26058 -388.742428) (xy 393.996164 -388.742428)
			(xy 393.996164 -387.878828) (xy 393.99665 -387.851577) (xy 394.004406 -387.797629) (xy 394.019761 -387.745334)
			(xy 394.042403 -387.695757) (xy 394.071869 -387.649907) (xy 394.10756 -387.608716) (xy 394.148751 -387.573025)
			(xy 394.194601 -387.543559) (xy 394.244178 -387.520917) (xy 394.296473 -387.505562) (xy 394.350421 -387.497806)
			(xy 394.404923 -387.497806) (xy 394.458871 -387.505562) (xy 394.511166 -387.520917) (xy 394.560743 -387.543559)
			(xy 394.606593 -387.573025) (xy 394.647784 -387.608716) (xy 394.683475 -387.649907) (xy 394.712941 -387.695757)
			(xy 394.735583 -387.745334) (xy 394.750938 -387.797629) (xy 394.758694 -387.851577) (xy 394.75918 -387.878828)
			(xy 394.75918 -388.742428) (xy 394.758694 -388.769679) (xy 394.750938 -388.823627) (xy 394.735583 -388.875922)
			(xy 394.732053 -388.883652) (xy 424.949112 -388.883652) (xy 424.949112 -388.688834) (xy 424.949466 -388.677725)
			(xy 424.955797 -388.656429) (xy 424.961558 -388.646924) (xy 425.15409 -388.35203) (xy 425.159766 -388.342629)
			(xy 425.166041 -388.321597) (xy 425.166048 -388.299649) (xy 425.159786 -388.278613) (xy 425.15409 -388.269226)
			(xy 424.961558 -387.975602) (xy 424.955794 -387.9661) (xy 424.949479 -387.9448) (xy 424.949112 -387.933692)
			(xy 424.949112 -387.737858) (xy 424.949571 -387.725769) (xy 424.957036 -387.702772) (xy 424.971226 -387.683195)
			(xy 424.990758 -387.668945) (xy 425.013733 -387.661409) (xy 425.02582 -387.660896) (xy 425.71162 -387.660896)
			(xy 425.723696 -387.661347) (xy 425.746664 -387.668816) (xy 425.766201 -387.683016) (xy 425.780395 -387.702557)
			(xy 425.787856 -387.725528) (xy 425.788328 -387.737604) (xy 425.788328 -387.932422) (xy 425.787929 -387.943525)
			(xy 425.781617 -387.964817) (xy 425.775882 -387.974332) (xy 425.58335 -388.267956) (xy 425.577661 -388.277348)
			(xy 425.571317 -388.298357) (xy 425.571238 -388.320302) (xy 425.577431 -388.341356) (xy 425.583096 -388.35076)
			(xy 425.775882 -388.646924) (xy 425.781614 -388.656443) (xy 425.78795 -388.67773) (xy 425.788328 -388.688834)
			(xy 425.788328 -388.742428) (xy 426.523912 -388.742428) (xy 426.523912 -387.878828) (xy 426.524398 -387.851577)
			(xy 426.532154 -387.797629) (xy 426.547509 -387.745334) (xy 426.570151 -387.695757) (xy 426.599617 -387.649907)
			(xy 426.635308 -387.608716) (xy 426.676499 -387.573025) (xy 426.722349 -387.543559) (xy 426.771926 -387.520917)
			(xy 426.824221 -387.505562) (xy 426.878169 -387.497806) (xy 426.932671 -387.497806) (xy 426.986619 -387.505562)
			(xy 427.038914 -387.520917) (xy 427.088491 -387.543559) (xy 427.134341 -387.573025) (xy 427.175532 -387.608716)
			(xy 427.211223 -387.649907) (xy 427.240689 -387.695757) (xy 427.263331 -387.745334) (xy 427.278686 -387.797629)
			(xy 427.286442 -387.851577) (xy 427.286928 -387.878828) (xy 427.286928 -388.742428) (xy 427.286442 -388.769679)
			(xy 427.278686 -388.823627) (xy 427.263331 -388.875922) (xy 427.240689 -388.925499) (xy 427.211223 -388.971349)
			(xy 427.175532 -389.01254) (xy 427.134341 -389.048231) (xy 427.088491 -389.077697) (xy 427.038914 -389.100339)
			(xy 426.986619 -389.115694) (xy 426.932671 -389.12345) (xy 426.878169 -389.12345) (xy 426.824221 -389.115694)
			(xy 426.771926 -389.100339) (xy 426.722349 -389.077697) (xy 426.676499 -389.048231) (xy 426.635308 -389.01254)
			(xy 426.599617 -388.971349) (xy 426.570151 -388.925499) (xy 426.547509 -388.875922) (xy 426.532154 -388.823627)
			(xy 426.524398 -388.769679) (xy 426.523912 -388.742428) (xy 425.788328 -388.742428) (xy 425.788328 -388.883398)
			(xy 425.78789 -388.895491) (xy 425.78043 -388.918496) (xy 425.766237 -388.938079) (xy 425.746695 -388.952329)
			(xy 425.723711 -388.959855) (xy 425.71162 -388.96036) (xy 425.02582 -388.96036) (xy 425.013734 -388.959969)
			(xy 424.990743 -388.952502) (xy 424.971189 -388.938291) (xy 424.956986 -388.918731) (xy 424.949526 -388.895739)
			(xy 424.949112 -388.883652) (xy 394.732053 -388.883652) (xy 394.712941 -388.925499) (xy 394.683475 -388.971349)
			(xy 394.647784 -389.01254) (xy 394.606593 -389.048231) (xy 394.560743 -389.077697) (xy 394.511166 -389.100339)
			(xy 394.458871 -389.115694) (xy 394.404923 -389.12345) (xy 394.350421 -389.12345) (xy 394.296473 -389.115694)
			(xy 394.244178 -389.100339) (xy 394.194601 -389.077697) (xy 394.148751 -389.048231) (xy 394.10756 -389.01254)
			(xy 394.071869 -388.971349) (xy 394.042403 -388.925499) (xy 394.019761 -388.875922) (xy 394.004406 -388.823627)
			(xy 393.99665 -388.769679) (xy 393.996164 -388.742428) (xy 393.26058 -388.742428) (xy 393.26058 -388.883398)
			(xy 393.260091 -388.895485) (xy 393.252637 -388.918483) (xy 393.238456 -388.938061) (xy 393.218928 -388.952312)
			(xy 393.195958 -388.959848) (xy 393.183872 -388.96036) (xy 392.498072 -388.96036) (xy 392.485983 -388.960011)
			(xy 392.462991 -388.952529) (xy 392.443437 -388.938309) (xy 392.429236 -388.918741) (xy 392.421778 -388.895741)
			(xy 392.421364 -388.883652) (xy 360.159605 -388.883652) (xy 360.140493 -388.925499) (xy 360.111027 -388.971349)
			(xy 360.075336 -389.01254) (xy 360.034145 -389.048231) (xy 359.988295 -389.077697) (xy 359.938718 -389.100339)
			(xy 359.886423 -389.115694) (xy 359.832475 -389.12345) (xy 359.777973 -389.12345) (xy 359.724025 -389.115694)
			(xy 359.67173 -389.100339) (xy 359.622153 -389.077697) (xy 359.576303 -389.048231) (xy 359.535112 -389.01254)
			(xy 359.499421 -388.971349) (xy 359.469955 -388.925499) (xy 359.447313 -388.875922) (xy 359.431958 -388.823627)
			(xy 359.424202 -388.769679) (xy 359.423716 -388.742428) (xy 358.68864 -388.742428) (xy 358.68864 -388.883398)
			(xy 358.688238 -388.895523) (xy 358.680744 -388.918585) (xy 358.666488 -388.938202) (xy 358.646867 -388.952453)
			(xy 358.623803 -388.959941) (xy 358.611678 -388.96036) (xy 357.925878 -388.96036) (xy 357.913762 -388.959907)
			(xy 357.890718 -388.952414) (xy 357.871116 -388.938167) (xy 357.856875 -388.918561) (xy 357.849389 -388.895514)
			(xy 357.848916 -388.883398) (xy 327.631973 -388.883398) (xy 327.612745 -388.925499) (xy 327.583279 -388.971349)
			(xy 327.547588 -389.01254) (xy 327.506397 -389.048231) (xy 327.460547 -389.077697) (xy 327.41097 -389.100339)
			(xy 327.358675 -389.115694) (xy 327.304727 -389.12345) (xy 327.250225 -389.12345) (xy 327.196277 -389.115694)
			(xy 327.143982 -389.100339) (xy 327.094405 -389.077697) (xy 327.048555 -389.048231) (xy 327.007364 -389.01254)
			(xy 326.971673 -388.971349) (xy 326.942207 -388.925499) (xy 326.919565 -388.875922) (xy 326.90421 -388.823627)
			(xy 326.896454 -388.769679) (xy 326.895968 -388.742428) (xy 326.160892 -388.742428) (xy 326.160892 -388.883398)
			(xy 326.160387 -388.895509) (xy 326.152904 -388.918547) (xy 326.138669 -388.938147) (xy 326.119076 -388.952389)
			(xy 326.096041 -388.959882) (xy 326.08393 -388.96036) (xy 325.39813 -388.96036) (xy 325.386009 -388.959915)
			(xy 325.36295 -388.95243) (xy 325.343335 -388.938185) (xy 325.329083 -388.918575) (xy 325.32159 -388.895519)
			(xy 325.321168 -388.883398) (xy 281.2288 -388.883398) (xy 281.2288 -390.75106) (xy 297.048936 -390.75106)
			(xy 297.048936 -389.88746) (xy 297.049422 -389.860209) (xy 297.057178 -389.806261) (xy 297.072533 -389.753966)
			(xy 297.095175 -389.704389) (xy 297.124641 -389.658539) (xy 297.160332 -389.617348) (xy 297.201523 -389.581657)
			(xy 297.247373 -389.552191) (xy 297.29695 -389.529549) (xy 297.349245 -389.514194) (xy 297.403193 -389.506438)
			(xy 297.457695 -389.506438) (xy 297.511643 -389.514194) (xy 297.563938 -389.529549) (xy 297.613515 -389.552191)
			(xy 297.659365 -389.581657) (xy 297.700556 -389.617348) (xy 297.736247 -389.658539) (xy 297.765713 -389.704389)
			(xy 297.788355 -389.753966) (xy 297.80371 -389.806261) (xy 297.811466 -389.860209) (xy 297.811952 -389.88746)
			(xy 297.811952 -390.75106) (xy 297.811466 -390.778311) (xy 297.80371 -390.832259) (xy 297.788355 -390.884554)
			(xy 297.784941 -390.89203) (xy 298.547536 -390.89203) (xy 298.547536 -390.697466) (xy 298.547954 -390.686341)
			(xy 298.554411 -390.665044) (xy 298.560236 -390.655556) (xy 298.752768 -390.360662) (xy 298.758503 -390.351294)
			(xy 298.764768 -390.330246) (xy 298.764758 -390.308287) (xy 298.758475 -390.287245) (xy 298.752768 -390.277858)
			(xy 298.560236 -389.984234) (xy 298.554417 -389.974745) (xy 298.547974 -389.953447) (xy 298.547536 -389.942324)
			(xy 298.547536 -389.74649) (xy 298.548003 -389.734375) (xy 298.555493 -389.711332) (xy 298.569736 -389.691731)
			(xy 298.589339 -389.677489) (xy 298.612383 -389.670002) (xy 298.624498 -389.669528) (xy 299.310298 -389.669528)
			(xy 299.322411 -389.670013) (xy 299.345453 -389.677499) (xy 299.365054 -389.691738) (xy 299.379296 -389.711336)
			(xy 299.386785 -389.734377) (xy 299.38726 -389.74649) (xy 299.38726 -389.941054) (xy 299.386851 -389.95218)
			(xy 299.380388 -389.973477) (xy 299.37456 -389.982964) (xy 299.182028 -390.276588) (xy 299.176313 -390.285966)
			(xy 299.169977 -390.306981) (xy 299.169906 -390.328931) (xy 299.176106 -390.349987) (xy 299.181774 -390.359392)
			(xy 299.37456 -390.655556) (xy 299.380375 -390.665047) (xy 299.386821 -390.686343) (xy 299.38726 -390.697466)
			(xy 299.38726 -390.75106) (xy 329.576684 -390.75106) (xy 329.576684 -389.88746) (xy 329.57717 -389.860209)
			(xy 329.584926 -389.806261) (xy 329.600281 -389.753966) (xy 329.622923 -389.704389) (xy 329.652389 -389.658539)
			(xy 329.68808 -389.617348) (xy 329.729271 -389.581657) (xy 329.775121 -389.552191) (xy 329.824698 -389.529549)
			(xy 329.876993 -389.514194) (xy 329.930941 -389.506438) (xy 329.985443 -389.506438) (xy 330.039391 -389.514194)
			(xy 330.091686 -389.529549) (xy 330.141263 -389.552191) (xy 330.187113 -389.581657) (xy 330.228304 -389.617348)
			(xy 330.263995 -389.658539) (xy 330.293461 -389.704389) (xy 330.316103 -389.753966) (xy 330.331458 -389.806261)
			(xy 330.339214 -389.860209) (xy 330.3397 -389.88746) (xy 330.3397 -390.75106) (xy 330.339214 -390.778311)
			(xy 330.331458 -390.832259) (xy 330.316103 -390.884554) (xy 330.312689 -390.89203) (xy 331.075284 -390.89203)
			(xy 331.075284 -390.697466) (xy 331.075695 -390.68634) (xy 331.082156 -390.665043) (xy 331.087984 -390.655556)
			(xy 331.280516 -390.360662) (xy 331.286255 -390.351295) (xy 331.292524 -390.330247) (xy 331.292514 -390.308286)
			(xy 331.286227 -390.287244) (xy 331.280516 -390.277858) (xy 331.087984 -389.984234) (xy 331.082161 -389.974748)
			(xy 331.075721 -389.953447) (xy 331.075284 -389.942324) (xy 331.075284 -389.74649) (xy 331.075652 -389.734362)
			(xy 331.083153 -389.711295) (xy 331.097416 -389.691676) (xy 331.117045 -389.677427) (xy 331.140118 -389.669944)
			(xy 331.152246 -389.669528) (xy 331.838046 -389.669528) (xy 331.850162 -389.669972) (xy 331.873205 -389.677471)
			(xy 331.892805 -389.691721) (xy 331.907045 -389.711327) (xy 331.914533 -389.734374) (xy 331.915008 -389.74649)
			(xy 331.915008 -389.941054) (xy 331.914592 -389.952179) (xy 331.908133 -389.973476) (xy 331.902308 -389.982964)
			(xy 331.709776 -390.276588) (xy 331.704064 -390.285967) (xy 331.697732 -390.306982) (xy 331.697661 -390.32893)
			(xy 331.703857 -390.349986) (xy 331.709522 -390.359392) (xy 331.902308 -390.655556) (xy 331.908127 -390.665045)
			(xy 331.914569 -390.686343) (xy 331.915008 -390.697466) (xy 331.915008 -390.75106) (xy 364.149132 -390.75106)
			(xy 364.149132 -389.88746) (xy 364.149618 -389.860209) (xy 364.157374 -389.806261) (xy 364.172729 -389.753966)
			(xy 364.195371 -389.704389) (xy 364.224837 -389.658539) (xy 364.260528 -389.617348) (xy 364.301719 -389.581657)
			(xy 364.347569 -389.552191) (xy 364.397146 -389.529549) (xy 364.449441 -389.514194) (xy 364.503389 -389.506438)
			(xy 364.557891 -389.506438) (xy 364.611839 -389.514194) (xy 364.664134 -389.529549) (xy 364.713711 -389.552191)
			(xy 364.759561 -389.581657) (xy 364.800752 -389.617348) (xy 364.836443 -389.658539) (xy 364.865909 -389.704389)
			(xy 364.888551 -389.753966) (xy 364.903906 -389.806261) (xy 364.911662 -389.860209) (xy 364.912148 -389.88746)
			(xy 364.912148 -390.75106) (xy 364.911662 -390.778311) (xy 364.903906 -390.832259) (xy 364.888551 -390.884554)
			(xy 364.885021 -390.892284) (xy 365.647732 -390.892284) (xy 365.647732 -390.697466) (xy 365.648096 -390.686358)
			(xy 365.65442 -390.665062) (xy 365.660178 -390.655556) (xy 365.85271 -390.360662) (xy 365.858449 -390.351295)
			(xy 365.864719 -390.330247) (xy 365.864709 -390.308286) (xy 365.858421 -390.287244) (xy 365.85271 -390.277858)
			(xy 365.660178 -389.984234) (xy 365.654427 -389.974725) (xy 365.648104 -389.953431) (xy 365.647732 -389.942324)
			(xy 365.647732 -389.74649) (xy 365.648199 -389.734401) (xy 365.655657 -389.711401) (xy 365.669844 -389.691822)
			(xy 365.689377 -389.677572) (xy 365.712352 -389.670039) (xy 365.72444 -389.669528) (xy 366.41024 -389.669528)
			(xy 366.42232 -389.669931) (xy 366.445295 -389.677408) (xy 366.464834 -389.69162) (xy 366.479026 -389.711173)
			(xy 366.486481 -389.734155) (xy 366.486948 -389.746236) (xy 366.486948 -389.941054) (xy 366.486574 -389.952159)
			(xy 366.480246 -389.973452) (xy 366.474502 -389.982964) (xy 366.28197 -390.276588) (xy 366.276259 -390.285967)
			(xy 366.269927 -390.306982) (xy 366.269856 -390.32893) (xy 366.276051 -390.349986) (xy 366.281716 -390.359392)
			(xy 366.474502 -390.655556) (xy 366.480248 -390.665068) (xy 366.486575 -390.68636) (xy 366.486948 -390.697466)
			(xy 366.486948 -390.75106) (xy 396.67688 -390.75106) (xy 396.67688 -389.88746) (xy 396.677366 -389.860209)
			(xy 396.685122 -389.806261) (xy 396.700477 -389.753966) (xy 396.723119 -389.704389) (xy 396.752585 -389.658539)
			(xy 396.788276 -389.617348) (xy 396.829467 -389.581657) (xy 396.875317 -389.552191) (xy 396.924894 -389.529549)
			(xy 396.977189 -389.514194) (xy 397.031137 -389.506438) (xy 397.085639 -389.506438) (xy 397.139587 -389.514194)
			(xy 397.191882 -389.529549) (xy 397.241459 -389.552191) (xy 397.287309 -389.581657) (xy 397.3285 -389.617348)
			(xy 397.364191 -389.658539) (xy 397.393657 -389.704389) (xy 397.416299 -389.753966) (xy 397.431654 -389.806261)
			(xy 397.43941 -389.860209) (xy 397.439896 -389.88746) (xy 397.439896 -390.75106) (xy 397.43941 -390.778311)
			(xy 397.431654 -390.832259) (xy 397.416299 -390.884554) (xy 397.412769 -390.892284) (xy 398.17548 -390.892284)
			(xy 398.17548 -390.697466) (xy 398.175852 -390.686359) (xy 398.182171 -390.665063) (xy 398.187926 -390.655556)
			(xy 398.380458 -390.360662) (xy 398.386194 -390.351294) (xy 398.392459 -390.330247) (xy 398.39245 -390.308287)
			(xy 398.386166 -390.287245) (xy 398.380458 -390.277858) (xy 398.187926 -389.984234) (xy 398.182179 -389.974723)
			(xy 398.175852 -389.95343) (xy 398.17548 -389.942324) (xy 398.17548 -389.74649) (xy 398.1759 -389.734396)
			(xy 398.183364 -389.711388) (xy 398.197561 -389.691805) (xy 398.217107 -389.677556) (xy 398.240095 -389.670032)
			(xy 398.252188 -389.669528) (xy 398.937988 -389.669528) (xy 398.950074 -389.669924) (xy 398.973062 -389.677392)
			(xy 398.992616 -389.691602) (xy 399.006819 -389.71116) (xy 399.01428 -389.73415) (xy 399.014696 -389.746236)
			(xy 399.014696 -389.941054) (xy 399.014314 -389.952159) (xy 399.007991 -389.97345) (xy 399.00225 -389.982964)
			(xy 398.809718 -390.276588) (xy 398.804004 -390.285966) (xy 398.797668 -390.306981) (xy 398.797597 -390.328931)
			(xy 398.803796 -390.349987) (xy 398.809464 -390.359392) (xy 399.00225 -390.655556) (xy 399.008 -390.665066)
			(xy 399.014324 -390.68636) (xy 399.014696 -390.697466) (xy 399.014696 -390.89203) (xy 399.014219 -390.904118)
			(xy 399.006758 -390.927113) (xy 398.992573 -390.946689) (xy 398.973044 -390.96094) (xy 398.950074 -390.968478)
			(xy 398.937988 -390.968992) (xy 398.252188 -390.968992) (xy 398.240103 -390.968597) (xy 398.217117 -390.961125)
			(xy 398.197566 -390.946914) (xy 398.183363 -390.927358) (xy 398.175898 -390.904369) (xy 398.17548 -390.892284)
			(xy 397.412769 -390.892284) (xy 397.393657 -390.934131) (xy 397.364191 -390.979981) (xy 397.3285 -391.021172)
			(xy 397.287309 -391.056863) (xy 397.241459 -391.086329) (xy 397.191882 -391.108971) (xy 397.139587 -391.124326)
			(xy 397.085639 -391.132082) (xy 397.031137 -391.132082) (xy 396.977189 -391.124326) (xy 396.924894 -391.108971)
			(xy 396.875317 -391.086329) (xy 396.829467 -391.056863) (xy 396.788276 -391.021172) (xy 396.752585 -390.979981)
			(xy 396.723119 -390.934131) (xy 396.700477 -390.884554) (xy 396.685122 -390.832259) (xy 396.677366 -390.778311)
			(xy 396.67688 -390.75106) (xy 366.486948 -390.75106) (xy 366.486948 -390.89203) (xy 366.486518 -390.904122)
			(xy 366.479052 -390.927126) (xy 366.464856 -390.946706) (xy 366.445314 -390.960956) (xy 366.422331 -390.968485)
			(xy 366.41024 -390.968992) (xy 365.72444 -390.968992) (xy 365.712358 -390.968553) (xy 365.689374 -390.961095)
			(xy 365.669821 -390.946896) (xy 365.655616 -390.927348) (xy 365.648151 -390.904366) (xy 365.647732 -390.892284)
			(xy 364.885021 -390.892284) (xy 364.865909 -390.934131) (xy 364.836443 -390.979981) (xy 364.800752 -391.021172)
			(xy 364.759561 -391.056863) (xy 364.713711 -391.086329) (xy 364.664134 -391.108971) (xy 364.611839 -391.124326)
			(xy 364.557891 -391.132082) (xy 364.503389 -391.132082) (xy 364.449441 -391.124326) (xy 364.397146 -391.108971)
			(xy 364.347569 -391.086329) (xy 364.301719 -391.056863) (xy 364.260528 -391.021172) (xy 364.224837 -390.979981)
			(xy 364.195371 -390.934131) (xy 364.172729 -390.884554) (xy 364.157374 -390.832259) (xy 364.149618 -390.778311)
			(xy 364.149132 -390.75106) (xy 331.915008 -390.75106) (xy 331.915008 -390.89203) (xy 331.914515 -390.904142)
			(xy 331.907025 -390.927178) (xy 331.892787 -390.946775) (xy 331.873192 -390.961017) (xy 331.850157 -390.968512)
			(xy 331.838046 -390.968992) (xy 331.152246 -390.968992) (xy 331.140129 -390.968501) (xy 331.117076 -390.961025)
			(xy 331.097463 -390.946791) (xy 331.083209 -390.927192) (xy 331.07571 -390.904147) (xy 331.075284 -390.89203)
			(xy 330.312689 -390.89203) (xy 330.293461 -390.934131) (xy 330.263995 -390.979981) (xy 330.228304 -391.021172)
			(xy 330.187113 -391.056863) (xy 330.141263 -391.086329) (xy 330.091686 -391.108971) (xy 330.039391 -391.124326)
			(xy 329.985443 -391.132082) (xy 329.930941 -391.132082) (xy 329.876993 -391.124326) (xy 329.824698 -391.108971)
			(xy 329.775121 -391.086329) (xy 329.729271 -391.056863) (xy 329.68808 -391.021172) (xy 329.652389 -390.979981)
			(xy 329.622923 -390.934131) (xy 329.600281 -390.884554) (xy 329.584926 -390.832259) (xy 329.57717 -390.778311)
			(xy 329.576684 -390.75106) (xy 299.38726 -390.75106) (xy 299.38726 -390.89203) (xy 299.386814 -390.904146)
			(xy 299.379318 -390.927191) (xy 299.36507 -390.946792) (xy 299.345462 -390.961033) (xy 299.322415 -390.968519)
			(xy 299.310298 -390.968992) (xy 298.624498 -390.968992) (xy 298.612386 -390.96849) (xy 298.589348 -390.961006)
			(xy 298.569749 -390.946771) (xy 298.555507 -390.927177) (xy 298.548014 -390.904141) (xy 298.547536 -390.89203)
			(xy 297.784941 -390.89203) (xy 297.765713 -390.934131) (xy 297.736247 -390.979981) (xy 297.700556 -391.021172)
			(xy 297.659365 -391.056863) (xy 297.613515 -391.086329) (xy 297.563938 -391.108971) (xy 297.511643 -391.124326)
			(xy 297.457695 -391.132082) (xy 297.403193 -391.132082) (xy 297.349245 -391.124326) (xy 297.29695 -391.108971)
			(xy 297.247373 -391.086329) (xy 297.201523 -391.056863) (xy 297.160332 -391.021172) (xy 297.124641 -390.979981)
			(xy 297.095175 -390.934131) (xy 297.072533 -390.884554) (xy 297.057178 -390.832259) (xy 297.049422 -390.778311)
			(xy 297.048936 -390.75106) (xy 281.2288 -390.75106) (xy 281.2288 -391.822686) (xy 302.989996 -391.822686)
			(xy 302.989996 -391.746486) (xy 302.990462 -391.731029) (xy 302.99786 -391.701015) (xy 303.012226 -391.673642)
			(xy 303.032725 -391.650504) (xy 303.058166 -391.632943) (xy 303.08707 -391.621981) (xy 303.117758 -391.618255)
			(xy 303.148446 -391.621981) (xy 303.17735 -391.632943) (xy 303.202791 -391.650504) (xy 303.22329 -391.673642)
			(xy 303.237656 -391.701015) (xy 303.245054 -391.731029) (xy 303.24552 -391.746486) (xy 303.24552 -391.822686)
			(xy 304.189892 -391.822686) (xy 304.189892 -391.746486) (xy 304.190358 -391.731029) (xy 304.197756 -391.701015)
			(xy 304.212122 -391.673642) (xy 304.232621 -391.650504) (xy 304.258062 -391.632943) (xy 304.286966 -391.621981)
			(xy 304.317654 -391.618255) (xy 304.348342 -391.621981) (xy 304.377246 -391.632943) (xy 304.402687 -391.650504)
			(xy 304.423186 -391.673642) (xy 304.437552 -391.701015) (xy 304.44495 -391.731029) (xy 304.445416 -391.746486)
			(xy 304.445416 -391.822686) (xy 305.390296 -391.822686) (xy 305.390296 -391.746486) (xy 305.390761 -391.73106)
			(xy 305.398144 -391.701105) (xy 305.412481 -391.673787) (xy 305.43294 -391.650694) (xy 305.45833 -391.633168)
			(xy 305.487177 -391.622228) (xy 305.517804 -391.61851) (xy 305.548431 -391.622228) (xy 305.577278 -391.633168)
			(xy 305.602668 -391.650694) (xy 305.623127 -391.673787) (xy 305.637464 -391.701105) (xy 305.644847 -391.73106)
			(xy 305.645312 -391.746486) (xy 305.645312 -391.822686) (xy 306.590192 -391.822686) (xy 306.590192 -391.746486)
			(xy 306.590657 -391.73106) (xy 306.59804 -391.701105) (xy 306.612377 -391.673787) (xy 306.632836 -391.650694)
			(xy 306.658226 -391.633168) (xy 306.687073 -391.622228) (xy 306.7177 -391.61851) (xy 306.748327 -391.622228)
			(xy 306.777174 -391.633168) (xy 306.802564 -391.650694) (xy 306.823023 -391.673787) (xy 306.83736 -391.701105)
			(xy 306.844743 -391.73106) (xy 306.845208 -391.746486) (xy 306.845208 -391.822686) (xy 307.790088 -391.822686)
			(xy 307.790088 -391.746486) (xy 307.790554 -391.731029) (xy 307.797952 -391.701015) (xy 307.812318 -391.673642)
			(xy 307.832817 -391.650504) (xy 307.858258 -391.632943) (xy 307.887162 -391.621981) (xy 307.91785 -391.618255)
			(xy 307.948538 -391.621981) (xy 307.977442 -391.632943) (xy 308.002883 -391.650504) (xy 308.023382 -391.673642)
			(xy 308.037748 -391.701015) (xy 308.045146 -391.731029) (xy 308.045612 -391.746486) (xy 308.045612 -391.822686)
			(xy 308.989984 -391.822686) (xy 308.989984 -391.746486) (xy 308.99045 -391.731029) (xy 308.997848 -391.701015)
			(xy 309.012214 -391.673642) (xy 309.032713 -391.650504) (xy 309.058154 -391.632943) (xy 309.087058 -391.621981)
			(xy 309.117746 -391.618255) (xy 309.148434 -391.621981) (xy 309.177338 -391.632943) (xy 309.202779 -391.650504)
			(xy 309.223278 -391.673642) (xy 309.237644 -391.701015) (xy 309.245042 -391.731029) (xy 309.245508 -391.746486)
			(xy 309.245508 -391.822686) (xy 310.190388 -391.822686) (xy 310.190388 -391.746486) (xy 310.190853 -391.73106)
			(xy 310.198236 -391.701105) (xy 310.212573 -391.673787) (xy 310.233032 -391.650694) (xy 310.258422 -391.633168)
			(xy 310.287269 -391.622228) (xy 310.317896 -391.61851) (xy 310.348523 -391.622228) (xy 310.37737 -391.633168)
			(xy 310.40276 -391.650694) (xy 310.423219 -391.673787) (xy 310.437556 -391.701105) (xy 310.444939 -391.73106)
			(xy 310.445404 -391.746486) (xy 310.445404 -391.822686) (xy 311.390284 -391.822686) (xy 311.390284 -391.746486)
			(xy 311.390749 -391.73106) (xy 311.398132 -391.701105) (xy 311.412469 -391.673787) (xy 311.432928 -391.650694)
			(xy 311.458318 -391.633168) (xy 311.487165 -391.622228) (xy 311.517792 -391.61851) (xy 311.548419 -391.622228)
			(xy 311.577266 -391.633168) (xy 311.602656 -391.650694) (xy 311.623115 -391.673787) (xy 311.637452 -391.701105)
			(xy 311.644835 -391.73106) (xy 311.6453 -391.746486) (xy 311.6453 -391.822686) (xy 312.59018 -391.822686)
			(xy 312.59018 -391.746486) (xy 312.590645 -391.73106) (xy 312.598028 -391.701105) (xy 312.612365 -391.673787)
			(xy 312.632824 -391.650694) (xy 312.658214 -391.633168) (xy 312.687061 -391.622228) (xy 312.717688 -391.61851)
			(xy 312.748315 -391.622228) (xy 312.777162 -391.633168) (xy 312.802552 -391.650694) (xy 312.823011 -391.673787)
			(xy 312.837348 -391.701105) (xy 312.844731 -391.73106) (xy 312.845196 -391.746486) (xy 312.845196 -391.822686)
			(xy 313.790076 -391.822686) (xy 313.790076 -391.746486) (xy 313.790542 -391.731029) (xy 313.79794 -391.701015)
			(xy 313.812306 -391.673642) (xy 313.832805 -391.650504) (xy 313.858246 -391.632943) (xy 313.88715 -391.621981)
			(xy 313.917838 -391.618255) (xy 313.948526 -391.621981) (xy 313.97743 -391.632943) (xy 314.002871 -391.650504)
			(xy 314.02337 -391.673642) (xy 314.037736 -391.701015) (xy 314.045134 -391.731029) (xy 314.0456 -391.746486)
			(xy 314.0456 -391.822686) (xy 314.989972 -391.822686) (xy 314.989972 -391.746486) (xy 314.990438 -391.731029)
			(xy 314.997836 -391.701015) (xy 315.012202 -391.673642) (xy 315.032701 -391.650504) (xy 315.058142 -391.632943)
			(xy 315.087046 -391.621981) (xy 315.117734 -391.618255) (xy 315.148422 -391.621981) (xy 315.177326 -391.632943)
			(xy 315.202767 -391.650504) (xy 315.223266 -391.673642) (xy 315.237632 -391.701015) (xy 315.24503 -391.731029)
			(xy 315.245496 -391.746486) (xy 315.245496 -391.822686) (xy 316.190376 -391.822686) (xy 316.190376 -391.746486)
			(xy 316.190841 -391.73106) (xy 316.198224 -391.701105) (xy 316.212561 -391.673787) (xy 316.23302 -391.650694)
			(xy 316.25841 -391.633168) (xy 316.287257 -391.622228) (xy 316.317884 -391.61851) (xy 316.348511 -391.622228)
			(xy 316.377358 -391.633168) (xy 316.402748 -391.650694) (xy 316.423207 -391.673787) (xy 316.437544 -391.701105)
			(xy 316.444927 -391.73106) (xy 316.445392 -391.746486) (xy 316.445392 -391.822686) (xy 317.390272 -391.822686)
			(xy 317.390272 -391.746486) (xy 317.390737 -391.73106) (xy 317.39812 -391.701105) (xy 317.412457 -391.673787)
			(xy 317.432916 -391.650694) (xy 317.458306 -391.633168) (xy 317.487153 -391.622228) (xy 317.51778 -391.61851)
			(xy 317.548407 -391.622228) (xy 317.577254 -391.633168) (xy 317.602644 -391.650694) (xy 317.623103 -391.673787)
			(xy 317.63744 -391.701105) (xy 317.644823 -391.73106) (xy 317.645288 -391.746486) (xy 317.645288 -391.822686)
			(xy 318.590168 -391.822686) (xy 318.590168 -391.746486) (xy 318.590633 -391.73106) (xy 318.598016 -391.701105)
			(xy 318.612353 -391.673787) (xy 318.632812 -391.650694) (xy 318.658202 -391.633168) (xy 318.687049 -391.622228)
			(xy 318.717676 -391.61851) (xy 318.748303 -391.622228) (xy 318.77715 -391.633168) (xy 318.80254 -391.650694)
			(xy 318.822999 -391.673787) (xy 318.837336 -391.701105) (xy 318.844719 -391.73106) (xy 318.845184 -391.746486)
			(xy 318.845184 -391.822686) (xy 319.790064 -391.822686) (xy 319.790064 -391.746486) (xy 319.79053 -391.731029)
			(xy 319.797928 -391.701015) (xy 319.812294 -391.673642) (xy 319.832793 -391.650504) (xy 319.858234 -391.632943)
			(xy 319.887138 -391.621981) (xy 319.917826 -391.618255) (xy 319.948514 -391.621981) (xy 319.977418 -391.632943)
			(xy 320.002859 -391.650504) (xy 320.023358 -391.673642) (xy 320.037724 -391.701015) (xy 320.045122 -391.731029)
			(xy 320.045588 -391.746486) (xy 320.045588 -391.822686) (xy 320.98996 -391.822686) (xy 320.98996 -391.746486)
			(xy 320.990426 -391.731029) (xy 320.997824 -391.701015) (xy 321.01219 -391.673642) (xy 321.032689 -391.650504)
			(xy 321.05813 -391.632943) (xy 321.087034 -391.621981) (xy 321.117722 -391.618255) (xy 321.14841 -391.621981)
			(xy 321.177314 -391.632943) (xy 321.202755 -391.650504) (xy 321.223254 -391.673642) (xy 321.23762 -391.701015)
			(xy 321.245018 -391.731029) (xy 321.245484 -391.746486) (xy 321.245484 -391.822686) (xy 335.517744 -391.822686)
			(xy 335.517744 -391.746486) (xy 335.51821 -391.731029) (xy 335.525608 -391.701015) (xy 335.539974 -391.673642)
			(xy 335.560473 -391.650504) (xy 335.585914 -391.632943) (xy 335.614818 -391.621981) (xy 335.645506 -391.618255)
			(xy 335.676194 -391.621981) (xy 335.705098 -391.632943) (xy 335.730539 -391.650504) (xy 335.751038 -391.673642)
			(xy 335.765404 -391.701015) (xy 335.772802 -391.731029) (xy 335.773268 -391.746486) (xy 335.773268 -391.822686)
			(xy 336.71764 -391.822686) (xy 336.71764 -391.746486) (xy 336.718106 -391.731029) (xy 336.725504 -391.701015)
			(xy 336.73987 -391.673642) (xy 336.760369 -391.650504) (xy 336.78581 -391.632943) (xy 336.814714 -391.621981)
			(xy 336.845402 -391.618255) (xy 336.87609 -391.621981) (xy 336.904994 -391.632943) (xy 336.930435 -391.650504)
			(xy 336.950934 -391.673642) (xy 336.9653 -391.701015) (xy 336.972698 -391.731029) (xy 336.973164 -391.746486)
			(xy 336.973164 -391.822686) (xy 337.918044 -391.822686) (xy 337.918044 -391.746486) (xy 337.918509 -391.73106)
			(xy 337.925892 -391.701105) (xy 337.940229 -391.673787) (xy 337.960688 -391.650694) (xy 337.986078 -391.633168)
			(xy 338.014925 -391.622228) (xy 338.045552 -391.61851) (xy 338.076179 -391.622228) (xy 338.105026 -391.633168)
			(xy 338.130416 -391.650694) (xy 338.150875 -391.673787) (xy 338.165212 -391.701105) (xy 338.172595 -391.73106)
			(xy 338.17306 -391.746486) (xy 338.17306 -391.822686) (xy 339.11794 -391.822686) (xy 339.11794 -391.746486)
			(xy 339.118405 -391.73106) (xy 339.125788 -391.701105) (xy 339.140125 -391.673787) (xy 339.160584 -391.650694)
			(xy 339.185974 -391.633168) (xy 339.214821 -391.622228) (xy 339.245448 -391.61851) (xy 339.276075 -391.622228)
			(xy 339.304922 -391.633168) (xy 339.330312 -391.650694) (xy 339.350771 -391.673787) (xy 339.365108 -391.701105)
			(xy 339.372491 -391.73106) (xy 339.372956 -391.746486) (xy 339.372956 -391.822686) (xy 340.317836 -391.822686)
			(xy 340.317836 -391.746486) (xy 340.318302 -391.731029) (xy 340.3257 -391.701015) (xy 340.340066 -391.673642)
			(xy 340.360565 -391.650504) (xy 340.386006 -391.632943) (xy 340.41491 -391.621981) (xy 340.445598 -391.618255)
			(xy 340.476286 -391.621981) (xy 340.50519 -391.632943) (xy 340.530631 -391.650504) (xy 340.55113 -391.673642)
			(xy 340.565496 -391.701015) (xy 340.572894 -391.731029) (xy 340.57336 -391.746486) (xy 340.57336 -391.822686)
			(xy 341.517732 -391.822686) (xy 341.517732 -391.746486) (xy 341.518198 -391.731029) (xy 341.525596 -391.701015)
			(xy 341.539962 -391.673642) (xy 341.560461 -391.650504) (xy 341.585902 -391.632943) (xy 341.614806 -391.621981)
			(xy 341.645494 -391.618255) (xy 341.676182 -391.621981) (xy 341.705086 -391.632943) (xy 341.730527 -391.650504)
			(xy 341.751026 -391.673642) (xy 341.765392 -391.701015) (xy 341.77279 -391.731029) (xy 341.773256 -391.746486)
			(xy 341.773256 -391.822686) (xy 342.718136 -391.822686) (xy 342.718136 -391.746486) (xy 342.718601 -391.73106)
			(xy 342.725984 -391.701105) (xy 342.740321 -391.673787) (xy 342.76078 -391.650694) (xy 342.78617 -391.633168)
			(xy 342.815017 -391.622228) (xy 342.845644 -391.61851) (xy 342.876271 -391.622228) (xy 342.905118 -391.633168)
			(xy 342.930508 -391.650694) (xy 342.950967 -391.673787) (xy 342.965304 -391.701105) (xy 342.972687 -391.73106)
			(xy 342.973152 -391.746486) (xy 342.973152 -391.822686) (xy 343.918032 -391.822686) (xy 343.918032 -391.746486)
			(xy 343.918497 -391.73106) (xy 343.92588 -391.701105) (xy 343.940217 -391.673787) (xy 343.960676 -391.650694)
			(xy 343.986066 -391.633168) (xy 344.014913 -391.622228) (xy 344.04554 -391.61851) (xy 344.076167 -391.622228)
			(xy 344.105014 -391.633168) (xy 344.130404 -391.650694) (xy 344.150863 -391.673787) (xy 344.1652 -391.701105)
			(xy 344.172583 -391.73106) (xy 344.173048 -391.746486) (xy 344.173048 -391.822686) (xy 345.117928 -391.822686)
			(xy 345.117928 -391.746486) (xy 345.118393 -391.73106) (xy 345.125776 -391.701105) (xy 345.140113 -391.673787)
			(xy 345.160572 -391.650694) (xy 345.185962 -391.633168) (xy 345.214809 -391.622228) (xy 345.245436 -391.61851)
			(xy 345.276063 -391.622228) (xy 345.30491 -391.633168) (xy 345.3303 -391.650694) (xy 345.350759 -391.673787)
			(xy 345.365096 -391.701105) (xy 345.372479 -391.73106) (xy 345.372944 -391.746486) (xy 345.372944 -391.822686)
			(xy 346.317824 -391.822686) (xy 346.317824 -391.746486) (xy 346.31829 -391.731029) (xy 346.325688 -391.701015)
			(xy 346.340054 -391.673642) (xy 346.360553 -391.650504) (xy 346.385994 -391.632943) (xy 346.414898 -391.621981)
			(xy 346.445586 -391.618255) (xy 346.476274 -391.621981) (xy 346.505178 -391.632943) (xy 346.530619 -391.650504)
			(xy 346.551118 -391.673642) (xy 346.565484 -391.701015) (xy 346.572882 -391.731029) (xy 346.573348 -391.746486)
			(xy 346.573348 -391.822686) (xy 347.51772 -391.822686) (xy 347.51772 -391.746486) (xy 347.518186 -391.731029)
			(xy 347.525584 -391.701015) (xy 347.53995 -391.673642) (xy 347.560449 -391.650504) (xy 347.58589 -391.632943)
			(xy 347.614794 -391.621981) (xy 347.645482 -391.618255) (xy 347.67617 -391.621981) (xy 347.705074 -391.632943)
			(xy 347.730515 -391.650504) (xy 347.751014 -391.673642) (xy 347.76538 -391.701015) (xy 347.772778 -391.731029)
			(xy 347.773244 -391.746486) (xy 347.773244 -391.822686) (xy 348.718124 -391.822686) (xy 348.718124 -391.746486)
			(xy 348.718589 -391.73106) (xy 348.725972 -391.701105) (xy 348.740309 -391.673787) (xy 348.760768 -391.650694)
			(xy 348.786158 -391.633168) (xy 348.815005 -391.622228) (xy 348.845632 -391.61851) (xy 348.876259 -391.622228)
			(xy 348.905106 -391.633168) (xy 348.930496 -391.650694) (xy 348.950955 -391.673787) (xy 348.965292 -391.701105)
			(xy 348.972675 -391.73106) (xy 348.97314 -391.746486) (xy 348.97314 -391.822686) (xy 349.91802 -391.822686)
			(xy 349.91802 -391.746486) (xy 349.918485 -391.73106) (xy 349.925868 -391.701105) (xy 349.940205 -391.673787)
			(xy 349.960664 -391.650694) (xy 349.986054 -391.633168) (xy 350.014901 -391.622228) (xy 350.045528 -391.61851)
			(xy 350.076155 -391.622228) (xy 350.105002 -391.633168) (xy 350.130392 -391.650694) (xy 350.150851 -391.673787)
			(xy 350.165188 -391.701105) (xy 350.172571 -391.73106) (xy 350.173036 -391.746486) (xy 350.173036 -391.822686)
			(xy 351.117916 -391.822686) (xy 351.117916 -391.746486) (xy 351.118381 -391.73106) (xy 351.125764 -391.701105)
			(xy 351.140101 -391.673787) (xy 351.16056 -391.650694) (xy 351.18595 -391.633168) (xy 351.214797 -391.622228)
			(xy 351.245424 -391.61851) (xy 351.276051 -391.622228) (xy 351.304898 -391.633168) (xy 351.330288 -391.650694)
			(xy 351.350747 -391.673787) (xy 351.365084 -391.701105) (xy 351.372467 -391.73106) (xy 351.372932 -391.746486)
			(xy 351.372932 -391.822686) (xy 352.317812 -391.822686) (xy 352.317812 -391.746486) (xy 352.318278 -391.731029)
			(xy 352.325676 -391.701015) (xy 352.340042 -391.673642) (xy 352.360541 -391.650504) (xy 352.385982 -391.632943)
			(xy 352.414886 -391.621981) (xy 352.445574 -391.618255) (xy 352.476262 -391.621981) (xy 352.505166 -391.632943)
			(xy 352.530607 -391.650504) (xy 352.551106 -391.673642) (xy 352.565472 -391.701015) (xy 352.57287 -391.731029)
			(xy 352.573336 -391.746486) (xy 352.573336 -391.822686) (xy 353.517708 -391.822686) (xy 353.517708 -391.746486)
			(xy 353.518174 -391.731029) (xy 353.525572 -391.701015) (xy 353.539938 -391.673642) (xy 353.560437 -391.650504)
			(xy 353.585878 -391.632943) (xy 353.614782 -391.621981) (xy 353.64547 -391.618255) (xy 353.676158 -391.621981)
			(xy 353.705062 -391.632943) (xy 353.730503 -391.650504) (xy 353.751002 -391.673642) (xy 353.765368 -391.701015)
			(xy 353.772766 -391.731029) (xy 353.773232 -391.746486) (xy 353.773232 -391.822686) (xy 370.090192 -391.822686)
			(xy 370.090192 -391.746486) (xy 370.090658 -391.731029) (xy 370.098056 -391.701015) (xy 370.112422 -391.673642)
			(xy 370.132921 -391.650504) (xy 370.158362 -391.632943) (xy 370.187266 -391.621981) (xy 370.217954 -391.618255)
			(xy 370.248642 -391.621981) (xy 370.277546 -391.632943) (xy 370.302987 -391.650504) (xy 370.323486 -391.673642)
			(xy 370.337852 -391.701015) (xy 370.34525 -391.731029) (xy 370.345716 -391.746486) (xy 370.345716 -391.822686)
			(xy 371.290088 -391.822686) (xy 371.290088 -391.746486) (xy 371.290554 -391.731029) (xy 371.297952 -391.701015)
			(xy 371.312318 -391.673642) (xy 371.332817 -391.650504) (xy 371.358258 -391.632943) (xy 371.387162 -391.621981)
			(xy 371.41785 -391.618255) (xy 371.448538 -391.621981) (xy 371.477442 -391.632943) (xy 371.502883 -391.650504)
			(xy 371.523382 -391.673642) (xy 371.537748 -391.701015) (xy 371.545146 -391.731029) (xy 371.545612 -391.746486)
			(xy 371.545612 -391.822686) (xy 372.490492 -391.822686) (xy 372.490492 -391.746486) (xy 372.490957 -391.73106)
			(xy 372.49834 -391.701105) (xy 372.512677 -391.673787) (xy 372.533136 -391.650694) (xy 372.558526 -391.633168)
			(xy 372.587373 -391.622228) (xy 372.618 -391.61851) (xy 372.648627 -391.622228) (xy 372.677474 -391.633168)
			(xy 372.702864 -391.650694) (xy 372.723323 -391.673787) (xy 372.73766 -391.701105) (xy 372.745043 -391.73106)
			(xy 372.745508 -391.746486) (xy 372.745508 -391.822686) (xy 373.690388 -391.822686) (xy 373.690388 -391.746486)
			(xy 373.690853 -391.73106) (xy 373.698236 -391.701105) (xy 373.712573 -391.673787) (xy 373.733032 -391.650694)
			(xy 373.758422 -391.633168) (xy 373.787269 -391.622228) (xy 373.817896 -391.61851) (xy 373.848523 -391.622228)
			(xy 373.87737 -391.633168) (xy 373.90276 -391.650694) (xy 373.923219 -391.673787) (xy 373.937556 -391.701105)
			(xy 373.944939 -391.73106) (xy 373.945404 -391.746486) (xy 373.945404 -391.822686) (xy 374.890284 -391.822686)
			(xy 374.890284 -391.746486) (xy 374.89075 -391.731029) (xy 374.898148 -391.701015) (xy 374.912514 -391.673642)
			(xy 374.933013 -391.650504) (xy 374.958454 -391.632943) (xy 374.987358 -391.621981) (xy 375.018046 -391.618255)
			(xy 375.048734 -391.621981) (xy 375.077638 -391.632943) (xy 375.103079 -391.650504) (xy 375.123578 -391.673642)
			(xy 375.137944 -391.701015) (xy 375.145342 -391.731029) (xy 375.145808 -391.746486) (xy 375.145808 -391.822686)
			(xy 376.09018 -391.822686) (xy 376.09018 -391.746486) (xy 376.090646 -391.731029) (xy 376.098044 -391.701015)
			(xy 376.11241 -391.673642) (xy 376.132909 -391.650504) (xy 376.15835 -391.632943) (xy 376.187254 -391.621981)
			(xy 376.217942 -391.618255) (xy 376.24863 -391.621981) (xy 376.277534 -391.632943) (xy 376.302975 -391.650504)
			(xy 376.323474 -391.673642) (xy 376.33784 -391.701015) (xy 376.345238 -391.731029) (xy 376.345704 -391.746486)
			(xy 376.345704 -391.822686) (xy 377.290584 -391.822686) (xy 377.290584 -391.746486) (xy 377.291049 -391.73106)
			(xy 377.298432 -391.701105) (xy 377.312769 -391.673787) (xy 377.333228 -391.650694) (xy 377.358618 -391.633168)
			(xy 377.387465 -391.622228) (xy 377.418092 -391.61851) (xy 377.448719 -391.622228) (xy 377.477566 -391.633168)
			(xy 377.502956 -391.650694) (xy 377.523415 -391.673787) (xy 377.537752 -391.701105) (xy 377.545135 -391.73106)
			(xy 377.5456 -391.746486) (xy 377.5456 -391.822686) (xy 378.49048 -391.822686) (xy 378.49048 -391.746486)
			(xy 378.490945 -391.73106) (xy 378.498328 -391.701105) (xy 378.512665 -391.673787) (xy 378.533124 -391.650694)
			(xy 378.558514 -391.633168) (xy 378.587361 -391.622228) (xy 378.617988 -391.61851) (xy 378.648615 -391.622228)
			(xy 378.677462 -391.633168) (xy 378.702852 -391.650694) (xy 378.723311 -391.673787) (xy 378.737648 -391.701105)
			(xy 378.745031 -391.73106) (xy 378.745496 -391.746486) (xy 378.745496 -391.822686) (xy 379.690376 -391.822686)
			(xy 379.690376 -391.746486) (xy 379.690841 -391.73106) (xy 379.698224 -391.701105) (xy 379.712561 -391.673787)
			(xy 379.73302 -391.650694) (xy 379.75841 -391.633168) (xy 379.787257 -391.622228) (xy 379.817884 -391.61851)
			(xy 379.848511 -391.622228) (xy 379.877358 -391.633168) (xy 379.902748 -391.650694) (xy 379.923207 -391.673787)
			(xy 379.937544 -391.701105) (xy 379.944927 -391.73106) (xy 379.945392 -391.746486) (xy 379.945392 -391.822686)
			(xy 380.890272 -391.822686) (xy 380.890272 -391.746486) (xy 380.890738 -391.731029) (xy 380.898136 -391.701015)
			(xy 380.912502 -391.673642) (xy 380.933001 -391.650504) (xy 380.958442 -391.632943) (xy 380.987346 -391.621981)
			(xy 381.018034 -391.618255) (xy 381.048722 -391.621981) (xy 381.077626 -391.632943) (xy 381.103067 -391.650504)
			(xy 381.123566 -391.673642) (xy 381.137932 -391.701015) (xy 381.14533 -391.731029) (xy 381.145796 -391.746486)
			(xy 381.145796 -391.822686) (xy 382.090168 -391.822686) (xy 382.090168 -391.746486) (xy 382.090634 -391.731029)
			(xy 382.098032 -391.701015) (xy 382.112398 -391.673642) (xy 382.132897 -391.650504) (xy 382.158338 -391.632943)
			(xy 382.187242 -391.621981) (xy 382.21793 -391.618255) (xy 382.248618 -391.621981) (xy 382.277522 -391.632943)
			(xy 382.302963 -391.650504) (xy 382.323462 -391.673642) (xy 382.337828 -391.701015) (xy 382.345226 -391.731029)
			(xy 382.345692 -391.746486) (xy 382.345692 -391.822686) (xy 383.290572 -391.822686) (xy 383.290572 -391.746486)
			(xy 383.291037 -391.73106) (xy 383.29842 -391.701105) (xy 383.312757 -391.673787) (xy 383.333216 -391.650694)
			(xy 383.358606 -391.633168) (xy 383.387453 -391.622228) (xy 383.41808 -391.61851) (xy 383.448707 -391.622228)
			(xy 383.477554 -391.633168) (xy 383.502944 -391.650694) (xy 383.523403 -391.673787) (xy 383.53774 -391.701105)
			(xy 383.545123 -391.73106) (xy 383.545588 -391.746486) (xy 383.545588 -391.822686) (xy 384.490468 -391.822686)
			(xy 384.490468 -391.746486) (xy 384.490933 -391.73106) (xy 384.498316 -391.701105) (xy 384.512653 -391.673787)
			(xy 384.533112 -391.650694) (xy 384.558502 -391.633168) (xy 384.587349 -391.622228) (xy 384.617976 -391.61851)
			(xy 384.648603 -391.622228) (xy 384.67745 -391.633168) (xy 384.70284 -391.650694) (xy 384.723299 -391.673787)
			(xy 384.737636 -391.701105) (xy 384.745019 -391.73106) (xy 384.745484 -391.746486) (xy 384.745484 -391.822686)
			(xy 385.690364 -391.822686) (xy 385.690364 -391.746486) (xy 385.690829 -391.73106) (xy 385.698212 -391.701105)
			(xy 385.712549 -391.673787) (xy 385.733008 -391.650694) (xy 385.758398 -391.633168) (xy 385.787245 -391.622228)
			(xy 385.817872 -391.61851) (xy 385.848499 -391.622228) (xy 385.877346 -391.633168) (xy 385.902736 -391.650694)
			(xy 385.923195 -391.673787) (xy 385.937532 -391.701105) (xy 385.944915 -391.73106) (xy 385.94538 -391.746486)
			(xy 385.94538 -391.822686) (xy 386.89026 -391.822686) (xy 386.89026 -391.746486) (xy 386.890726 -391.731029)
			(xy 386.898124 -391.701015) (xy 386.91249 -391.673642) (xy 386.932989 -391.650504) (xy 386.95843 -391.632943)
			(xy 386.987334 -391.621981) (xy 387.018022 -391.618255) (xy 387.04871 -391.621981) (xy 387.077614 -391.632943)
			(xy 387.103055 -391.650504) (xy 387.123554 -391.673642) (xy 387.13792 -391.701015) (xy 387.145318 -391.731029)
			(xy 387.145784 -391.746486) (xy 387.145784 -391.822686) (xy 388.090156 -391.822686) (xy 388.090156 -391.746486)
			(xy 388.090622 -391.731029) (xy 388.09802 -391.701015) (xy 388.112386 -391.673642) (xy 388.132885 -391.650504)
			(xy 388.158326 -391.632943) (xy 388.18723 -391.621981) (xy 388.217918 -391.618255) (xy 388.248606 -391.621981)
			(xy 388.27751 -391.632943) (xy 388.302951 -391.650504) (xy 388.32345 -391.673642) (xy 388.337816 -391.701015)
			(xy 388.345214 -391.731029) (xy 388.34568 -391.746486) (xy 388.34568 -391.822686) (xy 402.61794 -391.822686)
			(xy 402.61794 -391.746486) (xy 402.618406 -391.731029) (xy 402.625804 -391.701015) (xy 402.64017 -391.673642)
			(xy 402.660669 -391.650504) (xy 402.68611 -391.632943) (xy 402.715014 -391.621981) (xy 402.745702 -391.618255)
			(xy 402.77639 -391.621981) (xy 402.805294 -391.632943) (xy 402.830735 -391.650504) (xy 402.851234 -391.673642)
			(xy 402.8656 -391.701015) (xy 402.872998 -391.731029) (xy 402.873464 -391.746486) (xy 402.873464 -391.822686)
			(xy 403.817836 -391.822686) (xy 403.817836 -391.746486) (xy 403.818302 -391.731029) (xy 403.8257 -391.701015)
			(xy 403.840066 -391.673642) (xy 403.860565 -391.650504) (xy 403.886006 -391.632943) (xy 403.91491 -391.621981)
			(xy 403.945598 -391.618255) (xy 403.976286 -391.621981) (xy 404.00519 -391.632943) (xy 404.030631 -391.650504)
			(xy 404.05113 -391.673642) (xy 404.065496 -391.701015) (xy 404.072894 -391.731029) (xy 404.07336 -391.746486)
			(xy 404.07336 -391.822686) (xy 405.01824 -391.822686) (xy 405.01824 -391.746486) (xy 405.018705 -391.73106)
			(xy 405.026088 -391.701105) (xy 405.040425 -391.673787) (xy 405.060884 -391.650694) (xy 405.086274 -391.633168)
			(xy 405.115121 -391.622228) (xy 405.145748 -391.61851) (xy 405.176375 -391.622228) (xy 405.205222 -391.633168)
			(xy 405.230612 -391.650694) (xy 405.251071 -391.673787) (xy 405.265408 -391.701105) (xy 405.272791 -391.73106)
			(xy 405.273256 -391.746486) (xy 405.273256 -391.822686) (xy 406.218136 -391.822686) (xy 406.218136 -391.746486)
			(xy 406.218601 -391.73106) (xy 406.225984 -391.701105) (xy 406.240321 -391.673787) (xy 406.26078 -391.650694)
			(xy 406.28617 -391.633168) (xy 406.315017 -391.622228) (xy 406.345644 -391.61851) (xy 406.376271 -391.622228)
			(xy 406.405118 -391.633168) (xy 406.430508 -391.650694) (xy 406.450967 -391.673787) (xy 406.465304 -391.701105)
			(xy 406.472687 -391.73106) (xy 406.473152 -391.746486) (xy 406.473152 -391.822686) (xy 407.418032 -391.822686)
			(xy 407.418032 -391.746486) (xy 407.418498 -391.731029) (xy 407.425896 -391.701015) (xy 407.440262 -391.673642)
			(xy 407.460761 -391.650504) (xy 407.486202 -391.632943) (xy 407.515106 -391.621981) (xy 407.545794 -391.618255)
			(xy 407.576482 -391.621981) (xy 407.605386 -391.632943) (xy 407.630827 -391.650504) (xy 407.651326 -391.673642)
			(xy 407.665692 -391.701015) (xy 407.67309 -391.731029) (xy 407.673556 -391.746486) (xy 407.673556 -391.822686)
			(xy 408.617928 -391.822686) (xy 408.617928 -391.746486) (xy 408.618394 -391.731029) (xy 408.625792 -391.701015)
			(xy 408.640158 -391.673642) (xy 408.660657 -391.650504) (xy 408.686098 -391.632943) (xy 408.715002 -391.621981)
			(xy 408.74569 -391.618255) (xy 408.776378 -391.621981) (xy 408.805282 -391.632943) (xy 408.830723 -391.650504)
			(xy 408.851222 -391.673642) (xy 408.865588 -391.701015) (xy 408.872986 -391.731029) (xy 408.873452 -391.746486)
			(xy 408.873452 -391.822686) (xy 409.818332 -391.822686) (xy 409.818332 -391.746486) (xy 409.818797 -391.73106)
			(xy 409.82618 -391.701105) (xy 409.840517 -391.673787) (xy 409.860976 -391.650694) (xy 409.886366 -391.633168)
			(xy 409.915213 -391.622228) (xy 409.94584 -391.61851) (xy 409.976467 -391.622228) (xy 410.005314 -391.633168)
			(xy 410.030704 -391.650694) (xy 410.051163 -391.673787) (xy 410.0655 -391.701105) (xy 410.072883 -391.73106)
			(xy 410.073348 -391.746486) (xy 410.073348 -391.822686) (xy 411.018228 -391.822686) (xy 411.018228 -391.746486)
			(xy 411.018693 -391.73106) (xy 411.026076 -391.701105) (xy 411.040413 -391.673787) (xy 411.060872 -391.650694)
			(xy 411.086262 -391.633168) (xy 411.115109 -391.622228) (xy 411.145736 -391.61851) (xy 411.176363 -391.622228)
			(xy 411.20521 -391.633168) (xy 411.2306 -391.650694) (xy 411.251059 -391.673787) (xy 411.265396 -391.701105)
			(xy 411.272779 -391.73106) (xy 411.273244 -391.746486) (xy 411.273244 -391.822686) (xy 412.218124 -391.822686)
			(xy 412.218124 -391.746486) (xy 412.218589 -391.73106) (xy 412.225972 -391.701105) (xy 412.240309 -391.673787)
			(xy 412.260768 -391.650694) (xy 412.286158 -391.633168) (xy 412.315005 -391.622228) (xy 412.345632 -391.61851)
			(xy 412.376259 -391.622228) (xy 412.405106 -391.633168) (xy 412.430496 -391.650694) (xy 412.450955 -391.673787)
			(xy 412.465292 -391.701105) (xy 412.472675 -391.73106) (xy 412.47314 -391.746486) (xy 412.47314 -391.822686)
			(xy 413.41802 -391.822686) (xy 413.41802 -391.746486) (xy 413.418486 -391.731029) (xy 413.425884 -391.701015)
			(xy 413.44025 -391.673642) (xy 413.460749 -391.650504) (xy 413.48619 -391.632943) (xy 413.515094 -391.621981)
			(xy 413.545782 -391.618255) (xy 413.57647 -391.621981) (xy 413.605374 -391.632943) (xy 413.630815 -391.650504)
			(xy 413.651314 -391.673642) (xy 413.66568 -391.701015) (xy 413.673078 -391.731029) (xy 413.673544 -391.746486)
			(xy 413.673544 -391.822686) (xy 414.617916 -391.822686) (xy 414.617916 -391.746486) (xy 414.618382 -391.731029)
			(xy 414.62578 -391.701015) (xy 414.640146 -391.673642) (xy 414.660645 -391.650504) (xy 414.686086 -391.632943)
			(xy 414.71499 -391.621981) (xy 414.745678 -391.618255) (xy 414.776366 -391.621981) (xy 414.80527 -391.632943)
			(xy 414.830711 -391.650504) (xy 414.85121 -391.673642) (xy 414.865576 -391.701015) (xy 414.872974 -391.731029)
			(xy 414.87344 -391.746486) (xy 414.87344 -391.822686) (xy 415.81832 -391.822686) (xy 415.81832 -391.746486)
			(xy 415.818785 -391.73106) (xy 415.826168 -391.701105) (xy 415.840505 -391.673787) (xy 415.860964 -391.650694)
			(xy 415.886354 -391.633168) (xy 415.915201 -391.622228) (xy 415.945828 -391.61851) (xy 415.976455 -391.622228)
			(xy 416.005302 -391.633168) (xy 416.030692 -391.650694) (xy 416.051151 -391.673787) (xy 416.065488 -391.701105)
			(xy 416.072871 -391.73106) (xy 416.073336 -391.746486) (xy 416.073336 -391.822686) (xy 417.018216 -391.822686)
			(xy 417.018216 -391.746486) (xy 417.018681 -391.73106) (xy 417.026064 -391.701105) (xy 417.040401 -391.673787)
			(xy 417.06086 -391.650694) (xy 417.08625 -391.633168) (xy 417.115097 -391.622228) (xy 417.145724 -391.61851)
			(xy 417.176351 -391.622228) (xy 417.205198 -391.633168) (xy 417.230588 -391.650694) (xy 417.251047 -391.673787)
			(xy 417.265384 -391.701105) (xy 417.272767 -391.73106) (xy 417.273232 -391.746486) (xy 417.273232 -391.822686)
			(xy 418.218112 -391.822686) (xy 418.218112 -391.746486) (xy 418.218577 -391.73106) (xy 418.22596 -391.701105)
			(xy 418.240297 -391.673787) (xy 418.260756 -391.650694) (xy 418.286146 -391.633168) (xy 418.314993 -391.622228)
			(xy 418.34562 -391.61851) (xy 418.376247 -391.622228) (xy 418.405094 -391.633168) (xy 418.430484 -391.650694)
			(xy 418.450943 -391.673787) (xy 418.46528 -391.701105) (xy 418.472663 -391.73106) (xy 418.473128 -391.746486)
			(xy 418.473128 -391.822686) (xy 419.418008 -391.822686) (xy 419.418008 -391.746486) (xy 419.418474 -391.731029)
			(xy 419.425872 -391.701015) (xy 419.440238 -391.673642) (xy 419.460737 -391.650504) (xy 419.486178 -391.632943)
			(xy 419.515082 -391.621981) (xy 419.54577 -391.618255) (xy 419.576458 -391.621981) (xy 419.605362 -391.632943)
			(xy 419.630803 -391.650504) (xy 419.651302 -391.673642) (xy 419.665668 -391.701015) (xy 419.673066 -391.731029)
			(xy 419.673532 -391.746486) (xy 419.673532 -391.822686) (xy 420.617904 -391.822686) (xy 420.617904 -391.746486)
			(xy 420.61837 -391.731029) (xy 420.625768 -391.701015) (xy 420.640134 -391.673642) (xy 420.660633 -391.650504)
			(xy 420.686074 -391.632943) (xy 420.714978 -391.621981) (xy 420.745666 -391.618255) (xy 420.776354 -391.621981)
			(xy 420.805258 -391.632943) (xy 420.830699 -391.650504) (xy 420.851198 -391.673642) (xy 420.865564 -391.701015)
			(xy 420.872962 -391.731029) (xy 420.873428 -391.746486) (xy 420.873428 -391.822686) (xy 420.872962 -391.838143)
			(xy 420.865564 -391.868157) (xy 420.851198 -391.89553) (xy 420.830699 -391.918668) (xy 420.805258 -391.936229)
			(xy 420.776354 -391.947191) (xy 420.745666 -391.950917) (xy 420.714978 -391.947191) (xy 420.686074 -391.936229)
			(xy 420.660633 -391.918668) (xy 420.640134 -391.89553) (xy 420.625768 -391.868157) (xy 420.61837 -391.838143)
			(xy 420.617904 -391.822686) (xy 419.673532 -391.822686) (xy 419.673066 -391.838143) (xy 419.665668 -391.868157)
			(xy 419.651302 -391.89553) (xy 419.630803 -391.918668) (xy 419.605362 -391.936229) (xy 419.576458 -391.947191)
			(xy 419.54577 -391.950917) (xy 419.515082 -391.947191) (xy 419.486178 -391.936229) (xy 419.460737 -391.918668)
			(xy 419.440238 -391.89553) (xy 419.425872 -391.868157) (xy 419.418474 -391.838143) (xy 419.418008 -391.822686)
			(xy 418.473128 -391.822686) (xy 418.472663 -391.838112) (xy 418.46528 -391.868067) (xy 418.450943 -391.895385)
			(xy 418.430484 -391.918478) (xy 418.405094 -391.936004) (xy 418.376247 -391.946944) (xy 418.34562 -391.950663)
			(xy 418.314993 -391.946944) (xy 418.286146 -391.936004) (xy 418.260756 -391.918478) (xy 418.240297 -391.895385)
			(xy 418.22596 -391.868067) (xy 418.218577 -391.838112) (xy 418.218112 -391.822686) (xy 417.273232 -391.822686)
			(xy 417.272767 -391.838112) (xy 417.265384 -391.868067) (xy 417.251047 -391.895385) (xy 417.230588 -391.918478)
			(xy 417.205198 -391.936004) (xy 417.176351 -391.946944) (xy 417.145724 -391.950663) (xy 417.115097 -391.946944)
			(xy 417.08625 -391.936004) (xy 417.06086 -391.918478) (xy 417.040401 -391.895385) (xy 417.026064 -391.868067)
			(xy 417.018681 -391.838112) (xy 417.018216 -391.822686) (xy 416.073336 -391.822686) (xy 416.072871 -391.838112)
			(xy 416.065488 -391.868067) (xy 416.051151 -391.895385) (xy 416.030692 -391.918478) (xy 416.005302 -391.936004)
			(xy 415.976455 -391.946944) (xy 415.945828 -391.950663) (xy 415.915201 -391.946944) (xy 415.886354 -391.936004)
			(xy 415.860964 -391.918478) (xy 415.840505 -391.895385) (xy 415.826168 -391.868067) (xy 415.818785 -391.838112)
			(xy 415.81832 -391.822686) (xy 414.87344 -391.822686) (xy 414.872974 -391.838143) (xy 414.865576 -391.868157)
			(xy 414.85121 -391.89553) (xy 414.830711 -391.918668) (xy 414.80527 -391.936229) (xy 414.776366 -391.947191)
			(xy 414.745678 -391.950917) (xy 414.71499 -391.947191) (xy 414.686086 -391.936229) (xy 414.660645 -391.918668)
			(xy 414.640146 -391.89553) (xy 414.62578 -391.868157) (xy 414.618382 -391.838143) (xy 414.617916 -391.822686)
			(xy 413.673544 -391.822686) (xy 413.673078 -391.838143) (xy 413.66568 -391.868157) (xy 413.651314 -391.89553)
			(xy 413.630815 -391.918668) (xy 413.605374 -391.936229) (xy 413.57647 -391.947191) (xy 413.545782 -391.950917)
			(xy 413.515094 -391.947191) (xy 413.48619 -391.936229) (xy 413.460749 -391.918668) (xy 413.44025 -391.89553)
			(xy 413.425884 -391.868157) (xy 413.418486 -391.838143) (xy 413.41802 -391.822686) (xy 412.47314 -391.822686)
			(xy 412.472675 -391.838112) (xy 412.465292 -391.868067) (xy 412.450955 -391.895385) (xy 412.430496 -391.918478)
			(xy 412.405106 -391.936004) (xy 412.376259 -391.946944) (xy 412.345632 -391.950663) (xy 412.315005 -391.946944)
			(xy 412.286158 -391.936004) (xy 412.260768 -391.918478) (xy 412.240309 -391.895385) (xy 412.225972 -391.868067)
			(xy 412.218589 -391.838112) (xy 412.218124 -391.822686) (xy 411.273244 -391.822686) (xy 411.272779 -391.838112)
			(xy 411.265396 -391.868067) (xy 411.251059 -391.895385) (xy 411.2306 -391.918478) (xy 411.20521 -391.936004)
			(xy 411.176363 -391.946944) (xy 411.145736 -391.950663) (xy 411.115109 -391.946944) (xy 411.086262 -391.936004)
			(xy 411.060872 -391.918478) (xy 411.040413 -391.895385) (xy 411.026076 -391.868067) (xy 411.018693 -391.838112)
			(xy 411.018228 -391.822686) (xy 410.073348 -391.822686) (xy 410.072883 -391.838112) (xy 410.0655 -391.868067)
			(xy 410.051163 -391.895385) (xy 410.030704 -391.918478) (xy 410.005314 -391.936004) (xy 409.976467 -391.946944)
			(xy 409.94584 -391.950663) (xy 409.915213 -391.946944) (xy 409.886366 -391.936004) (xy 409.860976 -391.918478)
			(xy 409.840517 -391.895385) (xy 409.82618 -391.868067) (xy 409.818797 -391.838112) (xy 409.818332 -391.822686)
			(xy 408.873452 -391.822686) (xy 408.872986 -391.838143) (xy 408.865588 -391.868157) (xy 408.851222 -391.89553)
			(xy 408.830723 -391.918668) (xy 408.805282 -391.936229) (xy 408.776378 -391.947191) (xy 408.74569 -391.950917)
			(xy 408.715002 -391.947191) (xy 408.686098 -391.936229) (xy 408.660657 -391.918668) (xy 408.640158 -391.89553)
			(xy 408.625792 -391.868157) (xy 408.618394 -391.838143) (xy 408.617928 -391.822686) (xy 407.673556 -391.822686)
			(xy 407.67309 -391.838143) (xy 407.665692 -391.868157) (xy 407.651326 -391.89553) (xy 407.630827 -391.918668)
			(xy 407.605386 -391.936229) (xy 407.576482 -391.947191) (xy 407.545794 -391.950917) (xy 407.515106 -391.947191)
			(xy 407.486202 -391.936229) (xy 407.460761 -391.918668) (xy 407.440262 -391.89553) (xy 407.425896 -391.868157)
			(xy 407.418498 -391.838143) (xy 407.418032 -391.822686) (xy 406.473152 -391.822686) (xy 406.472687 -391.838112)
			(xy 406.465304 -391.868067) (xy 406.450967 -391.895385) (xy 406.430508 -391.918478) (xy 406.405118 -391.936004)
			(xy 406.376271 -391.946944) (xy 406.345644 -391.950663) (xy 406.315017 -391.946944) (xy 406.28617 -391.936004)
			(xy 406.26078 -391.918478) (xy 406.240321 -391.895385) (xy 406.225984 -391.868067) (xy 406.218601 -391.838112)
			(xy 406.218136 -391.822686) (xy 405.273256 -391.822686) (xy 405.272791 -391.838112) (xy 405.265408 -391.868067)
			(xy 405.251071 -391.895385) (xy 405.230612 -391.918478) (xy 405.205222 -391.936004) (xy 405.176375 -391.946944)
			(xy 405.145748 -391.950663) (xy 405.115121 -391.946944) (xy 405.086274 -391.936004) (xy 405.060884 -391.918478)
			(xy 405.040425 -391.895385) (xy 405.026088 -391.868067) (xy 405.018705 -391.838112) (xy 405.01824 -391.822686)
			(xy 404.07336 -391.822686) (xy 404.072894 -391.838143) (xy 404.065496 -391.868157) (xy 404.05113 -391.89553)
			(xy 404.030631 -391.918668) (xy 404.00519 -391.936229) (xy 403.976286 -391.947191) (xy 403.945598 -391.950917)
			(xy 403.91491 -391.947191) (xy 403.886006 -391.936229) (xy 403.860565 -391.918668) (xy 403.840066 -391.89553)
			(xy 403.8257 -391.868157) (xy 403.818302 -391.838143) (xy 403.817836 -391.822686) (xy 402.873464 -391.822686)
			(xy 402.872998 -391.838143) (xy 402.8656 -391.868157) (xy 402.851234 -391.89553) (xy 402.830735 -391.918668)
			(xy 402.805294 -391.936229) (xy 402.77639 -391.947191) (xy 402.745702 -391.950917) (xy 402.715014 -391.947191)
			(xy 402.68611 -391.936229) (xy 402.660669 -391.918668) (xy 402.64017 -391.89553) (xy 402.625804 -391.868157)
			(xy 402.618406 -391.838143) (xy 402.61794 -391.822686) (xy 388.34568 -391.822686) (xy 388.345214 -391.838143)
			(xy 388.337816 -391.868157) (xy 388.32345 -391.89553) (xy 388.302951 -391.918668) (xy 388.27751 -391.936229)
			(xy 388.248606 -391.947191) (xy 388.217918 -391.950917) (xy 388.18723 -391.947191) (xy 388.158326 -391.936229)
			(xy 388.132885 -391.918668) (xy 388.112386 -391.89553) (xy 388.09802 -391.868157) (xy 388.090622 -391.838143)
			(xy 388.090156 -391.822686) (xy 387.145784 -391.822686) (xy 387.145318 -391.838143) (xy 387.13792 -391.868157)
			(xy 387.123554 -391.89553) (xy 387.103055 -391.918668) (xy 387.077614 -391.936229) (xy 387.04871 -391.947191)
			(xy 387.018022 -391.950917) (xy 386.987334 -391.947191) (xy 386.95843 -391.936229) (xy 386.932989 -391.918668)
			(xy 386.91249 -391.89553) (xy 386.898124 -391.868157) (xy 386.890726 -391.838143) (xy 386.89026 -391.822686)
			(xy 385.94538 -391.822686) (xy 385.944915 -391.838112) (xy 385.937532 -391.868067) (xy 385.923195 -391.895385)
			(xy 385.902736 -391.918478) (xy 385.877346 -391.936004) (xy 385.848499 -391.946944) (xy 385.817872 -391.950663)
			(xy 385.787245 -391.946944) (xy 385.758398 -391.936004) (xy 385.733008 -391.918478) (xy 385.712549 -391.895385)
			(xy 385.698212 -391.868067) (xy 385.690829 -391.838112) (xy 385.690364 -391.822686) (xy 384.745484 -391.822686)
			(xy 384.745019 -391.838112) (xy 384.737636 -391.868067) (xy 384.723299 -391.895385) (xy 384.70284 -391.918478)
			(xy 384.67745 -391.936004) (xy 384.648603 -391.946944) (xy 384.617976 -391.950663) (xy 384.587349 -391.946944)
			(xy 384.558502 -391.936004) (xy 384.533112 -391.918478) (xy 384.512653 -391.895385) (xy 384.498316 -391.868067)
			(xy 384.490933 -391.838112) (xy 384.490468 -391.822686) (xy 383.545588 -391.822686) (xy 383.545123 -391.838112)
			(xy 383.53774 -391.868067) (xy 383.523403 -391.895385) (xy 383.502944 -391.918478) (xy 383.477554 -391.936004)
			(xy 383.448707 -391.946944) (xy 383.41808 -391.950663) (xy 383.387453 -391.946944) (xy 383.358606 -391.936004)
			(xy 383.333216 -391.918478) (xy 383.312757 -391.895385) (xy 383.29842 -391.868067) (xy 383.291037 -391.838112)
			(xy 383.290572 -391.822686) (xy 382.345692 -391.822686) (xy 382.345226 -391.838143) (xy 382.337828 -391.868157)
			(xy 382.323462 -391.89553) (xy 382.302963 -391.918668) (xy 382.277522 -391.936229) (xy 382.248618 -391.947191)
			(xy 382.21793 -391.950917) (xy 382.187242 -391.947191) (xy 382.158338 -391.936229) (xy 382.132897 -391.918668)
			(xy 382.112398 -391.89553) (xy 382.098032 -391.868157) (xy 382.090634 -391.838143) (xy 382.090168 -391.822686)
			(xy 381.145796 -391.822686) (xy 381.14533 -391.838143) (xy 381.137932 -391.868157) (xy 381.123566 -391.89553)
			(xy 381.103067 -391.918668) (xy 381.077626 -391.936229) (xy 381.048722 -391.947191) (xy 381.018034 -391.950917)
			(xy 380.987346 -391.947191) (xy 380.958442 -391.936229) (xy 380.933001 -391.918668) (xy 380.912502 -391.89553)
			(xy 380.898136 -391.868157) (xy 380.890738 -391.838143) (xy 380.890272 -391.822686) (xy 379.945392 -391.822686)
			(xy 379.944927 -391.838112) (xy 379.937544 -391.868067) (xy 379.923207 -391.895385) (xy 379.902748 -391.918478)
			(xy 379.877358 -391.936004) (xy 379.848511 -391.946944) (xy 379.817884 -391.950663) (xy 379.787257 -391.946944)
			(xy 379.75841 -391.936004) (xy 379.73302 -391.918478) (xy 379.712561 -391.895385) (xy 379.698224 -391.868067)
			(xy 379.690841 -391.838112) (xy 379.690376 -391.822686) (xy 378.745496 -391.822686) (xy 378.745031 -391.838112)
			(xy 378.737648 -391.868067) (xy 378.723311 -391.895385) (xy 378.702852 -391.918478) (xy 378.677462 -391.936004)
			(xy 378.648615 -391.946944) (xy 378.617988 -391.950663) (xy 378.587361 -391.946944) (xy 378.558514 -391.936004)
			(xy 378.533124 -391.918478) (xy 378.512665 -391.895385) (xy 378.498328 -391.868067) (xy 378.490945 -391.838112)
			(xy 378.49048 -391.822686) (xy 377.5456 -391.822686) (xy 377.545135 -391.838112) (xy 377.537752 -391.868067)
			(xy 377.523415 -391.895385) (xy 377.502956 -391.918478) (xy 377.477566 -391.936004) (xy 377.448719 -391.946944)
			(xy 377.418092 -391.950663) (xy 377.387465 -391.946944) (xy 377.358618 -391.936004) (xy 377.333228 -391.918478)
			(xy 377.312769 -391.895385) (xy 377.298432 -391.868067) (xy 377.291049 -391.838112) (xy 377.290584 -391.822686)
			(xy 376.345704 -391.822686) (xy 376.345238 -391.838143) (xy 376.33784 -391.868157) (xy 376.323474 -391.89553)
			(xy 376.302975 -391.918668) (xy 376.277534 -391.936229) (xy 376.24863 -391.947191) (xy 376.217942 -391.950917)
			(xy 376.187254 -391.947191) (xy 376.15835 -391.936229) (xy 376.132909 -391.918668) (xy 376.11241 -391.89553)
			(xy 376.098044 -391.868157) (xy 376.090646 -391.838143) (xy 376.09018 -391.822686) (xy 375.145808 -391.822686)
			(xy 375.145342 -391.838143) (xy 375.137944 -391.868157) (xy 375.123578 -391.89553) (xy 375.103079 -391.918668)
			(xy 375.077638 -391.936229) (xy 375.048734 -391.947191) (xy 375.018046 -391.950917) (xy 374.987358 -391.947191)
			(xy 374.958454 -391.936229) (xy 374.933013 -391.918668) (xy 374.912514 -391.89553) (xy 374.898148 -391.868157)
			(xy 374.89075 -391.838143) (xy 374.890284 -391.822686) (xy 373.945404 -391.822686) (xy 373.944939 -391.838112)
			(xy 373.937556 -391.868067) (xy 373.923219 -391.895385) (xy 373.90276 -391.918478) (xy 373.87737 -391.936004)
			(xy 373.848523 -391.946944) (xy 373.817896 -391.950663) (xy 373.787269 -391.946944) (xy 373.758422 -391.936004)
			(xy 373.733032 -391.918478) (xy 373.712573 -391.895385) (xy 373.698236 -391.868067) (xy 373.690853 -391.838112)
			(xy 373.690388 -391.822686) (xy 372.745508 -391.822686) (xy 372.745043 -391.838112) (xy 372.73766 -391.868067)
			(xy 372.723323 -391.895385) (xy 372.702864 -391.918478) (xy 372.677474 -391.936004) (xy 372.648627 -391.946944)
			(xy 372.618 -391.950663) (xy 372.587373 -391.946944) (xy 372.558526 -391.936004) (xy 372.533136 -391.918478)
			(xy 372.512677 -391.895385) (xy 372.49834 -391.868067) (xy 372.490957 -391.838112) (xy 372.490492 -391.822686)
			(xy 371.545612 -391.822686) (xy 371.545146 -391.838143) (xy 371.537748 -391.868157) (xy 371.523382 -391.89553)
			(xy 371.502883 -391.918668) (xy 371.477442 -391.936229) (xy 371.448538 -391.947191) (xy 371.41785 -391.950917)
			(xy 371.387162 -391.947191) (xy 371.358258 -391.936229) (xy 371.332817 -391.918668) (xy 371.312318 -391.89553)
			(xy 371.297952 -391.868157) (xy 371.290554 -391.838143) (xy 371.290088 -391.822686) (xy 370.345716 -391.822686)
			(xy 370.34525 -391.838143) (xy 370.337852 -391.868157) (xy 370.323486 -391.89553) (xy 370.302987 -391.918668)
			(xy 370.277546 -391.936229) (xy 370.248642 -391.947191) (xy 370.217954 -391.950917) (xy 370.187266 -391.947191)
			(xy 370.158362 -391.936229) (xy 370.132921 -391.918668) (xy 370.112422 -391.89553) (xy 370.098056 -391.868157)
			(xy 370.090658 -391.838143) (xy 370.090192 -391.822686) (xy 353.773232 -391.822686) (xy 353.772766 -391.838143)
			(xy 353.765368 -391.868157) (xy 353.751002 -391.89553) (xy 353.730503 -391.918668) (xy 353.705062 -391.936229)
			(xy 353.676158 -391.947191) (xy 353.64547 -391.950917) (xy 353.614782 -391.947191) (xy 353.585878 -391.936229)
			(xy 353.560437 -391.918668) (xy 353.539938 -391.89553) (xy 353.525572 -391.868157) (xy 353.518174 -391.838143)
			(xy 353.517708 -391.822686) (xy 352.573336 -391.822686) (xy 352.57287 -391.838143) (xy 352.565472 -391.868157)
			(xy 352.551106 -391.89553) (xy 352.530607 -391.918668) (xy 352.505166 -391.936229) (xy 352.476262 -391.947191)
			(xy 352.445574 -391.950917) (xy 352.414886 -391.947191) (xy 352.385982 -391.936229) (xy 352.360541 -391.918668)
			(xy 352.340042 -391.89553) (xy 352.325676 -391.868157) (xy 352.318278 -391.838143) (xy 352.317812 -391.822686)
			(xy 351.372932 -391.822686) (xy 351.372467 -391.838112) (xy 351.365084 -391.868067) (xy 351.350747 -391.895385)
			(xy 351.330288 -391.918478) (xy 351.304898 -391.936004) (xy 351.276051 -391.946944) (xy 351.245424 -391.950663)
			(xy 351.214797 -391.946944) (xy 351.18595 -391.936004) (xy 351.16056 -391.918478) (xy 351.140101 -391.895385)
			(xy 351.125764 -391.868067) (xy 351.118381 -391.838112) (xy 351.117916 -391.822686) (xy 350.173036 -391.822686)
			(xy 350.172571 -391.838112) (xy 350.165188 -391.868067) (xy 350.150851 -391.895385) (xy 350.130392 -391.918478)
			(xy 350.105002 -391.936004) (xy 350.076155 -391.946944) (xy 350.045528 -391.950663) (xy 350.014901 -391.946944)
			(xy 349.986054 -391.936004) (xy 349.960664 -391.918478) (xy 349.940205 -391.895385) (xy 349.925868 -391.868067)
			(xy 349.918485 -391.838112) (xy 349.91802 -391.822686) (xy 348.97314 -391.822686) (xy 348.972675 -391.838112)
			(xy 348.965292 -391.868067) (xy 348.950955 -391.895385) (xy 348.930496 -391.918478) (xy 348.905106 -391.936004)
			(xy 348.876259 -391.946944) (xy 348.845632 -391.950663) (xy 348.815005 -391.946944) (xy 348.786158 -391.936004)
			(xy 348.760768 -391.918478) (xy 348.740309 -391.895385) (xy 348.725972 -391.868067) (xy 348.718589 -391.838112)
			(xy 348.718124 -391.822686) (xy 347.773244 -391.822686) (xy 347.772778 -391.838143) (xy 347.76538 -391.868157)
			(xy 347.751014 -391.89553) (xy 347.730515 -391.918668) (xy 347.705074 -391.936229) (xy 347.67617 -391.947191)
			(xy 347.645482 -391.950917) (xy 347.614794 -391.947191) (xy 347.58589 -391.936229) (xy 347.560449 -391.918668)
			(xy 347.53995 -391.89553) (xy 347.525584 -391.868157) (xy 347.518186 -391.838143) (xy 347.51772 -391.822686)
			(xy 346.573348 -391.822686) (xy 346.572882 -391.838143) (xy 346.565484 -391.868157) (xy 346.551118 -391.89553)
			(xy 346.530619 -391.918668) (xy 346.505178 -391.936229) (xy 346.476274 -391.947191) (xy 346.445586 -391.950917)
			(xy 346.414898 -391.947191) (xy 346.385994 -391.936229) (xy 346.360553 -391.918668) (xy 346.340054 -391.89553)
			(xy 346.325688 -391.868157) (xy 346.31829 -391.838143) (xy 346.317824 -391.822686) (xy 345.372944 -391.822686)
			(xy 345.372479 -391.838112) (xy 345.365096 -391.868067) (xy 345.350759 -391.895385) (xy 345.3303 -391.918478)
			(xy 345.30491 -391.936004) (xy 345.276063 -391.946944) (xy 345.245436 -391.950663) (xy 345.214809 -391.946944)
			(xy 345.185962 -391.936004) (xy 345.160572 -391.918478) (xy 345.140113 -391.895385) (xy 345.125776 -391.868067)
			(xy 345.118393 -391.838112) (xy 345.117928 -391.822686) (xy 344.173048 -391.822686) (xy 344.172583 -391.838112)
			(xy 344.1652 -391.868067) (xy 344.150863 -391.895385) (xy 344.130404 -391.918478) (xy 344.105014 -391.936004)
			(xy 344.076167 -391.946944) (xy 344.04554 -391.950663) (xy 344.014913 -391.946944) (xy 343.986066 -391.936004)
			(xy 343.960676 -391.918478) (xy 343.940217 -391.895385) (xy 343.92588 -391.868067) (xy 343.918497 -391.838112)
			(xy 343.918032 -391.822686) (xy 342.973152 -391.822686) (xy 342.972687 -391.838112) (xy 342.965304 -391.868067)
			(xy 342.950967 -391.895385) (xy 342.930508 -391.918478) (xy 342.905118 -391.936004) (xy 342.876271 -391.946944)
			(xy 342.845644 -391.950663) (xy 342.815017 -391.946944) (xy 342.78617 -391.936004) (xy 342.76078 -391.918478)
			(xy 342.740321 -391.895385) (xy 342.725984 -391.868067) (xy 342.718601 -391.838112) (xy 342.718136 -391.822686)
			(xy 341.773256 -391.822686) (xy 341.77279 -391.838143) (xy 341.765392 -391.868157) (xy 341.751026 -391.89553)
			(xy 341.730527 -391.918668) (xy 341.705086 -391.936229) (xy 341.676182 -391.947191) (xy 341.645494 -391.950917)
			(xy 341.614806 -391.947191) (xy 341.585902 -391.936229) (xy 341.560461 -391.918668) (xy 341.539962 -391.89553)
			(xy 341.525596 -391.868157) (xy 341.518198 -391.838143) (xy 341.517732 -391.822686) (xy 340.57336 -391.822686)
			(xy 340.572894 -391.838143) (xy 340.565496 -391.868157) (xy 340.55113 -391.89553) (xy 340.530631 -391.918668)
			(xy 340.50519 -391.936229) (xy 340.476286 -391.947191) (xy 340.445598 -391.950917) (xy 340.41491 -391.947191)
			(xy 340.386006 -391.936229) (xy 340.360565 -391.918668) (xy 340.340066 -391.89553) (xy 340.3257 -391.868157)
			(xy 340.318302 -391.838143) (xy 340.317836 -391.822686) (xy 339.372956 -391.822686) (xy 339.372491 -391.838112)
			(xy 339.365108 -391.868067) (xy 339.350771 -391.895385) (xy 339.330312 -391.918478) (xy 339.304922 -391.936004)
			(xy 339.276075 -391.946944) (xy 339.245448 -391.950663) (xy 339.214821 -391.946944) (xy 339.185974 -391.936004)
			(xy 339.160584 -391.918478) (xy 339.140125 -391.895385) (xy 339.125788 -391.868067) (xy 339.118405 -391.838112)
			(xy 339.11794 -391.822686) (xy 338.17306 -391.822686) (xy 338.172595 -391.838112) (xy 338.165212 -391.868067)
			(xy 338.150875 -391.895385) (xy 338.130416 -391.918478) (xy 338.105026 -391.936004) (xy 338.076179 -391.946944)
			(xy 338.045552 -391.950663) (xy 338.014925 -391.946944) (xy 337.986078 -391.936004) (xy 337.960688 -391.918478)
			(xy 337.940229 -391.895385) (xy 337.925892 -391.868067) (xy 337.918509 -391.838112) (xy 337.918044 -391.822686)
			(xy 336.973164 -391.822686) (xy 336.972698 -391.838143) (xy 336.9653 -391.868157) (xy 336.950934 -391.89553)
			(xy 336.930435 -391.918668) (xy 336.904994 -391.936229) (xy 336.87609 -391.947191) (xy 336.845402 -391.950917)
			(xy 336.814714 -391.947191) (xy 336.78581 -391.936229) (xy 336.760369 -391.918668) (xy 336.73987 -391.89553)
			(xy 336.725504 -391.868157) (xy 336.718106 -391.838143) (xy 336.71764 -391.822686) (xy 335.773268 -391.822686)
			(xy 335.772802 -391.838143) (xy 335.765404 -391.868157) (xy 335.751038 -391.89553) (xy 335.730539 -391.918668)
			(xy 335.705098 -391.936229) (xy 335.676194 -391.947191) (xy 335.645506 -391.950917) (xy 335.614818 -391.947191)
			(xy 335.585914 -391.936229) (xy 335.560473 -391.918668) (xy 335.539974 -391.89553) (xy 335.525608 -391.868157)
			(xy 335.51821 -391.838143) (xy 335.517744 -391.822686) (xy 321.245484 -391.822686) (xy 321.245018 -391.838143)
			(xy 321.23762 -391.868157) (xy 321.223254 -391.89553) (xy 321.202755 -391.918668) (xy 321.177314 -391.936229)
			(xy 321.14841 -391.947191) (xy 321.117722 -391.950917) (xy 321.087034 -391.947191) (xy 321.05813 -391.936229)
			(xy 321.032689 -391.918668) (xy 321.01219 -391.89553) (xy 320.997824 -391.868157) (xy 320.990426 -391.838143)
			(xy 320.98996 -391.822686) (xy 320.045588 -391.822686) (xy 320.045122 -391.838143) (xy 320.037724 -391.868157)
			(xy 320.023358 -391.89553) (xy 320.002859 -391.918668) (xy 319.977418 -391.936229) (xy 319.948514 -391.947191)
			(xy 319.917826 -391.950917) (xy 319.887138 -391.947191) (xy 319.858234 -391.936229) (xy 319.832793 -391.918668)
			(xy 319.812294 -391.89553) (xy 319.797928 -391.868157) (xy 319.79053 -391.838143) (xy 319.790064 -391.822686)
			(xy 318.845184 -391.822686) (xy 318.844719 -391.838112) (xy 318.837336 -391.868067) (xy 318.822999 -391.895385)
			(xy 318.80254 -391.918478) (xy 318.77715 -391.936004) (xy 318.748303 -391.946944) (xy 318.717676 -391.950663)
			(xy 318.687049 -391.946944) (xy 318.658202 -391.936004) (xy 318.632812 -391.918478) (xy 318.612353 -391.895385)
			(xy 318.598016 -391.868067) (xy 318.590633 -391.838112) (xy 318.590168 -391.822686) (xy 317.645288 -391.822686)
			(xy 317.644823 -391.838112) (xy 317.63744 -391.868067) (xy 317.623103 -391.895385) (xy 317.602644 -391.918478)
			(xy 317.577254 -391.936004) (xy 317.548407 -391.946944) (xy 317.51778 -391.950663) (xy 317.487153 -391.946944)
			(xy 317.458306 -391.936004) (xy 317.432916 -391.918478) (xy 317.412457 -391.895385) (xy 317.39812 -391.868067)
			(xy 317.390737 -391.838112) (xy 317.390272 -391.822686) (xy 316.445392 -391.822686) (xy 316.444927 -391.838112)
			(xy 316.437544 -391.868067) (xy 316.423207 -391.895385) (xy 316.402748 -391.918478) (xy 316.377358 -391.936004)
			(xy 316.348511 -391.946944) (xy 316.317884 -391.950663) (xy 316.287257 -391.946944) (xy 316.25841 -391.936004)
			(xy 316.23302 -391.918478) (xy 316.212561 -391.895385) (xy 316.198224 -391.868067) (xy 316.190841 -391.838112)
			(xy 316.190376 -391.822686) (xy 315.245496 -391.822686) (xy 315.24503 -391.838143) (xy 315.237632 -391.868157)
			(xy 315.223266 -391.89553) (xy 315.202767 -391.918668) (xy 315.177326 -391.936229) (xy 315.148422 -391.947191)
			(xy 315.117734 -391.950917) (xy 315.087046 -391.947191) (xy 315.058142 -391.936229) (xy 315.032701 -391.918668)
			(xy 315.012202 -391.89553) (xy 314.997836 -391.868157) (xy 314.990438 -391.838143) (xy 314.989972 -391.822686)
			(xy 314.0456 -391.822686) (xy 314.045134 -391.838143) (xy 314.037736 -391.868157) (xy 314.02337 -391.89553)
			(xy 314.002871 -391.918668) (xy 313.97743 -391.936229) (xy 313.948526 -391.947191) (xy 313.917838 -391.950917)
			(xy 313.88715 -391.947191) (xy 313.858246 -391.936229) (xy 313.832805 -391.918668) (xy 313.812306 -391.89553)
			(xy 313.79794 -391.868157) (xy 313.790542 -391.838143) (xy 313.790076 -391.822686) (xy 312.845196 -391.822686)
			(xy 312.844731 -391.838112) (xy 312.837348 -391.868067) (xy 312.823011 -391.895385) (xy 312.802552 -391.918478)
			(xy 312.777162 -391.936004) (xy 312.748315 -391.946944) (xy 312.717688 -391.950663) (xy 312.687061 -391.946944)
			(xy 312.658214 -391.936004) (xy 312.632824 -391.918478) (xy 312.612365 -391.895385) (xy 312.598028 -391.868067)
			(xy 312.590645 -391.838112) (xy 312.59018 -391.822686) (xy 311.6453 -391.822686) (xy 311.644835 -391.838112)
			(xy 311.637452 -391.868067) (xy 311.623115 -391.895385) (xy 311.602656 -391.918478) (xy 311.577266 -391.936004)
			(xy 311.548419 -391.946944) (xy 311.517792 -391.950663) (xy 311.487165 -391.946944) (xy 311.458318 -391.936004)
			(xy 311.432928 -391.918478) (xy 311.412469 -391.895385) (xy 311.398132 -391.868067) (xy 311.390749 -391.838112)
			(xy 311.390284 -391.822686) (xy 310.445404 -391.822686) (xy 310.444939 -391.838112) (xy 310.437556 -391.868067)
			(xy 310.423219 -391.895385) (xy 310.40276 -391.918478) (xy 310.37737 -391.936004) (xy 310.348523 -391.946944)
			(xy 310.317896 -391.950663) (xy 310.287269 -391.946944) (xy 310.258422 -391.936004) (xy 310.233032 -391.918478)
			(xy 310.212573 -391.895385) (xy 310.198236 -391.868067) (xy 310.190853 -391.838112) (xy 310.190388 -391.822686)
			(xy 309.245508 -391.822686) (xy 309.245042 -391.838143) (xy 309.237644 -391.868157) (xy 309.223278 -391.89553)
			(xy 309.202779 -391.918668) (xy 309.177338 -391.936229) (xy 309.148434 -391.947191) (xy 309.117746 -391.950917)
			(xy 309.087058 -391.947191) (xy 309.058154 -391.936229) (xy 309.032713 -391.918668) (xy 309.012214 -391.89553)
			(xy 308.997848 -391.868157) (xy 308.99045 -391.838143) (xy 308.989984 -391.822686) (xy 308.045612 -391.822686)
			(xy 308.045146 -391.838143) (xy 308.037748 -391.868157) (xy 308.023382 -391.89553) (xy 308.002883 -391.918668)
			(xy 307.977442 -391.936229) (xy 307.948538 -391.947191) (xy 307.91785 -391.950917) (xy 307.887162 -391.947191)
			(xy 307.858258 -391.936229) (xy 307.832817 -391.918668) (xy 307.812318 -391.89553) (xy 307.797952 -391.868157)
			(xy 307.790554 -391.838143) (xy 307.790088 -391.822686) (xy 306.845208 -391.822686) (xy 306.844743 -391.838112)
			(xy 306.83736 -391.868067) (xy 306.823023 -391.895385) (xy 306.802564 -391.918478) (xy 306.777174 -391.936004)
			(xy 306.748327 -391.946944) (xy 306.7177 -391.950663) (xy 306.687073 -391.946944) (xy 306.658226 -391.936004)
			(xy 306.632836 -391.918478) (xy 306.612377 -391.895385) (xy 306.59804 -391.868067) (xy 306.590657 -391.838112)
			(xy 306.590192 -391.822686) (xy 305.645312 -391.822686) (xy 305.644847 -391.838112) (xy 305.637464 -391.868067)
			(xy 305.623127 -391.895385) (xy 305.602668 -391.918478) (xy 305.577278 -391.936004) (xy 305.548431 -391.946944)
			(xy 305.517804 -391.950663) (xy 305.487177 -391.946944) (xy 305.45833 -391.936004) (xy 305.43294 -391.918478)
			(xy 305.412481 -391.895385) (xy 305.398144 -391.868067) (xy 305.390761 -391.838112) (xy 305.390296 -391.822686)
			(xy 304.445416 -391.822686) (xy 304.44495 -391.838143) (xy 304.437552 -391.868157) (xy 304.423186 -391.89553)
			(xy 304.402687 -391.918668) (xy 304.377246 -391.936229) (xy 304.348342 -391.947191) (xy 304.317654 -391.950917)
			(xy 304.286966 -391.947191) (xy 304.258062 -391.936229) (xy 304.232621 -391.918668) (xy 304.212122 -391.89553)
			(xy 304.197756 -391.868157) (xy 304.190358 -391.838143) (xy 304.189892 -391.822686) (xy 303.24552 -391.822686)
			(xy 303.245054 -391.838143) (xy 303.237656 -391.868157) (xy 303.22329 -391.89553) (xy 303.202791 -391.918668)
			(xy 303.17735 -391.936229) (xy 303.148446 -391.947191) (xy 303.117758 -391.950917) (xy 303.08707 -391.947191)
			(xy 303.058166 -391.936229) (xy 303.032725 -391.918668) (xy 303.012226 -391.89553) (xy 302.99786 -391.868157)
			(xy 302.990462 -391.838143) (xy 302.989996 -391.822686) (xy 281.2288 -391.822686) (xy 281.2288 -392.180572)
			(xy 281.228283 -392.20552) (xy 281.220475 -392.254803) (xy 281.205064 -392.30226) (xy 281.204041 -392.30427)
			(xy 303.264049 -392.30427) (xy 303.268191 -392.268828) (xy 303.280395 -392.235297) (xy 303.300004 -392.205484)
			(xy 303.325959 -392.180997) (xy 303.356861 -392.163155) (xy 303.391045 -392.152921) (xy 303.426668 -392.150847)
			(xy 303.461809 -392.157043) (xy 303.494574 -392.171176) (xy 303.523196 -392.192485) (xy 303.546133 -392.21982)
			(xy 303.562147 -392.251707) (xy 303.570376 -392.286428) (xy 303.570894 -392.30427) (xy 304.463945 -392.30427)
			(xy 304.468087 -392.268828) (xy 304.480291 -392.235297) (xy 304.4999 -392.205484) (xy 304.525855 -392.180997)
			(xy 304.556757 -392.163155) (xy 304.590941 -392.152921) (xy 304.626564 -392.150847) (xy 304.661705 -392.157043)
			(xy 304.69447 -392.171176) (xy 304.723092 -392.192485) (xy 304.746029 -392.21982) (xy 304.762043 -392.251707)
			(xy 304.770272 -392.286428) (xy 304.77079 -392.30427) (xy 305.664095 -392.30427) (xy 305.668237 -392.268828)
			(xy 305.680441 -392.235297) (xy 305.70005 -392.205484) (xy 305.726005 -392.180997) (xy 305.756907 -392.163155)
			(xy 305.791091 -392.152921) (xy 305.826714 -392.150847) (xy 305.861855 -392.157043) (xy 305.89462 -392.171176)
			(xy 305.923242 -392.192485) (xy 305.946179 -392.21982) (xy 305.962193 -392.251707) (xy 305.970422 -392.286428)
			(xy 305.97094 -392.30427) (xy 306.863991 -392.30427) (xy 306.868133 -392.268828) (xy 306.880337 -392.235297)
			(xy 306.899946 -392.205484) (xy 306.925901 -392.180997) (xy 306.956803 -392.163155) (xy 306.990987 -392.152921)
			(xy 307.02661 -392.150847) (xy 307.061751 -392.157043) (xy 307.094516 -392.171176) (xy 307.123138 -392.192485)
			(xy 307.146075 -392.21982) (xy 307.162089 -392.251707) (xy 307.170318 -392.286428) (xy 307.170836 -392.30427)
			(xy 308.064141 -392.30427) (xy 308.068283 -392.268828) (xy 308.080487 -392.235297) (xy 308.100096 -392.205484)
			(xy 308.126051 -392.180997) (xy 308.156953 -392.163155) (xy 308.191137 -392.152921) (xy 308.22676 -392.150847)
			(xy 308.261901 -392.157043) (xy 308.294666 -392.171176) (xy 308.323288 -392.192485) (xy 308.346225 -392.21982)
			(xy 308.362239 -392.251707) (xy 308.370468 -392.286428) (xy 308.370986 -392.30427) (xy 309.264037 -392.30427)
			(xy 309.268179 -392.268828) (xy 309.280383 -392.235297) (xy 309.299992 -392.205484) (xy 309.325947 -392.180997)
			(xy 309.356849 -392.163155) (xy 309.391033 -392.152921) (xy 309.426656 -392.150847) (xy 309.461797 -392.157043)
			(xy 309.494562 -392.171176) (xy 309.523184 -392.192485) (xy 309.546121 -392.21982) (xy 309.562135 -392.251707)
			(xy 309.570364 -392.286428) (xy 309.570882 -392.30427) (xy 310.464187 -392.30427) (xy 310.468329 -392.268828)
			(xy 310.480533 -392.235297) (xy 310.500142 -392.205484) (xy 310.526097 -392.180997) (xy 310.556999 -392.163155)
			(xy 310.591183 -392.152921) (xy 310.626806 -392.150847) (xy 310.661947 -392.157043) (xy 310.694712 -392.171176)
			(xy 310.723334 -392.192485) (xy 310.746271 -392.21982) (xy 310.762285 -392.251707) (xy 310.770514 -392.286428)
			(xy 310.771032 -392.30427) (xy 311.664083 -392.30427) (xy 311.668225 -392.268828) (xy 311.680429 -392.235297)
			(xy 311.700038 -392.205484) (xy 311.725993 -392.180997) (xy 311.756895 -392.163155) (xy 311.791079 -392.152921)
			(xy 311.826702 -392.150847) (xy 311.861843 -392.157043) (xy 311.894608 -392.171176) (xy 311.92323 -392.192485)
			(xy 311.946167 -392.21982) (xy 311.962181 -392.251707) (xy 311.97041 -392.286428) (xy 311.970928 -392.30427)
			(xy 312.863979 -392.30427) (xy 312.868121 -392.268828) (xy 312.880325 -392.235297) (xy 312.899934 -392.205484)
			(xy 312.925889 -392.180997) (xy 312.956791 -392.163155) (xy 312.990975 -392.152921) (xy 313.026598 -392.150847)
			(xy 313.061739 -392.157043) (xy 313.094504 -392.171176) (xy 313.123126 -392.192485) (xy 313.146063 -392.21982)
			(xy 313.162077 -392.251707) (xy 313.170306 -392.286428) (xy 313.170824 -392.30427) (xy 314.064129 -392.30427)
			(xy 314.068271 -392.268828) (xy 314.080475 -392.235297) (xy 314.100084 -392.205484) (xy 314.126039 -392.180997)
			(xy 314.156941 -392.163155) (xy 314.191125 -392.152921) (xy 314.226748 -392.150847) (xy 314.261889 -392.157043)
			(xy 314.294654 -392.171176) (xy 314.323276 -392.192485) (xy 314.346213 -392.21982) (xy 314.362227 -392.251707)
			(xy 314.370456 -392.286428) (xy 314.370974 -392.30427) (xy 315.264025 -392.30427) (xy 315.268167 -392.268828)
			(xy 315.280371 -392.235297) (xy 315.29998 -392.205484) (xy 315.325935 -392.180997) (xy 315.356837 -392.163155)
			(xy 315.391021 -392.152921) (xy 315.426644 -392.150847) (xy 315.461785 -392.157043) (xy 315.49455 -392.171176)
			(xy 315.523172 -392.192485) (xy 315.546109 -392.21982) (xy 315.562123 -392.251707) (xy 315.570352 -392.286428)
			(xy 315.57087 -392.30427) (xy 316.464175 -392.30427) (xy 316.468317 -392.268828) (xy 316.480521 -392.235297)
			(xy 316.50013 -392.205484) (xy 316.526085 -392.180997) (xy 316.556987 -392.163155) (xy 316.591171 -392.152921)
			(xy 316.626794 -392.150847) (xy 316.661935 -392.157043) (xy 316.6947 -392.171176) (xy 316.723322 -392.192485)
			(xy 316.746259 -392.21982) (xy 316.762273 -392.251707) (xy 316.770502 -392.286428) (xy 316.77102 -392.30427)
			(xy 317.664071 -392.30427) (xy 317.668213 -392.268828) (xy 317.680417 -392.235297) (xy 317.700026 -392.205484)
			(xy 317.725981 -392.180997) (xy 317.756883 -392.163155) (xy 317.791067 -392.152921) (xy 317.82669 -392.150847)
			(xy 317.861831 -392.157043) (xy 317.894596 -392.171176) (xy 317.923218 -392.192485) (xy 317.946155 -392.21982)
			(xy 317.962169 -392.251707) (xy 317.970398 -392.286428) (xy 317.970916 -392.30427) (xy 318.863967 -392.30427)
			(xy 318.868109 -392.268828) (xy 318.880313 -392.235297) (xy 318.899922 -392.205484) (xy 318.925877 -392.180997)
			(xy 318.956779 -392.163155) (xy 318.990963 -392.152921) (xy 319.026586 -392.150847) (xy 319.061727 -392.157043)
			(xy 319.094492 -392.171176) (xy 319.123114 -392.192485) (xy 319.146051 -392.21982) (xy 319.162065 -392.251707)
			(xy 319.170294 -392.286428) (xy 319.170812 -392.30427) (xy 320.064117 -392.30427) (xy 320.068259 -392.268828)
			(xy 320.080463 -392.235297) (xy 320.100072 -392.205484) (xy 320.126027 -392.180997) (xy 320.156929 -392.163155)
			(xy 320.191113 -392.152921) (xy 320.226736 -392.150847) (xy 320.261877 -392.157043) (xy 320.294642 -392.171176)
			(xy 320.323264 -392.192485) (xy 320.346201 -392.21982) (xy 320.362215 -392.251707) (xy 320.370444 -392.286428)
			(xy 320.370962 -392.30427) (xy 321.264013 -392.30427) (xy 321.268155 -392.268828) (xy 321.280359 -392.235297)
			(xy 321.299968 -392.205484) (xy 321.325923 -392.180997) (xy 321.356825 -392.163155) (xy 321.391009 -392.152921)
			(xy 321.426632 -392.150847) (xy 321.461773 -392.157043) (xy 321.494538 -392.171176) (xy 321.52316 -392.192485)
			(xy 321.546097 -392.21982) (xy 321.562111 -392.251707) (xy 321.57034 -392.286428) (xy 321.570858 -392.30427)
			(xy 335.791797 -392.30427) (xy 335.795939 -392.268828) (xy 335.808143 -392.235297) (xy 335.827752 -392.205484)
			(xy 335.853707 -392.180997) (xy 335.884609 -392.163155) (xy 335.918793 -392.152921) (xy 335.954416 -392.150847)
			(xy 335.989557 -392.157043) (xy 336.022322 -392.171176) (xy 336.050944 -392.192485) (xy 336.073881 -392.21982)
			(xy 336.089895 -392.251707) (xy 336.098124 -392.286428) (xy 336.098642 -392.30427) (xy 336.991693 -392.30427)
			(xy 336.995835 -392.268828) (xy 337.008039 -392.235297) (xy 337.027648 -392.205484) (xy 337.053603 -392.180997)
			(xy 337.084505 -392.163155) (xy 337.118689 -392.152921) (xy 337.154312 -392.150847) (xy 337.189453 -392.157043)
			(xy 337.222218 -392.171176) (xy 337.25084 -392.192485) (xy 337.273777 -392.21982) (xy 337.289791 -392.251707)
			(xy 337.29802 -392.286428) (xy 337.298538 -392.30427) (xy 338.191843 -392.30427) (xy 338.195985 -392.268828)
			(xy 338.208189 -392.235297) (xy 338.227798 -392.205484) (xy 338.253753 -392.180997) (xy 338.284655 -392.163155)
			(xy 338.318839 -392.152921) (xy 338.354462 -392.150847) (xy 338.389603 -392.157043) (xy 338.422368 -392.171176)
			(xy 338.45099 -392.192485) (xy 338.473927 -392.21982) (xy 338.489941 -392.251707) (xy 338.49817 -392.286428)
			(xy 338.498688 -392.30427) (xy 339.391739 -392.30427) (xy 339.395881 -392.268828) (xy 339.408085 -392.235297)
			(xy 339.427694 -392.205484) (xy 339.453649 -392.180997) (xy 339.484551 -392.163155) (xy 339.518735 -392.152921)
			(xy 339.554358 -392.150847) (xy 339.589499 -392.157043) (xy 339.622264 -392.171176) (xy 339.650886 -392.192485)
			(xy 339.673823 -392.21982) (xy 339.689837 -392.251707) (xy 339.698066 -392.286428) (xy 339.698584 -392.30427)
			(xy 340.591889 -392.30427) (xy 340.596031 -392.268828) (xy 340.608235 -392.235297) (xy 340.627844 -392.205484)
			(xy 340.653799 -392.180997) (xy 340.684701 -392.163155) (xy 340.718885 -392.152921) (xy 340.754508 -392.150847)
			(xy 340.789649 -392.157043) (xy 340.822414 -392.171176) (xy 340.851036 -392.192485) (xy 340.873973 -392.21982)
			(xy 340.889987 -392.251707) (xy 340.898216 -392.286428) (xy 340.898734 -392.30427) (xy 341.791785 -392.30427)
			(xy 341.795927 -392.268828) (xy 341.808131 -392.235297) (xy 341.82774 -392.205484) (xy 341.853695 -392.180997)
			(xy 341.884597 -392.163155) (xy 341.918781 -392.152921) (xy 341.954404 -392.150847) (xy 341.989545 -392.157043)
			(xy 342.02231 -392.171176) (xy 342.050932 -392.192485) (xy 342.073869 -392.21982) (xy 342.089883 -392.251707)
			(xy 342.098112 -392.286428) (xy 342.09863 -392.30427) (xy 342.991935 -392.30427) (xy 342.996077 -392.268828)
			(xy 343.008281 -392.235297) (xy 343.02789 -392.205484) (xy 343.053845 -392.180997) (xy 343.084747 -392.163155)
			(xy 343.118931 -392.152921) (xy 343.154554 -392.150847) (xy 343.189695 -392.157043) (xy 343.22246 -392.171176)
			(xy 343.251082 -392.192485) (xy 343.274019 -392.21982) (xy 343.290033 -392.251707) (xy 343.298262 -392.286428)
			(xy 343.29878 -392.30427) (xy 344.191831 -392.30427) (xy 344.195973 -392.268828) (xy 344.208177 -392.235297)
			(xy 344.227786 -392.205484) (xy 344.253741 -392.180997) (xy 344.284643 -392.163155) (xy 344.318827 -392.152921)
			(xy 344.35445 -392.150847) (xy 344.389591 -392.157043) (xy 344.422356 -392.171176) (xy 344.450978 -392.192485)
			(xy 344.473915 -392.21982) (xy 344.489929 -392.251707) (xy 344.498158 -392.286428) (xy 344.498676 -392.30427)
			(xy 345.391727 -392.30427) (xy 345.395869 -392.268828) (xy 345.408073 -392.235297) (xy 345.427682 -392.205484)
			(xy 345.453637 -392.180997) (xy 345.484539 -392.163155) (xy 345.518723 -392.152921) (xy 345.554346 -392.150847)
			(xy 345.589487 -392.157043) (xy 345.622252 -392.171176) (xy 345.650874 -392.192485) (xy 345.673811 -392.21982)
			(xy 345.689825 -392.251707) (xy 345.698054 -392.286428) (xy 345.698572 -392.30427) (xy 346.591877 -392.30427)
			(xy 346.596019 -392.268828) (xy 346.608223 -392.235297) (xy 346.627832 -392.205484) (xy 346.653787 -392.180997)
			(xy 346.684689 -392.163155) (xy 346.718873 -392.152921) (xy 346.754496 -392.150847) (xy 346.789637 -392.157043)
			(xy 346.822402 -392.171176) (xy 346.851024 -392.192485) (xy 346.873961 -392.21982) (xy 346.889975 -392.251707)
			(xy 346.898204 -392.286428) (xy 346.898722 -392.30427) (xy 347.791773 -392.30427) (xy 347.795915 -392.268828)
			(xy 347.808119 -392.235297) (xy 347.827728 -392.205484) (xy 347.853683 -392.180997) (xy 347.884585 -392.163155)
			(xy 347.918769 -392.152921) (xy 347.954392 -392.150847) (xy 347.989533 -392.157043) (xy 348.022298 -392.171176)
			(xy 348.05092 -392.192485) (xy 348.073857 -392.21982) (xy 348.089871 -392.251707) (xy 348.0981 -392.286428)
			(xy 348.098618 -392.30427) (xy 348.991923 -392.30427) (xy 348.996065 -392.268828) (xy 349.008269 -392.235297)
			(xy 349.027878 -392.205484) (xy 349.053833 -392.180997) (xy 349.084735 -392.163155) (xy 349.118919 -392.152921)
			(xy 349.154542 -392.150847) (xy 349.189683 -392.157043) (xy 349.222448 -392.171176) (xy 349.25107 -392.192485)
			(xy 349.274007 -392.21982) (xy 349.290021 -392.251707) (xy 349.29825 -392.286428) (xy 349.298768 -392.30427)
			(xy 350.191819 -392.30427) (xy 350.195961 -392.268828) (xy 350.208165 -392.235297) (xy 350.227774 -392.205484)
			(xy 350.253729 -392.180997) (xy 350.284631 -392.163155) (xy 350.318815 -392.152921) (xy 350.354438 -392.150847)
			(xy 350.389579 -392.157043) (xy 350.422344 -392.171176) (xy 350.450966 -392.192485) (xy 350.473903 -392.21982)
			(xy 350.489917 -392.251707) (xy 350.498146 -392.286428) (xy 350.498664 -392.30427) (xy 351.391715 -392.30427)
			(xy 351.395857 -392.268828) (xy 351.408061 -392.235297) (xy 351.42767 -392.205484) (xy 351.453625 -392.180997)
			(xy 351.484527 -392.163155) (xy 351.518711 -392.152921) (xy 351.554334 -392.150847) (xy 351.589475 -392.157043)
			(xy 351.62224 -392.171176) (xy 351.650862 -392.192485) (xy 351.673799 -392.21982) (xy 351.689813 -392.251707)
			(xy 351.698042 -392.286428) (xy 351.69856 -392.30427) (xy 352.591865 -392.30427) (xy 352.596007 -392.268828)
			(xy 352.608211 -392.235297) (xy 352.62782 -392.205484) (xy 352.653775 -392.180997) (xy 352.684677 -392.163155)
			(xy 352.718861 -392.152921) (xy 352.754484 -392.150847) (xy 352.789625 -392.157043) (xy 352.82239 -392.171176)
			(xy 352.851012 -392.192485) (xy 352.873949 -392.21982) (xy 352.889963 -392.251707) (xy 352.898192 -392.286428)
			(xy 352.89871 -392.30427) (xy 353.791761 -392.30427) (xy 353.795903 -392.268828) (xy 353.808107 -392.235297)
			(xy 353.827716 -392.205484) (xy 353.853671 -392.180997) (xy 353.884573 -392.163155) (xy 353.918757 -392.152921)
			(xy 353.95438 -392.150847) (xy 353.989521 -392.157043) (xy 354.022286 -392.171176) (xy 354.050908 -392.192485)
			(xy 354.073845 -392.21982) (xy 354.089859 -392.251707) (xy 354.098088 -392.286428) (xy 354.098606 -392.30427)
			(xy 370.364245 -392.30427) (xy 370.368387 -392.268828) (xy 370.380591 -392.235297) (xy 370.4002 -392.205484)
			(xy 370.426155 -392.180997) (xy 370.457057 -392.163155) (xy 370.491241 -392.152921) (xy 370.526864 -392.150847)
			(xy 370.562005 -392.157043) (xy 370.59477 -392.171176) (xy 370.623392 -392.192485) (xy 370.646329 -392.21982)
			(xy 370.662343 -392.251707) (xy 370.670572 -392.286428) (xy 370.67109 -392.30427) (xy 371.564141 -392.30427)
			(xy 371.568283 -392.268828) (xy 371.580487 -392.235297) (xy 371.600096 -392.205484) (xy 371.626051 -392.180997)
			(xy 371.656953 -392.163155) (xy 371.691137 -392.152921) (xy 371.72676 -392.150847) (xy 371.761901 -392.157043)
			(xy 371.794666 -392.171176) (xy 371.823288 -392.192485) (xy 371.846225 -392.21982) (xy 371.862239 -392.251707)
			(xy 371.870468 -392.286428) (xy 371.870986 -392.30427) (xy 372.764291 -392.30427) (xy 372.768433 -392.268828)
			(xy 372.780637 -392.235297) (xy 372.800246 -392.205484) (xy 372.826201 -392.180997) (xy 372.857103 -392.163155)
			(xy 372.891287 -392.152921) (xy 372.92691 -392.150847) (xy 372.962051 -392.157043) (xy 372.994816 -392.171176)
			(xy 373.023438 -392.192485) (xy 373.046375 -392.21982) (xy 373.062389 -392.251707) (xy 373.070618 -392.286428)
			(xy 373.071136 -392.30427) (xy 373.964187 -392.30427) (xy 373.968329 -392.268828) (xy 373.980533 -392.235297)
			(xy 374.000142 -392.205484) (xy 374.026097 -392.180997) (xy 374.056999 -392.163155) (xy 374.091183 -392.152921)
			(xy 374.126806 -392.150847) (xy 374.161947 -392.157043) (xy 374.194712 -392.171176) (xy 374.223334 -392.192485)
			(xy 374.246271 -392.21982) (xy 374.262285 -392.251707) (xy 374.270514 -392.286428) (xy 374.271032 -392.30427)
			(xy 375.164337 -392.30427) (xy 375.168479 -392.268828) (xy 375.180683 -392.235297) (xy 375.200292 -392.205484)
			(xy 375.226247 -392.180997) (xy 375.257149 -392.163155) (xy 375.291333 -392.152921) (xy 375.326956 -392.150847)
			(xy 375.362097 -392.157043) (xy 375.394862 -392.171176) (xy 375.423484 -392.192485) (xy 375.446421 -392.21982)
			(xy 375.462435 -392.251707) (xy 375.470664 -392.286428) (xy 375.471182 -392.30427) (xy 376.364233 -392.30427)
			(xy 376.368375 -392.268828) (xy 376.380579 -392.235297) (xy 376.400188 -392.205484) (xy 376.426143 -392.180997)
			(xy 376.457045 -392.163155) (xy 376.491229 -392.152921) (xy 376.526852 -392.150847) (xy 376.561993 -392.157043)
			(xy 376.594758 -392.171176) (xy 376.62338 -392.192485) (xy 376.646317 -392.21982) (xy 376.662331 -392.251707)
			(xy 376.67056 -392.286428) (xy 376.671078 -392.30427) (xy 377.564383 -392.30427) (xy 377.568525 -392.268828)
			(xy 377.580729 -392.235297) (xy 377.600338 -392.205484) (xy 377.626293 -392.180997) (xy 377.657195 -392.163155)
			(xy 377.691379 -392.152921) (xy 377.727002 -392.150847) (xy 377.762143 -392.157043) (xy 377.794908 -392.171176)
			(xy 377.82353 -392.192485) (xy 377.846467 -392.21982) (xy 377.862481 -392.251707) (xy 377.87071 -392.286428)
			(xy 377.871228 -392.30427) (xy 378.764279 -392.30427) (xy 378.768421 -392.268828) (xy 378.780625 -392.235297)
			(xy 378.800234 -392.205484) (xy 378.826189 -392.180997) (xy 378.857091 -392.163155) (xy 378.891275 -392.152921)
			(xy 378.926898 -392.150847) (xy 378.962039 -392.157043) (xy 378.994804 -392.171176) (xy 379.023426 -392.192485)
			(xy 379.046363 -392.21982) (xy 379.062377 -392.251707) (xy 379.070606 -392.286428) (xy 379.071124 -392.30427)
			(xy 379.964175 -392.30427) (xy 379.968317 -392.268828) (xy 379.980521 -392.235297) (xy 380.00013 -392.205484)
			(xy 380.026085 -392.180997) (xy 380.056987 -392.163155) (xy 380.091171 -392.152921) (xy 380.126794 -392.150847)
			(xy 380.161935 -392.157043) (xy 380.1947 -392.171176) (xy 380.223322 -392.192485) (xy 380.246259 -392.21982)
			(xy 380.262273 -392.251707) (xy 380.270502 -392.286428) (xy 380.27102 -392.30427) (xy 381.164325 -392.30427)
			(xy 381.168467 -392.268828) (xy 381.180671 -392.235297) (xy 381.20028 -392.205484) (xy 381.226235 -392.180997)
			(xy 381.257137 -392.163155) (xy 381.291321 -392.152921) (xy 381.326944 -392.150847) (xy 381.362085 -392.157043)
			(xy 381.39485 -392.171176) (xy 381.423472 -392.192485) (xy 381.446409 -392.21982) (xy 381.462423 -392.251707)
			(xy 381.470652 -392.286428) (xy 381.47117 -392.30427) (xy 382.364221 -392.30427) (xy 382.368363 -392.268828)
			(xy 382.380567 -392.235297) (xy 382.400176 -392.205484) (xy 382.426131 -392.180997) (xy 382.457033 -392.163155)
			(xy 382.491217 -392.152921) (xy 382.52684 -392.150847) (xy 382.561981 -392.157043) (xy 382.594746 -392.171176)
			(xy 382.623368 -392.192485) (xy 382.646305 -392.21982) (xy 382.662319 -392.251707) (xy 382.670548 -392.286428)
			(xy 382.671066 -392.30427) (xy 383.564371 -392.30427) (xy 383.568513 -392.268828) (xy 383.580717 -392.235297)
			(xy 383.600326 -392.205484) (xy 383.626281 -392.180997) (xy 383.657183 -392.163155) (xy 383.691367 -392.152921)
			(xy 383.72699 -392.150847) (xy 383.762131 -392.157043) (xy 383.794896 -392.171176) (xy 383.823518 -392.192485)
			(xy 383.846455 -392.21982) (xy 383.862469 -392.251707) (xy 383.870698 -392.286428) (xy 383.871216 -392.30427)
			(xy 384.764267 -392.30427) (xy 384.768409 -392.268828) (xy 384.780613 -392.235297) (xy 384.800222 -392.205484)
			(xy 384.826177 -392.180997) (xy 384.857079 -392.163155) (xy 384.891263 -392.152921) (xy 384.926886 -392.150847)
			(xy 384.962027 -392.157043) (xy 384.994792 -392.171176) (xy 385.023414 -392.192485) (xy 385.046351 -392.21982)
			(xy 385.062365 -392.251707) (xy 385.070594 -392.286428) (xy 385.071112 -392.30427) (xy 385.964163 -392.30427)
			(xy 385.968305 -392.268828) (xy 385.980509 -392.235297) (xy 386.000118 -392.205484) (xy 386.026073 -392.180997)
			(xy 386.056975 -392.163155) (xy 386.091159 -392.152921) (xy 386.126782 -392.150847) (xy 386.161923 -392.157043)
			(xy 386.194688 -392.171176) (xy 386.22331 -392.192485) (xy 386.246247 -392.21982) (xy 386.262261 -392.251707)
			(xy 386.27049 -392.286428) (xy 386.271008 -392.30427) (xy 387.164313 -392.30427) (xy 387.168455 -392.268828)
			(xy 387.180659 -392.235297) (xy 387.200268 -392.205484) (xy 387.226223 -392.180997) (xy 387.257125 -392.163155)
			(xy 387.291309 -392.152921) (xy 387.326932 -392.150847) (xy 387.362073 -392.157043) (xy 387.394838 -392.171176)
			(xy 387.42346 -392.192485) (xy 387.446397 -392.21982) (xy 387.462411 -392.251707) (xy 387.47064 -392.286428)
			(xy 387.471158 -392.30427) (xy 388.364209 -392.30427) (xy 388.368351 -392.268828) (xy 388.380555 -392.235297)
			(xy 388.400164 -392.205484) (xy 388.426119 -392.180997) (xy 388.457021 -392.163155) (xy 388.491205 -392.152921)
			(xy 388.526828 -392.150847) (xy 388.561969 -392.157043) (xy 388.594734 -392.171176) (xy 388.623356 -392.192485)
			(xy 388.646293 -392.21982) (xy 388.662307 -392.251707) (xy 388.670536 -392.286428) (xy 388.671054 -392.30427)
			(xy 402.891993 -392.30427) (xy 402.896135 -392.268828) (xy 402.908339 -392.235297) (xy 402.927948 -392.205484)
			(xy 402.953903 -392.180997) (xy 402.984805 -392.163155) (xy 403.018989 -392.152921) (xy 403.054612 -392.150847)
			(xy 403.089753 -392.157043) (xy 403.122518 -392.171176) (xy 403.15114 -392.192485) (xy 403.174077 -392.21982)
			(xy 403.190091 -392.251707) (xy 403.19832 -392.286428) (xy 403.198838 -392.30427) (xy 404.091889 -392.30427)
			(xy 404.096031 -392.268828) (xy 404.108235 -392.235297) (xy 404.127844 -392.205484) (xy 404.153799 -392.180997)
			(xy 404.184701 -392.163155) (xy 404.218885 -392.152921) (xy 404.254508 -392.150847) (xy 404.289649 -392.157043)
			(xy 404.322414 -392.171176) (xy 404.351036 -392.192485) (xy 404.373973 -392.21982) (xy 404.389987 -392.251707)
			(xy 404.398216 -392.286428) (xy 404.398734 -392.30427) (xy 405.292039 -392.30427) (xy 405.296181 -392.268828)
			(xy 405.308385 -392.235297) (xy 405.327994 -392.205484) (xy 405.353949 -392.180997) (xy 405.384851 -392.163155)
			(xy 405.419035 -392.152921) (xy 405.454658 -392.150847) (xy 405.489799 -392.157043) (xy 405.522564 -392.171176)
			(xy 405.551186 -392.192485) (xy 405.574123 -392.21982) (xy 405.590137 -392.251707) (xy 405.598366 -392.286428)
			(xy 405.598884 -392.30427) (xy 406.491935 -392.30427) (xy 406.496077 -392.268828) (xy 406.508281 -392.235297)
			(xy 406.52789 -392.205484) (xy 406.553845 -392.180997) (xy 406.584747 -392.163155) (xy 406.618931 -392.152921)
			(xy 406.654554 -392.150847) (xy 406.689695 -392.157043) (xy 406.72246 -392.171176) (xy 406.751082 -392.192485)
			(xy 406.774019 -392.21982) (xy 406.790033 -392.251707) (xy 406.798262 -392.286428) (xy 406.79878 -392.30427)
			(xy 407.692085 -392.30427) (xy 407.696227 -392.268828) (xy 407.708431 -392.235297) (xy 407.72804 -392.205484)
			(xy 407.753995 -392.180997) (xy 407.784897 -392.163155) (xy 407.819081 -392.152921) (xy 407.854704 -392.150847)
			(xy 407.889845 -392.157043) (xy 407.92261 -392.171176) (xy 407.951232 -392.192485) (xy 407.974169 -392.21982)
			(xy 407.990183 -392.251707) (xy 407.998412 -392.286428) (xy 407.99893 -392.30427) (xy 408.891981 -392.30427)
			(xy 408.896123 -392.268828) (xy 408.908327 -392.235297) (xy 408.927936 -392.205484) (xy 408.953891 -392.180997)
			(xy 408.984793 -392.163155) (xy 409.018977 -392.152921) (xy 409.0546 -392.150847) (xy 409.089741 -392.157043)
			(xy 409.122506 -392.171176) (xy 409.151128 -392.192485) (xy 409.174065 -392.21982) (xy 409.190079 -392.251707)
			(xy 409.198308 -392.286428) (xy 409.198826 -392.30427) (xy 410.092131 -392.30427) (xy 410.096273 -392.268828)
			(xy 410.108477 -392.235297) (xy 410.128086 -392.205484) (xy 410.154041 -392.180997) (xy 410.184943 -392.163155)
			(xy 410.219127 -392.152921) (xy 410.25475 -392.150847) (xy 410.289891 -392.157043) (xy 410.322656 -392.171176)
			(xy 410.351278 -392.192485) (xy 410.374215 -392.21982) (xy 410.390229 -392.251707) (xy 410.398458 -392.286428)
			(xy 410.398976 -392.30427) (xy 411.292027 -392.30427) (xy 411.296169 -392.268828) (xy 411.308373 -392.235297)
			(xy 411.327982 -392.205484) (xy 411.353937 -392.180997) (xy 411.384839 -392.163155) (xy 411.419023 -392.152921)
			(xy 411.454646 -392.150847) (xy 411.489787 -392.157043) (xy 411.522552 -392.171176) (xy 411.551174 -392.192485)
			(xy 411.574111 -392.21982) (xy 411.590125 -392.251707) (xy 411.598354 -392.286428) (xy 411.598872 -392.30427)
			(xy 412.491923 -392.30427) (xy 412.496065 -392.268828) (xy 412.508269 -392.235297) (xy 412.527878 -392.205484)
			(xy 412.553833 -392.180997) (xy 412.584735 -392.163155) (xy 412.618919 -392.152921) (xy 412.654542 -392.150847)
			(xy 412.689683 -392.157043) (xy 412.722448 -392.171176) (xy 412.75107 -392.192485) (xy 412.774007 -392.21982)
			(xy 412.790021 -392.251707) (xy 412.79825 -392.286428) (xy 412.798768 -392.30427) (xy 413.692073 -392.30427)
			(xy 413.696215 -392.268828) (xy 413.708419 -392.235297) (xy 413.728028 -392.205484) (xy 413.753983 -392.180997)
			(xy 413.784885 -392.163155) (xy 413.819069 -392.152921) (xy 413.854692 -392.150847) (xy 413.889833 -392.157043)
			(xy 413.922598 -392.171176) (xy 413.95122 -392.192485) (xy 413.974157 -392.21982) (xy 413.990171 -392.251707)
			(xy 413.9984 -392.286428) (xy 413.998918 -392.30427) (xy 414.891969 -392.30427) (xy 414.896111 -392.268828)
			(xy 414.908315 -392.235297) (xy 414.927924 -392.205484) (xy 414.953879 -392.180997) (xy 414.984781 -392.163155)
			(xy 415.018965 -392.152921) (xy 415.054588 -392.150847) (xy 415.089729 -392.157043) (xy 415.122494 -392.171176)
			(xy 415.151116 -392.192485) (xy 415.174053 -392.21982) (xy 415.190067 -392.251707) (xy 415.198296 -392.286428)
			(xy 415.198814 -392.30427) (xy 416.092119 -392.30427) (xy 416.096261 -392.268828) (xy 416.108465 -392.235297)
			(xy 416.128074 -392.205484) (xy 416.154029 -392.180997) (xy 416.184931 -392.163155) (xy 416.219115 -392.152921)
			(xy 416.254738 -392.150847) (xy 416.289879 -392.157043) (xy 416.322644 -392.171176) (xy 416.351266 -392.192485)
			(xy 416.374203 -392.21982) (xy 416.390217 -392.251707) (xy 416.398446 -392.286428) (xy 416.398964 -392.30427)
			(xy 417.292015 -392.30427) (xy 417.296157 -392.268828) (xy 417.308361 -392.235297) (xy 417.32797 -392.205484)
			(xy 417.353925 -392.180997) (xy 417.384827 -392.163155) (xy 417.419011 -392.152921) (xy 417.454634 -392.150847)
			(xy 417.489775 -392.157043) (xy 417.52254 -392.171176) (xy 417.551162 -392.192485) (xy 417.574099 -392.21982)
			(xy 417.590113 -392.251707) (xy 417.598342 -392.286428) (xy 417.59886 -392.30427) (xy 418.491911 -392.30427)
			(xy 418.496053 -392.268828) (xy 418.508257 -392.235297) (xy 418.527866 -392.205484) (xy 418.553821 -392.180997)
			(xy 418.584723 -392.163155) (xy 418.618907 -392.152921) (xy 418.65453 -392.150847) (xy 418.689671 -392.157043)
			(xy 418.722436 -392.171176) (xy 418.751058 -392.192485) (xy 418.773995 -392.21982) (xy 418.790009 -392.251707)
			(xy 418.798238 -392.286428) (xy 418.798756 -392.30427) (xy 419.692061 -392.30427) (xy 419.696203 -392.268828)
			(xy 419.708407 -392.235297) (xy 419.728016 -392.205484) (xy 419.753971 -392.180997) (xy 419.784873 -392.163155)
			(xy 419.819057 -392.152921) (xy 419.85468 -392.150847) (xy 419.889821 -392.157043) (xy 419.922586 -392.171176)
			(xy 419.951208 -392.192485) (xy 419.974145 -392.21982) (xy 419.990159 -392.251707) (xy 419.998388 -392.286428)
			(xy 419.998906 -392.30427) (xy 420.891957 -392.30427) (xy 420.896099 -392.268828) (xy 420.908303 -392.235297)
			(xy 420.927912 -392.205484) (xy 420.953867 -392.180997) (xy 420.984769 -392.163155) (xy 421.018953 -392.152921)
			(xy 421.054576 -392.150847) (xy 421.089717 -392.157043) (xy 421.122482 -392.171176) (xy 421.151104 -392.192485)
			(xy 421.174041 -392.21982) (xy 421.190055 -392.251707) (xy 421.198284 -392.286428) (xy 421.198802 -392.30427)
			(xy 421.198284 -392.322112) (xy 421.190055 -392.356833) (xy 421.174041 -392.38872) (xy 421.151104 -392.416055)
			(xy 421.122482 -392.437364) (xy 421.089717 -392.451497) (xy 421.054576 -392.457693) (xy 421.018953 -392.455619)
			(xy 420.984769 -392.445385) (xy 420.953867 -392.427543) (xy 420.927912 -392.403056) (xy 420.908303 -392.373243)
			(xy 420.896099 -392.339712) (xy 420.891957 -392.30427) (xy 419.998906 -392.30427) (xy 419.998388 -392.322112)
			(xy 419.990159 -392.356833) (xy 419.974145 -392.38872) (xy 419.951208 -392.416055) (xy 419.922586 -392.437364)
			(xy 419.889821 -392.451497) (xy 419.85468 -392.457693) (xy 419.819057 -392.455619) (xy 419.784873 -392.445385)
			(xy 419.753971 -392.427543) (xy 419.728016 -392.403056) (xy 419.708407 -392.373243) (xy 419.696203 -392.339712)
			(xy 419.692061 -392.30427) (xy 418.798756 -392.30427) (xy 418.798238 -392.322112) (xy 418.790009 -392.356833)
			(xy 418.773995 -392.38872) (xy 418.751058 -392.416055) (xy 418.722436 -392.437364) (xy 418.689671 -392.451497)
			(xy 418.65453 -392.457693) (xy 418.618907 -392.455619) (xy 418.584723 -392.445385) (xy 418.553821 -392.427543)
			(xy 418.527866 -392.403056) (xy 418.508257 -392.373243) (xy 418.496053 -392.339712) (xy 418.491911 -392.30427)
			(xy 417.59886 -392.30427) (xy 417.598342 -392.322112) (xy 417.590113 -392.356833) (xy 417.574099 -392.38872)
			(xy 417.551162 -392.416055) (xy 417.52254 -392.437364) (xy 417.489775 -392.451497) (xy 417.454634 -392.457693)
			(xy 417.419011 -392.455619) (xy 417.384827 -392.445385) (xy 417.353925 -392.427543) (xy 417.32797 -392.403056)
			(xy 417.308361 -392.373243) (xy 417.296157 -392.339712) (xy 417.292015 -392.30427) (xy 416.398964 -392.30427)
			(xy 416.398446 -392.322112) (xy 416.390217 -392.356833) (xy 416.374203 -392.38872) (xy 416.351266 -392.416055)
			(xy 416.322644 -392.437364) (xy 416.289879 -392.451497) (xy 416.254738 -392.457693) (xy 416.219115 -392.455619)
			(xy 416.184931 -392.445385) (xy 416.154029 -392.427543) (xy 416.128074 -392.403056) (xy 416.108465 -392.373243)
			(xy 416.096261 -392.339712) (xy 416.092119 -392.30427) (xy 415.198814 -392.30427) (xy 415.198296 -392.322112)
			(xy 415.190067 -392.356833) (xy 415.174053 -392.38872) (xy 415.151116 -392.416055) (xy 415.122494 -392.437364)
			(xy 415.089729 -392.451497) (xy 415.054588 -392.457693) (xy 415.018965 -392.455619) (xy 414.984781 -392.445385)
			(xy 414.953879 -392.427543) (xy 414.927924 -392.403056) (xy 414.908315 -392.373243) (xy 414.896111 -392.339712)
			(xy 414.891969 -392.30427) (xy 413.998918 -392.30427) (xy 413.9984 -392.322112) (xy 413.990171 -392.356833)
			(xy 413.974157 -392.38872) (xy 413.95122 -392.416055) (xy 413.922598 -392.437364) (xy 413.889833 -392.451497)
			(xy 413.854692 -392.457693) (xy 413.819069 -392.455619) (xy 413.784885 -392.445385) (xy 413.753983 -392.427543)
			(xy 413.728028 -392.403056) (xy 413.708419 -392.373243) (xy 413.696215 -392.339712) (xy 413.692073 -392.30427)
			(xy 412.798768 -392.30427) (xy 412.79825 -392.322112) (xy 412.790021 -392.356833) (xy 412.774007 -392.38872)
			(xy 412.75107 -392.416055) (xy 412.722448 -392.437364) (xy 412.689683 -392.451497) (xy 412.654542 -392.457693)
			(xy 412.618919 -392.455619) (xy 412.584735 -392.445385) (xy 412.553833 -392.427543) (xy 412.527878 -392.403056)
			(xy 412.508269 -392.373243) (xy 412.496065 -392.339712) (xy 412.491923 -392.30427) (xy 411.598872 -392.30427)
			(xy 411.598354 -392.322112) (xy 411.590125 -392.356833) (xy 411.574111 -392.38872) (xy 411.551174 -392.416055)
			(xy 411.522552 -392.437364) (xy 411.489787 -392.451497) (xy 411.454646 -392.457693) (xy 411.419023 -392.455619)
			(xy 411.384839 -392.445385) (xy 411.353937 -392.427543) (xy 411.327982 -392.403056) (xy 411.308373 -392.373243)
			(xy 411.296169 -392.339712) (xy 411.292027 -392.30427) (xy 410.398976 -392.30427) (xy 410.398458 -392.322112)
			(xy 410.390229 -392.356833) (xy 410.374215 -392.38872) (xy 410.351278 -392.416055) (xy 410.322656 -392.437364)
			(xy 410.289891 -392.451497) (xy 410.25475 -392.457693) (xy 410.219127 -392.455619) (xy 410.184943 -392.445385)
			(xy 410.154041 -392.427543) (xy 410.128086 -392.403056) (xy 410.108477 -392.373243) (xy 410.096273 -392.339712)
			(xy 410.092131 -392.30427) (xy 409.198826 -392.30427) (xy 409.198308 -392.322112) (xy 409.190079 -392.356833)
			(xy 409.174065 -392.38872) (xy 409.151128 -392.416055) (xy 409.122506 -392.437364) (xy 409.089741 -392.451497)
			(xy 409.0546 -392.457693) (xy 409.018977 -392.455619) (xy 408.984793 -392.445385) (xy 408.953891 -392.427543)
			(xy 408.927936 -392.403056) (xy 408.908327 -392.373243) (xy 408.896123 -392.339712) (xy 408.891981 -392.30427)
			(xy 407.99893 -392.30427) (xy 407.998412 -392.322112) (xy 407.990183 -392.356833) (xy 407.974169 -392.38872)
			(xy 407.951232 -392.416055) (xy 407.92261 -392.437364) (xy 407.889845 -392.451497) (xy 407.854704 -392.457693)
			(xy 407.819081 -392.455619) (xy 407.784897 -392.445385) (xy 407.753995 -392.427543) (xy 407.72804 -392.403056)
			(xy 407.708431 -392.373243) (xy 407.696227 -392.339712) (xy 407.692085 -392.30427) (xy 406.79878 -392.30427)
			(xy 406.798262 -392.322112) (xy 406.790033 -392.356833) (xy 406.774019 -392.38872) (xy 406.751082 -392.416055)
			(xy 406.72246 -392.437364) (xy 406.689695 -392.451497) (xy 406.654554 -392.457693) (xy 406.618931 -392.455619)
			(xy 406.584747 -392.445385) (xy 406.553845 -392.427543) (xy 406.52789 -392.403056) (xy 406.508281 -392.373243)
			(xy 406.496077 -392.339712) (xy 406.491935 -392.30427) (xy 405.598884 -392.30427) (xy 405.598366 -392.322112)
			(xy 405.590137 -392.356833) (xy 405.574123 -392.38872) (xy 405.551186 -392.416055) (xy 405.522564 -392.437364)
			(xy 405.489799 -392.451497) (xy 405.454658 -392.457693) (xy 405.419035 -392.455619) (xy 405.384851 -392.445385)
			(xy 405.353949 -392.427543) (xy 405.327994 -392.403056) (xy 405.308385 -392.373243) (xy 405.296181 -392.339712)
			(xy 405.292039 -392.30427) (xy 404.398734 -392.30427) (xy 404.398216 -392.322112) (xy 404.389987 -392.356833)
			(xy 404.373973 -392.38872) (xy 404.351036 -392.416055) (xy 404.322414 -392.437364) (xy 404.289649 -392.451497)
			(xy 404.254508 -392.457693) (xy 404.218885 -392.455619) (xy 404.184701 -392.445385) (xy 404.153799 -392.427543)
			(xy 404.127844 -392.403056) (xy 404.108235 -392.373243) (xy 404.096031 -392.339712) (xy 404.091889 -392.30427)
			(xy 403.198838 -392.30427) (xy 403.19832 -392.322112) (xy 403.190091 -392.356833) (xy 403.174077 -392.38872)
			(xy 403.15114 -392.416055) (xy 403.122518 -392.437364) (xy 403.089753 -392.451497) (xy 403.054612 -392.457693)
			(xy 403.018989 -392.455619) (xy 402.984805 -392.445385) (xy 402.953903 -392.427543) (xy 402.927948 -392.403056)
			(xy 402.908339 -392.373243) (xy 402.896135 -392.339712) (xy 402.891993 -392.30427) (xy 388.671054 -392.30427)
			(xy 388.670536 -392.322112) (xy 388.662307 -392.356833) (xy 388.646293 -392.38872) (xy 388.623356 -392.416055)
			(xy 388.594734 -392.437364) (xy 388.561969 -392.451497) (xy 388.526828 -392.457693) (xy 388.491205 -392.455619)
			(xy 388.457021 -392.445385) (xy 388.426119 -392.427543) (xy 388.400164 -392.403056) (xy 388.380555 -392.373243)
			(xy 388.368351 -392.339712) (xy 388.364209 -392.30427) (xy 387.471158 -392.30427) (xy 387.47064 -392.322112)
			(xy 387.462411 -392.356833) (xy 387.446397 -392.38872) (xy 387.42346 -392.416055) (xy 387.394838 -392.437364)
			(xy 387.362073 -392.451497) (xy 387.326932 -392.457693) (xy 387.291309 -392.455619) (xy 387.257125 -392.445385)
			(xy 387.226223 -392.427543) (xy 387.200268 -392.403056) (xy 387.180659 -392.373243) (xy 387.168455 -392.339712)
			(xy 387.164313 -392.30427) (xy 386.271008 -392.30427) (xy 386.27049 -392.322112) (xy 386.262261 -392.356833)
			(xy 386.246247 -392.38872) (xy 386.22331 -392.416055) (xy 386.194688 -392.437364) (xy 386.161923 -392.451497)
			(xy 386.126782 -392.457693) (xy 386.091159 -392.455619) (xy 386.056975 -392.445385) (xy 386.026073 -392.427543)
			(xy 386.000118 -392.403056) (xy 385.980509 -392.373243) (xy 385.968305 -392.339712) (xy 385.964163 -392.30427)
			(xy 385.071112 -392.30427) (xy 385.070594 -392.322112) (xy 385.062365 -392.356833) (xy 385.046351 -392.38872)
			(xy 385.023414 -392.416055) (xy 384.994792 -392.437364) (xy 384.962027 -392.451497) (xy 384.926886 -392.457693)
			(xy 384.891263 -392.455619) (xy 384.857079 -392.445385) (xy 384.826177 -392.427543) (xy 384.800222 -392.403056)
			(xy 384.780613 -392.373243) (xy 384.768409 -392.339712) (xy 384.764267 -392.30427) (xy 383.871216 -392.30427)
			(xy 383.870698 -392.322112) (xy 383.862469 -392.356833) (xy 383.846455 -392.38872) (xy 383.823518 -392.416055)
			(xy 383.794896 -392.437364) (xy 383.762131 -392.451497) (xy 383.72699 -392.457693) (xy 383.691367 -392.455619)
			(xy 383.657183 -392.445385) (xy 383.626281 -392.427543) (xy 383.600326 -392.403056) (xy 383.580717 -392.373243)
			(xy 383.568513 -392.339712) (xy 383.564371 -392.30427) (xy 382.671066 -392.30427) (xy 382.670548 -392.322112)
			(xy 382.662319 -392.356833) (xy 382.646305 -392.38872) (xy 382.623368 -392.416055) (xy 382.594746 -392.437364)
			(xy 382.561981 -392.451497) (xy 382.52684 -392.457693) (xy 382.491217 -392.455619) (xy 382.457033 -392.445385)
			(xy 382.426131 -392.427543) (xy 382.400176 -392.403056) (xy 382.380567 -392.373243) (xy 382.368363 -392.339712)
			(xy 382.364221 -392.30427) (xy 381.47117 -392.30427) (xy 381.470652 -392.322112) (xy 381.462423 -392.356833)
			(xy 381.446409 -392.38872) (xy 381.423472 -392.416055) (xy 381.39485 -392.437364) (xy 381.362085 -392.451497)
			(xy 381.326944 -392.457693) (xy 381.291321 -392.455619) (xy 381.257137 -392.445385) (xy 381.226235 -392.427543)
			(xy 381.20028 -392.403056) (xy 381.180671 -392.373243) (xy 381.168467 -392.339712) (xy 381.164325 -392.30427)
			(xy 380.27102 -392.30427) (xy 380.270502 -392.322112) (xy 380.262273 -392.356833) (xy 380.246259 -392.38872)
			(xy 380.223322 -392.416055) (xy 380.1947 -392.437364) (xy 380.161935 -392.451497) (xy 380.126794 -392.457693)
			(xy 380.091171 -392.455619) (xy 380.056987 -392.445385) (xy 380.026085 -392.427543) (xy 380.00013 -392.403056)
			(xy 379.980521 -392.373243) (xy 379.968317 -392.339712) (xy 379.964175 -392.30427) (xy 379.071124 -392.30427)
			(xy 379.070606 -392.322112) (xy 379.062377 -392.356833) (xy 379.046363 -392.38872) (xy 379.023426 -392.416055)
			(xy 378.994804 -392.437364) (xy 378.962039 -392.451497) (xy 378.926898 -392.457693) (xy 378.891275 -392.455619)
			(xy 378.857091 -392.445385) (xy 378.826189 -392.427543) (xy 378.800234 -392.403056) (xy 378.780625 -392.373243)
			(xy 378.768421 -392.339712) (xy 378.764279 -392.30427) (xy 377.871228 -392.30427) (xy 377.87071 -392.322112)
			(xy 377.862481 -392.356833) (xy 377.846467 -392.38872) (xy 377.82353 -392.416055) (xy 377.794908 -392.437364)
			(xy 377.762143 -392.451497) (xy 377.727002 -392.457693) (xy 377.691379 -392.455619) (xy 377.657195 -392.445385)
			(xy 377.626293 -392.427543) (xy 377.600338 -392.403056) (xy 377.580729 -392.373243) (xy 377.568525 -392.339712)
			(xy 377.564383 -392.30427) (xy 376.671078 -392.30427) (xy 376.67056 -392.322112) (xy 376.662331 -392.356833)
			(xy 376.646317 -392.38872) (xy 376.62338 -392.416055) (xy 376.594758 -392.437364) (xy 376.561993 -392.451497)
			(xy 376.526852 -392.457693) (xy 376.491229 -392.455619) (xy 376.457045 -392.445385) (xy 376.426143 -392.427543)
			(xy 376.400188 -392.403056) (xy 376.380579 -392.373243) (xy 376.368375 -392.339712) (xy 376.364233 -392.30427)
			(xy 375.471182 -392.30427) (xy 375.470664 -392.322112) (xy 375.462435 -392.356833) (xy 375.446421 -392.38872)
			(xy 375.423484 -392.416055) (xy 375.394862 -392.437364) (xy 375.362097 -392.451497) (xy 375.326956 -392.457693)
			(xy 375.291333 -392.455619) (xy 375.257149 -392.445385) (xy 375.226247 -392.427543) (xy 375.200292 -392.403056)
			(xy 375.180683 -392.373243) (xy 375.168479 -392.339712) (xy 375.164337 -392.30427) (xy 374.271032 -392.30427)
			(xy 374.270514 -392.322112) (xy 374.262285 -392.356833) (xy 374.246271 -392.38872) (xy 374.223334 -392.416055)
			(xy 374.194712 -392.437364) (xy 374.161947 -392.451497) (xy 374.126806 -392.457693) (xy 374.091183 -392.455619)
			(xy 374.056999 -392.445385) (xy 374.026097 -392.427543) (xy 374.000142 -392.403056) (xy 373.980533 -392.373243)
			(xy 373.968329 -392.339712) (xy 373.964187 -392.30427) (xy 373.071136 -392.30427) (xy 373.070618 -392.322112)
			(xy 373.062389 -392.356833) (xy 373.046375 -392.38872) (xy 373.023438 -392.416055) (xy 372.994816 -392.437364)
			(xy 372.962051 -392.451497) (xy 372.92691 -392.457693) (xy 372.891287 -392.455619) (xy 372.857103 -392.445385)
			(xy 372.826201 -392.427543) (xy 372.800246 -392.403056) (xy 372.780637 -392.373243) (xy 372.768433 -392.339712)
			(xy 372.764291 -392.30427) (xy 371.870986 -392.30427) (xy 371.870468 -392.322112) (xy 371.862239 -392.356833)
			(xy 371.846225 -392.38872) (xy 371.823288 -392.416055) (xy 371.794666 -392.437364) (xy 371.761901 -392.451497)
			(xy 371.72676 -392.457693) (xy 371.691137 -392.455619) (xy 371.656953 -392.445385) (xy 371.626051 -392.427543)
			(xy 371.600096 -392.403056) (xy 371.580487 -392.373243) (xy 371.568283 -392.339712) (xy 371.564141 -392.30427)
			(xy 370.67109 -392.30427) (xy 370.670572 -392.322112) (xy 370.662343 -392.356833) (xy 370.646329 -392.38872)
			(xy 370.623392 -392.416055) (xy 370.59477 -392.437364) (xy 370.562005 -392.451497) (xy 370.526864 -392.457693)
			(xy 370.491241 -392.455619) (xy 370.457057 -392.445385) (xy 370.426155 -392.427543) (xy 370.4002 -392.403056)
			(xy 370.380591 -392.373243) (xy 370.368387 -392.339712) (xy 370.364245 -392.30427) (xy 354.098606 -392.30427)
			(xy 354.098088 -392.322112) (xy 354.089859 -392.356833) (xy 354.073845 -392.38872) (xy 354.050908 -392.416055)
			(xy 354.022286 -392.437364) (xy 353.989521 -392.451497) (xy 353.95438 -392.457693) (xy 353.918757 -392.455619)
			(xy 353.884573 -392.445385) (xy 353.853671 -392.427543) (xy 353.827716 -392.403056) (xy 353.808107 -392.373243)
			(xy 353.795903 -392.339712) (xy 353.791761 -392.30427) (xy 352.89871 -392.30427) (xy 352.898192 -392.322112)
			(xy 352.889963 -392.356833) (xy 352.873949 -392.38872) (xy 352.851012 -392.416055) (xy 352.82239 -392.437364)
			(xy 352.789625 -392.451497) (xy 352.754484 -392.457693) (xy 352.718861 -392.455619) (xy 352.684677 -392.445385)
			(xy 352.653775 -392.427543) (xy 352.62782 -392.403056) (xy 352.608211 -392.373243) (xy 352.596007 -392.339712)
			(xy 352.591865 -392.30427) (xy 351.69856 -392.30427) (xy 351.698042 -392.322112) (xy 351.689813 -392.356833)
			(xy 351.673799 -392.38872) (xy 351.650862 -392.416055) (xy 351.62224 -392.437364) (xy 351.589475 -392.451497)
			(xy 351.554334 -392.457693) (xy 351.518711 -392.455619) (xy 351.484527 -392.445385) (xy 351.453625 -392.427543)
			(xy 351.42767 -392.403056) (xy 351.408061 -392.373243) (xy 351.395857 -392.339712) (xy 351.391715 -392.30427)
			(xy 350.498664 -392.30427) (xy 350.498146 -392.322112) (xy 350.489917 -392.356833) (xy 350.473903 -392.38872)
			(xy 350.450966 -392.416055) (xy 350.422344 -392.437364) (xy 350.389579 -392.451497) (xy 350.354438 -392.457693)
			(xy 350.318815 -392.455619) (xy 350.284631 -392.445385) (xy 350.253729 -392.427543) (xy 350.227774 -392.403056)
			(xy 350.208165 -392.373243) (xy 350.195961 -392.339712) (xy 350.191819 -392.30427) (xy 349.298768 -392.30427)
			(xy 349.29825 -392.322112) (xy 349.290021 -392.356833) (xy 349.274007 -392.38872) (xy 349.25107 -392.416055)
			(xy 349.222448 -392.437364) (xy 349.189683 -392.451497) (xy 349.154542 -392.457693) (xy 349.118919 -392.455619)
			(xy 349.084735 -392.445385) (xy 349.053833 -392.427543) (xy 349.027878 -392.403056) (xy 349.008269 -392.373243)
			(xy 348.996065 -392.339712) (xy 348.991923 -392.30427) (xy 348.098618 -392.30427) (xy 348.0981 -392.322112)
			(xy 348.089871 -392.356833) (xy 348.073857 -392.38872) (xy 348.05092 -392.416055) (xy 348.022298 -392.437364)
			(xy 347.989533 -392.451497) (xy 347.954392 -392.457693) (xy 347.918769 -392.455619) (xy 347.884585 -392.445385)
			(xy 347.853683 -392.427543) (xy 347.827728 -392.403056) (xy 347.808119 -392.373243) (xy 347.795915 -392.339712)
			(xy 347.791773 -392.30427) (xy 346.898722 -392.30427) (xy 346.898204 -392.322112) (xy 346.889975 -392.356833)
			(xy 346.873961 -392.38872) (xy 346.851024 -392.416055) (xy 346.822402 -392.437364) (xy 346.789637 -392.451497)
			(xy 346.754496 -392.457693) (xy 346.718873 -392.455619) (xy 346.684689 -392.445385) (xy 346.653787 -392.427543)
			(xy 346.627832 -392.403056) (xy 346.608223 -392.373243) (xy 346.596019 -392.339712) (xy 346.591877 -392.30427)
			(xy 345.698572 -392.30427) (xy 345.698054 -392.322112) (xy 345.689825 -392.356833) (xy 345.673811 -392.38872)
			(xy 345.650874 -392.416055) (xy 345.622252 -392.437364) (xy 345.589487 -392.451497) (xy 345.554346 -392.457693)
			(xy 345.518723 -392.455619) (xy 345.484539 -392.445385) (xy 345.453637 -392.427543) (xy 345.427682 -392.403056)
			(xy 345.408073 -392.373243) (xy 345.395869 -392.339712) (xy 345.391727 -392.30427) (xy 344.498676 -392.30427)
			(xy 344.498158 -392.322112) (xy 344.489929 -392.356833) (xy 344.473915 -392.38872) (xy 344.450978 -392.416055)
			(xy 344.422356 -392.437364) (xy 344.389591 -392.451497) (xy 344.35445 -392.457693) (xy 344.318827 -392.455619)
			(xy 344.284643 -392.445385) (xy 344.253741 -392.427543) (xy 344.227786 -392.403056) (xy 344.208177 -392.373243)
			(xy 344.195973 -392.339712) (xy 344.191831 -392.30427) (xy 343.29878 -392.30427) (xy 343.298262 -392.322112)
			(xy 343.290033 -392.356833) (xy 343.274019 -392.38872) (xy 343.251082 -392.416055) (xy 343.22246 -392.437364)
			(xy 343.189695 -392.451497) (xy 343.154554 -392.457693) (xy 343.118931 -392.455619) (xy 343.084747 -392.445385)
			(xy 343.053845 -392.427543) (xy 343.02789 -392.403056) (xy 343.008281 -392.373243) (xy 342.996077 -392.339712)
			(xy 342.991935 -392.30427) (xy 342.09863 -392.30427) (xy 342.098112 -392.322112) (xy 342.089883 -392.356833)
			(xy 342.073869 -392.38872) (xy 342.050932 -392.416055) (xy 342.02231 -392.437364) (xy 341.989545 -392.451497)
			(xy 341.954404 -392.457693) (xy 341.918781 -392.455619) (xy 341.884597 -392.445385) (xy 341.853695 -392.427543)
			(xy 341.82774 -392.403056) (xy 341.808131 -392.373243) (xy 341.795927 -392.339712) (xy 341.791785 -392.30427)
			(xy 340.898734 -392.30427) (xy 340.898216 -392.322112) (xy 340.889987 -392.356833) (xy 340.873973 -392.38872)
			(xy 340.851036 -392.416055) (xy 340.822414 -392.437364) (xy 340.789649 -392.451497) (xy 340.754508 -392.457693)
			(xy 340.718885 -392.455619) (xy 340.684701 -392.445385) (xy 340.653799 -392.427543) (xy 340.627844 -392.403056)
			(xy 340.608235 -392.373243) (xy 340.596031 -392.339712) (xy 340.591889 -392.30427) (xy 339.698584 -392.30427)
			(xy 339.698066 -392.322112) (xy 339.689837 -392.356833) (xy 339.673823 -392.38872) (xy 339.650886 -392.416055)
			(xy 339.622264 -392.437364) (xy 339.589499 -392.451497) (xy 339.554358 -392.457693) (xy 339.518735 -392.455619)
			(xy 339.484551 -392.445385) (xy 339.453649 -392.427543) (xy 339.427694 -392.403056) (xy 339.408085 -392.373243)
			(xy 339.395881 -392.339712) (xy 339.391739 -392.30427) (xy 338.498688 -392.30427) (xy 338.49817 -392.322112)
			(xy 338.489941 -392.356833) (xy 338.473927 -392.38872) (xy 338.45099 -392.416055) (xy 338.422368 -392.437364)
			(xy 338.389603 -392.451497) (xy 338.354462 -392.457693) (xy 338.318839 -392.455619) (xy 338.284655 -392.445385)
			(xy 338.253753 -392.427543) (xy 338.227798 -392.403056) (xy 338.208189 -392.373243) (xy 338.195985 -392.339712)
			(xy 338.191843 -392.30427) (xy 337.298538 -392.30427) (xy 337.29802 -392.322112) (xy 337.289791 -392.356833)
			(xy 337.273777 -392.38872) (xy 337.25084 -392.416055) (xy 337.222218 -392.437364) (xy 337.189453 -392.451497)
			(xy 337.154312 -392.457693) (xy 337.118689 -392.455619) (xy 337.084505 -392.445385) (xy 337.053603 -392.427543)
			(xy 337.027648 -392.403056) (xy 337.008039 -392.373243) (xy 336.995835 -392.339712) (xy 336.991693 -392.30427)
			(xy 336.098642 -392.30427) (xy 336.098124 -392.322112) (xy 336.089895 -392.356833) (xy 336.073881 -392.38872)
			(xy 336.050944 -392.416055) (xy 336.022322 -392.437364) (xy 335.989557 -392.451497) (xy 335.954416 -392.457693)
			(xy 335.918793 -392.455619) (xy 335.884609 -392.445385) (xy 335.853707 -392.427543) (xy 335.827752 -392.403056)
			(xy 335.808143 -392.373243) (xy 335.795939 -392.339712) (xy 335.791797 -392.30427) (xy 321.570858 -392.30427)
			(xy 321.57034 -392.322112) (xy 321.562111 -392.356833) (xy 321.546097 -392.38872) (xy 321.52316 -392.416055)
			(xy 321.494538 -392.437364) (xy 321.461773 -392.451497) (xy 321.426632 -392.457693) (xy 321.391009 -392.455619)
			(xy 321.356825 -392.445385) (xy 321.325923 -392.427543) (xy 321.299968 -392.403056) (xy 321.280359 -392.373243)
			(xy 321.268155 -392.339712) (xy 321.264013 -392.30427) (xy 320.370962 -392.30427) (xy 320.370444 -392.322112)
			(xy 320.362215 -392.356833) (xy 320.346201 -392.38872) (xy 320.323264 -392.416055) (xy 320.294642 -392.437364)
			(xy 320.261877 -392.451497) (xy 320.226736 -392.457693) (xy 320.191113 -392.455619) (xy 320.156929 -392.445385)
			(xy 320.126027 -392.427543) (xy 320.100072 -392.403056) (xy 320.080463 -392.373243) (xy 320.068259 -392.339712)
			(xy 320.064117 -392.30427) (xy 319.170812 -392.30427) (xy 319.170294 -392.322112) (xy 319.162065 -392.356833)
			(xy 319.146051 -392.38872) (xy 319.123114 -392.416055) (xy 319.094492 -392.437364) (xy 319.061727 -392.451497)
			(xy 319.026586 -392.457693) (xy 318.990963 -392.455619) (xy 318.956779 -392.445385) (xy 318.925877 -392.427543)
			(xy 318.899922 -392.403056) (xy 318.880313 -392.373243) (xy 318.868109 -392.339712) (xy 318.863967 -392.30427)
			(xy 317.970916 -392.30427) (xy 317.970398 -392.322112) (xy 317.962169 -392.356833) (xy 317.946155 -392.38872)
			(xy 317.923218 -392.416055) (xy 317.894596 -392.437364) (xy 317.861831 -392.451497) (xy 317.82669 -392.457693)
			(xy 317.791067 -392.455619) (xy 317.756883 -392.445385) (xy 317.725981 -392.427543) (xy 317.700026 -392.403056)
			(xy 317.680417 -392.373243) (xy 317.668213 -392.339712) (xy 317.664071 -392.30427) (xy 316.77102 -392.30427)
			(xy 316.770502 -392.322112) (xy 316.762273 -392.356833) (xy 316.746259 -392.38872) (xy 316.723322 -392.416055)
			(xy 316.6947 -392.437364) (xy 316.661935 -392.451497) (xy 316.626794 -392.457693) (xy 316.591171 -392.455619)
			(xy 316.556987 -392.445385) (xy 316.526085 -392.427543) (xy 316.50013 -392.403056) (xy 316.480521 -392.373243)
			(xy 316.468317 -392.339712) (xy 316.464175 -392.30427) (xy 315.57087 -392.30427) (xy 315.570352 -392.322112)
			(xy 315.562123 -392.356833) (xy 315.546109 -392.38872) (xy 315.523172 -392.416055) (xy 315.49455 -392.437364)
			(xy 315.461785 -392.451497) (xy 315.426644 -392.457693) (xy 315.391021 -392.455619) (xy 315.356837 -392.445385)
			(xy 315.325935 -392.427543) (xy 315.29998 -392.403056) (xy 315.280371 -392.373243) (xy 315.268167 -392.339712)
			(xy 315.264025 -392.30427) (xy 314.370974 -392.30427) (xy 314.370456 -392.322112) (xy 314.362227 -392.356833)
			(xy 314.346213 -392.38872) (xy 314.323276 -392.416055) (xy 314.294654 -392.437364) (xy 314.261889 -392.451497)
			(xy 314.226748 -392.457693) (xy 314.191125 -392.455619) (xy 314.156941 -392.445385) (xy 314.126039 -392.427543)
			(xy 314.100084 -392.403056) (xy 314.080475 -392.373243) (xy 314.068271 -392.339712) (xy 314.064129 -392.30427)
			(xy 313.170824 -392.30427) (xy 313.170306 -392.322112) (xy 313.162077 -392.356833) (xy 313.146063 -392.38872)
			(xy 313.123126 -392.416055) (xy 313.094504 -392.437364) (xy 313.061739 -392.451497) (xy 313.026598 -392.457693)
			(xy 312.990975 -392.455619) (xy 312.956791 -392.445385) (xy 312.925889 -392.427543) (xy 312.899934 -392.403056)
			(xy 312.880325 -392.373243) (xy 312.868121 -392.339712) (xy 312.863979 -392.30427) (xy 311.970928 -392.30427)
			(xy 311.97041 -392.322112) (xy 311.962181 -392.356833) (xy 311.946167 -392.38872) (xy 311.92323 -392.416055)
			(xy 311.894608 -392.437364) (xy 311.861843 -392.451497) (xy 311.826702 -392.457693) (xy 311.791079 -392.455619)
			(xy 311.756895 -392.445385) (xy 311.725993 -392.427543) (xy 311.700038 -392.403056) (xy 311.680429 -392.373243)
			(xy 311.668225 -392.339712) (xy 311.664083 -392.30427) (xy 310.771032 -392.30427) (xy 310.770514 -392.322112)
			(xy 310.762285 -392.356833) (xy 310.746271 -392.38872) (xy 310.723334 -392.416055) (xy 310.694712 -392.437364)
			(xy 310.661947 -392.451497) (xy 310.626806 -392.457693) (xy 310.591183 -392.455619) (xy 310.556999 -392.445385)
			(xy 310.526097 -392.427543) (xy 310.500142 -392.403056) (xy 310.480533 -392.373243) (xy 310.468329 -392.339712)
			(xy 310.464187 -392.30427) (xy 309.570882 -392.30427) (xy 309.570364 -392.322112) (xy 309.562135 -392.356833)
			(xy 309.546121 -392.38872) (xy 309.523184 -392.416055) (xy 309.494562 -392.437364) (xy 309.461797 -392.451497)
			(xy 309.426656 -392.457693) (xy 309.391033 -392.455619) (xy 309.356849 -392.445385) (xy 309.325947 -392.427543)
			(xy 309.299992 -392.403056) (xy 309.280383 -392.373243) (xy 309.268179 -392.339712) (xy 309.264037 -392.30427)
			(xy 308.370986 -392.30427) (xy 308.370468 -392.322112) (xy 308.362239 -392.356833) (xy 308.346225 -392.38872)
			(xy 308.323288 -392.416055) (xy 308.294666 -392.437364) (xy 308.261901 -392.451497) (xy 308.22676 -392.457693)
			(xy 308.191137 -392.455619) (xy 308.156953 -392.445385) (xy 308.126051 -392.427543) (xy 308.100096 -392.403056)
			(xy 308.080487 -392.373243) (xy 308.068283 -392.339712) (xy 308.064141 -392.30427) (xy 307.170836 -392.30427)
			(xy 307.170318 -392.322112) (xy 307.162089 -392.356833) (xy 307.146075 -392.38872) (xy 307.123138 -392.416055)
			(xy 307.094516 -392.437364) (xy 307.061751 -392.451497) (xy 307.02661 -392.457693) (xy 306.990987 -392.455619)
			(xy 306.956803 -392.445385) (xy 306.925901 -392.427543) (xy 306.899946 -392.403056) (xy 306.880337 -392.373243)
			(xy 306.868133 -392.339712) (xy 306.863991 -392.30427) (xy 305.97094 -392.30427) (xy 305.970422 -392.322112)
			(xy 305.962193 -392.356833) (xy 305.946179 -392.38872) (xy 305.923242 -392.416055) (xy 305.89462 -392.437364)
			(xy 305.861855 -392.451497) (xy 305.826714 -392.457693) (xy 305.791091 -392.455619) (xy 305.756907 -392.445385)
			(xy 305.726005 -392.427543) (xy 305.70005 -392.403056) (xy 305.680441 -392.373243) (xy 305.668237 -392.339712)
			(xy 305.664095 -392.30427) (xy 304.77079 -392.30427) (xy 304.770272 -392.322112) (xy 304.762043 -392.356833)
			(xy 304.746029 -392.38872) (xy 304.723092 -392.416055) (xy 304.69447 -392.437364) (xy 304.661705 -392.451497)
			(xy 304.626564 -392.457693) (xy 304.590941 -392.455619) (xy 304.556757 -392.445385) (xy 304.525855 -392.427543)
			(xy 304.4999 -392.403056) (xy 304.480291 -392.373243) (xy 304.468087 -392.339712) (xy 304.463945 -392.30427)
			(xy 303.570894 -392.30427) (xy 303.570376 -392.322112) (xy 303.562147 -392.356833) (xy 303.546133 -392.38872)
			(xy 303.523196 -392.416055) (xy 303.494574 -392.437364) (xy 303.461809 -392.451497) (xy 303.426668 -392.457693)
			(xy 303.391045 -392.455619) (xy 303.356861 -392.445385) (xy 303.325959 -392.427543) (xy 303.300004 -392.403056)
			(xy 303.280395 -392.373243) (xy 303.268191 -392.339712) (xy 303.264049 -392.30427) (xy 281.204041 -392.30427)
			(xy 281.182426 -392.346726) (xy 281.153119 -392.387109) (xy 281.135836 -392.405108) (xy 280.810462 -392.730482)
			(xy 280.803632 -392.73789) (xy 280.795908 -392.756483) (xy 280.795476 -392.76655) (xy 280.795476 -393.110974)
			(xy 280.794938 -393.135921) (xy 280.787132 -393.185202) (xy 280.771724 -393.232658) (xy 280.749092 -393.277124)
			(xy 280.719792 -393.31751) (xy 280.702512 -393.33551) (xy 280.345622 -393.6924) (xy 303.079146 -393.6924)
			(xy 303.083331 -393.652578) (xy 303.095703 -393.614496) (xy 303.115722 -393.579818) (xy 303.142512 -393.55006)
			(xy 303.174903 -393.526521) (xy 303.211481 -393.51023) (xy 303.250646 -393.501899) (xy 303.270666 -393.501372)
			(xy 303.271174 -393.501372) (xy 303.292652 -393.501958) (xy 303.334516 -393.511584) (xy 303.373186 -393.530292)
			(xy 303.3903 -393.543282) (xy 303.390554 -393.543536) (xy 303.399047 -393.549655) (xy 303.419257 -393.555026)
			(xy 303.42967 -393.55395) (xy 303.514252 -393.541504) (xy 303.532286 -393.530074) (xy 303.538128 -393.521184)
			(xy 303.552512 -393.500919) (xy 303.586686 -393.464843) (xy 303.626243 -393.43477) (xy 303.670144 -393.411489)
			(xy 303.717231 -393.395615) (xy 303.766266 -393.387565) (xy 303.791112 -393.387072) (xy 303.815046 -393.38757)
			(xy 303.862329 -393.395022) (xy 303.907871 -393.409757) (xy 303.950558 -393.431416) (xy 303.989344 -393.459467)
			(xy 304.02328 -393.493224) (xy 304.051536 -393.531861) (xy 304.062892 -393.552934) (xy 304.0634 -393.55395)
			(xy 304.11039 -393.63523) (xy 304.115497 -393.643295) (xy 304.130391 -393.655215) (xy 304.1486 -393.660903)
			(xy 304.158142 -393.66063) (xy 304.249582 -393.653772) (xy 304.25896 -393.652618) (xy 304.276011 -393.644519)
			(xy 304.289014 -393.630835) (xy 304.293016 -393.622276) (xy 304.293016 -393.621768) (xy 304.300437 -393.604274)
			(xy 304.321197 -393.572451) (xy 304.347826 -393.545347) (xy 304.379277 -393.524026) (xy 304.414315 -393.509327)
			(xy 304.451564 -393.501826) (xy 304.470562 -393.501372) (xy 304.47107 -393.501372) (xy 304.492548 -393.50196)
			(xy 304.534412 -393.511586) (xy 304.573082 -393.530293) (xy 304.590196 -393.543282) (xy 304.59045 -393.543536)
			(xy 304.598944 -393.549653) (xy 304.619153 -393.555025) (xy 304.629566 -393.55395) (xy 304.714148 -393.541504)
			(xy 304.732182 -393.530074) (xy 304.738024 -393.521184) (xy 304.752411 -393.500921) (xy 304.786584 -393.464845)
			(xy 304.826141 -393.434771) (xy 304.870041 -393.411491) (xy 304.917128 -393.395616) (xy 304.966163 -393.387565)
			(xy 304.991008 -393.387072) (xy 305.014941 -393.387573) (xy 305.062224 -393.395024) (xy 305.107767 -393.409759)
			(xy 305.150453 -393.431417) (xy 305.189239 -393.459468) (xy 305.223176 -393.493224) (xy 305.251432 -393.531861)
			(xy 305.262788 -393.552934) (xy 305.263296 -393.55395) (xy 305.310286 -393.63523) (xy 305.315395 -393.643293)
			(xy 305.330288 -393.655213) (xy 305.348496 -393.660902) (xy 305.358038 -393.66063) (xy 305.449478 -393.653772)
			(xy 305.458856 -393.652615) (xy 305.475907 -393.644518) (xy 305.48891 -393.630834) (xy 305.492912 -393.622276)
			(xy 305.492912 -393.621768) (xy 305.500336 -393.604276) (xy 305.521096 -393.572453) (xy 305.547724 -393.545348)
			(xy 305.579175 -393.524028) (xy 305.614212 -393.509328) (xy 305.65146 -393.501827) (xy 305.670458 -393.501372)
			(xy 305.670966 -393.501372) (xy 305.692443 -393.501962) (xy 305.734308 -393.511587) (xy 305.772977 -393.530293)
			(xy 305.790092 -393.543282) (xy 305.790346 -393.543536) (xy 305.798842 -393.549651) (xy 305.819049 -393.555025)
			(xy 305.829462 -393.55395) (xy 305.914044 -393.541504) (xy 305.932078 -393.530074) (xy 305.93792 -393.521184)
			(xy 305.952309 -393.500922) (xy 305.986482 -393.464847) (xy 306.026038 -393.434773) (xy 306.069938 -393.411492)
			(xy 306.117025 -393.395617) (xy 306.166059 -393.387565) (xy 306.190904 -393.387072) (xy 306.191158 -393.387072)
			(xy 306.215093 -393.387532) (xy 306.262378 -393.394992) (xy 306.307921 -393.409734) (xy 306.350607 -393.431398)
			(xy 306.389393 -393.459455) (xy 306.423328 -393.493217) (xy 306.451583 -393.531859) (xy 306.462938 -393.552934)
			(xy 306.463446 -393.55395) (xy 306.510436 -393.63523) (xy 306.515579 -393.643269) (xy 306.530456 -393.655193)
			(xy 306.548651 -393.660893) (xy 306.558188 -393.66063) (xy 306.649628 -393.653772) (xy 306.659011 -393.652649)
			(xy 306.676063 -393.644535) (xy 306.689062 -393.630839) (xy 306.693062 -393.622276) (xy 306.693062 -393.621768)
			(xy 306.700526 -393.604295) (xy 306.721279 -393.572473) (xy 306.7479 -393.545369) (xy 306.779342 -393.524045)
			(xy 306.814372 -393.50934) (xy 306.851613 -393.501831) (xy 306.870608 -393.501372) (xy 306.871116 -393.501372)
			(xy 306.892595 -393.501936) (xy 306.93446 -393.511572) (xy 306.973129 -393.530288) (xy 306.990242 -393.543282)
			(xy 306.990496 -393.543536) (xy 306.999007 -393.549625) (xy 307.019203 -393.555015) (xy 307.029612 -393.55395)
			(xy 307.114194 -393.541504) (xy 307.132228 -393.530074) (xy 307.13807 -393.521184) (xy 307.152428 -393.500899)
			(xy 307.186607 -393.464825) (xy 307.22617 -393.434753) (xy 307.270075 -393.411476) (xy 307.317168 -393.395606)
			(xy 307.366207 -393.387561) (xy 307.391054 -393.387072) (xy 307.414989 -393.387536) (xy 307.462274 -393.394994)
			(xy 307.507817 -393.409736) (xy 307.550503 -393.4314) (xy 307.589289 -393.459456) (xy 307.623224 -393.493218)
			(xy 307.651479 -393.531859) (xy 307.662834 -393.552934) (xy 307.663342 -393.55395) (xy 307.710332 -393.63523)
			(xy 307.715478 -393.643267) (xy 307.730354 -393.655191) (xy 307.748547 -393.660892) (xy 307.758084 -393.66063)
			(xy 307.849524 -393.653772) (xy 307.858907 -393.652646) (xy 307.875958 -393.644534) (xy 307.888958 -393.630839)
			(xy 307.892958 -393.622276) (xy 307.892958 -393.621768) (xy 307.900425 -393.604296) (xy 307.921178 -393.572475)
			(xy 307.947798 -393.54537) (xy 307.979239 -393.524047) (xy 308.014268 -393.509341) (xy 308.051509 -393.501832)
			(xy 308.070504 -393.501372) (xy 308.071012 -393.501372) (xy 308.092491 -393.501938) (xy 308.134356 -393.511573)
			(xy 308.173025 -393.530288) (xy 308.190138 -393.543282) (xy 308.190392 -393.543536) (xy 308.198905 -393.549623)
			(xy 308.219099 -393.555014) (xy 308.229508 -393.55395) (xy 308.31409 -393.541504) (xy 308.332124 -393.530074)
			(xy 308.337966 -393.521184) (xy 308.352327 -393.500901) (xy 308.386505 -393.464826) (xy 308.426067 -393.434755)
			(xy 308.469972 -393.411477) (xy 308.517064 -393.395607) (xy 308.566103 -393.387562) (xy 308.59095 -393.387072)
			(xy 308.614885 -393.387539) (xy 308.662169 -393.394997) (xy 308.707712 -393.409738) (xy 308.750399 -393.431401)
			(xy 308.789184 -393.459457) (xy 308.82312 -393.493218) (xy 308.851375 -393.531859) (xy 308.86273 -393.552934)
			(xy 308.863238 -393.55395) (xy 308.910482 -393.635738) (xy 308.915616 -393.643765) (xy 308.930515 -393.655617)
			(xy 308.948712 -393.661209) (xy 308.958234 -393.660884) (xy 309.063898 -393.65301) (xy 309.08752 -393.635738)
			(xy 309.092854 -393.622022) (xy 309.100296 -393.604503) (xy 309.121071 -393.572613) (xy 309.147729 -393.54545)
			(xy 309.179224 -393.524082) (xy 309.214315 -393.509348) (xy 309.251624 -393.501829) (xy 309.270654 -393.501372)
			(xy 309.271162 -393.501372) (xy 309.292639 -393.501964) (xy 309.334504 -393.511588) (xy 309.373173 -393.530293)
			(xy 309.390288 -393.543282) (xy 309.390542 -393.543536) (xy 309.399039 -393.549649) (xy 309.419246 -393.555024)
			(xy 309.429658 -393.55395) (xy 309.51424 -393.541504) (xy 309.532274 -393.530074) (xy 309.538116 -393.521184)
			(xy 309.552445 -393.500878) (xy 309.58663 -393.464804) (xy 309.626199 -393.434734) (xy 309.67011 -393.411461)
			(xy 309.717208 -393.395596) (xy 309.766251 -393.387558) (xy 309.7911 -393.387072) (xy 309.815033 -393.38758)
			(xy 309.862316 -393.39503) (xy 309.907858 -393.409764) (xy 309.950544 -393.43142) (xy 309.989331 -393.45947)
			(xy 310.023268 -393.493226) (xy 310.051524 -393.531862) (xy 310.06288 -393.552934) (xy 310.063388 -393.55395)
			(xy 310.110378 -393.63523) (xy 310.115493 -393.643289) (xy 310.130383 -393.65521) (xy 310.148589 -393.660901)
			(xy 310.15813 -393.66063) (xy 310.24957 -393.653772) (xy 310.258947 -393.65261) (xy 310.275998 -393.644515)
			(xy 310.289001 -393.630833) (xy 310.293004 -393.622276) (xy 310.293004 -393.621768) (xy 310.300434 -393.604279)
			(xy 310.321193 -393.572456) (xy 310.34782 -393.545352) (xy 310.379269 -393.524031) (xy 310.414305 -393.50933)
			(xy 310.451553 -393.501828) (xy 310.47055 -393.501372) (xy 310.471058 -393.501372) (xy 310.492535 -393.501966)
			(xy 310.534399 -393.511589) (xy 310.573069 -393.530294) (xy 310.590184 -393.543282) (xy 310.590438 -393.543536)
			(xy 310.598936 -393.549647) (xy 310.619142 -393.555023) (xy 310.629554 -393.55395) (xy 310.714136 -393.541504)
			(xy 310.73217 -393.530074) (xy 310.738012 -393.521184) (xy 310.752344 -393.500879) (xy 310.786528 -393.464806)
			(xy 310.826096 -393.434736) (xy 310.870007 -393.411462) (xy 310.917104 -393.395597) (xy 310.966147 -393.387558)
			(xy 310.990996 -393.387072) (xy 311.014932 -393.387502) (xy 311.062218 -393.394966) (xy 311.107762 -393.409714)
			(xy 311.150449 -393.431384) (xy 311.189234 -393.459445) (xy 311.223168 -393.493212) (xy 311.251422 -393.531857)
			(xy 311.262776 -393.552934) (xy 311.263284 -393.55395) (xy 311.310274 -393.63523) (xy 311.315391 -393.643288)
			(xy 311.330281 -393.655208) (xy 311.348485 -393.6609) (xy 311.358026 -393.66063) (xy 311.449466 -393.653772)
			(xy 311.458842 -393.652607) (xy 311.475894 -393.644514) (xy 311.488897 -393.630833) (xy 311.4929 -393.622276)
			(xy 311.4929 -393.621768) (xy 311.500334 -393.60428) (xy 311.521092 -393.572457) (xy 311.547718 -393.545353)
			(xy 311.579167 -393.524032) (xy 311.614202 -393.509331) (xy 311.651449 -393.501828) (xy 311.670446 -393.501372)
			(xy 311.670954 -393.501372) (xy 311.692431 -393.501968) (xy 311.734295 -393.51159) (xy 311.772965 -393.530294)
			(xy 311.79008 -393.543282) (xy 311.790334 -393.543536) (xy 311.798833 -393.549645) (xy 311.819038 -393.555022)
			(xy 311.82945 -393.55395) (xy 311.914032 -393.541504) (xy 311.932066 -393.530074) (xy 311.937908 -393.521184)
			(xy 311.952242 -393.500881) (xy 311.986426 -393.464808) (xy 312.025994 -393.434738) (xy 312.069904 -393.411463)
			(xy 312.117001 -393.395598) (xy 312.166043 -393.387558) (xy 312.190892 -393.387072) (xy 312.191146 -393.387072)
			(xy 312.215081 -393.387542) (xy 312.262365 -393.394999) (xy 312.307908 -393.40974) (xy 312.350594 -393.431403)
			(xy 312.38938 -393.459458) (xy 312.423316 -393.493219) (xy 312.451571 -393.531859) (xy 312.462926 -393.552934)
			(xy 312.463434 -393.55395) (xy 312.510424 -393.63523) (xy 312.515575 -393.643263) (xy 312.530449 -393.655188)
			(xy 312.54864 -393.660891) (xy 312.558176 -393.66063) (xy 312.649616 -393.653772) (xy 312.658998 -393.652641)
			(xy 312.676049 -393.644531) (xy 312.68905 -393.630838) (xy 312.69305 -393.622276) (xy 312.69305 -393.621768)
			(xy 312.700524 -393.604299) (xy 312.721276 -393.572478) (xy 312.747894 -393.545374) (xy 312.779334 -393.52405)
			(xy 312.814362 -393.509343) (xy 312.851601 -393.501833) (xy 312.870596 -393.501372) (xy 312.871104 -393.501372)
			(xy 312.892583 -393.501942) (xy 312.934448 -393.511575) (xy 312.973117 -393.530289) (xy 312.99023 -393.543282)
			(xy 312.990484 -393.543536) (xy 312.998999 -393.549619) (xy 313.019191 -393.555012) (xy 313.0296 -393.55395)
			(xy 313.114182 -393.541504) (xy 313.132216 -393.530074) (xy 313.138058 -393.521184) (xy 313.152424 -393.500905)
			(xy 313.186601 -393.46483) (xy 313.226162 -393.434758) (xy 313.270066 -393.41148) (xy 313.317157 -393.395609)
			(xy 313.366195 -393.387562) (xy 313.391042 -393.387072) (xy 313.391296 -393.387072) (xy 313.415232 -393.387502)
			(xy 313.462518 -393.394966) (xy 313.508062 -393.409714) (xy 313.550749 -393.431384) (xy 313.589534 -393.459445)
			(xy 313.623468 -393.493212) (xy 313.651722 -393.531857) (xy 313.663076 -393.552934) (xy 313.663584 -393.55395)
			(xy 313.710574 -393.63523) (xy 313.715715 -393.643251) (xy 313.73061 -393.655105) (xy 313.748805 -393.6607)
			(xy 313.758326 -393.660376) (xy 313.849512 -393.653518) (xy 313.858899 -393.652415) (xy 313.875954 -393.644297)
			(xy 313.888951 -393.63059) (xy 313.892946 -393.622022) (xy 313.892946 -393.621768) (xy 313.900343 -393.604263)
			(xy 313.921107 -393.572439) (xy 313.947741 -393.545335) (xy 313.979197 -393.524016) (xy 314.014239 -393.50932)
			(xy 314.051492 -393.501824) (xy 314.070492 -393.501372) (xy 314.071 -393.501372) (xy 314.092479 -393.501944)
			(xy 314.134344 -393.511576) (xy 314.173013 -393.530289) (xy 314.190126 -393.543282) (xy 314.19038 -393.543536)
			(xy 314.198896 -393.549617) (xy 314.219088 -393.555011) (xy 314.229496 -393.55395) (xy 314.314078 -393.541504)
			(xy 314.332112 -393.530074) (xy 314.337954 -393.521184) (xy 314.352322 -393.500907) (xy 314.386499 -393.464832)
			(xy 314.42606 -393.434759) (xy 314.469963 -393.411481) (xy 314.517054 -393.395609) (xy 314.566091 -393.387563)
			(xy 314.590938 -393.387072) (xy 314.591192 -393.387072) (xy 314.615128 -393.387505) (xy 314.662414 -393.394969)
			(xy 314.707958 -393.409716) (xy 314.750644 -393.431385) (xy 314.78943 -393.459446) (xy 314.823364 -393.493212)
			(xy 314.851618 -393.531857) (xy 314.862972 -393.552934) (xy 314.86348 -393.55395) (xy 314.91047 -393.63523)
			(xy 314.91559 -393.643286) (xy 314.930478 -393.655207) (xy 314.948681 -393.660899) (xy 314.958222 -393.66063)
			(xy 315.049662 -393.653772) (xy 315.059038 -393.652605) (xy 315.076089 -393.644513) (xy 315.089093 -393.630833)
			(xy 315.093096 -393.622276) (xy 315.093096 -393.621768) (xy 315.100533 -393.604282) (xy 315.121291 -393.572459)
			(xy 315.147916 -393.545355) (xy 315.179364 -393.524033) (xy 315.214399 -393.509332) (xy 315.251645 -393.501828)
			(xy 315.270642 -393.501372) (xy 315.27115 -393.501372) (xy 315.292627 -393.50197) (xy 315.334491 -393.511591)
			(xy 315.373161 -393.530294) (xy 315.390276 -393.543282) (xy 315.39053 -393.543536) (xy 315.399031 -393.549642)
			(xy 315.419234 -393.555021) (xy 315.429646 -393.55395) (xy 315.514228 -393.541504) (xy 315.532262 -393.530074)
			(xy 315.538104 -393.521184) (xy 315.552441 -393.500883) (xy 315.586624 -393.464809) (xy 315.626191 -393.434739)
			(xy 315.670101 -393.411465) (xy 315.717197 -393.395599) (xy 315.76624 -393.387559) (xy 315.791088 -393.387072)
			(xy 315.815024 -393.387508) (xy 315.86231 -393.394972) (xy 315.907853 -393.409718) (xy 315.95054 -393.431387)
			(xy 315.989325 -393.459447) (xy 316.02326 -393.493213) (xy 316.051514 -393.531858) (xy 316.062868 -393.552934)
			(xy 316.063376 -393.55395) (xy 316.110366 -393.63523) (xy 316.115489 -393.643284) (xy 316.130376 -393.655205)
			(xy 316.148578 -393.660898) (xy 316.158118 -393.66063) (xy 316.249558 -393.653772) (xy 316.258933 -393.652602)
			(xy 316.275985 -393.644511) (xy 316.288989 -393.630832) (xy 316.292992 -393.622276) (xy 316.292992 -393.621768)
			(xy 316.300432 -393.604283) (xy 316.321189 -393.572461) (xy 316.347814 -393.545356) (xy 316.379262 -393.524035)
			(xy 316.414296 -393.509333) (xy 316.451541 -393.501829) (xy 316.470538 -393.501372) (xy 316.471046 -393.501372)
			(xy 316.492523 -393.501972) (xy 316.534387 -393.511593) (xy 316.573057 -393.530295) (xy 316.590172 -393.543282)
			(xy 316.590426 -393.543536) (xy 316.598928 -393.54964) (xy 316.619131 -393.555021) (xy 316.629542 -393.55395)
			(xy 316.714124 -393.541504) (xy 316.732158 -393.530074) (xy 316.738 -393.521184) (xy 316.752339 -393.500885)
			(xy 316.786522 -393.464811) (xy 316.826089 -393.434741) (xy 316.869998 -393.411466) (xy 316.917094 -393.395599)
			(xy 316.966136 -393.387559) (xy 316.990984 -393.387072) (xy 316.991238 -393.387072) (xy 317.015172 -393.387549)
			(xy 317.062456 -393.395005) (xy 317.107999 -393.409744) (xy 317.150686 -393.431406) (xy 317.189472 -393.45946)
			(xy 317.223407 -393.49322) (xy 317.251663 -393.53186) (xy 317.263018 -393.552934) (xy 317.263526 -393.55395)
			(xy 317.310516 -393.63523) (xy 317.315629 -393.643272) (xy 317.330537 -393.655122) (xy 317.348744 -393.660707)
			(xy 317.358268 -393.660376) (xy 317.449454 -393.653518) (xy 317.458835 -393.652376) (xy 317.47589 -393.644277)
			(xy 317.48889 -393.630585) (xy 317.492888 -393.622022) (xy 317.492888 -393.621768) (xy 317.500331 -393.604285)
			(xy 317.521088 -393.572462) (xy 317.547713 -393.545358) (xy 317.579159 -393.524036) (xy 317.614193 -393.509334)
			(xy 317.651437 -393.501829) (xy 317.670434 -393.501372) (xy 317.670688 -393.501372) (xy 317.692264 -393.501956)
			(xy 317.734318 -393.511636) (xy 317.773147 -393.530464) (xy 317.790322 -393.543536) (xy 317.798704 -393.550394)
			(xy 317.81877 -393.555728) (xy 317.914274 -393.541504) (xy 317.932308 -393.530074) (xy 317.93815 -393.521184)
			(xy 317.952521 -393.500908) (xy 317.986697 -393.464834) (xy 318.026257 -393.434761) (xy 318.07016 -393.411482)
			(xy 318.11725 -393.39561) (xy 318.166288 -393.387563) (xy 318.191134 -393.387072) (xy 318.215068 -393.387552)
			(xy 318.262352 -393.395007) (xy 318.307895 -393.409746) (xy 318.350581 -393.431407) (xy 318.389367 -393.459461)
			(xy 318.423303 -393.493221) (xy 318.451559 -393.53186) (xy 318.462914 -393.552934) (xy 318.463422 -393.55395)
			(xy 318.510412 -393.63523) (xy 318.515504 -393.643306) (xy 318.530405 -393.655224) (xy 318.54862 -393.660907)
			(xy 318.558164 -393.66063) (xy 318.649604 -393.653772) (xy 318.658984 -393.652633) (xy 318.676036 -393.644527)
			(xy 318.689037 -393.630837) (xy 318.693038 -393.622276) (xy 318.693038 -393.621768) (xy 318.700441 -393.604266)
			(xy 318.721205 -393.572442) (xy 318.747837 -393.545338) (xy 318.779292 -393.524019) (xy 318.814333 -393.509322)
			(xy 318.851585 -393.501824) (xy 318.870584 -393.501372) (xy 318.871092 -393.501372) (xy 318.89257 -393.501948)
			(xy 318.934435 -393.511579) (xy 318.973104 -393.53029) (xy 318.990218 -393.543282) (xy 318.990472 -393.543536)
			(xy 318.998959 -393.549664) (xy 319.019174 -393.55503) (xy 319.029588 -393.55395) (xy 319.11417 -393.541504)
			(xy 319.132204 -393.530074) (xy 319.138046 -393.521184) (xy 319.152419 -393.50091) (xy 319.186595 -393.464835)
			(xy 319.226155 -393.434763) (xy 319.270057 -393.411483) (xy 319.317147 -393.395611) (xy 319.366184 -393.387563)
			(xy 319.39103 -393.387072) (xy 319.391284 -393.387072) (xy 319.41522 -393.387511) (xy 319.462506 -393.394974)
			(xy 319.508049 -393.40972) (xy 319.550736 -393.431388) (xy 319.589521 -393.459448) (xy 319.623456 -393.493214)
			(xy 319.65171 -393.531858) (xy 319.663064 -393.552934) (xy 319.663572 -393.55395) (xy 319.710562 -393.63523)
			(xy 319.715712 -393.643245) (xy 319.730603 -393.6551) (xy 319.748794 -393.660698) (xy 319.758314 -393.660376)
			(xy 319.8495 -393.653518) (xy 319.858886 -393.652407) (xy 319.875941 -393.644293) (xy 319.888938 -393.630589)
			(xy 319.892934 -393.622022) (xy 319.892934 -393.621768) (xy 319.90034 -393.604267) (xy 319.921103 -393.572443)
			(xy 319.947735 -393.545339) (xy 319.979189 -393.52402) (xy 320.01423 -393.509323) (xy 320.051481 -393.501825)
			(xy 320.07048 -393.501372) (xy 320.070734 -393.501372) (xy 320.092311 -393.501932) (xy 320.134366 -393.511622)
			(xy 320.173194 -393.53046) (xy 320.190368 -393.543536) (xy 320.19875 -393.550394) (xy 320.218816 -393.555728)
			(xy 320.31432 -393.541504) (xy 320.332354 -393.530074) (xy 320.338196 -393.521184) (xy 320.352538 -393.500887)
			(xy 320.38672 -393.464813) (xy 320.426286 -393.434743) (xy 320.470195 -393.411467) (xy 320.51729 -393.3956)
			(xy 320.566332 -393.387559) (xy 320.59118 -393.387072) (xy 320.615116 -393.387515) (xy 320.662401 -393.394977)
			(xy 320.707945 -393.409722) (xy 320.750631 -393.43139) (xy 320.789417 -393.459449) (xy 320.823352 -393.493214)
			(xy 320.851606 -393.531858) (xy 320.86296 -393.552934) (xy 320.863468 -393.55395) (xy 320.910458 -393.63523)
			(xy 320.91561 -393.643243) (xy 320.9305 -393.655098) (xy 320.948691 -393.660697) (xy 320.95821 -393.660376)
			(xy 321.049396 -393.653518) (xy 321.058782 -393.652404) (xy 321.075837 -393.644291) (xy 321.088834 -393.630589)
			(xy 321.09283 -393.622022) (xy 321.09283 -393.621768) (xy 321.10024 -393.604269) (xy 321.121002 -393.572445)
			(xy 321.147633 -393.545341) (xy 321.179086 -393.524021) (xy 321.214126 -393.509324) (xy 321.251377 -393.501825)
			(xy 321.270376 -393.501372) (xy 321.27063 -393.501372) (xy 321.292207 -393.501934) (xy 321.334262 -393.511623)
			(xy 321.37309 -393.53046) (xy 321.390264 -393.543536) (xy 321.398646 -393.550394) (xy 321.418712 -393.555728)
			(xy 321.514216 -393.541504) (xy 321.53225 -393.530074) (xy 321.538092 -393.521184) (xy 321.552436 -393.500889)
			(xy 321.586618 -393.464815) (xy 321.626184 -393.434744) (xy 321.670092 -393.411469) (xy 321.717187 -393.395601)
			(xy 321.766228 -393.38756) (xy 321.791076 -393.387072) (xy 321.815011 -393.387518) (xy 321.862297 -393.39498)
			(xy 321.90784 -393.409724) (xy 321.950527 -393.431391) (xy 321.989312 -393.45945) (xy 322.023247 -393.493215)
			(xy 322.051501 -393.531858) (xy 322.062856 -393.552934) (xy 322.063364 -393.55395) (xy 322.143388 -393.6924)
			(xy 335.606809 -393.6924) (xy 335.610996 -393.652564) (xy 335.623374 -393.614469) (xy 335.643403 -393.579781)
			(xy 335.670206 -393.550015) (xy 335.702613 -393.526473) (xy 335.739206 -393.510183) (xy 335.778386 -393.501857)
			(xy 335.798414 -393.501372) (xy 335.798922 -393.501372) (xy 335.820401 -393.501933) (xy 335.862267 -393.51157)
			(xy 335.900935 -393.530287) (xy 335.918048 -393.543282) (xy 335.918302 -393.543536) (xy 335.926811 -393.549628)
			(xy 335.947008 -393.555016) (xy 335.957418 -393.55395) (xy 336.042 -393.541504) (xy 336.060034 -393.530074)
			(xy 336.065876 -393.521184) (xy 336.08023 -393.500896) (xy 336.11441 -393.464822) (xy 336.153973 -393.434751)
			(xy 336.19788 -393.411474) (xy 336.244973 -393.395605) (xy 336.294013 -393.387561) (xy 336.31886 -393.387072)
			(xy 336.342795 -393.387531) (xy 336.39008 -393.39499) (xy 336.435623 -393.409733) (xy 336.47831 -393.431398)
			(xy 336.517095 -393.459455) (xy 336.551031 -393.493217) (xy 336.579285 -393.531859) (xy 336.59064 -393.552934)
			(xy 336.591148 -393.55395) (xy 336.638138 -393.63523) (xy 336.64328 -393.64327) (xy 336.658158 -393.655193)
			(xy 336.676352 -393.660893) (xy 336.68589 -393.66063) (xy 336.77733 -393.653772) (xy 336.786713 -393.65265)
			(xy 336.803765 -393.644536) (xy 336.816764 -393.630839) (xy 336.820764 -393.622276) (xy 336.820764 -393.621768)
			(xy 336.828227 -393.604294) (xy 336.84898 -393.572472) (xy 336.875601 -393.545368) (xy 336.907043 -393.524045)
			(xy 336.942073 -393.50934) (xy 336.979315 -393.501831) (xy 336.99831 -393.501372) (xy 336.998818 -393.501372)
			(xy 337.020297 -393.501935) (xy 337.062163 -393.511571) (xy 337.100831 -393.530288) (xy 337.117944 -393.543282)
			(xy 337.118198 -393.543536) (xy 337.126709 -393.549626) (xy 337.146904 -393.555015) (xy 337.157314 -393.55395)
			(xy 337.241896 -393.541504) (xy 337.25993 -393.530074) (xy 337.265772 -393.521184) (xy 337.280129 -393.500898)
			(xy 337.314308 -393.464824) (xy 337.353871 -393.434752) (xy 337.397777 -393.411475) (xy 337.44487 -393.395605)
			(xy 337.493909 -393.387561) (xy 337.518756 -393.387072) (xy 337.542691 -393.387534) (xy 337.589976 -393.394993)
			(xy 337.635519 -393.409735) (xy 337.678205 -393.431399) (xy 337.716991 -393.459456) (xy 337.750926 -393.493218)
			(xy 337.779181 -393.531859) (xy 337.790536 -393.552934) (xy 337.791044 -393.55395) (xy 337.838034 -393.63523)
			(xy 337.843178 -393.643268) (xy 337.858055 -393.655192) (xy 337.876249 -393.660893) (xy 337.885786 -393.66063)
			(xy 337.977226 -393.653772) (xy 337.986609 -393.652648) (xy 338.00366 -393.644535) (xy 338.01666 -393.630839)
			(xy 338.02066 -393.622276) (xy 338.02066 -393.621768) (xy 338.028126 -393.604295) (xy 338.048879 -393.572474)
			(xy 338.075499 -393.545369) (xy 338.106941 -393.524046) (xy 338.14197 -393.509341) (xy 338.179211 -393.501832)
			(xy 338.198206 -393.501372) (xy 338.198714 -393.501372) (xy 338.220193 -393.501937) (xy 338.262058 -393.511572)
			(xy 338.300727 -393.530288) (xy 338.31784 -393.543282) (xy 338.318094 -393.543536) (xy 338.326606 -393.549624)
			(xy 338.346801 -393.555014) (xy 338.35721 -393.55395) (xy 338.441792 -393.541504) (xy 338.459826 -393.530074)
			(xy 338.465668 -393.521184) (xy 338.480027 -393.5009) (xy 338.514206 -393.464826) (xy 338.553768 -393.434754)
			(xy 338.597674 -393.411476) (xy 338.644766 -393.395606) (xy 338.693805 -393.387562) (xy 338.718652 -393.387072)
			(xy 338.718906 -393.387072) (xy 338.742839 -393.387575) (xy 338.790122 -393.395026) (xy 338.835664 -393.40976)
			(xy 338.878351 -393.431418) (xy 338.917137 -393.459468) (xy 338.951074 -393.493225) (xy 338.97933 -393.531861)
			(xy 338.990686 -393.552934) (xy 338.991194 -393.55395) (xy 339.038184 -393.63523) (xy 339.043295 -393.643292)
			(xy 339.058187 -393.655213) (xy 339.076394 -393.660902) (xy 339.085936 -393.66063) (xy 339.177376 -393.653772)
			(xy 339.186753 -393.652614) (xy 339.203805 -393.644517) (xy 339.216808 -393.630834) (xy 339.22081 -393.622276)
			(xy 339.22081 -393.621768) (xy 339.228236 -393.604276) (xy 339.248995 -393.572453) (xy 339.275623 -393.545349)
			(xy 339.307073 -393.524028) (xy 339.34211 -393.509329) (xy 339.379358 -393.501827) (xy 339.398356 -393.501372)
			(xy 339.398864 -393.501372) (xy 339.420341 -393.501963) (xy 339.462206 -393.511587) (xy 339.500875 -393.530293)
			(xy 339.51799 -393.543282) (xy 339.518244 -393.543536) (xy 339.52674 -393.54965) (xy 339.546948 -393.555024)
			(xy 339.55736 -393.55395) (xy 339.641942 -393.541504) (xy 339.659976 -393.530074) (xy 339.665818 -393.521184)
			(xy 339.680146 -393.500877) (xy 339.714331 -393.464803) (xy 339.7539 -393.434734) (xy 339.797812 -393.41146)
			(xy 339.844909 -393.395596) (xy 339.893953 -393.387558) (xy 339.918802 -393.387072) (xy 339.942735 -393.387578)
			(xy 339.990018 -393.395028) (xy 340.03556 -393.409763) (xy 340.078247 -393.43142) (xy 340.117033 -393.459469)
			(xy 340.15097 -393.493225) (xy 340.179226 -393.531861) (xy 340.190582 -393.552934) (xy 340.19109 -393.55395)
			(xy 340.23808 -393.63523) (xy 340.243193 -393.64329) (xy 340.258084 -393.655211) (xy 340.276291 -393.660901)
			(xy 340.285832 -393.66063) (xy 340.377272 -393.653772) (xy 340.386649 -393.652611) (xy 340.4037 -393.644516)
			(xy 340.416703 -393.630834) (xy 340.420706 -393.622276) (xy 340.420706 -393.621768) (xy 340.428135 -393.604278)
			(xy 340.448894 -393.572455) (xy 340.475521 -393.545351) (xy 340.506971 -393.52403) (xy 340.542007 -393.50933)
			(xy 340.579254 -393.501827) (xy 340.598252 -393.501372) (xy 340.59876 -393.501372) (xy 340.620237 -393.501965)
			(xy 340.662102 -393.511589) (xy 340.700771 -393.530293) (xy 340.717886 -393.543282) (xy 340.71814 -393.543536)
			(xy 340.726637 -393.549648) (xy 340.746844 -393.555023) (xy 340.757256 -393.55395) (xy 340.841838 -393.541504)
			(xy 340.859872 -393.530074) (xy 340.865714 -393.521184) (xy 340.880045 -393.500879) (xy 340.914229 -393.464805)
			(xy 340.953797 -393.434735) (xy 340.997709 -393.411462) (xy 341.044806 -393.395596) (xy 341.093849 -393.387558)
			(xy 341.118698 -393.387072) (xy 341.142634 -393.3875) (xy 341.189921 -393.394965) (xy 341.235464 -393.409713)
			(xy 341.278151 -393.431383) (xy 341.316936 -393.459445) (xy 341.35087 -393.493212) (xy 341.379124 -393.531857)
			(xy 341.390478 -393.552934) (xy 341.390986 -393.55395) (xy 341.43823 -393.635738) (xy 341.443332 -393.643789)
			(xy 341.458245 -393.655637) (xy 341.476456 -393.661218) (xy 341.485982 -393.660884) (xy 341.591646 -393.65301)
			(xy 341.615268 -393.635738) (xy 341.620602 -393.622022) (xy 341.628006 -393.604485) (xy 341.648786 -393.572593)
			(xy 341.675452 -393.545431) (xy 341.706955 -393.524065) (xy 341.742054 -393.509336) (xy 341.77937 -393.501824)
			(xy 341.798402 -393.501372) (xy 341.79891 -393.501372) (xy 341.820389 -393.501939) (xy 341.862254 -393.511573)
			(xy 341.900923 -393.530288) (xy 341.918036 -393.543282) (xy 341.91829 -393.543536) (xy 341.926803 -393.549622)
			(xy 341.946997 -393.555013) (xy 341.957406 -393.55395) (xy 342.041988 -393.541504) (xy 342.060022 -393.530074)
			(xy 342.065864 -393.521184) (xy 342.080226 -393.500902) (xy 342.114404 -393.464827) (xy 342.153966 -393.434755)
			(xy 342.197871 -393.411478) (xy 342.244963 -393.395607) (xy 342.294001 -393.387562) (xy 342.318848 -393.387072)
			(xy 342.342783 -393.387541) (xy 342.390067 -393.394998) (xy 342.43561 -393.409739) (xy 342.478297 -393.431402)
			(xy 342.517082 -393.459458) (xy 342.551018 -393.493219) (xy 342.579273 -393.531859) (xy 342.590628 -393.552934)
			(xy 342.591136 -393.55395) (xy 342.638126 -393.63523) (xy 342.643276 -393.643264) (xy 342.65815 -393.655189)
			(xy 342.676341 -393.660891) (xy 342.685878 -393.66063) (xy 342.777318 -393.653772) (xy 342.7867 -393.652642)
			(xy 342.803751 -393.644532) (xy 342.816752 -393.630838) (xy 342.820752 -393.622276) (xy 342.820752 -393.621768)
			(xy 342.828224 -393.604298) (xy 342.848976 -393.572477) (xy 342.875595 -393.545373) (xy 342.907036 -393.524049)
			(xy 342.942063 -393.509343) (xy 342.979303 -393.501832) (xy 342.998298 -393.501372) (xy 342.998806 -393.501372)
			(xy 343.020285 -393.501941) (xy 343.06215 -393.511575) (xy 343.100819 -393.530289) (xy 343.117932 -393.543282)
			(xy 343.118186 -393.543536) (xy 343.1267 -393.54962) (xy 343.146893 -393.555013) (xy 343.157302 -393.55395)
			(xy 343.241884 -393.541504) (xy 343.259918 -393.530074) (xy 343.26576 -393.521184) (xy 343.280124 -393.500904)
			(xy 343.314302 -393.464829) (xy 343.353863 -393.434757) (xy 343.397768 -393.411479) (xy 343.444859 -393.395608)
			(xy 343.493897 -393.387562) (xy 343.518744 -393.387072) (xy 343.542678 -393.387544) (xy 343.589963 -393.395001)
			(xy 343.635506 -393.409741) (xy 343.678192 -393.431404) (xy 343.716978 -393.459459) (xy 343.750914 -393.493219)
			(xy 343.779169 -393.53186) (xy 343.790524 -393.552934) (xy 343.791032 -393.55395) (xy 343.838022 -393.63523)
			(xy 343.843174 -393.643262) (xy 343.858048 -393.655187) (xy 343.876238 -393.660891) (xy 343.885774 -393.66063)
			(xy 343.977214 -393.653772) (xy 343.986595 -393.652639) (xy 344.003647 -393.64453) (xy 344.016647 -393.630838)
			(xy 344.020648 -393.622276) (xy 344.020648 -393.621768) (xy 344.028043 -393.604262) (xy 344.048808 -393.572438)
			(xy 344.075442 -393.545334) (xy 344.106898 -393.524015) (xy 344.141941 -393.509319) (xy 344.179194 -393.501823)
			(xy 344.198194 -393.501372) (xy 344.198702 -393.501372) (xy 344.220181 -393.501943) (xy 344.262046 -393.511576)
			(xy 344.300715 -393.530289) (xy 344.317828 -393.543282) (xy 344.318082 -393.543536) (xy 344.326598 -393.549618)
			(xy 344.346789 -393.555012) (xy 344.357198 -393.55395) (xy 344.44178 -393.541504) (xy 344.459814 -393.530074)
			(xy 344.465656 -393.521184) (xy 344.480023 -393.500906) (xy 344.5142 -393.464831) (xy 344.553761 -393.434759)
			(xy 344.597665 -393.41148) (xy 344.644756 -393.395609) (xy 344.693793 -393.387562) (xy 344.71864 -393.387072)
			(xy 344.718894 -393.387072) (xy 344.74283 -393.387503) (xy 344.790116 -393.394968) (xy 344.83566 -393.409715)
			(xy 344.878347 -393.431385) (xy 344.917132 -393.459446) (xy 344.951066 -393.493212) (xy 344.97932 -393.531857)
			(xy 344.990674 -393.552934) (xy 344.991182 -393.55395) (xy 345.038172 -393.63523) (xy 345.043291 -393.643287)
			(xy 345.058179 -393.655208) (xy 345.076383 -393.660899) (xy 345.085924 -393.66063) (xy 345.177364 -393.653772)
			(xy 345.18674 -393.652606) (xy 345.203791 -393.644513) (xy 345.216795 -393.630833) (xy 345.220798 -393.622276)
			(xy 345.220798 -393.621768) (xy 345.228233 -393.604281) (xy 345.248991 -393.572458) (xy 345.275617 -393.545354)
			(xy 345.307065 -393.524033) (xy 345.342101 -393.509332) (xy 345.379347 -393.501828) (xy 345.398344 -393.501372)
			(xy 345.398852 -393.501372) (xy 345.420329 -393.501969) (xy 345.462193 -393.511591) (xy 345.500863 -393.530294)
			(xy 345.517978 -393.543282) (xy 345.518232 -393.543536) (xy 345.526732 -393.549644) (xy 345.546936 -393.555022)
			(xy 345.557348 -393.55395) (xy 345.64193 -393.541504) (xy 345.659964 -393.530074) (xy 345.665806 -393.521184)
			(xy 345.680142 -393.500882) (xy 345.714325 -393.464808) (xy 345.753892 -393.434738) (xy 345.797803 -393.411464)
			(xy 345.844899 -393.395598) (xy 345.893941 -393.387559) (xy 345.91879 -393.387072) (xy 345.942726 -393.387506)
			(xy 345.990012 -393.39497) (xy 346.035556 -393.409717) (xy 346.078242 -393.431386) (xy 346.117027 -393.459447)
			(xy 346.150962 -393.493213) (xy 346.179216 -393.531857) (xy 346.19057 -393.552934) (xy 346.191078 -393.55395)
			(xy 346.238068 -393.63523) (xy 346.243189 -393.643285) (xy 346.258077 -393.655206) (xy 346.27628 -393.660899)
			(xy 346.28582 -393.66063) (xy 346.37726 -393.653772) (xy 346.386636 -393.652604) (xy 346.403687 -393.644512)
			(xy 346.416691 -393.630832) (xy 346.420694 -393.622276) (xy 346.420694 -393.621768) (xy 346.428133 -393.604283)
			(xy 346.44889 -393.57246) (xy 346.475515 -393.545356) (xy 346.506963 -393.524034) (xy 346.541997 -393.509333)
			(xy 346.579243 -393.501828) (xy 346.59824 -393.501372) (xy 346.598748 -393.501372) (xy 346.620225 -393.501971)
			(xy 346.662089 -393.511592) (xy 346.700759 -393.530295) (xy 346.717874 -393.543282) (xy 346.718128 -393.543536)
			(xy 346.726629 -393.549641) (xy 346.746833 -393.555021) (xy 346.757244 -393.55395) (xy 346.841826 -393.541504)
			(xy 346.85986 -393.530074) (xy 346.865702 -393.521184) (xy 346.88004 -393.500884) (xy 346.914223 -393.46481)
			(xy 346.95379 -393.43474) (xy 346.997699 -393.411465) (xy 347.044795 -393.395599) (xy 347.093838 -393.387559)
			(xy 347.118686 -393.387072) (xy 347.142622 -393.38751) (xy 347.189908 -393.394973) (xy 347.235451 -393.409719)
			(xy 347.278138 -393.431388) (xy 347.316923 -393.459448) (xy 347.350858 -393.493213) (xy 347.379112 -393.531858)
			(xy 347.390466 -393.552934) (xy 347.390974 -393.55395) (xy 347.438218 -393.635738) (xy 347.443328 -393.643783)
			(xy 347.458237 -393.655632) (xy 347.476445 -393.661216) (xy 347.48597 -393.660884) (xy 347.591634 -393.65301)
			(xy 347.615256 -393.635738) (xy 347.62059 -393.622022) (xy 347.628003 -393.604489) (xy 347.648782 -393.572598)
			(xy 347.675447 -393.545435) (xy 347.706947 -393.524069) (xy 347.742044 -393.509339) (xy 347.779358 -393.501825)
			(xy 347.79839 -393.501372) (xy 347.798898 -393.501372) (xy 347.820377 -393.501945) (xy 347.862242 -393.511577)
			(xy 347.900911 -393.53029) (xy 347.918024 -393.543282) (xy 347.918278 -393.543536) (xy 347.926795 -393.549616)
			(xy 347.946986 -393.555011) (xy 347.957394 -393.55395) (xy 348.041976 -393.541504) (xy 348.06001 -393.530074)
			(xy 348.065852 -393.521184) (xy 348.080221 -393.500907) (xy 348.114398 -393.464833) (xy 348.153958 -393.43476)
			(xy 348.197862 -393.411482) (xy 348.244952 -393.39561) (xy 348.29399 -393.387563) (xy 348.318836 -393.387072)
			(xy 348.34277 -393.38755) (xy 348.390054 -393.395006) (xy 348.435597 -393.409745) (xy 348.478284 -393.431407)
			(xy 348.517069 -393.459461) (xy 348.551005 -393.49322) (xy 348.579261 -393.53186) (xy 348.590616 -393.552934)
			(xy 348.591124 -393.55395) (xy 348.638114 -393.63523) (xy 348.643205 -393.643307) (xy 348.658106 -393.655225)
			(xy 348.676322 -393.660907) (xy 348.685866 -393.66063) (xy 348.777306 -393.653772) (xy 348.786687 -393.652634)
			(xy 348.803738 -393.644528) (xy 348.816739 -393.630837) (xy 348.82074 -393.622276) (xy 348.82074 -393.621768)
			(xy 348.828142 -393.604265) (xy 348.848905 -393.572441) (xy 348.875538 -393.545337) (xy 348.906993 -393.524018)
			(xy 348.942035 -393.509321) (xy 348.979287 -393.501824) (xy 348.998286 -393.501372) (xy 348.998794 -393.501372)
			(xy 349.020272 -393.501947) (xy 349.062137 -393.511578) (xy 349.100806 -393.53029) (xy 349.11792 -393.543282)
			(xy 349.118174 -393.543536) (xy 349.126692 -393.549614) (xy 349.146882 -393.55501) (xy 349.15729 -393.55395)
			(xy 349.241872 -393.541504) (xy 349.259906 -393.530074) (xy 349.265748 -393.521184) (xy 349.28012 -393.500909)
			(xy 349.314296 -393.464835) (xy 349.353856 -393.434762) (xy 349.397759 -393.411483) (xy 349.444849 -393.395611)
			(xy 349.493886 -393.387563) (xy 349.518732 -393.387072) (xy 349.542666 -393.387554) (xy 349.58995 -393.395009)
			(xy 349.635493 -393.409747) (xy 349.678179 -393.431408) (xy 349.716965 -393.459462) (xy 349.750901 -393.493221)
			(xy 349.779157 -393.53186) (xy 349.790512 -393.552934) (xy 349.79102 -393.55395) (xy 349.83801 -393.63523)
			(xy 349.843103 -393.643305) (xy 349.858003 -393.655223) (xy 349.876218 -393.660906) (xy 349.885762 -393.66063)
			(xy 349.977202 -393.653772) (xy 349.986582 -393.652631) (xy 350.003633 -393.644526) (xy 350.016635 -393.630836)
			(xy 350.020636 -393.622276) (xy 350.020636 -393.621768) (xy 350.028041 -393.604267) (xy 350.048804 -393.572443)
			(xy 350.075436 -393.545339) (xy 350.10689 -393.524019) (xy 350.141931 -393.509322) (xy 350.179183 -393.501825)
			(xy 350.198182 -393.501372) (xy 350.19869 -393.501372) (xy 350.220168 -393.501949) (xy 350.262033 -393.511579)
			(xy 350.300702 -393.53029) (xy 350.317816 -393.543282) (xy 350.31807 -393.543536) (xy 350.326558 -393.549663)
			(xy 350.346772 -393.55503) (xy 350.357186 -393.55395) (xy 350.441768 -393.541504) (xy 350.459802 -393.530074)
			(xy 350.465644 -393.521184) (xy 350.480018 -393.500911) (xy 350.514194 -393.464836) (xy 350.553753 -393.434763)
			(xy 350.597656 -393.411484) (xy 350.644745 -393.395612) (xy 350.693782 -393.387563) (xy 350.718628 -393.387072)
			(xy 350.718882 -393.387072) (xy 350.742818 -393.387513) (xy 350.790103 -393.394976) (xy 350.835647 -393.409721)
			(xy 350.878334 -393.431389) (xy 350.917119 -393.459449) (xy 350.951054 -393.493214) (xy 350.979308 -393.531858)
			(xy 350.990662 -393.552934) (xy 350.99117 -393.55395) (xy 351.03816 -393.63523) (xy 351.043287 -393.643281)
			(xy 351.058172 -393.655203) (xy 351.076372 -393.660897) (xy 351.085912 -393.66063) (xy 351.177352 -393.653772)
			(xy 351.186727 -393.652598) (xy 351.203778 -393.644509) (xy 351.216782 -393.630831) (xy 351.220786 -393.622276)
			(xy 351.220786 -393.621768) (xy 351.228231 -393.604286) (xy 351.248987 -393.572463) (xy 351.275612 -393.545359)
			(xy 351.307058 -393.524037) (xy 351.342091 -393.509335) (xy 351.379336 -393.501829) (xy 351.398332 -393.501372)
			(xy 351.39884 -393.501372) (xy 351.420317 -393.501975) (xy 351.462181 -393.511594) (xy 351.500851 -393.530295)
			(xy 351.517966 -393.543282) (xy 351.51822 -393.543536) (xy 351.526724 -393.549637) (xy 351.546925 -393.555019)
			(xy 351.557336 -393.55395) (xy 351.641918 -393.541504) (xy 351.659952 -393.530074) (xy 351.665794 -393.521184)
			(xy 351.680137 -393.500888) (xy 351.714319 -393.464814) (xy 351.753885 -393.434743) (xy 351.797793 -393.411468)
			(xy 351.844889 -393.395601) (xy 351.89393 -393.387559) (xy 351.918778 -393.387072) (xy 351.942713 -393.387516)
			(xy 351.989999 -393.394978) (xy 352.035543 -393.409723) (xy 352.078229 -393.431391) (xy 352.117015 -393.45945)
			(xy 352.150949 -393.493214) (xy 352.179204 -393.531858) (xy 352.190558 -393.552934) (xy 352.191066 -393.55395)
			(xy 352.238056 -393.63523) (xy 352.243185 -393.643279) (xy 352.258069 -393.655201) (xy 352.276269 -393.660897)
			(xy 352.285808 -393.66063) (xy 352.377248 -393.653772) (xy 352.386622 -393.652595) (xy 352.403673 -393.644507)
			(xy 352.416678 -393.630831) (xy 352.420682 -393.622276) (xy 352.420682 -393.621768) (xy 352.42813 -393.604287)
			(xy 352.448886 -393.572465) (xy 352.47551 -393.545361) (xy 352.506955 -393.524038) (xy 352.541988 -393.509336)
			(xy 352.579232 -393.50183) (xy 352.598228 -393.501372) (xy 352.598736 -393.501372) (xy 352.620213 -393.501977)
			(xy 352.662076 -393.511596) (xy 352.700747 -393.530296) (xy 352.717862 -393.543282) (xy 352.718116 -393.543536)
			(xy 352.726621 -393.549635) (xy 352.746821 -393.555019) (xy 352.757232 -393.55395) (xy 352.841814 -393.541504)
			(xy 352.859848 -393.530074) (xy 352.86569 -393.521184) (xy 352.880036 -393.50089) (xy 352.914217 -393.464816)
			(xy 352.953782 -393.434745) (xy 352.99769 -393.411469) (xy 353.044785 -393.395602) (xy 353.093826 -393.38756)
			(xy 353.118674 -393.387072) (xy 353.118928 -393.387072) (xy 353.142862 -393.387557) (xy 353.190146 -393.395011)
			(xy 353.235688 -393.409749) (xy 353.278375 -393.43141) (xy 353.317161 -393.459463) (xy 353.351097 -393.493222)
			(xy 353.379353 -393.53186) (xy 353.390708 -393.552934) (xy 353.391216 -393.55395) (xy 353.438206 -393.63523)
			(xy 353.443326 -393.643267) (xy 353.458231 -393.655118) (xy 353.476434 -393.660706) (xy 353.485958 -393.660376)
			(xy 353.577144 -393.653518) (xy 353.586524 -393.652369) (xy 353.603579 -393.644273) (xy 353.61658 -393.630584)
			(xy 353.620578 -393.622022) (xy 353.620578 -393.621768) (xy 353.628029 -393.604289) (xy 353.648785 -393.572467)
			(xy 353.675408 -393.545362) (xy 353.706852 -393.52404) (xy 353.741884 -393.509336) (xy 353.779128 -393.50183)
			(xy 353.798124 -393.501372) (xy 353.798378 -393.501372) (xy 353.819954 -393.501962) (xy 353.862007 -393.511639)
			(xy 353.900836 -393.530465) (xy 353.918012 -393.543536) (xy 353.926394 -393.550394) (xy 353.94646 -393.555728)
			(xy 354.041964 -393.541504) (xy 354.059998 -393.530074) (xy 354.06584 -393.521184) (xy 354.080217 -393.500913)
			(xy 354.114392 -393.464838) (xy 354.153951 -393.434765) (xy 354.197853 -393.411485) (xy 354.244942 -393.395612)
			(xy 354.293978 -393.387564) (xy 354.318824 -393.387072) (xy 354.342758 -393.38756) (xy 354.390042 -393.395014)
			(xy 354.435584 -393.409751) (xy 354.478271 -393.431411) (xy 354.517057 -393.459464) (xy 354.550993 -393.493222)
			(xy 354.579249 -393.53186) (xy 354.590604 -393.552934) (xy 354.591112 -393.55395) (xy 354.671136 -393.6924)
			(xy 370.179346 -393.6924) (xy 370.183531 -393.652579) (xy 370.195903 -393.614497) (xy 370.215921 -393.57982)
			(xy 370.24271 -393.550061) (xy 370.275101 -393.526522) (xy 370.311678 -393.510231) (xy 370.350842 -393.501899)
			(xy 370.370862 -393.501372) (xy 370.37137 -393.501372) (xy 370.392848 -393.50196) (xy 370.434712 -393.511586)
			(xy 370.473382 -393.530293) (xy 370.490496 -393.543282) (xy 370.49075 -393.543536) (xy 370.499244 -393.549653)
			(xy 370.519453 -393.555025) (xy 370.529866 -393.55395) (xy 370.614448 -393.541504) (xy 370.632482 -393.530074)
			(xy 370.638324 -393.521184) (xy 370.652711 -393.500921) (xy 370.686884 -393.464845) (xy 370.726441 -393.434771)
			(xy 370.770341 -393.411491) (xy 370.817428 -393.395616) (xy 370.866463 -393.387565) (xy 370.891308 -393.387072)
			(xy 370.915241 -393.387573) (xy 370.962524 -393.395024) (xy 371.008067 -393.409759) (xy 371.050753 -393.431417)
			(xy 371.089539 -393.459468) (xy 371.123476 -393.493224) (xy 371.151732 -393.531861) (xy 371.163088 -393.552934)
			(xy 371.163596 -393.55395) (xy 371.210586 -393.63523) (xy 371.215695 -393.643293) (xy 371.230588 -393.655213)
			(xy 371.248796 -393.660902) (xy 371.258338 -393.66063) (xy 371.349778 -393.653772) (xy 371.359156 -393.652615)
			(xy 371.376207 -393.644518) (xy 371.38921 -393.630834) (xy 371.393212 -393.622276) (xy 371.393212 -393.621768)
			(xy 371.400636 -393.604276) (xy 371.421396 -393.572453) (xy 371.448024 -393.545348) (xy 371.479475 -393.524028)
			(xy 371.514512 -393.509328) (xy 371.55176 -393.501827) (xy 371.570758 -393.501372) (xy 371.571266 -393.501372)
			(xy 371.592743 -393.501962) (xy 371.634608 -393.511587) (xy 371.673277 -393.530293) (xy 371.690392 -393.543282)
			(xy 371.690646 -393.543536) (xy 371.699142 -393.549651) (xy 371.719349 -393.555025) (xy 371.729762 -393.55395)
			(xy 371.814344 -393.541504) (xy 371.832378 -393.530074) (xy 371.83822 -393.521184) (xy 371.852609 -393.500922)
			(xy 371.886782 -393.464847) (xy 371.926338 -393.434773) (xy 371.970238 -393.411492) (xy 372.017325 -393.395617)
			(xy 372.066359 -393.387565) (xy 372.091204 -393.387072) (xy 372.115137 -393.387576) (xy 372.16242 -393.395027)
			(xy 372.207962 -393.409762) (xy 372.250649 -393.431419) (xy 372.289435 -393.459469) (xy 372.323372 -393.493225)
			(xy 372.351628 -393.531861) (xy 372.362984 -393.552934) (xy 372.363492 -393.55395) (xy 372.410482 -393.63523)
			(xy 372.415594 -393.643291) (xy 372.430486 -393.655212) (xy 372.448692 -393.660901) (xy 372.458234 -393.66063)
			(xy 372.549674 -393.653772) (xy 372.559051 -393.652613) (xy 372.576103 -393.644517) (xy 372.589105 -393.630834)
			(xy 372.593108 -393.622276) (xy 372.593108 -393.621768) (xy 372.600535 -393.604277) (xy 372.621295 -393.572454)
			(xy 372.647922 -393.54535) (xy 372.679372 -393.524029) (xy 372.714409 -393.509329) (xy 372.751656 -393.501827)
			(xy 372.770654 -393.501372) (xy 372.771162 -393.501372) (xy 372.792639 -393.501964) (xy 372.834504 -393.511588)
			(xy 372.873173 -393.530293) (xy 372.890288 -393.543282) (xy 372.890542 -393.543536) (xy 372.899039 -393.549649)
			(xy 372.919246 -393.555024) (xy 372.929658 -393.55395) (xy 373.01424 -393.541504) (xy 373.032274 -393.530074)
			(xy 373.038116 -393.521184) (xy 373.052445 -393.500878) (xy 373.08663 -393.464804) (xy 373.126199 -393.434734)
			(xy 373.17011 -393.411461) (xy 373.217208 -393.395596) (xy 373.266251 -393.387558) (xy 373.2911 -393.387072)
			(xy 373.315033 -393.38758) (xy 373.362316 -393.39503) (xy 373.407858 -393.409764) (xy 373.450544 -393.43142)
			(xy 373.489331 -393.45947) (xy 373.523268 -393.493226) (xy 373.551524 -393.531862) (xy 373.56288 -393.552934)
			(xy 373.563388 -393.55395) (xy 373.610632 -393.635738) (xy 373.615732 -393.64379) (xy 373.630646 -393.655638)
			(xy 373.648858 -393.661218) (xy 373.658384 -393.660884) (xy 373.764048 -393.65301) (xy 373.78767 -393.635738)
			(xy 373.793004 -393.622022) (xy 373.800406 -393.604484) (xy 373.821187 -393.572592) (xy 373.847853 -393.54543)
			(xy 373.879356 -393.524064) (xy 373.914456 -393.509336) (xy 373.951772 -393.501824) (xy 373.970804 -393.501372)
			(xy 373.971312 -393.501372) (xy 373.992791 -393.501938) (xy 374.034656 -393.511573) (xy 374.073325 -393.530288)
			(xy 374.090438 -393.543282) (xy 374.090692 -393.543536) (xy 374.099205 -393.549623) (xy 374.119399 -393.555014)
			(xy 374.129808 -393.55395) (xy 374.21439 -393.541504) (xy 374.232424 -393.530074) (xy 374.238266 -393.521184)
			(xy 374.252627 -393.500901) (xy 374.286805 -393.464826) (xy 374.326367 -393.434755) (xy 374.370272 -393.411477)
			(xy 374.417364 -393.395607) (xy 374.466403 -393.387562) (xy 374.49125 -393.387072) (xy 374.515185 -393.387539)
			(xy 374.562469 -393.394997) (xy 374.608012 -393.409738) (xy 374.650699 -393.431401) (xy 374.689484 -393.459457)
			(xy 374.72342 -393.493218) (xy 374.751675 -393.531859) (xy 374.76303 -393.552934) (xy 374.763538 -393.55395)
			(xy 374.810528 -393.63523) (xy 374.815676 -393.643265) (xy 374.830551 -393.655189) (xy 374.848743 -393.660892)
			(xy 374.85828 -393.66063) (xy 374.94972 -393.653772) (xy 374.959102 -393.652644) (xy 374.976154 -393.644533)
			(xy 374.989154 -393.630838) (xy 374.993154 -393.622276) (xy 374.993154 -393.621768) (xy 375.000625 -393.604298)
			(xy 375.021377 -393.572476) (xy 375.047996 -393.545372) (xy 375.079437 -393.524048) (xy 375.114465 -393.509342)
			(xy 375.151705 -393.501832) (xy 375.1707 -393.501372) (xy 375.171208 -393.501372) (xy 375.192687 -393.50194)
			(xy 375.234552 -393.511574) (xy 375.273221 -393.530289) (xy 375.290334 -393.543282) (xy 375.290588 -393.543536)
			(xy 375.299102 -393.549621) (xy 375.319295 -393.555013) (xy 375.329704 -393.55395) (xy 375.414286 -393.541504)
			(xy 375.43232 -393.530074) (xy 375.438162 -393.521184) (xy 375.452525 -393.500903) (xy 375.486703 -393.464828)
			(xy 375.526265 -393.434756) (xy 375.570169 -393.411478) (xy 375.617261 -393.395608) (xy 375.666299 -393.387562)
			(xy 375.691146 -393.387072) (xy 375.715081 -393.387542) (xy 375.762365 -393.394999) (xy 375.807908 -393.40974)
			(xy 375.850594 -393.431403) (xy 375.88938 -393.459458) (xy 375.923316 -393.493219) (xy 375.951571 -393.531859)
			(xy 375.962926 -393.552934) (xy 375.963434 -393.55395) (xy 376.010678 -393.635738) (xy 376.015814 -393.643763)
			(xy 376.030712 -393.655615) (xy 376.048909 -393.661209) (xy 376.05843 -393.660884) (xy 376.164094 -393.65301)
			(xy 376.187716 -393.635738) (xy 376.19305 -393.622022) (xy 376.200496 -393.604504) (xy 376.221269 -393.572615)
			(xy 376.247927 -393.545452) (xy 376.279421 -393.524083) (xy 376.314512 -393.509349) (xy 376.351821 -393.501829)
			(xy 376.37085 -393.501372) (xy 376.371358 -393.501372) (xy 376.392835 -393.501966) (xy 376.434699 -393.511589)
			(xy 376.473369 -393.530294) (xy 376.490484 -393.543282) (xy 376.490738 -393.543536) (xy 376.499236 -393.549647)
			(xy 376.519442 -393.555023) (xy 376.529854 -393.55395) (xy 376.614436 -393.541504) (xy 376.63247 -393.530074)
			(xy 376.638312 -393.521184) (xy 376.652644 -393.500879) (xy 376.686828 -393.464806) (xy 376.726396 -393.434736)
			(xy 376.770307 -393.411462) (xy 376.817404 -393.395597) (xy 376.866447 -393.387558) (xy 376.891296 -393.387072)
			(xy 376.915232 -393.387502) (xy 376.962518 -393.394966) (xy 377.008062 -393.409714) (xy 377.050749 -393.431384)
			(xy 377.089534 -393.459445) (xy 377.123468 -393.493212) (xy 377.151722 -393.531857) (xy 377.163076 -393.552934)
			(xy 377.163584 -393.55395) (xy 377.210574 -393.63523) (xy 377.215691 -393.643288) (xy 377.230581 -393.655208)
			(xy 377.248785 -393.6609) (xy 377.258326 -393.66063) (xy 377.349766 -393.653772) (xy 377.359142 -393.652607)
			(xy 377.376194 -393.644514) (xy 377.389197 -393.630833) (xy 377.3932 -393.622276) (xy 377.3932 -393.621768)
			(xy 377.400634 -393.60428) (xy 377.421392 -393.572457) (xy 377.448018 -393.545353) (xy 377.479467 -393.524032)
			(xy 377.514502 -393.509331) (xy 377.551749 -393.501828) (xy 377.570746 -393.501372) (xy 377.571254 -393.501372)
			(xy 377.592731 -393.501968) (xy 377.634595 -393.51159) (xy 377.673265 -393.530294) (xy 377.69038 -393.543282)
			(xy 377.690634 -393.543536) (xy 377.699133 -393.549645) (xy 377.719338 -393.555022) (xy 377.72975 -393.55395)
			(xy 377.814332 -393.541504) (xy 377.832366 -393.530074) (xy 377.838208 -393.521184) (xy 377.852542 -393.500881)
			(xy 377.886726 -393.464808) (xy 377.926294 -393.434738) (xy 377.970204 -393.411463) (xy 378.017301 -393.395598)
			(xy 378.066343 -393.387558) (xy 378.091192 -393.387072) (xy 378.115128 -393.387505) (xy 378.162414 -393.394969)
			(xy 378.207958 -393.409716) (xy 378.250644 -393.431385) (xy 378.28943 -393.459446) (xy 378.323364 -393.493212)
			(xy 378.351618 -393.531857) (xy 378.362972 -393.552934) (xy 378.36348 -393.55395) (xy 378.41047 -393.63523)
			(xy 378.41559 -393.643286) (xy 378.430478 -393.655207) (xy 378.448681 -393.660899) (xy 378.458222 -393.66063)
			(xy 378.549662 -393.653772) (xy 378.559038 -393.652605) (xy 378.576089 -393.644513) (xy 378.589093 -393.630833)
			(xy 378.593096 -393.622276) (xy 378.593096 -393.621768) (xy 378.600533 -393.604282) (xy 378.621291 -393.572459)
			(xy 378.647916 -393.545355) (xy 378.679364 -393.524033) (xy 378.714399 -393.509332) (xy 378.751645 -393.501828)
			(xy 378.770642 -393.501372) (xy 378.77115 -393.501372) (xy 378.792627 -393.50197) (xy 378.834491 -393.511591)
			(xy 378.873161 -393.530294) (xy 378.890276 -393.543282) (xy 378.89053 -393.543536) (xy 378.899031 -393.549642)
			(xy 378.919234 -393.555021) (xy 378.929646 -393.55395) (xy 379.014228 -393.541504) (xy 379.032262 -393.530074)
			(xy 379.038104 -393.521184) (xy 379.052441 -393.500883) (xy 379.086624 -393.464809) (xy 379.126191 -393.434739)
			(xy 379.170101 -393.411465) (xy 379.217197 -393.395599) (xy 379.26624 -393.387559) (xy 379.291088 -393.387072)
			(xy 379.315024 -393.387508) (xy 379.36231 -393.394972) (xy 379.407853 -393.409718) (xy 379.45054 -393.431387)
			(xy 379.489325 -393.459447) (xy 379.52326 -393.493213) (xy 379.551514 -393.531858) (xy 379.562868 -393.552934)
			(xy 379.563376 -393.55395) (xy 379.61062 -393.635738) (xy 379.615728 -393.643784) (xy 379.630639 -393.655633)
			(xy 379.648847 -393.661216) (xy 379.658372 -393.660884) (xy 379.764036 -393.65301) (xy 379.787658 -393.635738)
			(xy 379.792992 -393.622022) (xy 379.800404 -393.604488) (xy 379.821183 -393.572597) (xy 379.847848 -393.545435)
			(xy 379.879348 -393.524068) (xy 379.914446 -393.509339) (xy 379.95176 -393.501825) (xy 379.970792 -393.501372)
			(xy 379.9713 -393.501372) (xy 379.992779 -393.501944) (xy 380.034644 -393.511576) (xy 380.073313 -393.530289)
			(xy 380.090426 -393.543282) (xy 380.09068 -393.543536) (xy 380.099196 -393.549617) (xy 380.119388 -393.555011)
			(xy 380.129796 -393.55395) (xy 380.214378 -393.541504) (xy 380.232412 -393.530074) (xy 380.238254 -393.521184)
			(xy 380.252622 -393.500907) (xy 380.286799 -393.464832) (xy 380.32636 -393.434759) (xy 380.370263 -393.411481)
			(xy 380.417354 -393.395609) (xy 380.466391 -393.387563) (xy 380.491238 -393.387072) (xy 380.515172 -393.387549)
			(xy 380.562456 -393.395005) (xy 380.607999 -393.409744) (xy 380.650686 -393.431406) (xy 380.689472 -393.45946)
			(xy 380.723407 -393.49322) (xy 380.751663 -393.53186) (xy 380.763018 -393.552934) (xy 380.763526 -393.55395)
			(xy 380.810516 -393.63523) (xy 380.815605 -393.643308) (xy 380.830507 -393.655226) (xy 380.848723 -393.660907)
			(xy 380.858268 -393.66063) (xy 380.949708 -393.653772) (xy 380.959089 -393.652635) (xy 380.97614 -393.644528)
			(xy 380.989141 -393.630837) (xy 380.993142 -393.622276) (xy 380.993142 -393.621768) (xy 381.000542 -393.604264)
			(xy 381.021306 -393.57244) (xy 381.047939 -393.545336) (xy 381.079394 -393.524017) (xy 381.114436 -393.509321)
			(xy 381.151688 -393.501824) (xy 381.170688 -393.501372) (xy 381.171196 -393.501372) (xy 381.192674 -393.501946)
			(xy 381.234539 -393.511577) (xy 381.273209 -393.53029) (xy 381.290322 -393.543282) (xy 381.290576 -393.543536)
			(xy 381.299094 -393.549615) (xy 381.319284 -393.55501) (xy 381.329692 -393.55395) (xy 381.414274 -393.541504)
			(xy 381.432308 -393.530074) (xy 381.43815 -393.521184) (xy 381.452521 -393.500908) (xy 381.486697 -393.464834)
			(xy 381.526257 -393.434761) (xy 381.57016 -393.411482) (xy 381.61725 -393.39561) (xy 381.666288 -393.387563)
			(xy 381.691134 -393.387072) (xy 381.715068 -393.387552) (xy 381.762352 -393.395007) (xy 381.807895 -393.409746)
			(xy 381.850581 -393.431407) (xy 381.889367 -393.459461) (xy 381.923303 -393.493221) (xy 381.951559 -393.53186)
			(xy 381.962914 -393.552934) (xy 381.963422 -393.55395) (xy 382.010666 -393.635738) (xy 382.015811 -393.643757)
			(xy 382.030704 -393.65561) (xy 382.048898 -393.661207) (xy 382.058418 -393.660884) (xy 382.164082 -393.65301)
			(xy 382.187704 -393.635738) (xy 382.193038 -393.622022) (xy 382.200493 -393.604509) (xy 382.221265 -393.57262)
			(xy 382.247921 -393.545456) (xy 382.279413 -393.524087) (xy 382.314502 -393.509352) (xy 382.351809 -393.50183)
			(xy 382.370838 -393.501372) (xy 382.371346 -393.501372) (xy 382.392823 -393.501972) (xy 382.434687 -393.511593)
			(xy 382.473357 -393.530295) (xy 382.490472 -393.543282) (xy 382.490726 -393.543536) (xy 382.499228 -393.54964)
			(xy 382.519431 -393.555021) (xy 382.529842 -393.55395) (xy 382.614424 -393.541504) (xy 382.632458 -393.530074)
			(xy 382.6383 -393.521184) (xy 382.652639 -393.500885) (xy 382.686822 -393.464811) (xy 382.726389 -393.434741)
			(xy 382.770298 -393.411466) (xy 382.817394 -393.395599) (xy 382.866436 -393.387559) (xy 382.891284 -393.387072)
			(xy 382.91522 -393.387511) (xy 382.962506 -393.394974) (xy 383.008049 -393.40972) (xy 383.050736 -393.431388)
			(xy 383.089521 -393.459448) (xy 383.123456 -393.493214) (xy 383.15171 -393.531858) (xy 383.163064 -393.552934)
			(xy 383.163572 -393.55395) (xy 383.210562 -393.63523) (xy 383.215687 -393.643282) (xy 383.230573 -393.655203)
			(xy 383.248774 -393.660898) (xy 383.258314 -393.66063) (xy 383.349754 -393.653772) (xy 383.359129 -393.6526)
			(xy 383.37618 -393.64451) (xy 383.389185 -393.630832) (xy 383.393188 -393.622276) (xy 383.393188 -393.621768)
			(xy 383.400631 -393.604285) (xy 383.421388 -393.572462) (xy 383.448013 -393.545358) (xy 383.479459 -393.524036)
			(xy 383.514493 -393.509334) (xy 383.551737 -393.501829) (xy 383.570734 -393.501372) (xy 383.571242 -393.501372)
			(xy 383.592719 -393.501974) (xy 383.634583 -393.511594) (xy 383.673253 -393.530295) (xy 383.690368 -393.543282)
			(xy 383.690622 -393.543536) (xy 383.699125 -393.549638) (xy 383.719327 -393.55502) (xy 383.729738 -393.55395)
			(xy 383.81432 -393.541504) (xy 383.832354 -393.530074) (xy 383.838196 -393.521184) (xy 383.852538 -393.500887)
			(xy 383.88672 -393.464813) (xy 383.926286 -393.434743) (xy 383.970195 -393.411467) (xy 384.01729 -393.3956)
			(xy 384.066332 -393.387559) (xy 384.09118 -393.387072) (xy 384.115116 -393.387515) (xy 384.162401 -393.394977)
			(xy 384.207945 -393.409722) (xy 384.250631 -393.43139) (xy 384.289417 -393.459449) (xy 384.323352 -393.493214)
			(xy 384.351606 -393.531858) (xy 384.36296 -393.552934) (xy 384.363468 -393.55395) (xy 384.410458 -393.63523)
			(xy 384.415586 -393.64328) (xy 384.43047 -393.655202) (xy 384.448671 -393.660897) (xy 384.45821 -393.66063)
			(xy 384.54965 -393.653772) (xy 384.559024 -393.652596) (xy 384.576076 -393.644508) (xy 384.58908 -393.630831)
			(xy 384.593084 -393.622276) (xy 384.593084 -393.621768) (xy 384.600531 -393.604286) (xy 384.621287 -393.572464)
			(xy 384.647911 -393.54536) (xy 384.679356 -393.524038) (xy 384.714389 -393.509335) (xy 384.751634 -393.501829)
			(xy 384.77063 -393.501372) (xy 384.771138 -393.501372) (xy 384.792615 -393.501976) (xy 384.834478 -393.511595)
			(xy 384.873149 -393.530295) (xy 384.890264 -393.543282) (xy 384.890518 -393.543536) (xy 384.899022 -393.549636)
			(xy 384.919223 -393.555019) (xy 384.929634 -393.55395) (xy 385.014216 -393.541504) (xy 385.03225 -393.530074)
			(xy 385.038092 -393.521184) (xy 385.052436 -393.500889) (xy 385.086618 -393.464815) (xy 385.126184 -393.434744)
			(xy 385.170092 -393.411469) (xy 385.217187 -393.395601) (xy 385.266228 -393.38756) (xy 385.291076 -393.387072)
			(xy 385.315011 -393.387518) (xy 385.362297 -393.39498) (xy 385.40784 -393.409724) (xy 385.450527 -393.431391)
			(xy 385.489312 -393.45945) (xy 385.523247 -393.493215) (xy 385.551501 -393.531858) (xy 385.562856 -393.552934)
			(xy 385.563364 -393.55395) (xy 385.610608 -393.635738) (xy 385.615724 -393.643778) (xy 385.630631 -393.655628)
			(xy 385.648836 -393.661214) (xy 385.65836 -393.660884) (xy 385.764024 -393.65301) (xy 385.787646 -393.635738)
			(xy 385.79298 -393.622022) (xy 385.800401 -393.604493) (xy 385.821179 -393.572602) (xy 385.847842 -393.545439)
			(xy 385.87934 -393.524072) (xy 385.914436 -393.509342) (xy 385.951749 -393.501826) (xy 385.97078 -393.501372)
			(xy 385.971288 -393.501372) (xy 385.992766 -393.50195) (xy 386.034631 -393.51158) (xy 386.0733 -393.53029)
			(xy 386.090414 -393.543282) (xy 386.090668 -393.543536) (xy 386.099157 -393.549662) (xy 386.11937 -393.555029)
			(xy 386.129784 -393.55395) (xy 386.214366 -393.541504) (xy 386.2324 -393.530074) (xy 386.238242 -393.521184)
			(xy 386.252618 -393.500912) (xy 386.286793 -393.464837) (xy 386.326352 -393.434764) (xy 386.370254 -393.411485)
			(xy 386.417344 -393.395612) (xy 386.46638 -393.387564) (xy 386.491226 -393.387072) (xy 386.51516 -393.387558)
			(xy 386.562444 -393.395013) (xy 386.607986 -393.40975) (xy 386.650673 -393.43141) (xy 386.689459 -393.459463)
			(xy 386.723395 -393.493222) (xy 386.751651 -393.53186) (xy 386.763006 -393.552934) (xy 386.763514 -393.55395)
			(xy 386.810504 -393.63523) (xy 386.815601 -393.643302) (xy 386.8305 -393.655221) (xy 386.848712 -393.660905)
			(xy 386.858256 -393.66063) (xy 386.949696 -393.653772) (xy 386.959076 -393.652627) (xy 386.976127 -393.644524)
			(xy 386.989128 -393.630836) (xy 386.99313 -393.622276) (xy 386.99313 -393.621768) (xy 387.00054 -393.604269)
			(xy 387.021302 -393.572445) (xy 387.047933 -393.545341) (xy 387.079386 -393.524021) (xy 387.114426 -393.509324)
			(xy 387.151677 -393.501825) (xy 387.170676 -393.501372) (xy 387.171184 -393.501372) (xy 387.192662 -393.501952)
			(xy 387.234527 -393.511581) (xy 387.273196 -393.530291) (xy 387.29031 -393.543282) (xy 387.290564 -393.543536)
			(xy 387.299054 -393.54966) (xy 387.319266 -393.555028) (xy 387.32968 -393.55395) (xy 387.414262 -393.541504)
			(xy 387.432296 -393.530074) (xy 387.438138 -393.521184) (xy 387.452516 -393.500914) (xy 387.486691 -393.464839)
			(xy 387.52625 -393.434766) (xy 387.570151 -393.411486) (xy 387.61724 -393.395613) (xy 387.666276 -393.387564)
			(xy 387.691122 -393.387072) (xy 387.715056 -393.387562) (xy 387.762339 -393.395015) (xy 387.807882 -393.409752)
			(xy 387.850568 -393.431412) (xy 387.889354 -393.459464) (xy 387.923291 -393.493222) (xy 387.951547 -393.531861)
			(xy 387.962902 -393.552934) (xy 387.96341 -393.55395) (xy 388.0104 -393.63523) (xy 388.0155 -393.6433)
			(xy 388.030397 -393.655219) (xy 388.048609 -393.660904) (xy 388.058152 -393.66063) (xy 388.149592 -393.653772)
			(xy 388.158971 -393.652625) (xy 388.176022 -393.644523) (xy 388.189024 -393.630835) (xy 388.193026 -393.622276)
			(xy 388.193026 -393.621768) (xy 388.200439 -393.60427) (xy 388.221201 -393.572447) (xy 388.247831 -393.545343)
			(xy 388.279284 -393.524023) (xy 388.314323 -393.509325) (xy 388.351573 -393.501825) (xy 388.370572 -393.501372)
			(xy 388.370826 -393.501372) (xy 388.392403 -393.501937) (xy 388.434458 -393.511625) (xy 388.473286 -393.53046)
			(xy 388.49046 -393.543536) (xy 388.498842 -393.550394) (xy 388.518908 -393.555728) (xy 388.614412 -393.541504)
			(xy 388.632446 -393.530074) (xy 388.638288 -393.521184) (xy 388.652635 -393.500891) (xy 388.686816 -393.464817)
			(xy 388.726381 -393.434746) (xy 388.770289 -393.41147) (xy 388.817383 -393.395602) (xy 388.866424 -393.38756)
			(xy 388.891272 -393.387072) (xy 388.915207 -393.387521) (xy 388.962493 -393.394982) (xy 389.008036 -393.409727)
			(xy 389.050723 -393.431393) (xy 389.089508 -393.459451) (xy 389.123443 -393.493215) (xy 389.151697 -393.531858)
			(xy 389.163052 -393.552934) (xy 389.16356 -393.55395) (xy 389.243584 -393.6924) (xy 402.707009 -393.6924)
			(xy 402.711196 -393.652565) (xy 402.723574 -393.61447) (xy 402.743602 -393.579782) (xy 402.770405 -393.550017)
			(xy 402.80281 -393.526474) (xy 402.839403 -393.510184) (xy 402.878583 -393.501858) (xy 402.89861 -393.501372)
			(xy 402.899118 -393.501372) (xy 402.920597 -393.501935) (xy 402.962463 -393.511571) (xy 403.001131 -393.530288)
			(xy 403.018244 -393.543282) (xy 403.018498 -393.543536) (xy 403.027009 -393.549626) (xy 403.047204 -393.555015)
			(xy 403.057614 -393.55395) (xy 403.142196 -393.541504) (xy 403.16023 -393.530074) (xy 403.166072 -393.521184)
			(xy 403.180429 -393.500898) (xy 403.214608 -393.464824) (xy 403.254171 -393.434752) (xy 403.298077 -393.411475)
			(xy 403.34517 -393.395605) (xy 403.394209 -393.387561) (xy 403.419056 -393.387072) (xy 403.442991 -393.387534)
			(xy 403.490276 -393.394993) (xy 403.535819 -393.409735) (xy 403.578505 -393.431399) (xy 403.617291 -393.459456)
			(xy 403.651226 -393.493218) (xy 403.679481 -393.531859) (xy 403.690836 -393.552934) (xy 403.691344 -393.55395)
			(xy 403.738334 -393.63523) (xy 403.743478 -393.643268) (xy 403.758355 -393.655192) (xy 403.776549 -393.660893)
			(xy 403.786086 -393.66063) (xy 403.877526 -393.653772) (xy 403.886909 -393.652648) (xy 403.90396 -393.644535)
			(xy 403.91696 -393.630839) (xy 403.92096 -393.622276) (xy 403.92096 -393.621768) (xy 403.928426 -393.604295)
			(xy 403.949179 -393.572474) (xy 403.975799 -393.545369) (xy 404.007241 -393.524046) (xy 404.04227 -393.509341)
			(xy 404.079511 -393.501832) (xy 404.098506 -393.501372) (xy 404.099014 -393.501372) (xy 404.120493 -393.501937)
			(xy 404.162358 -393.511572) (xy 404.201027 -393.530288) (xy 404.21814 -393.543282) (xy 404.218394 -393.543536)
			(xy 404.226906 -393.549624) (xy 404.247101 -393.555014) (xy 404.25751 -393.55395) (xy 404.342092 -393.541504)
			(xy 404.360126 -393.530074) (xy 404.365968 -393.521184) (xy 404.380327 -393.5009) (xy 404.414506 -393.464826)
			(xy 404.454068 -393.434754) (xy 404.497974 -393.411476) (xy 404.545066 -393.395606) (xy 404.594105 -393.387562)
			(xy 404.618952 -393.387072) (xy 404.642887 -393.387537) (xy 404.690171 -393.394995) (xy 404.735714 -393.409737)
			(xy 404.778401 -393.431401) (xy 404.817187 -393.459457) (xy 404.851122 -393.493218) (xy 404.879377 -393.531859)
			(xy 404.890732 -393.552934) (xy 404.89124 -393.55395) (xy 404.93823 -393.63523) (xy 404.943377 -393.643266)
			(xy 404.958253 -393.65519) (xy 404.976445 -393.660892) (xy 404.985982 -393.66063) (xy 405.077422 -393.653772)
			(xy 405.086804 -393.652645) (xy 405.103856 -393.644533) (xy 405.116856 -393.630839) (xy 405.120856 -393.622276)
			(xy 405.120856 -393.621768) (xy 405.128325 -393.604297) (xy 405.149078 -393.572476) (xy 405.175697 -393.545371)
			(xy 405.207138 -393.524047) (xy 405.242167 -393.509342) (xy 405.279407 -393.501832) (xy 405.298402 -393.501372)
			(xy 405.29891 -393.501372) (xy 405.320389 -393.501939) (xy 405.362254 -393.511573) (xy 405.400923 -393.530288)
			(xy 405.418036 -393.543282) (xy 405.41829 -393.543536) (xy 405.426803 -393.549622) (xy 405.446997 -393.555013)
			(xy 405.457406 -393.55395) (xy 405.541988 -393.541504) (xy 405.560022 -393.530074) (xy 405.565864 -393.521184)
			(xy 405.580226 -393.500902) (xy 405.614404 -393.464827) (xy 405.653966 -393.434755) (xy 405.697871 -393.411478)
			(xy 405.744963 -393.395607) (xy 405.794001 -393.387562) (xy 405.818848 -393.387072) (xy 405.842783 -393.387541)
			(xy 405.890067 -393.394998) (xy 405.93561 -393.409739) (xy 405.978297 -393.431402) (xy 406.017082 -393.459458)
			(xy 406.051018 -393.493219) (xy 406.079273 -393.531859) (xy 406.090628 -393.552934) (xy 406.091136 -393.55395)
			(xy 406.13838 -393.635738) (xy 406.143515 -393.643764) (xy 406.158413 -393.655616) (xy 406.176611 -393.661209)
			(xy 406.186132 -393.660884) (xy 406.291796 -393.65301) (xy 406.315418 -393.635738) (xy 406.320752 -393.622022)
			(xy 406.328196 -393.604503) (xy 406.34897 -393.572614) (xy 406.375628 -393.545451) (xy 406.407122 -393.524082)
			(xy 406.442214 -393.509349) (xy 406.479523 -393.501829) (xy 406.498552 -393.501372) (xy 406.49906 -393.501372)
			(xy 406.520537 -393.501965) (xy 406.562402 -393.511589) (xy 406.601071 -393.530293) (xy 406.618186 -393.543282)
			(xy 406.61844 -393.543536) (xy 406.626937 -393.549648) (xy 406.647144 -393.555023) (xy 406.657556 -393.55395)
			(xy 406.742138 -393.541504) (xy 406.760172 -393.530074) (xy 406.766014 -393.521184) (xy 406.780345 -393.500879)
			(xy 406.814529 -393.464805) (xy 406.854097 -393.434735) (xy 406.898009 -393.411462) (xy 406.945106 -393.395596)
			(xy 406.994149 -393.387558) (xy 407.018998 -393.387072) (xy 407.042934 -393.3875) (xy 407.090221 -393.394965)
			(xy 407.135764 -393.409713) (xy 407.178451 -393.431383) (xy 407.217236 -393.459445) (xy 407.25117 -393.493212)
			(xy 407.279424 -393.531857) (xy 407.290778 -393.552934) (xy 407.291286 -393.55395) (xy 407.338276 -393.63523)
			(xy 407.343392 -393.643289) (xy 407.358282 -393.655209) (xy 407.376487 -393.6609) (xy 407.386028 -393.66063)
			(xy 407.477468 -393.653772) (xy 407.486844 -393.652609) (xy 407.503896 -393.644515) (xy 407.516899 -393.630833)
			(xy 407.520902 -393.622276) (xy 407.520902 -393.621768) (xy 407.528334 -393.604279) (xy 407.549093 -393.572457)
			(xy 407.575719 -393.545352) (xy 407.607168 -393.524031) (xy 407.642204 -393.509331) (xy 407.679451 -393.501828)
			(xy 407.698448 -393.501372) (xy 407.698956 -393.501372) (xy 407.720433 -393.501967) (xy 407.762297 -393.51159)
			(xy 407.800967 -393.530294) (xy 407.818082 -393.543282) (xy 407.818336 -393.543536) (xy 407.826835 -393.549646)
			(xy 407.84704 -393.555023) (xy 407.857452 -393.55395) (xy 407.942034 -393.541504) (xy 407.960068 -393.530074)
			(xy 407.96591 -393.521184) (xy 407.980243 -393.50088) (xy 408.014427 -393.464807) (xy 408.053995 -393.434737)
			(xy 408.097906 -393.411463) (xy 408.145002 -393.395597) (xy 408.194045 -393.387558) (xy 408.218894 -393.387072)
			(xy 408.24283 -393.387503) (xy 408.290116 -393.394968) (xy 408.33566 -393.409715) (xy 408.378347 -393.431385)
			(xy 408.417132 -393.459446) (xy 408.451066 -393.493212) (xy 408.47932 -393.531857) (xy 408.490674 -393.552934)
			(xy 408.491182 -393.55395) (xy 408.538426 -393.635738) (xy 408.54353 -393.643787) (xy 408.558442 -393.655635)
			(xy 408.576652 -393.661217) (xy 408.586178 -393.660884) (xy 408.691842 -393.65301) (xy 408.715464 -393.635738)
			(xy 408.720798 -393.622022) (xy 408.728205 -393.604486) (xy 408.748985 -393.572595) (xy 408.775651 -393.545432)
			(xy 408.807152 -393.524066) (xy 408.842251 -393.509337) (xy 408.879566 -393.501825) (xy 408.898598 -393.501372)
			(xy 408.899106 -393.501372) (xy 408.920585 -393.501941) (xy 408.96245 -393.511575) (xy 409.001119 -393.530289)
			(xy 409.018232 -393.543282) (xy 409.018486 -393.543536) (xy 409.027 -393.54962) (xy 409.047193 -393.555013)
			(xy 409.057602 -393.55395) (xy 409.142184 -393.541504) (xy 409.160218 -393.530074) (xy 409.16606 -393.521184)
			(xy 409.180424 -393.500904) (xy 409.214602 -393.464829) (xy 409.254163 -393.434757) (xy 409.298068 -393.411479)
			(xy 409.345159 -393.395608) (xy 409.394197 -393.387562) (xy 409.419044 -393.387072) (xy 409.442978 -393.387544)
			(xy 409.490263 -393.395001) (xy 409.535806 -393.409741) (xy 409.578492 -393.431404) (xy 409.617278 -393.459459)
			(xy 409.651214 -393.493219) (xy 409.679469 -393.53186) (xy 409.690824 -393.552934) (xy 409.691332 -393.55395)
			(xy 409.738322 -393.63523) (xy 409.743474 -393.643262) (xy 409.758348 -393.655187) (xy 409.776538 -393.660891)
			(xy 409.786074 -393.66063) (xy 409.877514 -393.653772) (xy 409.886895 -393.652639) (xy 409.903947 -393.64453)
			(xy 409.916947 -393.630838) (xy 409.920948 -393.622276) (xy 409.920948 -393.621768) (xy 409.928343 -393.604262)
			(xy 409.949108 -393.572438) (xy 409.975742 -393.545334) (xy 410.007198 -393.524015) (xy 410.042241 -393.509319)
			(xy 410.079494 -393.501823) (xy 410.098494 -393.501372) (xy 410.099002 -393.501372) (xy 410.120481 -393.501943)
			(xy 410.162346 -393.511576) (xy 410.201015 -393.530289) (xy 410.218128 -393.543282) (xy 410.218382 -393.543536)
			(xy 410.226898 -393.549618) (xy 410.247089 -393.555012) (xy 410.257498 -393.55395) (xy 410.34208 -393.541504)
			(xy 410.360114 -393.530074) (xy 410.365956 -393.521184) (xy 410.380323 -393.500906) (xy 410.4145 -393.464831)
			(xy 410.454061 -393.434759) (xy 410.497965 -393.41148) (xy 410.545056 -393.395609) (xy 410.594093 -393.387562)
			(xy 410.61894 -393.387072) (xy 410.642874 -393.387547) (xy 410.690159 -393.395003) (xy 410.735701 -393.409743)
			(xy 410.778388 -393.431405) (xy 410.817174 -393.45946) (xy 410.85111 -393.49322) (xy 410.879365 -393.53186)
			(xy 410.89072 -393.552934) (xy 410.891228 -393.55395) (xy 410.938218 -393.63523) (xy 410.943306 -393.643309)
			(xy 410.958209 -393.655227) (xy 410.976425 -393.660908) (xy 410.98597 -393.66063) (xy 411.07741 -393.653772)
			(xy 411.086791 -393.652637) (xy 411.103842 -393.644529) (xy 411.116843 -393.630837) (xy 411.120844 -393.622276)
			(xy 411.120844 -393.621768) (xy 411.128242 -393.604264) (xy 411.149007 -393.572439) (xy 411.17564 -393.545335)
			(xy 411.207095 -393.524016) (xy 411.242138 -393.50932) (xy 411.27939 -393.501824) (xy 411.29839 -393.501372)
			(xy 411.298898 -393.501372) (xy 411.320377 -393.501945) (xy 411.362242 -393.511577) (xy 411.400911 -393.53029)
			(xy 411.418024 -393.543282) (xy 411.418278 -393.543536) (xy 411.426795 -393.549616) (xy 411.446986 -393.555011)
			(xy 411.457394 -393.55395) (xy 411.541976 -393.541504) (xy 411.56001 -393.530074) (xy 411.565852 -393.521184)
			(xy 411.580221 -393.500907) (xy 411.614398 -393.464833) (xy 411.653958 -393.43476) (xy 411.697862 -393.411482)
			(xy 411.744952 -393.39561) (xy 411.79399 -393.387563) (xy 411.818836 -393.387072) (xy 411.84277 -393.38755)
			(xy 411.890054 -393.395006) (xy 411.935597 -393.409745) (xy 411.978284 -393.431407) (xy 412.017069 -393.459461)
			(xy 412.051005 -393.49322) (xy 412.079261 -393.53186) (xy 412.090616 -393.552934) (xy 412.091124 -393.55395)
			(xy 412.138368 -393.635738) (xy 412.143511 -393.643758) (xy 412.158406 -393.655611) (xy 412.1766 -393.661207)
			(xy 412.18612 -393.660884) (xy 412.291784 -393.65301) (xy 412.315406 -393.635738) (xy 412.32074 -393.622022)
			(xy 412.328194 -393.604508) (xy 412.348966 -393.572619) (xy 412.375622 -393.545456) (xy 412.407114 -393.524086)
			(xy 412.442204 -393.509351) (xy 412.479511 -393.50183) (xy 412.49854 -393.501372) (xy 412.499048 -393.501372)
			(xy 412.520525 -393.501971) (xy 412.562389 -393.511592) (xy 412.601059 -393.530295) (xy 412.618174 -393.543282)
			(xy 412.618428 -393.543536) (xy 412.626929 -393.549641) (xy 412.647133 -393.555021) (xy 412.657544 -393.55395)
			(xy 412.742126 -393.541504) (xy 412.76016 -393.530074) (xy 412.766002 -393.521184) (xy 412.78034 -393.500884)
			(xy 412.814523 -393.46481) (xy 412.85409 -393.43474) (xy 412.897999 -393.411465) (xy 412.945095 -393.395599)
			(xy 412.994138 -393.387559) (xy 413.018986 -393.387072) (xy 413.042922 -393.38751) (xy 413.090208 -393.394973)
			(xy 413.135751 -393.409719) (xy 413.178438 -393.431388) (xy 413.217223 -393.459448) (xy 413.251158 -393.493213)
			(xy 413.279412 -393.531858) (xy 413.290766 -393.552934) (xy 413.291274 -393.55395) (xy 413.338264 -393.63523)
			(xy 413.343388 -393.643283) (xy 413.358274 -393.655204) (xy 413.376476 -393.660898) (xy 413.386016 -393.66063)
			(xy 413.477456 -393.653772) (xy 413.486831 -393.652601) (xy 413.503883 -393.644511) (xy 413.516887 -393.630832)
			(xy 413.52089 -393.622276) (xy 413.52089 -393.621768) (xy 413.528332 -393.604284) (xy 413.549089 -393.572462)
			(xy 413.575714 -393.545357) (xy 413.60716 -393.524035) (xy 413.642194 -393.509334) (xy 413.679439 -393.501829)
			(xy 413.698436 -393.501372) (xy 413.698944 -393.501372) (xy 413.720421 -393.501973) (xy 413.762285 -393.511593)
			(xy 413.800955 -393.530295) (xy 413.81807 -393.543282) (xy 413.818324 -393.543536) (xy 413.826826 -393.549639)
			(xy 413.847029 -393.55502) (xy 413.85744 -393.55395) (xy 413.942022 -393.541504) (xy 413.960056 -393.530074)
			(xy 413.965898 -393.521184) (xy 413.980239 -393.500886) (xy 414.014421 -393.464812) (xy 414.053987 -393.434742)
			(xy 414.097896 -393.411467) (xy 414.144992 -393.3956) (xy 414.194034 -393.387559) (xy 414.218882 -393.387072)
			(xy 414.242818 -393.387513) (xy 414.290103 -393.394976) (xy 414.335647 -393.409721) (xy 414.378334 -393.431389)
			(xy 414.417119 -393.459449) (xy 414.451054 -393.493214) (xy 414.479308 -393.531858) (xy 414.490662 -393.552934)
			(xy 414.49117 -393.55395) (xy 414.538414 -393.635738) (xy 414.543526 -393.643781) (xy 414.558435 -393.65563)
			(xy 414.576642 -393.661215) (xy 414.586166 -393.660884) (xy 414.69183 -393.65301) (xy 414.715452 -393.635738)
			(xy 414.720786 -393.622022) (xy 414.728203 -393.604491) (xy 414.748981 -393.5726) (xy 414.775645 -393.545437)
			(xy 414.807144 -393.52407) (xy 414.842241 -393.50934) (xy 414.879555 -393.501826) (xy 414.898586 -393.501372)
			(xy 414.899094 -393.501372) (xy 414.920572 -393.501947) (xy 414.962437 -393.511578) (xy 415.001106 -393.53029)
			(xy 415.01822 -393.543282) (xy 415.018474 -393.543536) (xy 415.026992 -393.549614) (xy 415.047182 -393.55501)
			(xy 415.05759 -393.55395) (xy 415.142172 -393.541504) (xy 415.160206 -393.530074) (xy 415.166048 -393.521184)
			(xy 415.18042 -393.500909) (xy 415.214596 -393.464835) (xy 415.254156 -393.434762) (xy 415.298059 -393.411483)
			(xy 415.345149 -393.395611) (xy 415.394186 -393.387563) (xy 415.419032 -393.387072) (xy 415.442966 -393.387554)
			(xy 415.49025 -393.395009) (xy 415.535793 -393.409747) (xy 415.578479 -393.431408) (xy 415.617265 -393.459462)
			(xy 415.651201 -393.493221) (xy 415.679457 -393.53186) (xy 415.690812 -393.552934) (xy 415.69132 -393.55395)
			(xy 415.73831 -393.63523) (xy 415.743403 -393.643305) (xy 415.758303 -393.655223) (xy 415.776518 -393.660906)
			(xy 415.786062 -393.66063) (xy 415.877502 -393.653772) (xy 415.886882 -393.652631) (xy 415.903933 -393.644526)
			(xy 415.916935 -393.630836) (xy 415.920936 -393.622276) (xy 415.920936 -393.621768) (xy 415.928341 -393.604267)
			(xy 415.949104 -393.572443) (xy 415.975736 -393.545339) (xy 416.00719 -393.524019) (xy 416.042231 -393.509322)
			(xy 416.079483 -393.501825) (xy 416.098482 -393.501372) (xy 416.09899 -393.501372) (xy 416.120468 -393.501949)
			(xy 416.162333 -393.511579) (xy 416.201002 -393.53029) (xy 416.218116 -393.543282) (xy 416.21837 -393.543536)
			(xy 416.226858 -393.549663) (xy 416.247072 -393.55503) (xy 416.257486 -393.55395) (xy 416.342068 -393.541504)
			(xy 416.360102 -393.530074) (xy 416.365944 -393.521184) (xy 416.380318 -393.500911) (xy 416.414494 -393.464836)
			(xy 416.454053 -393.434763) (xy 416.497956 -393.411484) (xy 416.545045 -393.395612) (xy 416.594082 -393.387563)
			(xy 416.618928 -393.387072) (xy 416.642862 -393.387557) (xy 416.690146 -393.395011) (xy 416.735688 -393.409749)
			(xy 416.778375 -393.43141) (xy 416.817161 -393.459463) (xy 416.851097 -393.493222) (xy 416.879353 -393.53186)
			(xy 416.890708 -393.552934) (xy 416.891216 -393.55395) (xy 416.938206 -393.63523) (xy 416.943302 -393.643303)
			(xy 416.958201 -393.655222) (xy 416.976414 -393.660905) (xy 416.985958 -393.66063) (xy 417.077398 -393.653772)
			(xy 417.086778 -393.652629) (xy 417.103829 -393.644525) (xy 417.11683 -393.630836) (xy 417.120832 -393.622276)
			(xy 417.120832 -393.621768) (xy 417.12824 -393.604268) (xy 417.149003 -393.572444) (xy 417.175634 -393.54534)
			(xy 417.207088 -393.524021) (xy 417.242128 -393.509323) (xy 417.279379 -393.501825) (xy 417.298378 -393.501372)
			(xy 417.298886 -393.501372) (xy 417.320364 -393.501951) (xy 417.362229 -393.51158) (xy 417.400898 -393.530291)
			(xy 417.418012 -393.543282) (xy 417.418266 -393.543536) (xy 417.426755 -393.549661) (xy 417.446968 -393.555029)
			(xy 417.457382 -393.55395) (xy 417.541964 -393.541504) (xy 417.559998 -393.530074) (xy 417.56584 -393.521184)
			(xy 417.580217 -393.500913) (xy 417.614392 -393.464838) (xy 417.653951 -393.434765) (xy 417.697853 -393.411485)
			(xy 417.744942 -393.395612) (xy 417.793978 -393.387564) (xy 417.818824 -393.387072) (xy 417.842758 -393.38756)
			(xy 417.890042 -393.395014) (xy 417.935584 -393.409751) (xy 417.978271 -393.431411) (xy 418.017057 -393.459464)
			(xy 418.050993 -393.493222) (xy 418.079249 -393.53186) (xy 418.090604 -393.552934) (xy 418.091112 -393.55395)
			(xy 418.138356 -393.635738) (xy 418.143507 -393.643752) (xy 418.158398 -393.655606) (xy 418.176589 -393.661205)
			(xy 418.186108 -393.660884) (xy 418.291772 -393.65301) (xy 418.315394 -393.635738) (xy 418.320728 -393.622022)
			(xy 418.328191 -393.604512) (xy 418.348962 -393.572624) (xy 418.375616 -393.545461) (xy 418.407107 -393.524091)
			(xy 418.442194 -393.509354) (xy 418.4795 -393.501831) (xy 418.498528 -393.501372) (xy 418.499036 -393.501372)
			(xy 418.520513 -393.501977) (xy 418.562376 -393.511596) (xy 418.601047 -393.530296) (xy 418.618162 -393.543282)
			(xy 418.618416 -393.543536) (xy 418.626921 -393.549635) (xy 418.647121 -393.555019) (xy 418.657532 -393.55395)
			(xy 418.742114 -393.541504) (xy 418.760148 -393.530074) (xy 418.76599 -393.521184) (xy 418.780336 -393.50089)
			(xy 418.814517 -393.464816) (xy 418.854082 -393.434745) (xy 418.89799 -393.411469) (xy 418.945085 -393.395602)
			(xy 418.994126 -393.38756) (xy 419.018974 -393.387072) (xy 419.042909 -393.387519) (xy 419.090195 -393.394981)
			(xy 419.135738 -393.409726) (xy 419.178425 -393.431392) (xy 419.21721 -393.459451) (xy 419.251145 -393.493215)
			(xy 419.279399 -393.531858) (xy 419.290754 -393.552934) (xy 419.291262 -393.55395) (xy 419.338252 -393.63523)
			(xy 419.343384 -393.643277) (xy 419.358267 -393.655199) (xy 419.376465 -393.660896) (xy 419.386004 -393.66063)
			(xy 419.477444 -393.653772) (xy 419.486818 -393.652592) (xy 419.503869 -393.644506) (xy 419.516874 -393.630831)
			(xy 419.520878 -393.622276) (xy 419.520878 -393.621768) (xy 419.528329 -393.604289) (xy 419.549085 -393.572467)
			(xy 419.575708 -393.545362) (xy 419.607152 -393.52404) (xy 419.642184 -393.509336) (xy 419.679428 -393.50183)
			(xy 419.698424 -393.501372) (xy 419.698932 -393.501372) (xy 419.720408 -393.501979) (xy 419.762272 -393.511597)
			(xy 419.800943 -393.530296) (xy 419.818058 -393.543282) (xy 419.818312 -393.543536) (xy 419.826818 -393.549633)
			(xy 419.847018 -393.555018) (xy 419.857428 -393.55395) (xy 419.94201 -393.541504) (xy 419.960044 -393.530074)
			(xy 419.965886 -393.521184) (xy 419.980234 -393.500892) (xy 420.014415 -393.464817) (xy 420.05398 -393.434747)
			(xy 420.097887 -393.411471) (xy 420.144982 -393.395602) (xy 420.194022 -393.38756) (xy 420.21887 -393.387072)
			(xy 420.242805 -393.387523) (xy 420.290091 -393.394984) (xy 420.335634 -393.409728) (xy 420.378321 -393.431394)
			(xy 420.417106 -393.459452) (xy 420.451041 -393.493216) (xy 420.479295 -393.531858) (xy 420.49065 -393.552934)
			(xy 420.491158 -393.55395) (xy 420.538148 -393.63523) (xy 420.543283 -393.643275) (xy 420.558164 -393.655198)
			(xy 420.576361 -393.660895) (xy 420.5859 -393.66063) (xy 420.67734 -393.653772) (xy 420.686724 -393.652657)
			(xy 420.703776 -393.644539) (xy 420.716775 -393.63084) (xy 420.720774 -393.622276) (xy 420.720774 -393.621768)
			(xy 420.728229 -393.60429) (xy 420.748983 -393.572468) (xy 420.775606 -393.545364) (xy 420.80705 -393.524041)
			(xy 420.842081 -393.509337) (xy 420.879324 -393.50183) (xy 420.89832 -393.501372) (xy 420.898574 -393.501372)
			(xy 420.92015 -393.501964) (xy 420.962203 -393.51164) (xy 421.001032 -393.530466) (xy 421.018208 -393.543536)
			(xy 421.02659 -393.550394) (xy 421.046656 -393.555728) (xy 421.14216 -393.541504) (xy 421.160194 -393.530074)
			(xy 421.166036 -393.521184) (xy 421.180415 -393.500915) (xy 421.21459 -393.46484) (xy 421.254148 -393.434767)
			(xy 421.29805 -393.411487) (xy 421.345138 -393.395613) (xy 421.394174 -393.387564) (xy 421.41902 -393.387072)
			(xy 421.442954 -393.387563) (xy 421.490237 -393.395017) (xy 421.53578 -393.409753) (xy 421.578466 -393.431413)
			(xy 421.617252 -393.459465) (xy 421.651189 -393.493223) (xy 421.679444 -393.531861) (xy 421.6908 -393.552934)
			(xy 421.691308 -393.55395) (xy 422.083738 -394.232892) (xy 422.096563 -394.256225) (xy 422.114783 -394.306247)
			(xy 422.124043 -394.358673) (xy 422.124632 -394.385292) (xy 422.124131 -394.409269) (xy 422.116635 -394.456634)
			(xy 422.101826 -394.502244) (xy 422.080067 -394.544978) (xy 422.051895 -394.583784) (xy 422.018002 -394.617709)
			(xy 421.979222 -394.645918) (xy 421.936509 -394.667716) (xy 421.890912 -394.682568) (xy 421.843555 -394.690109)
			(xy 421.819578 -394.6906) (xy 421.81907 -394.6906) (xy 421.795495 -394.69023) (xy 421.748906 -394.682984)
			(xy 421.703987 -394.668654) (xy 421.661808 -394.647582) (xy 421.623376 -394.620268) (xy 421.589605 -394.587365)
			(xy 421.5613 -394.549657) (xy 421.54983 -394.529056) (xy 421.549322 -394.528294) (xy 421.53586 -394.504926)
			(xy 421.530463 -394.496484) (xy 421.51458 -394.484297) (xy 421.495242 -394.479119) (xy 421.475394 -394.481739)
			(xy 421.466518 -394.486384) (xy 421.457374 -394.491718) (xy 421.451278 -394.5001) (xy 421.440331 -394.513983)
			(xy 421.414254 -394.53785) (xy 421.384232 -394.556514) (xy 421.351291 -394.569341) (xy 421.316553 -394.575891)
			(xy 421.298878 -394.5763) (xy 421.29837 -394.5763) (xy 421.279595 -394.575831) (xy 421.242766 -394.568507)
			(xy 421.20807 -394.554146) (xy 421.176838 -394.533299) (xy 421.150267 -394.506765) (xy 421.129378 -394.475562)
			(xy 421.114969 -394.440886) (xy 421.107595 -394.404067) (xy 421.107108 -394.385292) (xy 421.107587 -394.366178)
			(xy 421.115148 -394.328707) (xy 421.130006 -394.293486) (xy 421.151568 -394.261922) (xy 421.178974 -394.235273)
			(xy 421.211131 -394.214604) (xy 421.228774 -394.207238) (xy 421.238934 -394.203174) (xy 421.254428 -394.187426)
			(xy 421.283638 -394.104114) (xy 421.286864 -394.093535) (xy 421.284885 -394.071532) (xy 421.279828 -394.061696)
			(xy 421.151558 -393.839954) (xy 421.139366 -393.81557) (xy 421.134588 -393.806021) (xy 421.118789 -393.791688)
			(xy 421.098533 -393.785003) (xy 421.077306 -393.787115) (xy 421.058765 -393.797662) (xy 421.05199 -393.805918)
			(xy 421.041065 -393.820029) (xy 421.014899 -393.84429) (xy 420.984685 -393.863273) (xy 420.951472 -393.876318)
			(xy 420.916415 -393.882973) (xy 420.898574 -393.883388) (xy 420.898066 -393.883388) (xy 420.891186 -393.88339)
			(xy 420.877456 -393.882497) (xy 420.870634 -393.88161) (xy 420.856156 -393.879324) (xy 420.829486 -393.891008)
			(xy 420.769796 -393.978892) (xy 420.764812 -393.987047) (xy 420.760631 -394.005677) (xy 420.763553 -394.024546)
			(xy 420.768018 -394.032994) (xy 420.883588 -394.232892) (xy 420.89632 -394.256211) (xy 420.914415 -394.306158)
			(xy 420.923631 -394.358477) (xy 420.924228 -394.385038) (xy 420.924228 -394.385292) (xy 420.92373 -394.409282)
			(xy 420.916226 -394.456672) (xy 420.901401 -394.502304) (xy 420.87962 -394.545055) (xy 420.85142 -394.583873)
			(xy 420.817494 -394.617801) (xy 420.778679 -394.646005) (xy 420.73593 -394.66779) (xy 420.690299 -394.682619)
			(xy 420.64291 -394.690128) (xy 420.61892 -394.6906) (xy 420.595347 -394.69019) (xy 420.548759 -394.682952)
			(xy 420.503841 -394.668629) (xy 420.461662 -394.647563) (xy 420.423229 -394.620256) (xy 420.389457 -394.587358)
			(xy 420.361151 -394.549655) (xy 420.34968 -394.529056) (xy 420.349172 -394.528294) (xy 420.33571 -394.504926)
			(xy 420.330364 -394.496446) (xy 420.314462 -394.48426) (xy 420.295107 -394.479091) (xy 420.275247 -394.481728)
			(xy 420.266368 -394.486384) (xy 420.257224 -394.491718) (xy 420.251128 -394.5001) (xy 420.24021 -394.514007)
			(xy 420.214125 -394.537872) (xy 420.184096 -394.556532) (xy 420.151148 -394.569353) (xy 420.116405 -394.575895)
			(xy 420.098728 -394.5763) (xy 420.09822 -394.5763) (xy 420.07945 -394.57586) (xy 420.04263 -394.56854)
			(xy 420.007947 -394.554176) (xy 419.976732 -394.533321) (xy 419.950186 -394.506777) (xy 419.92933 -394.475564)
			(xy 419.914964 -394.440881) (xy 419.907641 -394.404062) (xy 419.907212 -394.385292) (xy 419.907679 -394.366197)
			(xy 419.915248 -394.328766) (xy 419.930083 -394.293576) (xy 419.951597 -394.262024) (xy 419.978936 -394.23536)
			(xy 420.011017 -394.214642) (xy 420.028624 -394.207238) (xy 420.038784 -394.203174) (xy 420.054278 -394.187426)
			(xy 420.083488 -394.104114) (xy 420.08672 -394.093536) (xy 420.084739 -394.071531) (xy 420.079678 -394.061696)
			(xy 419.951408 -393.839954) (xy 419.93947 -393.815824) (xy 419.934688 -393.80628) (xy 419.918887 -393.791959)
			(xy 419.898635 -393.785279) (xy 419.877414 -393.787388) (xy 419.858873 -393.797923) (xy 419.852094 -393.806172)
			(xy 419.841159 -393.820259) (xy 419.814973 -393.844463) (xy 419.784753 -393.863389) (xy 419.751547 -393.876383)
			(xy 419.716507 -393.882992) (xy 419.698678 -393.883388) (xy 419.69817 -393.883388) (xy 419.69129 -393.883389)
			(xy 419.67756 -393.882496) (xy 419.670738 -393.88161) (xy 419.65626 -393.879324) (xy 419.62959 -393.891008)
			(xy 419.5699 -393.978892) (xy 419.564916 -393.987047) (xy 419.560734 -394.005677) (xy 419.563656 -394.024546)
			(xy 419.568122 -394.032994) (xy 419.683692 -394.232892) (xy 419.696424 -394.25621) (xy 419.714519 -394.306158)
			(xy 419.723735 -394.358477) (xy 419.724332 -394.385038) (xy 419.724332 -394.385292) (xy 419.72383 -394.409282)
			(xy 419.716326 -394.456671) (xy 419.701501 -394.502303) (xy 419.679721 -394.545054) (xy 419.651521 -394.583871)
			(xy 419.617596 -394.6178) (xy 419.578781 -394.646004) (xy 419.536032 -394.667789) (xy 419.490402 -394.682618)
			(xy 419.443014 -394.690128) (xy 419.419024 -394.6906) (xy 419.395451 -394.690187) (xy 419.348863 -394.682949)
			(xy 419.303945 -394.668627) (xy 419.261767 -394.647561) (xy 419.223333 -394.620255) (xy 419.189561 -394.587358)
			(xy 419.161255 -394.549655) (xy 419.149784 -394.529056) (xy 419.149276 -394.528294) (xy 419.135814 -394.504926)
			(xy 419.130464 -394.496449) (xy 419.114564 -394.484263) (xy 419.09521 -394.479093) (xy 419.075351 -394.481729)
			(xy 419.066472 -394.486384) (xy 419.057328 -394.491718) (xy 419.051232 -394.5001) (xy 419.040312 -394.514005)
			(xy 419.014227 -394.53787) (xy 418.984199 -394.556531) (xy 418.951252 -394.569352) (xy 418.916509 -394.575895)
			(xy 418.898832 -394.5763) (xy 418.898324 -394.5763) (xy 418.879554 -394.575857) (xy 418.842735 -394.568537)
			(xy 418.808051 -394.554174) (xy 418.776836 -394.53332) (xy 418.75029 -394.506776) (xy 418.729434 -394.475563)
			(xy 418.715068 -394.440881) (xy 418.707745 -394.404062) (xy 418.707316 -394.385292) (xy 418.70778 -394.366197)
			(xy 418.715349 -394.328765) (xy 418.730185 -394.293575) (xy 418.7517 -394.262023) (xy 418.77904 -394.235359)
			(xy 418.811121 -394.214641) (xy 418.828728 -394.207238) (xy 418.838888 -394.203174) (xy 418.854382 -394.187426)
			(xy 418.883592 -394.104114) (xy 418.886823 -394.093536) (xy 418.884843 -394.071531) (xy 418.879782 -394.061696)
			(xy 418.751512 -393.839954) (xy 418.739574 -393.815824) (xy 418.734787 -393.806283) (xy 418.718987 -393.791963)
			(xy 418.698737 -393.785282) (xy 418.677517 -393.78739) (xy 418.658977 -393.797924) (xy 418.652198 -393.806172)
			(xy 418.641278 -393.820239) (xy 418.615137 -393.844415) (xy 418.58497 -393.863331) (xy 418.551822 -393.876333)
			(xy 418.516839 -393.882971) (xy 418.499036 -393.883388) (xy 418.498528 -393.883388) (xy 418.470842 -393.881356)
			(xy 418.470588 -393.881356) (xy 418.461118 -393.880416) (xy 418.442605 -393.884745) (xy 418.426953 -393.895538)
			(xy 418.421312 -393.9032) (xy 418.36975 -393.978892) (xy 418.364764 -393.987047) (xy 418.360578 -394.005677)
			(xy 418.363503 -394.024547) (xy 418.367972 -394.032994) (xy 418.483542 -394.232892) (xy 418.496367 -394.256224)
			(xy 418.514587 -394.306247) (xy 418.523847 -394.358673) (xy 418.524436 -394.385292) (xy 418.523931 -394.409269)
			(xy 418.516435 -394.456633) (xy 418.501626 -394.502243) (xy 418.479868 -394.544977) (xy 418.451696 -394.583783)
			(xy 418.417804 -394.617708) (xy 418.379024 -394.645916) (xy 418.336311 -394.667715) (xy 418.290716 -394.682567)
			(xy 418.243358 -394.690108) (xy 418.219382 -394.6906) (xy 418.218874 -394.6906) (xy 418.195299 -394.690227)
			(xy 418.14871 -394.682982) (xy 418.103791 -394.668652) (xy 418.061613 -394.64758) (xy 418.02318 -394.620267)
			(xy 417.989409 -394.587365) (xy 417.961104 -394.549657) (xy 417.949634 -394.529056) (xy 417.949126 -394.528294)
			(xy 417.935664 -394.504926) (xy 417.930263 -394.496487) (xy 417.914381 -394.4843) (xy 417.895045 -394.479121)
			(xy 417.875198 -394.481739) (xy 417.866322 -394.486384) (xy 417.857178 -394.491718) (xy 417.851082 -394.5001)
			(xy 417.840133 -394.513982) (xy 417.814056 -394.537848) (xy 417.784035 -394.556513) (xy 417.751094 -394.56934)
			(xy 417.716356 -394.575891) (xy 417.698682 -394.5763) (xy 417.698174 -394.5763) (xy 417.679399 -394.575827)
			(xy 417.64257 -394.568504) (xy 417.607874 -394.554144) (xy 417.576642 -394.533298) (xy 417.550072 -394.506764)
			(xy 417.529182 -394.475561) (xy 417.514773 -394.440885) (xy 417.507399 -394.404066) (xy 417.506912 -394.385292)
			(xy 417.507388 -394.366178) (xy 417.514949 -394.328707) (xy 417.529808 -394.293486) (xy 417.551371 -394.261921)
			(xy 417.578778 -394.235272) (xy 417.610935 -394.214604) (xy 417.628578 -394.207238) (xy 417.638738 -394.203174)
			(xy 417.654232 -394.187426) (xy 417.683442 -394.104114) (xy 417.686667 -394.093535) (xy 417.684689 -394.071532)
			(xy 417.679632 -394.061696) (xy 417.551362 -393.839954) (xy 417.539424 -393.815824) (xy 417.534566 -393.806324)
			(xy 417.518787 -393.79201) (xy 417.498557 -393.785325) (xy 417.477355 -393.787421) (xy 417.458825 -393.797935)
			(xy 417.452048 -393.806172) (xy 417.441082 -393.820234) (xy 417.414904 -393.844439) (xy 417.384692 -393.86337)
			(xy 417.351493 -393.87637) (xy 417.316459 -393.882988) (xy 417.298632 -393.883388) (xy 417.298124 -393.883388)
			(xy 417.291244 -393.883383) (xy 417.277515 -393.882494) (xy 417.270692 -393.88161) (xy 417.256214 -393.879324)
			(xy 417.229544 -393.891008) (xy 417.169854 -393.978892) (xy 417.164872 -393.987047) (xy 417.160694 -394.005677)
			(xy 417.163613 -394.024546) (xy 417.168076 -394.032994) (xy 417.283646 -394.232892) (xy 417.296471 -394.256224)
			(xy 417.314691 -394.306247) (xy 417.323951 -394.358673) (xy 417.32454 -394.385292) (xy 417.324031 -394.409269)
			(xy 417.316535 -394.456633) (xy 417.301726 -394.502242) (xy 417.279969 -394.544976) (xy 417.251798 -394.583782)
			(xy 417.217906 -394.617706) (xy 417.179127 -394.645915) (xy 417.136414 -394.667714) (xy 417.090819 -394.682566)
			(xy 417.043462 -394.690108) (xy 417.019486 -394.6906) (xy 417.018978 -394.6906) (xy 416.995403 -394.690224)
			(xy 416.948814 -394.682979) (xy 416.903895 -394.66865) (xy 416.861717 -394.647579) (xy 416.823284 -394.620266)
			(xy 416.789513 -394.587364) (xy 416.761208 -394.549657) (xy 416.749738 -394.529056) (xy 416.74923 -394.528294)
			(xy 416.735768 -394.504926) (xy 416.730363 -394.49649) (xy 416.714483 -394.484303) (xy 416.695147 -394.479123)
			(xy 416.675302 -394.48174) (xy 416.666426 -394.486384) (xy 416.657282 -394.491718) (xy 416.651186 -394.5001)
			(xy 416.640235 -394.51398) (xy 416.614158 -394.537846) (xy 416.584138 -394.556511) (xy 416.551198 -394.569339)
			(xy 416.51646 -394.57589) (xy 416.498786 -394.5763) (xy 416.498278 -394.5763) (xy 416.479503 -394.575824)
			(xy 416.442674 -394.568501) (xy 416.407978 -394.554142) (xy 416.376746 -394.533296) (xy 416.350176 -394.506763)
			(xy 416.329286 -394.47556) (xy 416.314877 -394.440885) (xy 416.307503 -394.404066) (xy 416.307016 -394.385292)
			(xy 416.30749 -394.366178) (xy 416.315051 -394.328706) (xy 416.32991 -394.293485) (xy 416.351473 -394.26192)
			(xy 416.378881 -394.235272) (xy 416.411038 -394.214603) (xy 416.428682 -394.207238) (xy 416.438842 -394.203174)
			(xy 416.454336 -394.187426) (xy 416.483546 -394.104114) (xy 416.486771 -394.093535) (xy 416.484793 -394.071532)
			(xy 416.479736 -394.061696) (xy 416.351466 -393.839954) (xy 416.339528 -393.815824) (xy 416.334665 -393.806328)
			(xy 416.318887 -393.792013) (xy 416.298659 -393.785329) (xy 416.277458 -393.787423) (xy 416.258929 -393.797936)
			(xy 416.252152 -393.806172) (xy 416.241184 -393.820232) (xy 416.215007 -393.844437) (xy 416.184795 -393.863369)
			(xy 416.151596 -393.876369) (xy 416.116563 -393.882987) (xy 416.098736 -393.883388) (xy 416.098228 -393.883388)
			(xy 416.091348 -393.883383) (xy 416.077619 -393.882494) (xy 416.070796 -393.88161) (xy 416.056318 -393.879324)
			(xy 416.029648 -393.891008) (xy 415.969958 -393.978892) (xy 415.964976 -393.987047) (xy 415.960798 -394.005677)
			(xy 415.963717 -394.024546) (xy 415.96818 -394.032994) (xy 416.08375 -394.232892) (xy 416.096576 -394.256224)
			(xy 416.114795 -394.306247) (xy 416.124055 -394.358673) (xy 416.124644 -394.385292) (xy 416.124131 -394.409269)
			(xy 416.116635 -394.456632) (xy 416.101827 -394.502241) (xy 416.080069 -394.544974) (xy 416.051899 -394.58378)
			(xy 416.018007 -394.617705) (xy 415.979229 -394.645913) (xy 415.936517 -394.667712) (xy 415.890922 -394.682566)
			(xy 415.843566 -394.690108) (xy 415.81959 -394.6906) (xy 415.819082 -394.6906) (xy 415.795507 -394.690221)
			(xy 415.748919 -394.682977) (xy 415.704 -394.668648) (xy 415.661821 -394.647577) (xy 415.623388 -394.620265)
			(xy 415.589617 -394.587364) (xy 415.561312 -394.549657) (xy 415.549842 -394.529056) (xy 415.549334 -394.528294)
			(xy 415.535872 -394.504926) (xy 415.530463 -394.496493) (xy 415.514584 -394.484306) (xy 415.49525 -394.479126)
			(xy 415.475406 -394.481741) (xy 415.46653 -394.486384) (xy 415.457386 -394.491718) (xy 415.45129 -394.5001)
			(xy 415.440337 -394.513978) (xy 415.414261 -394.537845) (xy 415.384241 -394.55651) (xy 415.351301 -394.569338)
			(xy 415.316564 -394.57589) (xy 415.29889 -394.5763) (xy 415.298382 -394.5763) (xy 415.279607 -394.57582)
			(xy 415.242778 -394.568498) (xy 415.208083 -394.55414) (xy 415.176851 -394.533294) (xy 415.15028 -394.506762)
			(xy 415.12939 -394.47556) (xy 415.114981 -394.440884) (xy 415.107607 -394.404066) (xy 415.10712 -394.385292)
			(xy 415.107591 -394.366178) (xy 415.115153 -394.328706) (xy 415.130012 -394.293484) (xy 415.151576 -394.26192)
			(xy 415.178984 -394.235271) (xy 415.211142 -394.214603) (xy 415.228786 -394.207238) (xy 415.238946 -394.203174)
			(xy 415.25444 -394.187426) (xy 415.28365 -394.104114) (xy 415.286874 -394.093535) (xy 415.284896 -394.071532)
			(xy 415.27984 -394.061696) (xy 415.15157 -393.839954) (xy 415.139632 -393.815824) (xy 415.134763 -393.806331)
			(xy 415.118987 -393.792017) (xy 415.09876 -393.785332) (xy 415.077561 -393.787425) (xy 415.059033 -393.797937)
			(xy 415.052256 -393.806172) (xy 415.041303 -393.820211) (xy 415.01517 -393.844389) (xy 414.985011 -393.86331)
			(xy 414.951871 -393.876319) (xy 414.916895 -393.882966) (xy 414.899094 -393.883388) (xy 414.898586 -393.883388)
			(xy 414.8709 -393.881356) (xy 414.870646 -393.881356) (xy 414.861178 -393.880382) (xy 414.842661 -393.884726)
			(xy 414.827009 -393.895532) (xy 414.82137 -393.9032) (xy 414.769808 -393.978892) (xy 414.764824 -393.987047)
			(xy 414.760641 -394.005677) (xy 414.763564 -394.024547) (xy 414.76803 -394.032994) (xy 414.8836 -394.232892)
			(xy 414.896333 -394.25621) (xy 414.914427 -394.306158) (xy 414.923643 -394.358477) (xy 414.92424 -394.385038)
			(xy 414.92424 -394.385292) (xy 414.92373 -394.409281) (xy 414.916226 -394.45667) (xy 414.901402 -394.502301)
			(xy 414.879622 -394.545051) (xy 414.851423 -394.583869) (xy 414.817499 -394.617797) (xy 414.778686 -394.646001)
			(xy 414.735938 -394.667787) (xy 414.690309 -394.682617) (xy 414.642921 -394.690127) (xy 414.618932 -394.6906)
			(xy 414.595359 -394.69018) (xy 414.548772 -394.682944) (xy 414.503854 -394.668623) (xy 414.461675 -394.647558)
			(xy 414.423242 -394.620253) (xy 414.38947 -394.587357) (xy 414.361163 -394.549654) (xy 414.349692 -394.529056)
			(xy 414.349184 -394.528294) (xy 414.335722 -394.504926) (xy 414.330364 -394.496455) (xy 414.314467 -394.484269)
			(xy 414.295115 -394.479098) (xy 414.275258 -394.48173) (xy 414.26638 -394.486384) (xy 414.257236 -394.491718)
			(xy 414.25114 -394.5001) (xy 414.240215 -394.514002) (xy 414.214132 -394.537866) (xy 414.184105 -394.556528)
			(xy 414.151159 -394.56935) (xy 414.116416 -394.575894) (xy 414.09874 -394.5763) (xy 414.098232 -394.5763)
			(xy 414.079462 -394.575849) (xy 414.042643 -394.568531) (xy 414.00796 -394.554169) (xy 413.976745 -394.533316)
			(xy 413.950199 -394.506774) (xy 413.929342 -394.475562) (xy 413.914976 -394.44088) (xy 413.907653 -394.404062)
			(xy 413.907224 -394.385292) (xy 413.907683 -394.366197) (xy 413.915253 -394.328764) (xy 413.930089 -394.293574)
			(xy 413.951605 -394.262021) (xy 413.978946 -394.235358) (xy 414.011028 -394.214641) (xy 414.028636 -394.207238)
			(xy 414.038796 -394.203174) (xy 414.05429 -394.187426) (xy 414.0835 -394.104114) (xy 414.08673 -394.093536)
			(xy 414.08475 -394.071531) (xy 414.07969 -394.061696) (xy 413.95142 -393.839954) (xy 413.939482 -393.815824)
			(xy 413.934684 -393.80629) (xy 413.918887 -393.79197) (xy 413.89864 -393.785289) (xy 413.877423 -393.787395)
			(xy 413.858884 -393.797926) (xy 413.852106 -393.806172) (xy 413.841164 -393.820254) (xy 413.81498 -393.844457)
			(xy 413.784762 -393.863385) (xy 413.751557 -393.87638) (xy 413.716518 -393.882991) (xy 413.69869 -393.883388)
			(xy 413.698182 -393.883388) (xy 413.691302 -393.883388) (xy 413.677572 -393.882496) (xy 413.67075 -393.88161)
			(xy 413.656272 -393.879324) (xy 413.629602 -393.891008) (xy 413.569912 -393.978892) (xy 413.564928 -393.987047)
			(xy 413.560745 -394.005677) (xy 413.563667 -394.024547) (xy 413.568134 -394.032994) (xy 413.683704 -394.232892)
			(xy 413.696437 -394.25621) (xy 413.714531 -394.306158) (xy 413.723747 -394.358477) (xy 413.724344 -394.385038)
			(xy 413.724344 -394.385292) (xy 413.72383 -394.409281) (xy 413.716326 -394.456669) (xy 413.701502 -394.5023)
			(xy 413.679723 -394.54505) (xy 413.651524 -394.583867) (xy 413.617601 -394.617796) (xy 413.578788 -394.646)
			(xy 413.536041 -394.667785) (xy 413.490412 -394.682616) (xy 413.443025 -394.690127) (xy 413.419036 -394.6906)
			(xy 413.395463 -394.690177) (xy 413.348876 -394.682941) (xy 413.303958 -394.668621) (xy 413.26178 -394.647557)
			(xy 413.223346 -394.620252) (xy 413.189574 -394.587356) (xy 413.161267 -394.549654) (xy 413.149796 -394.529056)
			(xy 413.149288 -394.528294) (xy 413.135826 -394.504926) (xy 413.130464 -394.496458) (xy 413.114568 -394.484272)
			(xy 413.095218 -394.4791) (xy 413.075362 -394.481731) (xy 413.066484 -394.486384) (xy 413.05734 -394.491718)
			(xy 413.051244 -394.5001) (xy 413.040317 -394.514) (xy 413.014234 -394.537865) (xy 412.984208 -394.556527)
			(xy 412.951262 -394.569349) (xy 412.91652 -394.575894) (xy 412.898844 -394.5763) (xy 412.898336 -394.5763)
			(xy 412.879566 -394.575846) (xy 412.842747 -394.568528) (xy 412.808064 -394.554167) (xy 412.776849 -394.533315)
			(xy 412.750303 -394.506773) (xy 412.729446 -394.475561) (xy 412.71508 -394.440879) (xy 412.707757 -394.404062)
			(xy 412.707328 -394.385292) (xy 412.707785 -394.366197) (xy 412.715354 -394.328764) (xy 412.730191 -394.293573)
			(xy 412.751707 -394.262021) (xy 412.779049 -394.235357) (xy 412.811132 -394.21464) (xy 412.82874 -394.207238)
			(xy 412.8389 -394.203174) (xy 412.854394 -394.187426) (xy 412.883604 -394.104114) (xy 412.886834 -394.093536)
			(xy 412.884854 -394.071532) (xy 412.879794 -394.061696) (xy 412.751524 -393.839954) (xy 412.739586 -393.815824)
			(xy 412.734782 -393.806293) (xy 412.718987 -393.791974) (xy 412.698742 -393.785292) (xy 412.677526 -393.787397)
			(xy 412.658988 -393.797927) (xy 412.65221 -393.806172) (xy 412.641283 -393.820233) (xy 412.615143 -393.844409)
			(xy 412.584978 -393.863327) (xy 412.551832 -393.87633) (xy 412.51685 -393.88297) (xy 412.499048 -393.883388)
			(xy 412.49854 -393.883388) (xy 412.470854 -393.881356) (xy 412.4706 -393.881356) (xy 412.46113 -393.880425)
			(xy 412.442618 -393.88475) (xy 412.426966 -393.89554) (xy 412.421324 -393.9032) (xy 412.369762 -393.978892)
			(xy 412.36478 -393.987047) (xy 412.360601 -394.005677) (xy 412.363521 -394.024546) (xy 412.367984 -394.032994)
			(xy 412.483554 -394.232892) (xy 412.49638 -394.256224) (xy 412.514599 -394.306247) (xy 412.523859 -394.358673)
			(xy 412.524448 -394.385292) (xy 412.523931 -394.409268) (xy 412.516436 -394.456632) (xy 412.501627 -394.50224)
			(xy 412.47987 -394.544973) (xy 412.4517 -394.583779) (xy 412.417809 -394.617703) (xy 412.379031 -394.645912)
			(xy 412.33632 -394.667711) (xy 412.290726 -394.682565) (xy 412.24337 -394.690107) (xy 412.219394 -394.6906)
			(xy 412.218886 -394.6906) (xy 412.195312 -394.690217) (xy 412.148723 -394.682974) (xy 412.103804 -394.668646)
			(xy 412.061626 -394.647576) (xy 412.023193 -394.620264) (xy 411.989421 -394.587363) (xy 411.961116 -394.549656)
			(xy 411.949646 -394.529056) (xy 411.949138 -394.528294) (xy 411.935676 -394.504926) (xy 411.930263 -394.496496)
			(xy 411.914386 -394.484309) (xy 411.895053 -394.479128) (xy 411.87521 -394.481742) (xy 411.866334 -394.486384)
			(xy 411.85719 -394.491718) (xy 411.851094 -394.5001) (xy 411.840138 -394.513976) (xy 411.814063 -394.537843)
			(xy 411.784044 -394.556509) (xy 411.751104 -394.569337) (xy 411.716368 -394.57589) (xy 411.698694 -394.5763)
			(xy 411.698186 -394.5763) (xy 411.679411 -394.575816) (xy 411.642583 -394.568496) (xy 411.607887 -394.554137)
			(xy 411.576655 -394.533293) (xy 411.550084 -394.506761) (xy 411.529194 -394.475559) (xy 411.514785 -394.440884)
			(xy 411.507411 -394.404066) (xy 411.506924 -394.385292) (xy 411.507393 -394.366178) (xy 411.514954 -394.328705)
			(xy 411.529814 -394.293484) (xy 411.551378 -394.261919) (xy 411.578787 -394.235271) (xy 411.610946 -394.214603)
			(xy 411.62859 -394.207238) (xy 411.63875 -394.203174) (xy 411.654244 -394.187426) (xy 411.683454 -394.104114)
			(xy 411.686678 -394.093535) (xy 411.6847 -394.071532) (xy 411.679644 -394.061696) (xy 411.551374 -393.839954)
			(xy 411.539436 -393.815824) (xy 411.534562 -393.806334) (xy 411.518787 -393.792021) (xy 411.498562 -393.785336)
			(xy 411.477364 -393.787428) (xy 411.458837 -393.797938) (xy 411.45206 -393.806172) (xy 411.441087 -393.820228)
			(xy 411.414911 -393.844434) (xy 411.3847 -393.863366) (xy 411.351503 -393.876367) (xy 411.31647 -393.882987)
			(xy 411.298644 -393.883388) (xy 411.298136 -393.883388) (xy 411.291256 -393.883382) (xy 411.277527 -393.882494)
			(xy 411.270704 -393.88161) (xy 411.256226 -393.879324) (xy 411.229556 -393.891008) (xy 411.169866 -393.978892)
			(xy 411.164884 -393.987047) (xy 411.160705 -394.005677) (xy 411.163624 -394.024546) (xy 411.168088 -394.032994)
			(xy 411.283658 -394.232892) (xy 411.296484 -394.256224) (xy 411.314704 -394.306247) (xy 411.323963 -394.358673)
			(xy 411.324552 -394.385292) (xy 411.324031 -394.409268) (xy 411.316536 -394.456631) (xy 411.301727 -394.502239)
			(xy 411.279971 -394.544972) (xy 411.251801 -394.583778) (xy 411.217911 -394.617702) (xy 411.179133 -394.645911)
			(xy 411.136423 -394.66771) (xy 411.090829 -394.682564) (xy 411.043474 -394.690107) (xy 411.019498 -394.6906)
			(xy 411.01899 -394.6906) (xy 410.995416 -394.690214) (xy 410.948827 -394.682971) (xy 410.903908 -394.668644)
			(xy 410.86173 -394.647574) (xy 410.823297 -394.620263) (xy 410.789526 -394.587363) (xy 410.76122 -394.549656)
			(xy 410.74975 -394.529056) (xy 410.749242 -394.528294) (xy 410.73578 -394.504926) (xy 410.730363 -394.496499)
			(xy 410.714487 -394.484312) (xy 410.695156 -394.47913) (xy 410.675313 -394.481743) (xy 410.666438 -394.486384)
			(xy 410.657294 -394.491718) (xy 410.651198 -394.5001) (xy 410.64024 -394.513974) (xy 410.614165 -394.537841)
			(xy 410.584147 -394.556507) (xy 410.551208 -394.569336) (xy 410.516472 -394.575889) (xy 410.498798 -394.5763)
			(xy 410.49829 -394.5763) (xy 410.479516 -394.575812) (xy 410.442687 -394.568492) (xy 410.407991 -394.554135)
			(xy 410.376759 -394.533291) (xy 410.350189 -394.506759) (xy 410.329299 -394.475558) (xy 410.31489 -394.440883)
			(xy 410.307516 -394.404066) (xy 410.307028 -394.385292) (xy 410.307494 -394.366177) (xy 410.315056 -394.328705)
			(xy 410.329916 -394.293483) (xy 410.351481 -394.261918) (xy 410.37889 -394.23527) (xy 410.41105 -394.214602)
			(xy 410.428694 -394.207238) (xy 410.438854 -394.203174) (xy 410.454348 -394.187426) (xy 410.483558 -394.104114)
			(xy 410.486781 -394.093535) (xy 410.484804 -394.071532) (xy 410.479748 -394.061696) (xy 410.351478 -393.839954)
			(xy 410.33954 -393.815824) (xy 410.33466 -393.806338) (xy 410.318887 -393.792025) (xy 410.298664 -393.785339)
			(xy 410.277467 -393.78743) (xy 410.258941 -393.797939) (xy 410.252164 -393.806172) (xy 410.241189 -393.820226)
			(xy 410.215013 -393.844432) (xy 410.184803 -393.863364) (xy 410.151606 -393.876366) (xy 410.116574 -393.882986)
			(xy 410.098748 -393.883388) (xy 410.09824 -393.883388) (xy 410.09136 -393.883381) (xy 410.077631 -393.882494)
			(xy 410.070808 -393.88161) (xy 410.05633 -393.879324) (xy 410.02966 -393.891008) (xy 409.96997 -393.978892)
			(xy 409.964987 -393.987047) (xy 409.960808 -394.005677) (xy 409.963728 -394.024546) (xy 409.968192 -394.032994)
			(xy 410.083762 -394.232892) (xy 410.096589 -394.256224) (xy 410.114808 -394.306247) (xy 410.124067 -394.358673)
			(xy 410.124656 -394.385292) (xy 410.124131 -394.409268) (xy 410.116636 -394.45663) (xy 410.101828 -394.502239)
			(xy 410.080072 -394.544971) (xy 410.051902 -394.583776) (xy 410.018012 -394.617701) (xy 409.979235 -394.645909)
			(xy 409.936525 -394.667709) (xy 409.890932 -394.682563) (xy 409.843577 -394.690107) (xy 409.819602 -394.6906)
			(xy 409.819094 -394.6906) (xy 409.79552 -394.690211) (xy 409.748931 -394.682969) (xy 409.704013 -394.668642)
			(xy 409.661834 -394.647573) (xy 409.623401 -394.620262) (xy 409.58963 -394.587362) (xy 409.561324 -394.549656)
			(xy 409.549854 -394.529056) (xy 409.549346 -394.528294) (xy 409.535884 -394.504926) (xy 409.530463 -394.496502)
			(xy 409.514589 -394.484315) (xy 409.495259 -394.479132) (xy 409.475417 -394.481743) (xy 409.466542 -394.486384)
			(xy 409.457398 -394.491718) (xy 409.451302 -394.5001) (xy 409.440342 -394.513972) (xy 409.414268 -394.537839)
			(xy 409.38425 -394.556506) (xy 409.351311 -394.569335) (xy 409.316576 -394.575889) (xy 409.298902 -394.5763)
			(xy 409.298394 -394.5763) (xy 409.27962 -394.575809) (xy 409.242791 -394.568489) (xy 409.208096 -394.554133)
			(xy 409.176864 -394.533289) (xy 409.150293 -394.506758) (xy 409.129403 -394.475557) (xy 409.114994 -394.440883)
			(xy 409.10762 -394.404066) (xy 409.107132 -394.385292) (xy 409.107596 -394.366177) (xy 409.115158 -394.328704)
			(xy 409.130018 -394.293482) (xy 409.151583 -394.261917) (xy 409.178993 -394.235269) (xy 409.211153 -394.214602)
			(xy 409.228798 -394.207238) (xy 409.238958 -394.203174) (xy 409.254452 -394.187426) (xy 409.283662 -394.104114)
			(xy 409.286885 -394.093535) (xy 409.284908 -394.071532) (xy 409.279852 -394.061696) (xy 409.151582 -393.839954)
			(xy 409.139644 -393.815824) (xy 409.134899 -393.806258) (xy 409.119087 -393.791934) (xy 409.098824 -393.785256)
			(xy 409.077594 -393.787372) (xy 409.059047 -393.797917) (xy 409.052268 -393.806172) (xy 409.041308 -393.820205)
			(xy 409.015177 -393.844384) (xy 408.98502 -393.863306) (xy 408.951881 -393.876316) (xy 408.916906 -393.882965)
			(xy 408.899106 -393.883388) (xy 408.898598 -393.883388) (xy 408.870912 -393.881356) (xy 408.870658 -393.881356)
			(xy 408.86119 -393.880392) (xy 408.842674 -393.884731) (xy 408.827022 -393.895534) (xy 408.821382 -393.9032)
			(xy 408.76982 -393.978892) (xy 408.764835 -393.987047) (xy 408.760652 -394.005677) (xy 408.763575 -394.024547)
			(xy 408.768042 -394.032994) (xy 408.883612 -394.232892) (xy 408.896346 -394.25621) (xy 408.914439 -394.306158)
			(xy 408.923655 -394.358477) (xy 408.924252 -394.385038) (xy 408.924252 -394.385292) (xy 408.92373 -394.409281)
			(xy 408.916227 -394.456668) (xy 408.901403 -394.502298) (xy 408.879624 -394.545048) (xy 408.851427 -394.583865)
			(xy 408.817504 -394.617793) (xy 408.778692 -394.645997) (xy 408.735946 -394.667783) (xy 408.690319 -394.682614)
			(xy 408.642933 -394.690126) (xy 408.618944 -394.6906) (xy 408.595371 -394.690171) (xy 408.548785 -394.682936)
			(xy 408.503867 -394.668616) (xy 408.461689 -394.647554) (xy 408.423255 -394.620249) (xy 408.389482 -394.587355)
			(xy 408.361175 -394.549654) (xy 408.349704 -394.529056) (xy 408.349196 -394.528294) (xy 408.335734 -394.504926)
			(xy 408.330363 -394.496464) (xy 408.314471 -394.484278) (xy 408.295124 -394.479105) (xy 408.27527 -394.481733)
			(xy 408.266392 -394.486384) (xy 408.257248 -394.491718) (xy 408.251152 -394.5001) (xy 408.24022 -394.513996)
			(xy 408.214139 -394.537861) (xy 408.184114 -394.556524) (xy 408.151169 -394.569347) (xy 408.116428 -394.575893)
			(xy 408.098752 -394.5763) (xy 408.098244 -394.5763) (xy 408.079475 -394.575839) (xy 408.042656 -394.568522)
			(xy 408.007973 -394.554163) (xy 407.976758 -394.533311) (xy 407.950212 -394.50677) (xy 407.929354 -394.475559)
			(xy 407.914988 -394.440879) (xy 407.907665 -394.404061) (xy 407.907236 -394.385292) (xy 407.907688 -394.366196)
			(xy 407.915258 -394.328763) (xy 407.930095 -394.293572) (xy 407.951612 -394.262019) (xy 407.978955 -394.235356)
			(xy 408.011039 -394.21464) (xy 408.028648 -394.207238) (xy 408.038808 -394.203174) (xy 408.054302 -394.187426)
			(xy 408.083512 -394.104114) (xy 408.086741 -394.093535) (xy 408.084761 -394.071532) (xy 408.079702 -394.061696)
			(xy 407.951432 -393.839954) (xy 407.939494 -393.815824) (xy 407.934679 -393.8063) (xy 407.918887 -393.791981)
			(xy 407.898645 -393.785299) (xy 407.877432 -393.787402) (xy 407.858896 -393.797928) (xy 407.852118 -393.806172)
			(xy 407.841169 -393.820248) (xy 407.814987 -393.844452) (xy 407.78477 -393.863381) (xy 407.751567 -393.876377)
			(xy 407.71653 -393.88299) (xy 407.698702 -393.883388) (xy 407.698194 -393.883388) (xy 407.691314 -393.883386)
			(xy 407.677584 -393.882496) (xy 407.670762 -393.88161) (xy 407.656284 -393.879324) (xy 407.629614 -393.891008)
			(xy 407.569924 -393.978892) (xy 407.564939 -393.987047) (xy 407.560755 -394.005677) (xy 407.563678 -394.024547)
			(xy 407.568146 -394.032994) (xy 407.683716 -394.232892) (xy 407.69645 -394.256209) (xy 407.714543 -394.306158)
			(xy 407.723759 -394.358477) (xy 407.724356 -394.385038) (xy 407.724356 -394.385292) (xy 407.72383 -394.409281)
			(xy 407.716327 -394.456667) (xy 407.701503 -394.502297) (xy 407.679725 -394.545047) (xy 407.651528 -394.583863)
			(xy 407.617606 -394.617791) (xy 407.578794 -394.645996) (xy 407.536049 -394.667782) (xy 407.490422 -394.682614)
			(xy 407.443037 -394.690126) (xy 407.419048 -394.6906) (xy 407.395475 -394.690168) (xy 407.348889 -394.682933)
			(xy 407.303971 -394.668614) (xy 407.261793 -394.647552) (xy 407.223359 -394.620248) (xy 407.189586 -394.587354)
			(xy 407.161279 -394.549654) (xy 407.149808 -394.529056) (xy 407.1493 -394.528294) (xy 407.135838 -394.504926)
			(xy 407.130463 -394.496467) (xy 407.114572 -394.484281) (xy 407.095226 -394.479107) (xy 407.075374 -394.481734)
			(xy 407.066496 -394.486384) (xy 407.057352 -394.491718) (xy 407.051256 -394.5001) (xy 407.040322 -394.513994)
			(xy 407.014241 -394.537859) (xy 406.984216 -394.556522) (xy 406.951272 -394.569346) (xy 406.916532 -394.575893)
			(xy 406.898856 -394.5763) (xy 406.898348 -394.5763) (xy 406.879579 -394.575835) (xy 406.84276 -394.56852)
			(xy 406.808077 -394.55416) (xy 406.776862 -394.53331) (xy 406.750316 -394.506769) (xy 406.729458 -394.475558)
			(xy 406.715092 -394.440878) (xy 406.707769 -394.404061) (xy 406.70734 -394.385292) (xy 406.707789 -394.366196)
			(xy 406.715359 -394.328763) (xy 406.730197 -394.293571) (xy 406.751715 -394.262018) (xy 406.779058 -394.235355)
			(xy 406.811143 -394.21464) (xy 406.828752 -394.207238) (xy 406.838912 -394.203174) (xy 406.854406 -394.187426)
			(xy 406.883616 -394.104114) (xy 406.886845 -394.093535) (xy 406.884865 -394.071532) (xy 406.879806 -394.061696)
			(xy 406.751536 -393.839954) (xy 406.739598 -393.815824) (xy 406.734777 -393.806303) (xy 406.718987 -393.791985)
			(xy 406.698746 -393.785303) (xy 406.677535 -393.787404) (xy 406.659 -393.797929) (xy 406.652222 -393.806172)
			(xy 406.641288 -393.820227) (xy 406.61515 -393.844404) (xy 406.584987 -393.863322) (xy 406.551842 -393.876327)
			(xy 406.516862 -393.882969) (xy 406.49906 -393.883388) (xy 406.498552 -393.883388) (xy 406.470866 -393.881356)
			(xy 406.470612 -393.881356) (xy 406.461141 -393.880435) (xy 406.44263 -393.884755) (xy 406.426978 -393.895541)
			(xy 406.421336 -393.9032) (xy 406.369774 -393.978892) (xy 406.364791 -393.987047) (xy 406.360611 -394.005677)
			(xy 406.363532 -394.024546) (xy 406.367996 -394.032994) (xy 406.483566 -394.232892) (xy 406.496393 -394.256223)
			(xy 406.514612 -394.306247) (xy 406.523871 -394.358673) (xy 406.52446 -394.385292) (xy 406.524031 -394.409273)
			(xy 406.516532 -394.456644) (xy 406.501719 -394.502261) (xy 406.479954 -394.544999) (xy 406.451774 -394.583809)
			(xy 406.417872 -394.617735) (xy 406.379082 -394.645942) (xy 406.336359 -394.667737) (xy 406.290753 -394.682582)
			(xy 406.243386 -394.690114) (xy 406.219406 -394.6906) (xy 406.218898 -394.6906) (xy 406.195324 -394.690208)
			(xy 406.148736 -394.682966) (xy 406.103817 -394.66864) (xy 406.061639 -394.647571) (xy 406.023206 -394.620261)
			(xy 405.989434 -394.587361) (xy 405.961128 -394.549656) (xy 405.949658 -394.529056) (xy 405.94915 -394.528294)
			(xy 405.935688 -394.504926) (xy 405.930263 -394.496504) (xy 405.91439 -394.484318) (xy 405.895061 -394.479134)
			(xy 405.875221 -394.481744) (xy 405.866346 -394.486384) (xy 405.857202 -394.491718) (xy 405.851106 -394.5001)
			(xy 405.8402 -394.514018) (xy 405.814112 -394.537881) (xy 405.784081 -394.55654) (xy 405.75113 -394.569358)
			(xy 405.716384 -394.575897) (xy 405.698706 -394.5763) (xy 405.698198 -394.5763) (xy 405.679424 -394.575805)
			(xy 405.642596 -394.568486) (xy 405.6079 -394.55413) (xy 405.576668 -394.533287) (xy 405.550097 -394.506757)
			(xy 405.529207 -394.475556) (xy 405.514798 -394.440883) (xy 405.507424 -394.404065) (xy 405.506936 -394.385292)
			(xy 405.507397 -394.366177) (xy 405.514959 -394.328704) (xy 405.52982 -394.293482) (xy 405.551386 -394.261917)
			(xy 405.578796 -394.235269) (xy 405.610957 -394.214602) (xy 405.628602 -394.207238) (xy 405.638762 -394.203174)
			(xy 405.654256 -394.187426) (xy 405.683466 -394.104114) (xy 405.686689 -394.093535) (xy 405.684711 -394.071532)
			(xy 405.679656 -394.061696) (xy 405.551386 -393.839954) (xy 405.539448 -393.815824) (xy 405.534698 -393.806262)
			(xy 405.518887 -393.791938) (xy 405.498626 -393.785259) (xy 405.477397 -393.787374) (xy 405.458851 -393.797918)
			(xy 405.452072 -393.806172) (xy 405.44115 -393.82027) (xy 405.414961 -393.844472) (xy 405.384738 -393.863397)
			(xy 405.351528 -393.876388) (xy 405.316486 -393.882994) (xy 405.298656 -393.883388) (xy 405.298148 -393.883388)
			(xy 405.291268 -393.883381) (xy 405.277539 -393.882494) (xy 405.270716 -393.88161) (xy 405.256238 -393.879324)
			(xy 405.229568 -393.891008) (xy 405.169878 -393.978892) (xy 405.164895 -393.987047) (xy 405.160715 -394.005677)
			(xy 405.163635 -394.024546) (xy 405.1681 -394.032994) (xy 405.28367 -394.232892) (xy 405.296497 -394.256223)
			(xy 405.314716 -394.306247) (xy 405.323975 -394.358673) (xy 405.324564 -394.385292) (xy 405.324131 -394.409273)
			(xy 405.316633 -394.456644) (xy 405.301819 -394.50226) (xy 405.280055 -394.544998) (xy 405.251875 -394.583808)
			(xy 405.217974 -394.617733) (xy 405.179184 -394.645941) (xy 405.136461 -394.667735) (xy 405.090856 -394.682581)
			(xy 405.04349 -394.690114) (xy 405.01951 -394.6906) (xy 405.019002 -394.6906) (xy 404.995428 -394.690205)
			(xy 404.94884 -394.682963) (xy 404.903921 -394.668638) (xy 404.861743 -394.64757) (xy 404.82331 -394.62026)
			(xy 404.789538 -394.587361) (xy 404.761233 -394.549656) (xy 404.749762 -394.529056) (xy 404.749254 -394.528294)
			(xy 404.735792 -394.504926) (xy 404.730363 -394.496507) (xy 404.714491 -394.484321) (xy 404.695164 -394.479137)
			(xy 404.675325 -394.481745) (xy 404.66645 -394.486384) (xy 404.657306 -394.491718) (xy 404.65121 -394.5001)
			(xy 404.640302 -394.514016) (xy 404.614215 -394.537879) (xy 404.584183 -394.556539) (xy 404.551233 -394.569357)
			(xy 404.516487 -394.575897) (xy 404.49881 -394.5763) (xy 404.498302 -394.5763) (xy 404.479528 -394.575802)
			(xy 404.4427 -394.568484) (xy 404.408004 -394.554128) (xy 404.376772 -394.533286) (xy 404.350201 -394.506756)
			(xy 404.329311 -394.475555) (xy 404.314902 -394.440882) (xy 404.307528 -394.404065) (xy 404.30704 -394.385292)
			(xy 404.307499 -394.366177) (xy 404.315061 -394.328703) (xy 404.329922 -394.293481) (xy 404.351488 -394.261916)
			(xy 404.378899 -394.235268) (xy 404.411061 -394.214602) (xy 404.428706 -394.207238) (xy 404.438866 -394.203174)
			(xy 404.45436 -394.187426) (xy 404.48357 -394.104114) (xy 404.486792 -394.093534) (xy 404.484815 -394.071533)
			(xy 404.47976 -394.061696) (xy 404.35149 -393.839954) (xy 404.339552 -393.815824) (xy 404.334796 -393.806265)
			(xy 404.318987 -393.791942) (xy 404.298727 -393.785263) (xy 404.2775 -393.787376) (xy 404.258955 -393.797919)
			(xy 404.252176 -393.806172) (xy 404.241251 -393.820268) (xy 404.215063 -393.844471) (xy 404.18484 -393.863396)
			(xy 404.151632 -393.876387) (xy 404.11659 -393.882994) (xy 404.09876 -393.883388) (xy 404.098252 -393.883388)
			(xy 404.091372 -393.88338) (xy 404.077643 -393.882493) (xy 404.07082 -393.88161) (xy 404.056342 -393.879324)
			(xy 404.029672 -393.891008) (xy 403.969982 -393.978892) (xy 403.964999 -393.987047) (xy 403.960819 -394.005677)
			(xy 403.96374 -394.024546) (xy 403.968204 -394.032994) (xy 404.083774 -394.232892) (xy 404.096601 -394.256223)
			(xy 404.11482 -394.306247) (xy 404.124079 -394.358673) (xy 404.124668 -394.385292) (xy 404.124231 -394.409272)
			(xy 404.116733 -394.456643) (xy 404.101919 -394.502259) (xy 404.080155 -394.544997) (xy 404.051976 -394.583806)
			(xy 404.018075 -394.617732) (xy 403.979287 -394.645939) (xy 403.936564 -394.667734) (xy 403.890959 -394.682581)
			(xy 403.843594 -394.690113) (xy 403.819614 -394.6906) (xy 403.819106 -394.6906) (xy 403.795532 -394.690201)
			(xy 403.748944 -394.682961) (xy 403.704026 -394.668636) (xy 403.661847 -394.647568) (xy 403.623414 -394.620259)
			(xy 403.589642 -394.58736) (xy 403.561337 -394.549655) (xy 403.549866 -394.529056) (xy 403.549358 -394.528294)
			(xy 403.535896 -394.504926) (xy 403.530564 -394.496436) (xy 403.514657 -394.48425) (xy 403.495297 -394.479084)
			(xy 403.475434 -394.481725) (xy 403.466554 -394.486384) (xy 403.45741 -394.491718) (xy 403.451314 -394.5001)
			(xy 403.440404 -394.514014) (xy 403.414317 -394.537878) (xy 403.384286 -394.556537) (xy 403.351337 -394.569356)
			(xy 403.316591 -394.575897) (xy 403.298914 -394.5763) (xy 403.298406 -394.5763) (xy 403.279632 -394.575798)
			(xy 403.242804 -394.568481) (xy 403.208109 -394.554126) (xy 403.176877 -394.533284) (xy 403.150306 -394.506754)
			(xy 403.129415 -394.475555) (xy 403.115006 -394.440882) (xy 403.107632 -394.404065) (xy 403.107144 -394.385292)
			(xy 403.1076 -394.366177) (xy 403.115163 -394.328703) (xy 403.130024 -394.29348) (xy 403.151591 -394.261915)
			(xy 403.179002 -394.235268) (xy 403.211164 -394.214601) (xy 403.22881 -394.207238) (xy 403.23897 -394.203174)
			(xy 403.254464 -394.187426) (xy 403.283674 -394.104114) (xy 403.286896 -394.093534) (xy 403.284919 -394.071533)
			(xy 403.279864 -394.061696) (xy 403.151594 -393.839954) (xy 403.139656 -393.815824) (xy 403.134894 -393.806268)
			(xy 403.119087 -393.791946) (xy 403.098829 -393.785266) (xy 403.077603 -393.787379) (xy 403.059059 -393.79792)
			(xy 403.05228 -393.806172) (xy 403.04137 -393.820247) (xy 403.015226 -393.844422) (xy 402.985057 -393.863337)
			(xy 402.951906 -393.876337) (xy 402.916922 -393.882972) (xy 402.899118 -393.883388) (xy 402.89861 -393.883388)
			(xy 402.878583 -393.882942) (xy 402.839403 -393.874616) (xy 402.80281 -393.858326) (xy 402.770405 -393.834783)
			(xy 402.743602 -393.805018) (xy 402.723574 -393.77033) (xy 402.711196 -393.732235) (xy 402.707009 -393.6924)
			(xy 389.243584 -393.6924) (xy 389.55599 -394.232892) (xy 389.568819 -394.256222) (xy 389.587037 -394.306246)
			(xy 389.596295 -394.358673) (xy 389.596884 -394.385292) (xy 389.596431 -394.409272) (xy 389.588933 -394.456641)
			(xy 389.574121 -394.502255) (xy 389.552358 -394.544992) (xy 389.524181 -394.583801) (xy 389.490282 -394.617726)
			(xy 389.451496 -394.645934) (xy 389.408775 -394.66773) (xy 389.363173 -394.682578) (xy 389.315809 -394.690112)
			(xy 389.29183 -394.6906) (xy 389.291322 -394.6906) (xy 389.267749 -394.690188) (xy 389.221161 -394.68295)
			(xy 389.176243 -394.668628) (xy 389.134065 -394.647562) (xy 389.095631 -394.620255) (xy 389.061859 -394.587358)
			(xy 389.033553 -394.549655) (xy 389.022082 -394.529056) (xy 389.021574 -394.528294) (xy 389.008112 -394.504926)
			(xy 389.002764 -394.496448) (xy 388.986863 -394.484261) (xy 388.967508 -394.479092) (xy 388.947649 -394.481728)
			(xy 388.93877 -394.486384) (xy 388.929626 -394.491718) (xy 388.92353 -394.5001) (xy 388.912611 -394.514006)
			(xy 388.886526 -394.537871) (xy 388.856498 -394.556532) (xy 388.82355 -394.569352) (xy 388.788807 -394.575895)
			(xy 388.77113 -394.5763) (xy 388.770622 -394.5763) (xy 388.751849 -394.575783) (xy 388.715021 -394.568469)
			(xy 388.680326 -394.554117) (xy 388.649094 -394.533277) (xy 388.622522 -394.50675) (xy 388.601632 -394.475552)
			(xy 388.587222 -394.44088) (xy 388.579848 -394.404065) (xy 388.57936 -394.385292) (xy 388.579806 -394.366176)
			(xy 388.587369 -394.328701) (xy 388.602232 -394.293478) (xy 388.623801 -394.261912) (xy 388.651215 -394.235265)
			(xy 388.683379 -394.2146) (xy 388.701026 -394.207238) (xy 388.711186 -394.203174) (xy 388.72668 -394.187426)
			(xy 388.75589 -394.104114) (xy 388.759121 -394.093536) (xy 388.757141 -394.071531) (xy 388.75208 -394.061696)
			(xy 388.62381 -393.839954) (xy 388.611618 -393.81557) (xy 388.606767 -393.806064) (xy 388.590989 -393.791737)
			(xy 388.570754 -393.785048) (xy 388.549546 -393.787147) (xy 388.531016 -393.797674) (xy 388.524242 -393.805918)
			(xy 388.513287 -393.820005) (xy 388.487129 -393.844267) (xy 388.456922 -393.863254) (xy 388.423716 -393.876306)
			(xy 388.388665 -393.882968) (xy 388.370826 -393.883388) (xy 388.370318 -393.883388) (xy 388.363438 -393.883384)
			(xy 388.349708 -393.882495) (xy 388.342886 -393.88161) (xy 388.328408 -393.879324) (xy 388.301738 -393.891008)
			(xy 388.242048 -393.978892) (xy 388.237062 -393.987047) (xy 388.232876 -394.005677) (xy 388.235801 -394.024547)
			(xy 388.24027 -394.032994) (xy 388.35584 -394.232892) (xy 388.368576 -394.256208) (xy 388.386668 -394.306157)
			(xy 388.395883 -394.358476) (xy 388.39648 -394.385038) (xy 388.39648 -394.385292) (xy 388.396054 -394.409286)
			(xy 388.388548 -394.456684) (xy 388.373719 -394.502324) (xy 388.351932 -394.545082) (xy 388.323724 -394.583905)
			(xy 388.28979 -394.617837) (xy 388.250965 -394.646042) (xy 388.208206 -394.667826) (xy 388.162565 -394.682653)
			(xy 388.115166 -394.690156) (xy 388.091172 -394.6906) (xy 388.067597 -394.690229) (xy 388.021008 -394.682983)
			(xy 387.976089 -394.668653) (xy 387.93391 -394.647581) (xy 387.895478 -394.620268) (xy 387.861707 -394.587365)
			(xy 387.833402 -394.549657) (xy 387.821932 -394.529056) (xy 387.821424 -394.528294) (xy 387.807962 -394.504926)
			(xy 387.802563 -394.496485) (xy 387.786681 -394.484299) (xy 387.767343 -394.47912) (xy 387.747496 -394.481739)
			(xy 387.73862 -394.486384) (xy 387.729476 -394.491718) (xy 387.72338 -394.5001) (xy 387.712432 -394.513983)
			(xy 387.686355 -394.537849) (xy 387.656334 -394.556514) (xy 387.623393 -394.56934) (xy 387.588655 -394.575891)
			(xy 387.57098 -394.5763) (xy 387.570472 -394.5763) (xy 387.551703 -394.575873) (xy 387.514888 -394.568545)
			(xy 387.480209 -394.554176) (xy 387.449 -394.533318) (xy 387.422459 -394.506772) (xy 387.401607 -394.475559)
			(xy 387.387244 -394.440878) (xy 387.379923 -394.404061) (xy 387.379464 -394.385292) (xy 387.379898 -394.366195)
			(xy 387.387469 -394.32876) (xy 387.402309 -394.293567) (xy 387.42383 -394.262014) (xy 387.451177 -394.235352)
			(xy 387.483265 -394.214638) (xy 387.500876 -394.207238) (xy 387.511036 -394.203174) (xy 387.52653 -394.187426)
			(xy 387.55574 -394.104114) (xy 387.558966 -394.093535) (xy 387.556987 -394.071532) (xy 387.55193 -394.061696)
			(xy 387.42366 -393.839954) (xy 387.411722 -393.815824) (xy 387.406867 -393.806323) (xy 387.391087 -393.792008)
			(xy 387.370856 -393.785324) (xy 387.349654 -393.787419) (xy 387.331123 -393.797935) (xy 387.324346 -393.806172)
			(xy 387.313381 -393.820235) (xy 387.287203 -393.84444) (xy 387.25699 -393.863371) (xy 387.223791 -393.87637)
			(xy 387.188757 -393.882988) (xy 387.17093 -393.883388) (xy 387.170422 -393.883388) (xy 387.163542 -393.883383)
			(xy 387.149812 -393.882495) (xy 387.14299 -393.88161) (xy 387.128512 -393.879324) (xy 387.101842 -393.891008)
			(xy 387.042152 -393.978892) (xy 387.03717 -393.987047) (xy 387.032992 -394.005677) (xy 387.035911 -394.024546)
			(xy 387.040374 -394.032994) (xy 387.155944 -394.232892) (xy 387.16868 -394.256208) (xy 387.186772 -394.306157)
			(xy 387.195988 -394.358476) (xy 387.196584 -394.385038) (xy 387.196584 -394.385292) (xy 387.196154 -394.409286)
			(xy 387.188648 -394.456684) (xy 387.173819 -394.502323) (xy 387.152033 -394.545081) (xy 387.123825 -394.583904)
			(xy 387.089892 -394.617836) (xy 387.051067 -394.646041) (xy 387.008308 -394.667825) (xy 386.962668 -394.682652)
			(xy 386.91527 -394.690156) (xy 386.891276 -394.6906) (xy 386.867701 -394.690226) (xy 386.821112 -394.68298)
			(xy 386.776193 -394.668651) (xy 386.734015 -394.647579) (xy 386.695582 -394.620267) (xy 386.661811 -394.587365)
			(xy 386.633506 -394.549657) (xy 386.622036 -394.529056) (xy 386.621528 -394.528294) (xy 386.608066 -394.504926)
			(xy 386.602663 -394.496488) (xy 386.586782 -394.484302) (xy 386.567446 -394.479122) (xy 386.5476 -394.48174)
			(xy 386.538724 -394.486384) (xy 386.52958 -394.491718) (xy 386.523484 -394.5001) (xy 386.512534 -394.513981)
			(xy 386.486457 -394.537847) (xy 386.456437 -394.556512) (xy 386.423496 -394.569339) (xy 386.388758 -394.575891)
			(xy 386.371084 -394.5763) (xy 386.370576 -394.5763) (xy 386.351807 -394.57587) (xy 386.314992 -394.568542)
			(xy 386.280314 -394.554174) (xy 386.249104 -394.533316) (xy 386.222564 -394.506771) (xy 386.201711 -394.475558)
			(xy 386.187348 -394.440877) (xy 386.180027 -394.404061) (xy 386.179568 -394.385292) (xy 386.18 -394.366195)
			(xy 386.187571 -394.328759) (xy 386.202411 -394.293567) (xy 386.223932 -394.262013) (xy 386.25128 -394.235351)
			(xy 386.283369 -394.214638) (xy 386.30098 -394.207238) (xy 386.31114 -394.203174) (xy 386.326634 -394.187426)
			(xy 386.355844 -394.104114) (xy 386.359069 -394.093535) (xy 386.357091 -394.071532) (xy 386.352034 -394.061696)
			(xy 386.223764 -393.839954) (xy 386.211826 -393.815824) (xy 386.206966 -393.806326) (xy 386.191187 -393.792012)
			(xy 386.170958 -393.785327) (xy 386.149757 -393.787422) (xy 386.131227 -393.797936) (xy 386.12445 -393.806172)
			(xy 386.1135 -393.820214) (xy 386.087366 -393.844392) (xy 386.057207 -393.863312) (xy 386.024066 -393.87632)
			(xy 385.989089 -393.882966) (xy 385.971288 -393.883388) (xy 385.97078 -393.883388) (xy 385.943094 -393.881356)
			(xy 385.94284 -393.881356) (xy 385.933372 -393.880377) (xy 385.914854 -393.884723) (xy 385.899203 -393.895531)
			(xy 385.893564 -393.9032) (xy 385.842002 -393.978892) (xy 385.837018 -393.987047) (xy 385.832836 -394.005677)
			(xy 385.835758 -394.024547) (xy 385.840224 -394.032994) (xy 385.955794 -394.232892) (xy 385.968623 -394.256222)
			(xy 385.986841 -394.306246) (xy 385.996099 -394.358673) (xy 385.996688 -394.385292) (xy 385.996231 -394.409271)
			(xy 385.988733 -394.45664) (xy 385.973921 -394.502254) (xy 385.952159 -394.544991) (xy 385.923982 -394.5838)
			(xy 385.890084 -394.617725) (xy 385.851298 -394.645932) (xy 385.808578 -394.667728) (xy 385.762976 -394.682577)
			(xy 385.715613 -394.690112) (xy 385.691634 -394.6906) (xy 385.691126 -394.6906) (xy 385.667553 -394.690185)
			(xy 385.620965 -394.682948) (xy 385.576047 -394.668626) (xy 385.533869 -394.64756) (xy 385.495436 -394.620254)
			(xy 385.461663 -394.587357) (xy 385.433357 -394.549655) (xy 385.421886 -394.529056) (xy 385.421378 -394.528294)
			(xy 385.407916 -394.504926) (xy 385.402564 -394.496451) (xy 385.386665 -394.484264) (xy 385.367311 -394.479095)
			(xy 385.347453 -394.481729) (xy 385.338574 -394.486384) (xy 385.32943 -394.491718) (xy 385.323334 -394.5001)
			(xy 385.312412 -394.514004) (xy 385.286328 -394.537869) (xy 385.256301 -394.55653) (xy 385.223353 -394.569351)
			(xy 385.18861 -394.575895) (xy 385.170934 -394.5763) (xy 385.170426 -394.5763) (xy 385.151653 -394.57578)
			(xy 385.114826 -394.568466) (xy 385.08013 -394.554115) (xy 385.048898 -394.533276) (xy 385.022327 -394.506748)
			(xy 385.001436 -394.475551) (xy 384.987026 -394.440879) (xy 384.979652 -394.404064) (xy 384.979164 -394.385292)
			(xy 384.979608 -394.366176) (xy 384.987171 -394.328701) (xy 385.002034 -394.293477) (xy 385.023603 -394.261911)
			(xy 385.051018 -394.235265) (xy 385.083183 -394.2146) (xy 385.10083 -394.207238) (xy 385.11099 -394.203174)
			(xy 385.126484 -394.187426) (xy 385.155694 -394.104114) (xy 385.158925 -394.093536) (xy 385.156945 -394.071531)
			(xy 385.151884 -394.061696) (xy 385.023614 -393.839954) (xy 385.011676 -393.815824) (xy 385.006886 -393.806285)
			(xy 384.991087 -393.791965) (xy 384.970837 -393.785284) (xy 384.949619 -393.787391) (xy 384.931079 -393.797924)
			(xy 384.9243 -393.806172) (xy 384.913362 -393.820256) (xy 384.887177 -393.84446) (xy 384.856958 -393.863387)
			(xy 384.823752 -393.876382) (xy 384.788713 -393.882992) (xy 384.770884 -393.883388) (xy 384.770376 -393.883388)
			(xy 384.763496 -393.883388) (xy 384.749766 -393.882496) (xy 384.742944 -393.88161) (xy 384.728466 -393.879324)
			(xy 384.701796 -393.891008) (xy 384.642106 -393.978892) (xy 384.637122 -393.987047) (xy 384.63294 -394.005677)
			(xy 384.635862 -394.024547) (xy 384.640328 -394.032994) (xy 384.755898 -394.232892) (xy 384.768719 -394.256226)
			(xy 384.786942 -394.306248) (xy 384.796203 -394.358674) (xy 384.796792 -394.385292) (xy 384.796331 -394.409271)
			(xy 384.788834 -394.45664) (xy 384.774022 -394.502253) (xy 384.75226 -394.54499) (xy 384.724083 -394.583798)
			(xy 384.690186 -394.617723) (xy 384.6514 -394.645931) (xy 384.608681 -394.667727) (xy 384.563079 -394.682576)
			(xy 384.515717 -394.690112) (xy 384.491738 -394.6906) (xy 384.49123 -394.6906) (xy 384.467657 -394.690182)
			(xy 384.42107 -394.682945) (xy 384.376152 -394.668624) (xy 384.333973 -394.647559) (xy 384.29554 -394.620253)
			(xy 384.261768 -394.587357) (xy 384.233461 -394.549654) (xy 384.22199 -394.529056) (xy 384.221482 -394.528294)
			(xy 384.20802 -394.504926) (xy 384.202664 -394.496454) (xy 384.186766 -394.484267) (xy 384.167414 -394.479097)
			(xy 384.147556 -394.48173) (xy 384.138678 -394.486384) (xy 384.129534 -394.491718) (xy 384.123438 -394.5001)
			(xy 384.112514 -394.514002) (xy 384.086431 -394.537867) (xy 384.056404 -394.556529) (xy 384.023457 -394.56935)
			(xy 383.988714 -394.575895) (xy 383.971038 -394.5763) (xy 383.97053 -394.5763) (xy 383.951757 -394.575776)
			(xy 383.91493 -394.568463) (xy 383.880235 -394.554112) (xy 383.849002 -394.533274) (xy 383.822431 -394.506747)
			(xy 383.80154 -394.47555) (xy 383.78713 -394.440879) (xy 383.779756 -394.404064) (xy 383.779268 -394.385292)
			(xy 383.779709 -394.366176) (xy 383.787272 -394.3287) (xy 383.802136 -394.293476) (xy 383.823706 -394.261911)
			(xy 383.851121 -394.235264) (xy 383.883287 -394.2146) (xy 383.900934 -394.207238) (xy 383.911094 -394.203174)
			(xy 383.926588 -394.187426) (xy 383.955798 -394.104114) (xy 383.959028 -394.093536) (xy 383.957048 -394.071531)
			(xy 383.951988 -394.061696) (xy 383.823718 -393.839954) (xy 383.81178 -393.815824) (xy 383.806984 -393.806288)
			(xy 383.791187 -393.791968) (xy 383.770939 -393.785287) (xy 383.749722 -393.787394) (xy 383.731182 -393.797925)
			(xy 383.724404 -393.806172) (xy 383.713463 -393.820255) (xy 383.687279 -393.844458) (xy 383.65706 -393.863386)
			(xy 383.623855 -393.876381) (xy 383.588817 -393.882992) (xy 383.570988 -393.883388) (xy 383.57048 -393.883388)
			(xy 383.5636 -393.883388) (xy 383.54987 -393.882496) (xy 383.543048 -393.88161) (xy 383.52857 -393.879324)
			(xy 383.5019 -393.891008) (xy 383.44221 -393.978892) (xy 383.437226 -393.987047) (xy 383.433043 -394.005677)
			(xy 383.435965 -394.024547) (xy 383.440432 -394.032994) (xy 383.556002 -394.232892) (xy 383.568824 -394.256226)
			(xy 383.587046 -394.306248) (xy 383.596307 -394.358674) (xy 383.596896 -394.385292) (xy 383.596431 -394.409271)
			(xy 383.588934 -394.456639) (xy 383.574122 -394.502252) (xy 383.552361 -394.544989) (xy 383.524185 -394.583797)
			(xy 383.490287 -394.617722) (xy 383.451502 -394.64593) (xy 383.408784 -394.667726) (xy 383.363183 -394.682575)
			(xy 383.315821 -394.690111) (xy 383.291842 -394.6906) (xy 383.291334 -394.6906) (xy 383.267761 -394.690179)
			(xy 383.221174 -394.682942) (xy 383.176256 -394.668622) (xy 383.134078 -394.647557) (xy 383.095644 -394.620252)
			(xy 383.061872 -394.587356) (xy 383.033565 -394.549654) (xy 383.022094 -394.529056) (xy 383.021586 -394.528294)
			(xy 383.008124 -394.504926) (xy 383.002764 -394.496456) (xy 382.986867 -394.48427) (xy 382.967517 -394.479099)
			(xy 382.94766 -394.481731) (xy 382.938782 -394.486384) (xy 382.929638 -394.491718) (xy 382.923542 -394.5001)
			(xy 382.912616 -394.514001) (xy 382.886533 -394.537866) (xy 382.856506 -394.556527) (xy 382.82356 -394.569349)
			(xy 382.788818 -394.575894) (xy 382.771142 -394.5763) (xy 382.770634 -394.5763) (xy 382.751861 -394.575773)
			(xy 382.715034 -394.568461) (xy 382.680339 -394.55411) (xy 382.649107 -394.533272) (xy 382.622535 -394.506746)
			(xy 382.601644 -394.475549) (xy 382.587234 -394.440879) (xy 382.57986 -394.404064) (xy 382.579372 -394.385292)
			(xy 382.57981 -394.366176) (xy 382.587374 -394.3287) (xy 382.602238 -394.293476) (xy 382.623808 -394.26191)
			(xy 382.651224 -394.235263) (xy 382.68339 -394.2146) (xy 382.701038 -394.207238) (xy 382.711198 -394.203174)
			(xy 382.726692 -394.187426) (xy 382.755902 -394.104114) (xy 382.759132 -394.093536) (xy 382.757152 -394.071531)
			(xy 382.752092 -394.061696) (xy 382.623822 -393.839954) (xy 382.611884 -393.815824) (xy 382.607083 -393.806291)
			(xy 382.591287 -393.791972) (xy 382.571041 -393.785291) (xy 382.549825 -393.787396) (xy 382.531286 -393.797926)
			(xy 382.524508 -393.806172) (xy 382.513582 -393.820234) (xy 382.487442 -393.84441) (xy 382.457277 -393.863327)
			(xy 382.42413 -393.876331) (xy 382.389149 -393.88297) (xy 382.371346 -393.883388) (xy 382.370838 -393.883388)
			(xy 382.343152 -393.881356) (xy 382.342898 -393.881356) (xy 382.333428 -393.880424) (xy 382.314916 -393.884749)
			(xy 382.299263 -393.895539) (xy 382.293622 -393.9032) (xy 382.24206 -393.978892) (xy 382.237078 -393.987047)
			(xy 382.232899 -394.005677) (xy 382.235819 -394.024546) (xy 382.240282 -394.032994) (xy 382.355852 -394.232892)
			(xy 382.368589 -394.256208) (xy 382.386681 -394.306157) (xy 382.395896 -394.358476) (xy 382.396492 -394.385038)
			(xy 382.396492 -394.385292) (xy 382.396054 -394.409286) (xy 382.388548 -394.456682) (xy 382.37372 -394.502321)
			(xy 382.351934 -394.545079) (xy 382.323728 -394.583901) (xy 382.289795 -394.617833) (xy 382.250972 -394.646038)
			(xy 382.208214 -394.667823) (xy 382.162575 -394.68265) (xy 382.115178 -394.690155) (xy 382.091184 -394.6906)
			(xy 382.06761 -394.690219) (xy 382.021021 -394.682975) (xy 381.976102 -394.668647) (xy 381.933923 -394.647576)
			(xy 381.895491 -394.620265) (xy 381.861719 -394.587363) (xy 381.833414 -394.549656) (xy 381.821944 -394.529056)
			(xy 381.821436 -394.528294) (xy 381.807974 -394.504926) (xy 381.802563 -394.496494) (xy 381.786685 -394.484307)
			(xy 381.767352 -394.479127) (xy 381.747508 -394.481741) (xy 381.738632 -394.486384) (xy 381.729488 -394.491718)
			(xy 381.723392 -394.5001) (xy 381.712438 -394.513977) (xy 381.686362 -394.537844) (xy 381.656342 -394.556509)
			(xy 381.623403 -394.569337) (xy 381.588666 -394.57589) (xy 381.570992 -394.5763) (xy 381.570484 -394.5763)
			(xy 381.551716 -394.575862) (xy 381.514901 -394.568536) (xy 381.480222 -394.554169) (xy 381.449013 -394.533313)
			(xy 381.422472 -394.506769) (xy 381.401619 -394.475557) (xy 381.387257 -394.440876) (xy 381.379935 -394.40406)
			(xy 381.379476 -394.385292) (xy 381.379903 -394.366195) (xy 381.387474 -394.328758) (xy 381.402315 -394.293565)
			(xy 381.423837 -394.262012) (xy 381.451186 -394.23535) (xy 381.483277 -394.214637) (xy 381.500888 -394.207238)
			(xy 381.511048 -394.203174) (xy 381.526542 -394.187426) (xy 381.555752 -394.104114) (xy 381.558976 -394.093535)
			(xy 381.556998 -394.071532) (xy 381.551942 -394.061696) (xy 381.423672 -393.839954) (xy 381.411734 -393.815824)
			(xy 381.406862 -393.806333) (xy 381.391087 -393.792019) (xy 381.370861 -393.785334) (xy 381.349663 -393.787427)
			(xy 381.331135 -393.797937) (xy 381.324358 -393.806172) (xy 381.313386 -393.820229) (xy 381.28721 -393.844435)
			(xy 381.256999 -393.863366) (xy 381.223801 -393.876367) (xy 381.188768 -393.882987) (xy 381.170942 -393.883388)
			(xy 381.170434 -393.883388) (xy 381.163554 -393.883382) (xy 381.149825 -393.882494) (xy 381.143002 -393.88161)
			(xy 381.128524 -393.879324) (xy 381.101854 -393.891008) (xy 381.042164 -393.978892) (xy 381.037182 -393.987047)
			(xy 381.033003 -394.005677) (xy 381.035922 -394.024546) (xy 381.040386 -394.032994) (xy 381.155956 -394.232892)
			(xy 381.168693 -394.256208) (xy 381.186785 -394.306157) (xy 381.196 -394.358476) (xy 381.196596 -394.385038)
			(xy 381.196596 -394.385292) (xy 381.196154 -394.409286) (xy 381.188648 -394.456682) (xy 381.17382 -394.50232)
			(xy 381.152035 -394.545077) (xy 381.123829 -394.5839) (xy 381.089897 -394.617831) (xy 381.051074 -394.646037)
			(xy 381.008317 -394.667822) (xy 380.962678 -394.682649) (xy 380.915282 -394.690155) (xy 380.891288 -394.6906)
			(xy 380.867714 -394.690216) (xy 380.821125 -394.682973) (xy 380.776206 -394.668645) (xy 380.734028 -394.647575)
			(xy 380.695595 -394.620264) (xy 380.661823 -394.587363) (xy 380.633518 -394.549656) (xy 380.622048 -394.529056)
			(xy 380.62154 -394.528294) (xy 380.608078 -394.504926) (xy 380.602663 -394.496497) (xy 380.586786 -394.48431)
			(xy 380.567454 -394.479129) (xy 380.547611 -394.481742) (xy 380.538736 -394.486384) (xy 380.529592 -394.491718)
			(xy 380.523496 -394.5001) (xy 380.512539 -394.513975) (xy 380.486464 -394.537842) (xy 380.456445 -394.556508)
			(xy 380.423506 -394.569336) (xy 380.38877 -394.575889) (xy 380.371096 -394.5763) (xy 380.370588 -394.5763)
			(xy 380.35182 -394.575859) (xy 380.315005 -394.568534) (xy 380.280327 -394.554167) (xy 380.249117 -394.533311)
			(xy 380.222576 -394.506767) (xy 380.201724 -394.475556) (xy 380.187361 -394.440876) (xy 380.180039 -394.40406)
			(xy 380.17958 -394.385292) (xy 380.180004 -394.366195) (xy 380.187576 -394.328758) (xy 380.202417 -394.293565)
			(xy 380.22394 -394.262011) (xy 380.251289 -394.235349) (xy 380.28338 -394.214637) (xy 380.300992 -394.207238)
			(xy 380.311152 -394.203174) (xy 380.326646 -394.187426) (xy 380.355856 -394.104114) (xy 380.35908 -394.093535)
			(xy 380.357102 -394.071532) (xy 380.352046 -394.061696) (xy 380.223776 -393.839954) (xy 380.211838 -393.815824)
			(xy 380.206961 -393.806336) (xy 380.191187 -393.792023) (xy 380.170963 -393.785337) (xy 380.149766 -393.787429)
			(xy 380.131239 -393.797938) (xy 380.124462 -393.806172) (xy 380.113505 -393.820208) (xy 380.087373 -393.844387)
			(xy 380.057216 -393.863308) (xy 380.024076 -393.876317) (xy 379.9891 -393.882965) (xy 379.9713 -393.883388)
			(xy 379.970792 -393.883388) (xy 379.943106 -393.881356) (xy 379.942852 -393.881356) (xy 379.933384 -393.880387)
			(xy 379.914867 -393.884728) (xy 379.899215 -393.895533) (xy 379.893576 -393.9032) (xy 379.842014 -393.978892)
			(xy 379.837029 -393.987047) (xy 379.832847 -394.005677) (xy 379.835769 -394.024547) (xy 379.840236 -394.032994)
			(xy 379.955806 -394.232892) (xy 379.968628 -394.256226) (xy 379.98685 -394.306248) (xy 379.996111 -394.358674)
			(xy 379.9967 -394.385292) (xy 379.996231 -394.409271) (xy 379.988734 -394.456639) (xy 379.973922 -394.502251)
			(xy 379.952161 -394.544988) (xy 379.923986 -394.583795) (xy 379.890089 -394.617721) (xy 379.851304 -394.645928)
			(xy 379.808586 -394.667725) (xy 379.762986 -394.682574) (xy 379.715624 -394.690111) (xy 379.691646 -394.6906)
			(xy 379.691138 -394.6906) (xy 379.667565 -394.690176) (xy 379.620978 -394.68294) (xy 379.57606 -394.66862)
			(xy 379.533882 -394.647556) (xy 379.495448 -394.620251) (xy 379.461676 -394.587356) (xy 379.433369 -394.549654)
			(xy 379.421898 -394.529056) (xy 379.42139 -394.528294) (xy 379.407928 -394.504926) (xy 379.402564 -394.496459)
			(xy 379.386669 -394.484273) (xy 379.367319 -394.479101) (xy 379.347464 -394.481731) (xy 379.338586 -394.486384)
			(xy 379.329442 -394.491718) (xy 379.323346 -394.5001) (xy 379.312418 -394.513999) (xy 379.286335 -394.537864)
			(xy 379.256309 -394.556526) (xy 379.223364 -394.569348) (xy 379.188622 -394.575894) (xy 379.170946 -394.5763)
			(xy 379.170438 -394.5763) (xy 379.151665 -394.575769) (xy 379.114838 -394.568458) (xy 379.080143 -394.554108)
			(xy 379.048911 -394.533271) (xy 379.022339 -394.506745) (xy 379.001448 -394.475548) (xy 378.987039 -394.440878)
			(xy 378.979664 -394.404064) (xy 378.979176 -394.385292) (xy 378.979675 -394.36618) (xy 378.987234 -394.328711)
			(xy 379.002089 -394.293492) (xy 379.023648 -394.261928) (xy 379.05105 -394.235278) (xy 379.083201 -394.214606)
			(xy 379.100842 -394.207238) (xy 379.111002 -394.203174) (xy 379.126496 -394.187426) (xy 379.155706 -394.104114)
			(xy 379.158935 -394.093536) (xy 379.156956 -394.071532) (xy 379.151896 -394.061696) (xy 379.023626 -393.839954)
			(xy 379.011688 -393.815824) (xy 379.006881 -393.806295) (xy 378.991087 -393.791976) (xy 378.970842 -393.785294)
			(xy 378.949628 -393.787398) (xy 378.93109 -393.797927) (xy 378.924312 -393.806172) (xy 378.913367 -393.820251)
			(xy 378.887184 -393.844455) (xy 378.856966 -393.863383) (xy 378.823762 -393.876379) (xy 378.788724 -393.882991)
			(xy 378.770896 -393.883388) (xy 378.770388 -393.883388) (xy 378.763508 -393.883387) (xy 378.749778 -393.882496)
			(xy 378.742956 -393.88161) (xy 378.728478 -393.879324) (xy 378.701808 -393.891008) (xy 378.642118 -393.978892)
			(xy 378.637133 -393.987047) (xy 378.63295 -394.005677) (xy 378.635873 -394.024547) (xy 378.64034 -394.032994)
			(xy 378.75591 -394.232892) (xy 378.768732 -394.256226) (xy 378.786954 -394.306248) (xy 378.796215 -394.358673)
			(xy 378.796804 -394.385292) (xy 378.796331 -394.409271) (xy 378.788834 -394.456638) (xy 378.774023 -394.502251)
			(xy 378.752262 -394.544986) (xy 378.724087 -394.583794) (xy 378.690191 -394.617719) (xy 378.651407 -394.645927)
			(xy 378.608689 -394.667724) (xy 378.563089 -394.682574) (xy 378.515728 -394.690111) (xy 378.49175 -394.6906)
			(xy 378.491242 -394.6906) (xy 378.467669 -394.690172) (xy 378.421083 -394.682937) (xy 378.376165 -394.668617)
			(xy 378.333986 -394.647554) (xy 378.295553 -394.62025) (xy 378.26178 -394.587355) (xy 378.233473 -394.549654)
			(xy 378.222002 -394.529056) (xy 378.221494 -394.528294) (xy 378.208032 -394.504926) (xy 378.202663 -394.496463)
			(xy 378.18677 -394.484277) (xy 378.167422 -394.479104) (xy 378.147568 -394.481733) (xy 378.13869 -394.486384)
			(xy 378.129546 -394.491718) (xy 378.12345 -394.5001) (xy 378.112519 -394.513997) (xy 378.086438 -394.537862)
			(xy 378.056412 -394.556524) (xy 378.023467 -394.569347) (xy 377.988726 -394.575894) (xy 377.97105 -394.5763)
			(xy 377.970542 -394.5763) (xy 377.951769 -394.575765) (xy 377.914943 -394.568455) (xy 377.880248 -394.554106)
			(xy 377.849015 -394.533269) (xy 377.822443 -394.506744) (xy 377.801552 -394.475548) (xy 377.787143 -394.440878)
			(xy 377.779768 -394.404064) (xy 377.77928 -394.385292) (xy 377.779777 -394.366179) (xy 377.787336 -394.32871)
			(xy 377.802192 -394.293491) (xy 377.823751 -394.261927) (xy 377.851153 -394.235277) (xy 377.883305 -394.214606)
			(xy 377.900946 -394.207238) (xy 377.911106 -394.203174) (xy 377.9266 -394.187426) (xy 377.95581 -394.104114)
			(xy 377.959039 -394.093536) (xy 377.957059 -394.071532) (xy 377.952 -394.061696) (xy 377.82373 -393.839954)
			(xy 377.811792 -393.815824) (xy 377.80698 -393.806298) (xy 377.791187 -393.791979) (xy 377.770944 -393.785298)
			(xy 377.749731 -393.787401) (xy 377.731194 -393.797928) (xy 377.724416 -393.806172) (xy 377.713468 -393.820249)
			(xy 377.687286 -393.844453) (xy 377.657069 -393.863382) (xy 377.623866 -393.876378) (xy 377.588828 -393.88299)
			(xy 377.571 -393.883388) (xy 377.570492 -393.883388) (xy 377.563612 -393.883387) (xy 377.549882 -393.882496)
			(xy 377.54306 -393.88161) (xy 377.528582 -393.879324) (xy 377.501912 -393.891008) (xy 377.442222 -393.978892)
			(xy 377.437237 -393.987047) (xy 377.433053 -394.005677) (xy 377.435977 -394.024547) (xy 377.440444 -394.032994)
			(xy 377.556014 -394.232892) (xy 377.568837 -394.256226) (xy 377.587058 -394.306248) (xy 377.596319 -394.358673)
			(xy 377.596908 -394.385292) (xy 377.596431 -394.40927) (xy 377.588934 -394.456637) (xy 377.574123 -394.50225)
			(xy 377.552363 -394.544985) (xy 377.524188 -394.583793) (xy 377.490292 -394.617718) (xy 377.451509 -394.645926)
			(xy 377.408792 -394.667723) (xy 377.363192 -394.682573) (xy 377.315832 -394.69011) (xy 377.291854 -394.6906)
			(xy 377.291346 -394.6906) (xy 377.267773 -394.690169) (xy 377.221187 -394.682935) (xy 377.176269 -394.668615)
			(xy 377.134091 -394.647553) (xy 377.095657 -394.620249) (xy 377.061884 -394.587355) (xy 377.033577 -394.549654)
			(xy 377.022106 -394.529056) (xy 377.021598 -394.528294) (xy 377.008136 -394.504926) (xy 377.002763 -394.496466)
			(xy 376.986871 -394.484279) (xy 376.967525 -394.479106) (xy 376.947672 -394.481734) (xy 376.938794 -394.486384)
			(xy 376.92965 -394.491718) (xy 376.923554 -394.5001) (xy 376.912621 -394.513995) (xy 376.88654 -394.53786)
			(xy 376.856515 -394.556523) (xy 376.82357 -394.569346) (xy 376.78883 -394.575893) (xy 376.771154 -394.5763)
			(xy 376.770646 -394.5763) (xy 376.751873 -394.575762) (xy 376.715047 -394.568452) (xy 376.680352 -394.554104)
			(xy 376.649119 -394.533267) (xy 376.622548 -394.506742) (xy 376.601656 -394.475547) (xy 376.587247 -394.440877)
			(xy 376.579872 -394.404064) (xy 376.579384 -394.385292) (xy 376.579878 -394.366179) (xy 376.587438 -394.32871)
			(xy 376.602294 -394.29349) (xy 376.623853 -394.261926) (xy 376.651256 -394.235277) (xy 376.683409 -394.214605)
			(xy 376.70105 -394.207238) (xy 376.71121 -394.203174) (xy 376.726704 -394.187426) (xy 376.755914 -394.104114)
			(xy 376.759142 -394.093535) (xy 376.757163 -394.071532) (xy 376.752104 -394.061696) (xy 376.623834 -393.839954)
			(xy 376.611896 -393.815824) (xy 376.607078 -393.806301) (xy 376.591287 -393.791983) (xy 376.571046 -393.785301)
			(xy 376.549834 -393.787403) (xy 376.531298 -393.797929) (xy 376.52452 -393.806172) (xy 376.513587 -393.820228)
			(xy 376.487449 -393.844405) (xy 376.457286 -393.863323) (xy 376.42414 -393.876328) (xy 376.38916 -393.882969)
			(xy 376.371358 -393.883388) (xy 376.37085 -393.883388) (xy 376.343164 -393.881356) (xy 376.34291 -393.881356)
			(xy 376.33344 -393.880433) (xy 376.314928 -393.884754) (xy 376.299276 -393.895541) (xy 376.293634 -393.9032)
			(xy 376.242072 -393.978892) (xy 376.237089 -393.987047) (xy 376.23291 -394.005677) (xy 376.23583 -394.024546)
			(xy 376.240294 -394.032994) (xy 376.355864 -394.232892) (xy 376.368602 -394.256207) (xy 376.386693 -394.306157)
			(xy 376.395908 -394.358476) (xy 376.396504 -394.385038) (xy 376.396504 -394.385292) (xy 376.396054 -394.409285)
			(xy 376.388549 -394.456681) (xy 376.373721 -394.502319) (xy 376.351936 -394.545075) (xy 376.323731 -394.583897)
			(xy 376.2898 -394.617829) (xy 376.250978 -394.646034) (xy 376.208222 -394.66782) (xy 376.162585 -394.682648)
			(xy 376.115189 -394.690154) (xy 376.091196 -394.6906) (xy 376.067622 -394.690209) (xy 376.021033 -394.682967)
			(xy 375.976115 -394.668641) (xy 375.933936 -394.647572) (xy 375.895503 -394.620262) (xy 375.861732 -394.587362)
			(xy 375.833426 -394.549656) (xy 375.821956 -394.529056) (xy 375.821448 -394.528294) (xy 375.807986 -394.504926)
			(xy 375.802563 -394.496503) (xy 375.786689 -394.484316) (xy 375.76736 -394.479133) (xy 375.747519 -394.481744)
			(xy 375.738644 -394.486384) (xy 375.7295 -394.491718) (xy 375.723404 -394.5001) (xy 375.712443 -394.513971)
			(xy 375.686369 -394.537839) (xy 375.656351 -394.556505) (xy 375.623413 -394.569334) (xy 375.588678 -394.575889)
			(xy 375.571004 -394.5763) (xy 375.570496 -394.5763) (xy 375.551725 -394.575882) (xy 375.514905 -394.568557)
			(xy 375.480221 -394.554189) (xy 375.449006 -394.533331) (xy 375.422461 -394.506784) (xy 375.401605 -394.475569)
			(xy 375.38724 -394.440884) (xy 375.379917 -394.404063) (xy 375.379488 -394.385292) (xy 375.379907 -394.366194)
			(xy 375.387479 -394.328757) (xy 375.402321 -394.293563) (xy 375.423845 -394.26201) (xy 375.451195 -394.235348)
			(xy 375.483288 -394.214637) (xy 375.5009 -394.207238) (xy 375.51106 -394.203174) (xy 375.526554 -394.187426)
			(xy 375.555764 -394.104114) (xy 375.558987 -394.093535) (xy 375.55701 -394.071532) (xy 375.551954 -394.061696)
			(xy 375.423684 -393.839954) (xy 375.411746 -393.815824) (xy 375.406998 -393.80626) (xy 375.391187 -393.791936)
			(xy 375.370925 -393.785258) (xy 375.349696 -393.787373) (xy 375.331149 -393.797918) (xy 375.32437 -393.806172)
			(xy 375.313449 -393.820271) (xy 375.28726 -393.844473) (xy 375.257036 -393.863398) (xy 375.223827 -393.876389)
			(xy 375.188784 -393.882995) (xy 375.170954 -393.883388) (xy 375.170446 -393.883388) (xy 375.163566 -393.883381)
			(xy 375.149837 -393.882494) (xy 375.143014 -393.88161) (xy 375.128536 -393.879324) (xy 375.101866 -393.891008)
			(xy 375.042176 -393.978892) (xy 375.037193 -393.987047) (xy 375.033013 -394.005677) (xy 375.035934 -394.024546)
			(xy 375.040398 -394.032994) (xy 375.155968 -394.232892) (xy 375.168706 -394.256207) (xy 375.186797 -394.306157)
			(xy 375.196012 -394.358476) (xy 375.196608 -394.385038) (xy 375.196608 -394.385292) (xy 375.196154 -394.409285)
			(xy 375.188649 -394.45668) (xy 375.173821 -394.502318) (xy 375.152037 -394.545074) (xy 375.123832 -394.583896)
			(xy 375.089902 -394.617827) (xy 375.051081 -394.646033) (xy 375.008325 -394.667818) (xy 374.962688 -394.682647)
			(xy 374.915293 -394.690154) (xy 374.8913 -394.6906) (xy 374.867726 -394.690206) (xy 374.821138 -394.682965)
			(xy 374.776219 -394.668639) (xy 374.734041 -394.64757) (xy 374.695608 -394.620261) (xy 374.661836 -394.587361)
			(xy 374.63353 -394.549656) (xy 374.62206 -394.529056) (xy 374.621552 -394.528294) (xy 374.60809 -394.504926)
			(xy 374.602663 -394.496506) (xy 374.586791 -394.484319) (xy 374.567463 -394.479136) (xy 374.547623 -394.481745)
			(xy 374.538748 -394.486384) (xy 374.529604 -394.491718) (xy 374.523508 -394.5001) (xy 374.512601 -394.514017)
			(xy 374.486513 -394.53788) (xy 374.456482 -394.556539) (xy 374.423531 -394.569357) (xy 374.388786 -394.575897)
			(xy 374.371108 -394.5763) (xy 374.3706 -394.5763) (xy 374.351829 -394.575878) (xy 374.315009 -394.568554)
			(xy 374.280325 -394.554187) (xy 374.249111 -394.53333) (xy 374.222565 -394.506783) (xy 374.201709 -394.475568)
			(xy 374.187344 -394.440883) (xy 374.180021 -394.404063) (xy 374.179592 -394.385292) (xy 374.180071 -394.366198)
			(xy 374.187639 -394.328768) (xy 374.202472 -394.293579) (xy 374.223984 -394.262027) (xy 374.251321 -394.235362)
			(xy 374.283398 -394.214642) (xy 374.301004 -394.207238) (xy 374.311164 -394.203174) (xy 374.326658 -394.187426)
			(xy 374.355868 -394.104114) (xy 374.359091 -394.093535) (xy 374.357113 -394.071532) (xy 374.352058 -394.061696)
			(xy 374.223788 -393.839954) (xy 374.21185 -393.815824) (xy 374.207097 -393.806263) (xy 374.191287 -393.79194)
			(xy 374.171027 -393.785261) (xy 374.149799 -393.787375) (xy 374.131253 -393.797918) (xy 374.124474 -393.806172)
			(xy 374.113568 -393.82025) (xy 374.087423 -393.844425) (xy 374.057253 -393.86334) (xy 374.024101 -393.876339)
			(xy 373.989116 -393.882973) (xy 373.971312 -393.883388) (xy 373.970804 -393.883388) (xy 373.943118 -393.881356)
			(xy 373.942864 -393.881356) (xy 373.933395 -393.880397) (xy 373.91488 -393.884734) (xy 373.899228 -393.895535)
			(xy 373.893588 -393.9032) (xy 373.842026 -393.978892) (xy 373.837041 -393.987047) (xy 373.832857 -394.005677)
			(xy 373.83578 -394.024547) (xy 373.840248 -394.032994) (xy 373.955818 -394.232892) (xy 373.968641 -394.256226)
			(xy 373.986862 -394.306248) (xy 373.996123 -394.358673) (xy 373.996712 -394.385292) (xy 373.996231 -394.40927)
			(xy 373.988734 -394.456637) (xy 373.973924 -394.502249) (xy 373.952164 -394.544984) (xy 373.923989 -394.583791)
			(xy 373.890094 -394.617716) (xy 373.851311 -394.645924) (xy 373.808595 -394.667722) (xy 373.762996 -394.682572)
			(xy 373.715636 -394.69011) (xy 373.691658 -394.6906) (xy 373.69115 -394.6906) (xy 373.667577 -394.690166)
			(xy 373.620991 -394.682932) (xy 373.576073 -394.668613) (xy 373.533895 -394.647551) (xy 373.495461 -394.620248)
			(xy 373.461688 -394.587354) (xy 373.433381 -394.549653) (xy 373.42191 -394.529056) (xy 373.421402 -394.528294)
			(xy 373.40794 -394.504926) (xy 373.402563 -394.496469) (xy 373.386673 -394.484282) (xy 373.367328 -394.479108)
			(xy 373.347475 -394.481734) (xy 373.338598 -394.486384) (xy 373.329454 -394.491718) (xy 373.323358 -394.5001)
			(xy 373.312423 -394.513993) (xy 373.286342 -394.537859) (xy 373.256318 -394.556522) (xy 373.223374 -394.569345)
			(xy 373.188633 -394.575893) (xy 373.170958 -394.5763) (xy 373.17045 -394.5763) (xy 373.151678 -394.575758)
			(xy 373.114851 -394.568449) (xy 373.080156 -394.554101) (xy 373.048924 -394.533266) (xy 373.022352 -394.506741)
			(xy 373.00146 -394.475546) (xy 372.987051 -394.440877) (xy 372.979676 -394.404064) (xy 372.979188 -394.385292)
			(xy 372.97968 -394.366179) (xy 372.987239 -394.328709) (xy 373.002096 -394.29349) (xy 373.023656 -394.261925)
			(xy 373.051059 -394.235276) (xy 373.083212 -394.214605) (xy 373.100854 -394.207238) (xy 373.111014 -394.203174)
			(xy 373.126508 -394.187426) (xy 373.155718 -394.104114) (xy 373.158946 -394.093535) (xy 373.156967 -394.071532)
			(xy 373.151908 -394.061696) (xy 373.023638 -393.839954) (xy 373.0117 -393.815824) (xy 373.006876 -393.806305)
			(xy 372.991087 -393.791987) (xy 372.970847 -393.785304) (xy 372.949637 -393.787406) (xy 372.931102 -393.79793)
			(xy 372.924324 -393.806172) (xy 372.913372 -393.820245) (xy 372.887191 -393.84445) (xy 372.856975 -393.863379)
			(xy 372.823772 -393.876376) (xy 372.788736 -393.88299) (xy 372.770908 -393.883388) (xy 372.7704 -393.883388)
			(xy 372.76352 -393.883386) (xy 372.74979 -393.882495) (xy 372.742968 -393.88161) (xy 372.72849 -393.879324)
			(xy 372.70182 -393.891008) (xy 372.64213 -393.978892) (xy 372.637145 -393.987047) (xy 372.63296 -394.005677)
			(xy 372.635884 -394.024547) (xy 372.640352 -394.032994) (xy 372.755922 -394.232892) (xy 372.768745 -394.256225)
			(xy 372.786966 -394.306248) (xy 372.796227 -394.358673) (xy 372.796816 -394.385292) (xy 372.796331 -394.40927)
			(xy 372.788834 -394.456636) (xy 372.774024 -394.502248) (xy 372.752264 -394.544983) (xy 372.72409 -394.58379)
			(xy 372.690196 -394.617715) (xy 372.651413 -394.645923) (xy 372.608698 -394.66772) (xy 372.563099 -394.682571)
			(xy 372.51574 -394.69011) (xy 372.491762 -394.6906) (xy 372.491254 -394.6906) (xy 372.467682 -394.690163)
			(xy 372.421095 -394.682929) (xy 372.376178 -394.668611) (xy 372.333999 -394.64755) (xy 372.295566 -394.620247)
			(xy 372.261793 -394.587353) (xy 372.233485 -394.549653) (xy 372.222014 -394.529056) (xy 372.221506 -394.528294)
			(xy 372.208044 -394.504926) (xy 372.202663 -394.496472) (xy 372.186774 -394.484285) (xy 372.167431 -394.47911)
			(xy 372.147579 -394.481735) (xy 372.138702 -394.486384) (xy 372.129558 -394.491718) (xy 372.123462 -394.5001)
			(xy 372.112525 -394.513991) (xy 372.086445 -394.537857) (xy 372.056421 -394.55652) (xy 372.023477 -394.569344)
			(xy 371.988737 -394.575892) (xy 371.971062 -394.5763) (xy 371.970554 -394.5763) (xy 371.951778 -394.575845)
			(xy 371.914948 -394.568519) (xy 371.880252 -394.554155) (xy 371.849021 -394.533306) (xy 371.822451 -394.50677)
			(xy 371.801561 -394.475565) (xy 371.787153 -394.440888) (xy 371.779779 -394.404067) (xy 371.779292 -394.385292)
			(xy 371.779781 -394.366179) (xy 371.787341 -394.328709) (xy 371.802198 -394.293489) (xy 371.823758 -394.261925)
			(xy 371.851162 -394.235276) (xy 371.883316 -394.214605) (xy 371.900958 -394.207238) (xy 371.911118 -394.203174)
			(xy 371.926612 -394.187426) (xy 371.955822 -394.104114) (xy 371.95905 -394.093535) (xy 371.957071 -394.071532)
			(xy 371.952012 -394.061696) (xy 371.823742 -393.839954) (xy 371.811804 -393.815824) (xy 371.806975 -393.806308)
			(xy 371.791187 -393.791991) (xy 371.770949 -393.785308) (xy 371.74974 -393.787408) (xy 371.731206 -393.79793)
			(xy 371.724428 -393.806172) (xy 371.713474 -393.820243) (xy 371.687293 -393.844448) (xy 371.657078 -393.863377)
			(xy 371.623876 -393.876375) (xy 371.58884 -393.882989) (xy 371.571012 -393.883388) (xy 371.570504 -393.883388)
			(xy 371.563624 -393.883385) (xy 371.549894 -393.882495) (xy 371.543072 -393.88161) (xy 371.528594 -393.879324)
			(xy 371.501924 -393.891008) (xy 371.442234 -393.978892) (xy 371.437248 -393.987047) (xy 371.433064 -394.005677)
			(xy 371.435988 -394.024547) (xy 371.440456 -394.032994) (xy 371.556026 -394.232892) (xy 371.56885 -394.256225)
			(xy 371.587071 -394.306247) (xy 371.596331 -394.358673) (xy 371.59692 -394.385292) (xy 371.596431 -394.40927)
			(xy 371.588935 -394.456636) (xy 371.574124 -394.502247) (xy 371.552365 -394.544982) (xy 371.524192 -394.583789)
			(xy 371.490297 -394.617713) (xy 371.451516 -394.645922) (xy 371.4088 -394.667719) (xy 371.363202 -394.68257)
			(xy 371.315843 -394.69011) (xy 371.291866 -394.6906) (xy 371.291358 -394.6906) (xy 371.267786 -394.690159)
			(xy 371.2212 -394.682927) (xy 371.176282 -394.668609) (xy 371.134104 -394.647548) (xy 371.09567 -394.620246)
			(xy 371.061897 -394.587353) (xy 371.03359 -394.549653) (xy 371.022118 -394.529056) (xy 371.02161 -394.528294)
			(xy 371.008148 -394.504926) (xy 371.002763 -394.496475) (xy 370.986876 -394.484288) (xy 370.967533 -394.479113)
			(xy 370.947683 -394.481736) (xy 370.938806 -394.486384) (xy 370.929662 -394.491718) (xy 370.923566 -394.5001)
			(xy 370.912626 -394.513989) (xy 370.886547 -394.537855) (xy 370.856524 -394.556519) (xy 370.823581 -394.569343)
			(xy 370.788841 -394.575892) (xy 370.771166 -394.5763) (xy 370.770658 -394.5763) (xy 370.751882 -394.575842)
			(xy 370.715053 -394.568516) (xy 370.680357 -394.554153) (xy 370.649125 -394.533304) (xy 370.622555 -394.506769)
			(xy 370.601665 -394.475564) (xy 370.587257 -394.440887) (xy 370.579883 -394.404067) (xy 370.579396 -394.385292)
			(xy 370.579882 -394.366179) (xy 370.587443 -394.328708) (xy 370.6023 -394.293488) (xy 370.623861 -394.261924)
			(xy 370.651265 -394.235275) (xy 370.68342 -394.214605) (xy 370.701062 -394.207238) (xy 370.711222 -394.203174)
			(xy 370.726716 -394.187426) (xy 370.755926 -394.104114) (xy 370.759153 -394.093535) (xy 370.757174 -394.071532)
			(xy 370.752116 -394.061696) (xy 370.623846 -393.839954) (xy 370.611908 -393.815824) (xy 370.607073 -393.806311)
			(xy 370.591287 -393.791994) (xy 370.571051 -393.785311) (xy 370.549843 -393.78741) (xy 370.53131 -393.797931)
			(xy 370.524532 -393.806172) (xy 370.513592 -393.820222) (xy 370.487456 -393.8444) (xy 370.457294 -393.863319)
			(xy 370.42415 -393.876325) (xy 370.389172 -393.882968) (xy 370.37137 -393.883388) (xy 370.370862 -393.883388)
			(xy 370.350842 -393.882901) (xy 370.311678 -393.874569) (xy 370.275101 -393.858278) (xy 370.24271 -393.834739)
			(xy 370.215921 -393.80498) (xy 370.195903 -393.770303) (xy 370.183531 -393.732221) (xy 370.179346 -393.6924)
			(xy 354.671136 -393.6924) (xy 354.983542 -394.232892) (xy 354.996367 -394.256224) (xy 355.014587 -394.306247)
			(xy 355.023847 -394.358673) (xy 355.024436 -394.385292) (xy 355.023931 -394.409269) (xy 355.016435 -394.456633)
			(xy 355.001626 -394.502243) (xy 354.979868 -394.544977) (xy 354.951696 -394.583783) (xy 354.917804 -394.617708)
			(xy 354.879024 -394.645916) (xy 354.836311 -394.667715) (xy 354.790716 -394.682567) (xy 354.743358 -394.690108)
			(xy 354.719382 -394.6906) (xy 354.718874 -394.6906) (xy 354.695299 -394.690227) (xy 354.64871 -394.682982)
			(xy 354.603791 -394.668652) (xy 354.561613 -394.64758) (xy 354.52318 -394.620267) (xy 354.489409 -394.587365)
			(xy 354.461104 -394.549657) (xy 354.449634 -394.529056) (xy 354.449126 -394.528294) (xy 354.435664 -394.504926)
			(xy 354.430263 -394.496487) (xy 354.414381 -394.4843) (xy 354.395045 -394.479121) (xy 354.375198 -394.481739)
			(xy 354.366322 -394.486384) (xy 354.357178 -394.491718) (xy 354.351082 -394.5001) (xy 354.340133 -394.513982)
			(xy 354.314056 -394.537848) (xy 354.284035 -394.556513) (xy 354.251094 -394.56934) (xy 354.216356 -394.575891)
			(xy 354.198682 -394.5763) (xy 354.198174 -394.5763) (xy 354.179399 -394.575827) (xy 354.14257 -394.568504)
			(xy 354.107874 -394.554144) (xy 354.076642 -394.533298) (xy 354.050072 -394.506764) (xy 354.029182 -394.475561)
			(xy 354.014773 -394.440885) (xy 354.007399 -394.404066) (xy 354.006912 -394.385292) (xy 354.007388 -394.366178)
			(xy 354.014949 -394.328707) (xy 354.029808 -394.293486) (xy 354.051371 -394.261921) (xy 354.078778 -394.235272)
			(xy 354.110935 -394.214604) (xy 354.128578 -394.207238) (xy 354.138738 -394.203174) (xy 354.154232 -394.187426)
			(xy 354.183442 -394.104114) (xy 354.186667 -394.093535) (xy 354.184689 -394.071532) (xy 354.179632 -394.061696)
			(xy 354.051362 -393.839954) (xy 354.03917 -393.81557) (xy 354.034386 -393.806024) (xy 354.018589 -393.791692)
			(xy 353.998334 -393.785006) (xy 353.977109 -393.787118) (xy 353.958569 -393.797663) (xy 353.951794 -393.805918)
			(xy 353.940867 -393.820027) (xy 353.914701 -393.844288) (xy 353.884487 -393.863272) (xy 353.851275 -393.876317)
			(xy 353.816219 -393.882973) (xy 353.798378 -393.883388) (xy 353.79787 -393.883388) (xy 353.770692 -393.88161)
			(xy 353.75596 -393.879578) (xy 353.729544 -393.891008) (xy 353.670108 -393.978892) (xy 353.665115 -393.986983)
			(xy 353.661017 -394.005538) (xy 353.663913 -394.024319) (xy 353.66833 -394.03274) (xy 353.783646 -394.232892)
			(xy 353.796471 -394.256224) (xy 353.814691 -394.306247) (xy 353.823951 -394.358673) (xy 353.82454 -394.385292)
			(xy 353.824054 -394.409296) (xy 353.816541 -394.456713) (xy 353.8017 -394.502369) (xy 353.779896 -394.54514)
			(xy 353.751667 -394.583972) (xy 353.717709 -394.617907) (xy 353.678857 -394.646108) (xy 353.636071 -394.667882)
			(xy 353.590404 -394.682691) (xy 353.542982 -394.69017) (xy 353.518978 -394.6906) (xy 353.518724 -394.6906)
			(xy 353.495151 -394.690187) (xy 353.448563 -394.682949) (xy 353.403645 -394.668627) (xy 353.361467 -394.647561)
			(xy 353.323033 -394.620255) (xy 353.289261 -394.587358) (xy 353.260955 -394.549655) (xy 353.249484 -394.529056)
			(xy 353.248976 -394.528294) (xy 353.235514 -394.504926) (xy 353.230164 -394.496449) (xy 353.214264 -394.484263)
			(xy 353.19491 -394.479093) (xy 353.175051 -394.481729) (xy 353.166172 -394.486384) (xy 353.157028 -394.491718)
			(xy 353.150932 -394.5001) (xy 353.140012 -394.514005) (xy 353.113927 -394.53787) (xy 353.083899 -394.556531)
			(xy 353.050952 -394.569352) (xy 353.016209 -394.575895) (xy 352.998532 -394.5763) (xy 352.998024 -394.5763)
			(xy 352.979254 -394.575857) (xy 352.942435 -394.568537) (xy 352.907751 -394.554174) (xy 352.876536 -394.53332)
			(xy 352.84999 -394.506776) (xy 352.829134 -394.475563) (xy 352.814768 -394.440881) (xy 352.807445 -394.404062)
			(xy 352.807016 -394.385292) (xy 352.80748 -394.366197) (xy 352.815049 -394.328765) (xy 352.829885 -394.293575)
			(xy 352.8514 -394.262023) (xy 352.87874 -394.235359) (xy 352.910821 -394.214641) (xy 352.928428 -394.207238)
			(xy 352.938588 -394.203174) (xy 352.954082 -394.187426) (xy 352.983292 -394.104114) (xy 352.986523 -394.093536)
			(xy 352.984543 -394.071531) (xy 352.979482 -394.061696) (xy 352.851212 -393.839954) (xy 352.839274 -393.815824)
			(xy 352.834487 -393.806283) (xy 352.818687 -393.791963) (xy 352.798437 -393.785282) (xy 352.777217 -393.78739)
			(xy 352.758677 -393.797924) (xy 352.751898 -393.806172) (xy 352.740961 -393.820257) (xy 352.714776 -393.844461)
			(xy 352.684556 -393.863388) (xy 352.65135 -393.876382) (xy 352.616311 -393.882992) (xy 352.598482 -393.883388)
			(xy 352.597974 -393.883388) (xy 352.591094 -393.883389) (xy 352.577364 -393.882496) (xy 352.570542 -393.88161)
			(xy 352.556064 -393.879324) (xy 352.529394 -393.891008) (xy 352.469704 -393.978892) (xy 352.46472 -393.987047)
			(xy 352.460538 -394.005677) (xy 352.46346 -394.024547) (xy 352.467926 -394.032994) (xy 352.583496 -394.232892)
			(xy 352.596228 -394.25621) (xy 352.614323 -394.306158) (xy 352.623539 -394.358477) (xy 352.624136 -394.385038)
			(xy 352.624136 -394.385292) (xy 352.62363 -394.409282) (xy 352.616126 -394.45667) (xy 352.601301 -394.502302)
			(xy 352.579521 -394.545053) (xy 352.551322 -394.58387) (xy 352.517397 -394.617798) (xy 352.478583 -394.646002)
			(xy 352.435835 -394.667788) (xy 352.390205 -394.682618) (xy 352.342818 -394.690127) (xy 352.318828 -394.6906)
			(xy 352.295255 -394.690184) (xy 352.248668 -394.682946) (xy 352.20375 -394.668625) (xy 352.161571 -394.64756)
			(xy 352.123138 -394.620254) (xy 352.089365 -394.587357) (xy 352.061059 -394.549654) (xy 352.049588 -394.529056)
			(xy 352.04908 -394.528294) (xy 352.035618 -394.504926) (xy 352.030264 -394.496452) (xy 352.014365 -394.484266)
			(xy 351.995012 -394.479096) (xy 351.975155 -394.481729) (xy 351.966276 -394.486384) (xy 351.957132 -394.491718)
			(xy 351.951036 -394.5001) (xy 351.940113 -394.514003) (xy 351.91403 -394.537868) (xy 351.884002 -394.556529)
			(xy 351.851055 -394.569351) (xy 351.816312 -394.575895) (xy 351.798636 -394.5763) (xy 351.798128 -394.5763)
			(xy 351.779358 -394.575853) (xy 351.742539 -394.568534) (xy 351.707855 -394.554172) (xy 351.676641 -394.533318)
			(xy 351.650095 -394.506775) (xy 351.629238 -394.475562) (xy 351.614872 -394.44088) (xy 351.607549 -394.404062)
			(xy 351.60712 -394.385292) (xy 351.607582 -394.366197) (xy 351.615151 -394.328765) (xy 351.629987 -394.293575)
			(xy 351.651502 -394.262022) (xy 351.678843 -394.235358) (xy 351.710925 -394.214641) (xy 351.728532 -394.207238)
			(xy 351.738692 -394.203174) (xy 351.754186 -394.187426) (xy 351.783396 -394.104114) (xy 351.786627 -394.093536)
			(xy 351.784647 -394.071531) (xy 351.779586 -394.061696) (xy 351.651316 -393.839954) (xy 351.639378 -393.815824)
			(xy 351.634585 -393.806287) (xy 351.618787 -393.791966) (xy 351.598538 -393.785286) (xy 351.57732 -393.787392)
			(xy 351.558781 -393.797925) (xy 351.552002 -393.806172) (xy 351.541062 -393.820255) (xy 351.514878 -393.844459)
			(xy 351.484659 -393.863387) (xy 351.451454 -393.876381) (xy 351.416415 -393.882992) (xy 351.398586 -393.883388)
			(xy 351.398078 -393.883388) (xy 351.391198 -393.883388) (xy 351.377468 -393.882496) (xy 351.370646 -393.88161)
			(xy 351.356168 -393.879324) (xy 351.329498 -393.891008) (xy 351.269808 -393.978892) (xy 351.264824 -393.987047)
			(xy 351.260641 -394.005677) (xy 351.263564 -394.024547) (xy 351.26803 -394.032994) (xy 351.3836 -394.232892)
			(xy 351.396333 -394.25621) (xy 351.414427 -394.306158) (xy 351.423643 -394.358477) (xy 351.42424 -394.385038)
			(xy 351.42424 -394.385292) (xy 351.42373 -394.409281) (xy 351.416226 -394.45667) (xy 351.401402 -394.502301)
			(xy 351.379622 -394.545051) (xy 351.351423 -394.583869) (xy 351.317499 -394.617797) (xy 351.278686 -394.646001)
			(xy 351.235938 -394.667787) (xy 351.190309 -394.682617) (xy 351.142921 -394.690127) (xy 351.118932 -394.6906)
			(xy 351.118678 -394.6906) (xy 351.095103 -394.690224) (xy 351.048514 -394.682979) (xy 351.003595 -394.66865)
			(xy 350.961417 -394.647579) (xy 350.922984 -394.620266) (xy 350.889213 -394.587364) (xy 350.860908 -394.549657)
			(xy 350.849438 -394.529056) (xy 350.84893 -394.528294) (xy 350.835468 -394.504926) (xy 350.830063 -394.49649)
			(xy 350.814183 -394.484303) (xy 350.794847 -394.479123) (xy 350.775002 -394.48174) (xy 350.766126 -394.486384)
			(xy 350.756982 -394.491718) (xy 350.750886 -394.5001) (xy 350.739935 -394.51398) (xy 350.713858 -394.537846)
			(xy 350.683838 -394.556511) (xy 350.650898 -394.569339) (xy 350.61616 -394.57589) (xy 350.598486 -394.5763)
			(xy 350.597978 -394.5763) (xy 350.579203 -394.575824) (xy 350.542374 -394.568501) (xy 350.507678 -394.554142)
			(xy 350.476446 -394.533296) (xy 350.449876 -394.506763) (xy 350.428986 -394.47556) (xy 350.414577 -394.440885)
			(xy 350.407203 -394.404066) (xy 350.406716 -394.385292) (xy 350.40719 -394.366178) (xy 350.414751 -394.328706)
			(xy 350.42961 -394.293485) (xy 350.451173 -394.26192) (xy 350.478581 -394.235272) (xy 350.510738 -394.214603)
			(xy 350.528382 -394.207238) (xy 350.538542 -394.203174) (xy 350.554036 -394.187426) (xy 350.583246 -394.104114)
			(xy 350.586471 -394.093535) (xy 350.584493 -394.071532) (xy 350.579436 -394.061696) (xy 350.451166 -393.839954)
			(xy 350.439228 -393.815824) (xy 350.434365 -393.806328) (xy 350.418587 -393.792013) (xy 350.398359 -393.785329)
			(xy 350.377158 -393.787423) (xy 350.358629 -393.797936) (xy 350.351852 -393.806172) (xy 350.340884 -393.820232)
			(xy 350.314707 -393.844437) (xy 350.284495 -393.863369) (xy 350.251296 -393.876369) (xy 350.216263 -393.882987)
			(xy 350.198436 -393.883388) (xy 350.197928 -393.883388) (xy 350.191048 -393.883383) (xy 350.177319 -393.882494)
			(xy 350.170496 -393.88161) (xy 350.156018 -393.879324) (xy 350.129348 -393.891008) (xy 350.069658 -393.978892)
			(xy 350.064676 -393.987047) (xy 350.060498 -394.005677) (xy 350.063417 -394.024546) (xy 350.06788 -394.032994)
			(xy 350.18345 -394.232892) (xy 350.196276 -394.256224) (xy 350.214495 -394.306247) (xy 350.223755 -394.358673)
			(xy 350.224344 -394.385292) (xy 350.223831 -394.409269) (xy 350.216335 -394.456632) (xy 350.201527 -394.502241)
			(xy 350.179769 -394.544974) (xy 350.151599 -394.58378) (xy 350.117707 -394.617705) (xy 350.078929 -394.645913)
			(xy 350.036217 -394.667712) (xy 349.990622 -394.682566) (xy 349.943266 -394.690108) (xy 349.91929 -394.6906)
			(xy 349.918782 -394.6906) (xy 349.895207 -394.690221) (xy 349.848619 -394.682977) (xy 349.8037 -394.668648)
			(xy 349.761521 -394.647577) (xy 349.723088 -394.620265) (xy 349.689317 -394.587364) (xy 349.661012 -394.549657)
			(xy 349.649542 -394.529056) (xy 349.649034 -394.528294) (xy 349.635572 -394.504926) (xy 349.630163 -394.496493)
			(xy 349.614284 -394.484306) (xy 349.59495 -394.479126) (xy 349.575106 -394.481741) (xy 349.56623 -394.486384)
			(xy 349.557086 -394.491718) (xy 349.55099 -394.5001) (xy 349.540037 -394.513978) (xy 349.513961 -394.537845)
			(xy 349.483941 -394.55651) (xy 349.451001 -394.569338) (xy 349.416264 -394.57589) (xy 349.39859 -394.5763)
			(xy 349.398082 -394.5763) (xy 349.379307 -394.57582) (xy 349.342478 -394.568498) (xy 349.307783 -394.55414)
			(xy 349.276551 -394.533294) (xy 349.24998 -394.506762) (xy 349.22909 -394.47556) (xy 349.214681 -394.440884)
			(xy 349.207307 -394.404066) (xy 349.20682 -394.385292) (xy 349.207291 -394.366178) (xy 349.214853 -394.328706)
			(xy 349.229712 -394.293484) (xy 349.251276 -394.26192) (xy 349.278684 -394.235271) (xy 349.310842 -394.214603)
			(xy 349.328486 -394.207238) (xy 349.338646 -394.203174) (xy 349.35414 -394.187426) (xy 349.38335 -394.104114)
			(xy 349.386574 -394.093535) (xy 349.384596 -394.071532) (xy 349.37954 -394.061696) (xy 349.25127 -393.839954)
			(xy 349.239332 -393.815824) (xy 349.234463 -393.806331) (xy 349.218687 -393.792017) (xy 349.19846 -393.785332)
			(xy 349.177261 -393.787425) (xy 349.158733 -393.797937) (xy 349.151956 -393.806172) (xy 349.140985 -393.82023)
			(xy 349.114809 -393.844436) (xy 349.084598 -393.863367) (xy 349.0514 -393.876368) (xy 349.016366 -393.882987)
			(xy 348.99854 -393.883388) (xy 348.998032 -393.883388) (xy 348.991152 -393.883382) (xy 348.977423 -393.882494)
			(xy 348.9706 -393.88161) (xy 348.956122 -393.879324) (xy 348.929452 -393.891008) (xy 348.869762 -393.978892)
			(xy 348.86478 -393.987047) (xy 348.860601 -394.005677) (xy 348.863521 -394.024546) (xy 348.867984 -394.032994)
			(xy 348.983554 -394.232892) (xy 348.99638 -394.256224) (xy 349.014599 -394.306247) (xy 349.023859 -394.358673)
			(xy 349.024448 -394.385292) (xy 349.023931 -394.409268) (xy 349.016436 -394.456632) (xy 349.001627 -394.50224)
			(xy 348.97987 -394.544973) (xy 348.9517 -394.583779) (xy 348.917809 -394.617703) (xy 348.879031 -394.645912)
			(xy 348.83632 -394.667711) (xy 348.790726 -394.682565) (xy 348.74337 -394.690107) (xy 348.719394 -394.6906)
			(xy 348.718886 -394.6906) (xy 348.695312 -394.690217) (xy 348.648723 -394.682974) (xy 348.603804 -394.668646)
			(xy 348.561626 -394.647576) (xy 348.523193 -394.620264) (xy 348.489421 -394.587363) (xy 348.461116 -394.549656)
			(xy 348.449646 -394.529056) (xy 348.449138 -394.528294) (xy 348.435676 -394.504926) (xy 348.430263 -394.496496)
			(xy 348.414386 -394.484309) (xy 348.395053 -394.479128) (xy 348.37521 -394.481742) (xy 348.366334 -394.486384)
			(xy 348.35719 -394.491718) (xy 348.351094 -394.5001) (xy 348.340138 -394.513976) (xy 348.314063 -394.537843)
			(xy 348.284044 -394.556509) (xy 348.251104 -394.569337) (xy 348.216368 -394.57589) (xy 348.198694 -394.5763)
			(xy 348.198186 -394.5763) (xy 348.179411 -394.575816) (xy 348.142583 -394.568496) (xy 348.107887 -394.554137)
			(xy 348.076655 -394.533293) (xy 348.050084 -394.506761) (xy 348.029194 -394.475559) (xy 348.014785 -394.440884)
			(xy 348.007411 -394.404066) (xy 348.006924 -394.385292) (xy 348.007393 -394.366178) (xy 348.014954 -394.328705)
			(xy 348.029814 -394.293484) (xy 348.051378 -394.261919) (xy 348.078787 -394.235271) (xy 348.110946 -394.214603)
			(xy 348.12859 -394.207238) (xy 348.13875 -394.203174) (xy 348.154244 -394.187426) (xy 348.183454 -394.104114)
			(xy 348.186678 -394.093535) (xy 348.1847 -394.071532) (xy 348.179644 -394.061696) (xy 348.051374 -393.839954)
			(xy 348.039436 -393.815824) (xy 348.034562 -393.806334) (xy 348.018787 -393.792021) (xy 347.998562 -393.785336)
			(xy 347.977364 -393.787428) (xy 347.958837 -393.797938) (xy 347.95206 -393.806172) (xy 347.941104 -393.820209)
			(xy 347.914972 -393.844388) (xy 347.884814 -393.863309) (xy 347.851674 -393.876318) (xy 347.816698 -393.882965)
			(xy 347.798898 -393.883388) (xy 347.79839 -393.883388) (xy 347.770704 -393.881356) (xy 347.77045 -393.881356)
			(xy 347.760982 -393.880385) (xy 347.742465 -393.884727) (xy 347.726813 -393.895533) (xy 347.721174 -393.9032)
			(xy 347.669612 -393.978892) (xy 347.664628 -393.987047) (xy 347.660445 -394.005677) (xy 347.663367 -394.024547)
			(xy 347.667834 -394.032994) (xy 347.783404 -394.232892) (xy 347.796137 -394.25621) (xy 347.814231 -394.306158)
			(xy 347.823447 -394.358477) (xy 347.824044 -394.385038) (xy 347.824044 -394.385292) (xy 347.82353 -394.409281)
			(xy 347.816026 -394.456669) (xy 347.801202 -394.5023) (xy 347.779423 -394.54505) (xy 347.751224 -394.583867)
			(xy 347.717301 -394.617796) (xy 347.678488 -394.646) (xy 347.635741 -394.667785) (xy 347.590112 -394.682616)
			(xy 347.542725 -394.690127) (xy 347.518736 -394.6906) (xy 347.495163 -394.690177) (xy 347.448576 -394.682941)
			(xy 347.403658 -394.668621) (xy 347.36148 -394.647557) (xy 347.323046 -394.620252) (xy 347.289274 -394.587356)
			(xy 347.260967 -394.549654) (xy 347.249496 -394.529056) (xy 347.248988 -394.528294) (xy 347.235526 -394.504926)
			(xy 347.230164 -394.496458) (xy 347.214268 -394.484272) (xy 347.194918 -394.4791) (xy 347.175062 -394.481731)
			(xy 347.166184 -394.486384) (xy 347.15704 -394.491718) (xy 347.150944 -394.5001) (xy 347.140017 -394.514)
			(xy 347.113934 -394.537865) (xy 347.083908 -394.556527) (xy 347.050962 -394.569349) (xy 347.01622 -394.575894)
			(xy 346.998544 -394.5763) (xy 346.998036 -394.5763) (xy 346.979266 -394.575846) (xy 346.942447 -394.568528)
			(xy 346.907764 -394.554167) (xy 346.876549 -394.533315) (xy 346.850003 -394.506773) (xy 346.829146 -394.475561)
			(xy 346.81478 -394.440879) (xy 346.807457 -394.404062) (xy 346.807028 -394.385292) (xy 346.807485 -394.366197)
			(xy 346.815054 -394.328764) (xy 346.829891 -394.293573) (xy 346.851407 -394.262021) (xy 346.878749 -394.235357)
			(xy 346.910832 -394.21464) (xy 346.92844 -394.207238) (xy 346.9386 -394.203174) (xy 346.954094 -394.187426)
			(xy 346.983304 -394.104114) (xy 346.986534 -394.093536) (xy 346.984554 -394.071532) (xy 346.979494 -394.061696)
			(xy 346.851224 -393.839954) (xy 346.839286 -393.815824) (xy 346.834482 -393.806293) (xy 346.818687 -393.791974)
			(xy 346.798442 -393.785292) (xy 346.777226 -393.787397) (xy 346.758688 -393.797927) (xy 346.75191 -393.806172)
			(xy 346.740966 -393.820252) (xy 346.714783 -393.844456) (xy 346.684565 -393.863384) (xy 346.651361 -393.876379)
			(xy 346.616322 -393.882991) (xy 346.598494 -393.883388) (xy 346.597986 -393.883388) (xy 346.591106 -393.883387)
			(xy 346.577376 -393.882496) (xy 346.570554 -393.88161) (xy 346.556076 -393.879324) (xy 346.529406 -393.891008)
			(xy 346.469716 -393.978892) (xy 346.464731 -393.987047) (xy 346.460548 -394.005677) (xy 346.463471 -394.024547)
			(xy 346.467938 -394.032994) (xy 346.583508 -394.232892) (xy 346.596241 -394.25621) (xy 346.614335 -394.306158)
			(xy 346.623551 -394.358477) (xy 346.624148 -394.385038) (xy 346.624148 -394.385292) (xy 346.62363 -394.409281)
			(xy 346.616126 -394.456669) (xy 346.601303 -394.502299) (xy 346.579524 -394.545049) (xy 346.551325 -394.583866)
			(xy 346.517403 -394.617794) (xy 346.47859 -394.645998) (xy 346.435843 -394.667784) (xy 346.390215 -394.682615)
			(xy 346.342829 -394.690126) (xy 346.31884 -394.6906) (xy 346.295267 -394.690174) (xy 346.24868 -394.682939)
			(xy 346.203763 -394.668618) (xy 346.161584 -394.647555) (xy 346.123151 -394.620251) (xy 346.089378 -394.587355)
			(xy 346.061071 -394.549654) (xy 346.0496 -394.529056) (xy 346.049092 -394.528294) (xy 346.03563 -394.504926)
			(xy 346.030264 -394.496461) (xy 346.01437 -394.484275) (xy 345.995021 -394.479102) (xy 345.975166 -394.481732)
			(xy 345.966288 -394.486384) (xy 345.957144 -394.491718) (xy 345.951048 -394.5001) (xy 345.940118 -394.513998)
			(xy 345.914036 -394.537863) (xy 345.884011 -394.556525) (xy 345.851065 -394.569348) (xy 345.816324 -394.575894)
			(xy 345.798648 -394.5763) (xy 345.79814 -394.5763) (xy 345.779371 -394.575842) (xy 345.742552 -394.568525)
			(xy 345.707868 -394.554165) (xy 345.676653 -394.533313) (xy 345.650107 -394.506771) (xy 345.62925 -394.47556)
			(xy 345.614884 -394.440879) (xy 345.607561 -394.404061) (xy 345.607132 -394.385292) (xy 345.607586 -394.366197)
			(xy 345.615156 -394.328764) (xy 345.629993 -394.293573) (xy 345.65151 -394.26202) (xy 345.678852 -394.235357)
			(xy 345.710936 -394.21464) (xy 345.728544 -394.207238) (xy 345.738704 -394.203174) (xy 345.754198 -394.187426)
			(xy 345.783408 -394.104114) (xy 345.786637 -394.093536) (xy 345.784658 -394.071532) (xy 345.779598 -394.061696)
			(xy 345.651328 -393.839954) (xy 345.63939 -393.815824) (xy 345.63458 -393.806296) (xy 345.618787 -393.791978)
			(xy 345.598543 -393.785296) (xy 345.577329 -393.7874) (xy 345.558792 -393.797927) (xy 345.552014 -393.806172)
			(xy 345.541068 -393.82025) (xy 345.514885 -393.844454) (xy 345.484668 -393.863382) (xy 345.451464 -393.876378)
			(xy 345.416426 -393.882991) (xy 345.398598 -393.883388) (xy 345.39809 -393.883388) (xy 345.39121 -393.883387)
			(xy 345.37748 -393.882496) (xy 345.370658 -393.88161) (xy 345.35618 -393.879324) (xy 345.32951 -393.891008)
			(xy 345.26982 -393.978892) (xy 345.264835 -393.987047) (xy 345.260652 -394.005677) (xy 345.263575 -394.024547)
			(xy 345.268042 -394.032994) (xy 345.383612 -394.232892) (xy 345.396346 -394.25621) (xy 345.414439 -394.306158)
			(xy 345.423655 -394.358477) (xy 345.424252 -394.385038) (xy 345.424252 -394.385292) (xy 345.42373 -394.409281)
			(xy 345.416227 -394.456668) (xy 345.401403 -394.502298) (xy 345.379624 -394.545048) (xy 345.351427 -394.583865)
			(xy 345.317504 -394.617793) (xy 345.278692 -394.645997) (xy 345.235946 -394.667783) (xy 345.190319 -394.682614)
			(xy 345.142933 -394.690126) (xy 345.118944 -394.6906) (xy 345.11869 -394.6906) (xy 345.095116 -394.690214)
			(xy 345.048527 -394.682971) (xy 345.003608 -394.668644) (xy 344.96143 -394.647574) (xy 344.922997 -394.620263)
			(xy 344.889226 -394.587363) (xy 344.86092 -394.549656) (xy 344.84945 -394.529056) (xy 344.848942 -394.528294)
			(xy 344.83548 -394.504926) (xy 344.830063 -394.496499) (xy 344.814187 -394.484312) (xy 344.794856 -394.47913)
			(xy 344.775013 -394.481743) (xy 344.766138 -394.486384) (xy 344.756994 -394.491718) (xy 344.750898 -394.5001)
			(xy 344.73994 -394.513974) (xy 344.713865 -394.537841) (xy 344.683847 -394.556507) (xy 344.650908 -394.569336)
			(xy 344.616172 -394.575889) (xy 344.598498 -394.5763) (xy 344.59799 -394.5763) (xy 344.579216 -394.575812)
			(xy 344.542387 -394.568492) (xy 344.507691 -394.554135) (xy 344.476459 -394.533291) (xy 344.449889 -394.506759)
			(xy 344.428999 -394.475558) (xy 344.41459 -394.440883) (xy 344.407216 -394.404066) (xy 344.406728 -394.385292)
			(xy 344.407194 -394.366177) (xy 344.414756 -394.328705) (xy 344.429616 -394.293483) (xy 344.451181 -394.261918)
			(xy 344.47859 -394.23527) (xy 344.51075 -394.214602) (xy 344.528394 -394.207238) (xy 344.538554 -394.203174)
			(xy 344.554048 -394.187426) (xy 344.583258 -394.104114) (xy 344.586481 -394.093535) (xy 344.584504 -394.071532)
			(xy 344.579448 -394.061696) (xy 344.451178 -393.839954) (xy 344.43924 -393.815824) (xy 344.43436 -393.806338)
			(xy 344.418587 -393.792025) (xy 344.398364 -393.785339) (xy 344.377167 -393.78743) (xy 344.358641 -393.797939)
			(xy 344.351864 -393.806172) (xy 344.340889 -393.820226) (xy 344.314713 -393.844432) (xy 344.284503 -393.863364)
			(xy 344.251306 -393.876366) (xy 344.216274 -393.882986) (xy 344.198448 -393.883388) (xy 344.19794 -393.883388)
			(xy 344.19106 -393.883381) (xy 344.177331 -393.882494) (xy 344.170508 -393.88161) (xy 344.15603 -393.879324)
			(xy 344.12936 -393.891008) (xy 344.06967 -393.978892) (xy 344.064687 -393.987047) (xy 344.060508 -394.005677)
			(xy 344.063428 -394.024546) (xy 344.067892 -394.032994) (xy 344.183462 -394.232892) (xy 344.196289 -394.256224)
			(xy 344.214508 -394.306247) (xy 344.223767 -394.358673) (xy 344.224356 -394.385292) (xy 344.223831 -394.409268)
			(xy 344.216336 -394.45663) (xy 344.201528 -394.502239) (xy 344.179772 -394.544971) (xy 344.151602 -394.583776)
			(xy 344.117712 -394.617701) (xy 344.078935 -394.645909) (xy 344.036225 -394.667709) (xy 343.990632 -394.682563)
			(xy 343.943277 -394.690107) (xy 343.919302 -394.6906) (xy 343.918794 -394.6906) (xy 343.89522 -394.690211)
			(xy 343.848631 -394.682969) (xy 343.803713 -394.668642) (xy 343.761534 -394.647573) (xy 343.723101 -394.620262)
			(xy 343.68933 -394.587362) (xy 343.661024 -394.549656) (xy 343.649554 -394.529056) (xy 343.649046 -394.528294)
			(xy 343.635584 -394.504926) (xy 343.630163 -394.496502) (xy 343.614289 -394.484315) (xy 343.594959 -394.479132)
			(xy 343.575117 -394.481743) (xy 343.566242 -394.486384) (xy 343.557098 -394.491718) (xy 343.551002 -394.5001)
			(xy 343.540042 -394.513972) (xy 343.513968 -394.537839) (xy 343.48395 -394.556506) (xy 343.451011 -394.569335)
			(xy 343.416276 -394.575889) (xy 343.398602 -394.5763) (xy 343.398094 -394.5763) (xy 343.37932 -394.575809)
			(xy 343.342491 -394.568489) (xy 343.307796 -394.554133) (xy 343.276564 -394.533289) (xy 343.249993 -394.506758)
			(xy 343.229103 -394.475557) (xy 343.214694 -394.440883) (xy 343.20732 -394.404066) (xy 343.206832 -394.385292)
			(xy 343.207296 -394.366177) (xy 343.214858 -394.328704) (xy 343.229718 -394.293482) (xy 343.251283 -394.261917)
			(xy 343.278693 -394.235269) (xy 343.310853 -394.214602) (xy 343.328498 -394.207238) (xy 343.338658 -394.203174)
			(xy 343.354152 -394.187426) (xy 343.383362 -394.104114) (xy 343.386585 -394.093535) (xy 343.384608 -394.071532)
			(xy 343.379552 -394.061696) (xy 343.251282 -393.839954) (xy 343.239344 -393.815824) (xy 343.234599 -393.806258)
			(xy 343.218787 -393.791934) (xy 343.198524 -393.785256) (xy 343.177294 -393.787372) (xy 343.158747 -393.797917)
			(xy 343.151968 -393.806172) (xy 343.140991 -393.820224) (xy 343.114816 -393.84443) (xy 343.084606 -393.863363)
			(xy 343.05141 -393.876365) (xy 343.016378 -393.882986) (xy 342.998552 -393.883388) (xy 342.998044 -393.883388)
			(xy 342.991164 -393.883381) (xy 342.977435 -393.882494) (xy 342.970612 -393.88161) (xy 342.956134 -393.879324)
			(xy 342.929464 -393.891008) (xy 342.869774 -393.978892) (xy 342.864791 -393.987047) (xy 342.860611 -394.005677)
			(xy 342.863532 -394.024546) (xy 342.867996 -394.032994) (xy 342.983566 -394.232892) (xy 342.996393 -394.256223)
			(xy 343.014612 -394.306247) (xy 343.023871 -394.358673) (xy 343.02446 -394.385292) (xy 343.024031 -394.409273)
			(xy 343.016532 -394.456644) (xy 343.001719 -394.502261) (xy 342.979954 -394.544999) (xy 342.951774 -394.583809)
			(xy 342.917872 -394.617735) (xy 342.879082 -394.645942) (xy 342.836359 -394.667737) (xy 342.790753 -394.682582)
			(xy 342.743386 -394.690114) (xy 342.719406 -394.6906) (xy 342.718898 -394.6906) (xy 342.695324 -394.690208)
			(xy 342.648736 -394.682966) (xy 342.603817 -394.66864) (xy 342.561639 -394.647571) (xy 342.523206 -394.620261)
			(xy 342.489434 -394.587361) (xy 342.461128 -394.549656) (xy 342.449658 -394.529056) (xy 342.44915 -394.528294)
			(xy 342.435688 -394.504926) (xy 342.430263 -394.496504) (xy 342.41439 -394.484318) (xy 342.395061 -394.479134)
			(xy 342.375221 -394.481744) (xy 342.366346 -394.486384) (xy 342.357202 -394.491718) (xy 342.351106 -394.5001)
			(xy 342.3402 -394.514018) (xy 342.314112 -394.537881) (xy 342.284081 -394.55654) (xy 342.25113 -394.569358)
			(xy 342.216384 -394.575897) (xy 342.198706 -394.5763) (xy 342.198198 -394.5763) (xy 342.179424 -394.575805)
			(xy 342.142596 -394.568486) (xy 342.1079 -394.55413) (xy 342.076668 -394.533287) (xy 342.050097 -394.506757)
			(xy 342.029207 -394.475556) (xy 342.014798 -394.440883) (xy 342.007424 -394.404065) (xy 342.006936 -394.385292)
			(xy 342.007397 -394.366177) (xy 342.014959 -394.328704) (xy 342.02982 -394.293482) (xy 342.051386 -394.261917)
			(xy 342.078796 -394.235269) (xy 342.110957 -394.214602) (xy 342.128602 -394.207238) (xy 342.138762 -394.203174)
			(xy 342.154256 -394.187426) (xy 342.183466 -394.104114) (xy 342.186689 -394.093535) (xy 342.184711 -394.071532)
			(xy 342.179656 -394.061696) (xy 342.051386 -393.839954) (xy 342.039448 -393.815824) (xy 342.034698 -393.806262)
			(xy 342.018887 -393.791938) (xy 341.998626 -393.785259) (xy 341.977397 -393.787374) (xy 341.958851 -393.797918)
			(xy 341.952072 -393.806172) (xy 341.941167 -393.820251) (xy 341.915022 -393.844426) (xy 341.884851 -393.86334)
			(xy 341.8517 -393.876339) (xy 341.816714 -393.882973) (xy 341.79891 -393.883388) (xy 341.798402 -393.883388)
			(xy 341.770716 -393.881356) (xy 341.770462 -393.881356) (xy 341.760993 -393.880395) (xy 341.742478 -393.884733)
			(xy 341.726826 -393.895535) (xy 341.721186 -393.9032) (xy 341.669624 -393.978892) (xy 341.664639 -393.987047)
			(xy 341.660455 -394.005677) (xy 341.663378 -394.024547) (xy 341.667846 -394.032994) (xy 341.783416 -394.232892)
			(xy 341.79615 -394.256209) (xy 341.814243 -394.306158) (xy 341.823459 -394.358477) (xy 341.824056 -394.385038)
			(xy 341.824056 -394.385292) (xy 341.82353 -394.409281) (xy 341.816027 -394.456667) (xy 341.801203 -394.502297)
			(xy 341.779425 -394.545047) (xy 341.751228 -394.583863) (xy 341.717306 -394.617791) (xy 341.678494 -394.645996)
			(xy 341.635749 -394.667782) (xy 341.590122 -394.682614) (xy 341.542737 -394.690126) (xy 341.518748 -394.6906)
			(xy 341.495175 -394.690168) (xy 341.448589 -394.682933) (xy 341.403671 -394.668614) (xy 341.361493 -394.647552)
			(xy 341.323059 -394.620248) (xy 341.289286 -394.587354) (xy 341.260979 -394.549654) (xy 341.249508 -394.529056)
			(xy 341.249 -394.528294) (xy 341.235538 -394.504926) (xy 341.230163 -394.496467) (xy 341.214272 -394.484281)
			(xy 341.194926 -394.479107) (xy 341.175074 -394.481734) (xy 341.166196 -394.486384) (xy 341.157052 -394.491718)
			(xy 341.150956 -394.5001) (xy 341.140022 -394.513994) (xy 341.113941 -394.537859) (xy 341.083916 -394.556522)
			(xy 341.050972 -394.569346) (xy 341.016232 -394.575893) (xy 340.998556 -394.5763) (xy 340.998048 -394.5763)
			(xy 340.979279 -394.575835) (xy 340.94246 -394.56852) (xy 340.907777 -394.55416) (xy 340.876562 -394.53331)
			(xy 340.850016 -394.506769) (xy 340.829158 -394.475558) (xy 340.814792 -394.440878) (xy 340.807469 -394.404061)
			(xy 340.80704 -394.385292) (xy 340.807489 -394.366196) (xy 340.815059 -394.328763) (xy 340.829897 -394.293571)
			(xy 340.851415 -394.262018) (xy 340.878758 -394.235355) (xy 340.910843 -394.21464) (xy 340.928452 -394.207238)
			(xy 340.938612 -394.203174) (xy 340.954106 -394.187426) (xy 340.983316 -394.104114) (xy 340.986545 -394.093535)
			(xy 340.984565 -394.071532) (xy 340.979506 -394.061696) (xy 340.851236 -393.839954) (xy 340.839298 -393.815824)
			(xy 340.834477 -393.806303) (xy 340.818687 -393.791985) (xy 340.798446 -393.785303) (xy 340.777235 -393.787404)
			(xy 340.7587 -393.797929) (xy 340.751922 -393.806172) (xy 340.740971 -393.820246) (xy 340.714789 -393.84445)
			(xy 340.684573 -393.863379) (xy 340.651371 -393.876376) (xy 340.616334 -393.88299) (xy 340.598506 -393.883388)
			(xy 340.597998 -393.883388) (xy 340.591118 -393.883386) (xy 340.577388 -393.882495) (xy 340.570566 -393.88161)
			(xy 340.556088 -393.879324) (xy 340.529418 -393.891008) (xy 340.469728 -393.978892) (xy 340.464743 -393.987047)
			(xy 340.460559 -394.005677) (xy 340.463482 -394.024547) (xy 340.46795 -394.032994) (xy 340.58352 -394.232892)
			(xy 340.596254 -394.256209) (xy 340.614348 -394.306158) (xy 340.623563 -394.358476) (xy 340.62416 -394.385038)
			(xy 340.62416 -394.385292) (xy 340.623754 -394.409287) (xy 340.616247 -394.456687) (xy 340.601417 -394.502329)
			(xy 340.579628 -394.545088) (xy 340.551418 -394.583912) (xy 340.517482 -394.617844) (xy 340.478654 -394.646049)
			(xy 340.435892 -394.667832) (xy 340.390248 -394.682657) (xy 340.342847 -394.690157) (xy 340.318852 -394.6906)
			(xy 340.295279 -394.690164) (xy 340.248693 -394.682931) (xy 340.203776 -394.668612) (xy 340.161597 -394.647551)
			(xy 340.123164 -394.620247) (xy 340.089391 -394.587354) (xy 340.061083 -394.549653) (xy 340.049612 -394.529056)
			(xy 340.049104 -394.528294) (xy 340.035642 -394.504926) (xy 340.030263 -394.49647) (xy 340.014374 -394.484284)
			(xy 339.995029 -394.479109) (xy 339.975177 -394.481735) (xy 339.9663 -394.486384) (xy 339.957156 -394.491718)
			(xy 339.95106 -394.5001) (xy 339.940124 -394.513992) (xy 339.914043 -394.537858) (xy 339.884019 -394.556521)
			(xy 339.851076 -394.569345) (xy 339.816335 -394.575893) (xy 339.79866 -394.5763) (xy 339.798152 -394.5763)
			(xy 339.779383 -394.575891) (xy 339.742566 -394.56856) (xy 339.707888 -394.554187) (xy 339.676679 -394.533326)
			(xy 339.650138 -394.506778) (xy 339.629287 -394.475563) (xy 339.614924 -394.44088) (xy 339.607603 -394.404062)
			(xy 339.607144 -394.385292) (xy 339.607591 -394.366196) (xy 339.615161 -394.328762) (xy 339.629999 -394.293571)
			(xy 339.651517 -394.262018) (xy 339.678861 -394.235355) (xy 339.710947 -394.214639) (xy 339.728556 -394.207238)
			(xy 339.738716 -394.203174) (xy 339.75421 -394.187426) (xy 339.78342 -394.104114) (xy 339.786648 -394.093535)
			(xy 339.784669 -394.071532) (xy 339.77961 -394.061696) (xy 339.65134 -393.839954) (xy 339.639402 -393.815824)
			(xy 339.634576 -393.806306) (xy 339.618787 -393.791989) (xy 339.598548 -393.785306) (xy 339.577338 -393.787407)
			(xy 339.558804 -393.79793) (xy 339.552026 -393.806172) (xy 339.541073 -393.820244) (xy 339.514892 -393.844449)
			(xy 339.484676 -393.863378) (xy 339.451474 -393.876375) (xy 339.416438 -393.88299) (xy 339.39861 -393.883388)
			(xy 339.398102 -393.883388) (xy 339.391222 -393.883386) (xy 339.377492 -393.882495) (xy 339.37067 -393.88161)
			(xy 339.356192 -393.879324) (xy 339.329522 -393.891008) (xy 339.269832 -393.978892) (xy 339.264847 -393.987047)
			(xy 339.260662 -394.005677) (xy 339.263586 -394.024547) (xy 339.268054 -394.032994) (xy 339.383624 -394.232892)
			(xy 339.396359 -394.256209) (xy 339.414452 -394.306158) (xy 339.423667 -394.358476) (xy 339.424264 -394.385038)
			(xy 339.424264 -394.385292) (xy 339.423854 -394.409287) (xy 339.416347 -394.456687) (xy 339.401517 -394.502328)
			(xy 339.379729 -394.545087) (xy 339.351519 -394.583911) (xy 339.317583 -394.617843) (xy 339.278756 -394.646048)
			(xy 339.235995 -394.667831) (xy 339.190352 -394.682656) (xy 339.142951 -394.690157) (xy 339.118956 -394.6906)
			(xy 339.118702 -394.6906) (xy 339.095128 -394.690205) (xy 339.04854 -394.682963) (xy 339.003621 -394.668638)
			(xy 338.961443 -394.64757) (xy 338.92301 -394.62026) (xy 338.889238 -394.587361) (xy 338.860933 -394.549656)
			(xy 338.849462 -394.529056) (xy 338.848954 -394.528294) (xy 338.835492 -394.504926) (xy 338.830063 -394.496507)
			(xy 338.814191 -394.484321) (xy 338.794864 -394.479137) (xy 338.775025 -394.481745) (xy 338.76615 -394.486384)
			(xy 338.757006 -394.491718) (xy 338.75091 -394.5001) (xy 338.740002 -394.514016) (xy 338.713915 -394.537879)
			(xy 338.683883 -394.556539) (xy 338.650933 -394.569357) (xy 338.616187 -394.575897) (xy 338.59851 -394.5763)
			(xy 338.598002 -394.5763) (xy 338.579228 -394.575802) (xy 338.5424 -394.568484) (xy 338.507704 -394.554128)
			(xy 338.476472 -394.533286) (xy 338.449901 -394.506756) (xy 338.429011 -394.475555) (xy 338.414602 -394.440882)
			(xy 338.407228 -394.404065) (xy 338.40674 -394.385292) (xy 338.407199 -394.366177) (xy 338.414761 -394.328703)
			(xy 338.429622 -394.293481) (xy 338.451188 -394.261916) (xy 338.478599 -394.235268) (xy 338.510761 -394.214602)
			(xy 338.528406 -394.207238) (xy 338.538566 -394.203174) (xy 338.55406 -394.187426) (xy 338.58327 -394.104114)
			(xy 338.586492 -394.093534) (xy 338.584515 -394.071533) (xy 338.57946 -394.061696) (xy 338.45119 -393.839954)
			(xy 338.439252 -393.815824) (xy 338.434496 -393.806265) (xy 338.418687 -393.791942) (xy 338.398427 -393.785263)
			(xy 338.3772 -393.787376) (xy 338.358655 -393.797919) (xy 338.351876 -393.806172) (xy 338.340951 -393.820268)
			(xy 338.314763 -393.844471) (xy 338.28454 -393.863396) (xy 338.251332 -393.876387) (xy 338.21629 -393.882994)
			(xy 338.19846 -393.883388) (xy 338.197952 -393.883388) (xy 338.191072 -393.88338) (xy 338.177343 -393.882493)
			(xy 338.17052 -393.88161) (xy 338.156042 -393.879324) (xy 338.129372 -393.891008) (xy 338.069682 -393.978892)
			(xy 338.064699 -393.987047) (xy 338.060519 -394.005677) (xy 338.06344 -394.024546) (xy 338.067904 -394.032994)
			(xy 338.183474 -394.232892) (xy 338.196301 -394.256223) (xy 338.21452 -394.306247) (xy 338.223779 -394.358673)
			(xy 338.224368 -394.385292) (xy 338.223931 -394.409272) (xy 338.216433 -394.456643) (xy 338.201619 -394.502259)
			(xy 338.179855 -394.544997) (xy 338.151676 -394.583806) (xy 338.117775 -394.617732) (xy 338.078987 -394.645939)
			(xy 338.036264 -394.667734) (xy 337.990659 -394.682581) (xy 337.943294 -394.690113) (xy 337.919314 -394.6906)
			(xy 337.918806 -394.6906) (xy 337.895232 -394.690201) (xy 337.848644 -394.682961) (xy 337.803726 -394.668636)
			(xy 337.761547 -394.647568) (xy 337.723114 -394.620259) (xy 337.689342 -394.58736) (xy 337.661037 -394.549655)
			(xy 337.649566 -394.529056) (xy 337.649058 -394.528294) (xy 337.635596 -394.504926) (xy 337.630264 -394.496436)
			(xy 337.614357 -394.48425) (xy 337.594997 -394.479084) (xy 337.575134 -394.481725) (xy 337.566254 -394.486384)
			(xy 337.55711 -394.491718) (xy 337.551014 -394.5001) (xy 337.540104 -394.514014) (xy 337.514017 -394.537878)
			(xy 337.483986 -394.556537) (xy 337.451037 -394.569356) (xy 337.416291 -394.575897) (xy 337.398614 -394.5763)
			(xy 337.398106 -394.5763) (xy 337.379332 -394.575798) (xy 337.342504 -394.568481) (xy 337.307809 -394.554126)
			(xy 337.276577 -394.533284) (xy 337.250006 -394.506754) (xy 337.229115 -394.475555) (xy 337.214706 -394.440882)
			(xy 337.207332 -394.404065) (xy 337.206844 -394.385292) (xy 337.2073 -394.366177) (xy 337.214863 -394.328703)
			(xy 337.229724 -394.29348) (xy 337.251291 -394.261915) (xy 337.278702 -394.235268) (xy 337.310864 -394.214601)
			(xy 337.32851 -394.207238) (xy 337.33867 -394.203174) (xy 337.354164 -394.187426) (xy 337.383374 -394.104114)
			(xy 337.386596 -394.093534) (xy 337.384619 -394.071533) (xy 337.379564 -394.061696) (xy 337.251294 -393.839954)
			(xy 337.239356 -393.815824) (xy 337.234594 -393.806268) (xy 337.218787 -393.791946) (xy 337.198529 -393.785266)
			(xy 337.177303 -393.787379) (xy 337.158759 -393.79792) (xy 337.15198 -393.806172) (xy 337.141053 -393.820266)
			(xy 337.114865 -393.844469) (xy 337.084643 -393.863395) (xy 337.051435 -393.876386) (xy 337.016394 -393.882994)
			(xy 336.998564 -393.883388) (xy 336.998056 -393.883388) (xy 336.991176 -393.88338) (xy 336.977447 -393.882493)
			(xy 336.970624 -393.88161) (xy 336.956146 -393.879324) (xy 336.929476 -393.891008) (xy 336.869786 -393.978892)
			(xy 336.864803 -393.987047) (xy 336.860622 -394.005677) (xy 336.863543 -394.024546) (xy 336.868008 -394.032994)
			(xy 336.983578 -394.232892) (xy 336.996406 -394.256223) (xy 337.014624 -394.306247) (xy 337.023883 -394.358673)
			(xy 337.024472 -394.385292) (xy 337.024031 -394.409272) (xy 337.016533 -394.456643) (xy 337.00172 -394.502258)
			(xy 336.979956 -394.544996) (xy 336.951778 -394.583805) (xy 336.917877 -394.617731) (xy 336.879089 -394.645938)
			(xy 336.836367 -394.667733) (xy 336.790763 -394.68258) (xy 336.743398 -394.690113) (xy 336.719418 -394.6906)
			(xy 336.71891 -394.6906) (xy 336.695336 -394.690198) (xy 336.648748 -394.682958) (xy 336.60383 -394.668634)
			(xy 336.561652 -394.647566) (xy 336.523218 -394.620258) (xy 336.489447 -394.58736) (xy 336.461141 -394.549655)
			(xy 336.44967 -394.529056) (xy 336.449162 -394.528294) (xy 336.4357 -394.504926) (xy 336.430364 -394.496439)
			(xy 336.414459 -394.484253) (xy 336.3951 -394.479086) (xy 336.375237 -394.481726) (xy 336.366358 -394.486384)
			(xy 336.357214 -394.491718) (xy 336.351118 -394.5001) (xy 336.340205 -394.514012) (xy 336.314119 -394.537876)
			(xy 336.284089 -394.556536) (xy 336.25114 -394.569355) (xy 336.216395 -394.575896) (xy 336.198718 -394.5763)
			(xy 336.19821 -394.5763) (xy 336.179436 -394.575794) (xy 336.142608 -394.568478) (xy 336.107913 -394.554124)
			(xy 336.076681 -394.533282) (xy 336.05011 -394.506753) (xy 336.029219 -394.475554) (xy 336.01481 -394.440881)
			(xy 336.007436 -394.404065) (xy 336.006948 -394.385292) (xy 336.007402 -394.366177) (xy 336.014964 -394.328702)
			(xy 336.029826 -394.29348) (xy 336.051393 -394.261914) (xy 336.078805 -394.235267) (xy 336.110968 -394.214601)
			(xy 336.128614 -394.207238) (xy 336.138774 -394.203174) (xy 336.154268 -394.187426) (xy 336.183478 -394.104114)
			(xy 336.186699 -394.093534) (xy 336.184722 -394.071533) (xy 336.179668 -394.061696) (xy 336.051398 -393.839954)
			(xy 336.03946 -393.815824) (xy 336.034692 -393.806272) (xy 336.018887 -393.79195) (xy 335.998631 -393.78527)
			(xy 335.977406 -393.787382) (xy 335.958863 -393.797921) (xy 335.952084 -393.806172) (xy 335.941172 -393.820245)
			(xy 335.915029 -393.844421) (xy 335.88486 -393.863336) (xy 335.85171 -393.876336) (xy 335.816726 -393.882972)
			(xy 335.798922 -393.883388) (xy 335.798414 -393.883388) (xy 335.778386 -393.882943) (xy 335.739206 -393.874617)
			(xy 335.702613 -393.858327) (xy 335.670206 -393.834785) (xy 335.643403 -393.805019) (xy 335.623374 -393.770331)
			(xy 335.610996 -393.732236) (xy 335.606809 -393.6924) (xy 322.143388 -393.6924) (xy 322.455794 -394.232892)
			(xy 322.468623 -394.256222) (xy 322.486841 -394.306246) (xy 322.496099 -394.358673) (xy 322.496688 -394.385292)
			(xy 322.496231 -394.409271) (xy 322.488733 -394.45664) (xy 322.473921 -394.502254) (xy 322.452159 -394.544991)
			(xy 322.423982 -394.5838) (xy 322.390084 -394.617725) (xy 322.351298 -394.645932) (xy 322.308578 -394.667728)
			(xy 322.262976 -394.682577) (xy 322.215613 -394.690112) (xy 322.191634 -394.6906) (xy 322.191126 -394.6906)
			(xy 322.167553 -394.690185) (xy 322.120965 -394.682948) (xy 322.076047 -394.668626) (xy 322.033869 -394.64756)
			(xy 321.995436 -394.620254) (xy 321.961663 -394.587357) (xy 321.933357 -394.549655) (xy 321.921886 -394.529056)
			(xy 321.921378 -394.528294) (xy 321.907916 -394.504926) (xy 321.902564 -394.496451) (xy 321.886665 -394.484264)
			(xy 321.867311 -394.479095) (xy 321.847453 -394.481729) (xy 321.838574 -394.486384) (xy 321.82943 -394.491718)
			(xy 321.823334 -394.5001) (xy 321.812412 -394.514004) (xy 321.786328 -394.537869) (xy 321.756301 -394.55653)
			(xy 321.723353 -394.569351) (xy 321.68861 -394.575895) (xy 321.670934 -394.5763) (xy 321.670426 -394.5763)
			(xy 321.651653 -394.57578) (xy 321.614826 -394.568466) (xy 321.58013 -394.554115) (xy 321.548898 -394.533276)
			(xy 321.522327 -394.506748) (xy 321.501436 -394.475551) (xy 321.487026 -394.440879) (xy 321.479652 -394.404064)
			(xy 321.479164 -394.385292) (xy 321.479608 -394.366176) (xy 321.487171 -394.328701) (xy 321.502034 -394.293477)
			(xy 321.523603 -394.261911) (xy 321.551018 -394.235265) (xy 321.583183 -394.2146) (xy 321.60083 -394.207238)
			(xy 321.61099 -394.203174) (xy 321.626484 -394.187426) (xy 321.655694 -394.104114) (xy 321.658925 -394.093536)
			(xy 321.656945 -394.071531) (xy 321.651884 -394.061696) (xy 321.523614 -393.839954) (xy 321.511422 -393.81557)
			(xy 321.506565 -393.806067) (xy 321.490789 -393.791741) (xy 321.470556 -393.785051) (xy 321.449349 -393.78715)
			(xy 321.43082 -393.797675) (xy 321.424046 -393.805918) (xy 321.413089 -393.820003) (xy 321.386931 -393.844266)
			(xy 321.356725 -393.863253) (xy 321.323519 -393.876305) (xy 321.288469 -393.882968) (xy 321.27063 -393.883388)
			(xy 321.270122 -393.883388) (xy 321.242944 -393.88161) (xy 321.228212 -393.879578) (xy 321.201796 -393.891008)
			(xy 321.14236 -393.978892) (xy 321.137369 -393.986983) (xy 321.133275 -394.005538) (xy 321.136168 -394.024318)
			(xy 321.140582 -394.03274) (xy 321.255898 -394.232892) (xy 321.268719 -394.256226) (xy 321.286942 -394.306248)
			(xy 321.296203 -394.358674) (xy 321.296792 -394.385292) (xy 321.296331 -394.409271) (xy 321.288834 -394.45664)
			(xy 321.274022 -394.502253) (xy 321.25226 -394.54499) (xy 321.224083 -394.583798) (xy 321.190186 -394.617723)
			(xy 321.1514 -394.645931) (xy 321.108681 -394.667727) (xy 321.063079 -394.682576) (xy 321.015717 -394.690112)
			(xy 320.991738 -394.6906) (xy 320.99123 -394.6906) (xy 320.967657 -394.690182) (xy 320.92107 -394.682945)
			(xy 320.876152 -394.668624) (xy 320.833973 -394.647559) (xy 320.79554 -394.620253) (xy 320.761768 -394.587357)
			(xy 320.733461 -394.549654) (xy 320.72199 -394.529056) (xy 320.721482 -394.528294) (xy 320.70802 -394.504926)
			(xy 320.702645 -394.496482) (xy 320.686768 -394.484315) (xy 320.667457 -394.479097) (xy 320.647613 -394.481611)
			(xy 320.638678 -394.48613) (xy 320.629534 -394.491464) (xy 320.623184 -394.499846) (xy 320.612209 -394.513787)
			(xy 320.586064 -394.537766) (xy 320.555943 -394.556509) (xy 320.522882 -394.569372) (xy 320.488014 -394.575913)
			(xy 320.470276 -394.5763) (xy 320.451507 -394.57587) (xy 320.414692 -394.568542) (xy 320.380014 -394.554174)
			(xy 320.348804 -394.533316) (xy 320.322264 -394.506771) (xy 320.301411 -394.475558) (xy 320.287048 -394.440877)
			(xy 320.279727 -394.404061) (xy 320.279268 -394.385292) (xy 320.2797 -394.366195) (xy 320.287271 -394.328759)
			(xy 320.302111 -394.293567) (xy 320.323632 -394.262013) (xy 320.35098 -394.235351) (xy 320.383069 -394.214638)
			(xy 320.40068 -394.207238) (xy 320.411094 -394.203174) (xy 320.426588 -394.187426) (xy 320.455798 -394.104114)
			(xy 320.45886 -394.093564) (xy 320.456758 -394.071719) (xy 320.451734 -394.06195) (xy 320.323718 -393.839954)
			(xy 320.311526 -393.81557) (xy 320.306664 -393.80607) (xy 320.290889 -393.791744) (xy 320.270658 -393.785055)
			(xy 320.249452 -393.787152) (xy 320.230923 -393.797676) (xy 320.22415 -393.805918) (xy 320.213191 -393.820001)
			(xy 320.187033 -393.844264) (xy 320.156827 -393.863251) (xy 320.123623 -393.876304) (xy 320.088572 -393.882968)
			(xy 320.070734 -393.883388) (xy 320.070226 -393.883388) (xy 320.043048 -393.88161) (xy 320.028316 -393.879578)
			(xy 320.0019 -393.891008) (xy 319.942464 -393.978892) (xy 319.937473 -393.986983) (xy 319.933379 -394.005538)
			(xy 319.936271 -394.024319) (xy 319.940686 -394.03274) (xy 320.056002 -394.232892) (xy 320.068824 -394.256226)
			(xy 320.087046 -394.306248) (xy 320.096307 -394.358674) (xy 320.096896 -394.385292) (xy 320.096453 -394.409298)
			(xy 320.08894 -394.456719) (xy 320.074096 -394.502379) (xy 320.052288 -394.545153) (xy 320.024055 -394.583987)
			(xy 319.99009 -394.617922) (xy 319.951233 -394.646123) (xy 319.908441 -394.667895) (xy 319.862768 -394.6827)
			(xy 319.815341 -394.690174) (xy 319.791334 -394.6906) (xy 319.79108 -394.6906) (xy 319.767505 -394.690222)
			(xy 319.720916 -394.682978) (xy 319.675997 -394.668649) (xy 319.633819 -394.647578) (xy 319.595386 -394.620266)
			(xy 319.561615 -394.587364) (xy 319.53331 -394.549657) (xy 319.52184 -394.529056) (xy 319.521332 -394.528294)
			(xy 319.50787 -394.504926) (xy 319.502463 -394.496491) (xy 319.486584 -394.484304) (xy 319.467249 -394.479125)
			(xy 319.447404 -394.481741) (xy 319.438528 -394.486384) (xy 319.429384 -394.491718) (xy 319.423288 -394.5001)
			(xy 319.412336 -394.513979) (xy 319.38626 -394.537845) (xy 319.356239 -394.556511) (xy 319.323299 -394.569338)
			(xy 319.288562 -394.57589) (xy 319.270888 -394.5763) (xy 319.27038 -394.5763) (xy 319.251611 -394.575866)
			(xy 319.214796 -394.568539) (xy 319.180118 -394.554171) (xy 319.148909 -394.533314) (xy 319.122368 -394.50677)
			(xy 319.101515 -394.475557) (xy 319.087153 -394.440877) (xy 319.079831 -394.404061) (xy 319.079372 -394.385292)
			(xy 319.079801 -394.366195) (xy 319.087373 -394.328759) (xy 319.102213 -394.293566) (xy 319.123735 -394.262013)
			(xy 319.151083 -394.235351) (xy 319.183173 -394.214638) (xy 319.200784 -394.207238) (xy 319.210944 -394.203174)
			(xy 319.226438 -394.187426) (xy 319.255648 -394.104114) (xy 319.258873 -394.093535) (xy 319.256895 -394.071532)
			(xy 319.251838 -394.061696) (xy 319.123568 -393.839954) (xy 319.11163 -393.815824) (xy 319.106764 -393.806329)
			(xy 319.090987 -393.792015) (xy 319.07076 -393.785331) (xy 319.04956 -393.787424) (xy 319.031031 -393.797936)
			(xy 319.024254 -393.806172) (xy 319.013285 -393.820231) (xy 318.987108 -393.844436) (xy 318.956896 -393.863368)
			(xy 318.923698 -393.876368) (xy 318.888664 -393.882987) (xy 318.870838 -393.883388) (xy 318.87033 -393.883388)
			(xy 318.86345 -393.883383) (xy 318.849721 -393.882494) (xy 318.842898 -393.88161) (xy 318.82842 -393.879324)
			(xy 318.80175 -393.891008) (xy 318.74206 -393.978892) (xy 318.737078 -393.987047) (xy 318.732899 -394.005677)
			(xy 318.735819 -394.024546) (xy 318.740282 -394.032994) (xy 318.855852 -394.232892) (xy 318.868589 -394.256208)
			(xy 318.886681 -394.306157) (xy 318.895896 -394.358476) (xy 318.896492 -394.385038) (xy 318.896492 -394.385292)
			(xy 318.896054 -394.409286) (xy 318.888548 -394.456682) (xy 318.87372 -394.502321) (xy 318.851934 -394.545079)
			(xy 318.823728 -394.583901) (xy 318.789795 -394.617833) (xy 318.750972 -394.646038) (xy 318.708214 -394.667823)
			(xy 318.662575 -394.68265) (xy 318.615178 -394.690155) (xy 318.591184 -394.6906) (xy 318.56761 -394.690219)
			(xy 318.521021 -394.682975) (xy 318.476102 -394.668647) (xy 318.433923 -394.647576) (xy 318.395491 -394.620265)
			(xy 318.361719 -394.587363) (xy 318.333414 -394.549656) (xy 318.321944 -394.529056) (xy 318.321436 -394.528294)
			(xy 318.307974 -394.504926) (xy 318.302544 -394.496523) (xy 318.286687 -394.484355) (xy 318.267395 -394.479127)
			(xy 318.247564 -394.481622) (xy 318.238632 -394.48613) (xy 318.229488 -394.491464) (xy 318.223138 -394.499846)
			(xy 318.212189 -394.513809) (xy 318.186037 -394.537786) (xy 318.15591 -394.556525) (xy 318.122843 -394.569383)
			(xy 318.08797 -394.575917) (xy 318.07023 -394.5763) (xy 318.051457 -394.575776) (xy 318.01463 -394.568463)
			(xy 317.979935 -394.554112) (xy 317.948702 -394.533274) (xy 317.922131 -394.506747) (xy 317.90124 -394.47555)
			(xy 317.88683 -394.440879) (xy 317.879456 -394.404064) (xy 317.878968 -394.385292) (xy 317.879409 -394.366176)
			(xy 317.886972 -394.3287) (xy 317.901836 -394.293476) (xy 317.923406 -394.261911) (xy 317.950821 -394.235264)
			(xy 317.982987 -394.2146) (xy 318.000634 -394.207238) (xy 318.011048 -394.203174) (xy 318.026542 -394.187426)
			(xy 318.055752 -394.104114) (xy 318.058807 -394.093563) (xy 318.056708 -394.07172) (xy 318.051688 -394.06195)
			(xy 317.923672 -393.839954) (xy 317.91148 -393.81557) (xy 317.906682 -393.806032) (xy 317.890889 -393.791701)
			(xy 317.870639 -393.785015) (xy 317.849417 -393.787124) (xy 317.830879 -393.797665) (xy 317.824104 -393.805918)
			(xy 317.813171 -393.820023) (xy 317.787007 -393.844284) (xy 317.756795 -393.863268) (xy 317.723584 -393.876315)
			(xy 317.688528 -393.882972) (xy 317.670688 -393.883388) (xy 317.67018 -393.883388) (xy 317.643002 -393.88161)
			(xy 317.62827 -393.879578) (xy 317.601854 -393.891008) (xy 317.542418 -393.978892) (xy 317.537425 -393.986983)
			(xy 317.533326 -394.005538) (xy 317.536222 -394.024319) (xy 317.54064 -394.03274) (xy 317.655956 -394.232892)
			(xy 317.668693 -394.256208) (xy 317.686785 -394.306157) (xy 317.696 -394.358476) (xy 317.696596 -394.385038)
			(xy 317.696596 -394.385292) (xy 317.696154 -394.409286) (xy 317.688648 -394.456682) (xy 317.67382 -394.50232)
			(xy 317.652035 -394.545077) (xy 317.623829 -394.5839) (xy 317.589897 -394.617831) (xy 317.551074 -394.646037)
			(xy 317.508317 -394.667822) (xy 317.462678 -394.682649) (xy 317.415282 -394.690155) (xy 317.391288 -394.6906)
			(xy 317.391034 -394.6906) (xy 317.367461 -394.690179) (xy 317.320874 -394.682942) (xy 317.275956 -394.668622)
			(xy 317.233778 -394.647557) (xy 317.195344 -394.620252) (xy 317.161572 -394.587356) (xy 317.133265 -394.549654)
			(xy 317.121794 -394.529056) (xy 317.121286 -394.528294) (xy 317.107824 -394.504926) (xy 317.102464 -394.496456)
			(xy 317.086567 -394.48427) (xy 317.067217 -394.479099) (xy 317.04736 -394.481731) (xy 317.038482 -394.486384)
			(xy 317.029338 -394.491718) (xy 317.023242 -394.5001) (xy 317.012316 -394.514001) (xy 316.986233 -394.537866)
			(xy 316.956206 -394.556527) (xy 316.92326 -394.569349) (xy 316.888518 -394.575894) (xy 316.870842 -394.5763)
			(xy 316.870334 -394.5763) (xy 316.851561 -394.575773) (xy 316.814734 -394.568461) (xy 316.780039 -394.55411)
			(xy 316.748807 -394.533272) (xy 316.722235 -394.506746) (xy 316.701344 -394.475549) (xy 316.686934 -394.440879)
			(xy 316.67956 -394.404064) (xy 316.679072 -394.385292) (xy 316.67951 -394.366176) (xy 316.687074 -394.3287)
			(xy 316.701938 -394.293476) (xy 316.723508 -394.26191) (xy 316.750924 -394.235263) (xy 316.78309 -394.2146)
			(xy 316.800738 -394.207238) (xy 316.810898 -394.203174) (xy 316.826392 -394.187426) (xy 316.855602 -394.104114)
			(xy 316.858832 -394.093536) (xy 316.856852 -394.071531) (xy 316.851792 -394.061696) (xy 316.723522 -393.839954)
			(xy 316.711584 -393.815824) (xy 316.706783 -393.806291) (xy 316.690987 -393.791972) (xy 316.670741 -393.785291)
			(xy 316.649525 -393.787396) (xy 316.630986 -393.797926) (xy 316.624208 -393.806172) (xy 316.613265 -393.820253)
			(xy 316.587081 -393.844457) (xy 316.556863 -393.863384) (xy 316.523659 -393.87638) (xy 316.48862 -393.882991)
			(xy 316.470792 -393.883388) (xy 316.470284 -393.883388) (xy 316.463404 -393.883388) (xy 316.449674 -393.882496)
			(xy 316.442852 -393.88161) (xy 316.428374 -393.879324) (xy 316.401704 -393.891008) (xy 316.342014 -393.978892)
			(xy 316.337029 -393.987047) (xy 316.332847 -394.005677) (xy 316.335769 -394.024547) (xy 316.340236 -394.032994)
			(xy 316.455806 -394.232892) (xy 316.468628 -394.256226) (xy 316.48685 -394.306248) (xy 316.496111 -394.358674)
			(xy 316.4967 -394.385292) (xy 316.496231 -394.409271) (xy 316.488734 -394.456639) (xy 316.473922 -394.502251)
			(xy 316.452161 -394.544988) (xy 316.423986 -394.583795) (xy 316.390089 -394.617721) (xy 316.351304 -394.645928)
			(xy 316.308586 -394.667725) (xy 316.262986 -394.682574) (xy 316.215624 -394.690111) (xy 316.191646 -394.6906)
			(xy 316.191138 -394.6906) (xy 316.167565 -394.690176) (xy 316.120978 -394.68294) (xy 316.07606 -394.66862)
			(xy 316.033882 -394.647556) (xy 315.995448 -394.620251) (xy 315.961676 -394.587356) (xy 315.933369 -394.549654)
			(xy 315.921898 -394.529056) (xy 315.92139 -394.528294) (xy 315.907928 -394.504926) (xy 315.902564 -394.496459)
			(xy 315.886669 -394.484273) (xy 315.867319 -394.479101) (xy 315.847464 -394.481731) (xy 315.838586 -394.486384)
			(xy 315.829442 -394.491718) (xy 315.823346 -394.5001) (xy 315.812418 -394.513999) (xy 315.786335 -394.537864)
			(xy 315.756309 -394.556526) (xy 315.723364 -394.569348) (xy 315.688622 -394.575894) (xy 315.670946 -394.5763)
			(xy 315.670438 -394.5763) (xy 315.651665 -394.575769) (xy 315.614838 -394.568458) (xy 315.580143 -394.554108)
			(xy 315.548911 -394.533271) (xy 315.522339 -394.506745) (xy 315.501448 -394.475548) (xy 315.487039 -394.440878)
			(xy 315.479664 -394.404064) (xy 315.479176 -394.385292) (xy 315.479675 -394.36618) (xy 315.487234 -394.328711)
			(xy 315.502089 -394.293492) (xy 315.523648 -394.261928) (xy 315.55105 -394.235278) (xy 315.583201 -394.214606)
			(xy 315.600842 -394.207238) (xy 315.611002 -394.203174) (xy 315.626496 -394.187426) (xy 315.655706 -394.104114)
			(xy 315.658935 -394.093536) (xy 315.656956 -394.071532) (xy 315.651896 -394.061696) (xy 315.523626 -393.839954)
			(xy 315.511688 -393.815824) (xy 315.506881 -393.806295) (xy 315.491087 -393.791976) (xy 315.470842 -393.785294)
			(xy 315.449628 -393.787398) (xy 315.43109 -393.797927) (xy 315.424312 -393.806172) (xy 315.413367 -393.820251)
			(xy 315.387184 -393.844455) (xy 315.356966 -393.863383) (xy 315.323762 -393.876379) (xy 315.288724 -393.882991)
			(xy 315.270896 -393.883388) (xy 315.270388 -393.883388) (xy 315.263508 -393.883387) (xy 315.249778 -393.882496)
			(xy 315.242956 -393.88161) (xy 315.228478 -393.879324) (xy 315.201808 -393.891008) (xy 315.142118 -393.978892)
			(xy 315.137133 -393.987047) (xy 315.13295 -394.005677) (xy 315.135873 -394.024547) (xy 315.14034 -394.032994)
			(xy 315.25591 -394.232892) (xy 315.268732 -394.256226) (xy 315.286954 -394.306248) (xy 315.296215 -394.358673)
			(xy 315.296804 -394.385292) (xy 315.296354 -394.409298) (xy 315.28884 -394.456718) (xy 315.273997 -394.502377)
			(xy 315.25219 -394.545151) (xy 315.223957 -394.583984) (xy 315.189994 -394.61792) (xy 315.151137 -394.646121)
			(xy 315.108346 -394.667893) (xy 315.062674 -394.682698) (xy 315.015248 -394.690173) (xy 314.991242 -394.6906)
			(xy 314.990988 -394.6906) (xy 314.967414 -394.690216) (xy 314.920825 -394.682973) (xy 314.875906 -394.668645)
			(xy 314.833728 -394.647575) (xy 314.795295 -394.620264) (xy 314.761523 -394.587363) (xy 314.733218 -394.549656)
			(xy 314.721748 -394.529056) (xy 314.72124 -394.528294) (xy 314.707778 -394.504926) (xy 314.702363 -394.496497)
			(xy 314.686486 -394.48431) (xy 314.667154 -394.479129) (xy 314.647311 -394.481742) (xy 314.638436 -394.486384)
			(xy 314.629292 -394.491718) (xy 314.623196 -394.5001) (xy 314.612239 -394.513975) (xy 314.586164 -394.537842)
			(xy 314.556145 -394.556508) (xy 314.523206 -394.569336) (xy 314.48847 -394.575889) (xy 314.470796 -394.5763)
			(xy 314.470288 -394.5763) (xy 314.45152 -394.575859) (xy 314.414705 -394.568534) (xy 314.380027 -394.554167)
			(xy 314.348817 -394.533311) (xy 314.322276 -394.506767) (xy 314.301424 -394.475556) (xy 314.287061 -394.440876)
			(xy 314.279739 -394.40406) (xy 314.27928 -394.385292) (xy 314.279704 -394.366195) (xy 314.287276 -394.328758)
			(xy 314.302117 -394.293565) (xy 314.32364 -394.262011) (xy 314.350989 -394.235349) (xy 314.38308 -394.214637)
			(xy 314.400692 -394.207238) (xy 314.410852 -394.203174) (xy 314.426346 -394.187426) (xy 314.455556 -394.104114)
			(xy 314.45878 -394.093535) (xy 314.456802 -394.071532) (xy 314.451746 -394.061696) (xy 314.323476 -393.839954)
			(xy 314.311538 -393.815824) (xy 314.306661 -393.806336) (xy 314.290887 -393.792023) (xy 314.270663 -393.785337)
			(xy 314.249466 -393.787429) (xy 314.230939 -393.797938) (xy 314.224162 -393.806172) (xy 314.213188 -393.820227)
			(xy 314.187012 -393.844433) (xy 314.156802 -393.863365) (xy 314.123605 -393.876367) (xy 314.088572 -393.882986)
			(xy 314.070746 -393.883388) (xy 314.070238 -393.883388) (xy 314.04306 -393.88161) (xy 314.028328 -393.879578)
			(xy 314.001912 -393.891008) (xy 313.942476 -393.978892) (xy 313.937485 -393.986983) (xy 313.933389 -394.005538)
			(xy 313.936282 -394.024319) (xy 313.940698 -394.03274) (xy 314.056014 -394.232892) (xy 314.068837 -394.256226)
			(xy 314.087058 -394.306248) (xy 314.096319 -394.358673) (xy 314.096908 -394.385292) (xy 314.096454 -394.409298)
			(xy 314.08894 -394.456717) (xy 314.074097 -394.502377) (xy 314.052291 -394.54515) (xy 314.024058 -394.583983)
			(xy 313.990095 -394.617918) (xy 313.95124 -394.646119) (xy 313.908449 -394.667891) (xy 313.862778 -394.682698)
			(xy 313.815352 -394.690173) (xy 313.791346 -394.6906) (xy 313.791092 -394.6906) (xy 313.767518 -394.690213)
			(xy 313.720929 -394.68297) (xy 313.67601 -394.668643) (xy 313.633832 -394.647573) (xy 313.595399 -394.620263)
			(xy 313.561628 -394.587362) (xy 313.533322 -394.549656) (xy 313.521852 -394.529056) (xy 313.521344 -394.528294)
			(xy 313.507882 -394.504926) (xy 313.502463 -394.4965) (xy 313.486588 -394.484313) (xy 313.467257 -394.479131)
			(xy 313.447415 -394.481743) (xy 313.43854 -394.486384) (xy 313.429396 -394.491718) (xy 313.4233 -394.5001)
			(xy 313.412341 -394.513973) (xy 313.386266 -394.53784) (xy 313.356248 -394.556506) (xy 313.323309 -394.569335)
			(xy 313.288574 -394.575889) (xy 313.2709 -394.5763) (xy 313.270392 -394.5763) (xy 313.251624 -394.575855)
			(xy 313.214809 -394.568531) (xy 313.180131 -394.554165) (xy 313.148921 -394.533309) (xy 313.12238 -394.506766)
			(xy 313.101528 -394.475555) (xy 313.087165 -394.440875) (xy 313.079843 -394.40406) (xy 313.079384 -394.385292)
			(xy 313.079806 -394.366194) (xy 313.087378 -394.328758) (xy 313.102219 -394.293564) (xy 313.123742 -394.26201)
			(xy 313.151092 -394.235349) (xy 313.183184 -394.214637) (xy 313.200796 -394.207238) (xy 313.210956 -394.203174)
			(xy 313.22645 -394.187426) (xy 313.25566 -394.104114) (xy 313.258884 -394.093535) (xy 313.256906 -394.071532)
			(xy 313.25185 -394.061696) (xy 313.12358 -393.839954) (xy 313.111642 -393.815824) (xy 313.1069 -393.806257)
			(xy 313.091087 -393.791933) (xy 313.070823 -393.785254) (xy 313.049593 -393.78737) (xy 313.031045 -393.797917)
			(xy 313.024266 -393.806172) (xy 313.01329 -393.820225) (xy 312.987115 -393.844431) (xy 312.956905 -393.863364)
			(xy 312.923708 -393.876366) (xy 312.888676 -393.882986) (xy 312.87085 -393.883388) (xy 312.870342 -393.883388)
			(xy 312.863462 -393.883381) (xy 312.849733 -393.882494) (xy 312.84291 -393.88161) (xy 312.828432 -393.879324)
			(xy 312.801762 -393.891008) (xy 312.742072 -393.978892) (xy 312.737089 -393.987047) (xy 312.73291 -394.005677)
			(xy 312.73583 -394.024546) (xy 312.740294 -394.032994) (xy 312.855864 -394.232892) (xy 312.868602 -394.256207)
			(xy 312.886693 -394.306157) (xy 312.895908 -394.358476) (xy 312.896504 -394.385038) (xy 312.896504 -394.385292)
			(xy 312.896054 -394.409285) (xy 312.888549 -394.456681) (xy 312.873721 -394.502319) (xy 312.851936 -394.545075)
			(xy 312.823731 -394.583897) (xy 312.7898 -394.617829) (xy 312.750978 -394.646034) (xy 312.708222 -394.66782)
			(xy 312.662585 -394.682648) (xy 312.615189 -394.690154) (xy 312.591196 -394.6906) (xy 312.590942 -394.6906)
			(xy 312.567369 -394.690172) (xy 312.520783 -394.682937) (xy 312.475865 -394.668617) (xy 312.433686 -394.647554)
			(xy 312.395253 -394.62025) (xy 312.36148 -394.587355) (xy 312.333173 -394.549654) (xy 312.321702 -394.529056)
			(xy 312.321194 -394.528294) (xy 312.307732 -394.504926) (xy 312.302363 -394.496463) (xy 312.28647 -394.484277)
			(xy 312.267122 -394.479104) (xy 312.247268 -394.481733) (xy 312.23839 -394.486384) (xy 312.229246 -394.491718)
			(xy 312.22315 -394.5001) (xy 312.212219 -394.513997) (xy 312.186138 -394.537862) (xy 312.156112 -394.556524)
			(xy 312.123167 -394.569347) (xy 312.088426 -394.575894) (xy 312.07075 -394.5763) (xy 312.070242 -394.5763)
			(xy 312.051469 -394.575765) (xy 312.014643 -394.568455) (xy 311.979948 -394.554106) (xy 311.948715 -394.533269)
			(xy 311.922143 -394.506744) (xy 311.901252 -394.475548) (xy 311.886843 -394.440878) (xy 311.879468 -394.404064)
			(xy 311.87898 -394.385292) (xy 311.879477 -394.366179) (xy 311.887036 -394.32871) (xy 311.901892 -394.293491)
			(xy 311.923451 -394.261927) (xy 311.950853 -394.235277) (xy 311.983005 -394.214606) (xy 312.000646 -394.207238)
			(xy 312.010806 -394.203174) (xy 312.0263 -394.187426) (xy 312.05551 -394.104114) (xy 312.058739 -394.093536)
			(xy 312.056759 -394.071532) (xy 312.0517 -394.061696) (xy 311.92343 -393.839954) (xy 311.911492 -393.815824)
			(xy 311.90668 -393.806298) (xy 311.890887 -393.791979) (xy 311.870644 -393.785298) (xy 311.849431 -393.787401)
			(xy 311.830894 -393.797928) (xy 311.824116 -393.806172) (xy 311.813168 -393.820249) (xy 311.786986 -393.844453)
			(xy 311.756769 -393.863382) (xy 311.723566 -393.876378) (xy 311.688528 -393.88299) (xy 311.6707 -393.883388)
			(xy 311.670192 -393.883388) (xy 311.663312 -393.883387) (xy 311.649582 -393.882496) (xy 311.64276 -393.88161)
			(xy 311.628282 -393.879324) (xy 311.601612 -393.891008) (xy 311.541922 -393.978892) (xy 311.536937 -393.987047)
			(xy 311.532753 -394.005677) (xy 311.535677 -394.024547) (xy 311.540144 -394.032994) (xy 311.655714 -394.232892)
			(xy 311.668537 -394.256226) (xy 311.686758 -394.306248) (xy 311.696019 -394.358673) (xy 311.696608 -394.385292)
			(xy 311.696131 -394.40927) (xy 311.688634 -394.456637) (xy 311.673823 -394.50225) (xy 311.652063 -394.544985)
			(xy 311.623888 -394.583793) (xy 311.589992 -394.617718) (xy 311.551209 -394.645926) (xy 311.508492 -394.667723)
			(xy 311.462892 -394.682573) (xy 311.415532 -394.69011) (xy 311.391554 -394.6906) (xy 311.391046 -394.6906)
			(xy 311.367473 -394.690169) (xy 311.320887 -394.682935) (xy 311.275969 -394.668615) (xy 311.233791 -394.647553)
			(xy 311.195357 -394.620249) (xy 311.161584 -394.587355) (xy 311.133277 -394.549654) (xy 311.121806 -394.529056)
			(xy 311.121298 -394.528294) (xy 311.107836 -394.504926) (xy 311.102463 -394.496466) (xy 311.086571 -394.484279)
			(xy 311.067225 -394.479106) (xy 311.047372 -394.481734) (xy 311.038494 -394.486384) (xy 311.02935 -394.491718)
			(xy 311.023254 -394.5001) (xy 311.012321 -394.513995) (xy 310.98624 -394.53786) (xy 310.956215 -394.556523)
			(xy 310.92327 -394.569346) (xy 310.88853 -394.575893) (xy 310.870854 -394.5763) (xy 310.870346 -394.5763)
			(xy 310.851573 -394.575762) (xy 310.814747 -394.568452) (xy 310.780052 -394.554104) (xy 310.748819 -394.533267)
			(xy 310.722248 -394.506742) (xy 310.701356 -394.475547) (xy 310.686947 -394.440877) (xy 310.679572 -394.404064)
			(xy 310.679084 -394.385292) (xy 310.679578 -394.366179) (xy 310.687138 -394.32871) (xy 310.701994 -394.29349)
			(xy 310.723553 -394.261926) (xy 310.750956 -394.235277) (xy 310.783109 -394.214605) (xy 310.80075 -394.207238)
			(xy 310.81091 -394.203174) (xy 310.826404 -394.187426) (xy 310.855614 -394.104114) (xy 310.858842 -394.093535)
			(xy 310.856863 -394.071532) (xy 310.851804 -394.061696) (xy 310.723534 -393.839954) (xy 310.711596 -393.815824)
			(xy 310.706778 -393.806301) (xy 310.690987 -393.791983) (xy 310.670746 -393.785301) (xy 310.649534 -393.787403)
			(xy 310.630998 -393.797929) (xy 310.62422 -393.806172) (xy 310.61327 -393.820247) (xy 310.587088 -393.844451)
			(xy 310.556872 -393.86338) (xy 310.523669 -393.876377) (xy 310.488632 -393.88299) (xy 310.470804 -393.883388)
			(xy 310.470296 -393.883388) (xy 310.463416 -393.883386) (xy 310.449686 -393.882495) (xy 310.442864 -393.88161)
			(xy 310.428386 -393.879324) (xy 310.401716 -393.891008) (xy 310.342026 -393.978892) (xy 310.337041 -393.987047)
			(xy 310.332857 -394.005677) (xy 310.33578 -394.024547) (xy 310.340248 -394.032994) (xy 310.455818 -394.232892)
			(xy 310.468641 -394.256226) (xy 310.486862 -394.306248) (xy 310.496123 -394.358673) (xy 310.496712 -394.385292)
			(xy 310.496231 -394.40927) (xy 310.488734 -394.456637) (xy 310.473924 -394.502249) (xy 310.452164 -394.544984)
			(xy 310.423989 -394.583791) (xy 310.390094 -394.617716) (xy 310.351311 -394.645924) (xy 310.308595 -394.667722)
			(xy 310.262996 -394.682572) (xy 310.215636 -394.69011) (xy 310.191658 -394.6906) (xy 310.19115 -394.6906)
			(xy 310.167577 -394.690166) (xy 310.120991 -394.682932) (xy 310.076073 -394.668613) (xy 310.033895 -394.647551)
			(xy 309.995461 -394.620248) (xy 309.961688 -394.587354) (xy 309.933381 -394.549653) (xy 309.92191 -394.529056)
			(xy 309.921402 -394.528294) (xy 309.90794 -394.504926) (xy 309.902563 -394.496469) (xy 309.886673 -394.484282)
			(xy 309.867328 -394.479108) (xy 309.847475 -394.481734) (xy 309.838598 -394.486384) (xy 309.829454 -394.491718)
			(xy 309.823358 -394.5001) (xy 309.812423 -394.513993) (xy 309.786342 -394.537859) (xy 309.756318 -394.556522)
			(xy 309.723374 -394.569345) (xy 309.688633 -394.575893) (xy 309.670958 -394.5763) (xy 309.67045 -394.5763)
			(xy 309.651678 -394.575758) (xy 309.614851 -394.568449) (xy 309.580156 -394.554101) (xy 309.548924 -394.533266)
			(xy 309.522352 -394.506741) (xy 309.50146 -394.475546) (xy 309.487051 -394.440877) (xy 309.479676 -394.404064)
			(xy 309.479188 -394.385292) (xy 309.47968 -394.366179) (xy 309.487239 -394.328709) (xy 309.502096 -394.29349)
			(xy 309.523656 -394.261925) (xy 309.551059 -394.235276) (xy 309.583212 -394.214605) (xy 309.600854 -394.207238)
			(xy 309.611014 -394.203174) (xy 309.626508 -394.187426) (xy 309.655718 -394.104114) (xy 309.658946 -394.093535)
			(xy 309.656967 -394.071532) (xy 309.651908 -394.061696) (xy 309.523638 -393.839954) (xy 309.5117 -393.815824)
			(xy 309.506876 -393.806305) (xy 309.491087 -393.791987) (xy 309.470847 -393.785304) (xy 309.449637 -393.787406)
			(xy 309.431102 -393.79793) (xy 309.424324 -393.806172) (xy 309.413389 -393.820226) (xy 309.387251 -393.844403)
			(xy 309.357088 -393.863322) (xy 309.323944 -393.876327) (xy 309.288964 -393.882968) (xy 309.271162 -393.883388)
			(xy 309.270654 -393.883388) (xy 309.242968 -393.881356) (xy 309.242714 -393.881356) (xy 309.233243 -393.880436)
			(xy 309.214732 -393.884756) (xy 309.19908 -393.895541) (xy 309.193438 -393.9032) (xy 309.141876 -393.978892)
			(xy 309.136893 -393.987047) (xy 309.132713 -394.005677) (xy 309.135634 -394.024546) (xy 309.140098 -394.032994)
			(xy 309.255668 -394.232892) (xy 309.268406 -394.256207) (xy 309.286497 -394.306157) (xy 309.295712 -394.358476)
			(xy 309.296308 -394.385038) (xy 309.296308 -394.385292) (xy 309.295854 -394.409285) (xy 309.288349 -394.45668)
			(xy 309.273521 -394.502318) (xy 309.251737 -394.545074) (xy 309.223532 -394.583896) (xy 309.189602 -394.617827)
			(xy 309.150781 -394.646033) (xy 309.108025 -394.667818) (xy 309.062388 -394.682647) (xy 309.014993 -394.690154)
			(xy 308.991 -394.6906) (xy 308.967426 -394.690206) (xy 308.920838 -394.682965) (xy 308.875919 -394.668639)
			(xy 308.833741 -394.64757) (xy 308.795308 -394.620261) (xy 308.761536 -394.587361) (xy 308.73323 -394.549656)
			(xy 308.72176 -394.529056) (xy 308.721252 -394.528294) (xy 308.70779 -394.504926) (xy 308.702363 -394.496506)
			(xy 308.686491 -394.484319) (xy 308.667163 -394.479136) (xy 308.647323 -394.481745) (xy 308.638448 -394.486384)
			(xy 308.629304 -394.491718) (xy 308.623208 -394.5001) (xy 308.612301 -394.514017) (xy 308.586213 -394.53788)
			(xy 308.556182 -394.556539) (xy 308.523231 -394.569357) (xy 308.488486 -394.575897) (xy 308.470808 -394.5763)
			(xy 308.4703 -394.5763) (xy 308.451529 -394.575878) (xy 308.414709 -394.568554) (xy 308.380025 -394.554187)
			(xy 308.348811 -394.53333) (xy 308.322265 -394.506783) (xy 308.301409 -394.475568) (xy 308.287044 -394.440883)
			(xy 308.279721 -394.404063) (xy 308.279292 -394.385292) (xy 308.279771 -394.366198) (xy 308.287339 -394.328768)
			(xy 308.302172 -394.293579) (xy 308.323684 -394.262027) (xy 308.351021 -394.235362) (xy 308.383098 -394.214642)
			(xy 308.400704 -394.207238) (xy 308.410864 -394.203174) (xy 308.426358 -394.187426) (xy 308.455568 -394.104114)
			(xy 308.458791 -394.093535) (xy 308.456813 -394.071532) (xy 308.451758 -394.061696) (xy 308.323488 -393.839954)
			(xy 308.31155 -393.815824) (xy 308.306797 -393.806263) (xy 308.290987 -393.79194) (xy 308.270727 -393.785261)
			(xy 308.249499 -393.787375) (xy 308.230953 -393.797918) (xy 308.224174 -393.806172) (xy 308.213251 -393.820269)
			(xy 308.187062 -393.844471) (xy 308.156839 -393.863397) (xy 308.12363 -393.876388) (xy 308.088588 -393.882994)
			(xy 308.070758 -393.883388) (xy 308.07025 -393.883388) (xy 308.06337 -393.88338) (xy 308.049641 -393.882493)
			(xy 308.042818 -393.88161) (xy 308.02834 -393.879324) (xy 308.00167 -393.891008) (xy 307.94198 -393.978892)
			(xy 307.936997 -393.987047) (xy 307.932817 -394.005677) (xy 307.935737 -394.024546) (xy 307.940202 -394.032994)
			(xy 308.055772 -394.232892) (xy 308.068511 -394.256207) (xy 308.086601 -394.306157) (xy 308.095816 -394.358476)
			(xy 308.096412 -394.385038) (xy 308.096412 -394.385292) (xy 308.095954 -394.409285) (xy 308.088449 -394.45668)
			(xy 308.073622 -394.502317) (xy 308.051838 -394.545073) (xy 308.023634 -394.583894) (xy 307.989703 -394.617826)
			(xy 307.950883 -394.646032) (xy 307.908128 -394.667817) (xy 307.862491 -394.682646) (xy 307.815097 -394.690154)
			(xy 307.791104 -394.6906) (xy 307.76753 -394.690203) (xy 307.720942 -394.682962) (xy 307.676023 -394.668637)
			(xy 307.633845 -394.647569) (xy 307.595412 -394.62026) (xy 307.56164 -394.587361) (xy 307.533335 -394.549656)
			(xy 307.521864 -394.529056) (xy 307.521356 -394.528294) (xy 307.507894 -394.504926) (xy 307.502564 -394.496434)
			(xy 307.486657 -394.484248) (xy 307.467295 -394.479082) (xy 307.447432 -394.481724) (xy 307.438552 -394.486384)
			(xy 307.429408 -394.491718) (xy 307.423312 -394.5001) (xy 307.412403 -394.514015) (xy 307.386316 -394.537879)
			(xy 307.356285 -394.556538) (xy 307.323335 -394.569356) (xy 307.288589 -394.575897) (xy 307.270912 -394.5763)
			(xy 307.270404 -394.5763) (xy 307.251633 -394.575875) (xy 307.214813 -394.568551) (xy 307.180129 -394.554185)
			(xy 307.148915 -394.533328) (xy 307.122369 -394.506782) (xy 307.101513 -394.475567) (xy 307.087148 -394.440883)
			(xy 307.079825 -394.404063) (xy 307.079396 -394.385292) (xy 307.079873 -394.366198) (xy 307.087441 -394.328768)
			(xy 307.102275 -394.293579) (xy 307.123787 -394.262026) (xy 307.151124 -394.235362) (xy 307.183202 -394.214643)
			(xy 307.200808 -394.207238) (xy 307.210968 -394.203174) (xy 307.226462 -394.187426) (xy 307.255672 -394.104114)
			(xy 307.258894 -394.093534) (xy 307.256917 -394.071533) (xy 307.251862 -394.061696) (xy 307.123592 -393.839954)
			(xy 307.111654 -393.815824) (xy 307.106895 -393.806267) (xy 307.091087 -393.791944) (xy 307.070828 -393.785265)
			(xy 307.049602 -393.787378) (xy 307.031057 -393.797919) (xy 307.024278 -393.806172) (xy 307.013352 -393.820267)
			(xy 306.987164 -393.84447) (xy 306.956942 -393.863395) (xy 306.923733 -393.876387) (xy 306.888692 -393.882994)
			(xy 306.870862 -393.883388) (xy 306.870354 -393.883388) (xy 306.863474 -393.88338) (xy 306.849745 -393.882493)
			(xy 306.842922 -393.88161) (xy 306.828444 -393.879324) (xy 306.801774 -393.891008) (xy 306.742084 -393.978892)
			(xy 306.737101 -393.987047) (xy 306.732921 -394.005677) (xy 306.735841 -394.024546) (xy 306.740306 -394.032994)
			(xy 306.855876 -394.232892) (xy 306.868615 -394.256207) (xy 306.886705 -394.306157) (xy 306.89592 -394.358476)
			(xy 306.896516 -394.385038) (xy 306.896516 -394.385292) (xy 306.89603 -394.409283) (xy 306.888525 -394.456673)
			(xy 306.8737 -394.502306) (xy 306.851918 -394.545059) (xy 306.823716 -394.583877) (xy 306.789789 -394.617806)
			(xy 306.750972 -394.646009) (xy 306.708221 -394.667793) (xy 306.662589 -394.682622) (xy 306.615199 -394.690129)
			(xy 306.591208 -394.6906) (xy 306.590954 -394.6906) (xy 306.567382 -394.690163) (xy 306.520795 -394.682929)
			(xy 306.475878 -394.668611) (xy 306.433699 -394.64755) (xy 306.395266 -394.620247) (xy 306.361493 -394.587353)
			(xy 306.333185 -394.549653) (xy 306.321714 -394.529056) (xy 306.321206 -394.528294) (xy 306.307744 -394.504926)
			(xy 306.302363 -394.496472) (xy 306.286474 -394.484285) (xy 306.267131 -394.47911) (xy 306.247279 -394.481735)
			(xy 306.238402 -394.486384) (xy 306.229258 -394.491718) (xy 306.223162 -394.5001) (xy 306.212225 -394.513991)
			(xy 306.186145 -394.537857) (xy 306.156121 -394.55652) (xy 306.123177 -394.569344) (xy 306.088437 -394.575892)
			(xy 306.070762 -394.5763) (xy 306.070254 -394.5763) (xy 306.051478 -394.575845) (xy 306.014648 -394.568519)
			(xy 305.979952 -394.554155) (xy 305.948721 -394.533306) (xy 305.922151 -394.50677) (xy 305.901261 -394.475565)
			(xy 305.886853 -394.440888) (xy 305.879479 -394.404067) (xy 305.878992 -394.385292) (xy 305.879481 -394.366179)
			(xy 305.887041 -394.328709) (xy 305.901898 -394.293489) (xy 305.923458 -394.261925) (xy 305.950862 -394.235276)
			(xy 305.983016 -394.214605) (xy 306.000658 -394.207238) (xy 306.010818 -394.203174) (xy 306.026312 -394.187426)
			(xy 306.055522 -394.104114) (xy 306.05875 -394.093535) (xy 306.056771 -394.071532) (xy 306.051712 -394.061696)
			(xy 305.923442 -393.839954) (xy 305.911504 -393.815824) (xy 305.906675 -393.806308) (xy 305.890887 -393.791991)
			(xy 305.870649 -393.785308) (xy 305.84944 -393.787408) (xy 305.830906 -393.79793) (xy 305.824128 -393.806172)
			(xy 305.813174 -393.820243) (xy 305.786993 -393.844448) (xy 305.756778 -393.863377) (xy 305.723576 -393.876375)
			(xy 305.68854 -393.882989) (xy 305.670712 -393.883388) (xy 305.670204 -393.883388) (xy 305.663324 -393.883385)
			(xy 305.649594 -393.882495) (xy 305.642772 -393.88161) (xy 305.628294 -393.879324) (xy 305.601624 -393.891008)
			(xy 305.541934 -393.978892) (xy 305.536948 -393.987047) (xy 305.532764 -394.005677) (xy 305.535688 -394.024547)
			(xy 305.540156 -394.032994) (xy 305.655726 -394.232892) (xy 305.66855 -394.256225) (xy 305.686771 -394.306247)
			(xy 305.696031 -394.358673) (xy 305.69662 -394.385292) (xy 305.696131 -394.40927) (xy 305.688635 -394.456636)
			(xy 305.673824 -394.502247) (xy 305.652065 -394.544982) (xy 305.623892 -394.583789) (xy 305.589997 -394.617713)
			(xy 305.551216 -394.645922) (xy 305.5085 -394.667719) (xy 305.462902 -394.68257) (xy 305.415543 -394.69011)
			(xy 305.391566 -394.6906) (xy 305.391058 -394.6906) (xy 305.367486 -394.690159) (xy 305.3209 -394.682927)
			(xy 305.275982 -394.668609) (xy 305.233804 -394.647548) (xy 305.19537 -394.620246) (xy 305.161597 -394.587353)
			(xy 305.13329 -394.549653) (xy 305.121818 -394.529056) (xy 305.12131 -394.528294) (xy 305.107848 -394.504926)
			(xy 305.102463 -394.496475) (xy 305.086576 -394.484288) (xy 305.067233 -394.479113) (xy 305.047383 -394.481736)
			(xy 305.038506 -394.486384) (xy 305.029362 -394.491718) (xy 305.023266 -394.5001) (xy 305.012326 -394.513989)
			(xy 304.986247 -394.537855) (xy 304.956224 -394.556519) (xy 304.923281 -394.569343) (xy 304.888541 -394.575892)
			(xy 304.870866 -394.5763) (xy 304.870358 -394.5763) (xy 304.851582 -394.575842) (xy 304.814753 -394.568516)
			(xy 304.780057 -394.554153) (xy 304.748825 -394.533304) (xy 304.722255 -394.506769) (xy 304.701365 -394.475564)
			(xy 304.686957 -394.440887) (xy 304.679583 -394.404067) (xy 304.679096 -394.385292) (xy 304.679582 -394.366179)
			(xy 304.687143 -394.328708) (xy 304.702 -394.293488) (xy 304.723561 -394.261924) (xy 304.750965 -394.235275)
			(xy 304.78312 -394.214605) (xy 304.800762 -394.207238) (xy 304.810922 -394.203174) (xy 304.826416 -394.187426)
			(xy 304.855626 -394.104114) (xy 304.858853 -394.093535) (xy 304.856874 -394.071532) (xy 304.851816 -394.061696)
			(xy 304.723546 -393.839954) (xy 304.711608 -393.815824) (xy 304.706773 -393.806311) (xy 304.690987 -393.791994)
			(xy 304.670751 -393.785311) (xy 304.649543 -393.78741) (xy 304.63101 -393.797931) (xy 304.624232 -393.806172)
			(xy 304.613275 -393.820241) (xy 304.587095 -393.844446) (xy 304.55688 -393.863376) (xy 304.523679 -393.876374)
			(xy 304.488643 -393.882989) (xy 304.470816 -393.883388) (xy 304.470308 -393.883388) (xy 304.463428 -393.883385)
			(xy 304.449698 -393.882495) (xy 304.442876 -393.88161) (xy 304.428398 -393.879324) (xy 304.401728 -393.891008)
			(xy 304.342038 -393.978892) (xy 304.337052 -393.987047) (xy 304.332867 -394.005677) (xy 304.335791 -394.024547)
			(xy 304.34026 -394.032994) (xy 304.45583 -394.232892) (xy 304.468654 -394.256225) (xy 304.486875 -394.306247)
			(xy 304.496135 -394.358673) (xy 304.496724 -394.385292) (xy 304.496231 -394.40927) (xy 304.488735 -394.456635)
			(xy 304.473925 -394.502246) (xy 304.452166 -394.54498) (xy 304.423993 -394.583787) (xy 304.390099 -394.617712)
			(xy 304.351318 -394.64592) (xy 304.308603 -394.667718) (xy 304.263006 -394.68257) (xy 304.215647 -394.690109)
			(xy 304.19167 -394.6906) (xy 304.191162 -394.6906) (xy 304.16759 -394.690156) (xy 304.121004 -394.682924)
			(xy 304.076086 -394.668607) (xy 304.033908 -394.647547) (xy 303.995474 -394.620245) (xy 303.961701 -394.587352)
			(xy 303.933394 -394.549653) (xy 303.921922 -394.529056) (xy 303.921414 -394.528294) (xy 303.907952 -394.504926)
			(xy 303.902563 -394.496478) (xy 303.886677 -394.484291) (xy 303.867336 -394.479115) (xy 303.847487 -394.481737)
			(xy 303.83861 -394.486384) (xy 303.829466 -394.491718) (xy 303.82337 -394.5001) (xy 303.812428 -394.513987)
			(xy 303.786349 -394.537853) (xy 303.756327 -394.556517) (xy 303.723384 -394.569342) (xy 303.688645 -394.575892)
			(xy 303.67097 -394.5763) (xy 303.670462 -394.5763) (xy 303.651687 -394.575838) (xy 303.614857 -394.568513)
			(xy 303.580161 -394.554151) (xy 303.548929 -394.533303) (xy 303.522359 -394.506768) (xy 303.501469 -394.475563)
			(xy 303.487061 -394.440887) (xy 303.479687 -394.404067) (xy 303.4792 -394.385292) (xy 303.479684 -394.366179)
			(xy 303.487244 -394.328708) (xy 303.502102 -394.293488) (xy 303.523663 -394.261923) (xy 303.551068 -394.235274)
			(xy 303.583224 -394.214604) (xy 303.600866 -394.207238) (xy 303.611026 -394.203174) (xy 303.62652 -394.187426)
			(xy 303.65573 -394.104114) (xy 303.658957 -394.093535) (xy 303.656978 -394.071532) (xy 303.65192 -394.061696)
			(xy 303.52365 -393.839954) (xy 303.511712 -393.815824) (xy 303.506872 -393.806314) (xy 303.491087 -393.791998)
			(xy 303.470852 -393.785315) (xy 303.449646 -393.787413) (xy 303.431113 -393.797932) (xy 303.424336 -393.806172)
			(xy 303.413394 -393.820221) (xy 303.387258 -393.844398) (xy 303.357097 -393.863317) (xy 303.323954 -393.876324)
			(xy 303.288975 -393.882967) (xy 303.271174 -393.883388) (xy 303.270666 -393.883388) (xy 303.250646 -393.882901)
			(xy 303.211481 -393.87457) (xy 303.174903 -393.858279) (xy 303.142512 -393.83474) (xy 303.115722 -393.804982)
			(xy 303.095703 -393.770304) (xy 303.083331 -393.732222) (xy 303.079146 -393.6924) (xy 280.345622 -393.6924)
			(xy 280.093674 -393.944348) (xy 280.08686 -393.951769) (xy 280.079126 -393.970352) (xy 280.078688 -393.980416)
			(xy 280.079196 -394.062966) (xy 280.08707 -394.081508) (xy 280.094436 -394.08862) (xy 280.100532 -394.094716)
			(xy 280.483818 -394.478002) (xy 280.510712 -394.505555) (xy 280.558798 -394.565692) (xy 280.599841 -394.630839)
			(xy 280.633323 -394.700176) (xy 280.658823 -394.772829) (xy 280.67602 -394.847882) (xy 280.684696 -394.924389)
			(xy 280.68524 -394.962888) (xy 280.68524 -396.171674) (xy 296.901108 -396.171674) (xy 296.901108 -395.308074)
			(xy 296.901594 -395.280823) (xy 296.90935 -395.226875) (xy 296.924705 -395.17458) (xy 296.947347 -395.125003)
			(xy 296.976813 -395.079153) (xy 297.012504 -395.037962) (xy 297.053695 -395.002271) (xy 297.099545 -394.972805)
			(xy 297.149122 -394.950163) (xy 297.201417 -394.934808) (xy 297.255365 -394.927052) (xy 297.309867 -394.927052)
			(xy 297.363815 -394.934808) (xy 297.41611 -394.950163) (xy 297.465687 -394.972805) (xy 297.511537 -395.002271)
			(xy 297.552728 -395.037962) (xy 297.588419 -395.079153) (xy 297.617885 -395.125003) (xy 297.640527 -395.17458)
			(xy 297.655882 -395.226875) (xy 297.663638 -395.280823) (xy 297.664124 -395.308074) (xy 297.664124 -396.171674)
			(xy 329.428856 -396.171674) (xy 329.428856 -395.308074) (xy 329.429342 -395.280823) (xy 329.437098 -395.226875)
			(xy 329.452453 -395.17458) (xy 329.475095 -395.125003) (xy 329.504561 -395.079153) (xy 329.540252 -395.037962)
			(xy 329.581443 -395.002271) (xy 329.627293 -394.972805) (xy 329.67687 -394.950163) (xy 329.729165 -394.934808)
			(xy 329.783113 -394.927052) (xy 329.837615 -394.927052) (xy 329.891563 -394.934808) (xy 329.943858 -394.950163)
			(xy 329.993435 -394.972805) (xy 330.039285 -395.002271) (xy 330.080476 -395.037962) (xy 330.116167 -395.079153)
			(xy 330.145633 -395.125003) (xy 330.168275 -395.17458) (xy 330.18363 -395.226875) (xy 330.191386 -395.280823)
			(xy 330.191872 -395.308074) (xy 330.191872 -396.171674) (xy 364.001304 -396.171674) (xy 364.001304 -395.308074)
			(xy 364.00179 -395.280823) (xy 364.009546 -395.226875) (xy 364.024901 -395.17458) (xy 364.047543 -395.125003)
			(xy 364.077009 -395.079153) (xy 364.1127 -395.037962) (xy 364.153891 -395.002271) (xy 364.199741 -394.972805)
			(xy 364.249318 -394.950163) (xy 364.301613 -394.934808) (xy 364.355561 -394.927052) (xy 364.410063 -394.927052)
			(xy 364.464011 -394.934808) (xy 364.516306 -394.950163) (xy 364.565883 -394.972805) (xy 364.611733 -395.002271)
			(xy 364.652924 -395.037962) (xy 364.688615 -395.079153) (xy 364.718081 -395.125003) (xy 364.740723 -395.17458)
			(xy 364.756078 -395.226875) (xy 364.763834 -395.280823) (xy 364.76432 -395.308074) (xy 364.76432 -396.171674)
			(xy 396.529052 -396.171674) (xy 396.529052 -395.308074) (xy 396.529538 -395.280823) (xy 396.537294 -395.226875)
			(xy 396.552649 -395.17458) (xy 396.575291 -395.125003) (xy 396.604757 -395.079153) (xy 396.640448 -395.037962)
			(xy 396.681639 -395.002271) (xy 396.727489 -394.972805) (xy 396.777066 -394.950163) (xy 396.829361 -394.934808)
			(xy 396.883309 -394.927052) (xy 396.937811 -394.927052) (xy 396.991759 -394.934808) (xy 397.044054 -394.950163)
			(xy 397.093631 -394.972805) (xy 397.139481 -395.002271) (xy 397.180672 -395.037962) (xy 397.216363 -395.079153)
			(xy 397.245829 -395.125003) (xy 397.268471 -395.17458) (xy 397.283826 -395.226875) (xy 397.291582 -395.280823)
			(xy 397.292068 -395.308074) (xy 397.292068 -396.171674) (xy 397.291582 -396.198925) (xy 397.283826 -396.252873)
			(xy 397.268471 -396.305168) (xy 397.245829 -396.354745) (xy 397.216363 -396.400595) (xy 397.180672 -396.441786)
			(xy 397.139481 -396.477477) (xy 397.093631 -396.506943) (xy 397.044054 -396.529585) (xy 396.991759 -396.54494)
			(xy 396.937811 -396.552696) (xy 396.883309 -396.552696) (xy 396.829361 -396.54494) (xy 396.777066 -396.529585)
			(xy 396.727489 -396.506943) (xy 396.681639 -396.477477) (xy 396.640448 -396.441786) (xy 396.604757 -396.400595)
			(xy 396.575291 -396.354745) (xy 396.552649 -396.305168) (xy 396.537294 -396.252873) (xy 396.529538 -396.198925)
			(xy 396.529052 -396.171674) (xy 364.76432 -396.171674) (xy 364.763834 -396.198925) (xy 364.756078 -396.252873)
			(xy 364.740723 -396.305168) (xy 364.718081 -396.354745) (xy 364.688615 -396.400595) (xy 364.652924 -396.441786)
			(xy 364.611733 -396.477477) (xy 364.565883 -396.506943) (xy 364.516306 -396.529585) (xy 364.464011 -396.54494)
			(xy 364.410063 -396.552696) (xy 364.355561 -396.552696) (xy 364.301613 -396.54494) (xy 364.249318 -396.529585)
			(xy 364.199741 -396.506943) (xy 364.153891 -396.477477) (xy 364.1127 -396.441786) (xy 364.077009 -396.400595)
			(xy 364.047543 -396.354745) (xy 364.024901 -396.305168) (xy 364.009546 -396.252873) (xy 364.00179 -396.198925)
			(xy 364.001304 -396.171674) (xy 330.191872 -396.171674) (xy 330.191386 -396.198925) (xy 330.18363 -396.252873)
			(xy 330.168275 -396.305168) (xy 330.145633 -396.354745) (xy 330.116167 -396.400595) (xy 330.080476 -396.441786)
			(xy 330.039285 -396.477477) (xy 329.993435 -396.506943) (xy 329.943858 -396.529585) (xy 329.891563 -396.54494)
			(xy 329.837615 -396.552696) (xy 329.783113 -396.552696) (xy 329.729165 -396.54494) (xy 329.67687 -396.529585)
			(xy 329.627293 -396.506943) (xy 329.581443 -396.477477) (xy 329.540252 -396.441786) (xy 329.504561 -396.400595)
			(xy 329.475095 -396.354745) (xy 329.452453 -396.305168) (xy 329.437098 -396.252873) (xy 329.429342 -396.198925)
			(xy 329.428856 -396.171674) (xy 297.664124 -396.171674) (xy 297.663638 -396.198925) (xy 297.655882 -396.252873)
			(xy 297.640527 -396.305168) (xy 297.617885 -396.354745) (xy 297.588419 -396.400595) (xy 297.552728 -396.441786)
			(xy 297.511537 -396.477477) (xy 297.465687 -396.506943) (xy 297.41611 -396.529585) (xy 297.363815 -396.54494)
			(xy 297.309867 -396.552696) (xy 297.255365 -396.552696) (xy 297.201417 -396.54494) (xy 297.149122 -396.529585)
			(xy 297.099545 -396.506943) (xy 297.053695 -396.477477) (xy 297.012504 -396.441786) (xy 296.976813 -396.400595)
			(xy 296.947347 -396.354745) (xy 296.924705 -396.305168) (xy 296.90935 -396.252873) (xy 296.901594 -396.198925)
			(xy 296.901108 -396.171674) (xy 280.68524 -396.171674) (xy 280.68524 -397.1564) (xy 303.079198 -397.1564)
			(xy 303.083382 -397.116589) (xy 303.095751 -397.078517) (xy 303.115764 -397.043849) (xy 303.142547 -397.014098)
			(xy 303.174929 -396.990566) (xy 303.211497 -396.974279) (xy 303.250651 -396.96595) (xy 303.270666 -396.965424)
			(xy 303.271174 -396.965424) (xy 303.292651 -396.96602) (xy 303.334515 -396.975644) (xy 303.373185 -396.994347)
			(xy 303.3903 -397.007334) (xy 303.398428 -397.013938) (xy 303.419002 -397.019526) (xy 303.503584 -397.006826)
			(xy 303.513834 -397.004695) (xy 303.531538 -396.993567) (xy 303.537874 -396.985236) (xy 303.538128 -396.984982)
			(xy 303.552224 -396.965054) (xy 303.585644 -396.929483) (xy 303.624296 -396.899679) (xy 303.667196 -396.876401)
			(xy 303.713251 -396.860241) (xy 303.76129 -396.851611) (xy 303.81009 -396.850729) (xy 303.85841 -396.857619)
			(xy 303.905019 -396.872104) (xy 303.948731 -396.893817) (xy 303.988435 -396.922205) (xy 304.023119 -396.956545)
			(xy 304.0519 -396.995964) (xy 304.0634 -397.017494) (xy 304.063908 -397.018764) (xy 304.11039 -397.099282)
			(xy 304.115481 -397.107358) (xy 304.130385 -397.119271) (xy 304.148598 -397.124955) (xy 304.158142 -397.124682)
			(xy 304.249582 -397.117824) (xy 304.258965 -397.116698) (xy 304.27602 -397.10859) (xy 304.289019 -397.094893)
			(xy 304.293016 -397.086328) (xy 304.293016 -397.08582) (xy 304.300463 -397.068338) (xy 304.321215 -397.036512)
			(xy 304.347838 -397.009405) (xy 304.379284 -396.988082) (xy 304.414319 -396.97338) (xy 304.451565 -396.965879)
			(xy 304.470562 -396.965424) (xy 304.47107 -396.965424) (xy 304.492547 -396.966022) (xy 304.53441 -396.975645)
			(xy 304.573081 -396.994347) (xy 304.590196 -397.007334) (xy 304.598324 -397.013938) (xy 304.618898 -397.019526)
			(xy 304.70348 -397.006826) (xy 304.713729 -397.004694) (xy 304.731433 -396.993567) (xy 304.73777 -396.985236)
			(xy 304.738024 -396.984982) (xy 304.752125 -396.965058) (xy 304.785545 -396.929487) (xy 304.824197 -396.899684)
			(xy 304.867095 -396.876405) (xy 304.91315 -396.860245) (xy 304.961188 -396.851614) (xy 305.009988 -396.850732)
			(xy 305.058307 -396.857622) (xy 305.104916 -396.872107) (xy 305.148628 -396.893819) (xy 305.188331 -396.922206)
			(xy 305.223015 -396.956546) (xy 305.251796 -396.995964) (xy 305.263296 -397.017494) (xy 305.263804 -397.018764)
			(xy 305.310286 -397.099282) (xy 305.31538 -397.107356) (xy 305.330282 -397.11927) (xy 305.348494 -397.124954)
			(xy 305.358038 -397.124682) (xy 305.449478 -397.117824) (xy 305.458861 -397.116695) (xy 305.475916 -397.108589)
			(xy 305.488915 -397.094892) (xy 305.492912 -397.086328) (xy 305.492912 -397.08582) (xy 305.500362 -397.068339)
			(xy 305.521114 -397.036513) (xy 305.547736 -397.009406) (xy 305.579182 -396.988083) (xy 305.614216 -396.973381)
			(xy 305.651461 -396.965879) (xy 305.670458 -396.965424) (xy 305.688321 -396.965843) (xy 305.723422 -396.972494)
			(xy 305.756682 -396.985536) (xy 305.786949 -397.004517) (xy 305.813172 -397.02878) (xy 305.824128 -397.042894)
			(xy 305.830308 -397.050581) (xy 305.847128 -397.060857) (xy 305.866579 -397.064042) (xy 305.885797 -397.059668)
			(xy 305.901954 -397.048378) (xy 305.907694 -397.040354) (xy 305.911504 -397.032988) (xy 305.92141 -397.012668)
			(xy 305.933061 -396.991771) (xy 305.961857 -396.953565) (xy 305.996256 -396.920313) (xy 306.035416 -396.89283)
			(xy 306.078382 -396.871785) (xy 306.124103 -396.857694) (xy 306.171461 -396.850901) (xy 306.219298 -396.851573)
			(xy 306.266447 -396.859691) (xy 306.311754 -396.875059) (xy 306.354113 -396.8973) (xy 306.392487 -396.925872)
			(xy 306.42594 -396.960075) (xy 306.453653 -396.999074) (xy 306.464716 -397.020288) (xy 306.465478 -397.021812)
			(xy 306.510436 -397.099536) (xy 306.515577 -397.107576) (xy 306.530456 -397.119499) (xy 306.54865 -397.125199)
			(xy 306.558188 -397.124936) (xy 306.663852 -397.117062) (xy 306.687474 -397.09979) (xy 306.692808 -397.086074)
			(xy 306.700313 -397.068583) (xy 306.721073 -397.036693) (xy 306.747718 -397.009527) (xy 306.779201 -396.988153)
			(xy 306.814282 -396.973413) (xy 306.851582 -396.965885) (xy 306.870608 -396.965424) (xy 306.871116 -396.965424)
			(xy 306.892594 -396.965998) (xy 306.934459 -396.975631) (xy 306.973128 -396.994343) (xy 306.990242 -397.007334)
			(xy 306.99837 -397.013938) (xy 307.018944 -397.019526) (xy 307.103526 -397.006826) (xy 307.113781 -397.004715)
			(xy 307.131482 -396.993573) (xy 307.137816 -396.985236) (xy 307.13807 -396.984982) (xy 307.152109 -396.965012)
			(xy 307.185536 -396.92944) (xy 307.224195 -396.899636) (xy 307.267101 -396.876358) (xy 307.313163 -396.8602)
			(xy 307.361208 -396.851571) (xy 307.410014 -396.850693) (xy 307.458338 -396.857587) (xy 307.504952 -396.872077)
			(xy 307.548668 -396.893796) (xy 307.588374 -396.922189) (xy 307.62306 -396.956536) (xy 307.651842 -396.995961)
			(xy 307.663342 -397.017494) (xy 307.66385 -397.018764) (xy 307.710332 -397.099282) (xy 307.715462 -397.107329)
			(xy 307.730348 -397.119247) (xy 307.748545 -397.124945) (xy 307.758084 -397.124682) (xy 307.849524 -397.117824)
			(xy 307.858912 -397.116725) (xy 307.875967 -397.108605) (xy 307.888963 -397.094897) (xy 307.892958 -397.086328)
			(xy 307.892958 -397.08582) (xy 307.900451 -397.068359) (xy 307.921196 -397.036536) (xy 307.94781 -397.009428)
			(xy 307.979247 -396.988102) (xy 308.014272 -396.973395) (xy 308.05151 -396.965884) (xy 308.070504 -396.965424)
			(xy 308.071012 -396.965424) (xy 308.09249 -396.966) (xy 308.134354 -396.975632) (xy 308.173024 -396.994343)
			(xy 308.190138 -397.007334) (xy 308.198266 -397.013938) (xy 308.21884 -397.019526) (xy 308.303422 -397.006826)
			(xy 308.313677 -397.004713) (xy 308.331378 -396.993572) (xy 308.337712 -396.985236) (xy 308.337966 -396.984982)
			(xy 308.35201 -396.965016) (xy 308.385437 -396.929444) (xy 308.424095 -396.89964) (xy 308.467001 -396.876362)
			(xy 308.513062 -396.860204) (xy 308.561106 -396.851575) (xy 308.609912 -396.850696) (xy 308.658236 -396.85759)
			(xy 308.704849 -396.87208) (xy 308.748564 -396.893798) (xy 308.78827 -396.922191) (xy 308.822956 -396.956537)
			(xy 308.851738 -396.995961) (xy 308.863238 -397.017494) (xy 308.863746 -397.018764) (xy 308.910482 -397.099536)
			(xy 308.915592 -397.107599) (xy 308.930485 -397.119518) (xy 308.948692 -397.125207) (xy 308.958234 -397.124936)
			(xy 309.063898 -397.117062) (xy 309.08752 -397.09979) (xy 309.092854 -397.086074) (xy 309.100322 -397.068566)
			(xy 309.121088 -397.036674) (xy 309.147741 -397.009508) (xy 309.179231 -396.988137) (xy 309.214319 -396.973401)
			(xy 309.251626 -396.965881) (xy 309.270654 -396.965424) (xy 309.271162 -396.965424) (xy 309.292639 -396.966026)
			(xy 309.334502 -396.975647) (xy 309.373172 -396.994348) (xy 309.390288 -397.007334) (xy 309.398416 -397.013938)
			(xy 309.41899 -397.019526) (xy 309.503572 -397.006826) (xy 309.51382 -397.00469) (xy 309.531525 -396.993566)
			(xy 309.537862 -396.985236) (xy 309.538116 -396.984982) (xy 309.552228 -396.965066) (xy 309.585647 -396.929495)
			(xy 309.624297 -396.899692) (xy 309.667194 -396.876414) (xy 309.713248 -396.860253) (xy 309.761285 -396.851622)
			(xy 309.810084 -396.850739) (xy 309.858401 -396.857628) (xy 309.905009 -396.872112) (xy 309.948721 -396.893823)
			(xy 309.988423 -396.922209) (xy 310.023107 -396.956548) (xy 310.051889 -396.995965) (xy 310.063388 -397.017494)
			(xy 310.063896 -397.018764) (xy 310.110378 -397.099282) (xy 310.115477 -397.107352) (xy 310.130377 -397.119266)
			(xy 310.148587 -397.124953) (xy 310.15813 -397.124682) (xy 310.24957 -397.117824) (xy 310.258952 -397.116689)
			(xy 310.276007 -397.108586) (xy 310.289006 -397.094891) (xy 310.293004 -397.086328) (xy 310.293004 -397.08582)
			(xy 310.30046 -397.068342) (xy 310.321211 -397.036517) (xy 310.347832 -397.00941) (xy 310.379276 -396.988086)
			(xy 310.414309 -396.973383) (xy 310.451554 -396.96588) (xy 310.47055 -396.965424) (xy 310.471058 -396.965424)
			(xy 310.492534 -396.966028) (xy 310.534398 -396.975648) (xy 310.573068 -396.994348) (xy 310.590184 -397.007334)
			(xy 310.598312 -397.013938) (xy 310.618886 -397.019526) (xy 310.703468 -397.006826) (xy 310.713728 -397.004734)
			(xy 310.731427 -396.993578) (xy 310.737758 -396.985236) (xy 310.738012 -396.984982) (xy 310.752129 -396.96507)
			(xy 310.785548 -396.929499) (xy 310.824197 -396.899696) (xy 310.867094 -396.876418) (xy 310.913147 -396.860257)
			(xy 310.961183 -396.851626) (xy 311.009981 -396.850743) (xy 311.058299 -396.857631) (xy 311.104906 -396.872114)
			(xy 311.148617 -396.893825) (xy 311.18832 -396.922211) (xy 311.223003 -396.956549) (xy 311.251785 -396.995965)
			(xy 311.263284 -397.017494) (xy 311.263792 -397.018764) (xy 311.310274 -397.099282) (xy 311.315376 -397.10735)
			(xy 311.330274 -397.119265) (xy 311.348484 -397.124952) (xy 311.358026 -397.124682) (xy 311.449466 -397.117824)
			(xy 311.458848 -397.116687) (xy 311.475902 -397.108584) (xy 311.488902 -397.094891) (xy 311.4929 -397.086328)
			(xy 311.4929 -397.08582) (xy 311.500359 -397.068344) (xy 311.52111 -397.036518) (xy 311.54773 -397.009411)
			(xy 311.579174 -396.988087) (xy 311.614206 -396.973384) (xy 311.65145 -396.96588) (xy 311.670446 -396.965424)
			(xy 311.688308 -396.965852) (xy 311.723409 -396.972501) (xy 311.756669 -396.985541) (xy 311.786936 -397.00452)
			(xy 311.81316 -397.02878) (xy 311.824116 -397.042894) (xy 311.83031 -397.050568) (xy 311.847125 -397.060844)
			(xy 311.866572 -397.064032) (xy 311.885787 -397.059661) (xy 311.901942 -397.048375) (xy 311.907682 -397.040354)
			(xy 311.911492 -397.032988) (xy 311.921398 -397.012668) (xy 311.933067 -396.991781) (xy 311.961861 -396.953576)
			(xy 311.996258 -396.920325) (xy 312.035417 -396.892842) (xy 312.078381 -396.871797) (xy 312.1241 -396.857706)
			(xy 312.171456 -396.850913) (xy 312.219292 -396.851583) (xy 312.266439 -396.8597) (xy 312.311745 -396.875067)
			(xy 312.354103 -396.897307) (xy 312.392476 -396.925876) (xy 312.425928 -396.960078) (xy 312.453641 -396.999075)
			(xy 312.464704 -397.020288) (xy 312.465466 -397.021812) (xy 312.510424 -397.099536) (xy 312.515573 -397.10757)
			(xy 312.530448 -397.119494) (xy 312.548639 -397.125197) (xy 312.558176 -397.124936) (xy 312.66384 -397.117062)
			(xy 312.687462 -397.09979) (xy 312.692796 -397.086074) (xy 312.70023 -397.06855) (xy 312.721002 -397.036657)
			(xy 312.747661 -397.009491) (xy 312.779158 -396.988122) (xy 312.814253 -396.973391) (xy 312.851565 -396.965877)
			(xy 312.870596 -396.965424) (xy 312.871104 -396.965424) (xy 312.892582 -396.966004) (xy 312.934446 -396.975635)
			(xy 312.973115 -396.994344) (xy 312.99023 -397.007334) (xy 312.998358 -397.013938) (xy 313.018932 -397.019526)
			(xy 313.103514 -397.006826) (xy 313.113767 -397.004709) (xy 313.131469 -396.993571) (xy 313.137804 -396.985236)
			(xy 313.138058 -396.984982) (xy 313.152113 -396.965024) (xy 313.185539 -396.929452) (xy 313.224195 -396.899648)
			(xy 313.2671 -396.87637) (xy 313.31316 -396.860212) (xy 313.361203 -396.851583) (xy 313.410007 -396.850703)
			(xy 313.45833 -396.857596) (xy 313.504942 -396.872085) (xy 313.548657 -396.893802) (xy 313.588363 -396.922194)
			(xy 313.623048 -396.956538) (xy 313.65183 -396.995962) (xy 313.66333 -397.017494) (xy 313.663838 -397.018764)
			(xy 313.71032 -397.099282) (xy 313.715458 -397.107323) (xy 313.73034 -397.119242) (xy 313.748534 -397.124943)
			(xy 313.758072 -397.124682) (xy 313.849512 -397.117824) (xy 313.858899 -397.116717) (xy 313.875953 -397.108601)
			(xy 313.88895 -397.094896) (xy 313.892946 -397.086328) (xy 313.892946 -397.08582) (xy 313.900368 -397.068326)
			(xy 313.921125 -397.036499) (xy 313.947752 -397.009393) (xy 313.979204 -396.988071) (xy 314.014243 -396.973373)
			(xy 314.051493 -396.965876) (xy 314.070492 -396.965424) (xy 314.071 -396.965424) (xy 314.092478 -396.966006)
			(xy 314.134342 -396.975636) (xy 314.173011 -396.994344) (xy 314.190126 -397.007334) (xy 314.198254 -397.013938)
			(xy 314.218828 -397.019526) (xy 314.30341 -397.006826) (xy 314.313663 -397.004707) (xy 314.331365 -396.99357)
			(xy 314.3377 -396.985236) (xy 314.337954 -396.984982) (xy 314.352015 -396.965028) (xy 314.385439 -396.929456)
			(xy 314.424096 -396.899652) (xy 314.466999 -396.876375) (xy 314.513058 -396.860216) (xy 314.561101 -396.851586)
			(xy 314.609905 -396.850707) (xy 314.658227 -396.857599) (xy 314.704839 -396.872087) (xy 314.748554 -396.893804)
			(xy 314.788259 -396.922195) (xy 314.822944 -396.956539) (xy 314.851726 -396.995962) (xy 314.863226 -397.017494)
			(xy 314.863734 -397.018764) (xy 314.91047 -397.099536) (xy 314.915588 -397.107593) (xy 314.930477 -397.119513)
			(xy 314.948681 -397.125205) (xy 314.958222 -397.124936) (xy 315.063886 -397.117062) (xy 315.087508 -397.09979)
			(xy 315.092842 -397.086074) (xy 315.10032 -397.06857) (xy 315.121084 -397.036679) (xy 315.147735 -397.009513)
			(xy 315.179223 -396.988141) (xy 315.214309 -396.973404) (xy 315.251614 -396.965882) (xy 315.270642 -396.965424)
			(xy 315.27115 -396.965424) (xy 315.292626 -396.966032) (xy 315.334489 -396.975651) (xy 315.37316 -396.994349)
			(xy 315.390276 -397.007334) (xy 315.398404 -397.013938) (xy 315.418978 -397.019526) (xy 315.50356 -397.006826)
			(xy 315.513819 -397.004731) (xy 315.531518 -396.993577) (xy 315.53785 -396.985236) (xy 315.538104 -396.984982)
			(xy 315.552232 -396.965078) (xy 315.585649 -396.929508) (xy 315.624297 -396.899704) (xy 315.667193 -396.876426)
			(xy 315.713244 -396.860265) (xy 315.76128 -396.851633) (xy 315.810077 -396.85075) (xy 315.858393 -396.857637)
			(xy 315.905 -396.87212) (xy 315.94871 -396.89383) (xy 315.988412 -396.922214) (xy 316.023095 -396.956551)
			(xy 316.051877 -396.995966) (xy 316.063376 -397.017494) (xy 316.063884 -397.018764) (xy 316.110366 -397.099282)
			(xy 316.115473 -397.107346) (xy 316.130369 -397.119261) (xy 316.148576 -397.124951) (xy 316.158118 -397.124682)
			(xy 316.249558 -397.117824) (xy 316.258939 -397.116681) (xy 316.275993 -397.108582) (xy 316.288994 -397.09489)
			(xy 316.292992 -397.086328) (xy 316.292992 -397.08582) (xy 316.300458 -397.068347) (xy 316.321207 -397.036522)
			(xy 316.347826 -397.009414) (xy 316.379269 -396.98809) (xy 316.414299 -396.973386) (xy 316.451542 -396.965881)
			(xy 316.470538 -396.965424) (xy 316.471046 -396.965424) (xy 316.492522 -396.966034) (xy 316.534385 -396.975652)
			(xy 316.573056 -396.994349) (xy 316.590172 -397.007334) (xy 316.5983 -397.013938) (xy 316.618874 -397.019526)
			(xy 316.703456 -397.006826) (xy 316.713715 -397.004729) (xy 316.731414 -396.993577) (xy 316.737746 -396.985236)
			(xy 316.738 -396.984982) (xy 316.752133 -396.965082) (xy 316.78555 -396.929512) (xy 316.824197 -396.899709)
			(xy 316.867092 -396.87643) (xy 316.913143 -396.860269) (xy 316.961178 -396.851637) (xy 317.009975 -396.850753)
			(xy 317.058291 -396.85764) (xy 317.104897 -396.872122) (xy 317.148607 -396.893832) (xy 317.188308 -396.922215)
			(xy 317.222991 -396.956552) (xy 317.251773 -396.995966) (xy 317.263272 -397.017494) (xy 317.26378 -397.018764)
			(xy 317.310262 -397.099282) (xy 317.315372 -397.107344) (xy 317.330267 -397.11926) (xy 317.348473 -397.12495)
			(xy 317.358014 -397.124682) (xy 317.449454 -397.117824) (xy 317.458834 -397.116679) (xy 317.475889 -397.10858)
			(xy 317.48889 -397.09489) (xy 317.492888 -397.086328) (xy 317.492888 -397.08582) (xy 317.500357 -397.068348)
			(xy 317.521106 -397.036523) (xy 317.547724 -397.009416) (xy 317.579166 -396.988092) (xy 317.614196 -396.973387)
			(xy 317.651439 -396.965881) (xy 317.670434 -396.965424) (xy 317.688296 -396.96586) (xy 317.723396 -396.972507)
			(xy 317.756656 -396.985545) (xy 317.786923 -397.004522) (xy 317.813148 -397.028781) (xy 317.824104 -397.042894)
			(xy 317.830312 -397.050556) (xy 317.847122 -397.060832) (xy 317.866564 -397.064022) (xy 317.885777 -397.059654)
			(xy 317.90193 -397.048373) (xy 317.90767 -397.040354) (xy 317.91148 -397.032988) (xy 317.921386 -397.012668)
			(xy 317.933073 -396.991792) (xy 317.961866 -396.953587) (xy 317.996261 -396.920337) (xy 318.035418 -396.892854)
			(xy 318.07838 -396.871809) (xy 318.124097 -396.857718) (xy 318.171451 -396.850924) (xy 318.219286 -396.851593)
			(xy 318.266431 -396.859709) (xy 318.311736 -396.875075) (xy 318.354092 -396.897313) (xy 318.392465 -396.925881)
			(xy 318.425916 -396.96008) (xy 318.453629 -396.999076) (xy 318.464692 -397.020288) (xy 318.465454 -397.021812)
			(xy 318.510412 -397.099536) (xy 318.515502 -397.107613) (xy 318.530404 -397.119531) (xy 318.54862 -397.125213)
			(xy 318.558164 -397.124936) (xy 318.663828 -397.117062) (xy 318.68745 -397.09979) (xy 318.692784 -397.086074)
			(xy 318.700228 -397.068555) (xy 318.720998 -397.036662) (xy 318.747655 -397.009496) (xy 318.77915 -396.988126)
			(xy 318.814243 -396.973394) (xy 318.851554 -396.965878) (xy 318.870584 -396.965424) (xy 318.871092 -396.965424)
			(xy 318.89257 -396.96601) (xy 318.934433 -396.975638) (xy 318.973103 -396.994345) (xy 318.990218 -397.007334)
			(xy 318.998346 -397.013938) (xy 319.01892 -397.019526) (xy 319.103502 -397.006826) (xy 319.113754 -397.004704)
			(xy 319.131457 -396.993569) (xy 319.137792 -396.985236) (xy 319.138046 -396.984982) (xy 319.152117 -396.965036)
			(xy 319.185541 -396.929464) (xy 319.224196 -396.899661) (xy 319.267098 -396.876383) (xy 319.313156 -396.860223)
			(xy 319.361198 -396.851594) (xy 319.41 -396.850713) (xy 319.458322 -396.857605) (xy 319.504933 -396.872093)
			(xy 319.548647 -396.893808) (xy 319.588351 -396.922198) (xy 319.623036 -396.956541) (xy 319.651818 -396.995962)
			(xy 319.663318 -397.017494) (xy 319.663826 -397.018764) (xy 319.710308 -397.099282) (xy 319.715387 -397.107367)
			(xy 319.730296 -397.119279) (xy 319.748514 -397.124958) (xy 319.75806 -397.124682) (xy 319.8495 -397.117824)
			(xy 319.858885 -397.11671) (xy 319.87594 -397.108596) (xy 319.888938 -397.094894) (xy 319.892934 -397.086328)
			(xy 319.892934 -397.08582) (xy 319.900366 -397.068331) (xy 319.921121 -397.036504) (xy 319.947747 -397.009397)
			(xy 319.979196 -396.988075) (xy 320.014233 -396.973376) (xy 320.051482 -396.965877) (xy 320.07048 -396.965424)
			(xy 320.088343 -396.965828) (xy 320.123445 -396.972483) (xy 320.156706 -396.985528) (xy 320.186972 -397.004513)
			(xy 320.213195 -397.028778) (xy 320.22415 -397.042894) (xy 320.230419 -397.050501) (xy 320.247208 -397.060779)
			(xy 320.266632 -397.063977) (xy 320.28583 -397.059625) (xy 320.301976 -397.048363) (xy 320.307716 -397.040354)
			(xy 320.311526 -397.032988) (xy 320.321432 -397.012668) (xy 320.33305 -396.991751) (xy 320.361849 -396.953544)
			(xy 320.396251 -396.920292) (xy 320.435415 -396.892808) (xy 320.478384 -396.871763) (xy 320.524108 -396.857673)
			(xy 320.571469 -396.850881) (xy 320.61931 -396.851554) (xy 320.666462 -396.859675) (xy 320.711771 -396.875045)
			(xy 320.754132 -396.897289) (xy 320.792508 -396.925864) (xy 320.825961 -396.96007) (xy 320.853675 -396.999072)
			(xy 320.864738 -397.020288) (xy 320.8655 -397.021812) (xy 320.910458 -397.099536) (xy 320.915584 -397.107587)
			(xy 320.93047 -397.119508) (xy 320.94867 -397.125203) (xy 320.95821 -397.124936) (xy 321.063874 -397.117062)
			(xy 321.087496 -397.09979) (xy 321.09283 -397.086074) (xy 321.100317 -397.068575) (xy 321.12108 -397.036684)
			(xy 321.147729 -397.009518) (xy 321.179215 -396.988145) (xy 321.2143 -396.973407) (xy 321.251603 -396.965883)
			(xy 321.27063 -396.965424) (xy 321.271138 -396.965424) (xy 321.292614 -396.966038) (xy 321.334477 -396.975654)
			(xy 321.373148 -396.99435) (xy 321.390264 -397.007334) (xy 321.398392 -397.013938) (xy 321.418966 -397.019526)
			(xy 321.503548 -397.006826) (xy 321.513806 -397.004725) (xy 321.531506 -396.993576) (xy 321.537838 -396.985236)
			(xy 321.538092 -396.984982) (xy 321.552101 -396.96499) (xy 321.585532 -396.929417) (xy 321.624194 -396.899613)
			(xy 321.667104 -396.876335) (xy 321.713169 -396.860178) (xy 321.761217 -396.851551) (xy 321.810026 -396.850674)
			(xy 321.858353 -396.85757) (xy 321.904969 -396.872063) (xy 321.948687 -396.893784) (xy 321.988395 -396.922181)
			(xy 322.023081 -396.956531) (xy 322.051864 -396.995959) (xy 322.063364 -397.017494) (xy 322.063872 -397.018764)
			(xy 322.143412 -397.1564) (xy 335.606861 -397.1564) (xy 335.611047 -397.116575) (xy 335.623422 -397.078491)
			(xy 335.643445 -397.043812) (xy 335.670241 -397.014054) (xy 335.702639 -396.990518) (xy 335.739222 -396.974232)
			(xy 335.778392 -396.965909) (xy 335.798414 -396.965424) (xy 335.798922 -396.965424) (xy 335.8204 -396.965995)
			(xy 335.862265 -396.97563) (xy 335.900934 -396.994342) (xy 335.918048 -397.007334) (xy 335.926176 -397.013938)
			(xy 335.94675 -397.019526) (xy 336.031332 -397.006826) (xy 336.041588 -397.004718) (xy 336.059289 -396.993574)
			(xy 336.065622 -396.985236) (xy 336.065876 -396.984982) (xy 336.079907 -396.965006) (xy 336.113335 -396.929434)
			(xy 336.151995 -396.899629) (xy 336.194902 -396.876352) (xy 336.240965 -396.860194) (xy 336.289011 -396.851566)
			(xy 336.337817 -396.850688) (xy 336.386142 -396.857582) (xy 336.432756 -396.872073) (xy 336.476473 -396.893792)
			(xy 336.51618 -396.922187) (xy 336.550866 -396.956534) (xy 336.579648 -396.99596) (xy 336.591148 -397.017494)
			(xy 336.591656 -397.018764) (xy 336.638138 -397.099282) (xy 336.643264 -397.107332) (xy 336.658152 -397.11925)
			(xy 336.676351 -397.124946) (xy 336.68589 -397.124682) (xy 336.77733 -397.117824) (xy 336.786719 -397.116729)
			(xy 336.803773 -397.108607) (xy 336.816769 -397.094897) (xy 336.820764 -397.086328) (xy 336.820764 -397.08582)
			(xy 336.828252 -397.068357) (xy 336.848998 -397.036533) (xy 336.875612 -397.009426) (xy 336.90705 -396.9881)
			(xy 336.942077 -396.973393) (xy 336.979316 -396.965883) (xy 336.99831 -396.965424) (xy 336.998818 -396.965424)
			(xy 337.020296 -396.965997) (xy 337.062161 -396.975631) (xy 337.10083 -396.994343) (xy 337.117944 -397.007334)
			(xy 337.126072 -397.013938) (xy 337.146646 -397.019526) (xy 337.231228 -397.006826) (xy 337.241483 -397.004716)
			(xy 337.259185 -396.993573) (xy 337.265518 -396.985236) (xy 337.265772 -396.984982) (xy 337.279808 -396.96501)
			(xy 337.313236 -396.929438) (xy 337.351895 -396.899634) (xy 337.394801 -396.876356) (xy 337.440864 -396.860198)
			(xy 337.488909 -396.851569) (xy 337.537715 -396.850691) (xy 337.58604 -396.857585) (xy 337.632653 -396.872076)
			(xy 337.67637 -396.893794) (xy 337.716076 -396.922188) (xy 337.750762 -396.956535) (xy 337.779544 -396.995961)
			(xy 337.791044 -397.017494) (xy 337.791552 -397.018764) (xy 337.838034 -397.099282) (xy 337.843163 -397.10733)
			(xy 337.858049 -397.119248) (xy 337.876247 -397.124945) (xy 337.885786 -397.124682) (xy 337.977226 -397.117824)
			(xy 337.986614 -397.116727) (xy 338.003669 -397.108605) (xy 338.016665 -397.094897) (xy 338.02066 -397.086328)
			(xy 338.02066 -397.08582) (xy 338.028152 -397.068359) (xy 338.048897 -397.036535) (xy 338.07551 -397.009427)
			(xy 338.106948 -396.988101) (xy 338.141974 -396.973394) (xy 338.179212 -396.965884) (xy 338.198206 -396.965424)
			(xy 338.198714 -396.965424) (xy 338.220192 -396.965999) (xy 338.262057 -396.975632) (xy 338.300726 -396.994343)
			(xy 338.31784 -397.007334) (xy 338.325968 -397.013938) (xy 338.346542 -397.019526) (xy 338.431124 -397.006826)
			(xy 338.441379 -397.004714) (xy 338.45908 -396.993573) (xy 338.465414 -396.985236) (xy 338.465668 -396.984982)
			(xy 338.47971 -396.965014) (xy 338.513137 -396.929442) (xy 338.551795 -396.899638) (xy 338.594701 -396.87636)
			(xy 338.640762 -396.860202) (xy 338.688807 -396.851573) (xy 338.737613 -396.850695) (xy 338.785937 -396.857588)
			(xy 338.83255 -396.872078) (xy 338.876266 -396.893797) (xy 338.915972 -396.92219) (xy 338.950658 -396.956536)
			(xy 338.97944 -396.995961) (xy 338.99094 -397.017494) (xy 338.991448 -397.018764) (xy 339.038184 -397.099536)
			(xy 339.043293 -397.1076) (xy 339.058186 -397.119519) (xy 339.076394 -397.125208) (xy 339.085936 -397.124936)
			(xy 339.1916 -397.117062) (xy 339.215222 -397.09979) (xy 339.220556 -397.086074) (xy 339.228022 -397.068565)
			(xy 339.248789 -397.036673) (xy 339.275442 -397.009507) (xy 339.306932 -396.988136) (xy 339.342021 -396.973401)
			(xy 339.379327 -396.965881) (xy 339.398356 -396.965424) (xy 339.398864 -396.965424) (xy 339.420341 -396.966025)
			(xy 339.462204 -396.975647) (xy 339.500874 -396.994348) (xy 339.51799 -397.007334) (xy 339.526118 -397.013938)
			(xy 339.546692 -397.019526) (xy 339.631274 -397.006826) (xy 339.641522 -397.004691) (xy 339.659227 -396.993566)
			(xy 339.665564 -396.985236) (xy 339.665818 -396.984982) (xy 339.679927 -396.965064) (xy 339.713346 -396.929493)
			(xy 339.751997 -396.89969) (xy 339.794895 -396.876412) (xy 339.840948 -396.860251) (xy 339.888986 -396.85162)
			(xy 339.937785 -396.850738) (xy 339.986103 -396.857626) (xy 340.032711 -396.872111) (xy 340.076422 -396.893822)
			(xy 340.116125 -396.922209) (xy 340.150809 -396.956547) (xy 340.179591 -396.995965) (xy 340.19109 -397.017494)
			(xy 340.191598 -397.018764) (xy 340.23808 -397.099282) (xy 340.243178 -397.107353) (xy 340.258078 -397.119267)
			(xy 340.276289 -397.124953) (xy 340.285832 -397.124682) (xy 340.377272 -397.117824) (xy 340.386654 -397.116691)
			(xy 340.403709 -397.108587) (xy 340.416708 -397.094892) (xy 340.420706 -397.086328) (xy 340.420706 -397.08582)
			(xy 340.428161 -397.068341) (xy 340.448912 -397.036516) (xy 340.475533 -397.009409) (xy 340.506978 -396.988085)
			(xy 340.542011 -396.973383) (xy 340.579256 -396.965879) (xy 340.598252 -396.965424) (xy 340.59876 -396.965424)
			(xy 340.620237 -396.966027) (xy 340.6621 -396.975648) (xy 340.70077 -396.994348) (xy 340.717886 -397.007334)
			(xy 340.726014 -397.013938) (xy 340.746588 -397.019526) (xy 340.83117 -397.006826) (xy 340.841431 -397.004735)
			(xy 340.859129 -396.993578) (xy 340.86546 -396.985236) (xy 340.865714 -396.984982) (xy 340.879829 -396.965068)
			(xy 340.913247 -396.929497) (xy 340.951897 -396.899694) (xy 340.994794 -396.876416) (xy 341.040847 -396.860255)
			(xy 341.088884 -396.851624) (xy 341.137682 -396.850741) (xy 341.186 -396.857629) (xy 341.232608 -396.872113)
			(xy 341.276319 -396.893824) (xy 341.316021 -396.92221) (xy 341.350705 -396.956548) (xy 341.379487 -396.995965)
			(xy 341.390986 -397.017494) (xy 341.391494 -397.018764) (xy 341.43823 -397.099536) (xy 341.443375 -397.107573)
			(xy 341.458252 -397.119497) (xy 341.476445 -397.125198) (xy 341.485982 -397.124936) (xy 341.591646 -397.117062)
			(xy 341.615268 -397.09979) (xy 341.620602 -397.086074) (xy 341.628031 -397.068548) (xy 341.648804 -397.036654)
			(xy 341.675464 -397.009489) (xy 341.706962 -396.98812) (xy 341.742058 -396.973389) (xy 341.779371 -396.965876)
			(xy 341.798402 -396.965424) (xy 341.79891 -396.965424) (xy 341.820388 -396.966001) (xy 341.862252 -396.975633)
			(xy 341.900922 -396.994343) (xy 341.918036 -397.007334) (xy 341.926164 -397.013938) (xy 341.946738 -397.019526)
			(xy 342.03132 -397.006826) (xy 342.041574 -397.004712) (xy 342.059276 -396.993572) (xy 342.06561 -396.985236)
			(xy 342.065864 -396.984982) (xy 342.079911 -396.965018) (xy 342.113338 -396.929446) (xy 342.151995 -396.899642)
			(xy 342.1949 -396.876364) (xy 342.240961 -396.860206) (xy 342.289006 -396.851577) (xy 342.337811 -396.850698)
			(xy 342.386134 -396.857591) (xy 342.432747 -396.872081) (xy 342.476463 -396.893799) (xy 342.516168 -396.922191)
			(xy 342.550854 -396.956537) (xy 342.579636 -396.995961) (xy 342.591136 -397.017494) (xy 342.591644 -397.018764)
			(xy 342.638126 -397.099282) (xy 342.64326 -397.107326) (xy 342.658144 -397.119245) (xy 342.67634 -397.124944)
			(xy 342.685878 -397.124682) (xy 342.777318 -397.117824) (xy 342.786705 -397.116721) (xy 342.80376 -397.108603)
			(xy 342.816757 -397.094896) (xy 342.820752 -397.086328) (xy 342.820752 -397.08582) (xy 342.82825 -397.068362)
			(xy 342.848994 -397.036538) (xy 342.875607 -397.009431) (xy 342.907043 -396.988104) (xy 342.942067 -396.973396)
			(xy 342.979305 -396.965885) (xy 342.998298 -396.965424) (xy 342.998806 -396.965424) (xy 343.020284 -396.966003)
			(xy 343.062148 -396.975634) (xy 343.100818 -396.994344) (xy 343.117932 -397.007334) (xy 343.12606 -397.013938)
			(xy 343.146634 -397.019526) (xy 343.231216 -397.006826) (xy 343.24147 -397.00471) (xy 343.259171 -396.993571)
			(xy 343.265506 -396.985236) (xy 343.26576 -396.984982) (xy 343.279813 -396.965022) (xy 343.313238 -396.92945)
			(xy 343.351895 -396.899646) (xy 343.3948 -396.876368) (xy 343.44086 -396.86021) (xy 343.488904 -396.851581)
			(xy 343.537708 -396.850701) (xy 343.586032 -396.857594) (xy 343.632644 -396.872084) (xy 343.676359 -396.893801)
			(xy 343.716065 -396.922193) (xy 343.75075 -396.956538) (xy 343.779532 -396.995961) (xy 343.791032 -397.017494)
			(xy 343.79154 -397.018764) (xy 343.838022 -397.099282) (xy 343.843159 -397.107324) (xy 343.858041 -397.119243)
			(xy 343.876236 -397.124943) (xy 343.885774 -397.124682) (xy 343.977214 -397.117824) (xy 343.986601 -397.116719)
			(xy 344.003656 -397.108601) (xy 344.016652 -397.094896) (xy 344.020648 -397.086328) (xy 344.020648 -397.08582)
			(xy 344.028069 -397.068326) (xy 344.048826 -397.036499) (xy 344.075453 -397.009392) (xy 344.106905 -396.98807)
			(xy 344.141945 -396.973372) (xy 344.179195 -396.965876) (xy 344.198194 -396.965424) (xy 344.198702 -396.965424)
			(xy 344.22018 -396.966005) (xy 344.262044 -396.975635) (xy 344.300713 -396.994344) (xy 344.317828 -397.007334)
			(xy 344.325956 -397.013938) (xy 344.34653 -397.019526) (xy 344.431112 -397.006826) (xy 344.441365 -397.004708)
			(xy 344.459067 -396.993571) (xy 344.465402 -396.985236) (xy 344.465656 -396.984982) (xy 344.479714 -396.965026)
			(xy 344.513139 -396.929454) (xy 344.551796 -396.89965) (xy 344.594699 -396.876373) (xy 344.640759 -396.860214)
			(xy 344.688802 -396.851584) (xy 344.737606 -396.850705) (xy 344.785929 -396.857597) (xy 344.832541 -396.872086)
			(xy 344.876256 -396.893803) (xy 344.915961 -396.922194) (xy 344.950646 -396.956539) (xy 344.979428 -396.995962)
			(xy 344.990928 -397.017494) (xy 344.991436 -397.018764) (xy 345.038172 -397.099536) (xy 345.043289 -397.107594)
			(xy 345.058179 -397.119514) (xy 345.076383 -397.125205) (xy 345.085924 -397.124936) (xy 345.191588 -397.117062)
			(xy 345.21521 -397.09979) (xy 345.220544 -397.086074) (xy 345.22802 -397.06857) (xy 345.248785 -397.036678)
			(xy 345.275436 -397.009512) (xy 345.306924 -396.98814) (xy 345.342011 -396.973404) (xy 345.379316 -396.965882)
			(xy 345.398344 -396.965424) (xy 345.398852 -396.965424) (xy 345.420328 -396.966031) (xy 345.462191 -396.97565)
			(xy 345.500862 -396.994349) (xy 345.517978 -397.007334) (xy 345.526106 -397.013938) (xy 345.54668 -397.019526)
			(xy 345.631262 -397.006826) (xy 345.641522 -397.004732) (xy 345.659221 -396.993577) (xy 345.665552 -396.985236)
			(xy 345.665806 -396.984982) (xy 345.679931 -396.965076) (xy 345.713349 -396.929506) (xy 345.751997 -396.899702)
			(xy 345.794893 -396.876424) (xy 345.840945 -396.860263) (xy 345.888981 -396.851631) (xy 345.937778 -396.850748)
			(xy 345.986095 -396.857635) (xy 346.032701 -396.872118) (xy 346.076412 -396.893828) (xy 346.116114 -396.922213)
			(xy 346.150797 -396.95655) (xy 346.179579 -396.995966) (xy 346.191078 -397.017494) (xy 346.191586 -397.018764)
			(xy 346.238068 -397.099282) (xy 346.243174 -397.107347) (xy 346.258071 -397.119262) (xy 346.276278 -397.124951)
			(xy 346.28582 -397.124682) (xy 346.37726 -397.117824) (xy 346.386641 -397.116683) (xy 346.403696 -397.108582)
			(xy 346.416696 -397.09489) (xy 346.420694 -397.086328) (xy 346.420694 -397.08582) (xy 346.428158 -397.068346)
			(xy 346.448908 -397.036521) (xy 346.475527 -397.009414) (xy 346.50697 -396.988089) (xy 346.542001 -396.973386)
			(xy 346.579244 -396.965881) (xy 346.59824 -396.965424) (xy 346.598748 -396.965424) (xy 346.620224 -396.966033)
			(xy 346.662087 -396.975651) (xy 346.700758 -396.994349) (xy 346.717874 -397.007334) (xy 346.726002 -397.013938)
			(xy 346.746576 -397.019526) (xy 346.831158 -397.006826) (xy 346.841417 -397.00473) (xy 346.859116 -396.993577)
			(xy 346.865448 -396.985236) (xy 346.865702 -396.984982) (xy 346.879833 -396.96508) (xy 346.913249 -396.92951)
			(xy 346.951897 -396.899706) (xy 346.994793 -396.876428) (xy 347.040844 -396.860267) (xy 347.088879 -396.851635)
			(xy 347.137676 -396.850751) (xy 347.185992 -396.857638) (xy 347.232598 -396.872121) (xy 347.276308 -396.893831)
			(xy 347.31601 -396.922215) (xy 347.350693 -396.956551) (xy 347.379475 -396.995966) (xy 347.390974 -397.017494)
			(xy 347.391482 -397.018764) (xy 347.438218 -397.099536) (xy 347.443304 -397.107616) (xy 347.458208 -397.119533)
			(xy 347.476425 -397.125214) (xy 347.48597 -397.124936) (xy 347.591634 -397.117062) (xy 347.615256 -397.09979)
			(xy 347.62059 -397.086074) (xy 347.628029 -397.068552) (xy 347.6488 -397.036659) (xy 347.675458 -397.009493)
			(xy 347.706954 -396.988124) (xy 347.742048 -396.973392) (xy 347.77936 -396.965878) (xy 347.79839 -396.965424)
			(xy 347.798898 -396.965424) (xy 347.820376 -396.966007) (xy 347.86224 -396.975637) (xy 347.900909 -396.994344)
			(xy 347.918024 -397.007334) (xy 347.926152 -397.013938) (xy 347.946726 -397.019526) (xy 348.031308 -397.006826)
			(xy 348.041561 -397.004706) (xy 348.059263 -396.99357) (xy 348.065598 -396.985236) (xy 348.065852 -396.984982)
			(xy 348.079915 -396.96503) (xy 348.11334 -396.929458) (xy 348.151996 -396.899654) (xy 348.194899 -396.876377)
			(xy 348.240958 -396.860218) (xy 348.289 -396.851588) (xy 348.337804 -396.850708) (xy 348.386126 -396.8576)
			(xy 348.432738 -396.872089) (xy 348.476452 -396.893805) (xy 348.516157 -396.922196) (xy 348.550842 -396.95654)
			(xy 348.579624 -396.995962) (xy 348.591124 -397.017494) (xy 348.591632 -397.018764) (xy 348.638114 -397.099282)
			(xy 348.643189 -397.10737) (xy 348.6581 -397.119281) (xy 348.67632 -397.124959) (xy 348.685866 -397.124682)
			(xy 348.777306 -397.117824) (xy 348.786692 -397.116714) (xy 348.803747 -397.108598) (xy 348.816744 -397.094895)
			(xy 348.82074 -397.086328) (xy 348.82074 -397.08582) (xy 348.828167 -397.068329) (xy 348.848923 -397.036502)
			(xy 348.875549 -397.009395) (xy 348.907 -396.988073) (xy 348.942038 -396.973374) (xy 348.979288 -396.965876)
			(xy 348.998286 -396.965424) (xy 348.998794 -396.965424) (xy 349.020272 -396.966009) (xy 349.062136 -396.975638)
			(xy 349.100805 -396.994345) (xy 349.11792 -397.007334) (xy 349.126048 -397.013938) (xy 349.146622 -397.019526)
			(xy 349.231204 -397.006826) (xy 349.241456 -397.004705) (xy 349.259159 -396.99357) (xy 349.265494 -396.985236)
			(xy 349.265748 -396.984982) (xy 349.279817 -396.965034) (xy 349.313241 -396.929462) (xy 349.351896 -396.899659)
			(xy 349.394798 -396.876381) (xy 349.440857 -396.860221) (xy 349.488899 -396.851592) (xy 349.537702 -396.850712)
			(xy 349.586023 -396.857603) (xy 349.632634 -396.872091) (xy 349.676349 -396.893807) (xy 349.716053 -396.922197)
			(xy 349.750738 -396.956541) (xy 349.77952 -396.995962) (xy 349.79102 -397.017494) (xy 349.791528 -397.018764)
			(xy 349.83801 -397.099282) (xy 349.843088 -397.107368) (xy 349.857997 -397.11928) (xy 349.876216 -397.124959)
			(xy 349.885762 -397.124682) (xy 349.977202 -397.117824) (xy 349.986588 -397.116711) (xy 350.003642 -397.108597)
			(xy 350.01664 -397.094895) (xy 350.020636 -397.086328) (xy 350.020636 -397.08582) (xy 350.028066 -397.06833)
			(xy 350.048822 -397.036504) (xy 350.075448 -397.009397) (xy 350.106897 -396.988075) (xy 350.141935 -396.973375)
			(xy 350.179184 -396.965877) (xy 350.198182 -396.965424) (xy 350.19869 -396.965424) (xy 350.220167 -396.966011)
			(xy 350.262031 -396.975639) (xy 350.300701 -396.994345) (xy 350.317816 -397.007334) (xy 350.325944 -397.013938)
			(xy 350.346518 -397.019526) (xy 350.4311 -397.006826) (xy 350.441352 -397.004703) (xy 350.459054 -396.993569)
			(xy 350.46539 -396.985236) (xy 350.465644 -396.984982) (xy 350.479718 -396.965038) (xy 350.513141 -396.929467)
			(xy 350.551796 -396.899663) (xy 350.594698 -396.876385) (xy 350.640756 -396.860225) (xy 350.688797 -396.851596)
			(xy 350.737599 -396.850715) (xy 350.785921 -396.857606) (xy 350.832531 -396.872094) (xy 350.876245 -396.893809)
			(xy 350.91595 -396.922199) (xy 350.950634 -396.956542) (xy 350.979416 -396.995963) (xy 350.990916 -397.017494)
			(xy 350.991424 -397.018764) (xy 351.03816 -397.099536) (xy 351.043285 -397.107588) (xy 351.058171 -397.119509)
			(xy 351.076372 -397.125203) (xy 351.085912 -397.124936) (xy 351.191576 -397.117062) (xy 351.215198 -397.09979)
			(xy 351.220532 -397.086074) (xy 351.228018 -397.068574) (xy 351.248781 -397.036683) (xy 351.27543 -397.009517)
			(xy 351.306916 -396.988145) (xy 351.342001 -396.973407) (xy 351.379305 -396.965883) (xy 351.398332 -396.965424)
			(xy 351.39884 -396.965424) (xy 351.420316 -396.966037) (xy 351.462179 -396.975654) (xy 351.50085 -396.99435)
			(xy 351.517966 -397.007334) (xy 351.526094 -397.013938) (xy 351.546668 -397.019526) (xy 351.63125 -397.006826)
			(xy 351.641508 -397.004726) (xy 351.659208 -396.993576) (xy 351.66554 -396.985236) (xy 351.665794 -396.984982)
			(xy 351.679801 -396.964988) (xy 351.713232 -396.929415) (xy 351.751894 -396.899611) (xy 351.794804 -396.876333)
			(xy 351.84087 -396.860176) (xy 351.888918 -396.851549) (xy 351.937727 -396.850672) (xy 351.986055 -396.857568)
			(xy 352.032671 -396.872062) (xy 352.076389 -396.893783) (xy 352.116096 -396.92218) (xy 352.150783 -396.95653)
			(xy 352.179566 -396.995959) (xy 352.191066 -397.017494) (xy 352.191574 -397.018764) (xy 352.238056 -397.099282)
			(xy 352.24317 -397.107341) (xy 352.258063 -397.119257) (xy 352.276267 -397.124949) (xy 352.285808 -397.124682)
			(xy 352.377248 -397.117824) (xy 352.386628 -397.116675) (xy 352.403682 -397.108578) (xy 352.416683 -397.094889)
			(xy 352.420682 -397.086328) (xy 352.420682 -397.08582) (xy 352.428156 -397.06835) (xy 352.448904 -397.036526)
			(xy 352.475521 -397.009419) (xy 352.506962 -396.988094) (xy 352.541991 -396.973389) (xy 352.579233 -396.965882)
			(xy 352.598228 -396.965424) (xy 352.598736 -396.965424) (xy 352.620212 -396.966039) (xy 352.662075 -396.975655)
			(xy 352.700746 -396.99435) (xy 352.717862 -397.007334) (xy 352.72599 -397.013938) (xy 352.746564 -397.019526)
			(xy 352.831146 -397.006826) (xy 352.841404 -397.004724) (xy 352.859104 -396.993575) (xy 352.865436 -396.985236)
			(xy 352.86569 -396.984982) (xy 352.879702 -396.964992) (xy 352.913133 -396.929419) (xy 352.951794 -396.899615)
			(xy 352.994704 -396.876337) (xy 353.040769 -396.86018) (xy 353.088817 -396.851553) (xy 353.137625 -396.850676)
			(xy 353.185952 -396.857571) (xy 353.232568 -396.872064) (xy 353.276285 -396.893785) (xy 353.315993 -396.922182)
			(xy 353.350679 -396.956531) (xy 353.379462 -396.995959) (xy 353.390962 -397.017494) (xy 353.39147 -397.018764)
			(xy 353.438206 -397.099536) (xy 353.4433 -397.10761) (xy 353.4582 -397.119528) (xy 353.476414 -397.125211)
			(xy 353.485958 -397.124936) (xy 353.591622 -397.117062) (xy 353.615244 -397.09979) (xy 353.620578 -397.086074)
			(xy 353.628027 -397.068557) (xy 353.648796 -397.036664) (xy 353.675452 -397.009498) (xy 353.706946 -396.988128)
			(xy 353.742038 -396.973395) (xy 353.779348 -396.965879) (xy 353.798378 -396.965424) (xy 353.798886 -396.965424)
			(xy 353.820363 -396.966014) (xy 353.862227 -396.97564) (xy 353.900897 -396.994346) (xy 353.918012 -397.007334)
			(xy 353.92614 -397.013938) (xy 353.946714 -397.019526) (xy 354.031296 -397.006826) (xy 354.041547 -397.004701)
			(xy 354.05925 -396.993569) (xy 354.065586 -396.985236) (xy 354.06584 -396.984982) (xy 354.07992 -396.965042)
			(xy 354.113342 -396.929471) (xy 354.151996 -396.899667) (xy 354.194897 -396.876389) (xy 354.240955 -396.860229)
			(xy 354.288995 -396.851599) (xy 354.337797 -396.850719) (xy 354.386118 -396.857609) (xy 354.432728 -396.872096)
			(xy 354.476442 -396.893811) (xy 354.516146 -396.9222) (xy 354.55083 -396.956542) (xy 354.579612 -396.995963)
			(xy 354.591112 -397.017494) (xy 354.59162 -397.018764) (xy 354.67116 -397.1564) (xy 370.179398 -397.1564)
			(xy 370.183582 -397.116589) (xy 370.19595 -397.078518) (xy 370.215963 -397.04385) (xy 370.242745 -397.0141)
			(xy 370.275127 -396.990567) (xy 370.311694 -396.97428) (xy 370.350847 -396.965951) (xy 370.370862 -396.965424)
			(xy 370.37137 -396.965424) (xy 370.392847 -396.966022) (xy 370.43471 -396.975645) (xy 370.473381 -396.994347)
			(xy 370.490496 -397.007334) (xy 370.498624 -397.013938) (xy 370.519198 -397.019526) (xy 370.60378 -397.006826)
			(xy 370.614029 -397.004694) (xy 370.631733 -396.993567) (xy 370.63807 -396.985236) (xy 370.638324 -396.984982)
			(xy 370.652425 -396.965058) (xy 370.685845 -396.929487) (xy 370.724497 -396.899684) (xy 370.767395 -396.876405)
			(xy 370.81345 -396.860245) (xy 370.861488 -396.851614) (xy 370.910288 -396.850732) (xy 370.958607 -396.857622)
			(xy 371.005216 -396.872107) (xy 371.048928 -396.893819) (xy 371.088631 -396.922206) (xy 371.123315 -396.956546)
			(xy 371.152096 -396.995964) (xy 371.163596 -397.017494) (xy 371.164104 -397.018764) (xy 371.210586 -397.099282)
			(xy 371.21568 -397.107356) (xy 371.230582 -397.11927) (xy 371.248794 -397.124954) (xy 371.258338 -397.124682)
			(xy 371.349778 -397.117824) (xy 371.359161 -397.116695) (xy 371.376216 -397.108589) (xy 371.389215 -397.094892)
			(xy 371.393212 -397.086328) (xy 371.393212 -397.08582) (xy 371.400662 -397.068339) (xy 371.421414 -397.036513)
			(xy 371.448036 -397.009406) (xy 371.479482 -396.988083) (xy 371.514516 -396.973381) (xy 371.551761 -396.965879)
			(xy 371.570758 -396.965424) (xy 371.571266 -396.965424) (xy 371.592743 -396.966024) (xy 371.634606 -396.975646)
			(xy 371.673276 -396.994347) (xy 371.690392 -397.007334) (xy 371.69852 -397.013938) (xy 371.719094 -397.019526)
			(xy 371.803676 -397.006826) (xy 371.813925 -397.004692) (xy 371.831629 -396.993566) (xy 371.837966 -396.985236)
			(xy 371.83822 -396.984982) (xy 371.852326 -396.965062) (xy 371.885746 -396.929491) (xy 371.924397 -396.899688)
			(xy 371.967295 -396.87641) (xy 372.013349 -396.860249) (xy 372.061387 -396.851618) (xy 372.110186 -396.850736)
			(xy 372.158504 -396.857625) (xy 372.205112 -396.872109) (xy 372.248824 -396.893821) (xy 372.288527 -396.922208)
			(xy 372.323211 -396.956547) (xy 372.351993 -396.995964) (xy 372.363492 -397.017494) (xy 372.364 -397.018764)
			(xy 372.410482 -397.099282) (xy 372.415579 -397.107354) (xy 372.43048 -397.119268) (xy 372.448691 -397.124954)
			(xy 372.458234 -397.124682) (xy 372.549674 -397.117824) (xy 372.559057 -397.116692) (xy 372.576111 -397.108588)
			(xy 372.589111 -397.094892) (xy 372.593108 -397.086328) (xy 372.593108 -397.08582) (xy 372.600561 -397.068341)
			(xy 372.621313 -397.036515) (xy 372.647934 -397.009408) (xy 372.679379 -396.988084) (xy 372.714412 -396.973382)
			(xy 372.751657 -396.965879) (xy 372.770654 -396.965424) (xy 372.771162 -396.965424) (xy 372.792639 -396.966026)
			(xy 372.834502 -396.975647) (xy 372.873172 -396.994348) (xy 372.890288 -397.007334) (xy 372.898416 -397.013938)
			(xy 372.91899 -397.019526) (xy 373.003572 -397.006826) (xy 373.01382 -397.00469) (xy 373.031525 -396.993566)
			(xy 373.037862 -396.985236) (xy 373.038116 -396.984982) (xy 373.052228 -396.965066) (xy 373.085647 -396.929495)
			(xy 373.124297 -396.899692) (xy 373.167194 -396.876414) (xy 373.213248 -396.860253) (xy 373.261285 -396.851622)
			(xy 373.310084 -396.850739) (xy 373.358401 -396.857628) (xy 373.405009 -396.872112) (xy 373.448721 -396.893823)
			(xy 373.488423 -396.922209) (xy 373.523107 -396.956548) (xy 373.551889 -396.995965) (xy 373.563388 -397.017494)
			(xy 373.563896 -397.018764) (xy 373.610632 -397.099536) (xy 373.615776 -397.107574) (xy 373.630653 -397.119497)
			(xy 373.648847 -397.125198) (xy 373.658384 -397.124936) (xy 373.764048 -397.117062) (xy 373.78767 -397.09979)
			(xy 373.793004 -397.086074) (xy 373.800432 -397.068547) (xy 373.821205 -397.036653) (xy 373.847865 -397.009488)
			(xy 373.879363 -396.988119) (xy 373.914459 -396.973389) (xy 373.951773 -396.965876) (xy 373.970804 -396.965424)
			(xy 373.971312 -396.965424) (xy 373.99279 -396.966) (xy 374.034654 -396.975632) (xy 374.073324 -396.994343)
			(xy 374.090438 -397.007334) (xy 374.098566 -397.013938) (xy 374.11914 -397.019526) (xy 374.203722 -397.006826)
			(xy 374.213977 -397.004713) (xy 374.231678 -396.993572) (xy 374.238012 -396.985236) (xy 374.238266 -396.984982)
			(xy 374.25231 -396.965016) (xy 374.285737 -396.929444) (xy 374.324395 -396.89964) (xy 374.367301 -396.876362)
			(xy 374.413362 -396.860204) (xy 374.461406 -396.851575) (xy 374.510212 -396.850696) (xy 374.558536 -396.85759)
			(xy 374.605149 -396.87208) (xy 374.648864 -396.893798) (xy 374.68857 -396.922191) (xy 374.723256 -396.956537)
			(xy 374.752038 -396.995961) (xy 374.763538 -397.017494) (xy 374.764046 -397.018764) (xy 374.810528 -397.099282)
			(xy 374.815661 -397.107327) (xy 374.830545 -397.119245) (xy 374.848742 -397.124944) (xy 374.85828 -397.124682)
			(xy 374.94972 -397.117824) (xy 374.959108 -397.116723) (xy 374.976162 -397.108603) (xy 374.989159 -397.094896)
			(xy 374.993154 -397.086328) (xy 374.993154 -397.08582) (xy 375.00065 -397.068361) (xy 375.021395 -397.036537)
			(xy 375.048008 -397.00943) (xy 375.079444 -396.988103) (xy 375.114469 -396.973396) (xy 375.151706 -396.965884)
			(xy 375.1707 -396.965424) (xy 375.171208 -396.965424) (xy 375.192686 -396.966002) (xy 375.23455 -396.975634)
			(xy 375.27322 -396.994344) (xy 375.290334 -397.007334) (xy 375.298462 -397.013938) (xy 375.319036 -397.019526)
			(xy 375.403618 -397.006826) (xy 375.413872 -397.004712) (xy 375.431574 -396.993572) (xy 375.437908 -396.985236)
			(xy 375.438162 -396.984982) (xy 375.452212 -396.96502) (xy 375.485638 -396.929448) (xy 375.524295 -396.899644)
			(xy 375.5672 -396.876366) (xy 375.613261 -396.860208) (xy 375.661305 -396.851579) (xy 375.710109 -396.8507)
			(xy 375.758433 -396.857593) (xy 375.805045 -396.872082) (xy 375.848761 -396.8938) (xy 375.888466 -396.922192)
			(xy 375.923152 -396.956537) (xy 375.951934 -396.995961) (xy 375.963434 -397.017494) (xy 375.963942 -397.018764)
			(xy 376.010678 -397.099536) (xy 376.015791 -397.107597) (xy 376.030682 -397.119517) (xy 376.048889 -397.125207)
			(xy 376.05843 -397.124936) (xy 376.164094 -397.117062) (xy 376.187716 -397.09979) (xy 376.19305 -397.086074)
			(xy 376.200521 -397.068567) (xy 376.221287 -397.036676) (xy 376.247939 -397.00951) (xy 376.279428 -396.988138)
			(xy 376.314516 -396.973402) (xy 376.351822 -396.965881) (xy 376.37085 -396.965424) (xy 376.371358 -396.965424)
			(xy 376.392834 -396.966028) (xy 376.434698 -396.975648) (xy 376.473368 -396.994348) (xy 376.490484 -397.007334)
			(xy 376.498612 -397.013938) (xy 376.519186 -397.019526) (xy 376.603768 -397.006826) (xy 376.614028 -397.004734)
			(xy 376.631727 -396.993578) (xy 376.638058 -396.985236) (xy 376.638312 -396.984982) (xy 376.652429 -396.96507)
			(xy 376.685848 -396.929499) (xy 376.724497 -396.899696) (xy 376.767394 -396.876418) (xy 376.813447 -396.860257)
			(xy 376.861483 -396.851626) (xy 376.910281 -396.850743) (xy 376.958599 -396.857631) (xy 377.005206 -396.872114)
			(xy 377.048917 -396.893825) (xy 377.08862 -396.922211) (xy 377.123303 -396.956549) (xy 377.152085 -396.995965)
			(xy 377.163584 -397.017494) (xy 377.164092 -397.018764) (xy 377.210574 -397.099282) (xy 377.215676 -397.10735)
			(xy 377.230574 -397.119265) (xy 377.248784 -397.124952) (xy 377.258326 -397.124682) (xy 377.349766 -397.117824)
			(xy 377.359148 -397.116687) (xy 377.376202 -397.108584) (xy 377.389202 -397.094891) (xy 377.3932 -397.086328)
			(xy 377.3932 -397.08582) (xy 377.400659 -397.068344) (xy 377.42141 -397.036518) (xy 377.44803 -397.009411)
			(xy 377.479474 -396.988087) (xy 377.514506 -396.973384) (xy 377.55175 -396.96588) (xy 377.570746 -396.965424)
			(xy 377.571254 -396.965424) (xy 377.59273 -396.96603) (xy 377.634594 -396.975649) (xy 377.673264 -396.994348)
			(xy 377.69038 -397.007334) (xy 377.698508 -397.013938) (xy 377.719082 -397.019526) (xy 377.803664 -397.006826)
			(xy 377.813924 -397.004733) (xy 377.831623 -396.993578) (xy 377.837954 -396.985236) (xy 377.838208 -396.984982)
			(xy 377.852331 -396.965074) (xy 377.885748 -396.929504) (xy 377.924397 -396.8997) (xy 377.967293 -396.876422)
			(xy 378.013346 -396.860261) (xy 378.061382 -396.851629) (xy 378.110179 -396.850746) (xy 378.158496 -396.857634)
			(xy 378.205103 -396.872117) (xy 378.248814 -396.893827) (xy 378.288516 -396.922212) (xy 378.323199 -396.95655)
			(xy 378.351981 -396.995965) (xy 378.36348 -397.017494) (xy 378.363988 -397.018764) (xy 378.41047 -397.099282)
			(xy 378.415575 -397.107348) (xy 378.430472 -397.119263) (xy 378.44868 -397.124952) (xy 378.458222 -397.124682)
			(xy 378.549662 -397.117824) (xy 378.559043 -397.116684) (xy 378.576098 -397.108583) (xy 378.589098 -397.094891)
			(xy 378.593096 -397.086328) (xy 378.593096 -397.08582) (xy 378.600559 -397.068345) (xy 378.621309 -397.03652)
			(xy 378.647928 -397.009413) (xy 378.679371 -396.988089) (xy 378.714403 -396.973385) (xy 378.751646 -396.96588)
			(xy 378.770642 -396.965424) (xy 378.77115 -396.965424) (xy 378.792626 -396.966032) (xy 378.834489 -396.975651)
			(xy 378.87316 -396.994349) (xy 378.890276 -397.007334) (xy 378.898404 -397.013938) (xy 378.918978 -397.019526)
			(xy 379.00356 -397.006826) (xy 379.013819 -397.004731) (xy 379.031518 -396.993577) (xy 379.03785 -396.985236)
			(xy 379.038104 -396.984982) (xy 379.052232 -396.965078) (xy 379.085649 -396.929508) (xy 379.124297 -396.899704)
			(xy 379.167193 -396.876426) (xy 379.213244 -396.860265) (xy 379.26128 -396.851633) (xy 379.310077 -396.85075)
			(xy 379.358393 -396.857637) (xy 379.405 -396.87212) (xy 379.44871 -396.89383) (xy 379.488412 -396.922214)
			(xy 379.523095 -396.956551) (xy 379.551877 -396.995966) (xy 379.563376 -397.017494) (xy 379.563884 -397.018764)
			(xy 379.61062 -397.099536) (xy 379.615772 -397.107568) (xy 379.630646 -397.119492) (xy 379.648836 -397.125196)
			(xy 379.658372 -397.124936) (xy 379.764036 -397.117062) (xy 379.787658 -397.09979) (xy 379.792992 -397.086074)
			(xy 379.800429 -397.068552) (xy 379.821201 -397.036658) (xy 379.847859 -397.009493) (xy 379.879355 -396.988123)
			(xy 379.91445 -396.973392) (xy 379.951762 -396.965877) (xy 379.970792 -396.965424) (xy 379.9713 -396.965424)
			(xy 379.992778 -396.966006) (xy 380.034642 -396.975636) (xy 380.073311 -396.994344) (xy 380.090426 -397.007334)
			(xy 380.098554 -397.013938) (xy 380.119128 -397.019526) (xy 380.20371 -397.006826) (xy 380.213963 -397.004707)
			(xy 380.231665 -396.99357) (xy 380.238 -396.985236) (xy 380.238254 -396.984982) (xy 380.252315 -396.965028)
			(xy 380.285739 -396.929456) (xy 380.324396 -396.899652) (xy 380.367299 -396.876375) (xy 380.413358 -396.860216)
			(xy 380.461401 -396.851586) (xy 380.510205 -396.850707) (xy 380.558527 -396.857599) (xy 380.605139 -396.872087)
			(xy 380.648854 -396.893804) (xy 380.688559 -396.922195) (xy 380.723244 -396.956539) (xy 380.752026 -396.995962)
			(xy 380.763526 -397.017494) (xy 380.764034 -397.018764) (xy 380.810516 -397.099282) (xy 380.81559 -397.107371)
			(xy 380.830501 -397.119282) (xy 380.848722 -397.12496) (xy 380.858268 -397.124682) (xy 380.949708 -397.117824)
			(xy 380.959094 -397.116715) (xy 380.976149 -397.108599) (xy 380.989146 -397.094895) (xy 380.993142 -397.086328)
			(xy 380.993142 -397.08582) (xy 381.000568 -397.068328) (xy 381.021324 -397.036501) (xy 381.04795 -397.009394)
			(xy 381.079401 -396.988072) (xy 381.11444 -396.973374) (xy 381.15169 -396.965876) (xy 381.170688 -396.965424)
			(xy 381.171196 -396.965424) (xy 381.192674 -396.966008) (xy 381.234538 -396.975637) (xy 381.273207 -396.994345)
			(xy 381.290322 -397.007334) (xy 381.29845 -397.013938) (xy 381.319024 -397.019526) (xy 381.403606 -397.006826)
			(xy 381.413858 -397.004706) (xy 381.431561 -396.99357) (xy 381.437896 -396.985236) (xy 381.43815 -396.984982)
			(xy 381.452216 -396.965032) (xy 381.48564 -396.92946) (xy 381.524296 -396.899656) (xy 381.567199 -396.876379)
			(xy 381.613257 -396.860219) (xy 381.6613 -396.85159) (xy 381.710103 -396.85071) (xy 381.758425 -396.857602)
			(xy 381.805036 -396.87209) (xy 381.84875 -396.893806) (xy 381.888455 -396.922197) (xy 381.92314 -396.95654)
			(xy 381.951922 -396.995962) (xy 381.963422 -397.017494) (xy 381.96393 -397.018764) (xy 382.010666 -397.099536)
			(xy 382.015787 -397.107591) (xy 382.030675 -397.119512) (xy 382.048878 -397.125204) (xy 382.058418 -397.124936)
			(xy 382.164082 -397.117062) (xy 382.187704 -397.09979) (xy 382.193038 -397.086074) (xy 382.200519 -397.068572)
			(xy 382.221283 -397.036681) (xy 382.247933 -397.009515) (xy 382.27942 -396.988143) (xy 382.314506 -396.973405)
			(xy 382.35181 -396.965882) (xy 382.370838 -396.965424) (xy 382.371346 -396.965424) (xy 382.392822 -396.966034)
			(xy 382.434685 -396.975652) (xy 382.473356 -396.994349) (xy 382.490472 -397.007334) (xy 382.4986 -397.013938)
			(xy 382.519174 -397.019526) (xy 382.603756 -397.006826) (xy 382.614015 -397.004729) (xy 382.631714 -396.993577)
			(xy 382.638046 -396.985236) (xy 382.6383 -396.984982) (xy 382.652433 -396.965082) (xy 382.68585 -396.929512)
			(xy 382.724497 -396.899709) (xy 382.767392 -396.87643) (xy 382.813443 -396.860269) (xy 382.861478 -396.851637)
			(xy 382.910275 -396.850753) (xy 382.958591 -396.85764) (xy 383.005197 -396.872122) (xy 383.048907 -396.893832)
			(xy 383.088608 -396.922215) (xy 383.123291 -396.956552) (xy 383.152073 -396.995966) (xy 383.163572 -397.017494)
			(xy 383.16408 -397.018764) (xy 383.210562 -397.099282) (xy 383.215672 -397.107344) (xy 383.230567 -397.11926)
			(xy 383.248773 -397.12495) (xy 383.258314 -397.124682) (xy 383.349754 -397.117824) (xy 383.359134 -397.116679)
			(xy 383.376189 -397.10858) (xy 383.38919 -397.09489) (xy 383.393188 -397.086328) (xy 383.393188 -397.08582)
			(xy 383.400657 -397.068348) (xy 383.421406 -397.036523) (xy 383.448024 -397.009416) (xy 383.479466 -396.988092)
			(xy 383.514496 -396.973387) (xy 383.551739 -396.965881) (xy 383.570734 -396.965424) (xy 383.571242 -396.965424)
			(xy 383.592718 -396.966036) (xy 383.634581 -396.975653) (xy 383.673252 -396.99435) (xy 383.690368 -397.007334)
			(xy 383.698496 -397.013938) (xy 383.71907 -397.019526) (xy 383.803652 -397.006826) (xy 383.81391 -397.004727)
			(xy 383.83161 -396.993576) (xy 383.837942 -396.985236) (xy 383.838196 -396.984982) (xy 383.8522 -396.964986)
			(xy 383.885631 -396.929413) (xy 383.924294 -396.899609) (xy 383.967204 -396.876331) (xy 384.01327 -396.860174)
			(xy 384.061319 -396.851547) (xy 384.110129 -396.850671) (xy 384.158456 -396.857567) (xy 384.205072 -396.87206)
			(xy 384.24879 -396.893782) (xy 384.288498 -396.922179) (xy 384.323185 -396.95653) (xy 384.351968 -396.995959)
			(xy 384.363468 -397.017494) (xy 384.363976 -397.018764) (xy 384.410458 -397.099282) (xy 384.415571 -397.107342)
			(xy 384.430464 -397.119258) (xy 384.448669 -397.12495) (xy 384.45821 -397.124682) (xy 384.54965 -397.117824)
			(xy 384.55903 -397.116676) (xy 384.576085 -397.108579) (xy 384.589085 -397.09489) (xy 384.593084 -397.086328)
			(xy 384.593084 -397.08582) (xy 384.600556 -397.06835) (xy 384.621305 -397.036525) (xy 384.647922 -397.009418)
			(xy 384.679363 -396.988093) (xy 384.714393 -396.973388) (xy 384.751635 -396.965882) (xy 384.77063 -396.965424)
			(xy 384.771138 -396.965424) (xy 384.792614 -396.966038) (xy 384.834477 -396.975654) (xy 384.873148 -396.99435)
			(xy 384.890264 -397.007334) (xy 384.898392 -397.013938) (xy 384.918966 -397.019526) (xy 385.003548 -397.006826)
			(xy 385.013806 -397.004725) (xy 385.031506 -396.993576) (xy 385.037838 -396.985236) (xy 385.038092 -396.984982)
			(xy 385.052101 -396.96499) (xy 385.085532 -396.929417) (xy 385.124194 -396.899613) (xy 385.167104 -396.876335)
			(xy 385.213169 -396.860178) (xy 385.261217 -396.851551) (xy 385.310026 -396.850674) (xy 385.358353 -396.85757)
			(xy 385.404969 -396.872063) (xy 385.448687 -396.893784) (xy 385.488395 -396.922181) (xy 385.523081 -396.956531)
			(xy 385.551864 -396.995959) (xy 385.563364 -397.017494) (xy 385.563872 -397.018764) (xy 385.610608 -397.099536)
			(xy 385.615701 -397.107611) (xy 385.630602 -397.119529) (xy 385.648816 -397.125212) (xy 385.65836 -397.124936)
			(xy 385.764024 -397.117062) (xy 385.787646 -397.09979) (xy 385.79298 -397.086074) (xy 385.800427 -397.068556)
			(xy 385.821197 -397.036663) (xy 385.847853 -397.009497) (xy 385.879347 -396.988128) (xy 385.91444 -396.973395)
			(xy 385.95175 -396.965879) (xy 385.97078 -396.965424) (xy 385.971288 -396.965424) (xy 385.992765 -396.966013)
			(xy 386.034629 -396.975639) (xy 386.073299 -396.994345) (xy 386.090414 -397.007334) (xy 386.098542 -397.013938)
			(xy 386.119116 -397.019526) (xy 386.203698 -397.006826) (xy 386.213949 -397.004702) (xy 386.231652 -396.993569)
			(xy 386.237988 -396.985236) (xy 386.238242 -396.984982) (xy 386.252319 -396.96504) (xy 386.285742 -396.929469)
			(xy 386.324396 -396.899665) (xy 386.367298 -396.876387) (xy 386.413355 -396.860227) (xy 386.461396 -396.851598)
			(xy 386.510198 -396.850717) (xy 386.558519 -396.857608) (xy 386.60513 -396.872095) (xy 386.648843 -396.89381)
			(xy 386.688548 -396.9222) (xy 386.723232 -396.956542) (xy 386.752014 -396.995963) (xy 386.763514 -397.017494)
			(xy 386.764022 -397.018764) (xy 386.810504 -397.099282) (xy 386.815586 -397.107365) (xy 386.830494 -397.119277)
			(xy 386.848711 -397.124958) (xy 386.858256 -397.124682) (xy 386.949696 -397.117824) (xy 386.959081 -397.116707)
			(xy 386.976136 -397.108595) (xy 386.989134 -397.094894) (xy 386.99313 -397.086328) (xy 386.99313 -397.08582)
			(xy 387.000565 -397.068332) (xy 387.02132 -397.036506) (xy 387.047945 -397.009399) (xy 387.079393 -396.988077)
			(xy 387.11443 -396.973377) (xy 387.151678 -396.965877) (xy 387.170676 -396.965424) (xy 387.171184 -396.965424)
			(xy 387.192661 -396.966015) (xy 387.234525 -396.975641) (xy 387.273195 -396.994346) (xy 387.29031 -397.007334)
			(xy 387.298438 -397.013938) (xy 387.319012 -397.019526) (xy 387.403594 -397.006826) (xy 387.413845 -397.0047)
			(xy 387.431548 -396.993568) (xy 387.437884 -396.985236) (xy 387.438138 -396.984982) (xy 387.45222 -396.965044)
			(xy 387.485643 -396.929473) (xy 387.524296 -396.899669) (xy 387.567197 -396.876391) (xy 387.613254 -396.860231)
			(xy 387.661294 -396.851601) (xy 387.710096 -396.85072) (xy 387.758417 -396.857611) (xy 387.805027 -396.872098)
			(xy 387.84874 -396.893812) (xy 387.888444 -396.922201) (xy 387.923128 -396.956543) (xy 387.95191 -396.995963)
			(xy 387.96341 -397.017494) (xy 387.963918 -397.018764) (xy 388.010654 -397.099536) (xy 388.015783 -397.107585)
			(xy 388.030667 -397.119507) (xy 388.048867 -397.125202) (xy 388.058406 -397.124936) (xy 388.16407 -397.117062)
			(xy 388.187692 -397.09979) (xy 388.193026 -397.086074) (xy 388.200517 -397.068576) (xy 388.221279 -397.036685)
			(xy 388.247927 -397.009519) (xy 388.279412 -396.988147) (xy 388.314496 -396.973408) (xy 388.351799 -396.965884)
			(xy 388.370826 -396.965424) (xy 388.371334 -396.965424) (xy 388.39281 -396.96604) (xy 388.434673 -396.975655)
			(xy 388.473344 -396.99435) (xy 388.49046 -397.007334) (xy 388.498588 -397.013938) (xy 388.519162 -397.019526)
			(xy 388.603744 -397.006826) (xy 388.614001 -397.004723) (xy 388.631702 -396.993575) (xy 388.638034 -396.985236)
			(xy 388.638288 -396.984982) (xy 388.652303 -396.964994) (xy 388.685733 -396.929421) (xy 388.724394 -396.899617)
			(xy 388.767303 -396.87634) (xy 388.813368 -396.860182) (xy 388.861416 -396.851554) (xy 388.910224 -396.850677)
			(xy 388.958551 -396.857573) (xy 389.005166 -396.872065) (xy 389.048883 -396.893786) (xy 389.088591 -396.922182)
			(xy 389.123277 -396.956532) (xy 389.15206 -396.995959) (xy 389.16356 -397.017494) (xy 389.164068 -397.018764)
			(xy 389.243608 -397.1564) (xy 402.707061 -397.1564) (xy 402.711247 -397.116575) (xy 402.723622 -397.078492)
			(xy 402.743644 -397.043813) (xy 402.770439 -397.014055) (xy 402.802836 -396.990519) (xy 402.839419 -396.974233)
			(xy 402.878588 -396.965909) (xy 402.89861 -396.965424) (xy 402.899118 -396.965424) (xy 402.920596 -396.965997)
			(xy 402.962461 -396.975631) (xy 403.00113 -396.994343) (xy 403.018244 -397.007334) (xy 403.026372 -397.013938)
			(xy 403.046946 -397.019526) (xy 403.131528 -397.006826) (xy 403.141783 -397.004716) (xy 403.159485 -396.993573)
			(xy 403.165818 -396.985236) (xy 403.166072 -396.984982) (xy 403.180108 -396.96501) (xy 403.213536 -396.929438)
			(xy 403.252195 -396.899634) (xy 403.295101 -396.876356) (xy 403.341164 -396.860198) (xy 403.389209 -396.851569)
			(xy 403.438015 -396.850691) (xy 403.48634 -396.857585) (xy 403.532953 -396.872076) (xy 403.57667 -396.893794)
			(xy 403.616376 -396.922188) (xy 403.651062 -396.956535) (xy 403.679844 -396.995961) (xy 403.691344 -397.017494)
			(xy 403.691852 -397.018764) (xy 403.738334 -397.099282) (xy 403.743463 -397.10733) (xy 403.758349 -397.119248)
			(xy 403.776547 -397.124945) (xy 403.786086 -397.124682) (xy 403.877526 -397.117824) (xy 403.886914 -397.116727)
			(xy 403.903969 -397.108605) (xy 403.916965 -397.094897) (xy 403.92096 -397.086328) (xy 403.92096 -397.08582)
			(xy 403.928452 -397.068359) (xy 403.949197 -397.036535) (xy 403.97581 -397.009427) (xy 404.007248 -396.988101)
			(xy 404.042274 -396.973394) (xy 404.079512 -396.965884) (xy 404.098506 -396.965424) (xy 404.099014 -396.965424)
			(xy 404.120492 -396.965999) (xy 404.162357 -396.975632) (xy 404.201026 -396.994343) (xy 404.21814 -397.007334)
			(xy 404.226268 -397.013938) (xy 404.246842 -397.019526) (xy 404.331424 -397.006826) (xy 404.341679 -397.004714)
			(xy 404.35938 -396.993573) (xy 404.365714 -396.985236) (xy 404.365968 -396.984982) (xy 404.38001 -396.965014)
			(xy 404.413437 -396.929442) (xy 404.452095 -396.899638) (xy 404.495001 -396.87636) (xy 404.541062 -396.860202)
			(xy 404.589107 -396.851573) (xy 404.637913 -396.850695) (xy 404.686237 -396.857588) (xy 404.73285 -396.872078)
			(xy 404.776566 -396.893797) (xy 404.816272 -396.92219) (xy 404.850958 -396.956536) (xy 404.87974 -396.995961)
			(xy 404.89124 -397.017494) (xy 404.891748 -397.018764) (xy 404.93823 -397.099282) (xy 404.943361 -397.107328)
			(xy 404.958247 -397.119246) (xy 404.976444 -397.124945) (xy 404.985982 -397.124682) (xy 405.077422 -397.117824)
			(xy 405.08681 -397.116724) (xy 405.103864 -397.108604) (xy 405.116861 -397.094897) (xy 405.120856 -397.086328)
			(xy 405.120856 -397.08582) (xy 405.128351 -397.06836) (xy 405.149095 -397.036536) (xy 405.175709 -397.009429)
			(xy 405.207145 -396.988103) (xy 405.24217 -396.973395) (xy 405.279408 -396.965884) (xy 405.298402 -396.965424)
			(xy 405.316263 -396.965883) (xy 405.351362 -396.972524) (xy 405.384622 -396.985556) (xy 405.414889 -397.004529)
			(xy 405.441115 -397.028783) (xy 405.452072 -397.042894) (xy 405.458316 -397.050523) (xy 405.475114 -397.060801)
			(xy 405.494545 -397.063995) (xy 405.513749 -397.059637) (xy 405.529898 -397.048367) (xy 405.535638 -397.040354)
			(xy 405.539448 -397.032988) (xy 405.549354 -397.012668) (xy 405.560939 -396.991732) (xy 405.589741 -396.953523)
			(xy 405.624146 -396.92027) (xy 405.663314 -396.892785) (xy 405.706287 -396.871741) (xy 405.752014 -396.857652)
			(xy 405.799378 -396.850861) (xy 405.847222 -396.851535) (xy 405.894376 -396.859658) (xy 405.939688 -396.875031)
			(xy 405.982051 -396.897278) (xy 406.020428 -396.925855) (xy 406.053883 -396.960065) (xy 406.081596 -396.99907)
			(xy 406.09266 -397.020288) (xy 406.093422 -397.021812) (xy 406.13838 -397.099536) (xy 406.143492 -397.107598)
			(xy 406.158384 -397.119517) (xy 406.17659 -397.125207) (xy 406.186132 -397.124936) (xy 406.291796 -397.117062)
			(xy 406.315418 -397.09979) (xy 406.320752 -397.086074) (xy 406.328222 -397.068567) (xy 406.348988 -397.036675)
			(xy 406.37564 -397.009509) (xy 406.407129 -396.988138) (xy 406.442217 -396.973402) (xy 406.479524 -396.965881)
			(xy 406.498552 -396.965424) (xy 406.49906 -396.965424) (xy 406.520537 -396.966027) (xy 406.5624 -396.975648)
			(xy 406.60107 -396.994348) (xy 406.618186 -397.007334) (xy 406.626314 -397.013938) (xy 406.646888 -397.019526)
			(xy 406.73147 -397.006826) (xy 406.741731 -397.004735) (xy 406.759429 -396.993578) (xy 406.76576 -396.985236)
			(xy 406.766014 -396.984982) (xy 406.780129 -396.965068) (xy 406.813547 -396.929497) (xy 406.852197 -396.899694)
			(xy 406.895094 -396.876416) (xy 406.941147 -396.860255) (xy 406.989184 -396.851624) (xy 407.037982 -396.850741)
			(xy 407.0863 -396.857629) (xy 407.132908 -396.872113) (xy 407.176619 -396.893824) (xy 407.216321 -396.92221)
			(xy 407.251005 -396.956548) (xy 407.279787 -396.995965) (xy 407.291286 -397.017494) (xy 407.291794 -397.018764)
			(xy 407.338276 -397.099282) (xy 407.343377 -397.107351) (xy 407.358276 -397.119265) (xy 407.376485 -397.124953)
			(xy 407.386028 -397.124682) (xy 407.477468 -397.117824) (xy 407.48685 -397.116688) (xy 407.503904 -397.108585)
			(xy 407.516904 -397.094891) (xy 407.520902 -397.086328) (xy 407.520902 -397.08582) (xy 407.52836 -397.068343)
			(xy 407.549111 -397.036518) (xy 407.575731 -397.00941) (xy 407.607175 -396.988087) (xy 407.642208 -396.973384)
			(xy 407.679452 -396.96588) (xy 407.698448 -396.965424) (xy 407.698956 -396.965424) (xy 407.720432 -396.966029)
			(xy 407.762296 -396.975649) (xy 407.800966 -396.994348) (xy 407.818082 -397.007334) (xy 407.82621 -397.013938)
			(xy 407.846784 -397.019526) (xy 407.931366 -397.006826) (xy 407.941626 -397.004734) (xy 407.959325 -396.993578)
			(xy 407.965656 -396.985236) (xy 407.96591 -396.984982) (xy 407.98003 -396.965072) (xy 408.013448 -396.929502)
			(xy 408.052097 -396.899698) (xy 408.094994 -396.87642) (xy 408.141046 -396.860259) (xy 408.189082 -396.851628)
			(xy 408.23788 -396.850744) (xy 408.286197 -396.857632) (xy 408.332805 -396.872116) (xy 408.376515 -396.893826)
			(xy 408.416218 -396.922212) (xy 408.450901 -396.956549) (xy 408.479683 -396.995965) (xy 408.491182 -397.017494)
			(xy 408.49169 -397.018764) (xy 408.538426 -397.099536) (xy 408.543574 -397.107571) (xy 408.558449 -397.119495)
			(xy 408.576641 -397.125197) (xy 408.586178 -397.124936) (xy 408.691842 -397.117062) (xy 408.715464 -397.09979)
			(xy 408.720798 -397.086074) (xy 408.728231 -397.068549) (xy 408.749003 -397.036656) (xy 408.775662 -397.00949)
			(xy 408.807159 -396.988121) (xy 408.842255 -396.97339) (xy 408.879567 -396.965877) (xy 408.898598 -396.965424)
			(xy 408.899106 -396.965424) (xy 408.920584 -396.966003) (xy 408.962448 -396.975634) (xy 409.001118 -396.994344)
			(xy 409.018232 -397.007334) (xy 409.02636 -397.013938) (xy 409.046934 -397.019526) (xy 409.131516 -397.006826)
			(xy 409.14177 -397.00471) (xy 409.159471 -396.993571) (xy 409.165806 -396.985236) (xy 409.16606 -396.984982)
			(xy 409.180113 -396.965022) (xy 409.213538 -396.92945) (xy 409.252195 -396.899646) (xy 409.2951 -396.876368)
			(xy 409.34116 -396.86021) (xy 409.389204 -396.851581) (xy 409.438008 -396.850701) (xy 409.486332 -396.857594)
			(xy 409.532944 -396.872084) (xy 409.576659 -396.893801) (xy 409.616365 -396.922193) (xy 409.65105 -396.956538)
			(xy 409.679832 -396.995961) (xy 409.691332 -397.017494) (xy 409.69184 -397.018764) (xy 409.738322 -397.099282)
			(xy 409.743459 -397.107324) (xy 409.758341 -397.119243) (xy 409.776536 -397.124943) (xy 409.786074 -397.124682)
			(xy 409.877514 -397.117824) (xy 409.886901 -397.116719) (xy 409.903956 -397.108601) (xy 409.916952 -397.094896)
			(xy 409.920948 -397.086328) (xy 409.920948 -397.08582) (xy 409.928369 -397.068326) (xy 409.949126 -397.036499)
			(xy 409.975753 -397.009392) (xy 410.007205 -396.98807) (xy 410.042245 -396.973372) (xy 410.079495 -396.965876)
			(xy 410.098494 -396.965424) (xy 410.099002 -396.965424) (xy 410.12048 -396.966005) (xy 410.162344 -396.975635)
			(xy 410.201013 -396.994344) (xy 410.218128 -397.007334) (xy 410.226256 -397.013938) (xy 410.24683 -397.019526)
			(xy 410.331412 -397.006826) (xy 410.341665 -397.004708) (xy 410.359367 -396.993571) (xy 410.365702 -396.985236)
			(xy 410.365956 -396.984982) (xy 410.380014 -396.965026) (xy 410.413439 -396.929454) (xy 410.452096 -396.89965)
			(xy 410.494999 -396.876373) (xy 410.541059 -396.860214) (xy 410.589102 -396.851584) (xy 410.637906 -396.850705)
			(xy 410.686229 -396.857597) (xy 410.732841 -396.872086) (xy 410.776556 -396.893803) (xy 410.816261 -396.922194)
			(xy 410.850946 -396.956539) (xy 410.879728 -396.995962) (xy 410.891228 -397.017494) (xy 410.891736 -397.018764)
			(xy 410.938218 -397.099282) (xy 410.943291 -397.107372) (xy 410.958202 -397.119283) (xy 410.976424 -397.12496)
			(xy 410.98597 -397.124682) (xy 411.07741 -397.117824) (xy 411.086797 -397.116716) (xy 411.103851 -397.1086)
			(xy 411.116848 -397.094895) (xy 411.120844 -397.086328) (xy 411.120844 -397.08582) (xy 411.128268 -397.068327)
			(xy 411.149024 -397.0365) (xy 411.175651 -397.009393) (xy 411.207102 -396.988072) (xy 411.242141 -396.973373)
			(xy 411.279391 -396.965876) (xy 411.29839 -396.965424) (xy 411.316254 -396.965821) (xy 411.351356 -396.972477)
			(xy 411.384617 -396.985525) (xy 411.414883 -397.004511) (xy 411.441105 -397.028778) (xy 411.45206 -397.042894)
			(xy 411.458318 -397.050511) (xy 411.475111 -397.060788) (xy 411.494538 -397.063985) (xy 411.513739 -397.05963)
			(xy 411.529886 -397.048364) (xy 411.535626 -397.040354) (xy 411.539436 -397.032988) (xy 411.549342 -397.012668)
			(xy 411.560945 -396.991743) (xy 411.589745 -396.953534) (xy 411.624149 -396.920282) (xy 411.663315 -396.892797)
			(xy 411.706285 -396.871753) (xy 411.752011 -396.857663) (xy 411.799373 -396.850872) (xy 411.847216 -396.851545)
			(xy 411.894368 -396.859667) (xy 411.939679 -396.875038) (xy 411.98204 -396.897284) (xy 412.020417 -396.92586)
			(xy 412.053871 -396.960068) (xy 412.081585 -396.999071) (xy 412.092648 -397.020288) (xy 412.09341 -397.021812)
			(xy 412.138368 -397.099536) (xy 412.143488 -397.107592) (xy 412.158376 -397.119512) (xy 412.17658 -397.125205)
			(xy 412.18612 -397.124936) (xy 412.291784 -397.117062) (xy 412.315406 -397.09979) (xy 412.32074 -397.086074)
			(xy 412.328219 -397.068571) (xy 412.348984 -397.03668) (xy 412.375634 -397.009514) (xy 412.407121 -396.988142)
			(xy 412.442208 -396.973405) (xy 412.479512 -396.965882) (xy 412.49854 -396.965424) (xy 412.499048 -396.965424)
			(xy 412.520524 -396.966033) (xy 412.562387 -396.975651) (xy 412.601058 -396.994349) (xy 412.618174 -397.007334)
			(xy 412.626302 -397.013938) (xy 412.646876 -397.019526) (xy 412.731458 -397.006826) (xy 412.741717 -397.00473)
			(xy 412.759416 -396.993577) (xy 412.765748 -396.985236) (xy 412.766002 -396.984982) (xy 412.780133 -396.96508)
			(xy 412.813549 -396.92951) (xy 412.852197 -396.899706) (xy 412.895093 -396.876428) (xy 412.941144 -396.860267)
			(xy 412.989179 -396.851635) (xy 413.037976 -396.850751) (xy 413.086292 -396.857638) (xy 413.132898 -396.872121)
			(xy 413.176608 -396.893831) (xy 413.21631 -396.922215) (xy 413.250993 -396.956551) (xy 413.279775 -396.995966)
			(xy 413.291274 -397.017494) (xy 413.291782 -397.018764) (xy 413.338264 -397.099282) (xy 413.343373 -397.107345)
			(xy 413.358268 -397.11926) (xy 413.376474 -397.124951) (xy 413.386016 -397.124682) (xy 413.477456 -397.117824)
			(xy 413.486836 -397.11668) (xy 413.503891 -397.108581) (xy 413.516892 -397.09489) (xy 413.52089 -397.086328)
			(xy 413.52089 -397.08582) (xy 413.528357 -397.068347) (xy 413.549107 -397.036522) (xy 413.575725 -397.009415)
			(xy 413.607167 -396.988091) (xy 413.642198 -396.973387) (xy 413.67944 -396.965881) (xy 413.698436 -396.965424)
			(xy 413.698944 -396.965424) (xy 413.72042 -396.966035) (xy 413.762283 -396.975652) (xy 413.800954 -396.994349)
			(xy 413.81807 -397.007334) (xy 413.826198 -397.013938) (xy 413.846772 -397.019526) (xy 413.931354 -397.006826)
			(xy 413.941613 -397.004728) (xy 413.959312 -396.993576) (xy 413.965644 -396.985236) (xy 413.965898 -396.984982)
			(xy 413.980034 -396.965084) (xy 414.01345 -396.929514) (xy 414.052097 -396.899711) (xy 414.094992 -396.876432)
			(xy 414.141043 -396.860271) (xy 414.189077 -396.851639) (xy 414.237873 -396.850755) (xy 414.286189 -396.857641)
			(xy 414.332795 -396.872123) (xy 414.376505 -396.893833) (xy 414.416206 -396.922216) (xy 414.450889 -396.956552)
			(xy 414.479671 -396.995966) (xy 414.49117 -397.017494) (xy 414.491678 -397.018764) (xy 414.538414 -397.099536)
			(xy 414.543503 -397.107614) (xy 414.558405 -397.119532) (xy 414.576621 -397.125213) (xy 414.586166 -397.124936)
			(xy 414.69183 -397.117062) (xy 414.715452 -397.09979) (xy 414.720786 -397.086074) (xy 414.728228 -397.068554)
			(xy 414.748999 -397.036661) (xy 414.775656 -397.009495) (xy 414.807151 -396.988126) (xy 414.842245 -396.973393)
			(xy 414.879556 -396.965878) (xy 414.898586 -396.965424) (xy 414.899094 -396.965424) (xy 414.920572 -396.966009)
			(xy 414.962436 -396.975638) (xy 415.001105 -396.994345) (xy 415.01822 -397.007334) (xy 415.026348 -397.013938)
			(xy 415.046922 -397.019526) (xy 415.131504 -397.006826) (xy 415.141756 -397.004705) (xy 415.159459 -396.99357)
			(xy 415.165794 -396.985236) (xy 415.166048 -396.984982) (xy 415.180117 -396.965034) (xy 415.213541 -396.929462)
			(xy 415.252196 -396.899659) (xy 415.295098 -396.876381) (xy 415.341157 -396.860221) (xy 415.389199 -396.851592)
			(xy 415.438002 -396.850712) (xy 415.486323 -396.857603) (xy 415.532934 -396.872091) (xy 415.576649 -396.893807)
			(xy 415.616353 -396.922197) (xy 415.651038 -396.956541) (xy 415.67982 -396.995962) (xy 415.69132 -397.017494)
			(xy 415.691828 -397.018764) (xy 415.73831 -397.099282) (xy 415.743388 -397.107368) (xy 415.758297 -397.11928)
			(xy 415.776516 -397.124959) (xy 415.786062 -397.124682) (xy 415.877502 -397.117824) (xy 415.886888 -397.116711)
			(xy 415.903942 -397.108597) (xy 415.91694 -397.094895) (xy 415.920936 -397.086328) (xy 415.920936 -397.08582)
			(xy 415.928366 -397.06833) (xy 415.949122 -397.036504) (xy 415.975748 -397.009397) (xy 416.007197 -396.988075)
			(xy 416.042235 -396.973375) (xy 416.079484 -396.965877) (xy 416.098482 -396.965424) (xy 416.09899 -396.965424)
			(xy 416.120467 -396.966011) (xy 416.162331 -396.975639) (xy 416.201001 -396.994345) (xy 416.218116 -397.007334)
			(xy 416.226244 -397.013938) (xy 416.246818 -397.019526) (xy 416.3314 -397.006826) (xy 416.341652 -397.004703)
			(xy 416.359354 -396.993569) (xy 416.36569 -396.985236) (xy 416.365944 -396.984982) (xy 416.380018 -396.965038)
			(xy 416.413441 -396.929467) (xy 416.452096 -396.899663) (xy 416.494998 -396.876385) (xy 416.541056 -396.860225)
			(xy 416.589097 -396.851596) (xy 416.637899 -396.850715) (xy 416.686221 -396.857606) (xy 416.732831 -396.872094)
			(xy 416.776545 -396.893809) (xy 416.81625 -396.922199) (xy 416.850934 -396.956542) (xy 416.879716 -396.995963)
			(xy 416.891216 -397.017494) (xy 416.891724 -397.018764) (xy 416.938206 -397.099282) (xy 416.943287 -397.107366)
			(xy 416.958195 -397.119278) (xy 416.976413 -397.124958) (xy 416.985958 -397.124682) (xy 417.077398 -397.117824)
			(xy 417.086783 -397.116708) (xy 417.103838 -397.108596) (xy 417.116836 -397.094894) (xy 417.120832 -397.086328)
			(xy 417.120832 -397.08582) (xy 417.128266 -397.068332) (xy 417.14902 -397.036505) (xy 417.175646 -397.009398)
			(xy 417.207095 -396.988076) (xy 417.242132 -396.973376) (xy 417.27938 -396.965877) (xy 417.298378 -396.965424)
			(xy 417.316241 -396.965829) (xy 417.351343 -396.972484) (xy 417.384604 -396.985529) (xy 417.41487 -397.004513)
			(xy 417.441093 -397.028778) (xy 417.452048 -397.042894) (xy 417.458319 -397.050499) (xy 417.475108 -397.060777)
			(xy 417.494531 -397.063975) (xy 417.513729 -397.059624) (xy 417.529874 -397.048362) (xy 417.535614 -397.040354)
			(xy 417.539424 -397.032988) (xy 417.54933 -397.012668) (xy 417.560951 -396.991753) (xy 417.58975 -396.953546)
			(xy 417.624152 -396.920294) (xy 417.663315 -396.89281) (xy 417.706284 -396.871765) (xy 417.752008 -396.857675)
			(xy 417.799369 -396.850883) (xy 417.847209 -396.851556) (xy 417.89436 -396.859676) (xy 417.93967 -396.875046)
			(xy 417.98203 -396.89729) (xy 418.020406 -396.925864) (xy 418.053859 -396.96007) (xy 418.081573 -396.999072)
			(xy 418.092636 -397.020288) (xy 418.093398 -397.021812) (xy 418.138356 -397.099536) (xy 418.143484 -397.107586)
			(xy 418.158369 -397.119507) (xy 418.176569 -397.125203) (xy 418.186108 -397.124936) (xy 418.291772 -397.117062)
			(xy 418.315394 -397.09979) (xy 418.320728 -397.086074) (xy 418.328217 -397.068576) (xy 418.34898 -397.036685)
			(xy 418.375628 -397.009519) (xy 418.407114 -396.988146) (xy 418.442198 -396.973408) (xy 418.479501 -396.965883)
			(xy 418.498528 -396.965424) (xy 418.499036 -396.965424) (xy 418.520512 -396.966039) (xy 418.562375 -396.975655)
			(xy 418.601046 -396.99435) (xy 418.618162 -397.007334) (xy 418.62629 -397.013938) (xy 418.646864 -397.019526)
			(xy 418.731446 -397.006826) (xy 418.741704 -397.004724) (xy 418.759404 -396.993575) (xy 418.765736 -396.985236)
			(xy 418.76599 -396.984982) (xy 418.780002 -396.964992) (xy 418.813433 -396.929419) (xy 418.852094 -396.899615)
			(xy 418.895004 -396.876337) (xy 418.941069 -396.86018) (xy 418.989117 -396.851553) (xy 419.037925 -396.850676)
			(xy 419.086252 -396.857571) (xy 419.132868 -396.872064) (xy 419.176585 -396.893785) (xy 419.216293 -396.922182)
			(xy 419.250979 -396.956531) (xy 419.279762 -396.995959) (xy 419.291262 -397.017494) (xy 419.29177 -397.018764)
			(xy 419.338252 -397.099282) (xy 419.343369 -397.107339) (xy 419.358261 -397.119255) (xy 419.376464 -397.124948)
			(xy 419.386004 -397.124682) (xy 419.477444 -397.117824) (xy 419.486823 -397.116672) (xy 419.503878 -397.108577)
			(xy 419.516879 -397.094889) (xy 419.520878 -397.086328) (xy 419.520878 -397.08582) (xy 419.528355 -397.068352)
			(xy 419.549103 -397.036527) (xy 419.575719 -397.00942) (xy 419.60716 -396.988095) (xy 419.642188 -396.97339)
			(xy 419.679429 -396.965882) (xy 419.698424 -396.965424) (xy 419.716285 -396.965867) (xy 419.751386 -396.972512)
			(xy 419.784646 -396.985549) (xy 419.814913 -397.004524) (xy 419.841138 -397.028782) (xy 419.852094 -397.042894)
			(xy 419.858313 -397.050546) (xy 419.875119 -397.060823) (xy 419.894558 -397.064013) (xy 419.913768 -397.059649)
			(xy 419.92992 -397.048371) (xy 419.93566 -397.040354) (xy 419.93947 -397.032988) (xy 419.949376 -397.012668)
			(xy 419.961078 -396.991801) (xy 419.989869 -396.953597) (xy 420.024263 -396.920347) (xy 420.063418 -396.892864)
			(xy 420.106379 -396.871819) (xy 420.152094 -396.857728) (xy 420.199447 -396.850933) (xy 420.24728 -396.851601)
			(xy 420.294425 -396.859717) (xy 420.339728 -396.875081) (xy 420.382084 -396.897318) (xy 420.420456 -396.925885)
			(xy 420.453907 -396.960083) (xy 420.481619 -396.999076) (xy 420.492682 -397.020288) (xy 420.493444 -397.021812)
			(xy 420.538402 -397.099536) (xy 420.543499 -397.107608) (xy 420.558398 -397.119527) (xy 420.57661 -397.125211)
			(xy 420.586154 -397.124936) (xy 420.691818 -397.117062) (xy 420.71544 -397.09979) (xy 420.720774 -397.086074)
			(xy 420.728226 -397.068558) (xy 420.748995 -397.036666) (xy 420.77565 -397.0095) (xy 420.807144 -396.98813)
			(xy 420.842235 -396.973396) (xy 420.879545 -396.965879) (xy 420.898574 -396.965424) (xy 420.899082 -396.965424)
			(xy 420.920559 -396.966016) (xy 420.962423 -396.975641) (xy 421.001093 -396.994346) (xy 421.018208 -397.007334)
			(xy 421.026336 -397.013938) (xy 421.04691 -397.019526) (xy 421.131492 -397.006826) (xy 421.141743 -397.004699)
			(xy 421.159446 -396.993568) (xy 421.165782 -396.985236) (xy 421.166036 -396.984982) (xy 421.180121 -396.965046)
			(xy 421.213543 -396.929475) (xy 421.252196 -396.899671) (xy 421.295097 -396.876393) (xy 421.341153 -396.860233)
			(xy 421.389194 -396.851603) (xy 421.437995 -396.850722) (xy 421.486315 -396.857612) (xy 421.532925 -396.872099)
			(xy 421.576638 -396.893813) (xy 421.616342 -396.922202) (xy 421.651026 -396.956543) (xy 421.679808 -396.995963)
			(xy 421.691308 -397.017494) (xy 421.691816 -397.018764) (xy 422.083738 -397.696944) (xy 422.083992 -397.697452)
			(xy 422.084246 -397.697452) (xy 422.085516 -397.699992) (xy 422.097788 -397.722907) (xy 422.115194 -397.771885)
			(xy 422.124068 -397.823101) (xy 422.124632 -397.84909) (xy 422.124632 -397.849344) (xy 422.124179 -397.873323)
			(xy 422.116675 -397.920689) (xy 422.101859 -397.9663) (xy 422.080094 -398.009034) (xy 422.051916 -398.04784)
			(xy 422.018018 -398.081764) (xy 421.979234 -398.109971) (xy 421.936517 -398.131769) (xy 421.890917 -398.14662)
			(xy 421.843556 -398.154161) (xy 421.819578 -398.154652) (xy 421.81907 -398.154652) (xy 421.795408 -398.154156)
			(xy 421.748649 -398.146856) (xy 421.703575 -398.132435) (xy 421.661263 -398.111238) (xy 421.622724 -398.083772)
			(xy 421.58888 -398.050693) (xy 421.560539 -398.012793) (xy 421.549068 -397.992092) (xy 421.548814 -397.99133)
			(xy 421.53586 -397.968978) (xy 421.53042 -397.960576) (xy 421.514553 -397.948414) (xy 421.495239 -397.943246)
			(xy 421.475418 -397.945859) (xy 421.466518 -397.950436) (xy 421.457374 -397.95577) (xy 421.451278 -397.964152)
			(xy 421.440345 -397.978046) (xy 421.414262 -398.001909) (xy 421.384237 -398.02057) (xy 421.351293 -398.033394)
			(xy 421.316553 -398.039943) (xy 421.298878 -398.040352) (xy 421.29837 -398.040352) (xy 421.279592 -398.039931)
			(xy 421.242757 -398.032604) (xy 421.208056 -398.018239) (xy 421.176821 -397.997386) (xy 421.15025 -397.970844)
			(xy 421.129362 -397.939633) (xy 421.114958 -397.904948) (xy 421.107591 -397.868122) (xy 421.107108 -397.849344)
			(xy 421.107546 -397.830228) (xy 421.115116 -397.792755) (xy 421.129983 -397.757534) (xy 421.151553 -397.72597)
			(xy 421.178966 -397.699322) (xy 421.211128 -397.678654) (xy 421.228774 -397.67129) (xy 421.238934 -397.667226)
			(xy 421.254428 -397.651478) (xy 421.283638 -397.568166) (xy 421.286831 -397.55758) (xy 421.284874 -397.535584)
			(xy 421.279828 -397.525748) (xy 421.151558 -397.304006) (xy 421.13962 -397.279876) (xy 421.134766 -397.270371)
			(xy 421.118989 -397.256043) (xy 421.098755 -397.249353) (xy 421.077547 -397.251452) (xy 421.059017 -397.261979)
			(xy 421.052244 -397.270224) (xy 421.041311 -397.28428) (xy 421.015171 -397.308454) (xy 420.985007 -397.32737)
			(xy 420.951863 -397.340375) (xy 420.916884 -397.347019) (xy 420.899082 -397.34744) (xy 420.898574 -397.34744)
			(xy 420.870888 -397.345408) (xy 420.870634 -397.345408) (xy 420.861167 -397.344402) (xy 420.842644 -397.348755)
			(xy 420.826993 -397.359576) (xy 420.821358 -397.367252) (xy 420.769796 -397.442944) (xy 420.764771 -397.451077)
			(xy 420.760603 -397.469721) (xy 420.763542 -397.488598) (xy 420.768018 -397.497046) (xy 420.865808 -397.665956)
			(xy 420.865808 -397.666464) (xy 420.88562 -397.699992) (xy 420.897893 -397.722907) (xy 420.915298 -397.771885)
			(xy 420.924172 -397.823101) (xy 420.924736 -397.84909) (xy 420.924736 -397.849344) (xy 420.924302 -397.87335)
			(xy 420.916781 -397.920768) (xy 420.901933 -397.966426) (xy 420.880122 -398.009197) (xy 420.851887 -398.048029)
			(xy 420.817923 -398.081963) (xy 420.779067 -398.110164) (xy 420.736276 -398.131936) (xy 420.690605 -398.146744)
			(xy 420.64318 -398.154223) (xy 420.619174 -398.154652) (xy 420.61892 -398.154652) (xy 420.595348 -398.154215)
			(xy 420.548763 -398.146978) (xy 420.503847 -398.132658) (xy 420.46167 -398.111595) (xy 420.423236 -398.084293)
			(xy 420.389462 -398.051402) (xy 420.361153 -398.013704) (xy 420.34968 -397.993108) (xy 420.349172 -397.992346)
			(xy 420.33571 -397.968978) (xy 420.330321 -397.960539) (xy 420.314435 -397.948377) (xy 420.295104 -397.943219)
			(xy 420.275271 -397.945849) (xy 420.266368 -397.950436) (xy 420.257224 -397.95577) (xy 420.251128 -397.964152)
			(xy 420.240223 -397.97807) (xy 420.214133 -398.001931) (xy 420.184101 -398.020588) (xy 420.151151 -398.033406)
			(xy 420.116405 -398.039948) (xy 420.098728 -398.040352) (xy 420.09822 -398.040352) (xy 420.079456 -398.03983)
			(xy 420.042648 -398.032513) (xy 420.007975 -398.018157) (xy 419.976769 -397.997312) (xy 419.950228 -397.970781)
			(xy 419.929373 -397.939581) (xy 419.915005 -397.904913) (xy 419.907676 -397.868108) (xy 419.907212 -397.849344)
			(xy 419.907722 -397.830251) (xy 419.915281 -397.792822) (xy 419.930107 -397.757633) (xy 419.951613 -397.72608)
			(xy 419.978945 -397.699414) (xy 420.01102 -397.678695) (xy 420.028624 -397.67129) (xy 420.038784 -397.667226)
			(xy 420.054278 -397.651478) (xy 420.083488 -397.568166) (xy 420.086687 -397.557581) (xy 420.084728 -397.535584)
			(xy 420.079678 -397.525748) (xy 419.951408 -397.304006) (xy 419.93947 -397.279876) (xy 419.934686 -397.27033)
			(xy 419.91889 -397.255996) (xy 419.898634 -397.24931) (xy 419.877409 -397.251422) (xy 419.858868 -397.261968)
			(xy 419.852094 -397.270224) (xy 419.841173 -397.284322) (xy 419.814982 -397.308522) (xy 419.784758 -397.327445)
			(xy 419.751549 -397.340437) (xy 419.716508 -397.347045) (xy 419.698678 -397.34744) (xy 419.69817 -397.34744)
			(xy 419.69129 -397.347442) (xy 419.67756 -397.346549) (xy 419.670738 -397.345662) (xy 419.65626 -397.343376)
			(xy 419.62959 -397.35506) (xy 419.5699 -397.442944) (xy 419.564874 -397.451077) (xy 419.560706 -397.469721)
			(xy 419.563646 -397.488598) (xy 419.568122 -397.497046) (xy 419.683692 -397.696944) (xy 419.683946 -397.697452)
			(xy 419.6842 -397.697452) (xy 419.68547 -397.699992) (xy 419.697699 -397.722918) (xy 419.715022 -397.771903)
			(xy 419.72381 -397.823111) (xy 419.724332 -397.84909) (xy 419.724332 -397.849344) (xy 419.723878 -397.873335)
			(xy 419.716366 -397.920726) (xy 419.701534 -397.966359) (xy 419.679747 -398.00911) (xy 419.651542 -398.047927)
			(xy 419.617612 -398.081855) (xy 419.578793 -398.110058) (xy 419.53604 -398.131842) (xy 419.490407 -398.146671)
			(xy 419.443015 -398.15418) (xy 419.419024 -398.154652) (xy 419.39536 -398.154193) (xy 419.3486 -398.146886)
			(xy 419.303525 -398.132459) (xy 419.261213 -398.111256) (xy 419.222674 -398.083784) (xy 419.188831 -398.0507)
			(xy 419.160493 -398.012795) (xy 419.149022 -397.992092) (xy 419.148768 -397.99133) (xy 419.135814 -397.968978)
			(xy 419.130421 -397.960542) (xy 419.114536 -397.94838) (xy 419.095207 -397.943221) (xy 419.075375 -397.94585)
			(xy 419.066472 -397.950436) (xy 419.057328 -397.95577) (xy 419.051232 -397.964152) (xy 419.040325 -397.978068)
			(xy 419.014235 -398.001929) (xy 418.984204 -398.020587) (xy 418.951254 -398.033405) (xy 418.916509 -398.039947)
			(xy 418.898832 -398.040352) (xy 418.898324 -398.040352) (xy 418.87956 -398.039827) (xy 418.842753 -398.03251)
			(xy 418.80808 -398.018155) (xy 418.776873 -397.997311) (xy 418.750333 -397.970779) (xy 418.729478 -397.93958)
			(xy 418.715109 -397.904912) (xy 418.70778 -397.868108) (xy 418.707316 -397.849344) (xy 418.707824 -397.830251)
			(xy 418.715383 -397.792822) (xy 418.730209 -397.757632) (xy 418.751715 -397.726079) (xy 418.779048 -397.699414)
			(xy 418.811124 -397.678694) (xy 418.828728 -397.67129) (xy 418.838888 -397.667226) (xy 418.854382 -397.651478)
			(xy 418.883592 -397.568166) (xy 418.88679 -397.557581) (xy 418.884832 -397.535584) (xy 418.879782 -397.525748)
			(xy 418.751512 -397.304006) (xy 418.739574 -397.279876) (xy 418.734785 -397.270333) (xy 418.71899 -397.256)
			(xy 418.698736 -397.249313) (xy 418.677512 -397.251424) (xy 418.658972 -397.261969) (xy 418.652198 -397.270224)
			(xy 418.641291 -397.284301) (xy 418.615145 -397.308474) (xy 418.584975 -397.327387) (xy 418.551824 -397.340386)
			(xy 418.51684 -397.347023) (xy 418.499036 -397.34744) (xy 418.498528 -397.34744) (xy 418.470842 -397.345408)
			(xy 418.470588 -397.345408) (xy 418.461119 -397.344445) (xy 418.442601 -397.348779) (xy 418.426949 -397.359584)
			(xy 418.421312 -397.367252) (xy 418.36975 -397.442944) (xy 418.364722 -397.451076) (xy 418.36055 -397.469721)
			(xy 418.363493 -397.488599) (xy 418.367972 -397.497046) (xy 418.465762 -397.665956) (xy 418.465762 -397.666464)
			(xy 418.485574 -397.699992) (xy 418.497804 -397.722918) (xy 418.515126 -397.771903) (xy 418.523914 -397.823111)
			(xy 418.524436 -397.84909) (xy 418.524436 -397.849344) (xy 418.523978 -397.873335) (xy 418.516466 -397.920726)
			(xy 418.501635 -397.966358) (xy 418.479848 -398.009109) (xy 418.451643 -398.047926) (xy 418.417713 -398.081853)
			(xy 418.378895 -398.110056) (xy 418.336143 -398.131841) (xy 418.29051 -398.14667) (xy 418.243119 -398.154179)
			(xy 418.219128 -398.154652) (xy 418.218874 -398.154652) (xy 418.195301 -398.154252) (xy 418.148714 -398.147008)
			(xy 418.103797 -398.132681) (xy 418.06162 -398.111613) (xy 418.023187 -398.084305) (xy 417.989414 -398.051408)
			(xy 417.961106 -398.013706) (xy 417.949634 -397.993108) (xy 417.949126 -397.992346) (xy 417.935664 -397.968978)
			(xy 417.93022 -397.96058) (xy 417.914354 -397.948418) (xy 417.895042 -397.943249) (xy 417.875222 -397.945861)
			(xy 417.866322 -397.950436) (xy 417.857178 -397.95577) (xy 417.851082 -397.964152) (xy 417.840146 -397.978044)
			(xy 417.814064 -398.001907) (xy 417.78404 -398.020569) (xy 417.751096 -398.033393) (xy 417.716357 -398.039943)
			(xy 417.698682 -398.040352) (xy 417.698174 -398.040352) (xy 417.679396 -398.039927) (xy 417.642561 -398.032602)
			(xy 417.607861 -398.018237) (xy 417.576626 -397.997384) (xy 417.550054 -397.970843) (xy 417.529166 -397.939632)
			(xy 417.514762 -397.904948) (xy 417.507395 -397.868121) (xy 417.506912 -397.849344) (xy 417.507348 -397.830228)
			(xy 417.514918 -397.792755) (xy 417.529785 -397.757533) (xy 417.551355 -397.725969) (xy 417.578769 -397.699321)
			(xy 417.610932 -397.678654) (xy 417.628578 -397.67129) (xy 417.638738 -397.667226) (xy 417.654232 -397.651478)
			(xy 417.683442 -397.568166) (xy 417.686635 -397.55758) (xy 417.684678 -397.535585) (xy 417.679632 -397.525748)
			(xy 417.551362 -397.304006) (xy 417.539424 -397.279876) (xy 417.534564 -397.270374) (xy 417.518789 -397.256047)
			(xy 417.498557 -397.249356) (xy 417.47735 -397.251455) (xy 417.458821 -397.26198) (xy 417.452048 -397.270224)
			(xy 417.441096 -397.284296) (xy 417.414913 -397.308498) (xy 417.384697 -397.327426) (xy 417.351495 -397.340423)
			(xy 417.316459 -397.34704) (xy 417.298632 -397.34744) (xy 417.298124 -397.34744) (xy 417.291244 -397.347436)
			(xy 417.277514 -397.346547) (xy 417.270692 -397.345662) (xy 417.256214 -397.343376) (xy 417.229544 -397.35506)
			(xy 417.169854 -397.442944) (xy 417.164831 -397.451077) (xy 417.160667 -397.469721) (xy 417.163604 -397.488597)
			(xy 417.168076 -397.497046) (xy 417.283646 -397.696944) (xy 417.2839 -397.697452) (xy 417.284154 -397.697452)
			(xy 417.285424 -397.699992) (xy 417.297697 -397.722907) (xy 417.315102 -397.771885) (xy 417.323976 -397.823101)
			(xy 417.32454 -397.84909) (xy 417.32454 -397.849344) (xy 417.324079 -397.873322) (xy 417.316575 -397.920688)
			(xy 417.301759 -397.966298) (xy 417.279995 -398.009032) (xy 417.251818 -398.047837) (xy 417.217922 -398.081761)
			(xy 417.179138 -398.109969) (xy 417.136422 -398.131767) (xy 417.090824 -398.146619) (xy 417.043464 -398.15416)
			(xy 417.019486 -398.154652) (xy 417.018978 -398.154652) (xy 416.995313 -398.15423) (xy 416.948551 -398.146916)
			(xy 416.903475 -398.132482) (xy 416.861163 -398.111273) (xy 416.822625 -398.083796) (xy 416.788783 -398.050707)
			(xy 416.760446 -398.012797) (xy 416.748976 -397.992092) (xy 416.748722 -397.99133) (xy 416.735768 -397.968978)
			(xy 416.73032 -397.960583) (xy 416.714455 -397.94842) (xy 416.695145 -397.943251) (xy 416.675326 -397.945861)
			(xy 416.666426 -397.950436) (xy 416.657282 -397.95577) (xy 416.651186 -397.964152) (xy 416.640248 -397.978042)
			(xy 416.614167 -398.001905) (xy 416.584143 -398.020567) (xy 416.5512 -398.033392) (xy 416.516461 -398.039943)
			(xy 416.498786 -398.040352) (xy 416.498278 -398.040352) (xy 416.4795 -398.039923) (xy 416.442665 -398.032599)
			(xy 416.407965 -398.018235) (xy 416.37673 -397.997383) (xy 416.350159 -397.970842) (xy 416.32927 -397.939631)
			(xy 416.314866 -397.904947) (xy 416.307499 -397.868121) (xy 416.307016 -397.849344) (xy 416.30745 -397.830228)
			(xy 416.31502 -397.792754) (xy 416.329887 -397.757533) (xy 416.351458 -397.725968) (xy 416.378873 -397.699321)
			(xy 416.411036 -397.678654) (xy 416.428682 -397.67129) (xy 416.438842 -397.667226) (xy 416.454336 -397.651478)
			(xy 416.483546 -397.568166) (xy 416.486739 -397.55758) (xy 416.484782 -397.535584) (xy 416.479736 -397.525748)
			(xy 416.351466 -397.304006) (xy 416.339528 -397.279876) (xy 416.334662 -397.270377) (xy 416.318889 -397.256051)
			(xy 416.298658 -397.24936) (xy 416.277453 -397.251457) (xy 416.258925 -397.261981) (xy 416.252152 -397.270224)
			(xy 416.241197 -397.284295) (xy 416.215015 -397.308496) (xy 416.184799 -397.327425) (xy 416.151598 -397.340422)
			(xy 416.116563 -397.347039) (xy 416.098736 -397.34744) (xy 416.098228 -397.34744) (xy 416.091348 -397.347435)
			(xy 416.077618 -397.346546) (xy 416.070796 -397.345662) (xy 416.056318 -397.343376) (xy 416.029648 -397.35506)
			(xy 415.969958 -397.442944) (xy 415.964935 -397.451077) (xy 415.96077 -397.469721) (xy 415.963707 -397.488597)
			(xy 415.96818 -397.497046) (xy 416.08375 -397.696944) (xy 416.084004 -397.697452) (xy 416.084258 -397.697452)
			(xy 416.085528 -397.699992) (xy 416.097801 -397.722907) (xy 416.115206 -397.771885) (xy 416.12408 -397.823101)
			(xy 416.124644 -397.84909) (xy 416.124644 -397.849344) (xy 416.124179 -397.873322) (xy 416.116676 -397.920687)
			(xy 416.10186 -397.966297) (xy 416.080096 -398.00903) (xy 416.05192 -398.047836) (xy 416.018023 -398.08176)
			(xy 415.97924 -398.109967) (xy 415.936525 -398.131765) (xy 415.890927 -398.146618) (xy 415.843568 -398.15416)
			(xy 415.81959 -398.154652) (xy 415.819082 -398.154652) (xy 415.795417 -398.154227) (xy 415.748655 -398.146914)
			(xy 415.70358 -398.13248) (xy 415.661267 -398.111272) (xy 415.622729 -398.083795) (xy 415.588887 -398.050706)
			(xy 415.56055 -398.012797) (xy 415.54908 -397.992092) (xy 415.548826 -397.99133) (xy 415.535872 -397.968978)
			(xy 415.53042 -397.960586) (xy 415.514557 -397.948423) (xy 415.495248 -397.943254) (xy 415.47543 -397.945862)
			(xy 415.46653 -397.950436) (xy 415.457386 -397.95577) (xy 415.45129 -397.964152) (xy 415.44035 -397.97804)
			(xy 415.414269 -398.001904) (xy 415.384246 -398.020566) (xy 415.351303 -398.033391) (xy 415.316565 -398.039942)
			(xy 415.29889 -398.040352) (xy 415.298382 -398.040352) (xy 415.279604 -398.03992) (xy 415.24277 -398.032596)
			(xy 415.208069 -398.018233) (xy 415.176834 -397.997381) (xy 415.150263 -397.970841) (xy 415.129374 -397.93963)
			(xy 415.11497 -397.904947) (xy 415.107603 -397.868121) (xy 415.10712 -397.849344) (xy 415.107551 -397.830228)
			(xy 415.115122 -397.792754) (xy 415.129989 -397.757532) (xy 415.151561 -397.725968) (xy 415.178976 -397.699321)
			(xy 415.21114 -397.678654) (xy 415.228786 -397.67129) (xy 415.238946 -397.667226) (xy 415.25444 -397.651478)
			(xy 415.28365 -397.568166) (xy 415.286842 -397.55758) (xy 415.284886 -397.535585) (xy 415.27984 -397.525748)
			(xy 415.15157 -397.304006) (xy 415.139632 -397.279876) (xy 415.134761 -397.270381) (xy 415.118989 -397.256054)
			(xy 415.09876 -397.249363) (xy 415.077556 -397.251459) (xy 415.059029 -397.261982) (xy 415.052256 -397.270224)
			(xy 415.041316 -397.284274) (xy 415.015178 -397.308448) (xy 414.985016 -397.327366) (xy 414.951873 -397.340372)
			(xy 414.916895 -397.347018) (xy 414.899094 -397.34744) (xy 414.898586 -397.34744) (xy 414.8709 -397.345408)
			(xy 414.870646 -397.345408) (xy 414.861178 -397.344412) (xy 414.842656 -397.34876) (xy 414.827006 -397.359578)
			(xy 414.82137 -397.367252) (xy 414.769808 -397.442944) (xy 414.764782 -397.451077) (xy 414.760613 -397.469721)
			(xy 414.763554 -397.488598) (xy 414.76803 -397.497046) (xy 414.8836 -397.696944) (xy 414.883854 -397.697452)
			(xy 414.884108 -397.697452) (xy 414.885378 -397.699992) (xy 414.897608 -397.722918) (xy 414.91493 -397.771903)
			(xy 414.923718 -397.823111) (xy 414.92424 -397.84909) (xy 414.92424 -397.849344) (xy 414.923778 -397.873335)
			(xy 414.916266 -397.920725) (xy 414.901435 -397.966357) (xy 414.879649 -398.009107) (xy 414.851444 -398.047924)
			(xy 414.817515 -398.081852) (xy 414.778697 -398.110055) (xy 414.735946 -398.13184) (xy 414.690313 -398.146669)
			(xy 414.642923 -398.154179) (xy 414.618932 -398.154652) (xy 414.595269 -398.154187) (xy 414.548509 -398.146881)
			(xy 414.503434 -398.132455) (xy 414.461121 -398.111253) (xy 414.422583 -398.083782) (xy 414.38874 -398.050699)
			(xy 414.360401 -398.012794) (xy 414.34893 -397.992092) (xy 414.348676 -397.99133) (xy 414.335722 -397.968978)
			(xy 414.330321 -397.960548) (xy 414.314439 -397.948386) (xy 414.295113 -397.943226) (xy 414.275282 -397.945851)
			(xy 414.26638 -397.950436) (xy 414.257236 -397.95577) (xy 414.25114 -397.964152) (xy 414.240228 -397.978064)
			(xy 414.21414 -398.001925) (xy 414.18411 -398.020584) (xy 414.151161 -398.033403) (xy 414.116417 -398.039947)
			(xy 414.09874 -398.040352) (xy 414.098232 -398.040352) (xy 414.079468 -398.039819) (xy 414.042661 -398.032505)
			(xy 414.007988 -398.01815) (xy 413.976782 -397.997307) (xy 413.950241 -397.970777) (xy 413.929386 -397.939579)
			(xy 413.915017 -397.904912) (xy 413.907688 -397.868107) (xy 413.907224 -397.849344) (xy 413.907727 -397.830251)
			(xy 413.915286 -397.792821) (xy 413.930113 -397.757631) (xy 413.951621 -397.726078) (xy 413.978955 -397.699413)
			(xy 414.011031 -397.678694) (xy 414.028636 -397.67129) (xy 414.038796 -397.667226) (xy 414.05429 -397.651478)
			(xy 414.0835 -397.568166) (xy 414.086698 -397.55758) (xy 414.084739 -397.535584) (xy 414.07969 -397.525748)
			(xy 413.95142 -397.304006) (xy 413.939482 -397.279876) (xy 413.934681 -397.27034) (xy 413.918889 -397.256008)
			(xy 413.898639 -397.249321) (xy 413.877418 -397.251429) (xy 413.85888 -397.261971) (xy 413.852106 -397.270224)
			(xy 413.841178 -397.284316) (xy 413.814989 -397.308517) (xy 413.784767 -397.327441) (xy 413.751559 -397.340434)
			(xy 413.716519 -397.347044) (xy 413.69869 -397.34744) (xy 413.698182 -397.34744) (xy 413.691302 -397.34744)
			(xy 413.677572 -397.346548) (xy 413.67075 -397.345662) (xy 413.656272 -397.343376) (xy 413.629602 -397.35506)
			(xy 413.569912 -397.442944) (xy 413.564886 -397.451077) (xy 413.560717 -397.469721) (xy 413.563658 -397.488598)
			(xy 413.568134 -397.497046) (xy 413.683704 -397.696944) (xy 413.683958 -397.697452) (xy 413.684212 -397.697452)
			(xy 413.685482 -397.699992) (xy 413.697712 -397.722918) (xy 413.715034 -397.771903) (xy 413.723822 -397.823111)
			(xy 413.724344 -397.84909) (xy 413.724344 -397.849344) (xy 413.723878 -397.873335) (xy 413.716367 -397.920724)
			(xy 413.701535 -397.966356) (xy 413.679749 -398.009106) (xy 413.651545 -398.047923) (xy 413.617617 -398.08185)
			(xy 413.578799 -398.110054) (xy 413.536049 -398.131838) (xy 413.490417 -398.146668) (xy 413.443027 -398.154179)
			(xy 413.419036 -398.154652) (xy 413.395373 -398.154184) (xy 413.348613 -398.146878) (xy 413.303538 -398.132453)
			(xy 413.261226 -398.111251) (xy 413.222687 -398.083781) (xy 413.188844 -398.050698) (xy 413.160505 -398.012794)
			(xy 413.149034 -397.992092) (xy 413.14878 -397.99133) (xy 413.135826 -397.968978) (xy 413.130421 -397.960551)
			(xy 413.11454 -397.948389) (xy 413.095216 -397.943228) (xy 413.075386 -397.945852) (xy 413.066484 -397.950436)
			(xy 413.05734 -397.95577) (xy 413.051244 -397.964152) (xy 413.04033 -397.978062) (xy 413.014242 -398.001924)
			(xy 412.984212 -398.020582) (xy 412.951264 -398.033402) (xy 412.916521 -398.039946) (xy 412.898844 -398.040352)
			(xy 412.898336 -398.040352) (xy 412.879573 -398.039816) (xy 412.842766 -398.032502) (xy 412.808093 -398.018148)
			(xy 412.776886 -397.997306) (xy 412.750345 -397.970776) (xy 412.72949 -397.939578) (xy 412.715121 -397.904911)
			(xy 412.707792 -397.868107) (xy 412.707328 -397.849344) (xy 412.707828 -397.830251) (xy 412.715388 -397.79282)
			(xy 412.730215 -397.75763) (xy 412.751723 -397.726077) (xy 412.779058 -397.699412) (xy 412.811135 -397.678693)
			(xy 412.82874 -397.67129) (xy 412.8389 -397.667226) (xy 412.854394 -397.651478) (xy 412.883604 -397.568166)
			(xy 412.886801 -397.55758) (xy 412.884843 -397.535584) (xy 412.879794 -397.525748) (xy 412.751524 -397.304006)
			(xy 412.739586 -397.279876) (xy 412.734779 -397.270343) (xy 412.718989 -397.256012) (xy 412.698741 -397.249324)
			(xy 412.677521 -397.251432) (xy 412.658984 -397.261972) (xy 412.65221 -397.270224) (xy 412.641297 -397.284296)
			(xy 412.615152 -397.308469) (xy 412.584983 -397.327382) (xy 412.551834 -397.340383) (xy 412.516851 -397.347022)
			(xy 412.499048 -397.34744) (xy 412.49854 -397.34744) (xy 412.470854 -397.345408) (xy 412.4706 -397.345408)
			(xy 412.46113 -397.344455) (xy 412.442613 -397.348784) (xy 412.426962 -397.359585) (xy 412.421324 -397.367252)
			(xy 412.369762 -397.442944) (xy 412.364738 -397.451077) (xy 412.360573 -397.469721) (xy 412.363511 -397.488597)
			(xy 412.367984 -397.497046) (xy 412.465774 -397.665956) (xy 412.465774 -397.666464) (xy 412.485586 -397.699992)
			(xy 412.497817 -397.722917) (xy 412.515138 -397.771902) (xy 412.523926 -397.823111) (xy 412.524448 -397.84909)
			(xy 412.524448 -397.849344) (xy 412.523978 -397.873334) (xy 412.516467 -397.920724) (xy 412.501636 -397.966355)
			(xy 412.47985 -398.009105) (xy 412.451646 -398.047922) (xy 412.417718 -398.081849) (xy 412.378902 -398.110052)
			(xy 412.336151 -398.131837) (xy 412.29052 -398.146668) (xy 412.24313 -398.154178) (xy 412.21914 -398.154652)
			(xy 412.218886 -398.154652) (xy 412.195313 -398.154242) (xy 412.148727 -398.147) (xy 412.10381 -398.132675)
			(xy 412.061633 -398.111608) (xy 412.0232 -398.084302) (xy 411.989427 -398.051406) (xy 411.961119 -398.013705)
			(xy 411.949646 -397.993108) (xy 411.949138 -397.992346) (xy 411.935676 -397.968978) (xy 411.93022 -397.960589)
			(xy 411.914358 -397.948426) (xy 411.895051 -397.943256) (xy 411.875234 -397.945863) (xy 411.866334 -397.950436)
			(xy 411.85719 -397.95577) (xy 411.851094 -397.964152) (xy 411.840152 -397.978039) (xy 411.814071 -398.001902)
			(xy 411.784048 -398.020564) (xy 411.751107 -398.03339) (xy 411.716369 -398.039942) (xy 411.698694 -398.040352)
			(xy 411.698186 -398.040352) (xy 411.679408 -398.039916) (xy 411.642574 -398.032593) (xy 411.607874 -398.01823)
			(xy 411.576639 -397.997379) (xy 411.550067 -397.97084) (xy 411.529178 -397.93963) (xy 411.514774 -397.904947)
			(xy 411.507407 -397.868121) (xy 411.506924 -397.849344) (xy 411.507353 -397.830228) (xy 411.514923 -397.792753)
			(xy 411.529791 -397.757531) (xy 411.551363 -397.725967) (xy 411.578779 -397.69932) (xy 411.610943 -397.678654)
			(xy 411.62859 -397.67129) (xy 411.63875 -397.667226) (xy 411.654244 -397.651478) (xy 411.683454 -397.568166)
			(xy 411.686646 -397.55758) (xy 411.684689 -397.535585) (xy 411.679644 -397.525748) (xy 411.551374 -397.304006)
			(xy 411.539436 -397.279876) (xy 411.534559 -397.270384) (xy 411.518789 -397.256059) (xy 411.498562 -397.249367)
			(xy 411.477359 -397.251462) (xy 411.458833 -397.261983) (xy 411.45206 -397.270224) (xy 411.441101 -397.284291)
			(xy 411.414919 -397.308493) (xy 411.384705 -397.327422) (xy 411.351505 -397.34042) (xy 411.316471 -397.347039)
			(xy 411.298644 -397.34744) (xy 411.298136 -397.34744) (xy 411.291256 -397.347434) (xy 411.277527 -397.346546)
			(xy 411.270704 -397.345662) (xy 411.256226 -397.343376) (xy 411.229556 -397.35506) (xy 411.169866 -397.442944)
			(xy 411.164842 -397.451077) (xy 411.160677 -397.469721) (xy 411.163615 -397.488597) (xy 411.168088 -397.497046)
			(xy 411.283658 -397.696944) (xy 411.283912 -397.697452) (xy 411.284166 -397.697452) (xy 411.285436 -397.699992)
			(xy 411.29771 -397.722906) (xy 411.315115 -397.771885) (xy 411.323988 -397.823101) (xy 411.324552 -397.84909)
			(xy 411.324552 -397.849344) (xy 411.324079 -397.873322) (xy 411.316576 -397.920686) (xy 411.301761 -397.966295)
			(xy 411.279998 -398.009028) (xy 411.251822 -398.047833) (xy 411.217927 -398.081757) (xy 411.179145 -398.109965)
			(xy 411.13643 -398.131763) (xy 411.090833 -398.146616) (xy 411.043475 -398.154159) (xy 411.019498 -398.154652)
			(xy 411.01899 -398.154652) (xy 410.995325 -398.154221) (xy 410.948564 -398.146909) (xy 410.903488 -398.132476)
			(xy 410.861176 -398.111269) (xy 410.822638 -398.083793) (xy 410.788796 -398.050705) (xy 410.760458 -398.012796)
			(xy 410.748988 -397.992092) (xy 410.748734 -397.99133) (xy 410.73578 -397.968978) (xy 410.73032 -397.960592)
			(xy 410.714459 -397.948429) (xy 410.695153 -397.943258) (xy 410.675337 -397.945864) (xy 410.666438 -397.950436)
			(xy 410.657294 -397.95577) (xy 410.651198 -397.964152) (xy 410.640253 -397.978037) (xy 410.614173 -398.0019)
			(xy 410.584151 -398.020563) (xy 410.55121 -398.033389) (xy 410.516472 -398.039941) (xy 410.498798 -398.040352)
			(xy 410.49829 -398.040352) (xy 410.479513 -398.039912) (xy 410.442678 -398.03259) (xy 410.407978 -398.018228)
			(xy 410.376743 -397.997377) (xy 410.350172 -397.970838) (xy 410.329283 -397.939629) (xy 410.314879 -397.904946)
			(xy 410.307511 -397.868121) (xy 410.307028 -397.849344) (xy 410.307454 -397.830228) (xy 410.315025 -397.792753)
			(xy 410.329893 -397.75753) (xy 410.351466 -397.725966) (xy 410.378882 -397.699319) (xy 410.411047 -397.678654)
			(xy 410.428694 -397.67129) (xy 410.438854 -397.667226) (xy 410.454348 -397.651478) (xy 410.483558 -397.568166)
			(xy 410.486749 -397.557579) (xy 410.484793 -397.535585) (xy 410.479748 -397.525748) (xy 410.351478 -397.304006)
			(xy 410.33954 -397.279876) (xy 410.334657 -397.270388) (xy 410.318889 -397.256062) (xy 410.298663 -397.249371)
			(xy 410.277462 -397.251465) (xy 410.258937 -397.261984) (xy 410.252164 -397.270224) (xy 410.241202 -397.284289)
			(xy 410.215022 -397.308491) (xy 410.184808 -397.32742) (xy 410.151609 -397.340419) (xy 410.116575 -397.347038)
			(xy 410.098748 -397.34744) (xy 410.09824 -397.34744) (xy 410.09136 -397.347434) (xy 410.077631 -397.346546)
			(xy 410.070808 -397.345662) (xy 410.05633 -397.343376) (xy 410.02966 -397.35506) (xy 409.96997 -397.442944)
			(xy 409.964946 -397.451077) (xy 409.96078 -397.469721) (xy 409.963718 -397.488597) (xy 409.968192 -397.497046)
			(xy 410.083762 -397.696944) (xy 410.084016 -397.697452) (xy 410.08427 -397.697452) (xy 410.08554 -397.699992)
			(xy 410.097814 -397.722906) (xy 410.115219 -397.771885) (xy 410.124092 -397.823101) (xy 410.124656 -397.84909)
			(xy 410.124656 -397.849344) (xy 410.124179 -397.873321) (xy 410.116676 -397.920686) (xy 410.101861 -397.966295)
			(xy 410.080098 -398.009027) (xy 410.051923 -398.047832) (xy 410.018028 -398.081755) (xy 409.979247 -398.109963)
			(xy 409.936533 -398.131762) (xy 409.890937 -398.146616) (xy 409.843579 -398.154159) (xy 409.819602 -398.154652)
			(xy 409.819094 -398.154652) (xy 409.795429 -398.154217) (xy 409.748668 -398.146906) (xy 409.703593 -398.132474)
			(xy 409.66128 -398.111267) (xy 409.622742 -398.083792) (xy 409.5889 -398.050704) (xy 409.560562 -398.012796)
			(xy 409.549092 -397.992092) (xy 409.548838 -397.99133) (xy 409.535884 -397.968978) (xy 409.530419 -397.960595)
			(xy 409.514561 -397.948432) (xy 409.495256 -397.94326) (xy 409.475441 -397.945865) (xy 409.466542 -397.950436)
			(xy 409.457398 -397.95577) (xy 409.451302 -397.964152) (xy 409.440355 -397.978035) (xy 409.414276 -398.001898)
			(xy 409.384254 -398.020562) (xy 409.351313 -398.033388) (xy 409.316576 -398.039941) (xy 409.298902 -398.040352)
			(xy 409.298394 -398.040352) (xy 409.279617 -398.039908) (xy 409.242783 -398.032587) (xy 409.208083 -398.018225)
			(xy 409.176847 -397.997376) (xy 409.150276 -397.970837) (xy 409.129387 -397.939628) (xy 409.114983 -397.904946)
			(xy 409.107615 -397.868121) (xy 409.107132 -397.849344) (xy 409.107556 -397.830228) (xy 409.115127 -397.792752)
			(xy 409.129995 -397.75753) (xy 409.151568 -397.725965) (xy 409.178985 -397.699319) (xy 409.211151 -397.678653)
			(xy 409.228798 -397.67129) (xy 409.238958 -397.667226) (xy 409.254452 -397.651478) (xy 409.283662 -397.568166)
			(xy 409.286853 -397.557579) (xy 409.284897 -397.535585) (xy 409.279852 -397.525748) (xy 409.151582 -397.304006)
			(xy 409.139644 -397.279876) (xy 409.134897 -397.270308) (xy 409.11909 -397.255972) (xy 409.098824 -397.249288)
			(xy 409.077589 -397.251406) (xy 409.059043 -397.261963) (xy 409.052268 -397.270224) (xy 409.041321 -397.284268)
			(xy 409.015185 -397.308443) (xy 408.985025 -397.327362) (xy 408.951883 -397.340369) (xy 408.916907 -397.347017)
			(xy 408.899106 -397.34744) (xy 408.898598 -397.34744) (xy 408.870912 -397.345408) (xy 408.870658 -397.345408)
			(xy 408.86119 -397.344421) (xy 408.842669 -397.348765) (xy 408.827018 -397.359579) (xy 408.821382 -397.367252)
			(xy 408.76982 -397.442944) (xy 408.764794 -397.451077) (xy 408.760624 -397.469721) (xy 408.763565 -397.488598)
			(xy 408.768042 -397.497046) (xy 408.883612 -397.696944) (xy 408.883866 -397.697452) (xy 408.88412 -397.697452)
			(xy 408.88539 -397.699992) (xy 408.897621 -397.722917) (xy 408.914942 -397.771902) (xy 408.92373 -397.823111)
			(xy 408.924252 -397.84909) (xy 408.924252 -397.849344) (xy 408.923778 -397.873334) (xy 408.916267 -397.920723)
			(xy 408.901436 -397.966354) (xy 408.879651 -398.009104) (xy 408.851448 -398.04792) (xy 408.81752 -398.081848)
			(xy 408.778704 -398.110051) (xy 408.735954 -398.131836) (xy 408.690323 -398.146667) (xy 408.642934 -398.154178)
			(xy 408.618944 -398.154652) (xy 408.595281 -398.154177) (xy 408.548521 -398.146873) (xy 408.503447 -398.132449)
			(xy 408.461134 -398.111248) (xy 408.422596 -398.083779) (xy 408.388752 -398.050697) (xy 408.360413 -398.012794)
			(xy 408.348942 -397.992092) (xy 408.348688 -397.99133) (xy 408.335734 -397.968978) (xy 408.33032 -397.960557)
			(xy 408.314443 -397.948395) (xy 408.295121 -397.943232) (xy 408.275294 -397.945854) (xy 408.266392 -397.950436)
			(xy 408.257248 -397.95577) (xy 408.251152 -397.964152) (xy 408.240233 -397.978059) (xy 408.214147 -398.00192)
			(xy 408.184118 -398.020579) (xy 408.151171 -398.0334) (xy 408.116428 -398.039946) (xy 408.098752 -398.040352)
			(xy 408.098244 -398.040352) (xy 408.079481 -398.039809) (xy 408.042674 -398.032496) (xy 408.008001 -398.018143)
			(xy 407.976795 -397.997302) (xy 407.950254 -397.970773) (xy 407.929398 -397.939576) (xy 407.91503 -397.90491)
			(xy 407.9077 -397.868107) (xy 407.907236 -397.849344) (xy 407.907731 -397.83025) (xy 407.915291 -397.792819)
			(xy 407.930119 -397.757629) (xy 407.951628 -397.726075) (xy 407.978964 -397.699411) (xy 408.011042 -397.678693)
			(xy 408.028648 -397.67129) (xy 408.038808 -397.667226) (xy 408.054302 -397.651478) (xy 408.083512 -397.568166)
			(xy 408.086708 -397.55758) (xy 408.08475 -397.535584) (xy 408.079702 -397.525748) (xy 407.951432 -397.304006)
			(xy 407.939494 -397.279876) (xy 407.934676 -397.27035) (xy 407.918889 -397.256019) (xy 407.898644 -397.249331)
			(xy 407.877427 -397.251437) (xy 407.858892 -397.261974) (xy 407.852118 -397.270224) (xy 407.841183 -397.284311)
			(xy 407.814995 -397.308511) (xy 407.784775 -397.327437) (xy 407.75157 -397.340431) (xy 407.716531 -397.347042)
			(xy 407.698702 -397.34744) (xy 407.698194 -397.34744) (xy 407.691314 -397.347439) (xy 407.677584 -397.346548)
			(xy 407.670762 -397.345662) (xy 407.656284 -397.343376) (xy 407.629614 -397.35506) (xy 407.569924 -397.442944)
			(xy 407.564898 -397.451077) (xy 407.560728 -397.469721) (xy 407.563669 -397.488598) (xy 407.568146 -397.497046)
			(xy 407.683716 -397.696944) (xy 407.68397 -397.697452) (xy 407.684224 -397.697452) (xy 407.685494 -397.699992)
			(xy 407.697725 -397.722917) (xy 407.715046 -397.771902) (xy 407.723834 -397.823111) (xy 407.724356 -397.84909)
			(xy 407.724356 -397.849344) (xy 407.723878 -397.873334) (xy 407.716367 -397.920723) (xy 407.701536 -397.966353)
			(xy 407.679752 -398.009103) (xy 407.651549 -398.047919) (xy 407.617622 -398.081846) (xy 407.578806 -398.11005)
			(xy 407.536057 -398.131835) (xy 407.490427 -398.146666) (xy 407.443038 -398.154178) (xy 407.419048 -398.154652)
			(xy 407.395385 -398.154174) (xy 407.348626 -398.146871) (xy 407.303551 -398.132447) (xy 407.261239 -398.111247)
			(xy 407.2227 -398.083778) (xy 407.188857 -398.050697) (xy 407.160517 -398.012794) (xy 407.149046 -397.992092)
			(xy 407.148792 -397.99133) (xy 407.135838 -397.968978) (xy 407.13042 -397.96056) (xy 407.114545 -397.948398)
			(xy 407.095224 -397.943234) (xy 407.075398 -397.945855) (xy 407.066496 -397.950436) (xy 407.057352 -397.95577)
			(xy 407.051256 -397.964152) (xy 407.040335 -397.978057) (xy 407.014249 -398.001918) (xy 406.984221 -398.020578)
			(xy 406.951274 -398.033399) (xy 406.916532 -398.039945) (xy 406.898856 -398.040352) (xy 406.898348 -398.040352)
			(xy 406.879582 -398.039835) (xy 406.84277 -398.032522) (xy 406.808091 -398.018168) (xy 406.77688 -397.997324)
			(xy 406.750334 -397.970792) (xy 406.729475 -397.93959) (xy 406.715104 -397.904919) (xy 406.707774 -397.86811)
			(xy 406.70734 -397.849344) (xy 406.707833 -397.83025) (xy 406.715393 -397.792819) (xy 406.730221 -397.757628)
			(xy 406.751731 -397.726075) (xy 406.779067 -397.69941) (xy 406.811146 -397.678693) (xy 406.828752 -397.67129)
			(xy 406.838912 -397.667226) (xy 406.854406 -397.651478) (xy 406.883616 -397.568166) (xy 406.886812 -397.55758)
			(xy 406.884854 -397.535584) (xy 406.879806 -397.525748) (xy 406.751536 -397.304006) (xy 406.739598 -397.279876)
			(xy 406.734775 -397.270353) (xy 406.718989 -397.256023) (xy 406.698746 -397.249334) (xy 406.67753 -397.251439)
			(xy 406.658996 -397.261975) (xy 406.652222 -397.270224) (xy 406.641302 -397.28429) (xy 406.615159 -397.308463)
			(xy 406.584992 -397.327378) (xy 406.551844 -397.340381) (xy 406.516863 -397.347021) (xy 406.49906 -397.34744)
			(xy 406.498552 -397.34744) (xy 406.470866 -397.345408) (xy 406.470612 -397.345408) (xy 406.461142 -397.344464)
			(xy 406.442626 -397.348789) (xy 406.426974 -397.359587) (xy 406.421336 -397.367252) (xy 406.369774 -397.442944)
			(xy 406.36475 -397.451077) (xy 406.360584 -397.469721) (xy 406.363522 -397.488597) (xy 406.367996 -397.497046)
			(xy 406.465786 -397.665956) (xy 406.465786 -397.666464) (xy 406.485598 -397.699992) (xy 406.497829 -397.722917)
			(xy 406.51515 -397.771902) (xy 406.523938 -397.823111) (xy 406.52446 -397.84909) (xy 406.52446 -397.849344)
			(xy 406.524102 -397.873341) (xy 406.516587 -397.920742) (xy 406.50175 -397.966385) (xy 406.479955 -398.009144)
			(xy 406.451739 -398.047968) (xy 406.417798 -398.081899) (xy 406.378966 -398.110103) (xy 406.3362 -398.131885)
			(xy 406.290553 -398.146709) (xy 406.243149 -398.154209) (xy 406.219152 -398.154652) (xy 406.218898 -398.154652)
			(xy 406.195325 -398.154232) (xy 406.14874 -398.146992) (xy 406.103823 -398.132669) (xy 406.061646 -398.111604)
			(xy 406.023213 -398.084299) (xy 405.989439 -398.051405) (xy 405.961131 -398.013705) (xy 405.949658 -397.993108)
			(xy 405.94915 -397.992346) (xy 405.935688 -397.968978) (xy 405.930219 -397.960598) (xy 405.914362 -397.948435)
			(xy 405.895059 -397.943262) (xy 405.875245 -397.945866) (xy 405.866346 -397.950436) (xy 405.857202 -397.95577)
			(xy 405.851106 -397.964152) (xy 405.840214 -397.97808) (xy 405.81412 -398.00194) (xy 405.784085 -398.020596)
			(xy 405.751132 -398.033411) (xy 405.716384 -398.03995) (xy 405.698706 -398.040352) (xy 405.698198 -398.040352)
			(xy 405.679421 -398.039905) (xy 405.642587 -398.032584) (xy 405.607887 -398.018223) (xy 405.576652 -397.997374)
			(xy 405.55008 -397.970836) (xy 405.529191 -397.939627) (xy 405.514787 -397.904945) (xy 405.507419 -397.868121)
			(xy 405.506936 -397.849344) (xy 405.507357 -397.830227) (xy 405.514928 -397.792752) (xy 405.529797 -397.757529)
			(xy 405.551371 -397.725965) (xy 405.578788 -397.699318) (xy 405.610954 -397.678653) (xy 405.628602 -397.67129)
			(xy 405.638762 -397.667226) (xy 405.654256 -397.651478) (xy 405.683466 -397.568166) (xy 405.686656 -397.557579)
			(xy 405.6847 -397.535585) (xy 405.679656 -397.525748) (xy 405.551386 -397.304006) (xy 405.539448 -397.279876)
			(xy 405.534695 -397.270312) (xy 405.51889 -397.255976) (xy 405.498625 -397.249291) (xy 405.477392 -397.251408)
			(xy 405.458847 -397.261964) (xy 405.452072 -397.270224) (xy 405.441163 -397.284332) (xy 405.414969 -397.308531)
			(xy 405.384742 -397.327453) (xy 405.351531 -397.340442) (xy 405.316487 -397.347047) (xy 405.298656 -397.34744)
			(xy 405.298148 -397.34744) (xy 405.291268 -397.347433) (xy 405.277539 -397.346546) (xy 405.270716 -397.345662)
			(xy 405.256238 -397.343376) (xy 405.229568 -397.35506) (xy 405.169878 -397.442944) (xy 405.164854 -397.451077)
			(xy 405.160687 -397.469721) (xy 405.163626 -397.488597) (xy 405.1681 -397.497046) (xy 405.28367 -397.696944)
			(xy 405.283924 -397.697452) (xy 405.284178 -397.697452) (xy 405.285448 -397.699992) (xy 405.297723 -397.722906)
			(xy 405.315127 -397.771885) (xy 405.324 -397.823101) (xy 405.324564 -397.84909) (xy 405.324564 -397.849344)
			(xy 405.324179 -397.873326) (xy 405.316673 -397.920699) (xy 405.301852 -397.966316) (xy 405.280081 -398.009054)
			(xy 405.251896 -398.047863) (xy 405.21799 -398.081788) (xy 405.179196 -398.109994) (xy 405.136469 -398.131788)
			(xy 405.090861 -398.146634) (xy 405.043492 -398.154166) (xy 405.01951 -398.154652) (xy 405.019002 -398.154652)
			(xy 404.995338 -398.154211) (xy 404.948577 -398.146901) (xy 404.903501 -398.13247) (xy 404.861189 -398.111264)
			(xy 404.822651 -398.08379) (xy 404.788808 -398.050703) (xy 404.76047 -398.012796) (xy 404.749 -397.992092)
			(xy 404.748746 -397.99133) (xy 404.735792 -397.968978) (xy 404.730319 -397.960601) (xy 404.714464 -397.948438)
			(xy 404.695162 -397.943264) (xy 404.675349 -397.945866) (xy 404.66645 -397.950436) (xy 404.657306 -397.95577)
			(xy 404.65121 -397.964152) (xy 404.640315 -397.978078) (xy 404.614223 -398.001939) (xy 404.584188 -398.020595)
			(xy 404.551235 -398.03341) (xy 404.516488 -398.039949) (xy 404.49881 -398.040352) (xy 404.498302 -398.040352)
			(xy 404.479525 -398.039901) (xy 404.442691 -398.032581) (xy 404.407991 -398.018221) (xy 404.376756 -397.997372)
			(xy 404.350184 -397.970835) (xy 404.329295 -397.939626) (xy 404.314891 -397.904945) (xy 404.307523 -397.86812)
			(xy 404.30704 -397.849344) (xy 404.307459 -397.830227) (xy 404.31503 -397.792751) (xy 404.329899 -397.757528)
			(xy 404.351473 -397.725964) (xy 404.378891 -397.699318) (xy 404.411058 -397.678653) (xy 404.428706 -397.67129)
			(xy 404.438866 -397.667226) (xy 404.45436 -397.651478) (xy 404.48357 -397.568166) (xy 404.48676 -397.557579)
			(xy 404.484804 -397.535585) (xy 404.47976 -397.525748) (xy 404.35149 -397.304006) (xy 404.339552 -397.279876)
			(xy 404.334793 -397.270315) (xy 404.31899 -397.25598) (xy 404.298727 -397.249294) (xy 404.277495 -397.251411)
			(xy 404.258951 -397.261964) (xy 404.252176 -397.270224) (xy 404.241265 -397.284331) (xy 404.215072 -397.30853)
			(xy 404.184845 -397.327452) (xy 404.151634 -397.340441) (xy 404.11659 -397.347046) (xy 404.09876 -397.34744)
			(xy 404.098252 -397.34744) (xy 404.091372 -397.347433) (xy 404.077643 -397.346546) (xy 404.07082 -397.345662)
			(xy 404.056342 -397.343376) (xy 404.029672 -397.35506) (xy 403.969982 -397.442944) (xy 403.964957 -397.451077)
			(xy 403.960791 -397.469721) (xy 403.963729 -397.488597) (xy 403.968204 -397.497046) (xy 404.083774 -397.696944)
			(xy 404.084028 -397.697452) (xy 404.084282 -397.697452) (xy 404.085552 -397.699992) (xy 404.097827 -397.722906)
			(xy 404.115231 -397.771885) (xy 404.124104 -397.823101) (xy 404.124668 -397.84909) (xy 404.124668 -397.849344)
			(xy 404.124279 -397.873326) (xy 404.116773 -397.920698) (xy 404.101952 -397.966315) (xy 404.080182 -398.009053)
			(xy 404.051997 -398.047862) (xy 404.018091 -398.081787) (xy 403.979298 -398.109993) (xy 403.936572 -398.131787)
			(xy 403.890964 -398.146633) (xy 403.843595 -398.154165) (xy 403.819614 -398.154652) (xy 403.819106 -398.154652)
			(xy 403.795442 -398.154208) (xy 403.748681 -398.146898) (xy 403.703606 -398.132468) (xy 403.661293 -398.111263)
			(xy 403.622755 -398.083789) (xy 403.588913 -398.050703) (xy 403.560574 -398.012795) (xy 403.549104 -397.992092)
			(xy 403.54885 -397.99133) (xy 403.535896 -397.968978) (xy 403.530521 -397.960529) (xy 403.51463 -397.948367)
			(xy 403.495294 -397.943211) (xy 403.475458 -397.945846) (xy 403.466554 -397.950436) (xy 403.45741 -397.95577)
			(xy 403.451314 -397.964152) (xy 403.440417 -397.978077) (xy 403.414325 -398.001937) (xy 403.384291 -398.020593)
			(xy 403.351339 -398.033409) (xy 403.316592 -398.039949) (xy 403.298914 -398.040352) (xy 403.298406 -398.040352)
			(xy 403.279629 -398.039898) (xy 403.242796 -398.032578) (xy 403.208096 -398.018219) (xy 403.17686 -397.997371)
			(xy 403.150288 -397.970833) (xy 403.129399 -397.939625) (xy 403.114995 -397.904944) (xy 403.107627 -397.86812)
			(xy 403.107144 -397.849344) (xy 403.10756 -397.830227) (xy 403.115132 -397.792751) (xy 403.130001 -397.757528)
			(xy 403.151576 -397.725963) (xy 403.178994 -397.699317) (xy 403.211162 -397.678653) (xy 403.22881 -397.67129)
			(xy 403.23897 -397.667226) (xy 403.254464 -397.651478) (xy 403.283674 -397.568166) (xy 403.286863 -397.557579)
			(xy 403.284908 -397.535585) (xy 403.279864 -397.525748) (xy 403.151594 -397.304006) (xy 403.139656 -397.279876)
			(xy 403.134892 -397.270318) (xy 403.11909 -397.255983) (xy 403.098829 -397.249298) (xy 403.077598 -397.251413)
			(xy 403.059055 -397.261965) (xy 403.05228 -397.270224) (xy 403.041384 -397.28431) (xy 403.015235 -397.308482)
			(xy 402.985062 -397.327393) (xy 402.951909 -397.340391) (xy 402.916922 -397.347025) (xy 402.899118 -397.34744)
			(xy 402.89861 -397.34744) (xy 402.878588 -397.346891) (xy 402.839419 -397.338567) (xy 402.802836 -397.322281)
			(xy 402.770439 -397.298745) (xy 402.743644 -397.268987) (xy 402.723622 -397.234308) (xy 402.711247 -397.196225)
			(xy 402.707061 -397.1564) (xy 389.243608 -397.1564) (xy 389.55599 -397.696944) (xy 389.556244 -397.697452)
			(xy 389.556498 -397.697452) (xy 389.557768 -397.699992) (xy 389.570036 -397.722909) (xy 389.587445 -397.771886)
			(xy 389.59632 -397.823102) (xy 389.596884 -397.84909) (xy 389.596884 -397.849344) (xy 389.596479 -397.873325)
			(xy 389.588973 -397.920696) (xy 389.574154 -397.966311) (xy 389.552385 -398.009048) (xy 389.524202 -398.047856)
			(xy 389.490298 -398.081781) (xy 389.451507 -398.109988) (xy 389.408783 -398.131783) (xy 389.363177 -398.14663)
			(xy 389.315811 -398.154164) (xy 389.29183 -398.154652) (xy 389.291322 -398.154652) (xy 389.267658 -398.154195)
			(xy 389.220898 -398.146888) (xy 389.175823 -398.13246) (xy 389.133511 -398.111257) (xy 389.094972 -398.083784)
			(xy 389.061129 -398.0507) (xy 389.032791 -398.012795) (xy 389.02132 -397.992092) (xy 389.021066 -397.99133)
			(xy 389.008112 -397.968978) (xy 389.002721 -397.960541) (xy 388.986835 -397.948379) (xy 388.967506 -397.94322)
			(xy 388.947673 -397.945849) (xy 388.93877 -397.950436) (xy 388.929626 -397.95577) (xy 388.92353 -397.964152)
			(xy 388.912624 -397.978069) (xy 388.886534 -398.00193) (xy 388.856502 -398.020587) (xy 388.823552 -398.033406)
			(xy 388.788807 -398.039947) (xy 388.77113 -398.040352) (xy 388.770622 -398.040352) (xy 388.751846 -398.039883)
			(xy 388.715013 -398.032567) (xy 388.680313 -398.01821) (xy 388.649077 -397.997364) (xy 388.622505 -397.970829)
			(xy 388.601616 -397.939622) (xy 388.587211 -397.904942) (xy 388.579843 -397.86812) (xy 388.57936 -397.849344)
			(xy 388.579766 -397.830226) (xy 388.587338 -397.792749) (xy 388.60221 -397.757525) (xy 388.623786 -397.72596)
			(xy 388.651207 -397.699315) (xy 388.683377 -397.678651) (xy 388.701026 -397.67129) (xy 388.711186 -397.667226)
			(xy 388.72668 -397.651478) (xy 388.75589 -397.568166) (xy 388.759089 -397.557581) (xy 388.75713 -397.535584)
			(xy 388.75208 -397.525748) (xy 388.62381 -397.304006) (xy 388.611872 -397.279876) (xy 388.607085 -397.270331)
			(xy 388.59129 -397.255998) (xy 388.571035 -397.249311) (xy 388.54981 -397.251423) (xy 388.53127 -397.261969)
			(xy 388.524496 -397.270224) (xy 388.513591 -397.284302) (xy 388.487444 -397.308475) (xy 388.457273 -397.327388)
			(xy 388.424122 -397.340387) (xy 388.389138 -397.347023) (xy 388.371334 -397.34744) (xy 388.370826 -397.34744)
			(xy 388.34314 -397.345408) (xy 388.342886 -397.345408) (xy 388.333417 -397.344444) (xy 388.314898 -397.348778)
			(xy 388.299247 -397.359583) (xy 388.29361 -397.367252) (xy 388.242048 -397.442944) (xy 388.23702 -397.451076)
			(xy 388.232848 -397.469721) (xy 388.235791 -397.488599) (xy 388.24027 -397.497046) (xy 388.35584 -397.696944)
			(xy 388.356094 -397.697452) (xy 388.356348 -397.697452) (xy 388.357618 -397.699992) (xy 388.369851 -397.722916)
			(xy 388.387171 -397.771902) (xy 388.395958 -397.823111) (xy 388.39648 -397.84909) (xy 388.39648 -397.849344)
			(xy 388.396078 -397.873338) (xy 388.388564 -397.920734) (xy 388.373729 -397.966371) (xy 388.351938 -398.009125)
			(xy 388.323726 -398.047945) (xy 388.28979 -398.081873) (xy 388.250964 -398.110075) (xy 388.208204 -398.131857)
			(xy 388.162564 -398.146681) (xy 388.115166 -398.154184) (xy 388.091172 -398.154652) (xy 388.06751 -398.154155)
			(xy 388.020751 -398.146855) (xy 387.975677 -398.132434) (xy 387.933365 -398.111238) (xy 387.894826 -398.083772)
			(xy 387.860982 -398.050693) (xy 387.832641 -398.012793) (xy 387.82117 -397.992092) (xy 387.820916 -397.99133)
			(xy 387.807962 -397.968978) (xy 387.80252 -397.960578) (xy 387.786653 -397.948416) (xy 387.767341 -397.943248)
			(xy 387.74752 -397.94586) (xy 387.73862 -397.950436) (xy 387.729476 -397.95577) (xy 387.72338 -397.964152)
			(xy 387.712446 -397.978045) (xy 387.686363 -398.001908) (xy 387.656338 -398.020569) (xy 387.623395 -398.033394)
			(xy 387.588655 -398.039943) (xy 387.57098 -398.040352) (xy 387.570472 -398.040352) (xy 387.551706 -398.039874)
			(xy 387.514897 -398.032548) (xy 387.480224 -398.018184) (xy 387.449018 -397.997332) (xy 387.422478 -397.970795)
			(xy 387.401624 -397.939591) (xy 387.387257 -397.904918) (xy 387.379928 -397.868109) (xy 387.379464 -397.849344)
			(xy 387.379942 -397.830249) (xy 387.387503 -397.792816) (xy 387.402334 -397.757624) (xy 387.423846 -397.72607)
			(xy 387.451186 -397.699407) (xy 387.483268 -397.678691) (xy 387.500876 -397.67129) (xy 387.511036 -397.667226)
			(xy 387.52653 -397.651478) (xy 387.55574 -397.568166) (xy 387.558933 -397.55758) (xy 387.556976 -397.535584)
			(xy 387.55193 -397.525748) (xy 387.42366 -397.304006) (xy 387.411722 -397.279876) (xy 387.406865 -397.270373)
			(xy 387.391089 -397.256045) (xy 387.370856 -397.249355) (xy 387.349649 -397.251453) (xy 387.331119 -397.26198)
			(xy 387.324346 -397.270224) (xy 387.313395 -397.284297) (xy 387.287211 -397.308499) (xy 387.256995 -397.327427)
			(xy 387.223793 -397.340424) (xy 387.188757 -397.34704) (xy 387.17093 -397.34744) (xy 387.170422 -397.34744)
			(xy 387.163542 -397.347436) (xy 387.149812 -397.346547) (xy 387.14299 -397.345662) (xy 387.128512 -397.343376)
			(xy 387.101842 -397.35506) (xy 387.042152 -397.442944) (xy 387.037129 -397.451077) (xy 387.032965 -397.469721)
			(xy 387.035902 -397.488597) (xy 387.040374 -397.497046) (xy 387.155944 -397.696944) (xy 387.156198 -397.697452)
			(xy 387.156452 -397.697452) (xy 387.157722 -397.699992) (xy 387.169955 -397.722916) (xy 387.187275 -397.771902)
			(xy 387.196062 -397.823111) (xy 387.196584 -397.84909) (xy 387.196584 -397.849344) (xy 387.196178 -397.873338)
			(xy 387.188664 -397.920733) (xy 387.17383 -397.96637) (xy 387.152038 -398.009124) (xy 387.123828 -398.047943)
			(xy 387.089892 -398.081872) (xy 387.051066 -398.110074) (xy 387.008307 -398.131856) (xy 386.962667 -398.14668)
			(xy 386.91527 -398.154183) (xy 386.891276 -398.154652) (xy 386.867611 -398.154232) (xy 386.820849 -398.146918)
			(xy 386.775773 -398.132483) (xy 386.733461 -398.111274) (xy 386.694923 -398.083796) (xy 386.661081 -398.050707)
			(xy 386.632744 -398.012797) (xy 386.621274 -397.992092) (xy 386.62102 -397.99133) (xy 386.608066 -397.968978)
			(xy 386.60262 -397.960581) (xy 386.586754 -397.948419) (xy 386.567444 -397.94325) (xy 386.547624 -397.945861)
			(xy 386.538724 -397.950436) (xy 386.52958 -397.95577) (xy 386.523484 -397.964152) (xy 386.512547 -397.978043)
			(xy 386.486465 -398.001906) (xy 386.456441 -398.020568) (xy 386.423498 -398.033393) (xy 386.388759 -398.039943)
			(xy 386.371084 -398.040352) (xy 386.370576 -398.040352) (xy 386.351811 -398.03987) (xy 386.315001 -398.032545)
			(xy 386.280328 -398.018181) (xy 386.249122 -397.997331) (xy 386.222582 -397.970794) (xy 386.201728 -397.93959)
			(xy 386.187361 -397.904918) (xy 386.180032 -397.868109) (xy 386.179568 -397.849344) (xy 386.180043 -397.830249)
			(xy 386.187604 -397.792816) (xy 386.202436 -397.757624) (xy 386.223948 -397.72607) (xy 386.251289 -397.699406)
			(xy 386.283372 -397.678691) (xy 386.30098 -397.67129) (xy 386.31114 -397.667226) (xy 386.326634 -397.651478)
			(xy 386.355844 -397.568166) (xy 386.359036 -397.55758) (xy 386.35708 -397.535585) (xy 386.352034 -397.525748)
			(xy 386.223764 -397.304006) (xy 386.211826 -397.279876) (xy 386.206963 -397.270376) (xy 386.191189 -397.256049)
			(xy 386.170957 -397.249358) (xy 386.149752 -397.251456) (xy 386.131223 -397.261981) (xy 386.12445 -397.270224)
			(xy 386.113514 -397.284277) (xy 386.087375 -397.308451) (xy 386.057212 -397.327368) (xy 386.024068 -397.340374)
			(xy 385.989089 -397.347018) (xy 385.971288 -397.34744) (xy 385.97078 -397.34744) (xy 385.943094 -397.345408)
			(xy 385.94284 -397.345408) (xy 385.933373 -397.344407) (xy 385.91485 -397.348757) (xy 385.899199 -397.359577)
			(xy 385.893564 -397.367252) (xy 385.842002 -397.442944) (xy 385.836976 -397.451077) (xy 385.832808 -397.469721)
			(xy 385.835748 -397.488598) (xy 385.840224 -397.497046) (xy 385.955794 -397.696944) (xy 385.956048 -397.697452)
			(xy 385.956302 -397.697452) (xy 385.957572 -397.699992) (xy 385.969841 -397.722909) (xy 385.987249 -397.771886)
			(xy 385.996124 -397.823102) (xy 385.996688 -397.84909) (xy 385.996688 -397.849344) (xy 385.996279 -397.873325)
			(xy 385.988774 -397.920695) (xy 385.973954 -397.96631) (xy 385.952186 -398.009047) (xy 385.924003 -398.047855)
			(xy 385.8901 -398.08178) (xy 385.851309 -398.109986) (xy 385.808586 -398.131782) (xy 385.76298 -398.146629)
			(xy 385.715614 -398.154164) (xy 385.691634 -398.154652) (xy 385.691126 -398.154652) (xy 385.667462 -398.154192)
			(xy 385.620702 -398.146885) (xy 385.575627 -398.132458) (xy 385.533315 -398.111255) (xy 385.494777 -398.083783)
			(xy 385.460934 -398.0507) (xy 385.432595 -398.012795) (xy 385.421124 -397.992092) (xy 385.42087 -397.99133)
			(xy 385.407916 -397.968978) (xy 385.402521 -397.960544) (xy 385.386637 -397.948382) (xy 385.367309 -397.943222)
			(xy 385.347477 -397.94585) (xy 385.338574 -397.950436) (xy 385.32943 -397.95577) (xy 385.323334 -397.964152)
			(xy 385.312426 -397.978067) (xy 385.286337 -398.001928) (xy 385.256305 -398.020586) (xy 385.223356 -398.033405)
			(xy 385.188611 -398.039947) (xy 385.170934 -398.040352) (xy 385.170426 -398.040352) (xy 385.15165 -398.039879)
			(xy 385.114817 -398.032564) (xy 385.080117 -398.018208) (xy 385.048882 -397.997362) (xy 385.022309 -397.970827)
			(xy 385.00142 -397.939622) (xy 384.987015 -397.904942) (xy 384.979647 -397.86812) (xy 384.979164 -397.849344)
			(xy 384.979568 -397.830226) (xy 384.98714 -397.792749) (xy 385.002012 -397.757524) (xy 385.023589 -397.72596)
			(xy 385.05101 -397.699314) (xy 385.08318 -397.678651) (xy 385.10083 -397.67129) (xy 385.11099 -397.667226)
			(xy 385.126484 -397.651478) (xy 385.155694 -397.568166) (xy 385.158892 -397.557581) (xy 385.156933 -397.535584)
			(xy 385.151884 -397.525748) (xy 385.023614 -397.304006) (xy 385.011676 -397.279876) (xy 385.006884 -397.270335)
			(xy 384.99109 -397.256002) (xy 384.970837 -397.249315) (xy 384.949613 -397.251425) (xy 384.931074 -397.26197)
			(xy 384.9243 -397.270224) (xy 384.913375 -397.284319) (xy 384.887185 -397.308519) (xy 384.856962 -397.327443)
			(xy 384.823754 -397.340435) (xy 384.788713 -397.347044) (xy 384.770884 -397.34744) (xy 384.770376 -397.34744)
			(xy 384.763496 -397.347441) (xy 384.749766 -397.346548) (xy 384.742944 -397.345662) (xy 384.728466 -397.343376)
			(xy 384.701796 -397.35506) (xy 384.642106 -397.442944) (xy 384.63708 -397.451077) (xy 384.632911 -397.469721)
			(xy 384.635852 -397.488598) (xy 384.640328 -397.497046) (xy 384.755898 -397.696944) (xy 384.756152 -397.697452)
			(xy 384.756406 -397.697452) (xy 384.757676 -397.699992) (xy 384.769945 -397.722909) (xy 384.787353 -397.771886)
			(xy 384.796228 -397.823102) (xy 384.796792 -397.84909) (xy 384.796792 -397.849344) (xy 384.796379 -397.873325)
			(xy 384.788874 -397.920695) (xy 384.774055 -397.966309) (xy 384.752287 -398.009046) (xy 384.724104 -398.047854)
			(xy 384.690201 -398.081778) (xy 384.651412 -398.109985) (xy 384.608689 -398.13178) (xy 384.563084 -398.146628)
			(xy 384.515718 -398.154164) (xy 384.491738 -398.154652) (xy 384.49123 -398.154652) (xy 384.467566 -398.154188)
			(xy 384.420807 -398.146882) (xy 384.375732 -398.132456) (xy 384.333419 -398.111254) (xy 384.294881 -398.083782)
			(xy 384.261038 -398.050699) (xy 384.232699 -398.012794) (xy 384.221228 -397.992092) (xy 384.220974 -397.99133)
			(xy 384.20802 -397.968978) (xy 384.202621 -397.960547) (xy 384.186738 -397.948385) (xy 384.167411 -397.943225)
			(xy 384.147581 -397.945851) (xy 384.138678 -397.950436) (xy 384.129534 -397.95577) (xy 384.123438 -397.964152)
			(xy 384.112527 -397.978065) (xy 384.086439 -398.001926) (xy 384.056408 -398.020584) (xy 384.023459 -398.033404)
			(xy 383.988715 -398.039947) (xy 383.971038 -398.040352) (xy 383.97053 -398.040352) (xy 383.951754 -398.039876)
			(xy 383.914921 -398.032561) (xy 383.880221 -398.018205) (xy 383.848986 -397.997361) (xy 383.822414 -397.970826)
			(xy 383.801524 -397.939621) (xy 383.787119 -397.904942) (xy 383.779751 -397.868119) (xy 383.779268 -397.849344)
			(xy 383.779669 -397.830226) (xy 383.787242 -397.792748) (xy 383.802114 -397.757524) (xy 383.823691 -397.725959)
			(xy 383.851113 -397.699313) (xy 383.883284 -397.678651) (xy 383.900934 -397.67129) (xy 383.911094 -397.667226)
			(xy 383.926588 -397.651478) (xy 383.955798 -397.568166) (xy 383.958996 -397.55758) (xy 383.957037 -397.535584)
			(xy 383.951988 -397.525748) (xy 383.823718 -397.304006) (xy 383.81178 -397.279876) (xy 383.806982 -397.270338)
			(xy 383.791189 -397.256006) (xy 383.770938 -397.249319) (xy 383.749717 -397.251428) (xy 383.731178 -397.261971)
			(xy 383.724404 -397.270224) (xy 383.713477 -397.284317) (xy 383.687288 -397.308517) (xy 383.657065 -397.327442)
			(xy 383.623858 -397.340434) (xy 383.588817 -397.347044) (xy 383.570988 -397.34744) (xy 383.57048 -397.34744)
			(xy 383.5636 -397.34744) (xy 383.54987 -397.346548) (xy 383.543048 -397.345662) (xy 383.52857 -397.343376)
			(xy 383.5019 -397.35506) (xy 383.44221 -397.442944) (xy 383.437184 -397.451077) (xy 383.433015 -397.469721)
			(xy 383.435955 -397.488598) (xy 383.440432 -397.497046) (xy 383.556002 -397.696944) (xy 383.556256 -397.697452)
			(xy 383.55651 -397.697452) (xy 383.55778 -397.699992) (xy 383.570049 -397.722909) (xy 383.587457 -397.771886)
			(xy 383.596332 -397.823102) (xy 383.596896 -397.84909) (xy 383.596896 -397.849344) (xy 383.596479 -397.873324)
			(xy 383.588974 -397.920694) (xy 383.574155 -397.966308) (xy 383.552387 -398.009045) (xy 383.524206 -398.047852)
			(xy 383.490303 -398.081777) (xy 383.451514 -398.109984) (xy 383.408792 -398.131779) (xy 383.363187 -398.146628)
			(xy 383.315822 -398.154163) (xy 383.291842 -398.154652) (xy 383.291334 -398.154652) (xy 383.267671 -398.154185)
			(xy 383.220911 -398.14688) (xy 383.175836 -398.132454) (xy 383.133524 -398.111252) (xy 383.094985 -398.083781)
			(xy 383.061142 -398.050699) (xy 383.032803 -398.012794) (xy 383.021332 -397.992092) (xy 383.021078 -397.99133)
			(xy 383.008124 -397.968978) (xy 383.002721 -397.96055) (xy 382.98684 -397.948388) (xy 382.967514 -397.943227)
			(xy 382.947684 -397.945852) (xy 382.938782 -397.950436) (xy 382.929638 -397.95577) (xy 382.923542 -397.964152)
			(xy 382.912629 -397.978063) (xy 382.886541 -398.001925) (xy 382.856511 -398.020583) (xy 382.823563 -398.033403)
			(xy 382.788819 -398.039946) (xy 382.771142 -398.040352) (xy 382.770634 -398.040352) (xy 382.751858 -398.039872)
			(xy 382.715026 -398.032558) (xy 382.680326 -398.018203) (xy 382.64909 -397.997359) (xy 382.622518 -397.970825)
			(xy 382.601628 -397.93962) (xy 382.587223 -397.904941) (xy 382.579855 -397.868119) (xy 382.579372 -397.849344)
			(xy 382.57977 -397.830226) (xy 382.587343 -397.792748) (xy 382.602216 -397.757523) (xy 382.623794 -397.725958)
			(xy 382.651216 -397.699313) (xy 382.683388 -397.678651) (xy 382.701038 -397.67129) (xy 382.711198 -397.667226)
			(xy 382.726692 -397.651478) (xy 382.755902 -397.568166) (xy 382.7591 -397.55758) (xy 382.757141 -397.535584)
			(xy 382.752092 -397.525748) (xy 382.623822 -397.304006) (xy 382.611884 -397.279876) (xy 382.60708 -397.270342)
			(xy 382.591289 -397.25601) (xy 382.57104 -397.249322) (xy 382.54982 -397.251431) (xy 382.531282 -397.261972)
			(xy 382.524508 -397.270224) (xy 382.513596 -397.284297) (xy 382.487451 -397.308469) (xy 382.457282 -397.327383)
			(xy 382.424132 -397.340384) (xy 382.389149 -397.347022) (xy 382.371346 -397.34744) (xy 382.370838 -397.34744)
			(xy 382.343152 -397.345408) (xy 382.342898 -397.345408) (xy 382.333428 -397.344453) (xy 382.314911 -397.348783)
			(xy 382.29926 -397.359585) (xy 382.293622 -397.367252) (xy 382.24206 -397.442944) (xy 382.237037 -397.451077)
			(xy 382.232872 -397.469721) (xy 382.235809 -397.488597) (xy 382.240282 -397.497046) (xy 382.355852 -397.696944)
			(xy 382.356106 -397.697452) (xy 382.35636 -397.697452) (xy 382.35763 -397.699992) (xy 382.369864 -397.722916)
			(xy 382.387183 -397.771902) (xy 382.395971 -397.823111) (xy 382.396492 -397.84909) (xy 382.396492 -397.849344)
			(xy 382.396078 -397.873337) (xy 382.388565 -397.920732) (xy 382.37373 -397.966368) (xy 382.35194 -398.009122)
			(xy 382.32373 -398.047941) (xy 382.289795 -398.081869) (xy 382.250971 -398.110071) (xy 382.208212 -398.131853)
			(xy 382.162574 -398.146679) (xy 382.115177 -398.154183) (xy 382.091184 -398.154652) (xy 382.067519 -398.154226)
			(xy 382.020757 -398.146913) (xy 381.975682 -398.132479) (xy 381.933369 -398.111271) (xy 381.894832 -398.083794)
			(xy 381.860989 -398.050706) (xy 381.832652 -398.012796) (xy 381.821182 -397.992092) (xy 381.820928 -397.99133)
			(xy 381.807974 -397.968978) (xy 381.80252 -397.960587) (xy 381.786657 -397.948425) (xy 381.767349 -397.943255)
			(xy 381.747532 -397.945863) (xy 381.738632 -397.950436) (xy 381.729488 -397.95577) (xy 381.723392 -397.964152)
			(xy 381.712451 -397.97804) (xy 381.68637 -398.001903) (xy 381.656347 -398.020565) (xy 381.623405 -398.033391)
			(xy 381.588667 -398.039942) (xy 381.570992 -398.040352) (xy 381.570484 -398.040352) (xy 381.551719 -398.039863)
			(xy 381.51491 -398.032539) (xy 381.480237 -398.018177) (xy 381.449031 -397.997327) (xy 381.422491 -397.970791)
			(xy 381.401636 -397.939588) (xy 381.387269 -397.904917) (xy 381.37994 -397.868109) (xy 381.379476 -397.849344)
			(xy 381.379946 -397.830249) (xy 381.387508 -397.792815) (xy 381.40234 -397.757622) (xy 381.423853 -397.726068)
			(xy 381.451195 -397.699405) (xy 381.483279 -397.67869) (xy 381.500888 -397.67129) (xy 381.511048 -397.667226)
			(xy 381.526542 -397.651478) (xy 381.555752 -397.568166) (xy 381.558944 -397.55758) (xy 381.556987 -397.535585)
			(xy 381.551942 -397.525748) (xy 381.423672 -397.304006) (xy 381.411734 -397.279876) (xy 381.40686 -397.270383)
			(xy 381.391089 -397.256057) (xy 381.370861 -397.249365) (xy 381.349658 -397.251461) (xy 381.331131 -397.261983)
			(xy 381.324358 -397.270224) (xy 381.3134 -397.284292) (xy 381.287218 -397.308494) (xy 381.257004 -397.327422)
			(xy 381.223803 -397.340421) (xy 381.188769 -397.347039) (xy 381.170942 -397.34744) (xy 381.170434 -397.34744)
			(xy 381.163554 -397.347435) (xy 381.149825 -397.346546) (xy 381.143002 -397.345662) (xy 381.128524 -397.343376)
			(xy 381.101854 -397.35506) (xy 381.042164 -397.442944) (xy 381.03714 -397.451077) (xy 381.032975 -397.469721)
			(xy 381.035913 -397.488597) (xy 381.040386 -397.497046) (xy 381.155956 -397.696944) (xy 381.15621 -397.697452)
			(xy 381.156464 -397.697452) (xy 381.157734 -397.699992) (xy 381.169968 -397.722915) (xy 381.187288 -397.771902)
			(xy 381.196075 -397.823111) (xy 381.196596 -397.84909) (xy 381.196596 -397.849344) (xy 381.196178 -397.873337)
			(xy 381.188665 -397.920731) (xy 381.173831 -397.966367) (xy 381.152041 -398.009121) (xy 381.123831 -398.047939)
			(xy 381.089897 -398.081868) (xy 381.051073 -398.11007) (xy 381.008315 -398.131852) (xy 380.962677 -398.146678)
			(xy 380.915281 -398.154182) (xy 380.891288 -398.154652) (xy 380.867623 -398.154222) (xy 380.820862 -398.14691)
			(xy 380.775786 -398.132477) (xy 380.733474 -398.111269) (xy 380.694936 -398.083793) (xy 380.661094 -398.050705)
			(xy 380.632756 -398.012796) (xy 380.621286 -397.992092) (xy 380.621032 -397.99133) (xy 380.608078 -397.968978)
			(xy 380.60262 -397.96059) (xy 380.586759 -397.948428) (xy 380.567452 -397.943257) (xy 380.547636 -397.945864)
			(xy 380.538736 -397.950436) (xy 380.529592 -397.95577) (xy 380.523496 -397.964152) (xy 380.512553 -397.978038)
			(xy 380.486472 -398.001901) (xy 380.45645 -398.020564) (xy 380.423508 -398.03339) (xy 380.388771 -398.039942)
			(xy 380.371096 -398.040352) (xy 380.370588 -398.040352) (xy 380.351823 -398.039859) (xy 380.315014 -398.032536)
			(xy 380.280341 -398.018175) (xy 380.249135 -397.997326) (xy 380.222595 -397.97079) (xy 380.20174 -397.939587)
			(xy 380.187373 -397.904916) (xy 380.180044 -397.868109) (xy 380.17958 -397.849344) (xy 380.180047 -397.830249)
			(xy 380.187609 -397.792814) (xy 380.202442 -397.757622) (xy 380.223956 -397.726067) (xy 380.251298 -397.699404)
			(xy 380.283383 -397.67869) (xy 380.300992 -397.67129) (xy 380.311152 -397.667226) (xy 380.326646 -397.651478)
			(xy 380.355856 -397.568166) (xy 380.359047 -397.557579) (xy 380.357091 -397.535585) (xy 380.352046 -397.525748)
			(xy 380.223776 -397.304006) (xy 380.211838 -397.279876) (xy 380.206958 -397.270386) (xy 380.191189 -397.25606)
			(xy 380.170962 -397.249369) (xy 380.149761 -397.251464) (xy 380.131235 -397.261984) (xy 380.124462 -397.270224)
			(xy 380.113519 -397.284271) (xy 380.087381 -397.308446) (xy 380.05722 -397.327364) (xy 380.024078 -397.340371)
			(xy 379.989101 -397.347017) (xy 379.9713 -397.34744) (xy 379.970792 -397.34744) (xy 379.943106 -397.345408)
			(xy 379.942852 -397.345408) (xy 379.933384 -397.344416) (xy 379.914862 -397.348762) (xy 379.899212 -397.359579)
			(xy 379.893576 -397.367252) (xy 379.842014 -397.442944) (xy 379.836988 -397.451077) (xy 379.832819 -397.469721)
			(xy 379.83576 -397.488598) (xy 379.840236 -397.497046) (xy 379.955806 -397.696944) (xy 379.95606 -397.697452)
			(xy 379.956314 -397.697452) (xy 379.957584 -397.699992) (xy 379.969854 -397.722909) (xy 379.987261 -397.771886)
			(xy 379.996136 -397.823101) (xy 379.9967 -397.84909) (xy 379.9967 -397.849344) (xy 379.996279 -397.873324)
			(xy 379.988774 -397.920694) (xy 379.973956 -397.966307) (xy 379.952188 -398.009044) (xy 379.924007 -398.047851)
			(xy 379.890105 -398.081775) (xy 379.851316 -398.109982) (xy 379.808594 -398.131778) (xy 379.76299 -398.146627)
			(xy 379.715626 -398.154163) (xy 379.691646 -398.154652) (xy 379.691138 -398.154652) (xy 379.667475 -398.154182)
			(xy 379.620715 -398.146877) (xy 379.57564 -398.132452) (xy 379.533328 -398.111251) (xy 379.494789 -398.08378)
			(xy 379.460946 -398.050698) (xy 379.432607 -398.012794) (xy 379.421136 -397.992092) (xy 379.420882 -397.99133)
			(xy 379.407928 -397.968978) (xy 379.402521 -397.960553) (xy 379.386641 -397.948391) (xy 379.367317 -397.943229)
			(xy 379.347488 -397.945853) (xy 379.338586 -397.950436) (xy 379.329442 -397.95577) (xy 379.323346 -397.964152)
			(xy 379.312431 -397.978061) (xy 379.286343 -398.001923) (xy 379.256314 -398.020582) (xy 379.223366 -398.033402)
			(xy 379.188623 -398.039946) (xy 379.170946 -398.040352) (xy 379.170438 -398.040352) (xy 379.151662 -398.039869)
			(xy 379.11483 -398.032555) (xy 379.08013 -398.018201) (xy 379.048895 -397.997357) (xy 379.022322 -397.970824)
			(xy 379.001432 -397.939619) (xy 378.987027 -397.904941) (xy 378.979659 -397.868119) (xy 378.979176 -397.849344)
			(xy 378.979635 -397.83023) (xy 378.987203 -397.792759) (xy 379.002067 -397.757539) (xy 379.023633 -397.725975)
			(xy 379.051041 -397.699327) (xy 379.083199 -397.678657) (xy 379.100842 -397.67129) (xy 379.111002 -397.667226)
			(xy 379.126496 -397.651478) (xy 379.155706 -397.568166) (xy 379.158903 -397.55758) (xy 379.156945 -397.535584)
			(xy 379.151896 -397.525748) (xy 379.023626 -397.304006) (xy 379.011688 -397.279876) (xy 379.006879 -397.270345)
			(xy 378.991089 -397.256013) (xy 378.970842 -397.249326) (xy 378.949623 -397.251433) (xy 378.931086 -397.261973)
			(xy 378.924312 -397.270224) (xy 378.91338 -397.284314) (xy 378.887192 -397.308514) (xy 378.856971 -397.327439)
			(xy 378.823765 -397.340432) (xy 378.788725 -397.347043) (xy 378.770896 -397.34744) (xy 378.770388 -397.34744)
			(xy 378.763508 -397.34744) (xy 378.749778 -397.346548) (xy 378.742956 -397.345662) (xy 378.728478 -397.343376)
			(xy 378.701808 -397.35506) (xy 378.642118 -397.442944) (xy 378.637092 -397.451077) (xy 378.632922 -397.469721)
			(xy 378.635863 -397.488598) (xy 378.64034 -397.497046) (xy 378.75591 -397.696944) (xy 378.756164 -397.697452)
			(xy 378.756418 -397.697452) (xy 378.757688 -397.699992) (xy 378.769958 -397.722908) (xy 378.787365 -397.771886)
			(xy 378.79624 -397.823101) (xy 378.796804 -397.84909) (xy 378.796804 -397.849344) (xy 378.796379 -397.873324)
			(xy 378.788874 -397.920693) (xy 378.774056 -397.966307) (xy 378.752289 -398.009042) (xy 378.724108 -398.04785)
			(xy 378.690206 -398.081774) (xy 378.651418 -398.109981) (xy 378.608697 -398.131777) (xy 378.563094 -398.146626)
			(xy 378.51573 -398.154163) (xy 378.49175 -398.154652) (xy 378.491242 -398.154652) (xy 378.467579 -398.154179)
			(xy 378.420819 -398.146875) (xy 378.375745 -398.13245) (xy 378.333432 -398.111249) (xy 378.294894 -398.083779)
			(xy 378.26105 -398.050697) (xy 378.232711 -398.012794) (xy 378.22124 -397.992092) (xy 378.220986 -397.99133)
			(xy 378.208032 -397.968978) (xy 378.20262 -397.960556) (xy 378.186743 -397.948394) (xy 378.16742 -397.943231)
			(xy 378.147592 -397.945854) (xy 378.13869 -397.950436) (xy 378.129546 -397.95577) (xy 378.12345 -397.964152)
			(xy 378.112533 -397.978059) (xy 378.086446 -398.001921) (xy 378.056417 -398.02058) (xy 378.023469 -398.033401)
			(xy 377.988726 -398.039946) (xy 377.97105 -398.040352) (xy 377.970542 -398.040352) (xy 377.951766 -398.039865)
			(xy 377.914934 -398.032552) (xy 377.880234 -398.018199) (xy 377.848999 -397.997356) (xy 377.822426 -397.970823)
			(xy 377.801537 -397.939618) (xy 377.787131 -397.90494) (xy 377.779763 -397.868119) (xy 377.77928 -397.849344)
			(xy 377.779736 -397.83023) (xy 377.787305 -397.792758) (xy 377.802169 -397.757538) (xy 377.823735 -397.725975)
			(xy 377.851144 -397.699326) (xy 377.883302 -397.678656) (xy 377.900946 -397.67129) (xy 377.911106 -397.667226)
			(xy 377.9266 -397.651478) (xy 377.95581 -397.568166) (xy 377.959007 -397.55758) (xy 377.957049 -397.535584)
			(xy 377.952 -397.525748) (xy 377.82373 -397.304006) (xy 377.811792 -397.279876) (xy 377.806977 -397.270348)
			(xy 377.791189 -397.256017) (xy 377.770943 -397.249329) (xy 377.749726 -397.251435) (xy 377.73119 -397.261973)
			(xy 377.724416 -397.270224) (xy 377.713482 -397.284312) (xy 377.687294 -397.308512) (xy 377.657074 -397.327437)
			(xy 377.623868 -397.340431) (xy 377.588829 -397.347043) (xy 377.571 -397.34744) (xy 377.570492 -397.34744)
			(xy 377.563612 -397.347439) (xy 377.549882 -397.346548) (xy 377.54306 -397.345662) (xy 377.528582 -397.343376)
			(xy 377.501912 -397.35506) (xy 377.442222 -397.442944) (xy 377.437196 -397.451077) (xy 377.433026 -397.469721)
			(xy 377.435967 -397.488598) (xy 377.440444 -397.497046) (xy 377.556014 -397.696944) (xy 377.556268 -397.697452)
			(xy 377.556522 -397.697452) (xy 377.557792 -397.699992) (xy 377.570062 -397.722908) (xy 377.587469 -397.771886)
			(xy 377.596344 -397.823101) (xy 377.596908 -397.84909) (xy 377.596908 -397.849344) (xy 377.596479 -397.873324)
			(xy 377.588974 -397.920693) (xy 377.574156 -397.966306) (xy 377.552389 -398.009041) (xy 377.524209 -398.047848)
			(xy 377.490308 -398.081772) (xy 377.45152 -398.10998) (xy 377.4088 -398.131776) (xy 377.363197 -398.146625)
			(xy 377.315833 -398.154162) (xy 377.291854 -398.154652) (xy 377.291346 -398.154652) (xy 377.267683 -398.154176)
			(xy 377.220924 -398.146872) (xy 377.175849 -398.132448) (xy 377.133537 -398.111248) (xy 377.094998 -398.083778)
			(xy 377.061154 -398.050697) (xy 377.032815 -398.012794) (xy 377.021344 -397.992092) (xy 377.02109 -397.99133)
			(xy 377.008136 -397.968978) (xy 377.00272 -397.960559) (xy 376.986844 -397.948397) (xy 376.967523 -397.943233)
			(xy 376.947696 -397.945854) (xy 376.938794 -397.950436) (xy 376.92965 -397.95577) (xy 376.923554 -397.964152)
			(xy 376.912634 -397.978058) (xy 376.886548 -398.001919) (xy 376.85652 -398.020579) (xy 376.823573 -398.0334)
			(xy 376.78883 -398.039945) (xy 376.771154 -398.040352) (xy 376.770646 -398.040352) (xy 376.75187 -398.039861)
			(xy 376.715038 -398.032549) (xy 376.680339 -398.018196) (xy 376.649103 -397.997354) (xy 376.622531 -397.970822)
			(xy 376.601641 -397.939618) (xy 376.587235 -397.90494) (xy 376.579867 -397.868119) (xy 376.579384 -397.849344)
			(xy 376.579838 -397.830229) (xy 376.587406 -397.792758) (xy 376.602271 -397.757538) (xy 376.623838 -397.725974)
			(xy 376.651247 -397.699326) (xy 376.683406 -397.678656) (xy 376.70105 -397.67129) (xy 376.71121 -397.667226)
			(xy 376.726704 -397.651478) (xy 376.755914 -397.568166) (xy 376.75911 -397.55758) (xy 376.757152 -397.535584)
			(xy 376.752104 -397.525748) (xy 376.623834 -397.304006) (xy 376.611896 -397.279876) (xy 376.607075 -397.270351)
			(xy 376.591289 -397.256021) (xy 376.571045 -397.249332) (xy 376.549829 -397.251438) (xy 376.531294 -397.261974)
			(xy 376.52452 -397.270224) (xy 376.513601 -397.284291) (xy 376.487457 -397.308464) (xy 376.45729 -397.327379)
			(xy 376.424143 -397.340381) (xy 376.389161 -397.347021) (xy 376.371358 -397.34744) (xy 376.37085 -397.34744)
			(xy 376.343164 -397.345408) (xy 376.34291 -397.345408) (xy 376.33344 -397.344463) (xy 376.314924 -397.348789)
			(xy 376.299272 -397.359587) (xy 376.293634 -397.367252) (xy 376.242072 -397.442944) (xy 376.237048 -397.451077)
			(xy 376.232882 -397.469721) (xy 376.23582 -397.488597) (xy 376.240294 -397.497046) (xy 376.355864 -397.696944)
			(xy 376.356118 -397.697452) (xy 376.356372 -397.697452) (xy 376.357642 -397.699992) (xy 376.369877 -397.722915)
			(xy 376.387196 -397.771902) (xy 376.395983 -397.823111) (xy 376.396504 -397.84909) (xy 376.396504 -397.849344)
			(xy 376.396078 -397.873337) (xy 376.388565 -397.92073) (xy 376.373731 -397.966365) (xy 376.351942 -398.009118)
			(xy 376.323733 -398.047937) (xy 376.2898 -398.081865) (xy 376.250977 -398.110067) (xy 376.208221 -398.13185)
			(xy 376.162583 -398.146676) (xy 376.115189 -398.154182) (xy 376.091196 -398.154652) (xy 376.067531 -398.154216)
			(xy 376.02077 -398.146905) (xy 375.975695 -398.132473) (xy 375.933382 -398.111266) (xy 375.894844 -398.083791)
			(xy 375.861002 -398.050704) (xy 375.832664 -398.012796) (xy 375.821194 -397.992092) (xy 375.82094 -397.99133)
			(xy 375.807986 -397.968978) (xy 375.802519 -397.960596) (xy 375.786662 -397.948434) (xy 375.767358 -397.943261)
			(xy 375.747543 -397.945865) (xy 375.738644 -397.950436) (xy 375.7295 -397.95577) (xy 375.723404 -397.964152)
			(xy 375.712456 -397.978034) (xy 375.686377 -398.001898) (xy 375.656356 -398.020561) (xy 375.623415 -398.033388)
			(xy 375.588678 -398.039941) (xy 375.571004 -398.040352) (xy 375.570496 -398.040352) (xy 375.551731 -398.039852)
			(xy 375.514923 -398.032531) (xy 375.48025 -398.01817) (xy 375.449043 -397.997322) (xy 375.422503 -397.970788)
			(xy 375.401649 -397.939586) (xy 375.387281 -397.904916) (xy 375.379952 -397.868109) (xy 375.379488 -397.849344)
			(xy 375.37995 -397.830248) (xy 375.387513 -397.792813) (xy 375.402346 -397.75762) (xy 375.423861 -397.726066)
			(xy 375.451204 -397.699403) (xy 375.48329 -397.67869) (xy 375.5009 -397.67129) (xy 375.51106 -397.667226)
			(xy 375.526554 -397.651478) (xy 375.555764 -397.568166) (xy 375.558954 -397.557579) (xy 375.556998 -397.535585)
			(xy 375.551954 -397.525748) (xy 375.423684 -397.304006) (xy 375.411746 -397.279876) (xy 375.406996 -397.27031)
			(xy 375.39119 -397.255974) (xy 375.370924 -397.249289) (xy 375.349691 -397.251407) (xy 375.331145 -397.261963)
			(xy 375.32437 -397.270224) (xy 375.313462 -397.284333) (xy 375.287268 -397.308532) (xy 375.257041 -397.327454)
			(xy 375.223829 -397.340442) (xy 375.188785 -397.347047) (xy 375.170954 -397.34744) (xy 375.170446 -397.34744)
			(xy 375.163566 -397.347433) (xy 375.149837 -397.346546) (xy 375.143014 -397.345662) (xy 375.128536 -397.343376)
			(xy 375.101866 -397.35506) (xy 375.042176 -397.442944) (xy 375.037152 -397.451077) (xy 375.032986 -397.469721)
			(xy 375.035924 -397.488597) (xy 375.040398 -397.497046) (xy 375.155968 -397.696944) (xy 375.156222 -397.697452)
			(xy 375.156476 -397.697452) (xy 375.157746 -397.699992) (xy 375.169981 -397.722915) (xy 375.1873 -397.771902)
			(xy 375.196087 -397.823111) (xy 375.196608 -397.84909) (xy 375.196608 -397.849344) (xy 375.196178 -397.873336)
			(xy 375.188665 -397.92073) (xy 375.173832 -397.966364) (xy 375.152043 -398.009117) (xy 375.123835 -398.047935)
			(xy 375.089902 -398.081863) (xy 375.051079 -398.110066) (xy 375.008324 -398.131849) (xy 374.962687 -398.146676)
			(xy 374.915292 -398.154181) (xy 374.8913 -398.154652) (xy 374.867636 -398.154213) (xy 374.820875 -398.146902)
			(xy 374.775799 -398.132471) (xy 374.733487 -398.111265) (xy 374.694949 -398.08379) (xy 374.661106 -398.050703)
			(xy 374.632768 -398.012796) (xy 374.621298 -397.992092) (xy 374.621044 -397.99133) (xy 374.60809 -397.968978)
			(xy 374.602619 -397.960599) (xy 374.586763 -397.948437) (xy 374.56746 -397.943263) (xy 374.547647 -397.945866)
			(xy 374.538748 -397.950436) (xy 374.529604 -397.95577) (xy 374.523508 -397.964152) (xy 374.512614 -397.978079)
			(xy 374.486522 -398.001939) (xy 374.456487 -398.020595) (xy 374.423534 -398.033411) (xy 374.388786 -398.039949)
			(xy 374.371108 -398.040352) (xy 374.3706 -398.040352) (xy 374.351835 -398.039848) (xy 374.315027 -398.032528)
			(xy 374.280354 -398.018168) (xy 374.249148 -397.997321) (xy 374.222607 -397.970786) (xy 374.201753 -397.939585)
			(xy 374.187385 -397.904915) (xy 374.180056 -397.868108) (xy 374.179592 -397.849344) (xy 374.180115 -397.830252)
			(xy 374.187673 -397.792824) (xy 374.202497 -397.757636) (xy 374.224 -397.726083) (xy 374.25133 -397.699417)
			(xy 374.283401 -397.678696) (xy 374.301004 -397.67129) (xy 374.311164 -397.667226) (xy 374.326658 -397.651478)
			(xy 374.355868 -397.568166) (xy 374.359058 -397.557579) (xy 374.357102 -397.535585) (xy 374.352058 -397.525748)
			(xy 374.223788 -397.304006) (xy 374.21185 -397.279876) (xy 374.207094 -397.270313) (xy 374.19129 -397.255978)
			(xy 374.171026 -397.249293) (xy 374.149794 -397.25141) (xy 374.131249 -397.261964) (xy 374.124474 -397.270224)
			(xy 374.113581 -397.284313) (xy 374.087431 -397.308484) (xy 374.057257 -397.327395) (xy 374.024104 -397.340392)
			(xy 373.989117 -397.347025) (xy 373.971312 -397.34744) (xy 373.970804 -397.34744) (xy 373.943118 -397.345408)
			(xy 373.942864 -397.345408) (xy 373.933396 -397.344426) (xy 373.914875 -397.348768) (xy 373.899224 -397.35958)
			(xy 373.893588 -397.367252) (xy 373.842026 -397.442944) (xy 373.836999 -397.451077) (xy 373.832829 -397.469721)
			(xy 373.835771 -397.488598) (xy 373.840248 -397.497046) (xy 373.955818 -397.696944) (xy 373.956072 -397.697452)
			(xy 373.956326 -397.697452) (xy 373.957596 -397.699992) (xy 373.969867 -397.722908) (xy 373.987274 -397.771886)
			(xy 373.996148 -397.823101) (xy 373.996712 -397.84909) (xy 373.996712 -397.849344) (xy 373.996279 -397.873324)
			(xy 373.988774 -397.920692) (xy 373.973957 -397.966305) (xy 373.95219 -398.00904) (xy 373.92401 -398.047847)
			(xy 373.89011 -398.081771) (xy 373.851323 -398.109978) (xy 373.808603 -398.131775) (xy 373.763 -398.146624)
			(xy 373.715637 -398.154162) (xy 373.691658 -398.154652) (xy 373.69115 -398.154652) (xy 373.667487 -398.154172)
			(xy 373.620728 -398.146869) (xy 373.575653 -398.132446) (xy 373.533341 -398.111246) (xy 373.494802 -398.083777)
			(xy 373.460959 -398.050696) (xy 373.432619 -398.012793) (xy 373.421148 -397.992092) (xy 373.420894 -397.99133)
			(xy 373.40794 -397.968978) (xy 373.40252 -397.960562) (xy 373.386645 -397.948399) (xy 373.367325 -397.943236)
			(xy 373.347499 -397.945855) (xy 373.338598 -397.950436) (xy 373.329454 -397.95577) (xy 373.323358 -397.964152)
			(xy 373.312436 -397.978056) (xy 373.28635 -398.001918) (xy 373.256323 -398.020577) (xy 373.223376 -398.033399)
			(xy 373.188634 -398.039945) (xy 373.170958 -398.040352) (xy 373.17045 -398.040352) (xy 373.151675 -398.039858)
			(xy 373.114843 -398.032546) (xy 373.080143 -398.018194) (xy 373.048907 -397.997352) (xy 373.022335 -397.97082)
			(xy 373.001445 -397.939617) (xy 372.987039 -397.904939) (xy 372.979671 -397.868119) (xy 372.979188 -397.849344)
			(xy 372.979639 -397.830229) (xy 372.987208 -397.792757) (xy 373.002073 -397.757537) (xy 373.02364 -397.725973)
			(xy 373.051051 -397.699325) (xy 373.08321 -397.678656) (xy 373.100854 -397.67129) (xy 373.111014 -397.667226)
			(xy 373.126508 -397.651478) (xy 373.155718 -397.568166) (xy 373.158914 -397.55758) (xy 373.156956 -397.535584)
			(xy 373.151908 -397.525748) (xy 373.023638 -397.304006) (xy 373.0117 -397.279876) (xy 373.006874 -397.270355)
			(xy 372.991089 -397.256025) (xy 372.970847 -397.249336) (xy 372.949632 -397.25144) (xy 372.931098 -397.261975)
			(xy 372.924324 -397.270224) (xy 372.913385 -397.284308) (xy 372.887199 -397.308509) (xy 372.856979 -397.327435)
			(xy 372.823775 -397.340429) (xy 372.788736 -397.347042) (xy 372.770908 -397.34744) (xy 372.7704 -397.34744)
			(xy 372.76352 -397.347438) (xy 372.74979 -397.346548) (xy 372.742968 -397.345662) (xy 372.72849 -397.343376)
			(xy 372.70182 -397.35506) (xy 372.64213 -397.442944) (xy 372.637103 -397.451076) (xy 372.632933 -397.469721)
			(xy 372.635874 -397.488598) (xy 372.640352 -397.497046) (xy 372.755922 -397.696944) (xy 372.756176 -397.697452)
			(xy 372.75643 -397.697452) (xy 372.7577 -397.699992) (xy 372.769971 -397.722908) (xy 372.787378 -397.771886)
			(xy 372.796252 -397.823101) (xy 372.796816 -397.84909) (xy 372.796816 -397.849344) (xy 372.796379 -397.873323)
			(xy 372.788875 -397.920691) (xy 372.774057 -397.966304) (xy 372.752291 -398.009039) (xy 372.724111 -398.047846)
			(xy 372.690212 -398.08177) (xy 372.651425 -398.109977) (xy 372.608705 -398.131773) (xy 372.563104 -398.146624)
			(xy 372.515741 -398.154162) (xy 372.491762 -398.154652) (xy 372.491254 -398.154652) (xy 372.467591 -398.154169)
			(xy 372.420832 -398.146867) (xy 372.375758 -398.132444) (xy 372.333445 -398.111245) (xy 372.294907 -398.083776)
			(xy 372.261063 -398.050696) (xy 372.232723 -398.012793) (xy 372.221252 -397.992092) (xy 372.220998 -397.99133)
			(xy 372.208044 -397.968978) (xy 372.20262 -397.960564) (xy 372.186747 -397.948402) (xy 372.167428 -397.943238)
			(xy 372.147603 -397.945856) (xy 372.138702 -397.950436) (xy 372.129558 -397.95577) (xy 372.123462 -397.964152)
			(xy 372.112538 -397.978054) (xy 372.086453 -398.001916) (xy 372.056425 -398.020576) (xy 372.023479 -398.033398)
			(xy 371.988738 -398.039945) (xy 371.971062 -398.040352) (xy 371.970554 -398.040352) (xy 371.951775 -398.039945)
			(xy 371.91494 -398.032616) (xy 371.880239 -398.018248) (xy 371.849004 -397.997393) (xy 371.822433 -397.970849)
			(xy 371.801545 -397.939636) (xy 371.787142 -397.90495) (xy 371.779775 -397.868122) (xy 371.779292 -397.849344)
			(xy 371.779741 -397.830229) (xy 371.78731 -397.792757) (xy 371.802175 -397.757536) (xy 371.823743 -397.725972)
			(xy 371.851154 -397.699324) (xy 371.883313 -397.678655) (xy 371.900958 -397.67129) (xy 371.911118 -397.667226)
			(xy 371.926612 -397.651478) (xy 371.955822 -397.568166) (xy 371.959017 -397.55758) (xy 371.95706 -397.535584)
			(xy 371.952012 -397.525748) (xy 371.823742 -397.304006) (xy 371.811804 -397.279876) (xy 371.806972 -397.270358)
			(xy 371.791189 -397.256028) (xy 371.770948 -397.249339) (xy 371.749735 -397.251443) (xy 371.731202 -397.261976)
			(xy 371.724428 -397.270224) (xy 371.713487 -397.284306) (xy 371.687301 -397.308507) (xy 371.657082 -397.327433)
			(xy 371.623878 -397.340428) (xy 371.58884 -397.347042) (xy 371.571012 -397.34744) (xy 371.570504 -397.34744)
			(xy 371.563624 -397.347438) (xy 371.549894 -397.346547) (xy 371.543072 -397.345662) (xy 371.528594 -397.343376)
			(xy 371.501924 -397.35506) (xy 371.442234 -397.442944) (xy 371.437207 -397.451076) (xy 371.433036 -397.469721)
			(xy 371.435978 -397.488598) (xy 371.440456 -397.497046) (xy 371.556026 -397.696944) (xy 371.55628 -397.697452)
			(xy 371.556534 -397.697452) (xy 371.557804 -397.699992) (xy 371.570075 -397.722908) (xy 371.587482 -397.771886)
			(xy 371.596356 -397.823101) (xy 371.59692 -397.84909) (xy 371.59692 -397.849344) (xy 371.596479 -397.873323)
			(xy 371.588975 -397.920691) (xy 371.574157 -397.966303) (xy 371.552392 -398.009038) (xy 371.524213 -398.047844)
			(xy 371.490313 -398.081768) (xy 371.451527 -398.109975) (xy 371.408808 -398.131772) (xy 371.363207 -398.146623)
			(xy 371.315845 -398.154162) (xy 371.291866 -398.154652) (xy 371.291358 -398.154652) (xy 371.267695 -398.154166)
			(xy 371.220936 -398.146864) (xy 371.175862 -398.132442) (xy 371.13355 -398.111243) (xy 371.095011 -398.083775)
			(xy 371.061167 -398.050695) (xy 371.032827 -398.012793) (xy 371.021356 -397.992092) (xy 371.021102 -397.99133)
			(xy 371.008148 -397.968978) (xy 371.00272 -397.960567) (xy 370.986848 -397.948405) (xy 370.967531 -397.94324)
			(xy 370.947707 -397.945857) (xy 370.938806 -397.950436) (xy 370.929662 -397.95577) (xy 370.923566 -397.964152)
			(xy 370.91264 -397.978052) (xy 370.886555 -398.001914) (xy 370.856528 -398.020574) (xy 370.823583 -398.033397)
			(xy 370.788842 -398.039944) (xy 370.771166 -398.040352) (xy 370.770658 -398.040352) (xy 370.751879 -398.039941)
			(xy 370.715044 -398.032613) (xy 370.680343 -398.018246) (xy 370.649109 -397.997391) (xy 370.622538 -397.970848)
			(xy 370.60165 -397.939635) (xy 370.587246 -397.90495) (xy 370.579879 -397.868122) (xy 370.579396 -397.849344)
			(xy 370.579842 -397.830229) (xy 370.587411 -397.792756) (xy 370.602277 -397.757536) (xy 370.623845 -397.725972)
			(xy 370.651257 -397.699324) (xy 370.683417 -397.678655) (xy 370.701062 -397.67129) (xy 370.711222 -397.667226)
			(xy 370.726716 -397.651478) (xy 370.755926 -397.568166) (xy 370.759121 -397.55758) (xy 370.757163 -397.535584)
			(xy 370.752116 -397.525748) (xy 370.623846 -397.304006) (xy 370.611908 -397.279876) (xy 370.607071 -397.270361)
			(xy 370.591289 -397.256032) (xy 370.57105 -397.249343) (xy 370.549838 -397.251445) (xy 370.531306 -397.261977)
			(xy 370.524532 -397.270224) (xy 370.513606 -397.284285) (xy 370.487464 -397.308459) (xy 370.457299 -397.327375)
			(xy 370.424153 -397.340378) (xy 370.389172 -397.34702) (xy 370.37137 -397.34744) (xy 370.370862 -397.34744)
			(xy 370.350847 -397.346849) (xy 370.311694 -397.33852) (xy 370.275127 -397.322233) (xy 370.242745 -397.2987)
			(xy 370.215963 -397.26895) (xy 370.19595 -397.234282) (xy 370.183582 -397.196211) (xy 370.179398 -397.1564)
			(xy 354.67116 -397.1564) (xy 354.983542 -397.696944) (xy 354.983796 -397.697452) (xy 354.98405 -397.697452)
			(xy 354.98532 -397.699992) (xy 354.997593 -397.722907) (xy 355.014998 -397.771885) (xy 355.023872 -397.823101)
			(xy 355.024436 -397.84909) (xy 355.024436 -397.849344) (xy 355.023979 -397.873322) (xy 355.016475 -397.920688)
			(xy 355.001659 -397.966299) (xy 354.979895 -398.009033) (xy 354.951717 -398.047839) (xy 354.91782 -398.081762)
			(xy 354.879036 -398.10997) (xy 354.836319 -398.131768) (xy 354.79072 -398.14662) (xy 354.74336 -398.15416)
			(xy 354.719382 -398.154652) (xy 354.718874 -398.154652) (xy 354.695212 -398.154153) (xy 354.648453 -398.146854)
			(xy 354.603379 -398.132433) (xy 354.561067 -398.111237) (xy 354.522528 -398.083771) (xy 354.488684 -398.050693)
			(xy 354.460343 -398.012792) (xy 354.448872 -397.992092) (xy 354.448618 -397.99133) (xy 354.435664 -397.968978)
			(xy 354.43022 -397.96058) (xy 354.414354 -397.948418) (xy 354.395042 -397.943249) (xy 354.375222 -397.945861)
			(xy 354.366322 -397.950436) (xy 354.357178 -397.95577) (xy 354.351082 -397.964152) (xy 354.340146 -397.978044)
			(xy 354.314064 -398.001907) (xy 354.28404 -398.020569) (xy 354.251096 -398.033393) (xy 354.216357 -398.039943)
			(xy 354.198682 -398.040352) (xy 354.198174 -398.040352) (xy 354.179396 -398.039927) (xy 354.142561 -398.032602)
			(xy 354.107861 -398.018237) (xy 354.076626 -397.997384) (xy 354.050054 -397.970843) (xy 354.029166 -397.939632)
			(xy 354.014762 -397.904948) (xy 354.007395 -397.868121) (xy 354.006912 -397.849344) (xy 354.007348 -397.830228)
			(xy 354.014918 -397.792755) (xy 354.029785 -397.757533) (xy 354.051355 -397.725969) (xy 354.078769 -397.699321)
			(xy 354.110932 -397.678654) (xy 354.128578 -397.67129) (xy 354.138738 -397.667226) (xy 354.154232 -397.651478)
			(xy 354.183442 -397.568166) (xy 354.186635 -397.55758) (xy 354.184678 -397.535585) (xy 354.179632 -397.525748)
			(xy 354.051362 -397.304006) (xy 354.039424 -397.279876) (xy 354.034564 -397.270374) (xy 354.018789 -397.256047)
			(xy 353.998557 -397.249356) (xy 353.97735 -397.251455) (xy 353.958821 -397.26198) (xy 353.952048 -397.270224)
			(xy 353.941113 -397.284278) (xy 353.914973 -397.308452) (xy 353.88481 -397.327369) (xy 353.851666 -397.340374)
			(xy 353.816688 -397.347018) (xy 353.798886 -397.34744) (xy 353.798378 -397.34744) (xy 353.770692 -397.345408)
			(xy 353.770438 -397.345408) (xy 353.760971 -397.344405) (xy 353.742448 -397.348756) (xy 353.726797 -397.359577)
			(xy 353.721162 -397.367252) (xy 353.6696 -397.442944) (xy 353.664574 -397.451077) (xy 353.660406 -397.469721)
			(xy 353.663346 -397.488598) (xy 353.667822 -397.497046) (xy 353.783392 -397.696944) (xy 353.783646 -397.697452)
			(xy 353.7839 -397.697452) (xy 353.78517 -397.699992) (xy 353.797399 -397.722918) (xy 353.814722 -397.771903)
			(xy 353.82351 -397.823111) (xy 353.824032 -397.84909) (xy 353.824032 -397.849344) (xy 353.823578 -397.873335)
			(xy 353.816066 -397.920726) (xy 353.801234 -397.966359) (xy 353.779447 -398.00911) (xy 353.751242 -398.047927)
			(xy 353.717312 -398.081855) (xy 353.678493 -398.110058) (xy 353.63574 -398.131842) (xy 353.590107 -398.146671)
			(xy 353.542715 -398.15418) (xy 353.518724 -398.154652) (xy 353.49506 -398.154193) (xy 353.4483 -398.146886)
			(xy 353.403225 -398.132459) (xy 353.360913 -398.111256) (xy 353.322374 -398.083784) (xy 353.288531 -398.0507)
			(xy 353.260193 -398.012795) (xy 353.248722 -397.992092) (xy 353.248468 -397.99133) (xy 353.235514 -397.968978)
			(xy 353.230121 -397.960542) (xy 353.214236 -397.94838) (xy 353.194907 -397.943221) (xy 353.175075 -397.94585)
			(xy 353.166172 -397.950436) (xy 353.157028 -397.95577) (xy 353.150932 -397.964152) (xy 353.140025 -397.978068)
			(xy 353.113935 -398.001929) (xy 353.083904 -398.020587) (xy 353.050954 -398.033405) (xy 353.016209 -398.039947)
			(xy 352.998532 -398.040352) (xy 352.998024 -398.040352) (xy 352.97926 -398.039827) (xy 352.942453 -398.03251)
			(xy 352.90778 -398.018155) (xy 352.876573 -397.997311) (xy 352.850033 -397.970779) (xy 352.829178 -397.93958)
			(xy 352.814809 -397.904912) (xy 352.80748 -397.868108) (xy 352.807016 -397.849344) (xy 352.807524 -397.830251)
			(xy 352.815083 -397.792822) (xy 352.829909 -397.757632) (xy 352.851415 -397.726079) (xy 352.878748 -397.699414)
			(xy 352.910824 -397.678694) (xy 352.928428 -397.67129) (xy 352.938588 -397.667226) (xy 352.954082 -397.651478)
			(xy 352.983292 -397.568166) (xy 352.98649 -397.557581) (xy 352.984532 -397.535584) (xy 352.979482 -397.525748)
			(xy 352.851212 -397.304006) (xy 352.839274 -397.279876) (xy 352.834485 -397.270333) (xy 352.81869 -397.256)
			(xy 352.798436 -397.249313) (xy 352.777212 -397.251424) (xy 352.758672 -397.261969) (xy 352.751898 -397.270224)
			(xy 352.740974 -397.28432) (xy 352.714784 -397.30852) (xy 352.684561 -397.327444) (xy 352.651353 -397.340436)
			(xy 352.616312 -397.347044) (xy 352.598482 -397.34744) (xy 352.597974 -397.34744) (xy 352.591094 -397.347441)
			(xy 352.577364 -397.346548) (xy 352.570542 -397.345662) (xy 352.556064 -397.343376) (xy 352.529394 -397.35506)
			(xy 352.469704 -397.442944) (xy 352.464678 -397.451077) (xy 352.46051 -397.469721) (xy 352.46345 -397.488598)
			(xy 352.467926 -397.497046) (xy 352.583496 -397.696944) (xy 352.58375 -397.697452) (xy 352.584004 -397.697452)
			(xy 352.585274 -397.699992) (xy 352.597504 -397.722918) (xy 352.614826 -397.771903) (xy 352.623614 -397.823111)
			(xy 352.624136 -397.84909) (xy 352.624136 -397.849344) (xy 352.623678 -397.873335) (xy 352.616166 -397.920726)
			(xy 352.601335 -397.966358) (xy 352.579548 -398.009109) (xy 352.551343 -398.047926) (xy 352.517413 -398.081853)
			(xy 352.478595 -398.110056) (xy 352.435843 -398.131841) (xy 352.39021 -398.14667) (xy 352.342819 -398.154179)
			(xy 352.318828 -398.154652) (xy 352.295164 -398.15419) (xy 352.248404 -398.146884) (xy 352.203329 -398.132457)
			(xy 352.161017 -398.111254) (xy 352.122479 -398.083783) (xy 352.088636 -398.050699) (xy 352.060297 -398.012794)
			(xy 352.048826 -397.992092) (xy 352.048572 -397.99133) (xy 352.035618 -397.968978) (xy 352.030221 -397.960545)
			(xy 352.014338 -397.948383) (xy 351.99501 -397.943223) (xy 351.975179 -397.945851) (xy 351.966276 -397.950436)
			(xy 351.957132 -397.95577) (xy 351.951036 -397.964152) (xy 351.940127 -397.978066) (xy 351.914038 -398.001927)
			(xy 351.884007 -398.020585) (xy 351.851057 -398.033404) (xy 351.816313 -398.039947) (xy 351.798636 -398.040352)
			(xy 351.798128 -398.040352) (xy 351.779364 -398.039823) (xy 351.742557 -398.032508) (xy 351.707884 -398.018152)
			(xy 351.676678 -397.997309) (xy 351.650137 -397.970778) (xy 351.629282 -397.93958) (xy 351.614913 -397.904912)
			(xy 351.607584 -397.868107) (xy 351.60712 -397.849344) (xy 351.607625 -397.830251) (xy 351.615184 -397.792821)
			(xy 351.630011 -397.757632) (xy 351.651518 -397.726078) (xy 351.678851 -397.699413) (xy 351.710927 -397.678694)
			(xy 351.728532 -397.67129) (xy 351.738692 -397.667226) (xy 351.754186 -397.651478) (xy 351.783396 -397.568166)
			(xy 351.786594 -397.55758) (xy 351.784635 -397.535584) (xy 351.779586 -397.525748) (xy 351.651316 -397.304006)
			(xy 351.639378 -397.279876) (xy 351.634583 -397.270337) (xy 351.618789 -397.256004) (xy 351.598538 -397.249317)
			(xy 351.577315 -397.251427) (xy 351.558776 -397.26197) (xy 351.552002 -397.270224) (xy 351.541093 -397.284299)
			(xy 351.514947 -397.308472) (xy 351.484777 -397.327385) (xy 351.451627 -397.340385) (xy 351.416643 -397.347023)
			(xy 351.39884 -397.34744) (xy 351.398332 -397.34744) (xy 351.370646 -397.345408) (xy 351.370392 -397.345408)
			(xy 351.360923 -397.344448) (xy 351.342405 -397.348781) (xy 351.326754 -397.359584) (xy 351.321116 -397.367252)
			(xy 351.269554 -397.442944) (xy 351.264531 -397.451077) (xy 351.260367 -397.469721) (xy 351.263304 -397.488597)
			(xy 351.267776 -397.497046) (xy 351.383346 -397.696944) (xy 351.3836 -397.697452) (xy 351.383854 -397.697452)
			(xy 351.385124 -397.699992) (xy 351.397397 -397.722907) (xy 351.414802 -397.771885) (xy 351.423676 -397.823101)
			(xy 351.42424 -397.84909) (xy 351.42424 -397.849344) (xy 351.423779 -397.873322) (xy 351.416275 -397.920688)
			(xy 351.401459 -397.966298) (xy 351.379695 -398.009032) (xy 351.351518 -398.047837) (xy 351.317622 -398.081761)
			(xy 351.278838 -398.109969) (xy 351.236122 -398.131767) (xy 351.190524 -398.146619) (xy 351.143164 -398.15416)
			(xy 351.119186 -398.154652) (xy 351.118678 -398.154652) (xy 351.095013 -398.15423) (xy 351.048251 -398.146916)
			(xy 351.003175 -398.132482) (xy 350.960863 -398.111273) (xy 350.922325 -398.083796) (xy 350.888483 -398.050707)
			(xy 350.860146 -398.012797) (xy 350.848676 -397.992092) (xy 350.848422 -397.99133) (xy 350.835468 -397.968978)
			(xy 350.83002 -397.960583) (xy 350.814155 -397.94842) (xy 350.794845 -397.943251) (xy 350.775026 -397.945861)
			(xy 350.766126 -397.950436) (xy 350.756982 -397.95577) (xy 350.750886 -397.964152) (xy 350.739948 -397.978042)
			(xy 350.713867 -398.001905) (xy 350.683843 -398.020567) (xy 350.6509 -398.033392) (xy 350.616161 -398.039943)
			(xy 350.598486 -398.040352) (xy 350.597978 -398.040352) (xy 350.5792 -398.039923) (xy 350.542365 -398.032599)
			(xy 350.507665 -398.018235) (xy 350.47643 -397.997383) (xy 350.449859 -397.970842) (xy 350.42897 -397.939631)
			(xy 350.414566 -397.904947) (xy 350.407199 -397.868121) (xy 350.406716 -397.849344) (xy 350.40715 -397.830228)
			(xy 350.41472 -397.792754) (xy 350.429587 -397.757533) (xy 350.451158 -397.725968) (xy 350.478573 -397.699321)
			(xy 350.510736 -397.678654) (xy 350.528382 -397.67129) (xy 350.538542 -397.667226) (xy 350.554036 -397.651478)
			(xy 350.583246 -397.568166) (xy 350.586439 -397.55758) (xy 350.584482 -397.535584) (xy 350.579436 -397.525748)
			(xy 350.451166 -397.304006) (xy 350.439228 -397.279876) (xy 350.434362 -397.270377) (xy 350.418589 -397.256051)
			(xy 350.398358 -397.24936) (xy 350.377153 -397.251457) (xy 350.358625 -397.261981) (xy 350.351852 -397.270224)
			(xy 350.340897 -397.284295) (xy 350.314715 -397.308496) (xy 350.284499 -397.327425) (xy 350.251298 -397.340422)
			(xy 350.216263 -397.347039) (xy 350.198436 -397.34744) (xy 350.197928 -397.34744) (xy 350.191048 -397.347435)
			(xy 350.177318 -397.346546) (xy 350.170496 -397.345662) (xy 350.156018 -397.343376) (xy 350.129348 -397.35506)
			(xy 350.069658 -397.442944) (xy 350.064635 -397.451077) (xy 350.06047 -397.469721) (xy 350.063407 -397.488597)
			(xy 350.06788 -397.497046) (xy 350.18345 -397.696944) (xy 350.183704 -397.697452) (xy 350.183958 -397.697452)
			(xy 350.185228 -397.699992) (xy 350.197501 -397.722907) (xy 350.214906 -397.771885) (xy 350.22378 -397.823101)
			(xy 350.224344 -397.84909) (xy 350.224344 -397.849344) (xy 350.223879 -397.873322) (xy 350.216376 -397.920687)
			(xy 350.20156 -397.966297) (xy 350.179796 -398.00903) (xy 350.15162 -398.047836) (xy 350.117723 -398.08176)
			(xy 350.07894 -398.109967) (xy 350.036225 -398.131765) (xy 349.990627 -398.146618) (xy 349.943268 -398.15416)
			(xy 349.91929 -398.154652) (xy 349.918782 -398.154652) (xy 349.895117 -398.154227) (xy 349.848355 -398.146914)
			(xy 349.80328 -398.13248) (xy 349.760967 -398.111272) (xy 349.722429 -398.083795) (xy 349.688587 -398.050706)
			(xy 349.66025 -398.012797) (xy 349.64878 -397.992092) (xy 349.648526 -397.99133) (xy 349.635572 -397.968978)
			(xy 349.63012 -397.960586) (xy 349.614257 -397.948423) (xy 349.594948 -397.943254) (xy 349.57513 -397.945862)
			(xy 349.56623 -397.950436) (xy 349.557086 -397.95577) (xy 349.55099 -397.964152) (xy 349.54005 -397.97804)
			(xy 349.513969 -398.001904) (xy 349.483946 -398.020566) (xy 349.451003 -398.033391) (xy 349.416265 -398.039942)
			(xy 349.39859 -398.040352) (xy 349.398082 -398.040352) (xy 349.379304 -398.03992) (xy 349.34247 -398.032596)
			(xy 349.307769 -398.018233) (xy 349.276534 -397.997381) (xy 349.249963 -397.970841) (xy 349.229074 -397.93963)
			(xy 349.21467 -397.904947) (xy 349.207303 -397.868121) (xy 349.20682 -397.849344) (xy 349.207251 -397.830228)
			(xy 349.214822 -397.792754) (xy 349.229689 -397.757532) (xy 349.251261 -397.725968) (xy 349.278676 -397.699321)
			(xy 349.31084 -397.678654) (xy 349.328486 -397.67129) (xy 349.338646 -397.667226) (xy 349.35414 -397.651478)
			(xy 349.38335 -397.568166) (xy 349.386542 -397.55758) (xy 349.384586 -397.535585) (xy 349.37954 -397.525748)
			(xy 349.25127 -397.304006) (xy 349.239332 -397.279876) (xy 349.234461 -397.270381) (xy 349.218689 -397.256054)
			(xy 349.19846 -397.249363) (xy 349.177256 -397.251459) (xy 349.158729 -397.261982) (xy 349.151956 -397.270224)
			(xy 349.140999 -397.284293) (xy 349.114817 -397.308495) (xy 349.084602 -397.327423) (xy 349.051402 -397.340421)
			(xy 349.016367 -397.347039) (xy 348.99854 -397.34744) (xy 348.998032 -397.34744) (xy 348.991152 -397.347435)
			(xy 348.977423 -397.346546) (xy 348.9706 -397.345662) (xy 348.956122 -397.343376) (xy 348.929452 -397.35506)
			(xy 348.869762 -397.442944) (xy 348.864738 -397.451077) (xy 348.860573 -397.469721) (xy 348.863511 -397.488597)
			(xy 348.867984 -397.497046) (xy 348.983554 -397.696944) (xy 348.983808 -397.697452) (xy 348.984062 -397.697452)
			(xy 348.985332 -397.699992) (xy 348.997606 -397.722907) (xy 349.015011 -397.771885) (xy 349.023884 -397.823101)
			(xy 349.024448 -397.84909) (xy 349.024448 -397.849344) (xy 349.023979 -397.873322) (xy 349.016476 -397.920687)
			(xy 349.00166 -397.966296) (xy 348.979897 -398.009029) (xy 348.951721 -398.047835) (xy 348.917825 -398.081758)
			(xy 348.879043 -398.109966) (xy 348.836328 -398.131764) (xy 348.79073 -398.146617) (xy 348.743371 -398.154159)
			(xy 348.719394 -398.154652) (xy 348.718886 -398.154652) (xy 348.695221 -398.154224) (xy 348.64846 -398.146911)
			(xy 348.603384 -398.132478) (xy 348.561072 -398.11127) (xy 348.522534 -398.083794) (xy 348.488692 -398.050705)
			(xy 348.460354 -398.012796) (xy 348.448884 -397.992092) (xy 348.44863 -397.99133) (xy 348.435676 -397.968978)
			(xy 348.43022 -397.960589) (xy 348.414358 -397.948426) (xy 348.395051 -397.943256) (xy 348.375234 -397.945863)
			(xy 348.366334 -397.950436) (xy 348.35719 -397.95577) (xy 348.351094 -397.964152) (xy 348.340152 -397.978039)
			(xy 348.314071 -398.001902) (xy 348.284048 -398.020564) (xy 348.251107 -398.03339) (xy 348.216369 -398.039942)
			(xy 348.198694 -398.040352) (xy 348.198186 -398.040352) (xy 348.179408 -398.039916) (xy 348.142574 -398.032593)
			(xy 348.107874 -398.01823) (xy 348.076639 -397.997379) (xy 348.050067 -397.97084) (xy 348.029178 -397.93963)
			(xy 348.014774 -397.904947) (xy 348.007407 -397.868121) (xy 348.006924 -397.849344) (xy 348.007353 -397.830228)
			(xy 348.014923 -397.792753) (xy 348.029791 -397.757531) (xy 348.051363 -397.725967) (xy 348.078779 -397.69932)
			(xy 348.110943 -397.678654) (xy 348.12859 -397.67129) (xy 348.13875 -397.667226) (xy 348.154244 -397.651478)
			(xy 348.183454 -397.568166) (xy 348.186646 -397.55758) (xy 348.184689 -397.535585) (xy 348.179644 -397.525748)
			(xy 348.051374 -397.304006) (xy 348.039436 -397.279876) (xy 348.034559 -397.270384) (xy 348.018789 -397.256059)
			(xy 347.998562 -397.249367) (xy 347.977359 -397.251462) (xy 347.958833 -397.261983) (xy 347.95206 -397.270224)
			(xy 347.941118 -397.284272) (xy 347.91498 -397.308447) (xy 347.884819 -397.327365) (xy 347.851676 -397.340371)
			(xy 347.816699 -397.347017) (xy 347.798898 -397.34744) (xy 347.79839 -397.34744) (xy 347.770704 -397.345408)
			(xy 347.77045 -397.345408) (xy 347.760982 -397.344415) (xy 347.74246 -397.348762) (xy 347.72681 -397.359578)
			(xy 347.721174 -397.367252) (xy 347.669612 -397.442944) (xy 347.664586 -397.451077) (xy 347.660417 -397.469721)
			(xy 347.663358 -397.488598) (xy 347.667834 -397.497046) (xy 347.783404 -397.696944) (xy 347.783658 -397.697452)
			(xy 347.783912 -397.697452) (xy 347.785182 -397.699992) (xy 347.797412 -397.722918) (xy 347.814734 -397.771903)
			(xy 347.823522 -397.823111) (xy 347.824044 -397.84909) (xy 347.824044 -397.849344) (xy 347.823578 -397.873335)
			(xy 347.816067 -397.920724) (xy 347.801235 -397.966356) (xy 347.779449 -398.009106) (xy 347.751245 -398.047923)
			(xy 347.717317 -398.08185) (xy 347.678499 -398.110054) (xy 347.635749 -398.131838) (xy 347.590117 -398.146668)
			(xy 347.542727 -398.154179) (xy 347.518736 -398.154652) (xy 347.495073 -398.154184) (xy 347.448313 -398.146878)
			(xy 347.403238 -398.132453) (xy 347.360926 -398.111251) (xy 347.322387 -398.083781) (xy 347.288544 -398.050698)
			(xy 347.260205 -398.012794) (xy 347.248734 -397.992092) (xy 347.24848 -397.99133) (xy 347.235526 -397.968978)
			(xy 347.230121 -397.960551) (xy 347.21424 -397.948389) (xy 347.194916 -397.943228) (xy 347.175086 -397.945852)
			(xy 347.166184 -397.950436) (xy 347.15704 -397.95577) (xy 347.150944 -397.964152) (xy 347.14003 -397.978062)
			(xy 347.113942 -398.001924) (xy 347.083912 -398.020582) (xy 347.050964 -398.033402) (xy 347.016221 -398.039946)
			(xy 346.998544 -398.040352) (xy 346.998036 -398.040352) (xy 346.979273 -398.039816) (xy 346.942466 -398.032502)
			(xy 346.907793 -398.018148) (xy 346.876586 -397.997306) (xy 346.850045 -397.970776) (xy 346.82919 -397.939578)
			(xy 346.814821 -397.904911) (xy 346.807492 -397.868107) (xy 346.807028 -397.849344) (xy 346.807528 -397.830251)
			(xy 346.815088 -397.79282) (xy 346.829915 -397.75763) (xy 346.851423 -397.726077) (xy 346.878758 -397.699412)
			(xy 346.910835 -397.678693) (xy 346.92844 -397.67129) (xy 346.9386 -397.667226) (xy 346.954094 -397.651478)
			(xy 346.983304 -397.568166) (xy 346.986501 -397.55758) (xy 346.984543 -397.535584) (xy 346.979494 -397.525748)
			(xy 346.851224 -397.304006) (xy 346.839286 -397.279876) (xy 346.834479 -397.270343) (xy 346.818689 -397.256012)
			(xy 346.798441 -397.249324) (xy 346.777221 -397.251432) (xy 346.758684 -397.261972) (xy 346.75191 -397.270224)
			(xy 346.740979 -397.284314) (xy 346.714791 -397.308515) (xy 346.684569 -397.32744) (xy 346.651363 -397.340433)
			(xy 346.616323 -397.347043) (xy 346.598494 -397.34744) (xy 346.597986 -397.34744) (xy 346.591106 -397.34744)
			(xy 346.577376 -397.346548) (xy 346.570554 -397.345662) (xy 346.556076 -397.343376) (xy 346.529406 -397.35506)
			(xy 346.469716 -397.442944) (xy 346.46469 -397.451077) (xy 346.460521 -397.469721) (xy 346.463461 -397.488598)
			(xy 346.467938 -397.497046) (xy 346.583508 -397.696944) (xy 346.583762 -397.697452) (xy 346.584016 -397.697452)
			(xy 346.585286 -397.699992) (xy 346.597517 -397.722917) (xy 346.614838 -397.771902) (xy 346.623626 -397.823111)
			(xy 346.624148 -397.84909) (xy 346.624148 -397.849344) (xy 346.623678 -397.873334) (xy 346.616167 -397.920724)
			(xy 346.601336 -397.966355) (xy 346.57955 -398.009105) (xy 346.551346 -398.047922) (xy 346.517418 -398.081849)
			(xy 346.478602 -398.110052) (xy 346.435851 -398.131837) (xy 346.39022 -398.146668) (xy 346.34283 -398.154178)
			(xy 346.31884 -398.154652) (xy 346.295177 -398.15418) (xy 346.248417 -398.146876) (xy 346.203342 -398.132451)
			(xy 346.16103 -398.11125) (xy 346.122492 -398.08378) (xy 346.088648 -398.050698) (xy 346.060309 -398.012794)
			(xy 346.048838 -397.992092) (xy 346.048584 -397.99133) (xy 346.03563 -397.968978) (xy 346.030221 -397.960554)
			(xy 346.014342 -397.948392) (xy 345.995018 -397.94323) (xy 345.97519 -397.945853) (xy 345.966288 -397.950436)
			(xy 345.957144 -397.95577) (xy 345.951048 -397.964152) (xy 345.940132 -397.97806) (xy 345.914045 -398.001922)
			(xy 345.884015 -398.020581) (xy 345.851068 -398.033401) (xy 345.816325 -398.039946) (xy 345.798648 -398.040352)
			(xy 345.79814 -398.040352) (xy 345.779377 -398.039812) (xy 345.74257 -398.032499) (xy 345.707897 -398.018146)
			(xy 345.67669 -397.997304) (xy 345.650149 -397.970775) (xy 345.629294 -397.939577) (xy 345.614925 -397.904911)
			(xy 345.607596 -397.868107) (xy 345.607132 -397.849344) (xy 345.60763 -397.830251) (xy 345.615189 -397.79282)
			(xy 345.630017 -397.75763) (xy 345.651526 -397.726076) (xy 345.678861 -397.699411) (xy 345.710938 -397.678693)
			(xy 345.728544 -397.67129) (xy 345.738704 -397.667226) (xy 345.754198 -397.651478) (xy 345.783408 -397.568166)
			(xy 345.786605 -397.55758) (xy 345.784647 -397.535584) (xy 345.779598 -397.525748) (xy 345.651328 -397.304006)
			(xy 345.63939 -397.279876) (xy 345.634578 -397.270346) (xy 345.618789 -397.256015) (xy 345.598543 -397.249327)
			(xy 345.577324 -397.251434) (xy 345.558788 -397.261973) (xy 345.552014 -397.270224) (xy 345.541098 -397.284294)
			(xy 345.514954 -397.308467) (xy 345.484786 -397.327381) (xy 345.451638 -397.340383) (xy 345.416655 -397.347022)
			(xy 345.398852 -397.34744) (xy 345.398344 -397.34744) (xy 345.370658 -397.345408) (xy 345.370404 -397.345408)
			(xy 345.360934 -397.344458) (xy 345.342417 -397.348786) (xy 345.326766 -397.359586) (xy 345.321128 -397.367252)
			(xy 345.269566 -397.442944) (xy 345.264542 -397.451077) (xy 345.260377 -397.469721) (xy 345.263315 -397.488597)
			(xy 345.267788 -397.497046) (xy 345.383358 -397.696944) (xy 345.383612 -397.697452) (xy 345.383866 -397.697452)
			(xy 345.385136 -397.699992) (xy 345.39741 -397.722906) (xy 345.414815 -397.771885) (xy 345.423688 -397.823101)
			(xy 345.424252 -397.84909) (xy 345.424252 -397.849344) (xy 345.423779 -397.873322) (xy 345.416276 -397.920686)
			(xy 345.401461 -397.966295) (xy 345.379698 -398.009028) (xy 345.351522 -398.047833) (xy 345.317627 -398.081757)
			(xy 345.278845 -398.109965) (xy 345.23613 -398.131763) (xy 345.190533 -398.146616) (xy 345.143175 -398.154159)
			(xy 345.119198 -398.154652) (xy 345.11869 -398.154652) (xy 345.095025 -398.154221) (xy 345.048264 -398.146909)
			(xy 345.003188 -398.132476) (xy 344.960876 -398.111269) (xy 344.922338 -398.083793) (xy 344.888496 -398.050705)
			(xy 344.860158 -398.012796) (xy 344.848688 -397.992092) (xy 344.848434 -397.99133) (xy 344.83548 -397.968978)
			(xy 344.83002 -397.960592) (xy 344.814159 -397.948429) (xy 344.794853 -397.943258) (xy 344.775037 -397.945864)
			(xy 344.766138 -397.950436) (xy 344.756994 -397.95577) (xy 344.750898 -397.964152) (xy 344.739953 -397.978037)
			(xy 344.713873 -398.0019) (xy 344.683851 -398.020563) (xy 344.65091 -398.033389) (xy 344.616172 -398.039941)
			(xy 344.598498 -398.040352) (xy 344.59799 -398.040352) (xy 344.579213 -398.039912) (xy 344.542378 -398.03259)
			(xy 344.507678 -398.018228) (xy 344.476443 -397.997377) (xy 344.449872 -397.970838) (xy 344.428983 -397.939629)
			(xy 344.414579 -397.904946) (xy 344.407211 -397.868121) (xy 344.406728 -397.849344) (xy 344.407154 -397.830228)
			(xy 344.414725 -397.792753) (xy 344.429593 -397.75753) (xy 344.451166 -397.725966) (xy 344.478582 -397.699319)
			(xy 344.510747 -397.678654) (xy 344.528394 -397.67129) (xy 344.538554 -397.667226) (xy 344.554048 -397.651478)
			(xy 344.583258 -397.568166) (xy 344.586449 -397.557579) (xy 344.584493 -397.535585) (xy 344.579448 -397.525748)
			(xy 344.451178 -397.304006) (xy 344.43924 -397.279876) (xy 344.434357 -397.270388) (xy 344.418589 -397.256062)
			(xy 344.398363 -397.249371) (xy 344.377162 -397.251465) (xy 344.358637 -397.261984) (xy 344.351864 -397.270224)
			(xy 344.340902 -397.284289) (xy 344.314722 -397.308491) (xy 344.284508 -397.32742) (xy 344.251309 -397.340419)
			(xy 344.216275 -397.347038) (xy 344.198448 -397.34744) (xy 344.19794 -397.34744) (xy 344.19106 -397.347434)
			(xy 344.177331 -397.346546) (xy 344.170508 -397.345662) (xy 344.15603 -397.343376) (xy 344.12936 -397.35506)
			(xy 344.06967 -397.442944) (xy 344.064646 -397.451077) (xy 344.06048 -397.469721) (xy 344.063418 -397.488597)
			(xy 344.067892 -397.497046) (xy 344.183462 -397.696944) (xy 344.183716 -397.697452) (xy 344.18397 -397.697452)
			(xy 344.18524 -397.699992) (xy 344.197514 -397.722906) (xy 344.214919 -397.771885) (xy 344.223792 -397.823101)
			(xy 344.224356 -397.84909) (xy 344.224356 -397.849344) (xy 344.223879 -397.873321) (xy 344.216376 -397.920686)
			(xy 344.201561 -397.966295) (xy 344.179798 -398.009027) (xy 344.151623 -398.047832) (xy 344.117728 -398.081755)
			(xy 344.078947 -398.109963) (xy 344.036233 -398.131762) (xy 343.990637 -398.146616) (xy 343.943279 -398.154159)
			(xy 343.919302 -398.154652) (xy 343.918794 -398.154652) (xy 343.895129 -398.154217) (xy 343.848368 -398.146906)
			(xy 343.803293 -398.132474) (xy 343.76098 -398.111267) (xy 343.722442 -398.083792) (xy 343.6886 -398.050704)
			(xy 343.660262 -398.012796) (xy 343.648792 -397.992092) (xy 343.648538 -397.99133) (xy 343.635584 -397.968978)
			(xy 343.630119 -397.960595) (xy 343.614261 -397.948432) (xy 343.594956 -397.94326) (xy 343.575141 -397.945865)
			(xy 343.566242 -397.950436) (xy 343.557098 -397.95577) (xy 343.551002 -397.964152) (xy 343.540055 -397.978035)
			(xy 343.513976 -398.001898) (xy 343.483954 -398.020562) (xy 343.451013 -398.033388) (xy 343.416276 -398.039941)
			(xy 343.398602 -398.040352) (xy 343.398094 -398.040352) (xy 343.379317 -398.039908) (xy 343.342483 -398.032587)
			(xy 343.307783 -398.018225) (xy 343.276547 -397.997376) (xy 343.249976 -397.970837) (xy 343.229087 -397.939628)
			(xy 343.214683 -397.904946) (xy 343.207315 -397.868121) (xy 343.206832 -397.849344) (xy 343.207256 -397.830228)
			(xy 343.214827 -397.792752) (xy 343.229695 -397.75753) (xy 343.251268 -397.725965) (xy 343.278685 -397.699319)
			(xy 343.310851 -397.678653) (xy 343.328498 -397.67129) (xy 343.338658 -397.667226) (xy 343.354152 -397.651478)
			(xy 343.383362 -397.568166) (xy 343.386553 -397.557579) (xy 343.384597 -397.535585) (xy 343.379552 -397.525748)
			(xy 343.251282 -397.304006) (xy 343.239344 -397.279876) (xy 343.234597 -397.270308) (xy 343.21879 -397.255972)
			(xy 343.198524 -397.249288) (xy 343.177289 -397.251406) (xy 343.158743 -397.261963) (xy 343.151968 -397.270224)
			(xy 343.141004 -397.284287) (xy 343.114824 -397.308489) (xy 343.084611 -397.327419) (xy 343.051412 -397.340419)
			(xy 343.016379 -397.347038) (xy 342.998552 -397.34744) (xy 342.998044 -397.34744) (xy 342.991164 -397.347433)
			(xy 342.977435 -397.346546) (xy 342.970612 -397.345662) (xy 342.956134 -397.343376) (xy 342.929464 -397.35506)
			(xy 342.869774 -397.442944) (xy 342.86475 -397.451077) (xy 342.860584 -397.469721) (xy 342.863522 -397.488597)
			(xy 342.867996 -397.497046) (xy 342.983566 -397.696944) (xy 342.98382 -397.697452) (xy 342.984074 -397.697452)
			(xy 342.985344 -397.699992) (xy 342.997619 -397.722906) (xy 343.015023 -397.771885) (xy 343.023896 -397.823101)
			(xy 343.02446 -397.84909) (xy 343.02446 -397.849344) (xy 343.024079 -397.873326) (xy 343.016573 -397.9207)
			(xy 343.001752 -397.966317) (xy 342.979981 -398.009055) (xy 342.951795 -398.047865) (xy 342.917888 -398.08179)
			(xy 342.879094 -398.109996) (xy 342.836367 -398.13179) (xy 342.790757 -398.146635) (xy 342.743388 -398.154166)
			(xy 342.719406 -398.154652) (xy 342.718898 -398.154652) (xy 342.695234 -398.154214) (xy 342.648472 -398.146903)
			(xy 342.603397 -398.132472) (xy 342.561085 -398.111266) (xy 342.522547 -398.083791) (xy 342.488704 -398.050704)
			(xy 342.460366 -398.012796) (xy 342.448896 -397.992092) (xy 342.448642 -397.99133) (xy 342.435688 -397.968978)
			(xy 342.430219 -397.960598) (xy 342.414362 -397.948435) (xy 342.395059 -397.943262) (xy 342.375245 -397.945866)
			(xy 342.366346 -397.950436) (xy 342.357202 -397.95577) (xy 342.351106 -397.964152) (xy 342.340214 -397.97808)
			(xy 342.31412 -398.00194) (xy 342.284085 -398.020596) (xy 342.251132 -398.033411) (xy 342.216384 -398.03995)
			(xy 342.198706 -398.040352) (xy 342.198198 -398.040352) (xy 342.179421 -398.039905) (xy 342.142587 -398.032584)
			(xy 342.107887 -398.018223) (xy 342.076652 -397.997374) (xy 342.05008 -397.970836) (xy 342.029191 -397.939627)
			(xy 342.014787 -397.904945) (xy 342.007419 -397.868121) (xy 342.006936 -397.849344) (xy 342.007357 -397.830227)
			(xy 342.014928 -397.792752) (xy 342.029797 -397.757529) (xy 342.051371 -397.725965) (xy 342.078788 -397.699318)
			(xy 342.110954 -397.678653) (xy 342.128602 -397.67129) (xy 342.138762 -397.667226) (xy 342.154256 -397.651478)
			(xy 342.183466 -397.568166) (xy 342.186656 -397.557579) (xy 342.1847 -397.535585) (xy 342.179656 -397.525748)
			(xy 342.051386 -397.304006) (xy 342.039448 -397.279876) (xy 342.034695 -397.270312) (xy 342.01889 -397.255976)
			(xy 341.998625 -397.249291) (xy 341.977392 -397.251408) (xy 341.958847 -397.261964) (xy 341.952072 -397.270224)
			(xy 341.94118 -397.284314) (xy 341.91503 -397.308485) (xy 341.884856 -397.327396) (xy 341.851702 -397.340393)
			(xy 341.816715 -397.347025) (xy 341.79891 -397.34744) (xy 341.798402 -397.34744) (xy 341.770716 -397.345408)
			(xy 341.770462 -397.345408) (xy 341.760994 -397.344424) (xy 341.742473 -397.348767) (xy 341.726822 -397.35958)
			(xy 341.721186 -397.367252) (xy 341.669624 -397.442944) (xy 341.664598 -397.451077) (xy 341.660428 -397.469721)
			(xy 341.663369 -397.488598) (xy 341.667846 -397.497046) (xy 341.783416 -397.696944) (xy 341.78367 -397.697452)
			(xy 341.783924 -397.697452) (xy 341.785194 -397.699992) (xy 341.797425 -397.722917) (xy 341.814746 -397.771902)
			(xy 341.823534 -397.823111) (xy 341.824056 -397.84909) (xy 341.824056 -397.849344) (xy 341.823578 -397.873334)
			(xy 341.816067 -397.920723) (xy 341.801236 -397.966353) (xy 341.779452 -398.009103) (xy 341.751249 -398.047919)
			(xy 341.717322 -398.081846) (xy 341.678506 -398.11005) (xy 341.635757 -398.131835) (xy 341.590127 -398.146666)
			(xy 341.542738 -398.154178) (xy 341.518748 -398.154652) (xy 341.495085 -398.154174) (xy 341.448326 -398.146871)
			(xy 341.403251 -398.132447) (xy 341.360939 -398.111247) (xy 341.3224 -398.083778) (xy 341.288557 -398.050697)
			(xy 341.260217 -398.012794) (xy 341.248746 -397.992092) (xy 341.248492 -397.99133) (xy 341.235538 -397.968978)
			(xy 341.23012 -397.96056) (xy 341.214245 -397.948398) (xy 341.194924 -397.943234) (xy 341.175098 -397.945855)
			(xy 341.166196 -397.950436) (xy 341.157052 -397.95577) (xy 341.150956 -397.964152) (xy 341.140035 -397.978057)
			(xy 341.113949 -398.001918) (xy 341.083921 -398.020578) (xy 341.050974 -398.033399) (xy 341.016232 -398.039945)
			(xy 340.998556 -398.040352) (xy 340.998048 -398.040352) (xy 340.979282 -398.039835) (xy 340.94247 -398.032522)
			(xy 340.907791 -398.018168) (xy 340.87658 -397.997324) (xy 340.850034 -397.970792) (xy 340.829175 -397.93959)
			(xy 340.814804 -397.904919) (xy 340.807474 -397.86811) (xy 340.80704 -397.849344) (xy 340.807533 -397.83025)
			(xy 340.815093 -397.792819) (xy 340.829921 -397.757628) (xy 340.851431 -397.726075) (xy 340.878767 -397.69941)
			(xy 340.910846 -397.678693) (xy 340.928452 -397.67129) (xy 340.938612 -397.667226) (xy 340.954106 -397.651478)
			(xy 340.983316 -397.568166) (xy 340.986512 -397.55758) (xy 340.984554 -397.535584) (xy 340.979506 -397.525748)
			(xy 340.851236 -397.304006) (xy 340.839298 -397.279876) (xy 340.834475 -397.270353) (xy 340.818689 -397.256023)
			(xy 340.798446 -397.249334) (xy 340.77723 -397.251439) (xy 340.758696 -397.261975) (xy 340.751922 -397.270224)
			(xy 340.740985 -397.284309) (xy 340.714798 -397.30851) (xy 340.684578 -397.327435) (xy 340.651373 -397.34043)
			(xy 340.616334 -397.347042) (xy 340.598506 -397.34744) (xy 340.597998 -397.34744) (xy 340.591118 -397.347438)
			(xy 340.577388 -397.346548) (xy 340.570566 -397.345662) (xy 340.556088 -397.343376) (xy 340.529418 -397.35506)
			(xy 340.469728 -397.442944) (xy 340.464701 -397.451077) (xy 340.460531 -397.469721) (xy 340.463472 -397.488598)
			(xy 340.46795 -397.497046) (xy 340.58352 -397.696944) (xy 340.583774 -397.697452) (xy 340.584028 -397.697452)
			(xy 340.585298 -397.699992) (xy 340.597529 -397.722917) (xy 340.61485 -397.771902) (xy 340.623638 -397.823111)
			(xy 340.62416 -397.84909) (xy 340.62416 -397.849344) (xy 340.623802 -397.873341) (xy 340.616287 -397.920742)
			(xy 340.60145 -397.966385) (xy 340.579655 -398.009144) (xy 340.551439 -398.047968) (xy 340.517498 -398.081899)
			(xy 340.478666 -398.110103) (xy 340.4359 -398.131885) (xy 340.390253 -398.146709) (xy 340.342849 -398.154209)
			(xy 340.318852 -398.154652) (xy 340.295189 -398.154171) (xy 340.24843 -398.146868) (xy 340.203356 -398.132445)
			(xy 340.161043 -398.111245) (xy 340.122505 -398.083777) (xy 340.088661 -398.050696) (xy 340.060321 -398.012793)
			(xy 340.04885 -397.992092) (xy 340.048596 -397.99133) (xy 340.035642 -397.968978) (xy 340.03022 -397.960563)
			(xy 340.014346 -397.948401) (xy 339.995027 -397.943237) (xy 339.975201 -397.945856) (xy 339.9663 -397.950436)
			(xy 339.957156 -397.95577) (xy 339.95106 -397.964152) (xy 339.940137 -397.978055) (xy 339.914052 -398.001917)
			(xy 339.884024 -398.020577) (xy 339.851078 -398.033398) (xy 339.816336 -398.039945) (xy 339.79866 -398.040352)
			(xy 339.798152 -398.040352) (xy 339.779386 -398.039892) (xy 339.742576 -398.032562) (xy 339.707902 -398.018195)
			(xy 339.676696 -397.99734) (xy 339.650157 -397.970801) (xy 339.629303 -397.939594) (xy 339.614936 -397.90492)
			(xy 339.607608 -397.86811) (xy 339.607144 -397.849344) (xy 339.607634 -397.83025) (xy 339.615194 -397.792818)
			(xy 339.630023 -397.757628) (xy 339.651533 -397.726074) (xy 339.67887 -397.69941) (xy 339.710949 -397.678692)
			(xy 339.728556 -397.67129) (xy 339.738716 -397.667226) (xy 339.75421 -397.651478) (xy 339.78342 -397.568166)
			(xy 339.786615 -397.55758) (xy 339.784658 -397.535584) (xy 339.77961 -397.525748) (xy 339.65134 -397.304006)
			(xy 339.639402 -397.279876) (xy 339.634573 -397.270356) (xy 339.618789 -397.256026) (xy 339.598548 -397.249338)
			(xy 339.577333 -397.251441) (xy 339.5588 -397.261976) (xy 339.552026 -397.270224) (xy 339.541103 -397.284288)
			(xy 339.514961 -397.308462) (xy 339.484795 -397.327377) (xy 339.451648 -397.34038) (xy 339.416666 -397.34702)
			(xy 339.398864 -397.34744) (xy 339.398356 -397.34744) (xy 339.37067 -397.345408) (xy 339.370416 -397.345408)
			(xy 339.360946 -397.344467) (xy 339.34243 -397.348791) (xy 339.326779 -397.359587) (xy 339.32114 -397.367252)
			(xy 339.269578 -397.442944) (xy 339.264554 -397.451077) (xy 339.260387 -397.469721) (xy 339.263326 -397.488597)
			(xy 339.2678 -397.497046) (xy 339.38337 -397.696944) (xy 339.383624 -397.697452) (xy 339.383878 -397.697452)
			(xy 339.385148 -397.699992) (xy 339.397423 -397.722906) (xy 339.414827 -397.771885) (xy 339.4237 -397.823101)
			(xy 339.424264 -397.84909) (xy 339.424264 -397.849344) (xy 339.423879 -397.873326) (xy 339.416373 -397.920699)
			(xy 339.401552 -397.966316) (xy 339.379781 -398.009054) (xy 339.351596 -398.047863) (xy 339.31769 -398.081788)
			(xy 339.278896 -398.109994) (xy 339.236169 -398.131788) (xy 339.190561 -398.146634) (xy 339.143192 -398.154166)
			(xy 339.11921 -398.154652) (xy 339.118702 -398.154652) (xy 339.095038 -398.154211) (xy 339.048277 -398.146901)
			(xy 339.003201 -398.13247) (xy 338.960889 -398.111264) (xy 338.922351 -398.08379) (xy 338.888508 -398.050703)
			(xy 338.86017 -398.012796) (xy 338.8487 -397.992092) (xy 338.848446 -397.99133) (xy 338.835492 -397.968978)
			(xy 338.830019 -397.960601) (xy 338.814164 -397.948438) (xy 338.794862 -397.943264) (xy 338.775049 -397.945866)
			(xy 338.76615 -397.950436) (xy 338.757006 -397.95577) (xy 338.75091 -397.964152) (xy 338.740015 -397.978078)
			(xy 338.713923 -398.001939) (xy 338.683888 -398.020595) (xy 338.650935 -398.03341) (xy 338.616188 -398.039949)
			(xy 338.59851 -398.040352) (xy 338.598002 -398.040352) (xy 338.579225 -398.039901) (xy 338.542391 -398.032581)
			(xy 338.507691 -398.018221) (xy 338.476456 -397.997372) (xy 338.449884 -397.970835) (xy 338.428995 -397.939626)
			(xy 338.414591 -397.904945) (xy 338.407223 -397.86812) (xy 338.40674 -397.849344) (xy 338.407159 -397.830227)
			(xy 338.41473 -397.792751) (xy 338.429599 -397.757528) (xy 338.451173 -397.725964) (xy 338.478591 -397.699318)
			(xy 338.510758 -397.678653) (xy 338.528406 -397.67129) (xy 338.538566 -397.667226) (xy 338.55406 -397.651478)
			(xy 338.58327 -397.568166) (xy 338.58646 -397.557579) (xy 338.584504 -397.535585) (xy 338.57946 -397.525748)
			(xy 338.45119 -397.304006) (xy 338.439252 -397.279876) (xy 338.434493 -397.270315) (xy 338.41869 -397.25598)
			(xy 338.398427 -397.249294) (xy 338.377195 -397.251411) (xy 338.358651 -397.261964) (xy 338.351876 -397.270224)
			(xy 338.340965 -397.284331) (xy 338.314772 -397.30853) (xy 338.284545 -397.327452) (xy 338.251334 -397.340441)
			(xy 338.21629 -397.347046) (xy 338.19846 -397.34744) (xy 338.197952 -397.34744) (xy 338.191072 -397.347433)
			(xy 338.177343 -397.346546) (xy 338.17052 -397.345662) (xy 338.156042 -397.343376) (xy 338.129372 -397.35506)
			(xy 338.069682 -397.442944) (xy 338.064657 -397.451077) (xy 338.060491 -397.469721) (xy 338.063429 -397.488597)
			(xy 338.067904 -397.497046) (xy 338.183474 -397.696944) (xy 338.183728 -397.697452) (xy 338.183982 -397.697452)
			(xy 338.185252 -397.699992) (xy 338.197527 -397.722906) (xy 338.214931 -397.771885) (xy 338.223804 -397.823101)
			(xy 338.224368 -397.84909) (xy 338.224368 -397.849344) (xy 338.223979 -397.873326) (xy 338.216473 -397.920698)
			(xy 338.201652 -397.966315) (xy 338.179882 -398.009053) (xy 338.151697 -398.047862) (xy 338.117791 -398.081787)
			(xy 338.078998 -398.109993) (xy 338.036272 -398.131787) (xy 337.990664 -398.146633) (xy 337.943295 -398.154165)
			(xy 337.919314 -398.154652) (xy 337.918806 -398.154652) (xy 337.895142 -398.154208) (xy 337.848381 -398.146898)
			(xy 337.803306 -398.132468) (xy 337.760993 -398.111263) (xy 337.722455 -398.083789) (xy 337.688613 -398.050703)
			(xy 337.660274 -398.012795) (xy 337.648804 -397.992092) (xy 337.64855 -397.99133) (xy 337.635596 -397.968978)
			(xy 337.630221 -397.960529) (xy 337.61433 -397.948367) (xy 337.594994 -397.943211) (xy 337.575158 -397.945846)
			(xy 337.566254 -397.950436) (xy 337.55711 -397.95577) (xy 337.551014 -397.964152) (xy 337.540117 -397.978077)
			(xy 337.514025 -398.001937) (xy 337.483991 -398.020593) (xy 337.451039 -398.033409) (xy 337.416292 -398.039949)
			(xy 337.398614 -398.040352) (xy 337.398106 -398.040352) (xy 337.379329 -398.039898) (xy 337.342496 -398.032578)
			(xy 337.307796 -398.018219) (xy 337.27656 -397.997371) (xy 337.249988 -397.970833) (xy 337.229099 -397.939625)
			(xy 337.214695 -397.904944) (xy 337.207327 -397.86812) (xy 337.206844 -397.849344) (xy 337.20726 -397.830227)
			(xy 337.214832 -397.792751) (xy 337.229701 -397.757528) (xy 337.251276 -397.725963) (xy 337.278694 -397.699317)
			(xy 337.310862 -397.678653) (xy 337.32851 -397.67129) (xy 337.33867 -397.667226) (xy 337.354164 -397.651478)
			(xy 337.383374 -397.568166) (xy 337.386563 -397.557579) (xy 337.384608 -397.535585) (xy 337.379564 -397.525748)
			(xy 337.251294 -397.304006) (xy 337.239356 -397.279876) (xy 337.234592 -397.270318) (xy 337.21879 -397.255983)
			(xy 337.198529 -397.249298) (xy 337.177298 -397.251413) (xy 337.158755 -397.261965) (xy 337.15198 -397.270224)
			(xy 337.141067 -397.284329) (xy 337.114874 -397.308528) (xy 337.084648 -397.32745) (xy 337.051437 -397.34044)
			(xy 337.016394 -397.347046) (xy 336.998564 -397.34744) (xy 336.998056 -397.34744) (xy 336.991176 -397.347432)
			(xy 336.977447 -397.346545) (xy 336.970624 -397.345662) (xy 336.956146 -397.343376) (xy 336.929476 -397.35506)
			(xy 336.869786 -397.442944) (xy 336.864761 -397.451077) (xy 336.860594 -397.469721) (xy 336.863533 -397.488598)
			(xy 336.868008 -397.497046) (xy 336.983578 -397.696944) (xy 336.983832 -397.697452) (xy 336.984086 -397.697452)
			(xy 336.985356 -397.699992) (xy 336.997631 -397.722906) (xy 337.015035 -397.771885) (xy 337.023908 -397.823101)
			(xy 337.024472 -397.84909) (xy 337.024472 -397.849344) (xy 337.024079 -397.873326) (xy 337.016573 -397.920698)
			(xy 337.001753 -397.966314) (xy 336.979983 -398.009052) (xy 336.951799 -398.047861) (xy 336.917893 -398.081785)
			(xy 336.8791 -398.109992) (xy 336.836375 -398.131786) (xy 336.790767 -398.146632) (xy 336.743399 -398.154165)
			(xy 336.719418 -398.154652) (xy 336.71891 -398.154652) (xy 336.695246 -398.154205) (xy 336.648485 -398.146896)
			(xy 336.60341 -398.132466) (xy 336.561098 -398.111261) (xy 336.522559 -398.083788) (xy 336.488717 -398.050702)
			(xy 336.460378 -398.012795) (xy 336.448908 -397.992092) (xy 336.448654 -397.99133) (xy 336.4357 -397.968978)
			(xy 336.430321 -397.960532) (xy 336.414431 -397.94837) (xy 336.395097 -397.943214) (xy 336.375262 -397.945847)
			(xy 336.366358 -397.950436) (xy 336.357214 -397.95577) (xy 336.351118 -397.964152) (xy 336.340219 -397.978075)
			(xy 336.314127 -398.001935) (xy 336.284094 -398.020592) (xy 336.251142 -398.033408) (xy 336.216396 -398.039949)
			(xy 336.198718 -398.040352) (xy 336.19821 -398.040352) (xy 336.179433 -398.039894) (xy 336.1426 -398.032575)
			(xy 336.1079 -398.018216) (xy 336.076665 -397.997369) (xy 336.050093 -397.970832) (xy 336.029204 -397.939625)
			(xy 336.014799 -397.904944) (xy 336.007431 -397.86812) (xy 336.006948 -397.849344) (xy 336.007362 -397.830227)
			(xy 336.014933 -397.792751) (xy 336.029803 -397.757527) (xy 336.051378 -397.725962) (xy 336.078797 -397.699316)
			(xy 336.110966 -397.678652) (xy 336.128614 -397.67129) (xy 336.138774 -397.667226) (xy 336.154268 -397.651478)
			(xy 336.183478 -397.568166) (xy 336.186667 -397.557579) (xy 336.184711 -397.535585) (xy 336.179668 -397.525748)
			(xy 336.051398 -397.304006) (xy 336.03946 -397.279876) (xy 336.03469 -397.270322) (xy 336.01889 -397.255987)
			(xy 335.99863 -397.249301) (xy 335.977401 -397.251416) (xy 335.958859 -397.261966) (xy 335.952084 -397.270224)
			(xy 335.941185 -397.284308) (xy 335.915037 -397.30848) (xy 335.884865 -397.327392) (xy 335.851712 -397.34039)
			(xy 335.816726 -397.347024) (xy 335.798922 -397.34744) (xy 335.798414 -397.34744) (xy 335.778392 -397.346891)
			(xy 335.739222 -397.338568) (xy 335.702639 -397.322282) (xy 335.670241 -397.298746) (xy 335.643445 -397.268988)
			(xy 335.623422 -397.234309) (xy 335.611047 -397.196225) (xy 335.606861 -397.1564) (xy 322.143412 -397.1564)
			(xy 322.455794 -397.696944) (xy 322.456048 -397.697452) (xy 322.456302 -397.697452) (xy 322.457572 -397.699992)
			(xy 322.469841 -397.722909) (xy 322.487249 -397.771886) (xy 322.496124 -397.823102) (xy 322.496688 -397.84909)
			(xy 322.496688 -397.849344) (xy 322.496279 -397.873325) (xy 322.488774 -397.920695) (xy 322.473954 -397.96631)
			(xy 322.452186 -398.009047) (xy 322.424003 -398.047855) (xy 322.3901 -398.08178) (xy 322.351309 -398.109986)
			(xy 322.308586 -398.131782) (xy 322.26298 -398.146629) (xy 322.215614 -398.154164) (xy 322.191634 -398.154652)
			(xy 322.191126 -398.154652) (xy 322.167462 -398.154192) (xy 322.120702 -398.146885) (xy 322.075627 -398.132458)
			(xy 322.033315 -398.111255) (xy 321.994777 -398.083783) (xy 321.960934 -398.0507) (xy 321.932595 -398.012795)
			(xy 321.921124 -397.992092) (xy 321.92087 -397.99133) (xy 321.907916 -397.968978) (xy 321.902521 -397.960544)
			(xy 321.886637 -397.948382) (xy 321.867309 -397.943222) (xy 321.847477 -397.94585) (xy 321.838574 -397.950436)
			(xy 321.82943 -397.95577) (xy 321.823334 -397.964152) (xy 321.812426 -397.978067) (xy 321.786337 -398.001928)
			(xy 321.756305 -398.020586) (xy 321.723356 -398.033405) (xy 321.688611 -398.039947) (xy 321.670934 -398.040352)
			(xy 321.670426 -398.040352) (xy 321.65165 -398.039879) (xy 321.614817 -398.032564) (xy 321.580117 -398.018208)
			(xy 321.548882 -397.997362) (xy 321.522309 -397.970827) (xy 321.50142 -397.939622) (xy 321.487015 -397.904942)
			(xy 321.479647 -397.86812) (xy 321.479164 -397.849344) (xy 321.479568 -397.830226) (xy 321.48714 -397.792749)
			(xy 321.502012 -397.757524) (xy 321.523589 -397.72596) (xy 321.55101 -397.699314) (xy 321.58318 -397.678651)
			(xy 321.60083 -397.67129) (xy 321.61099 -397.667226) (xy 321.626484 -397.651478) (xy 321.655694 -397.568166)
			(xy 321.658892 -397.557581) (xy 321.656933 -397.535584) (xy 321.651884 -397.525748) (xy 321.523614 -397.304006)
			(xy 321.511676 -397.279876) (xy 321.506884 -397.270335) (xy 321.49109 -397.256002) (xy 321.470837 -397.249315)
			(xy 321.449613 -397.251425) (xy 321.431074 -397.26197) (xy 321.4243 -397.270224) (xy 321.413392 -397.2843)
			(xy 321.387246 -397.308473) (xy 321.357076 -397.327386) (xy 321.323926 -397.340386) (xy 321.288942 -397.347023)
			(xy 321.271138 -397.34744) (xy 321.27063 -397.34744) (xy 321.242944 -397.345408) (xy 321.24269 -397.345408)
			(xy 321.233221 -397.344447) (xy 321.214703 -397.34878) (xy 321.199052 -397.359584) (xy 321.193414 -397.367252)
			(xy 321.141852 -397.442944) (xy 321.136829 -397.451077) (xy 321.132665 -397.469721) (xy 321.135602 -397.488597)
			(xy 321.140074 -397.497046) (xy 321.237864 -397.665956) (xy 321.237864 -397.666464) (xy 321.257676 -397.699992)
			(xy 321.269945 -397.722909) (xy 321.287353 -397.771886) (xy 321.296228 -397.823102) (xy 321.296792 -397.84909)
			(xy 321.296792 -397.849344) (xy 321.296401 -397.873352) (xy 321.28888 -397.920775) (xy 321.274029 -397.966436)
			(xy 321.252214 -398.009211) (xy 321.223974 -398.048044) (xy 321.190005 -398.081979) (xy 321.151142 -398.110179)
			(xy 321.108346 -398.131949) (xy 321.062669 -398.146753) (xy 321.015238 -398.154226) (xy 320.99123 -398.154652)
			(xy 320.990976 -398.154652) (xy 320.967403 -398.15425) (xy 320.920816 -398.147007) (xy 320.875899 -398.13268)
			(xy 320.833722 -398.111612) (xy 320.795289 -398.084305) (xy 320.761516 -398.051408) (xy 320.733208 -398.013706)
			(xy 320.721736 -397.993108) (xy 320.721228 -397.992346) (xy 320.707766 -397.968978) (xy 320.70232 -397.960581)
			(xy 320.686454 -397.948419) (xy 320.667144 -397.94325) (xy 320.647324 -397.945861) (xy 320.638424 -397.950436)
			(xy 320.62928 -397.95577) (xy 320.623184 -397.964152) (xy 320.612247 -397.978043) (xy 320.586165 -398.001906)
			(xy 320.556141 -398.020568) (xy 320.523198 -398.033393) (xy 320.488459 -398.039943) (xy 320.470784 -398.040352)
			(xy 320.470276 -398.040352) (xy 320.451511 -398.03987) (xy 320.414701 -398.032545) (xy 320.380028 -398.018181)
			(xy 320.348822 -397.997331) (xy 320.322282 -397.970794) (xy 320.301428 -397.93959) (xy 320.287061 -397.904918)
			(xy 320.279732 -397.868109) (xy 320.279268 -397.849344) (xy 320.279743 -397.830249) (xy 320.287304 -397.792816)
			(xy 320.302136 -397.757624) (xy 320.323648 -397.72607) (xy 320.350989 -397.699406) (xy 320.383072 -397.678691)
			(xy 320.40068 -397.67129) (xy 320.41084 -397.667226) (xy 320.426334 -397.651478) (xy 320.455544 -397.568166)
			(xy 320.458736 -397.55758) (xy 320.45678 -397.535585) (xy 320.451734 -397.525748) (xy 320.323464 -397.304006)
			(xy 320.311526 -397.279876) (xy 320.306663 -397.270376) (xy 320.290889 -397.256049) (xy 320.270657 -397.249358)
			(xy 320.249452 -397.251456) (xy 320.230923 -397.261981) (xy 320.22415 -397.270224) (xy 320.213196 -397.284295)
			(xy 320.187014 -397.308497) (xy 320.156798 -397.327425) (xy 320.123597 -397.340423) (xy 320.088561 -397.34704)
			(xy 320.070734 -397.34744) (xy 320.070226 -397.34744) (xy 320.063346 -397.347435) (xy 320.049616 -397.346547)
			(xy 320.042794 -397.345662) (xy 320.028316 -397.343376) (xy 320.001646 -397.35506) (xy 319.941956 -397.442944)
			(xy 319.936933 -397.451077) (xy 319.932768 -397.469721) (xy 319.935705 -397.488597) (xy 319.940178 -397.497046)
			(xy 320.055748 -397.696944) (xy 320.056002 -397.697452) (xy 320.056256 -397.697452) (xy 320.057526 -397.699992)
			(xy 320.06976 -397.722916) (xy 320.087079 -397.771902) (xy 320.095866 -397.823111) (xy 320.096388 -397.84909)
			(xy 320.096388 -397.849344) (xy 320.095978 -397.873337) (xy 320.088465 -397.920733) (xy 320.07363 -397.966369)
			(xy 320.051839 -398.009123) (xy 320.023629 -398.047942) (xy 319.989693 -398.08187) (xy 319.950868 -398.110073)
			(xy 319.90811 -398.131854) (xy 319.86247 -398.14668) (xy 319.815074 -398.154183) (xy 319.79108 -398.154652)
			(xy 319.767415 -398.154229) (xy 319.720653 -398.146915) (xy 319.675577 -398.132481) (xy 319.633265 -398.111272)
			(xy 319.594727 -398.083795) (xy 319.560885 -398.050706) (xy 319.532548 -398.012797) (xy 319.521078 -397.992092)
			(xy 319.520824 -397.99133) (xy 319.50787 -397.968978) (xy 319.50242 -397.960584) (xy 319.486556 -397.948422)
			(xy 319.467246 -397.943252) (xy 319.447428 -397.945862) (xy 319.438528 -397.950436) (xy 319.429384 -397.95577)
			(xy 319.423288 -397.964152) (xy 319.412349 -397.978041) (xy 319.386268 -398.001905) (xy 319.356244 -398.020567)
			(xy 319.323302 -398.033392) (xy 319.288563 -398.039942) (xy 319.270888 -398.040352) (xy 319.27038 -398.040352)
			(xy 319.251615 -398.039866) (xy 319.214806 -398.032542) (xy 319.180132 -398.018179) (xy 319.148926 -397.997329)
			(xy 319.122386 -397.970792) (xy 319.101532 -397.939589) (xy 319.087165 -397.904917) (xy 319.079836 -397.868109)
			(xy 319.079372 -397.849344) (xy 319.079844 -397.830249) (xy 319.087406 -397.792815) (xy 319.102238 -397.757623)
			(xy 319.123751 -397.726069) (xy 319.151092 -397.699405) (xy 319.183175 -397.678691) (xy 319.200784 -397.67129)
			(xy 319.210944 -397.667226) (xy 319.226438 -397.651478) (xy 319.255648 -397.568166) (xy 319.25884 -397.55758)
			(xy 319.256884 -397.535584) (xy 319.251838 -397.525748) (xy 319.123568 -397.304006) (xy 319.11163 -397.279876)
			(xy 319.106762 -397.270379) (xy 319.090989 -397.256053) (xy 319.070759 -397.249362) (xy 319.049555 -397.251458)
			(xy 319.031027 -397.261982) (xy 319.024254 -397.270224) (xy 319.013315 -397.284275) (xy 318.987177 -397.308449)
			(xy 318.957015 -397.327367) (xy 318.923871 -397.340373) (xy 318.888893 -397.347018) (xy 318.871092 -397.34744)
			(xy 318.870584 -397.34744) (xy 318.842898 -397.345408) (xy 318.842644 -397.345408) (xy 318.833176 -397.34441)
			(xy 318.814654 -397.348759) (xy 318.799003 -397.359578) (xy 318.793368 -397.367252) (xy 318.741806 -397.442944)
			(xy 318.73678 -397.451077) (xy 318.732611 -397.469721) (xy 318.735552 -397.488598) (xy 318.740028 -397.497046)
			(xy 318.837818 -397.665956) (xy 318.837818 -397.666464) (xy 318.85763 -397.699992) (xy 318.869864 -397.722916)
			(xy 318.887183 -397.771902) (xy 318.895971 -397.823111) (xy 318.896492 -397.84909) (xy 318.896492 -397.849344)
			(xy 318.896078 -397.873337) (xy 318.888565 -397.920732) (xy 318.87373 -397.966368) (xy 318.85194 -398.009122)
			(xy 318.82373 -398.047941) (xy 318.789795 -398.081869) (xy 318.750971 -398.110071) (xy 318.708212 -398.131853)
			(xy 318.662574 -398.146679) (xy 318.615177 -398.154183) (xy 318.591184 -398.154652) (xy 318.59093 -398.154652)
			(xy 318.567358 -398.154207) (xy 318.520774 -398.146971) (xy 318.475858 -398.132652) (xy 318.43368 -398.111592)
			(xy 318.395247 -398.084291) (xy 318.361473 -398.0514) (xy 318.333163 -398.013704) (xy 318.32169 -397.993108)
			(xy 318.321182 -397.992346) (xy 318.30772 -397.968978) (xy 318.302321 -397.960547) (xy 318.286438 -397.948385)
			(xy 318.267111 -397.943225) (xy 318.247281 -397.945851) (xy 318.238378 -397.950436) (xy 318.229234 -397.95577)
			(xy 318.223138 -397.964152) (xy 318.212227 -397.978065) (xy 318.186139 -398.001926) (xy 318.156108 -398.020584)
			(xy 318.123159 -398.033404) (xy 318.088415 -398.039947) (xy 318.070738 -398.040352) (xy 318.07023 -398.040352)
			(xy 318.051454 -398.039876) (xy 318.014621 -398.032561) (xy 317.979921 -398.018205) (xy 317.948686 -397.997361)
			(xy 317.922114 -397.970826) (xy 317.901224 -397.939621) (xy 317.886819 -397.904942) (xy 317.879451 -397.868119)
			(xy 317.878968 -397.849344) (xy 317.879369 -397.830226) (xy 317.886942 -397.792748) (xy 317.901814 -397.757524)
			(xy 317.923391 -397.725959) (xy 317.950813 -397.699313) (xy 317.982984 -397.678651) (xy 318.000634 -397.67129)
			(xy 318.010794 -397.667226) (xy 318.026288 -397.651478) (xy 318.055498 -397.568166) (xy 318.058696 -397.55758)
			(xy 318.056737 -397.535584) (xy 318.051688 -397.525748) (xy 317.923418 -397.304006) (xy 317.91148 -397.279876)
			(xy 317.906682 -397.270338) (xy 317.890889 -397.256006) (xy 317.870638 -397.249319) (xy 317.849417 -397.251428)
			(xy 317.830878 -397.261971) (xy 317.824104 -397.270224) (xy 317.813177 -397.284317) (xy 317.786988 -397.308517)
			(xy 317.756765 -397.327442) (xy 317.723558 -397.340434) (xy 317.688517 -397.347044) (xy 317.670688 -397.34744)
			(xy 317.67018 -397.34744) (xy 317.6633 -397.34744) (xy 317.64957 -397.346548) (xy 317.642748 -397.345662)
			(xy 317.62827 -397.343376) (xy 317.6016 -397.35506) (xy 317.54191 -397.442944) (xy 317.536884 -397.451077)
			(xy 317.532715 -397.469721) (xy 317.535655 -397.488598) (xy 317.540132 -397.497046) (xy 317.655702 -397.696944)
			(xy 317.655956 -397.697452) (xy 317.65621 -397.697452) (xy 317.65748 -397.699992) (xy 317.669749 -397.722909)
			(xy 317.687157 -397.771886) (xy 317.696032 -397.823102) (xy 317.696596 -397.84909) (xy 317.696596 -397.849344)
			(xy 317.696179 -397.873324) (xy 317.688674 -397.920694) (xy 317.673855 -397.966308) (xy 317.652087 -398.009045)
			(xy 317.623906 -398.047852) (xy 317.590003 -398.081777) (xy 317.551214 -398.109984) (xy 317.508492 -398.131779)
			(xy 317.462887 -398.146628) (xy 317.415522 -398.154163) (xy 317.391542 -398.154652) (xy 317.391034 -398.154652)
			(xy 317.367371 -398.154185) (xy 317.320611 -398.14688) (xy 317.275536 -398.132454) (xy 317.233224 -398.111252)
			(xy 317.194685 -398.083781) (xy 317.160842 -398.050699) (xy 317.132503 -398.012794) (xy 317.121032 -397.992092)
			(xy 317.120778 -397.99133) (xy 317.107824 -397.968978) (xy 317.102421 -397.96055) (xy 317.08654 -397.948388)
			(xy 317.067214 -397.943227) (xy 317.047384 -397.945852) (xy 317.038482 -397.950436) (xy 317.029338 -397.95577)
			(xy 317.023242 -397.964152) (xy 317.012329 -397.978063) (xy 316.986241 -398.001925) (xy 316.956211 -398.020583)
			(xy 316.923263 -398.033403) (xy 316.888519 -398.039946) (xy 316.870842 -398.040352) (xy 316.870334 -398.040352)
			(xy 316.851558 -398.039872) (xy 316.814726 -398.032558) (xy 316.780026 -398.018203) (xy 316.74879 -397.997359)
			(xy 316.722218 -397.970825) (xy 316.701328 -397.93962) (xy 316.686923 -397.904941) (xy 316.679555 -397.868119)
			(xy 316.679072 -397.849344) (xy 316.67947 -397.830226) (xy 316.687043 -397.792748) (xy 316.701916 -397.757523)
			(xy 316.723494 -397.725958) (xy 316.750916 -397.699313) (xy 316.783088 -397.678651) (xy 316.800738 -397.67129)
			(xy 316.810898 -397.667226) (xy 316.826392 -397.651478) (xy 316.855602 -397.568166) (xy 316.8588 -397.55758)
			(xy 316.856841 -397.535584) (xy 316.851792 -397.525748) (xy 316.723522 -397.304006) (xy 316.711584 -397.279876)
			(xy 316.70678 -397.270342) (xy 316.690989 -397.25601) (xy 316.67074 -397.249322) (xy 316.64952 -397.251431)
			(xy 316.630982 -397.261972) (xy 316.624208 -397.270224) (xy 316.613279 -397.284315) (xy 316.58709 -397.308516)
			(xy 316.556868 -397.32744) (xy 316.523661 -397.340433) (xy 316.488621 -397.347043) (xy 316.470792 -397.34744)
			(xy 316.470284 -397.34744) (xy 316.463404 -397.34744) (xy 316.449674 -397.346548) (xy 316.442852 -397.345662)
			(xy 316.428374 -397.343376) (xy 316.401704 -397.35506) (xy 316.342014 -397.442944) (xy 316.336988 -397.451077)
			(xy 316.332819 -397.469721) (xy 316.33576 -397.488598) (xy 316.340236 -397.497046) (xy 316.455806 -397.696944)
			(xy 316.45606 -397.697452) (xy 316.456314 -397.697452) (xy 316.457584 -397.699992) (xy 316.469854 -397.722909)
			(xy 316.487261 -397.771886) (xy 316.496136 -397.823101) (xy 316.4967 -397.84909) (xy 316.4967 -397.849344)
			(xy 316.496279 -397.873324) (xy 316.488774 -397.920694) (xy 316.473956 -397.966307) (xy 316.452188 -398.009044)
			(xy 316.424007 -398.047851) (xy 316.390105 -398.081775) (xy 316.351316 -398.109982) (xy 316.308594 -398.131778)
			(xy 316.26299 -398.146627) (xy 316.215626 -398.154163) (xy 316.191646 -398.154652) (xy 316.191138 -398.154652)
			(xy 316.167475 -398.154182) (xy 316.120715 -398.146877) (xy 316.07564 -398.132452) (xy 316.033328 -398.111251)
			(xy 315.994789 -398.08378) (xy 315.960946 -398.050698) (xy 315.932607 -398.012794) (xy 315.921136 -397.992092)
			(xy 315.920882 -397.99133) (xy 315.907928 -397.968978) (xy 315.902521 -397.960553) (xy 315.886641 -397.948391)
			(xy 315.867317 -397.943229) (xy 315.847488 -397.945853) (xy 315.838586 -397.950436) (xy 315.829442 -397.95577)
			(xy 315.823346 -397.964152) (xy 315.812431 -397.978061) (xy 315.786343 -398.001923) (xy 315.756314 -398.020582)
			(xy 315.723366 -398.033402) (xy 315.688623 -398.039946) (xy 315.670946 -398.040352) (xy 315.670438 -398.040352)
			(xy 315.651662 -398.039869) (xy 315.61483 -398.032555) (xy 315.58013 -398.018201) (xy 315.548895 -397.997357)
			(xy 315.522322 -397.970824) (xy 315.501432 -397.939619) (xy 315.487027 -397.904941) (xy 315.479659 -397.868119)
			(xy 315.479176 -397.849344) (xy 315.479635 -397.83023) (xy 315.487203 -397.792759) (xy 315.502067 -397.757539)
			(xy 315.523633 -397.725975) (xy 315.551041 -397.699327) (xy 315.583199 -397.678657) (xy 315.600842 -397.67129)
			(xy 315.611002 -397.667226) (xy 315.626496 -397.651478) (xy 315.655706 -397.568166) (xy 315.658903 -397.55758)
			(xy 315.656945 -397.535584) (xy 315.651896 -397.525748) (xy 315.523626 -397.304006) (xy 315.511688 -397.279876)
			(xy 315.506879 -397.270345) (xy 315.491089 -397.256013) (xy 315.470842 -397.249326) (xy 315.449623 -397.251433)
			(xy 315.431086 -397.261973) (xy 315.424312 -397.270224) (xy 315.413397 -397.284295) (xy 315.387253 -397.308468)
			(xy 315.357085 -397.327382) (xy 315.323936 -397.340383) (xy 315.288953 -397.347022) (xy 315.27115 -397.34744)
			(xy 315.270642 -397.34744) (xy 315.242956 -397.345408) (xy 315.242702 -397.345408) (xy 315.233232 -397.344456)
			(xy 315.214715 -397.348785) (xy 315.199064 -397.359586) (xy 315.193426 -397.367252) (xy 315.141864 -397.442944)
			(xy 315.13684 -397.451077) (xy 315.132675 -397.469721) (xy 315.135613 -397.488597) (xy 315.140086 -397.497046)
			(xy 315.255656 -397.696944) (xy 315.25591 -397.697452) (xy 315.256164 -397.697452) (xy 315.257434 -397.699992)
			(xy 315.269668 -397.722915) (xy 315.286988 -397.771902) (xy 315.295775 -397.823111) (xy 315.296296 -397.84909)
			(xy 315.296296 -397.849344) (xy 315.295878 -397.873337) (xy 315.288365 -397.920731) (xy 315.273531 -397.966367)
			(xy 315.251741 -398.009121) (xy 315.223531 -398.047939) (xy 315.189597 -398.081868) (xy 315.150773 -398.11007)
			(xy 315.108015 -398.131852) (xy 315.062377 -398.146678) (xy 315.014981 -398.154182) (xy 314.990988 -398.154652)
			(xy 314.967323 -398.154222) (xy 314.920562 -398.14691) (xy 314.875486 -398.132477) (xy 314.833174 -398.111269)
			(xy 314.794636 -398.083793) (xy 314.760794 -398.050705) (xy 314.732456 -398.012796) (xy 314.720986 -397.992092)
			(xy 314.720732 -397.99133) (xy 314.707778 -397.968978) (xy 314.70232 -397.96059) (xy 314.686459 -397.948428)
			(xy 314.667152 -397.943257) (xy 314.647336 -397.945864) (xy 314.638436 -397.950436) (xy 314.629292 -397.95577)
			(xy 314.623196 -397.964152) (xy 314.612253 -397.978038) (xy 314.586172 -398.001901) (xy 314.55615 -398.020564)
			(xy 314.523208 -398.03339) (xy 314.488471 -398.039942) (xy 314.470796 -398.040352) (xy 314.470288 -398.040352)
			(xy 314.451523 -398.039859) (xy 314.414714 -398.032536) (xy 314.380041 -398.018175) (xy 314.348835 -397.997326)
			(xy 314.322295 -397.97079) (xy 314.30144 -397.939587) (xy 314.287073 -397.904916) (xy 314.279744 -397.868109)
			(xy 314.27928 -397.849344) (xy 314.279747 -397.830249) (xy 314.287309 -397.792814) (xy 314.302142 -397.757622)
			(xy 314.323656 -397.726067) (xy 314.350998 -397.699404) (xy 314.383083 -397.67869) (xy 314.400692 -397.67129)
			(xy 314.410852 -397.667226) (xy 314.426346 -397.651478) (xy 314.455556 -397.568166) (xy 314.458747 -397.557579)
			(xy 314.456791 -397.535585) (xy 314.451746 -397.525748) (xy 314.323476 -397.304006) (xy 314.311538 -397.279876)
			(xy 314.306658 -397.270386) (xy 314.290889 -397.25606) (xy 314.270662 -397.249369) (xy 314.249461 -397.251464)
			(xy 314.230935 -397.261984) (xy 314.224162 -397.270224) (xy 314.213202 -397.28429) (xy 314.187021 -397.308492)
			(xy 314.156807 -397.327421) (xy 314.123607 -397.34042) (xy 314.088573 -397.347039) (xy 314.070746 -397.34744)
			(xy 314.070238 -397.34744) (xy 314.063358 -397.347434) (xy 314.049629 -397.346546) (xy 314.042806 -397.345662)
			(xy 314.028328 -397.343376) (xy 314.001658 -397.35506) (xy 313.941968 -397.442944) (xy 313.936944 -397.451077)
			(xy 313.932779 -397.469721) (xy 313.935717 -397.488597) (xy 313.94019 -397.497046) (xy 314.05576 -397.696944)
			(xy 314.056014 -397.697452) (xy 314.056268 -397.697452) (xy 314.057538 -397.699992) (xy 314.069773 -397.722915)
			(xy 314.087092 -397.771902) (xy 314.095879 -397.823111) (xy 314.0964 -397.84909) (xy 314.0964 -397.849344)
			(xy 314.095978 -397.873337) (xy 314.088465 -397.920731) (xy 314.073631 -397.966366) (xy 314.051841 -398.009119)
			(xy 314.023632 -398.047938) (xy 313.989698 -398.081866) (xy 313.950875 -398.110069) (xy 313.908118 -398.131851)
			(xy 313.86248 -398.146677) (xy 313.815085 -398.154182) (xy 313.791092 -398.154652) (xy 313.767427 -398.154219)
			(xy 313.720666 -398.146907) (xy 313.67559 -398.132475) (xy 313.633278 -398.111268) (xy 313.59474 -398.083792)
			(xy 313.560898 -398.050705) (xy 313.53256 -398.012796) (xy 313.52109 -397.992092) (xy 313.520836 -397.99133)
			(xy 313.507882 -397.968978) (xy 313.50242 -397.960593) (xy 313.48656 -397.948431) (xy 313.467255 -397.943259)
			(xy 313.447439 -397.945864) (xy 313.43854 -397.950436) (xy 313.429396 -397.95577) (xy 313.4233 -397.964152)
			(xy 313.412354 -397.978036) (xy 313.386275 -398.001899) (xy 313.356253 -398.020562) (xy 313.323312 -398.033389)
			(xy 313.288574 -398.039941) (xy 313.2709 -398.040352) (xy 313.270392 -398.040352) (xy 313.251627 -398.039856)
			(xy 313.214819 -398.032534) (xy 313.180145 -398.018172) (xy 313.148939 -397.997324) (xy 313.122399 -397.970789)
			(xy 313.101545 -397.939587) (xy 313.087177 -397.904916) (xy 313.079848 -397.868109) (xy 313.079384 -397.849344)
			(xy 313.079849 -397.830248) (xy 313.087411 -397.792814) (xy 313.102244 -397.757621) (xy 313.123758 -397.726067)
			(xy 313.151101 -397.699404) (xy 313.183187 -397.67869) (xy 313.200796 -397.67129) (xy 313.210956 -397.667226)
			(xy 313.22645 -397.651478) (xy 313.25566 -397.568166) (xy 313.258851 -397.557579) (xy 313.256895 -397.535585)
			(xy 313.25185 -397.525748) (xy 313.12358 -397.304006) (xy 313.111642 -397.279876) (xy 313.106897 -397.270307)
			(xy 313.09109 -397.25597) (xy 313.070823 -397.249286) (xy 313.049588 -397.251405) (xy 313.031041 -397.261962)
			(xy 313.024266 -397.270224) (xy 313.01332 -397.284269) (xy 312.987184 -397.308444) (xy 312.957023 -397.327362)
			(xy 312.923882 -397.34037) (xy 312.888905 -397.347017) (xy 312.871104 -397.34744) (xy 312.870596 -397.34744)
			(xy 312.84291 -397.345408) (xy 312.842656 -397.345408) (xy 312.833188 -397.34442) (xy 312.814667 -397.348764)
			(xy 312.799016 -397.359579) (xy 312.79338 -397.367252) (xy 312.741818 -397.442944) (xy 312.736792 -397.451077)
			(xy 312.732622 -397.469721) (xy 312.735563 -397.488598) (xy 312.74004 -397.497046) (xy 312.83783 -397.665956)
			(xy 312.83783 -397.666464) (xy 312.857642 -397.699992) (xy 312.869877 -397.722915) (xy 312.887196 -397.771902)
			(xy 312.895983 -397.823111) (xy 312.896504 -397.84909) (xy 312.896504 -397.849344) (xy 312.896078 -397.873337)
			(xy 312.888565 -397.92073) (xy 312.873731 -397.966365) (xy 312.851942 -398.009118) (xy 312.823733 -398.047937)
			(xy 312.7898 -398.081865) (xy 312.750977 -398.110067) (xy 312.708221 -398.13185) (xy 312.662583 -398.146676)
			(xy 312.615189 -398.154182) (xy 312.591196 -398.154652) (xy 312.590942 -398.154652) (xy 312.567371 -398.154197)
			(xy 312.520786 -398.146963) (xy 312.475871 -398.132646) (xy 312.433693 -398.111587) (xy 312.39526 -398.084288)
			(xy 312.361486 -398.051398) (xy 312.333176 -398.013703) (xy 312.321702 -397.993108) (xy 312.321194 -397.992346)
			(xy 312.307732 -397.968978) (xy 312.30232 -397.960556) (xy 312.286443 -397.948394) (xy 312.26712 -397.943231)
			(xy 312.247292 -397.945854) (xy 312.23839 -397.950436) (xy 312.229246 -397.95577) (xy 312.22315 -397.964152)
			(xy 312.212233 -397.978059) (xy 312.186146 -398.001921) (xy 312.156117 -398.02058) (xy 312.123169 -398.033401)
			(xy 312.088426 -398.039946) (xy 312.07075 -398.040352) (xy 312.070242 -398.040352) (xy 312.051466 -398.039865)
			(xy 312.014634 -398.032552) (xy 311.979934 -398.018199) (xy 311.948699 -397.997356) (xy 311.922126 -397.970823)
			(xy 311.901237 -397.939618) (xy 311.886831 -397.90494) (xy 311.879463 -397.868119) (xy 311.87898 -397.849344)
			(xy 311.879436 -397.83023) (xy 311.887005 -397.792758) (xy 311.901869 -397.757538) (xy 311.923435 -397.725975)
			(xy 311.950844 -397.699326) (xy 311.983002 -397.678656) (xy 312.000646 -397.67129) (xy 312.010806 -397.667226)
			(xy 312.0263 -397.651478) (xy 312.05551 -397.568166) (xy 312.058707 -397.55758) (xy 312.056749 -397.535584)
			(xy 312.0517 -397.525748) (xy 311.92343 -397.304006) (xy 311.911492 -397.279876) (xy 311.906677 -397.270348)
			(xy 311.890889 -397.256017) (xy 311.870643 -397.249329) (xy 311.849426 -397.251435) (xy 311.83089 -397.261973)
			(xy 311.824116 -397.270224) (xy 311.813182 -397.284312) (xy 311.786994 -397.308512) (xy 311.756774 -397.327437)
			(xy 311.723568 -397.340431) (xy 311.688529 -397.347043) (xy 311.6707 -397.34744) (xy 311.670192 -397.34744)
			(xy 311.663312 -397.347439) (xy 311.649582 -397.346548) (xy 311.64276 -397.345662) (xy 311.628282 -397.343376)
			(xy 311.601612 -397.35506) (xy 311.541922 -397.442944) (xy 311.536896 -397.451077) (xy 311.532726 -397.469721)
			(xy 311.535667 -397.488598) (xy 311.540144 -397.497046) (xy 311.655714 -397.696944) (xy 311.655968 -397.697452)
			(xy 311.656222 -397.697452) (xy 311.657492 -397.699992) (xy 311.669762 -397.722908) (xy 311.687169 -397.771886)
			(xy 311.696044 -397.823101) (xy 311.696608 -397.84909) (xy 311.696608 -397.849344) (xy 311.696179 -397.873324)
			(xy 311.688674 -397.920693) (xy 311.673856 -397.966306) (xy 311.652089 -398.009041) (xy 311.623909 -398.047848)
			(xy 311.590008 -398.081772) (xy 311.55122 -398.10998) (xy 311.5085 -398.131776) (xy 311.462897 -398.146625)
			(xy 311.415533 -398.154162) (xy 311.391554 -398.154652) (xy 311.391046 -398.154652) (xy 311.367383 -398.154176)
			(xy 311.320624 -398.146872) (xy 311.275549 -398.132448) (xy 311.233237 -398.111248) (xy 311.194698 -398.083778)
			(xy 311.160854 -398.050697) (xy 311.132515 -398.012794) (xy 311.121044 -397.992092) (xy 311.12079 -397.99133)
			(xy 311.107836 -397.968978) (xy 311.10242 -397.960559) (xy 311.086544 -397.948397) (xy 311.067223 -397.943233)
			(xy 311.047396 -397.945854) (xy 311.038494 -397.950436) (xy 311.02935 -397.95577) (xy 311.023254 -397.964152)
			(xy 311.012334 -397.978058) (xy 310.986248 -398.001919) (xy 310.95622 -398.020579) (xy 310.923273 -398.0334)
			(xy 310.88853 -398.039945) (xy 310.870854 -398.040352) (xy 310.870346 -398.040352) (xy 310.85157 -398.039861)
			(xy 310.814738 -398.032549) (xy 310.780039 -398.018196) (xy 310.748803 -397.997354) (xy 310.722231 -397.970822)
			(xy 310.701341 -397.939618) (xy 310.686935 -397.90494) (xy 310.679567 -397.868119) (xy 310.679084 -397.849344)
			(xy 310.679538 -397.830229) (xy 310.687106 -397.792758) (xy 310.701971 -397.757538) (xy 310.723538 -397.725974)
			(xy 310.750947 -397.699326) (xy 310.783106 -397.678656) (xy 310.80075 -397.67129) (xy 310.81091 -397.667226)
			(xy 310.826404 -397.651478) (xy 310.855614 -397.568166) (xy 310.85881 -397.55758) (xy 310.856852 -397.535584)
			(xy 310.851804 -397.525748) (xy 310.723534 -397.304006) (xy 310.711596 -397.279876) (xy 310.706775 -397.270351)
			(xy 310.690989 -397.256021) (xy 310.670745 -397.249332) (xy 310.649529 -397.251438) (xy 310.630994 -397.261974)
			(xy 310.62422 -397.270224) (xy 310.613284 -397.28431) (xy 310.587097 -397.30851) (xy 310.556877 -397.327436)
			(xy 310.523671 -397.34043) (xy 310.488633 -397.347042) (xy 310.470804 -397.34744) (xy 310.470296 -397.34744)
			(xy 310.463416 -397.347439) (xy 310.449686 -397.346548) (xy 310.442864 -397.345662) (xy 310.428386 -397.343376)
			(xy 310.401716 -397.35506) (xy 310.342026 -397.442944) (xy 310.336999 -397.451077) (xy 310.332829 -397.469721)
			(xy 310.335771 -397.488598) (xy 310.340248 -397.497046) (xy 310.455818 -397.696944) (xy 310.456072 -397.697452)
			(xy 310.456326 -397.697452) (xy 310.457596 -397.699992) (xy 310.469867 -397.722908) (xy 310.487274 -397.771886)
			(xy 310.496148 -397.823101) (xy 310.496712 -397.84909) (xy 310.496712 -397.849344) (xy 310.496279 -397.873324)
			(xy 310.488774 -397.920692) (xy 310.473957 -397.966305) (xy 310.45219 -398.00904) (xy 310.42401 -398.047847)
			(xy 310.39011 -398.081771) (xy 310.351323 -398.109978) (xy 310.308603 -398.131775) (xy 310.263 -398.146624)
			(xy 310.215637 -398.154162) (xy 310.191658 -398.154652) (xy 310.19115 -398.154652) (xy 310.167487 -398.154172)
			(xy 310.120728 -398.146869) (xy 310.075653 -398.132446) (xy 310.033341 -398.111246) (xy 309.994802 -398.083777)
			(xy 309.960959 -398.050696) (xy 309.932619 -398.012793) (xy 309.921148 -397.992092) (xy 309.920894 -397.99133)
			(xy 309.90794 -397.968978) (xy 309.90252 -397.960562) (xy 309.886645 -397.948399) (xy 309.867325 -397.943236)
			(xy 309.847499 -397.945855) (xy 309.838598 -397.950436) (xy 309.829454 -397.95577) (xy 309.823358 -397.964152)
			(xy 309.812436 -397.978056) (xy 309.78635 -398.001918) (xy 309.756323 -398.020577) (xy 309.723376 -398.033399)
			(xy 309.688634 -398.039945) (xy 309.670958 -398.040352) (xy 309.67045 -398.040352) (xy 309.651675 -398.039858)
			(xy 309.614843 -398.032546) (xy 309.580143 -398.018194) (xy 309.548907 -397.997352) (xy 309.522335 -397.97082)
			(xy 309.501445 -397.939617) (xy 309.487039 -397.904939) (xy 309.479671 -397.868119) (xy 309.479188 -397.849344)
			(xy 309.479639 -397.830229) (xy 309.487208 -397.792757) (xy 309.502073 -397.757537) (xy 309.52364 -397.725973)
			(xy 309.551051 -397.699325) (xy 309.58321 -397.678656) (xy 309.600854 -397.67129) (xy 309.611014 -397.667226)
			(xy 309.626508 -397.651478) (xy 309.655718 -397.568166) (xy 309.658914 -397.55758) (xy 309.656956 -397.535584)
			(xy 309.651908 -397.525748) (xy 309.523638 -397.304006) (xy 309.5117 -397.279876) (xy 309.506874 -397.270355)
			(xy 309.491089 -397.256025) (xy 309.470847 -397.249336) (xy 309.449632 -397.25144) (xy 309.431098 -397.261975)
			(xy 309.424324 -397.270224) (xy 309.413402 -397.284289) (xy 309.38726 -397.308462) (xy 309.357093 -397.327377)
			(xy 309.323946 -397.34038) (xy 309.288965 -397.347021) (xy 309.271162 -397.34744) (xy 309.270654 -397.34744)
			(xy 309.242968 -397.345408) (xy 309.242714 -397.345408) (xy 309.233244 -397.344466) (xy 309.214728 -397.34879)
			(xy 309.199076 -397.359587) (xy 309.193438 -397.367252) (xy 309.141876 -397.442944) (xy 309.136852 -397.451077)
			(xy 309.132686 -397.469721) (xy 309.135624 -397.488597) (xy 309.140098 -397.497046) (xy 309.255668 -397.696944)
			(xy 309.255922 -397.697452) (xy 309.256176 -397.697452) (xy 309.257446 -397.699992) (xy 309.269681 -397.722915)
			(xy 309.287 -397.771902) (xy 309.295787 -397.823111) (xy 309.296308 -397.84909) (xy 309.296308 -397.849344)
			(xy 309.295878 -397.873336) (xy 309.288365 -397.92073) (xy 309.273532 -397.966364) (xy 309.251743 -398.009117)
			(xy 309.223535 -398.047935) (xy 309.189602 -398.081863) (xy 309.150779 -398.110066) (xy 309.108024 -398.131849)
			(xy 309.062387 -398.146676) (xy 309.014992 -398.154181) (xy 308.991 -398.154652) (xy 308.967336 -398.154213)
			(xy 308.920575 -398.146902) (xy 308.875499 -398.132471) (xy 308.833187 -398.111265) (xy 308.794649 -398.08379)
			(xy 308.760806 -398.050703) (xy 308.732468 -398.012796) (xy 308.720998 -397.992092) (xy 308.720744 -397.99133)
			(xy 308.70779 -397.968978) (xy 308.702319 -397.960599) (xy 308.686463 -397.948437) (xy 308.66716 -397.943263)
			(xy 308.647347 -397.945866) (xy 308.638448 -397.950436) (xy 308.629304 -397.95577) (xy 308.623208 -397.964152)
			(xy 308.612314 -397.978079) (xy 308.586222 -398.001939) (xy 308.556187 -398.020595) (xy 308.523234 -398.033411)
			(xy 308.488486 -398.039949) (xy 308.470808 -398.040352) (xy 308.4703 -398.040352) (xy 308.451535 -398.039848)
			(xy 308.414727 -398.032528) (xy 308.380054 -398.018168) (xy 308.348848 -397.997321) (xy 308.322307 -397.970786)
			(xy 308.301453 -397.939585) (xy 308.287085 -397.904915) (xy 308.279756 -397.868108) (xy 308.279292 -397.849344)
			(xy 308.279815 -397.830252) (xy 308.287373 -397.792824) (xy 308.302197 -397.757636) (xy 308.3237 -397.726083)
			(xy 308.35103 -397.699417) (xy 308.383101 -397.678696) (xy 308.400704 -397.67129) (xy 308.410864 -397.667226)
			(xy 308.426358 -397.651478) (xy 308.455568 -397.568166) (xy 308.458758 -397.557579) (xy 308.456802 -397.535585)
			(xy 308.451758 -397.525748) (xy 308.323488 -397.304006) (xy 308.31155 -397.279876) (xy 308.306794 -397.270313)
			(xy 308.29099 -397.255978) (xy 308.270726 -397.249293) (xy 308.249494 -397.25141) (xy 308.230949 -397.261964)
			(xy 308.224174 -397.270224) (xy 308.213264 -397.284332) (xy 308.18707 -397.30853) (xy 308.156844 -397.327453)
			(xy 308.123632 -397.340441) (xy 308.088589 -397.347046) (xy 308.070758 -397.34744) (xy 308.07025 -397.34744)
			(xy 308.06337 -397.347433) (xy 308.049641 -397.346546) (xy 308.042818 -397.345662) (xy 308.02834 -397.343376)
			(xy 308.00167 -397.35506) (xy 307.94198 -397.442944) (xy 307.936955 -397.451077) (xy 307.932789 -397.469721)
			(xy 307.935728 -397.488597) (xy 307.940202 -397.497046) (xy 308.055772 -397.696944) (xy 308.056026 -397.697452)
			(xy 308.05628 -397.697452) (xy 308.05755 -397.699992) (xy 308.069786 -397.722915) (xy 308.087104 -397.771901)
			(xy 308.095891 -397.823111) (xy 308.096412 -397.84909) (xy 308.096412 -397.849344) (xy 308.095978 -397.873336)
			(xy 308.088465 -397.920729) (xy 308.073632 -397.966363) (xy 308.051844 -398.009116) (xy 308.023636 -398.047934)
			(xy 307.989703 -398.081862) (xy 307.950882 -398.110065) (xy 307.908126 -398.131848) (xy 307.86249 -398.146675)
			(xy 307.815096 -398.154181) (xy 307.791104 -398.154652) (xy 307.76744 -398.154209) (xy 307.720679 -398.146899)
			(xy 307.675603 -398.132469) (xy 307.633291 -398.111263) (xy 307.594753 -398.083789) (xy 307.56091 -398.050703)
			(xy 307.532572 -398.012796) (xy 307.521102 -397.992092) (xy 307.520848 -397.99133) (xy 307.507894 -397.968978)
			(xy 307.502521 -397.960527) (xy 307.486629 -397.948366) (xy 307.467293 -397.94321) (xy 307.447456 -397.945846)
			(xy 307.438552 -397.950436) (xy 307.429408 -397.95577) (xy 307.423312 -397.964152) (xy 307.412416 -397.978078)
			(xy 307.386324 -398.001938) (xy 307.356289 -398.020594) (xy 307.323337 -398.03341) (xy 307.28859 -398.039949)
			(xy 307.270912 -398.040352) (xy 307.270404 -398.040352) (xy 307.25164 -398.039845) (xy 307.214831 -398.032525)
			(xy 307.180158 -398.018166) (xy 307.148952 -397.997319) (xy 307.122412 -397.970785) (xy 307.101557 -397.939584)
			(xy 307.087189 -397.904915) (xy 307.07986 -397.868108) (xy 307.079396 -397.849344) (xy 307.079916 -397.830252)
			(xy 307.087474 -397.792824) (xy 307.102299 -397.757636) (xy 307.123803 -397.726083) (xy 307.151133 -397.699417)
			(xy 307.183205 -397.678696) (xy 307.200808 -397.67129) (xy 307.210968 -397.667226) (xy 307.226462 -397.651478)
			(xy 307.255672 -397.568166) (xy 307.258861 -397.557579) (xy 307.256906 -397.535585) (xy 307.251862 -397.525748)
			(xy 307.123592 -397.304006) (xy 307.111654 -397.279876) (xy 307.106893 -397.270317) (xy 307.09109 -397.255981)
			(xy 307.070828 -397.249296) (xy 307.049597 -397.251412) (xy 307.031053 -397.261965) (xy 307.024278 -397.270224)
			(xy 307.013383 -397.284311) (xy 306.987233 -397.308482) (xy 306.95706 -397.327394) (xy 306.923907 -397.340391)
			(xy 306.88892 -397.347025) (xy 306.871116 -397.34744) (xy 306.870608 -397.34744) (xy 306.842922 -397.345408)
			(xy 306.842668 -397.345408) (xy 306.833199 -397.344429) (xy 306.814679 -397.34877) (xy 306.799028 -397.359581)
			(xy 306.793392 -397.367252) (xy 306.74183 -397.442944) (xy 306.736803 -397.451076) (xy 306.732633 -397.469721)
			(xy 306.735574 -397.488598) (xy 306.740052 -397.497046) (xy 306.837842 -397.665956) (xy 306.837842 -397.666464)
			(xy 306.857654 -397.699992) (xy 306.86989 -397.722915) (xy 306.887208 -397.771901) (xy 306.895995 -397.823111)
			(xy 306.896516 -397.84909) (xy 306.896516 -397.849344) (xy 306.896078 -397.873336) (xy 306.888566 -397.920728)
			(xy 306.873733 -397.966362) (xy 306.851944 -398.009115) (xy 306.823737 -398.047932) (xy 306.789805 -398.08186)
			(xy 306.750984 -398.110063) (xy 306.708229 -398.131846) (xy 306.662593 -398.146674) (xy 306.6152 -398.154181)
			(xy 306.591208 -398.154652) (xy 306.590954 -398.154652) (xy 306.567383 -398.154187) (xy 306.520799 -398.146955)
			(xy 306.475884 -398.13264) (xy 306.433706 -398.111583) (xy 306.395273 -398.084285) (xy 306.361498 -398.051397)
			(xy 306.333188 -398.013702) (xy 306.321714 -397.993108) (xy 306.321206 -397.992346) (xy 306.307744 -397.968978)
			(xy 306.30232 -397.960564) (xy 306.286447 -397.948402) (xy 306.267128 -397.943238) (xy 306.247303 -397.945856)
			(xy 306.238402 -397.950436) (xy 306.229258 -397.95577) (xy 306.223162 -397.964152) (xy 306.212238 -397.978054)
			(xy 306.186153 -398.001916) (xy 306.156125 -398.020576) (xy 306.123179 -398.033398) (xy 306.088438 -398.039945)
			(xy 306.070762 -398.040352) (xy 306.070254 -398.040352) (xy 306.051475 -398.039945) (xy 306.01464 -398.032616)
			(xy 305.979939 -398.018248) (xy 305.948704 -397.997393) (xy 305.922133 -397.970849) (xy 305.901245 -397.939636)
			(xy 305.886842 -397.90495) (xy 305.879475 -397.868122) (xy 305.878992 -397.849344) (xy 305.879441 -397.830229)
			(xy 305.88701 -397.792757) (xy 305.901875 -397.757536) (xy 305.923443 -397.725972) (xy 305.950854 -397.699324)
			(xy 305.983013 -397.678655) (xy 306.000658 -397.67129) (xy 306.010818 -397.667226) (xy 306.026312 -397.651478)
			(xy 306.055522 -397.568166) (xy 306.058717 -397.55758) (xy 306.05676 -397.535584) (xy 306.051712 -397.525748)
			(xy 305.923442 -397.304006) (xy 305.911504 -397.279876) (xy 305.906672 -397.270358) (xy 305.890889 -397.256028)
			(xy 305.870648 -397.249339) (xy 305.849435 -397.251443) (xy 305.830902 -397.261976) (xy 305.824128 -397.270224)
			(xy 305.813187 -397.284306) (xy 305.787001 -397.308507) (xy 305.756782 -397.327433) (xy 305.723578 -397.340428)
			(xy 305.68854 -397.347042) (xy 305.670712 -397.34744) (xy 305.670204 -397.34744) (xy 305.663324 -397.347438)
			(xy 305.649594 -397.346547) (xy 305.642772 -397.345662) (xy 305.628294 -397.343376) (xy 305.601624 -397.35506)
			(xy 305.541934 -397.442944) (xy 305.536907 -397.451076) (xy 305.532736 -397.469721) (xy 305.535678 -397.488598)
			(xy 305.540156 -397.497046) (xy 305.655726 -397.696944) (xy 305.65598 -397.697452) (xy 305.656234 -397.697452)
			(xy 305.657504 -397.699992) (xy 305.669775 -397.722908) (xy 305.687182 -397.771886) (xy 305.696056 -397.823101)
			(xy 305.69662 -397.84909) (xy 305.69662 -397.849344) (xy 305.696179 -397.873323) (xy 305.688675 -397.920691)
			(xy 305.673857 -397.966303) (xy 305.652092 -398.009038) (xy 305.623913 -398.047844) (xy 305.590013 -398.081768)
			(xy 305.551227 -398.109975) (xy 305.508508 -398.131772) (xy 305.462907 -398.146623) (xy 305.415545 -398.154162)
			(xy 305.391566 -398.154652) (xy 305.391058 -398.154652) (xy 305.367395 -398.154166) (xy 305.320636 -398.146864)
			(xy 305.275562 -398.132442) (xy 305.23325 -398.111243) (xy 305.194711 -398.083775) (xy 305.160867 -398.050695)
			(xy 305.132527 -398.012793) (xy 305.121056 -397.992092) (xy 305.120802 -397.99133) (xy 305.107848 -397.968978)
			(xy 305.10242 -397.960567) (xy 305.086548 -397.948405) (xy 305.067231 -397.94324) (xy 305.047407 -397.945857)
			(xy 305.038506 -397.950436) (xy 305.029362 -397.95577) (xy 305.023266 -397.964152) (xy 305.01234 -397.978052)
			(xy 304.986255 -398.001914) (xy 304.956228 -398.020574) (xy 304.923283 -398.033397) (xy 304.888542 -398.039944)
			(xy 304.870866 -398.040352) (xy 304.870358 -398.040352) (xy 304.851579 -398.039941) (xy 304.814744 -398.032613)
			(xy 304.780043 -398.018246) (xy 304.748809 -397.997391) (xy 304.722238 -397.970848) (xy 304.70135 -397.939635)
			(xy 304.686946 -397.90495) (xy 304.679579 -397.868122) (xy 304.679096 -397.849344) (xy 304.679542 -397.830229)
			(xy 304.687111 -397.792756) (xy 304.701977 -397.757536) (xy 304.723545 -397.725972) (xy 304.750957 -397.699324)
			(xy 304.783117 -397.678655) (xy 304.800762 -397.67129) (xy 304.810922 -397.667226) (xy 304.826416 -397.651478)
			(xy 304.855626 -397.568166) (xy 304.858821 -397.55758) (xy 304.856863 -397.535584) (xy 304.851816 -397.525748)
			(xy 304.723546 -397.304006) (xy 304.711608 -397.279876) (xy 304.706771 -397.270361) (xy 304.690989 -397.256032)
			(xy 304.67075 -397.249343) (xy 304.649538 -397.251445) (xy 304.631006 -397.261977) (xy 304.624232 -397.270224)
			(xy 304.613289 -397.284304) (xy 304.587103 -397.308505) (xy 304.556885 -397.327432) (xy 304.523681 -397.340427)
			(xy 304.488644 -397.347041) (xy 304.470816 -397.34744) (xy 304.470308 -397.34744) (xy 304.463428 -397.347437)
			(xy 304.449698 -397.346547) (xy 304.442876 -397.345662) (xy 304.428398 -397.343376) (xy 304.401728 -397.35506)
			(xy 304.342038 -397.442944) (xy 304.337011 -397.451076) (xy 304.33284 -397.469721) (xy 304.335782 -397.488599)
			(xy 304.34026 -397.497046) (xy 304.45583 -397.696944) (xy 304.456084 -397.697452) (xy 304.456338 -397.697452)
			(xy 304.457608 -397.699992) (xy 304.46988 -397.722908) (xy 304.487286 -397.771886) (xy 304.49616 -397.823101)
			(xy 304.496724 -397.84909) (xy 304.496724 -397.849344) (xy 304.496279 -397.873323) (xy 304.488775 -397.92069)
			(xy 304.473958 -397.966302) (xy 304.452192 -398.009036) (xy 304.424014 -398.047843) (xy 304.390115 -398.081767)
			(xy 304.351329 -398.109974) (xy 304.308611 -398.131771) (xy 304.26301 -398.146622) (xy 304.215649 -398.154161)
			(xy 304.19167 -398.154652) (xy 304.191162 -398.154652) (xy 304.167499 -398.154163) (xy 304.120741 -398.146861)
			(xy 304.075666 -398.132439) (xy 304.033354 -398.111241) (xy 303.994815 -398.083774) (xy 303.960971 -398.050695)
			(xy 303.932631 -398.012793) (xy 303.92116 -397.992092) (xy 303.920906 -397.99133) (xy 303.907952 -397.968978)
			(xy 303.90252 -397.96057) (xy 303.88665 -397.948408) (xy 303.867334 -397.943242) (xy 303.847511 -397.945858)
			(xy 303.83861 -397.950436) (xy 303.829466 -397.95577) (xy 303.82337 -397.964152) (xy 303.812441 -397.97805)
			(xy 303.786357 -398.001912) (xy 303.756331 -398.020573) (xy 303.723386 -398.033396) (xy 303.688646 -398.039944)
			(xy 303.67097 -398.040352) (xy 303.670462 -398.040352) (xy 303.651684 -398.039938) (xy 303.614848 -398.03261)
			(xy 303.580148 -398.018244) (xy 303.548913 -397.997389) (xy 303.522342 -397.970847) (xy 303.501454 -397.939634)
			(xy 303.48705 -397.904949) (xy 303.479683 -397.868122) (xy 303.4792 -397.849344) (xy 303.479643 -397.830229)
			(xy 303.487213 -397.792756) (xy 303.502079 -397.757535) (xy 303.523648 -397.725971) (xy 303.55106 -397.699323)
			(xy 303.583221 -397.678655) (xy 303.600866 -397.67129) (xy 303.611026 -397.667226) (xy 303.62652 -397.651478)
			(xy 303.65573 -397.568166) (xy 303.658924 -397.55758) (xy 303.656967 -397.535584) (xy 303.65192 -397.525748)
			(xy 303.52365 -397.304006) (xy 303.511712 -397.279876) (xy 303.506869 -397.270364) (xy 303.491089 -397.256036)
			(xy 303.470852 -397.249346) (xy 303.449641 -397.251447) (xy 303.431109 -397.261978) (xy 303.424336 -397.270224)
			(xy 303.413408 -397.284283) (xy 303.387267 -397.308457) (xy 303.357102 -397.327373) (xy 303.323956 -397.340377)
			(xy 303.288976 -397.34702) (xy 303.271174 -397.34744) (xy 303.270666 -397.34744) (xy 303.250651 -397.34685)
			(xy 303.211497 -397.338521) (xy 303.174929 -397.322234) (xy 303.142547 -397.298702) (xy 303.115764 -397.268951)
			(xy 303.095751 -397.234283) (xy 303.083382 -397.196211) (xy 303.079198 -397.1564) (xy 280.68524 -397.1564)
			(xy 280.68524 -399.143474) (xy 303.264049 -399.143474) (xy 303.268191 -399.108032) (xy 303.280395 -399.074501)
			(xy 303.300004 -399.044688) (xy 303.325959 -399.020201) (xy 303.356861 -399.002359) (xy 303.391045 -398.992125)
			(xy 303.426668 -398.990051) (xy 303.461809 -398.996247) (xy 303.494574 -399.01038) (xy 303.523196 -399.031689)
			(xy 303.546133 -399.059024) (xy 303.562147 -399.090911) (xy 303.570376 -399.125632) (xy 303.570894 -399.143474)
			(xy 304.463945 -399.143474) (xy 304.468087 -399.108032) (xy 304.480291 -399.074501) (xy 304.4999 -399.044688)
			(xy 304.525855 -399.020201) (xy 304.556757 -399.002359) (xy 304.590941 -398.992125) (xy 304.626564 -398.990051)
			(xy 304.661705 -398.996247) (xy 304.69447 -399.01038) (xy 304.723092 -399.031689) (xy 304.746029 -399.059024)
			(xy 304.762043 -399.090911) (xy 304.770272 -399.125632) (xy 304.77079 -399.143474) (xy 305.664095 -399.143474)
			(xy 305.668237 -399.108032) (xy 305.680441 -399.074501) (xy 305.70005 -399.044688) (xy 305.726005 -399.020201)
			(xy 305.756907 -399.002359) (xy 305.791091 -398.992125) (xy 305.826714 -398.990051) (xy 305.861855 -398.996247)
			(xy 305.89462 -399.01038) (xy 305.923242 -399.031689) (xy 305.946179 -399.059024) (xy 305.962193 -399.090911)
			(xy 305.970422 -399.125632) (xy 305.97094 -399.143474) (xy 306.863991 -399.143474) (xy 306.868133 -399.108032)
			(xy 306.880337 -399.074501) (xy 306.899946 -399.044688) (xy 306.925901 -399.020201) (xy 306.956803 -399.002359)
			(xy 306.990987 -398.992125) (xy 307.02661 -398.990051) (xy 307.061751 -398.996247) (xy 307.094516 -399.01038)
			(xy 307.123138 -399.031689) (xy 307.146075 -399.059024) (xy 307.162089 -399.090911) (xy 307.170318 -399.125632)
			(xy 307.170836 -399.143474) (xy 308.064141 -399.143474) (xy 308.068283 -399.108032) (xy 308.080487 -399.074501)
			(xy 308.100096 -399.044688) (xy 308.126051 -399.020201) (xy 308.156953 -399.002359) (xy 308.191137 -398.992125)
			(xy 308.22676 -398.990051) (xy 308.261901 -398.996247) (xy 308.294666 -399.01038) (xy 308.323288 -399.031689)
			(xy 308.346225 -399.059024) (xy 308.362239 -399.090911) (xy 308.370468 -399.125632) (xy 308.370986 -399.143474)
			(xy 309.264037 -399.143474) (xy 309.268179 -399.108032) (xy 309.280383 -399.074501) (xy 309.299992 -399.044688)
			(xy 309.325947 -399.020201) (xy 309.356849 -399.002359) (xy 309.391033 -398.992125) (xy 309.426656 -398.990051)
			(xy 309.461797 -398.996247) (xy 309.494562 -399.01038) (xy 309.523184 -399.031689) (xy 309.546121 -399.059024)
			(xy 309.562135 -399.090911) (xy 309.570364 -399.125632) (xy 309.570882 -399.143474) (xy 310.464187 -399.143474)
			(xy 310.468329 -399.108032) (xy 310.480533 -399.074501) (xy 310.500142 -399.044688) (xy 310.526097 -399.020201)
			(xy 310.556999 -399.002359) (xy 310.591183 -398.992125) (xy 310.626806 -398.990051) (xy 310.661947 -398.996247)
			(xy 310.694712 -399.01038) (xy 310.723334 -399.031689) (xy 310.746271 -399.059024) (xy 310.762285 -399.090911)
			(xy 310.770514 -399.125632) (xy 310.771032 -399.143474) (xy 311.664083 -399.143474) (xy 311.668225 -399.108032)
			(xy 311.680429 -399.074501) (xy 311.700038 -399.044688) (xy 311.725993 -399.020201) (xy 311.756895 -399.002359)
			(xy 311.791079 -398.992125) (xy 311.826702 -398.990051) (xy 311.861843 -398.996247) (xy 311.894608 -399.01038)
			(xy 311.92323 -399.031689) (xy 311.946167 -399.059024) (xy 311.962181 -399.090911) (xy 311.97041 -399.125632)
			(xy 311.970928 -399.143474) (xy 312.863979 -399.143474) (xy 312.868121 -399.108032) (xy 312.880325 -399.074501)
			(xy 312.899934 -399.044688) (xy 312.925889 -399.020201) (xy 312.956791 -399.002359) (xy 312.990975 -398.992125)
			(xy 313.026598 -398.990051) (xy 313.061739 -398.996247) (xy 313.094504 -399.01038) (xy 313.123126 -399.031689)
			(xy 313.146063 -399.059024) (xy 313.162077 -399.090911) (xy 313.170306 -399.125632) (xy 313.170824 -399.143474)
			(xy 314.064129 -399.143474) (xy 314.068271 -399.108032) (xy 314.080475 -399.074501) (xy 314.100084 -399.044688)
			(xy 314.126039 -399.020201) (xy 314.156941 -399.002359) (xy 314.191125 -398.992125) (xy 314.226748 -398.990051)
			(xy 314.261889 -398.996247) (xy 314.294654 -399.01038) (xy 314.323276 -399.031689) (xy 314.346213 -399.059024)
			(xy 314.362227 -399.090911) (xy 314.370456 -399.125632) (xy 314.370974 -399.143474) (xy 315.264025 -399.143474)
			(xy 315.268167 -399.108032) (xy 315.280371 -399.074501) (xy 315.29998 -399.044688) (xy 315.325935 -399.020201)
			(xy 315.356837 -399.002359) (xy 315.391021 -398.992125) (xy 315.426644 -398.990051) (xy 315.461785 -398.996247)
			(xy 315.49455 -399.01038) (xy 315.523172 -399.031689) (xy 315.546109 -399.059024) (xy 315.562123 -399.090911)
			(xy 315.570352 -399.125632) (xy 315.57087 -399.143474) (xy 316.464175 -399.143474) (xy 316.468317 -399.108032)
			(xy 316.480521 -399.074501) (xy 316.50013 -399.044688) (xy 316.526085 -399.020201) (xy 316.556987 -399.002359)
			(xy 316.591171 -398.992125) (xy 316.626794 -398.990051) (xy 316.661935 -398.996247) (xy 316.6947 -399.01038)
			(xy 316.723322 -399.031689) (xy 316.746259 -399.059024) (xy 316.762273 -399.090911) (xy 316.770502 -399.125632)
			(xy 316.77102 -399.143474) (xy 317.664071 -399.143474) (xy 317.668213 -399.108032) (xy 317.680417 -399.074501)
			(xy 317.700026 -399.044688) (xy 317.725981 -399.020201) (xy 317.756883 -399.002359) (xy 317.791067 -398.992125)
			(xy 317.82669 -398.990051) (xy 317.861831 -398.996247) (xy 317.894596 -399.01038) (xy 317.923218 -399.031689)
			(xy 317.946155 -399.059024) (xy 317.962169 -399.090911) (xy 317.970398 -399.125632) (xy 317.970916 -399.143474)
			(xy 318.863967 -399.143474) (xy 318.868109 -399.108032) (xy 318.880313 -399.074501) (xy 318.899922 -399.044688)
			(xy 318.925877 -399.020201) (xy 318.956779 -399.002359) (xy 318.990963 -398.992125) (xy 319.026586 -398.990051)
			(xy 319.061727 -398.996247) (xy 319.094492 -399.01038) (xy 319.123114 -399.031689) (xy 319.146051 -399.059024)
			(xy 319.162065 -399.090911) (xy 319.170294 -399.125632) (xy 319.170812 -399.143474) (xy 320.064117 -399.143474)
			(xy 320.068259 -399.108032) (xy 320.080463 -399.074501) (xy 320.100072 -399.044688) (xy 320.126027 -399.020201)
			(xy 320.156929 -399.002359) (xy 320.191113 -398.992125) (xy 320.226736 -398.990051) (xy 320.261877 -398.996247)
			(xy 320.294642 -399.01038) (xy 320.323264 -399.031689) (xy 320.346201 -399.059024) (xy 320.362215 -399.090911)
			(xy 320.370444 -399.125632) (xy 320.370962 -399.143474) (xy 321.264013 -399.143474) (xy 321.268155 -399.108032)
			(xy 321.280359 -399.074501) (xy 321.299968 -399.044688) (xy 321.325923 -399.020201) (xy 321.356825 -399.002359)
			(xy 321.391009 -398.992125) (xy 321.426632 -398.990051) (xy 321.461773 -398.996247) (xy 321.494538 -399.01038)
			(xy 321.52316 -399.031689) (xy 321.546097 -399.059024) (xy 321.562111 -399.090911) (xy 321.57034 -399.125632)
			(xy 321.570858 -399.143474) (xy 335.791797 -399.143474) (xy 335.795939 -399.108032) (xy 335.808143 -399.074501)
			(xy 335.827752 -399.044688) (xy 335.853707 -399.020201) (xy 335.884609 -399.002359) (xy 335.918793 -398.992125)
			(xy 335.954416 -398.990051) (xy 335.989557 -398.996247) (xy 336.022322 -399.01038) (xy 336.050944 -399.031689)
			(xy 336.073881 -399.059024) (xy 336.089895 -399.090911) (xy 336.098124 -399.125632) (xy 336.098642 -399.143474)
			(xy 336.991693 -399.143474) (xy 336.995835 -399.108032) (xy 337.008039 -399.074501) (xy 337.027648 -399.044688)
			(xy 337.053603 -399.020201) (xy 337.084505 -399.002359) (xy 337.118689 -398.992125) (xy 337.154312 -398.990051)
			(xy 337.189453 -398.996247) (xy 337.222218 -399.01038) (xy 337.25084 -399.031689) (xy 337.273777 -399.059024)
			(xy 337.289791 -399.090911) (xy 337.29802 -399.125632) (xy 337.298538 -399.143474) (xy 338.191843 -399.143474)
			(xy 338.195985 -399.108032) (xy 338.208189 -399.074501) (xy 338.227798 -399.044688) (xy 338.253753 -399.020201)
			(xy 338.284655 -399.002359) (xy 338.318839 -398.992125) (xy 338.354462 -398.990051) (xy 338.389603 -398.996247)
			(xy 338.422368 -399.01038) (xy 338.45099 -399.031689) (xy 338.473927 -399.059024) (xy 338.489941 -399.090911)
			(xy 338.49817 -399.125632) (xy 338.498688 -399.143474) (xy 339.391739 -399.143474) (xy 339.395881 -399.108032)
			(xy 339.408085 -399.074501) (xy 339.427694 -399.044688) (xy 339.453649 -399.020201) (xy 339.484551 -399.002359)
			(xy 339.518735 -398.992125) (xy 339.554358 -398.990051) (xy 339.589499 -398.996247) (xy 339.622264 -399.01038)
			(xy 339.650886 -399.031689) (xy 339.673823 -399.059024) (xy 339.689837 -399.090911) (xy 339.698066 -399.125632)
			(xy 339.698584 -399.143474) (xy 340.591889 -399.143474) (xy 340.596031 -399.108032) (xy 340.608235 -399.074501)
			(xy 340.627844 -399.044688) (xy 340.653799 -399.020201) (xy 340.684701 -399.002359) (xy 340.718885 -398.992125)
			(xy 340.754508 -398.990051) (xy 340.789649 -398.996247) (xy 340.822414 -399.01038) (xy 340.851036 -399.031689)
			(xy 340.873973 -399.059024) (xy 340.889987 -399.090911) (xy 340.898216 -399.125632) (xy 340.898734 -399.143474)
			(xy 341.791785 -399.143474) (xy 341.795927 -399.108032) (xy 341.808131 -399.074501) (xy 341.82774 -399.044688)
			(xy 341.853695 -399.020201) (xy 341.884597 -399.002359) (xy 341.918781 -398.992125) (xy 341.954404 -398.990051)
			(xy 341.989545 -398.996247) (xy 342.02231 -399.01038) (xy 342.050932 -399.031689) (xy 342.073869 -399.059024)
			(xy 342.089883 -399.090911) (xy 342.098112 -399.125632) (xy 342.09863 -399.143474) (xy 342.991935 -399.143474)
			(xy 342.996077 -399.108032) (xy 343.008281 -399.074501) (xy 343.02789 -399.044688) (xy 343.053845 -399.020201)
			(xy 343.084747 -399.002359) (xy 343.118931 -398.992125) (xy 343.154554 -398.990051) (xy 343.189695 -398.996247)
			(xy 343.22246 -399.01038) (xy 343.251082 -399.031689) (xy 343.274019 -399.059024) (xy 343.290033 -399.090911)
			(xy 343.298262 -399.125632) (xy 343.29878 -399.143474) (xy 344.191831 -399.143474) (xy 344.195973 -399.108032)
			(xy 344.208177 -399.074501) (xy 344.227786 -399.044688) (xy 344.253741 -399.020201) (xy 344.284643 -399.002359)
			(xy 344.318827 -398.992125) (xy 344.35445 -398.990051) (xy 344.389591 -398.996247) (xy 344.422356 -399.01038)
			(xy 344.450978 -399.031689) (xy 344.473915 -399.059024) (xy 344.489929 -399.090911) (xy 344.498158 -399.125632)
			(xy 344.498676 -399.143474) (xy 345.391727 -399.143474) (xy 345.395869 -399.108032) (xy 345.408073 -399.074501)
			(xy 345.427682 -399.044688) (xy 345.453637 -399.020201) (xy 345.484539 -399.002359) (xy 345.518723 -398.992125)
			(xy 345.554346 -398.990051) (xy 345.589487 -398.996247) (xy 345.622252 -399.01038) (xy 345.650874 -399.031689)
			(xy 345.673811 -399.059024) (xy 345.689825 -399.090911) (xy 345.698054 -399.125632) (xy 345.698572 -399.143474)
			(xy 346.591877 -399.143474) (xy 346.596019 -399.108032) (xy 346.608223 -399.074501) (xy 346.627832 -399.044688)
			(xy 346.653787 -399.020201) (xy 346.684689 -399.002359) (xy 346.718873 -398.992125) (xy 346.754496 -398.990051)
			(xy 346.789637 -398.996247) (xy 346.822402 -399.01038) (xy 346.851024 -399.031689) (xy 346.873961 -399.059024)
			(xy 346.889975 -399.090911) (xy 346.898204 -399.125632) (xy 346.898722 -399.143474) (xy 347.791773 -399.143474)
			(xy 347.795915 -399.108032) (xy 347.808119 -399.074501) (xy 347.827728 -399.044688) (xy 347.853683 -399.020201)
			(xy 347.884585 -399.002359) (xy 347.918769 -398.992125) (xy 347.954392 -398.990051) (xy 347.989533 -398.996247)
			(xy 348.022298 -399.01038) (xy 348.05092 -399.031689) (xy 348.073857 -399.059024) (xy 348.089871 -399.090911)
			(xy 348.0981 -399.125632) (xy 348.098618 -399.143474) (xy 348.991923 -399.143474) (xy 348.996065 -399.108032)
			(xy 349.008269 -399.074501) (xy 349.027878 -399.044688) (xy 349.053833 -399.020201) (xy 349.084735 -399.002359)
			(xy 349.118919 -398.992125) (xy 349.154542 -398.990051) (xy 349.189683 -398.996247) (xy 349.222448 -399.01038)
			(xy 349.25107 -399.031689) (xy 349.274007 -399.059024) (xy 349.290021 -399.090911) (xy 349.29825 -399.125632)
			(xy 349.298768 -399.143474) (xy 350.191819 -399.143474) (xy 350.195961 -399.108032) (xy 350.208165 -399.074501)
			(xy 350.227774 -399.044688) (xy 350.253729 -399.020201) (xy 350.284631 -399.002359) (xy 350.318815 -398.992125)
			(xy 350.354438 -398.990051) (xy 350.389579 -398.996247) (xy 350.422344 -399.01038) (xy 350.450966 -399.031689)
			(xy 350.473903 -399.059024) (xy 350.489917 -399.090911) (xy 350.498146 -399.125632) (xy 350.498664 -399.143474)
			(xy 351.391715 -399.143474) (xy 351.395857 -399.108032) (xy 351.408061 -399.074501) (xy 351.42767 -399.044688)
			(xy 351.453625 -399.020201) (xy 351.484527 -399.002359) (xy 351.518711 -398.992125) (xy 351.554334 -398.990051)
			(xy 351.589475 -398.996247) (xy 351.62224 -399.01038) (xy 351.650862 -399.031689) (xy 351.673799 -399.059024)
			(xy 351.689813 -399.090911) (xy 351.698042 -399.125632) (xy 351.69856 -399.143474) (xy 352.591865 -399.143474)
			(xy 352.596007 -399.108032) (xy 352.608211 -399.074501) (xy 352.62782 -399.044688) (xy 352.653775 -399.020201)
			(xy 352.684677 -399.002359) (xy 352.718861 -398.992125) (xy 352.754484 -398.990051) (xy 352.789625 -398.996247)
			(xy 352.82239 -399.01038) (xy 352.851012 -399.031689) (xy 352.873949 -399.059024) (xy 352.889963 -399.090911)
			(xy 352.898192 -399.125632) (xy 352.89871 -399.143474) (xy 353.791761 -399.143474) (xy 353.795903 -399.108032)
			(xy 353.808107 -399.074501) (xy 353.827716 -399.044688) (xy 353.853671 -399.020201) (xy 353.884573 -399.002359)
			(xy 353.918757 -398.992125) (xy 353.95438 -398.990051) (xy 353.989521 -398.996247) (xy 354.022286 -399.01038)
			(xy 354.050908 -399.031689) (xy 354.073845 -399.059024) (xy 354.089859 -399.090911) (xy 354.098088 -399.125632)
			(xy 354.098606 -399.143474) (xy 370.364245 -399.143474) (xy 370.368387 -399.108032) (xy 370.380591 -399.074501)
			(xy 370.4002 -399.044688) (xy 370.426155 -399.020201) (xy 370.457057 -399.002359) (xy 370.491241 -398.992125)
			(xy 370.526864 -398.990051) (xy 370.562005 -398.996247) (xy 370.59477 -399.01038) (xy 370.623392 -399.031689)
			(xy 370.646329 -399.059024) (xy 370.662343 -399.090911) (xy 370.670572 -399.125632) (xy 370.67109 -399.143474)
			(xy 371.564141 -399.143474) (xy 371.568283 -399.108032) (xy 371.580487 -399.074501) (xy 371.600096 -399.044688)
			(xy 371.626051 -399.020201) (xy 371.656953 -399.002359) (xy 371.691137 -398.992125) (xy 371.72676 -398.990051)
			(xy 371.761901 -398.996247) (xy 371.794666 -399.01038) (xy 371.823288 -399.031689) (xy 371.846225 -399.059024)
			(xy 371.862239 -399.090911) (xy 371.870468 -399.125632) (xy 371.870986 -399.143474) (xy 372.764291 -399.143474)
			(xy 372.768433 -399.108032) (xy 372.780637 -399.074501) (xy 372.800246 -399.044688) (xy 372.826201 -399.020201)
			(xy 372.857103 -399.002359) (xy 372.891287 -398.992125) (xy 372.92691 -398.990051) (xy 372.962051 -398.996247)
			(xy 372.994816 -399.01038) (xy 373.023438 -399.031689) (xy 373.046375 -399.059024) (xy 373.062389 -399.090911)
			(xy 373.070618 -399.125632) (xy 373.071136 -399.143474) (xy 373.964187 -399.143474) (xy 373.968329 -399.108032)
			(xy 373.980533 -399.074501) (xy 374.000142 -399.044688) (xy 374.026097 -399.020201) (xy 374.056999 -399.002359)
			(xy 374.091183 -398.992125) (xy 374.126806 -398.990051) (xy 374.161947 -398.996247) (xy 374.194712 -399.01038)
			(xy 374.223334 -399.031689) (xy 374.246271 -399.059024) (xy 374.262285 -399.090911) (xy 374.270514 -399.125632)
			(xy 374.271032 -399.143474) (xy 375.164337 -399.143474) (xy 375.168479 -399.108032) (xy 375.180683 -399.074501)
			(xy 375.200292 -399.044688) (xy 375.226247 -399.020201) (xy 375.257149 -399.002359) (xy 375.291333 -398.992125)
			(xy 375.326956 -398.990051) (xy 375.362097 -398.996247) (xy 375.394862 -399.01038) (xy 375.423484 -399.031689)
			(xy 375.446421 -399.059024) (xy 375.462435 -399.090911) (xy 375.470664 -399.125632) (xy 375.471182 -399.143474)
			(xy 376.364233 -399.143474) (xy 376.368375 -399.108032) (xy 376.380579 -399.074501) (xy 376.400188 -399.044688)
			(xy 376.426143 -399.020201) (xy 376.457045 -399.002359) (xy 376.491229 -398.992125) (xy 376.526852 -398.990051)
			(xy 376.561993 -398.996247) (xy 376.594758 -399.01038) (xy 376.62338 -399.031689) (xy 376.646317 -399.059024)
			(xy 376.662331 -399.090911) (xy 376.67056 -399.125632) (xy 376.671078 -399.143474) (xy 377.564383 -399.143474)
			(xy 377.568525 -399.108032) (xy 377.580729 -399.074501) (xy 377.600338 -399.044688) (xy 377.626293 -399.020201)
			(xy 377.657195 -399.002359) (xy 377.691379 -398.992125) (xy 377.727002 -398.990051) (xy 377.762143 -398.996247)
			(xy 377.794908 -399.01038) (xy 377.82353 -399.031689) (xy 377.846467 -399.059024) (xy 377.862481 -399.090911)
			(xy 377.87071 -399.125632) (xy 377.871228 -399.143474) (xy 378.764279 -399.143474) (xy 378.768421 -399.108032)
			(xy 378.780625 -399.074501) (xy 378.800234 -399.044688) (xy 378.826189 -399.020201) (xy 378.857091 -399.002359)
			(xy 378.891275 -398.992125) (xy 378.926898 -398.990051) (xy 378.962039 -398.996247) (xy 378.994804 -399.01038)
			(xy 379.023426 -399.031689) (xy 379.046363 -399.059024) (xy 379.062377 -399.090911) (xy 379.070606 -399.125632)
			(xy 379.071124 -399.143474) (xy 379.964175 -399.143474) (xy 379.968317 -399.108032) (xy 379.980521 -399.074501)
			(xy 380.00013 -399.044688) (xy 380.026085 -399.020201) (xy 380.056987 -399.002359) (xy 380.091171 -398.992125)
			(xy 380.126794 -398.990051) (xy 380.161935 -398.996247) (xy 380.1947 -399.01038) (xy 380.223322 -399.031689)
			(xy 380.246259 -399.059024) (xy 380.262273 -399.090911) (xy 380.270502 -399.125632) (xy 380.27102 -399.143474)
			(xy 381.164325 -399.143474) (xy 381.168467 -399.108032) (xy 381.180671 -399.074501) (xy 381.20028 -399.044688)
			(xy 381.226235 -399.020201) (xy 381.257137 -399.002359) (xy 381.291321 -398.992125) (xy 381.326944 -398.990051)
			(xy 381.362085 -398.996247) (xy 381.39485 -399.01038) (xy 381.423472 -399.031689) (xy 381.446409 -399.059024)
			(xy 381.462423 -399.090911) (xy 381.470652 -399.125632) (xy 381.47117 -399.143474) (xy 382.364221 -399.143474)
			(xy 382.368363 -399.108032) (xy 382.380567 -399.074501) (xy 382.400176 -399.044688) (xy 382.426131 -399.020201)
			(xy 382.457033 -399.002359) (xy 382.491217 -398.992125) (xy 382.52684 -398.990051) (xy 382.561981 -398.996247)
			(xy 382.594746 -399.01038) (xy 382.623368 -399.031689) (xy 382.646305 -399.059024) (xy 382.662319 -399.090911)
			(xy 382.670548 -399.125632) (xy 382.671066 -399.143474) (xy 383.564371 -399.143474) (xy 383.568513 -399.108032)
			(xy 383.580717 -399.074501) (xy 383.600326 -399.044688) (xy 383.626281 -399.020201) (xy 383.657183 -399.002359)
			(xy 383.691367 -398.992125) (xy 383.72699 -398.990051) (xy 383.762131 -398.996247) (xy 383.794896 -399.01038)
			(xy 383.823518 -399.031689) (xy 383.846455 -399.059024) (xy 383.862469 -399.090911) (xy 383.870698 -399.125632)
			(xy 383.871216 -399.143474) (xy 384.764267 -399.143474) (xy 384.768409 -399.108032) (xy 384.780613 -399.074501)
			(xy 384.800222 -399.044688) (xy 384.826177 -399.020201) (xy 384.857079 -399.002359) (xy 384.891263 -398.992125)
			(xy 384.926886 -398.990051) (xy 384.962027 -398.996247) (xy 384.994792 -399.01038) (xy 385.023414 -399.031689)
			(xy 385.046351 -399.059024) (xy 385.062365 -399.090911) (xy 385.070594 -399.125632) (xy 385.071112 -399.143474)
			(xy 385.964163 -399.143474) (xy 385.968305 -399.108032) (xy 385.980509 -399.074501) (xy 386.000118 -399.044688)
			(xy 386.026073 -399.020201) (xy 386.056975 -399.002359) (xy 386.091159 -398.992125) (xy 386.126782 -398.990051)
			(xy 386.161923 -398.996247) (xy 386.194688 -399.01038) (xy 386.22331 -399.031689) (xy 386.246247 -399.059024)
			(xy 386.262261 -399.090911) (xy 386.27049 -399.125632) (xy 386.271008 -399.143474) (xy 387.164313 -399.143474)
			(xy 387.168455 -399.108032) (xy 387.180659 -399.074501) (xy 387.200268 -399.044688) (xy 387.226223 -399.020201)
			(xy 387.257125 -399.002359) (xy 387.291309 -398.992125) (xy 387.326932 -398.990051) (xy 387.362073 -398.996247)
			(xy 387.394838 -399.01038) (xy 387.42346 -399.031689) (xy 387.446397 -399.059024) (xy 387.462411 -399.090911)
			(xy 387.47064 -399.125632) (xy 387.471158 -399.143474) (xy 388.364209 -399.143474) (xy 388.368351 -399.108032)
			(xy 388.380555 -399.074501) (xy 388.400164 -399.044688) (xy 388.426119 -399.020201) (xy 388.457021 -399.002359)
			(xy 388.491205 -398.992125) (xy 388.526828 -398.990051) (xy 388.561969 -398.996247) (xy 388.594734 -399.01038)
			(xy 388.623356 -399.031689) (xy 388.646293 -399.059024) (xy 388.662307 -399.090911) (xy 388.670536 -399.125632)
			(xy 388.671054 -399.143474) (xy 402.891993 -399.143474) (xy 402.896135 -399.108032) (xy 402.908339 -399.074501)
			(xy 402.927948 -399.044688) (xy 402.953903 -399.020201) (xy 402.984805 -399.002359) (xy 403.018989 -398.992125)
			(xy 403.054612 -398.990051) (xy 403.089753 -398.996247) (xy 403.122518 -399.01038) (xy 403.15114 -399.031689)
			(xy 403.174077 -399.059024) (xy 403.190091 -399.090911) (xy 403.19832 -399.125632) (xy 403.198838 -399.143474)
			(xy 404.091889 -399.143474) (xy 404.096031 -399.108032) (xy 404.108235 -399.074501) (xy 404.127844 -399.044688)
			(xy 404.153799 -399.020201) (xy 404.184701 -399.002359) (xy 404.218885 -398.992125) (xy 404.254508 -398.990051)
			(xy 404.289649 -398.996247) (xy 404.322414 -399.01038) (xy 404.351036 -399.031689) (xy 404.373973 -399.059024)
			(xy 404.389987 -399.090911) (xy 404.398216 -399.125632) (xy 404.398734 -399.143474) (xy 405.292039 -399.143474)
			(xy 405.296181 -399.108032) (xy 405.308385 -399.074501) (xy 405.327994 -399.044688) (xy 405.353949 -399.020201)
			(xy 405.384851 -399.002359) (xy 405.419035 -398.992125) (xy 405.454658 -398.990051) (xy 405.489799 -398.996247)
			(xy 405.522564 -399.01038) (xy 405.551186 -399.031689) (xy 405.574123 -399.059024) (xy 405.590137 -399.090911)
			(xy 405.598366 -399.125632) (xy 405.598884 -399.143474) (xy 406.491935 -399.143474) (xy 406.496077 -399.108032)
			(xy 406.508281 -399.074501) (xy 406.52789 -399.044688) (xy 406.553845 -399.020201) (xy 406.584747 -399.002359)
			(xy 406.618931 -398.992125) (xy 406.654554 -398.990051) (xy 406.689695 -398.996247) (xy 406.72246 -399.01038)
			(xy 406.751082 -399.031689) (xy 406.774019 -399.059024) (xy 406.790033 -399.090911) (xy 406.798262 -399.125632)
			(xy 406.79878 -399.143474) (xy 407.692085 -399.143474) (xy 407.696227 -399.108032) (xy 407.708431 -399.074501)
			(xy 407.72804 -399.044688) (xy 407.753995 -399.020201) (xy 407.784897 -399.002359) (xy 407.819081 -398.992125)
			(xy 407.854704 -398.990051) (xy 407.889845 -398.996247) (xy 407.92261 -399.01038) (xy 407.951232 -399.031689)
			(xy 407.974169 -399.059024) (xy 407.990183 -399.090911) (xy 407.998412 -399.125632) (xy 407.99893 -399.143474)
			(xy 408.891981 -399.143474) (xy 408.896123 -399.108032) (xy 408.908327 -399.074501) (xy 408.927936 -399.044688)
			(xy 408.953891 -399.020201) (xy 408.984793 -399.002359) (xy 409.018977 -398.992125) (xy 409.0546 -398.990051)
			(xy 409.089741 -398.996247) (xy 409.122506 -399.01038) (xy 409.151128 -399.031689) (xy 409.174065 -399.059024)
			(xy 409.190079 -399.090911) (xy 409.198308 -399.125632) (xy 409.198826 -399.143474) (xy 410.092131 -399.143474)
			(xy 410.096273 -399.108032) (xy 410.108477 -399.074501) (xy 410.128086 -399.044688) (xy 410.154041 -399.020201)
			(xy 410.184943 -399.002359) (xy 410.219127 -398.992125) (xy 410.25475 -398.990051) (xy 410.289891 -398.996247)
			(xy 410.322656 -399.01038) (xy 410.351278 -399.031689) (xy 410.374215 -399.059024) (xy 410.390229 -399.090911)
			(xy 410.398458 -399.125632) (xy 410.398976 -399.143474) (xy 411.292027 -399.143474) (xy 411.296169 -399.108032)
			(xy 411.308373 -399.074501) (xy 411.327982 -399.044688) (xy 411.353937 -399.020201) (xy 411.384839 -399.002359)
			(xy 411.419023 -398.992125) (xy 411.454646 -398.990051) (xy 411.489787 -398.996247) (xy 411.522552 -399.01038)
			(xy 411.551174 -399.031689) (xy 411.574111 -399.059024) (xy 411.590125 -399.090911) (xy 411.598354 -399.125632)
			(xy 411.598872 -399.143474) (xy 412.491923 -399.143474) (xy 412.496065 -399.108032) (xy 412.508269 -399.074501)
			(xy 412.527878 -399.044688) (xy 412.553833 -399.020201) (xy 412.584735 -399.002359) (xy 412.618919 -398.992125)
			(xy 412.654542 -398.990051) (xy 412.689683 -398.996247) (xy 412.722448 -399.01038) (xy 412.75107 -399.031689)
			(xy 412.774007 -399.059024) (xy 412.790021 -399.090911) (xy 412.79825 -399.125632) (xy 412.798768 -399.143474)
			(xy 413.692073 -399.143474) (xy 413.696215 -399.108032) (xy 413.708419 -399.074501) (xy 413.728028 -399.044688)
			(xy 413.753983 -399.020201) (xy 413.784885 -399.002359) (xy 413.819069 -398.992125) (xy 413.854692 -398.990051)
			(xy 413.889833 -398.996247) (xy 413.922598 -399.01038) (xy 413.95122 -399.031689) (xy 413.974157 -399.059024)
			(xy 413.990171 -399.090911) (xy 413.9984 -399.125632) (xy 413.998918 -399.143474) (xy 414.891969 -399.143474)
			(xy 414.896111 -399.108032) (xy 414.908315 -399.074501) (xy 414.927924 -399.044688) (xy 414.953879 -399.020201)
			(xy 414.984781 -399.002359) (xy 415.018965 -398.992125) (xy 415.054588 -398.990051) (xy 415.089729 -398.996247)
			(xy 415.122494 -399.01038) (xy 415.151116 -399.031689) (xy 415.174053 -399.059024) (xy 415.190067 -399.090911)
			(xy 415.198296 -399.125632) (xy 415.198814 -399.143474) (xy 416.092119 -399.143474) (xy 416.096261 -399.108032)
			(xy 416.108465 -399.074501) (xy 416.128074 -399.044688) (xy 416.154029 -399.020201) (xy 416.184931 -399.002359)
			(xy 416.219115 -398.992125) (xy 416.254738 -398.990051) (xy 416.289879 -398.996247) (xy 416.322644 -399.01038)
			(xy 416.351266 -399.031689) (xy 416.374203 -399.059024) (xy 416.390217 -399.090911) (xy 416.398446 -399.125632)
			(xy 416.398964 -399.143474) (xy 417.292015 -399.143474) (xy 417.296157 -399.108032) (xy 417.308361 -399.074501)
			(xy 417.32797 -399.044688) (xy 417.353925 -399.020201) (xy 417.384827 -399.002359) (xy 417.419011 -398.992125)
			(xy 417.454634 -398.990051) (xy 417.489775 -398.996247) (xy 417.52254 -399.01038) (xy 417.551162 -399.031689)
			(xy 417.574099 -399.059024) (xy 417.590113 -399.090911) (xy 417.598342 -399.125632) (xy 417.59886 -399.143474)
			(xy 418.491911 -399.143474) (xy 418.496053 -399.108032) (xy 418.508257 -399.074501) (xy 418.527866 -399.044688)
			(xy 418.553821 -399.020201) (xy 418.584723 -399.002359) (xy 418.618907 -398.992125) (xy 418.65453 -398.990051)
			(xy 418.689671 -398.996247) (xy 418.722436 -399.01038) (xy 418.751058 -399.031689) (xy 418.773995 -399.059024)
			(xy 418.790009 -399.090911) (xy 418.798238 -399.125632) (xy 418.798756 -399.143474) (xy 419.692061 -399.143474)
			(xy 419.696203 -399.108032) (xy 419.708407 -399.074501) (xy 419.728016 -399.044688) (xy 419.753971 -399.020201)
			(xy 419.784873 -399.002359) (xy 419.819057 -398.992125) (xy 419.85468 -398.990051) (xy 419.889821 -398.996247)
			(xy 419.922586 -399.01038) (xy 419.951208 -399.031689) (xy 419.974145 -399.059024) (xy 419.990159 -399.090911)
			(xy 419.998388 -399.125632) (xy 419.998906 -399.143474) (xy 420.891957 -399.143474) (xy 420.896099 -399.108032)
			(xy 420.908303 -399.074501) (xy 420.927912 -399.044688) (xy 420.953867 -399.020201) (xy 420.984769 -399.002359)
			(xy 421.018953 -398.992125) (xy 421.054576 -398.990051) (xy 421.089717 -398.996247) (xy 421.122482 -399.01038)
			(xy 421.151104 -399.031689) (xy 421.174041 -399.059024) (xy 421.190055 -399.090911) (xy 421.198284 -399.125632)
			(xy 421.198802 -399.143474) (xy 421.198284 -399.161316) (xy 421.190055 -399.196037) (xy 421.174041 -399.227924)
			(xy 421.151104 -399.255259) (xy 421.122482 -399.276568) (xy 421.089717 -399.290701) (xy 421.054576 -399.296897)
			(xy 421.018953 -399.294823) (xy 420.984769 -399.284589) (xy 420.953867 -399.266747) (xy 420.927912 -399.24226)
			(xy 420.908303 -399.212447) (xy 420.896099 -399.178916) (xy 420.891957 -399.143474) (xy 419.998906 -399.143474)
			(xy 419.998388 -399.161316) (xy 419.990159 -399.196037) (xy 419.974145 -399.227924) (xy 419.951208 -399.255259)
			(xy 419.922586 -399.276568) (xy 419.889821 -399.290701) (xy 419.85468 -399.296897) (xy 419.819057 -399.294823)
			(xy 419.784873 -399.284589) (xy 419.753971 -399.266747) (xy 419.728016 -399.24226) (xy 419.708407 -399.212447)
			(xy 419.696203 -399.178916) (xy 419.692061 -399.143474) (xy 418.798756 -399.143474) (xy 418.798238 -399.161316)
			(xy 418.790009 -399.196037) (xy 418.773995 -399.227924) (xy 418.751058 -399.255259) (xy 418.722436 -399.276568)
			(xy 418.689671 -399.290701) (xy 418.65453 -399.296897) (xy 418.618907 -399.294823) (xy 418.584723 -399.284589)
			(xy 418.553821 -399.266747) (xy 418.527866 -399.24226) (xy 418.508257 -399.212447) (xy 418.496053 -399.178916)
			(xy 418.491911 -399.143474) (xy 417.59886 -399.143474) (xy 417.598342 -399.161316) (xy 417.590113 -399.196037)
			(xy 417.574099 -399.227924) (xy 417.551162 -399.255259) (xy 417.52254 -399.276568) (xy 417.489775 -399.290701)
			(xy 417.454634 -399.296897) (xy 417.419011 -399.294823) (xy 417.384827 -399.284589) (xy 417.353925 -399.266747)
			(xy 417.32797 -399.24226) (xy 417.308361 -399.212447) (xy 417.296157 -399.178916) (xy 417.292015 -399.143474)
			(xy 416.398964 -399.143474) (xy 416.398446 -399.161316) (xy 416.390217 -399.196037) (xy 416.374203 -399.227924)
			(xy 416.351266 -399.255259) (xy 416.322644 -399.276568) (xy 416.289879 -399.290701) (xy 416.254738 -399.296897)
			(xy 416.219115 -399.294823) (xy 416.184931 -399.284589) (xy 416.154029 -399.266747) (xy 416.128074 -399.24226)
			(xy 416.108465 -399.212447) (xy 416.096261 -399.178916) (xy 416.092119 -399.143474) (xy 415.198814 -399.143474)
			(xy 415.198296 -399.161316) (xy 415.190067 -399.196037) (xy 415.174053 -399.227924) (xy 415.151116 -399.255259)
			(xy 415.122494 -399.276568) (xy 415.089729 -399.290701) (xy 415.054588 -399.296897) (xy 415.018965 -399.294823)
			(xy 414.984781 -399.284589) (xy 414.953879 -399.266747) (xy 414.927924 -399.24226) (xy 414.908315 -399.212447)
			(xy 414.896111 -399.178916) (xy 414.891969 -399.143474) (xy 413.998918 -399.143474) (xy 413.9984 -399.161316)
			(xy 413.990171 -399.196037) (xy 413.974157 -399.227924) (xy 413.95122 -399.255259) (xy 413.922598 -399.276568)
			(xy 413.889833 -399.290701) (xy 413.854692 -399.296897) (xy 413.819069 -399.294823) (xy 413.784885 -399.284589)
			(xy 413.753983 -399.266747) (xy 413.728028 -399.24226) (xy 413.708419 -399.212447) (xy 413.696215 -399.178916)
			(xy 413.692073 -399.143474) (xy 412.798768 -399.143474) (xy 412.79825 -399.161316) (xy 412.790021 -399.196037)
			(xy 412.774007 -399.227924) (xy 412.75107 -399.255259) (xy 412.722448 -399.276568) (xy 412.689683 -399.290701)
			(xy 412.654542 -399.296897) (xy 412.618919 -399.294823) (xy 412.584735 -399.284589) (xy 412.553833 -399.266747)
			(xy 412.527878 -399.24226) (xy 412.508269 -399.212447) (xy 412.496065 -399.178916) (xy 412.491923 -399.143474)
			(xy 411.598872 -399.143474) (xy 411.598354 -399.161316) (xy 411.590125 -399.196037) (xy 411.574111 -399.227924)
			(xy 411.551174 -399.255259) (xy 411.522552 -399.276568) (xy 411.489787 -399.290701) (xy 411.454646 -399.296897)
			(xy 411.419023 -399.294823) (xy 411.384839 -399.284589) (xy 411.353937 -399.266747) (xy 411.327982 -399.24226)
			(xy 411.308373 -399.212447) (xy 411.296169 -399.178916) (xy 411.292027 -399.143474) (xy 410.398976 -399.143474)
			(xy 410.398458 -399.161316) (xy 410.390229 -399.196037) (xy 410.374215 -399.227924) (xy 410.351278 -399.255259)
			(xy 410.322656 -399.276568) (xy 410.289891 -399.290701) (xy 410.25475 -399.296897) (xy 410.219127 -399.294823)
			(xy 410.184943 -399.284589) (xy 410.154041 -399.266747) (xy 410.128086 -399.24226) (xy 410.108477 -399.212447)
			(xy 410.096273 -399.178916) (xy 410.092131 -399.143474) (xy 409.198826 -399.143474) (xy 409.198308 -399.161316)
			(xy 409.190079 -399.196037) (xy 409.174065 -399.227924) (xy 409.151128 -399.255259) (xy 409.122506 -399.276568)
			(xy 409.089741 -399.290701) (xy 409.0546 -399.296897) (xy 409.018977 -399.294823) (xy 408.984793 -399.284589)
			(xy 408.953891 -399.266747) (xy 408.927936 -399.24226) (xy 408.908327 -399.212447) (xy 408.896123 -399.178916)
			(xy 408.891981 -399.143474) (xy 407.99893 -399.143474) (xy 407.998412 -399.161316) (xy 407.990183 -399.196037)
			(xy 407.974169 -399.227924) (xy 407.951232 -399.255259) (xy 407.92261 -399.276568) (xy 407.889845 -399.290701)
			(xy 407.854704 -399.296897) (xy 407.819081 -399.294823) (xy 407.784897 -399.284589) (xy 407.753995 -399.266747)
			(xy 407.72804 -399.24226) (xy 407.708431 -399.212447) (xy 407.696227 -399.178916) (xy 407.692085 -399.143474)
			(xy 406.79878 -399.143474) (xy 406.798262 -399.161316) (xy 406.790033 -399.196037) (xy 406.774019 -399.227924)
			(xy 406.751082 -399.255259) (xy 406.72246 -399.276568) (xy 406.689695 -399.290701) (xy 406.654554 -399.296897)
			(xy 406.618931 -399.294823) (xy 406.584747 -399.284589) (xy 406.553845 -399.266747) (xy 406.52789 -399.24226)
			(xy 406.508281 -399.212447) (xy 406.496077 -399.178916) (xy 406.491935 -399.143474) (xy 405.598884 -399.143474)
			(xy 405.598366 -399.161316) (xy 405.590137 -399.196037) (xy 405.574123 -399.227924) (xy 405.551186 -399.255259)
			(xy 405.522564 -399.276568) (xy 405.489799 -399.290701) (xy 405.454658 -399.296897) (xy 405.419035 -399.294823)
			(xy 405.384851 -399.284589) (xy 405.353949 -399.266747) (xy 405.327994 -399.24226) (xy 405.308385 -399.212447)
			(xy 405.296181 -399.178916) (xy 405.292039 -399.143474) (xy 404.398734 -399.143474) (xy 404.398216 -399.161316)
			(xy 404.389987 -399.196037) (xy 404.373973 -399.227924) (xy 404.351036 -399.255259) (xy 404.322414 -399.276568)
			(xy 404.289649 -399.290701) (xy 404.254508 -399.296897) (xy 404.218885 -399.294823) (xy 404.184701 -399.284589)
			(xy 404.153799 -399.266747) (xy 404.127844 -399.24226) (xy 404.108235 -399.212447) (xy 404.096031 -399.178916)
			(xy 404.091889 -399.143474) (xy 403.198838 -399.143474) (xy 403.19832 -399.161316) (xy 403.190091 -399.196037)
			(xy 403.174077 -399.227924) (xy 403.15114 -399.255259) (xy 403.122518 -399.276568) (xy 403.089753 -399.290701)
			(xy 403.054612 -399.296897) (xy 403.018989 -399.294823) (xy 402.984805 -399.284589) (xy 402.953903 -399.266747)
			(xy 402.927948 -399.24226) (xy 402.908339 -399.212447) (xy 402.896135 -399.178916) (xy 402.891993 -399.143474)
			(xy 388.671054 -399.143474) (xy 388.670536 -399.161316) (xy 388.662307 -399.196037) (xy 388.646293 -399.227924)
			(xy 388.623356 -399.255259) (xy 388.594734 -399.276568) (xy 388.561969 -399.290701) (xy 388.526828 -399.296897)
			(xy 388.491205 -399.294823) (xy 388.457021 -399.284589) (xy 388.426119 -399.266747) (xy 388.400164 -399.24226)
			(xy 388.380555 -399.212447) (xy 388.368351 -399.178916) (xy 388.364209 -399.143474) (xy 387.471158 -399.143474)
			(xy 387.47064 -399.161316) (xy 387.462411 -399.196037) (xy 387.446397 -399.227924) (xy 387.42346 -399.255259)
			(xy 387.394838 -399.276568) (xy 387.362073 -399.290701) (xy 387.326932 -399.296897) (xy 387.291309 -399.294823)
			(xy 387.257125 -399.284589) (xy 387.226223 -399.266747) (xy 387.200268 -399.24226) (xy 387.180659 -399.212447)
			(xy 387.168455 -399.178916) (xy 387.164313 -399.143474) (xy 386.271008 -399.143474) (xy 386.27049 -399.161316)
			(xy 386.262261 -399.196037) (xy 386.246247 -399.227924) (xy 386.22331 -399.255259) (xy 386.194688 -399.276568)
			(xy 386.161923 -399.290701) (xy 386.126782 -399.296897) (xy 386.091159 -399.294823) (xy 386.056975 -399.284589)
			(xy 386.026073 -399.266747) (xy 386.000118 -399.24226) (xy 385.980509 -399.212447) (xy 385.968305 -399.178916)
			(xy 385.964163 -399.143474) (xy 385.071112 -399.143474) (xy 385.070594 -399.161316) (xy 385.062365 -399.196037)
			(xy 385.046351 -399.227924) (xy 385.023414 -399.255259) (xy 384.994792 -399.276568) (xy 384.962027 -399.290701)
			(xy 384.926886 -399.296897) (xy 384.891263 -399.294823) (xy 384.857079 -399.284589) (xy 384.826177 -399.266747)
			(xy 384.800222 -399.24226) (xy 384.780613 -399.212447) (xy 384.768409 -399.178916) (xy 384.764267 -399.143474)
			(xy 383.871216 -399.143474) (xy 383.870698 -399.161316) (xy 383.862469 -399.196037) (xy 383.846455 -399.227924)
			(xy 383.823518 -399.255259) (xy 383.794896 -399.276568) (xy 383.762131 -399.290701) (xy 383.72699 -399.296897)
			(xy 383.691367 -399.294823) (xy 383.657183 -399.284589) (xy 383.626281 -399.266747) (xy 383.600326 -399.24226)
			(xy 383.580717 -399.212447) (xy 383.568513 -399.178916) (xy 383.564371 -399.143474) (xy 382.671066 -399.143474)
			(xy 382.670548 -399.161316) (xy 382.662319 -399.196037) (xy 382.646305 -399.227924) (xy 382.623368 -399.255259)
			(xy 382.594746 -399.276568) (xy 382.561981 -399.290701) (xy 382.52684 -399.296897) (xy 382.491217 -399.294823)
			(xy 382.457033 -399.284589) (xy 382.426131 -399.266747) (xy 382.400176 -399.24226) (xy 382.380567 -399.212447)
			(xy 382.368363 -399.178916) (xy 382.364221 -399.143474) (xy 381.47117 -399.143474) (xy 381.470652 -399.161316)
			(xy 381.462423 -399.196037) (xy 381.446409 -399.227924) (xy 381.423472 -399.255259) (xy 381.39485 -399.276568)
			(xy 381.362085 -399.290701) (xy 381.326944 -399.296897) (xy 381.291321 -399.294823) (xy 381.257137 -399.284589)
			(xy 381.226235 -399.266747) (xy 381.20028 -399.24226) (xy 381.180671 -399.212447) (xy 381.168467 -399.178916)
			(xy 381.164325 -399.143474) (xy 380.27102 -399.143474) (xy 380.270502 -399.161316) (xy 380.262273 -399.196037)
			(xy 380.246259 -399.227924) (xy 380.223322 -399.255259) (xy 380.1947 -399.276568) (xy 380.161935 -399.290701)
			(xy 380.126794 -399.296897) (xy 380.091171 -399.294823) (xy 380.056987 -399.284589) (xy 380.026085 -399.266747)
			(xy 380.00013 -399.24226) (xy 379.980521 -399.212447) (xy 379.968317 -399.178916) (xy 379.964175 -399.143474)
			(xy 379.071124 -399.143474) (xy 379.070606 -399.161316) (xy 379.062377 -399.196037) (xy 379.046363 -399.227924)
			(xy 379.023426 -399.255259) (xy 378.994804 -399.276568) (xy 378.962039 -399.290701) (xy 378.926898 -399.296897)
			(xy 378.891275 -399.294823) (xy 378.857091 -399.284589) (xy 378.826189 -399.266747) (xy 378.800234 -399.24226)
			(xy 378.780625 -399.212447) (xy 378.768421 -399.178916) (xy 378.764279 -399.143474) (xy 377.871228 -399.143474)
			(xy 377.87071 -399.161316) (xy 377.862481 -399.196037) (xy 377.846467 -399.227924) (xy 377.82353 -399.255259)
			(xy 377.794908 -399.276568) (xy 377.762143 -399.290701) (xy 377.727002 -399.296897) (xy 377.691379 -399.294823)
			(xy 377.657195 -399.284589) (xy 377.626293 -399.266747) (xy 377.600338 -399.24226) (xy 377.580729 -399.212447)
			(xy 377.568525 -399.178916) (xy 377.564383 -399.143474) (xy 376.671078 -399.143474) (xy 376.67056 -399.161316)
			(xy 376.662331 -399.196037) (xy 376.646317 -399.227924) (xy 376.62338 -399.255259) (xy 376.594758 -399.276568)
			(xy 376.561993 -399.290701) (xy 376.526852 -399.296897) (xy 376.491229 -399.294823) (xy 376.457045 -399.284589)
			(xy 376.426143 -399.266747) (xy 376.400188 -399.24226) (xy 376.380579 -399.212447) (xy 376.368375 -399.178916)
			(xy 376.364233 -399.143474) (xy 375.471182 -399.143474) (xy 375.470664 -399.161316) (xy 375.462435 -399.196037)
			(xy 375.446421 -399.227924) (xy 375.423484 -399.255259) (xy 375.394862 -399.276568) (xy 375.362097 -399.290701)
			(xy 375.326956 -399.296897) (xy 375.291333 -399.294823) (xy 375.257149 -399.284589) (xy 375.226247 -399.266747)
			(xy 375.200292 -399.24226) (xy 375.180683 -399.212447) (xy 375.168479 -399.178916) (xy 375.164337 -399.143474)
			(xy 374.271032 -399.143474) (xy 374.270514 -399.161316) (xy 374.262285 -399.196037) (xy 374.246271 -399.227924)
			(xy 374.223334 -399.255259) (xy 374.194712 -399.276568) (xy 374.161947 -399.290701) (xy 374.126806 -399.296897)
			(xy 374.091183 -399.294823) (xy 374.056999 -399.284589) (xy 374.026097 -399.266747) (xy 374.000142 -399.24226)
			(xy 373.980533 -399.212447) (xy 373.968329 -399.178916) (xy 373.964187 -399.143474) (xy 373.071136 -399.143474)
			(xy 373.070618 -399.161316) (xy 373.062389 -399.196037) (xy 373.046375 -399.227924) (xy 373.023438 -399.255259)
			(xy 372.994816 -399.276568) (xy 372.962051 -399.290701) (xy 372.92691 -399.296897) (xy 372.891287 -399.294823)
			(xy 372.857103 -399.284589) (xy 372.826201 -399.266747) (xy 372.800246 -399.24226) (xy 372.780637 -399.212447)
			(xy 372.768433 -399.178916) (xy 372.764291 -399.143474) (xy 371.870986 -399.143474) (xy 371.870468 -399.161316)
			(xy 371.862239 -399.196037) (xy 371.846225 -399.227924) (xy 371.823288 -399.255259) (xy 371.794666 -399.276568)
			(xy 371.761901 -399.290701) (xy 371.72676 -399.296897) (xy 371.691137 -399.294823) (xy 371.656953 -399.284589)
			(xy 371.626051 -399.266747) (xy 371.600096 -399.24226) (xy 371.580487 -399.212447) (xy 371.568283 -399.178916)
			(xy 371.564141 -399.143474) (xy 370.67109 -399.143474) (xy 370.670572 -399.161316) (xy 370.662343 -399.196037)
			(xy 370.646329 -399.227924) (xy 370.623392 -399.255259) (xy 370.59477 -399.276568) (xy 370.562005 -399.290701)
			(xy 370.526864 -399.296897) (xy 370.491241 -399.294823) (xy 370.457057 -399.284589) (xy 370.426155 -399.266747)
			(xy 370.4002 -399.24226) (xy 370.380591 -399.212447) (xy 370.368387 -399.178916) (xy 370.364245 -399.143474)
			(xy 354.098606 -399.143474) (xy 354.098088 -399.161316) (xy 354.089859 -399.196037) (xy 354.073845 -399.227924)
			(xy 354.050908 -399.255259) (xy 354.022286 -399.276568) (xy 353.989521 -399.290701) (xy 353.95438 -399.296897)
			(xy 353.918757 -399.294823) (xy 353.884573 -399.284589) (xy 353.853671 -399.266747) (xy 353.827716 -399.24226)
			(xy 353.808107 -399.212447) (xy 353.795903 -399.178916) (xy 353.791761 -399.143474) (xy 352.89871 -399.143474)
			(xy 352.898192 -399.161316) (xy 352.889963 -399.196037) (xy 352.873949 -399.227924) (xy 352.851012 -399.255259)
			(xy 352.82239 -399.276568) (xy 352.789625 -399.290701) (xy 352.754484 -399.296897) (xy 352.718861 -399.294823)
			(xy 352.684677 -399.284589) (xy 352.653775 -399.266747) (xy 352.62782 -399.24226) (xy 352.608211 -399.212447)
			(xy 352.596007 -399.178916) (xy 352.591865 -399.143474) (xy 351.69856 -399.143474) (xy 351.698042 -399.161316)
			(xy 351.689813 -399.196037) (xy 351.673799 -399.227924) (xy 351.650862 -399.255259) (xy 351.62224 -399.276568)
			(xy 351.589475 -399.290701) (xy 351.554334 -399.296897) (xy 351.518711 -399.294823) (xy 351.484527 -399.284589)
			(xy 351.453625 -399.266747) (xy 351.42767 -399.24226) (xy 351.408061 -399.212447) (xy 351.395857 -399.178916)
			(xy 351.391715 -399.143474) (xy 350.498664 -399.143474) (xy 350.498146 -399.161316) (xy 350.489917 -399.196037)
			(xy 350.473903 -399.227924) (xy 350.450966 -399.255259) (xy 350.422344 -399.276568) (xy 350.389579 -399.290701)
			(xy 350.354438 -399.296897) (xy 350.318815 -399.294823) (xy 350.284631 -399.284589) (xy 350.253729 -399.266747)
			(xy 350.227774 -399.24226) (xy 350.208165 -399.212447) (xy 350.195961 -399.178916) (xy 350.191819 -399.143474)
			(xy 349.298768 -399.143474) (xy 349.29825 -399.161316) (xy 349.290021 -399.196037) (xy 349.274007 -399.227924)
			(xy 349.25107 -399.255259) (xy 349.222448 -399.276568) (xy 349.189683 -399.290701) (xy 349.154542 -399.296897)
			(xy 349.118919 -399.294823) (xy 349.084735 -399.284589) (xy 349.053833 -399.266747) (xy 349.027878 -399.24226)
			(xy 349.008269 -399.212447) (xy 348.996065 -399.178916) (xy 348.991923 -399.143474) (xy 348.098618 -399.143474)
			(xy 348.0981 -399.161316) (xy 348.089871 -399.196037) (xy 348.073857 -399.227924) (xy 348.05092 -399.255259)
			(xy 348.022298 -399.276568) (xy 347.989533 -399.290701) (xy 347.954392 -399.296897) (xy 347.918769 -399.294823)
			(xy 347.884585 -399.284589) (xy 347.853683 -399.266747) (xy 347.827728 -399.24226) (xy 347.808119 -399.212447)
			(xy 347.795915 -399.178916) (xy 347.791773 -399.143474) (xy 346.898722 -399.143474) (xy 346.898204 -399.161316)
			(xy 346.889975 -399.196037) (xy 346.873961 -399.227924) (xy 346.851024 -399.255259) (xy 346.822402 -399.276568)
			(xy 346.789637 -399.290701) (xy 346.754496 -399.296897) (xy 346.718873 -399.294823) (xy 346.684689 -399.284589)
			(xy 346.653787 -399.266747) (xy 346.627832 -399.24226) (xy 346.608223 -399.212447) (xy 346.596019 -399.178916)
			(xy 346.591877 -399.143474) (xy 345.698572 -399.143474) (xy 345.698054 -399.161316) (xy 345.689825 -399.196037)
			(xy 345.673811 -399.227924) (xy 345.650874 -399.255259) (xy 345.622252 -399.276568) (xy 345.589487 -399.290701)
			(xy 345.554346 -399.296897) (xy 345.518723 -399.294823) (xy 345.484539 -399.284589) (xy 345.453637 -399.266747)
			(xy 345.427682 -399.24226) (xy 345.408073 -399.212447) (xy 345.395869 -399.178916) (xy 345.391727 -399.143474)
			(xy 344.498676 -399.143474) (xy 344.498158 -399.161316) (xy 344.489929 -399.196037) (xy 344.473915 -399.227924)
			(xy 344.450978 -399.255259) (xy 344.422356 -399.276568) (xy 344.389591 -399.290701) (xy 344.35445 -399.296897)
			(xy 344.318827 -399.294823) (xy 344.284643 -399.284589) (xy 344.253741 -399.266747) (xy 344.227786 -399.24226)
			(xy 344.208177 -399.212447) (xy 344.195973 -399.178916) (xy 344.191831 -399.143474) (xy 343.29878 -399.143474)
			(xy 343.298262 -399.161316) (xy 343.290033 -399.196037) (xy 343.274019 -399.227924) (xy 343.251082 -399.255259)
			(xy 343.22246 -399.276568) (xy 343.189695 -399.290701) (xy 343.154554 -399.296897) (xy 343.118931 -399.294823)
			(xy 343.084747 -399.284589) (xy 343.053845 -399.266747) (xy 343.02789 -399.24226) (xy 343.008281 -399.212447)
			(xy 342.996077 -399.178916) (xy 342.991935 -399.143474) (xy 342.09863 -399.143474) (xy 342.098112 -399.161316)
			(xy 342.089883 -399.196037) (xy 342.073869 -399.227924) (xy 342.050932 -399.255259) (xy 342.02231 -399.276568)
			(xy 341.989545 -399.290701) (xy 341.954404 -399.296897) (xy 341.918781 -399.294823) (xy 341.884597 -399.284589)
			(xy 341.853695 -399.266747) (xy 341.82774 -399.24226) (xy 341.808131 -399.212447) (xy 341.795927 -399.178916)
			(xy 341.791785 -399.143474) (xy 340.898734 -399.143474) (xy 340.898216 -399.161316) (xy 340.889987 -399.196037)
			(xy 340.873973 -399.227924) (xy 340.851036 -399.255259) (xy 340.822414 -399.276568) (xy 340.789649 -399.290701)
			(xy 340.754508 -399.296897) (xy 340.718885 -399.294823) (xy 340.684701 -399.284589) (xy 340.653799 -399.266747)
			(xy 340.627844 -399.24226) (xy 340.608235 -399.212447) (xy 340.596031 -399.178916) (xy 340.591889 -399.143474)
			(xy 339.698584 -399.143474) (xy 339.698066 -399.161316) (xy 339.689837 -399.196037) (xy 339.673823 -399.227924)
			(xy 339.650886 -399.255259) (xy 339.622264 -399.276568) (xy 339.589499 -399.290701) (xy 339.554358 -399.296897)
			(xy 339.518735 -399.294823) (xy 339.484551 -399.284589) (xy 339.453649 -399.266747) (xy 339.427694 -399.24226)
			(xy 339.408085 -399.212447) (xy 339.395881 -399.178916) (xy 339.391739 -399.143474) (xy 338.498688 -399.143474)
			(xy 338.49817 -399.161316) (xy 338.489941 -399.196037) (xy 338.473927 -399.227924) (xy 338.45099 -399.255259)
			(xy 338.422368 -399.276568) (xy 338.389603 -399.290701) (xy 338.354462 -399.296897) (xy 338.318839 -399.294823)
			(xy 338.284655 -399.284589) (xy 338.253753 -399.266747) (xy 338.227798 -399.24226) (xy 338.208189 -399.212447)
			(xy 338.195985 -399.178916) (xy 338.191843 -399.143474) (xy 337.298538 -399.143474) (xy 337.29802 -399.161316)
			(xy 337.289791 -399.196037) (xy 337.273777 -399.227924) (xy 337.25084 -399.255259) (xy 337.222218 -399.276568)
			(xy 337.189453 -399.290701) (xy 337.154312 -399.296897) (xy 337.118689 -399.294823) (xy 337.084505 -399.284589)
			(xy 337.053603 -399.266747) (xy 337.027648 -399.24226) (xy 337.008039 -399.212447) (xy 336.995835 -399.178916)
			(xy 336.991693 -399.143474) (xy 336.098642 -399.143474) (xy 336.098124 -399.161316) (xy 336.089895 -399.196037)
			(xy 336.073881 -399.227924) (xy 336.050944 -399.255259) (xy 336.022322 -399.276568) (xy 335.989557 -399.290701)
			(xy 335.954416 -399.296897) (xy 335.918793 -399.294823) (xy 335.884609 -399.284589) (xy 335.853707 -399.266747)
			(xy 335.827752 -399.24226) (xy 335.808143 -399.212447) (xy 335.795939 -399.178916) (xy 335.791797 -399.143474)
			(xy 321.570858 -399.143474) (xy 321.57034 -399.161316) (xy 321.562111 -399.196037) (xy 321.546097 -399.227924)
			(xy 321.52316 -399.255259) (xy 321.494538 -399.276568) (xy 321.461773 -399.290701) (xy 321.426632 -399.296897)
			(xy 321.391009 -399.294823) (xy 321.356825 -399.284589) (xy 321.325923 -399.266747) (xy 321.299968 -399.24226)
			(xy 321.280359 -399.212447) (xy 321.268155 -399.178916) (xy 321.264013 -399.143474) (xy 320.370962 -399.143474)
			(xy 320.370444 -399.161316) (xy 320.362215 -399.196037) (xy 320.346201 -399.227924) (xy 320.323264 -399.255259)
			(xy 320.294642 -399.276568) (xy 320.261877 -399.290701) (xy 320.226736 -399.296897) (xy 320.191113 -399.294823)
			(xy 320.156929 -399.284589) (xy 320.126027 -399.266747) (xy 320.100072 -399.24226) (xy 320.080463 -399.212447)
			(xy 320.068259 -399.178916) (xy 320.064117 -399.143474) (xy 319.170812 -399.143474) (xy 319.170294 -399.161316)
			(xy 319.162065 -399.196037) (xy 319.146051 -399.227924) (xy 319.123114 -399.255259) (xy 319.094492 -399.276568)
			(xy 319.061727 -399.290701) (xy 319.026586 -399.296897) (xy 318.990963 -399.294823) (xy 318.956779 -399.284589)
			(xy 318.925877 -399.266747) (xy 318.899922 -399.24226) (xy 318.880313 -399.212447) (xy 318.868109 -399.178916)
			(xy 318.863967 -399.143474) (xy 317.970916 -399.143474) (xy 317.970398 -399.161316) (xy 317.962169 -399.196037)
			(xy 317.946155 -399.227924) (xy 317.923218 -399.255259) (xy 317.894596 -399.276568) (xy 317.861831 -399.290701)
			(xy 317.82669 -399.296897) (xy 317.791067 -399.294823) (xy 317.756883 -399.284589) (xy 317.725981 -399.266747)
			(xy 317.700026 -399.24226) (xy 317.680417 -399.212447) (xy 317.668213 -399.178916) (xy 317.664071 -399.143474)
			(xy 316.77102 -399.143474) (xy 316.770502 -399.161316) (xy 316.762273 -399.196037) (xy 316.746259 -399.227924)
			(xy 316.723322 -399.255259) (xy 316.6947 -399.276568) (xy 316.661935 -399.290701) (xy 316.626794 -399.296897)
			(xy 316.591171 -399.294823) (xy 316.556987 -399.284589) (xy 316.526085 -399.266747) (xy 316.50013 -399.24226)
			(xy 316.480521 -399.212447) (xy 316.468317 -399.178916) (xy 316.464175 -399.143474) (xy 315.57087 -399.143474)
			(xy 315.570352 -399.161316) (xy 315.562123 -399.196037) (xy 315.546109 -399.227924) (xy 315.523172 -399.255259)
			(xy 315.49455 -399.276568) (xy 315.461785 -399.290701) (xy 315.426644 -399.296897) (xy 315.391021 -399.294823)
			(xy 315.356837 -399.284589) (xy 315.325935 -399.266747) (xy 315.29998 -399.24226) (xy 315.280371 -399.212447)
			(xy 315.268167 -399.178916) (xy 315.264025 -399.143474) (xy 314.370974 -399.143474) (xy 314.370456 -399.161316)
			(xy 314.362227 -399.196037) (xy 314.346213 -399.227924) (xy 314.323276 -399.255259) (xy 314.294654 -399.276568)
			(xy 314.261889 -399.290701) (xy 314.226748 -399.296897) (xy 314.191125 -399.294823) (xy 314.156941 -399.284589)
			(xy 314.126039 -399.266747) (xy 314.100084 -399.24226) (xy 314.080475 -399.212447) (xy 314.068271 -399.178916)
			(xy 314.064129 -399.143474) (xy 313.170824 -399.143474) (xy 313.170306 -399.161316) (xy 313.162077 -399.196037)
			(xy 313.146063 -399.227924) (xy 313.123126 -399.255259) (xy 313.094504 -399.276568) (xy 313.061739 -399.290701)
			(xy 313.026598 -399.296897) (xy 312.990975 -399.294823) (xy 312.956791 -399.284589) (xy 312.925889 -399.266747)
			(xy 312.899934 -399.24226) (xy 312.880325 -399.212447) (xy 312.868121 -399.178916) (xy 312.863979 -399.143474)
			(xy 311.970928 -399.143474) (xy 311.97041 -399.161316) (xy 311.962181 -399.196037) (xy 311.946167 -399.227924)
			(xy 311.92323 -399.255259) (xy 311.894608 -399.276568) (xy 311.861843 -399.290701) (xy 311.826702 -399.296897)
			(xy 311.791079 -399.294823) (xy 311.756895 -399.284589) (xy 311.725993 -399.266747) (xy 311.700038 -399.24226)
			(xy 311.680429 -399.212447) (xy 311.668225 -399.178916) (xy 311.664083 -399.143474) (xy 310.771032 -399.143474)
			(xy 310.770514 -399.161316) (xy 310.762285 -399.196037) (xy 310.746271 -399.227924) (xy 310.723334 -399.255259)
			(xy 310.694712 -399.276568) (xy 310.661947 -399.290701) (xy 310.626806 -399.296897) (xy 310.591183 -399.294823)
			(xy 310.556999 -399.284589) (xy 310.526097 -399.266747) (xy 310.500142 -399.24226) (xy 310.480533 -399.212447)
			(xy 310.468329 -399.178916) (xy 310.464187 -399.143474) (xy 309.570882 -399.143474) (xy 309.570364 -399.161316)
			(xy 309.562135 -399.196037) (xy 309.546121 -399.227924) (xy 309.523184 -399.255259) (xy 309.494562 -399.276568)
			(xy 309.461797 -399.290701) (xy 309.426656 -399.296897) (xy 309.391033 -399.294823) (xy 309.356849 -399.284589)
			(xy 309.325947 -399.266747) (xy 309.299992 -399.24226) (xy 309.280383 -399.212447) (xy 309.268179 -399.178916)
			(xy 309.264037 -399.143474) (xy 308.370986 -399.143474) (xy 308.370468 -399.161316) (xy 308.362239 -399.196037)
			(xy 308.346225 -399.227924) (xy 308.323288 -399.255259) (xy 308.294666 -399.276568) (xy 308.261901 -399.290701)
			(xy 308.22676 -399.296897) (xy 308.191137 -399.294823) (xy 308.156953 -399.284589) (xy 308.126051 -399.266747)
			(xy 308.100096 -399.24226) (xy 308.080487 -399.212447) (xy 308.068283 -399.178916) (xy 308.064141 -399.143474)
			(xy 307.170836 -399.143474) (xy 307.170318 -399.161316) (xy 307.162089 -399.196037) (xy 307.146075 -399.227924)
			(xy 307.123138 -399.255259) (xy 307.094516 -399.276568) (xy 307.061751 -399.290701) (xy 307.02661 -399.296897)
			(xy 306.990987 -399.294823) (xy 306.956803 -399.284589) (xy 306.925901 -399.266747) (xy 306.899946 -399.24226)
			(xy 306.880337 -399.212447) (xy 306.868133 -399.178916) (xy 306.863991 -399.143474) (xy 305.97094 -399.143474)
			(xy 305.970422 -399.161316) (xy 305.962193 -399.196037) (xy 305.946179 -399.227924) (xy 305.923242 -399.255259)
			(xy 305.89462 -399.276568) (xy 305.861855 -399.290701) (xy 305.826714 -399.296897) (xy 305.791091 -399.294823)
			(xy 305.756907 -399.284589) (xy 305.726005 -399.266747) (xy 305.70005 -399.24226) (xy 305.680441 -399.212447)
			(xy 305.668237 -399.178916) (xy 305.664095 -399.143474) (xy 304.77079 -399.143474) (xy 304.770272 -399.161316)
			(xy 304.762043 -399.196037) (xy 304.746029 -399.227924) (xy 304.723092 -399.255259) (xy 304.69447 -399.276568)
			(xy 304.661705 -399.290701) (xy 304.626564 -399.296897) (xy 304.590941 -399.294823) (xy 304.556757 -399.284589)
			(xy 304.525855 -399.266747) (xy 304.4999 -399.24226) (xy 304.480291 -399.212447) (xy 304.468087 -399.178916)
			(xy 304.463945 -399.143474) (xy 303.570894 -399.143474) (xy 303.570376 -399.161316) (xy 303.562147 -399.196037)
			(xy 303.546133 -399.227924) (xy 303.523196 -399.255259) (xy 303.494574 -399.276568) (xy 303.461809 -399.290701)
			(xy 303.426668 -399.296897) (xy 303.391045 -399.294823) (xy 303.356861 -399.284589) (xy 303.325959 -399.266747)
			(xy 303.300004 -399.24226) (xy 303.280395 -399.212447) (xy 303.268191 -399.178916) (xy 303.264049 -399.143474)
			(xy 280.68524 -399.143474) (xy 280.68524 -399.701258) (xy 302.989996 -399.701258) (xy 302.989996 -399.625058)
			(xy 302.990462 -399.609601) (xy 302.99786 -399.579587) (xy 303.012226 -399.552214) (xy 303.032725 -399.529076)
			(xy 303.058166 -399.511515) (xy 303.08707 -399.500553) (xy 303.117758 -399.496827) (xy 303.148446 -399.500553)
			(xy 303.17735 -399.511515) (xy 303.202791 -399.529076) (xy 303.22329 -399.552214) (xy 303.237656 -399.579587)
			(xy 303.245054 -399.609601) (xy 303.24552 -399.625058) (xy 303.24552 -399.701258) (xy 304.189892 -399.701258)
			(xy 304.189892 -399.625058) (xy 304.190358 -399.609601) (xy 304.197756 -399.579587) (xy 304.212122 -399.552214)
			(xy 304.232621 -399.529076) (xy 304.258062 -399.511515) (xy 304.286966 -399.500553) (xy 304.317654 -399.496827)
			(xy 304.348342 -399.500553) (xy 304.377246 -399.511515) (xy 304.402687 -399.529076) (xy 304.423186 -399.552214)
			(xy 304.437552 -399.579587) (xy 304.44495 -399.609601) (xy 304.445416 -399.625058) (xy 304.445416 -399.701258)
			(xy 305.390296 -399.701258) (xy 305.390296 -399.625058) (xy 305.390761 -399.609632) (xy 305.398144 -399.579677)
			(xy 305.412481 -399.552359) (xy 305.43294 -399.529266) (xy 305.45833 -399.51174) (xy 305.487177 -399.5008)
			(xy 305.517804 -399.497082) (xy 305.548431 -399.5008) (xy 305.577278 -399.51174) (xy 305.602668 -399.529266)
			(xy 305.623127 -399.552359) (xy 305.637464 -399.579677) (xy 305.644847 -399.609632) (xy 305.645312 -399.625058)
			(xy 305.645312 -399.701258) (xy 306.590192 -399.701258) (xy 306.590192 -399.625058) (xy 306.590657 -399.609632)
			(xy 306.59804 -399.579677) (xy 306.612377 -399.552359) (xy 306.632836 -399.529266) (xy 306.658226 -399.51174)
			(xy 306.687073 -399.5008) (xy 306.7177 -399.497082) (xy 306.748327 -399.5008) (xy 306.777174 -399.51174)
			(xy 306.802564 -399.529266) (xy 306.823023 -399.552359) (xy 306.83736 -399.579677) (xy 306.844743 -399.609632)
			(xy 306.845208 -399.625058) (xy 306.845208 -399.701258) (xy 307.790088 -399.701258) (xy 307.790088 -399.625058)
			(xy 307.790554 -399.609601) (xy 307.797952 -399.579587) (xy 307.812318 -399.552214) (xy 307.832817 -399.529076)
			(xy 307.858258 -399.511515) (xy 307.887162 -399.500553) (xy 307.91785 -399.496827) (xy 307.948538 -399.500553)
			(xy 307.977442 -399.511515) (xy 308.002883 -399.529076) (xy 308.023382 -399.552214) (xy 308.037748 -399.579587)
			(xy 308.045146 -399.609601) (xy 308.045612 -399.625058) (xy 308.045612 -399.701258) (xy 308.989984 -399.701258)
			(xy 308.989984 -399.625058) (xy 308.99045 -399.609601) (xy 308.997848 -399.579587) (xy 309.012214 -399.552214)
			(xy 309.032713 -399.529076) (xy 309.058154 -399.511515) (xy 309.087058 -399.500553) (xy 309.117746 -399.496827)
			(xy 309.148434 -399.500553) (xy 309.177338 -399.511515) (xy 309.202779 -399.529076) (xy 309.223278 -399.552214)
			(xy 309.237644 -399.579587) (xy 309.245042 -399.609601) (xy 309.245508 -399.625058) (xy 309.245508 -399.701258)
			(xy 310.190388 -399.701258) (xy 310.190388 -399.625058) (xy 310.190853 -399.609632) (xy 310.198236 -399.579677)
			(xy 310.212573 -399.552359) (xy 310.233032 -399.529266) (xy 310.258422 -399.51174) (xy 310.287269 -399.5008)
			(xy 310.317896 -399.497082) (xy 310.348523 -399.5008) (xy 310.37737 -399.51174) (xy 310.40276 -399.529266)
			(xy 310.423219 -399.552359) (xy 310.437556 -399.579677) (xy 310.444939 -399.609632) (xy 310.445404 -399.625058)
			(xy 310.445404 -399.701258) (xy 311.390284 -399.701258) (xy 311.390284 -399.625058) (xy 311.390749 -399.609632)
			(xy 311.398132 -399.579677) (xy 311.412469 -399.552359) (xy 311.432928 -399.529266) (xy 311.458318 -399.51174)
			(xy 311.487165 -399.5008) (xy 311.517792 -399.497082) (xy 311.548419 -399.5008) (xy 311.577266 -399.51174)
			(xy 311.602656 -399.529266) (xy 311.623115 -399.552359) (xy 311.637452 -399.579677) (xy 311.644835 -399.609632)
			(xy 311.6453 -399.625058) (xy 311.6453 -399.701258) (xy 312.59018 -399.701258) (xy 312.59018 -399.625058)
			(xy 312.590645 -399.609632) (xy 312.598028 -399.579677) (xy 312.612365 -399.552359) (xy 312.632824 -399.529266)
			(xy 312.658214 -399.51174) (xy 312.687061 -399.5008) (xy 312.717688 -399.497082) (xy 312.748315 -399.5008)
			(xy 312.777162 -399.51174) (xy 312.802552 -399.529266) (xy 312.823011 -399.552359) (xy 312.837348 -399.579677)
			(xy 312.844731 -399.609632) (xy 312.845196 -399.625058) (xy 312.845196 -399.701258) (xy 313.790076 -399.701258)
			(xy 313.790076 -399.625058) (xy 313.790542 -399.609601) (xy 313.79794 -399.579587) (xy 313.812306 -399.552214)
			(xy 313.832805 -399.529076) (xy 313.858246 -399.511515) (xy 313.88715 -399.500553) (xy 313.917838 -399.496827)
			(xy 313.948526 -399.500553) (xy 313.97743 -399.511515) (xy 314.002871 -399.529076) (xy 314.02337 -399.552214)
			(xy 314.037736 -399.579587) (xy 314.045134 -399.609601) (xy 314.0456 -399.625058) (xy 314.0456 -399.701258)
			(xy 314.989972 -399.701258) (xy 314.989972 -399.625058) (xy 314.990438 -399.609601) (xy 314.997836 -399.579587)
			(xy 315.012202 -399.552214) (xy 315.032701 -399.529076) (xy 315.058142 -399.511515) (xy 315.087046 -399.500553)
			(xy 315.117734 -399.496827) (xy 315.148422 -399.500553) (xy 315.177326 -399.511515) (xy 315.202767 -399.529076)
			(xy 315.223266 -399.552214) (xy 315.237632 -399.579587) (xy 315.24503 -399.609601) (xy 315.245496 -399.625058)
			(xy 315.245496 -399.701258) (xy 316.190376 -399.701258) (xy 316.190376 -399.625058) (xy 316.190841 -399.609632)
			(xy 316.198224 -399.579677) (xy 316.212561 -399.552359) (xy 316.23302 -399.529266) (xy 316.25841 -399.51174)
			(xy 316.287257 -399.5008) (xy 316.317884 -399.497082) (xy 316.348511 -399.5008) (xy 316.377358 -399.51174)
			(xy 316.402748 -399.529266) (xy 316.423207 -399.552359) (xy 316.437544 -399.579677) (xy 316.444927 -399.609632)
			(xy 316.445392 -399.625058) (xy 316.445392 -399.701258) (xy 317.390272 -399.701258) (xy 317.390272 -399.625058)
			(xy 317.390737 -399.609632) (xy 317.39812 -399.579677) (xy 317.412457 -399.552359) (xy 317.432916 -399.529266)
			(xy 317.458306 -399.51174) (xy 317.487153 -399.5008) (xy 317.51778 -399.497082) (xy 317.548407 -399.5008)
			(xy 317.577254 -399.51174) (xy 317.602644 -399.529266) (xy 317.623103 -399.552359) (xy 317.63744 -399.579677)
			(xy 317.644823 -399.609632) (xy 317.645288 -399.625058) (xy 317.645288 -399.701258) (xy 318.590168 -399.701258)
			(xy 318.590168 -399.625058) (xy 318.590633 -399.609632) (xy 318.598016 -399.579677) (xy 318.612353 -399.552359)
			(xy 318.632812 -399.529266) (xy 318.658202 -399.51174) (xy 318.687049 -399.5008) (xy 318.717676 -399.497082)
			(xy 318.748303 -399.5008) (xy 318.77715 -399.51174) (xy 318.80254 -399.529266) (xy 318.822999 -399.552359)
			(xy 318.837336 -399.579677) (xy 318.844719 -399.609632) (xy 318.845184 -399.625058) (xy 318.845184 -399.701258)
			(xy 319.790064 -399.701258) (xy 319.790064 -399.625058) (xy 319.79053 -399.609601) (xy 319.797928 -399.579587)
			(xy 319.812294 -399.552214) (xy 319.832793 -399.529076) (xy 319.858234 -399.511515) (xy 319.887138 -399.500553)
			(xy 319.917826 -399.496827) (xy 319.948514 -399.500553) (xy 319.977418 -399.511515) (xy 320.002859 -399.529076)
			(xy 320.023358 -399.552214) (xy 320.037724 -399.579587) (xy 320.045122 -399.609601) (xy 320.045588 -399.625058)
			(xy 320.045588 -399.701258) (xy 320.98996 -399.701258) (xy 320.98996 -399.625058) (xy 320.990426 -399.609601)
			(xy 320.997824 -399.579587) (xy 321.01219 -399.552214) (xy 321.032689 -399.529076) (xy 321.05813 -399.511515)
			(xy 321.087034 -399.500553) (xy 321.117722 -399.496827) (xy 321.14841 -399.500553) (xy 321.177314 -399.511515)
			(xy 321.202755 -399.529076) (xy 321.223254 -399.552214) (xy 321.23762 -399.579587) (xy 321.245018 -399.609601)
			(xy 321.245484 -399.625058) (xy 321.245484 -399.701258) (xy 335.517744 -399.701258) (xy 335.517744 -399.625058)
			(xy 335.51821 -399.609601) (xy 335.525608 -399.579587) (xy 335.539974 -399.552214) (xy 335.560473 -399.529076)
			(xy 335.585914 -399.511515) (xy 335.614818 -399.500553) (xy 335.645506 -399.496827) (xy 335.676194 -399.500553)
			(xy 335.705098 -399.511515) (xy 335.730539 -399.529076) (xy 335.751038 -399.552214) (xy 335.765404 -399.579587)
			(xy 335.772802 -399.609601) (xy 335.773268 -399.625058) (xy 335.773268 -399.701258) (xy 336.71764 -399.701258)
			(xy 336.71764 -399.625058) (xy 336.718106 -399.609601) (xy 336.725504 -399.579587) (xy 336.73987 -399.552214)
			(xy 336.760369 -399.529076) (xy 336.78581 -399.511515) (xy 336.814714 -399.500553) (xy 336.845402 -399.496827)
			(xy 336.87609 -399.500553) (xy 336.904994 -399.511515) (xy 336.930435 -399.529076) (xy 336.950934 -399.552214)
			(xy 336.9653 -399.579587) (xy 336.972698 -399.609601) (xy 336.973164 -399.625058) (xy 336.973164 -399.701258)
			(xy 337.918044 -399.701258) (xy 337.918044 -399.625058) (xy 337.918509 -399.609632) (xy 337.925892 -399.579677)
			(xy 337.940229 -399.552359) (xy 337.960688 -399.529266) (xy 337.986078 -399.51174) (xy 338.014925 -399.5008)
			(xy 338.045552 -399.497082) (xy 338.076179 -399.5008) (xy 338.105026 -399.51174) (xy 338.130416 -399.529266)
			(xy 338.150875 -399.552359) (xy 338.165212 -399.579677) (xy 338.172595 -399.609632) (xy 338.17306 -399.625058)
			(xy 338.17306 -399.701258) (xy 339.11794 -399.701258) (xy 339.11794 -399.625058) (xy 339.118405 -399.609632)
			(xy 339.125788 -399.579677) (xy 339.140125 -399.552359) (xy 339.160584 -399.529266) (xy 339.185974 -399.51174)
			(xy 339.214821 -399.5008) (xy 339.245448 -399.497082) (xy 339.276075 -399.5008) (xy 339.304922 -399.51174)
			(xy 339.330312 -399.529266) (xy 339.350771 -399.552359) (xy 339.365108 -399.579677) (xy 339.372491 -399.609632)
			(xy 339.372956 -399.625058) (xy 339.372956 -399.701258) (xy 340.317836 -399.701258) (xy 340.317836 -399.625058)
			(xy 340.318302 -399.609601) (xy 340.3257 -399.579587) (xy 340.340066 -399.552214) (xy 340.360565 -399.529076)
			(xy 340.386006 -399.511515) (xy 340.41491 -399.500553) (xy 340.445598 -399.496827) (xy 340.476286 -399.500553)
			(xy 340.50519 -399.511515) (xy 340.530631 -399.529076) (xy 340.55113 -399.552214) (xy 340.565496 -399.579587)
			(xy 340.572894 -399.609601) (xy 340.57336 -399.625058) (xy 340.57336 -399.701258) (xy 341.517732 -399.701258)
			(xy 341.517732 -399.625058) (xy 341.518198 -399.609601) (xy 341.525596 -399.579587) (xy 341.539962 -399.552214)
			(xy 341.560461 -399.529076) (xy 341.585902 -399.511515) (xy 341.614806 -399.500553) (xy 341.645494 -399.496827)
			(xy 341.676182 -399.500553) (xy 341.705086 -399.511515) (xy 341.730527 -399.529076) (xy 341.751026 -399.552214)
			(xy 341.765392 -399.579587) (xy 341.77279 -399.609601) (xy 341.773256 -399.625058) (xy 341.773256 -399.701258)
			(xy 342.718136 -399.701258) (xy 342.718136 -399.625058) (xy 342.718601 -399.609632) (xy 342.725984 -399.579677)
			(xy 342.740321 -399.552359) (xy 342.76078 -399.529266) (xy 342.78617 -399.51174) (xy 342.815017 -399.5008)
			(xy 342.845644 -399.497082) (xy 342.876271 -399.5008) (xy 342.905118 -399.51174) (xy 342.930508 -399.529266)
			(xy 342.950967 -399.552359) (xy 342.965304 -399.579677) (xy 342.972687 -399.609632) (xy 342.973152 -399.625058)
			(xy 342.973152 -399.701258) (xy 343.918032 -399.701258) (xy 343.918032 -399.625058) (xy 343.918497 -399.609632)
			(xy 343.92588 -399.579677) (xy 343.940217 -399.552359) (xy 343.960676 -399.529266) (xy 343.986066 -399.51174)
			(xy 344.014913 -399.5008) (xy 344.04554 -399.497082) (xy 344.076167 -399.5008) (xy 344.105014 -399.51174)
			(xy 344.130404 -399.529266) (xy 344.150863 -399.552359) (xy 344.1652 -399.579677) (xy 344.172583 -399.609632)
			(xy 344.173048 -399.625058) (xy 344.173048 -399.701258) (xy 345.117928 -399.701258) (xy 345.117928 -399.625058)
			(xy 345.118393 -399.609632) (xy 345.125776 -399.579677) (xy 345.140113 -399.552359) (xy 345.160572 -399.529266)
			(xy 345.185962 -399.51174) (xy 345.214809 -399.5008) (xy 345.245436 -399.497082) (xy 345.276063 -399.5008)
			(xy 345.30491 -399.51174) (xy 345.3303 -399.529266) (xy 345.350759 -399.552359) (xy 345.365096 -399.579677)
			(xy 345.372479 -399.609632) (xy 345.372944 -399.625058) (xy 345.372944 -399.701258) (xy 346.317824 -399.701258)
			(xy 346.317824 -399.625058) (xy 346.31829 -399.609601) (xy 346.325688 -399.579587) (xy 346.340054 -399.552214)
			(xy 346.360553 -399.529076) (xy 346.385994 -399.511515) (xy 346.414898 -399.500553) (xy 346.445586 -399.496827)
			(xy 346.476274 -399.500553) (xy 346.505178 -399.511515) (xy 346.530619 -399.529076) (xy 346.551118 -399.552214)
			(xy 346.565484 -399.579587) (xy 346.572882 -399.609601) (xy 346.573348 -399.625058) (xy 346.573348 -399.701258)
			(xy 347.51772 -399.701258) (xy 347.51772 -399.625058) (xy 347.518186 -399.609601) (xy 347.525584 -399.579587)
			(xy 347.53995 -399.552214) (xy 347.560449 -399.529076) (xy 347.58589 -399.511515) (xy 347.614794 -399.500553)
			(xy 347.645482 -399.496827) (xy 347.67617 -399.500553) (xy 347.705074 -399.511515) (xy 347.730515 -399.529076)
			(xy 347.751014 -399.552214) (xy 347.76538 -399.579587) (xy 347.772778 -399.609601) (xy 347.773244 -399.625058)
			(xy 347.773244 -399.701258) (xy 348.718124 -399.701258) (xy 348.718124 -399.625058) (xy 348.718589 -399.609632)
			(xy 348.725972 -399.579677) (xy 348.740309 -399.552359) (xy 348.760768 -399.529266) (xy 348.786158 -399.51174)
			(xy 348.815005 -399.5008) (xy 348.845632 -399.497082) (xy 348.876259 -399.5008) (xy 348.905106 -399.51174)
			(xy 348.930496 -399.529266) (xy 348.950955 -399.552359) (xy 348.965292 -399.579677) (xy 348.972675 -399.609632)
			(xy 348.97314 -399.625058) (xy 348.97314 -399.701258) (xy 349.91802 -399.701258) (xy 349.91802 -399.625058)
			(xy 349.918485 -399.609632) (xy 349.925868 -399.579677) (xy 349.940205 -399.552359) (xy 349.960664 -399.529266)
			(xy 349.986054 -399.51174) (xy 350.014901 -399.5008) (xy 350.045528 -399.497082) (xy 350.076155 -399.5008)
			(xy 350.105002 -399.51174) (xy 350.130392 -399.529266) (xy 350.150851 -399.552359) (xy 350.165188 -399.579677)
			(xy 350.172571 -399.609632) (xy 350.173036 -399.625058) (xy 350.173036 -399.701258) (xy 351.117916 -399.701258)
			(xy 351.117916 -399.625058) (xy 351.118381 -399.609632) (xy 351.125764 -399.579677) (xy 351.140101 -399.552359)
			(xy 351.16056 -399.529266) (xy 351.18595 -399.51174) (xy 351.214797 -399.5008) (xy 351.245424 -399.497082)
			(xy 351.276051 -399.5008) (xy 351.304898 -399.51174) (xy 351.330288 -399.529266) (xy 351.350747 -399.552359)
			(xy 351.365084 -399.579677) (xy 351.372467 -399.609632) (xy 351.372932 -399.625058) (xy 351.372932 -399.701258)
			(xy 352.317812 -399.701258) (xy 352.317812 -399.625058) (xy 352.318278 -399.609601) (xy 352.325676 -399.579587)
			(xy 352.340042 -399.552214) (xy 352.360541 -399.529076) (xy 352.385982 -399.511515) (xy 352.414886 -399.500553)
			(xy 352.445574 -399.496827) (xy 352.476262 -399.500553) (xy 352.505166 -399.511515) (xy 352.530607 -399.529076)
			(xy 352.551106 -399.552214) (xy 352.565472 -399.579587) (xy 352.57287 -399.609601) (xy 352.573336 -399.625058)
			(xy 352.573336 -399.701258) (xy 353.517708 -399.701258) (xy 353.517708 -399.625058) (xy 353.518174 -399.609601)
			(xy 353.525572 -399.579587) (xy 353.539938 -399.552214) (xy 353.560437 -399.529076) (xy 353.585878 -399.511515)
			(xy 353.614782 -399.500553) (xy 353.64547 -399.496827) (xy 353.676158 -399.500553) (xy 353.705062 -399.511515)
			(xy 353.730503 -399.529076) (xy 353.751002 -399.552214) (xy 353.765368 -399.579587) (xy 353.772766 -399.609601)
			(xy 353.773232 -399.625058) (xy 353.773232 -399.701258) (xy 370.090192 -399.701258) (xy 370.090192 -399.625058)
			(xy 370.090658 -399.609601) (xy 370.098056 -399.579587) (xy 370.112422 -399.552214) (xy 370.132921 -399.529076)
			(xy 370.158362 -399.511515) (xy 370.187266 -399.500553) (xy 370.217954 -399.496827) (xy 370.248642 -399.500553)
			(xy 370.277546 -399.511515) (xy 370.302987 -399.529076) (xy 370.323486 -399.552214) (xy 370.337852 -399.579587)
			(xy 370.34525 -399.609601) (xy 370.345716 -399.625058) (xy 370.345716 -399.701258) (xy 371.290088 -399.701258)
			(xy 371.290088 -399.625058) (xy 371.290554 -399.609601) (xy 371.297952 -399.579587) (xy 371.312318 -399.552214)
			(xy 371.332817 -399.529076) (xy 371.358258 -399.511515) (xy 371.387162 -399.500553) (xy 371.41785 -399.496827)
			(xy 371.448538 -399.500553) (xy 371.477442 -399.511515) (xy 371.502883 -399.529076) (xy 371.523382 -399.552214)
			(xy 371.537748 -399.579587) (xy 371.545146 -399.609601) (xy 371.545612 -399.625058) (xy 371.545612 -399.701258)
			(xy 372.490492 -399.701258) (xy 372.490492 -399.625058) (xy 372.490957 -399.609632) (xy 372.49834 -399.579677)
			(xy 372.512677 -399.552359) (xy 372.533136 -399.529266) (xy 372.558526 -399.51174) (xy 372.587373 -399.5008)
			(xy 372.618 -399.497082) (xy 372.648627 -399.5008) (xy 372.677474 -399.51174) (xy 372.702864 -399.529266)
			(xy 372.723323 -399.552359) (xy 372.73766 -399.579677) (xy 372.745043 -399.609632) (xy 372.745508 -399.625058)
			(xy 372.745508 -399.701258) (xy 373.690388 -399.701258) (xy 373.690388 -399.625058) (xy 373.690853 -399.609632)
			(xy 373.698236 -399.579677) (xy 373.712573 -399.552359) (xy 373.733032 -399.529266) (xy 373.758422 -399.51174)
			(xy 373.787269 -399.5008) (xy 373.817896 -399.497082) (xy 373.848523 -399.5008) (xy 373.87737 -399.51174)
			(xy 373.90276 -399.529266) (xy 373.923219 -399.552359) (xy 373.937556 -399.579677) (xy 373.944939 -399.609632)
			(xy 373.945404 -399.625058) (xy 373.945404 -399.701258) (xy 374.890284 -399.701258) (xy 374.890284 -399.625058)
			(xy 374.89075 -399.609601) (xy 374.898148 -399.579587) (xy 374.912514 -399.552214) (xy 374.933013 -399.529076)
			(xy 374.958454 -399.511515) (xy 374.987358 -399.500553) (xy 375.018046 -399.496827) (xy 375.048734 -399.500553)
			(xy 375.077638 -399.511515) (xy 375.103079 -399.529076) (xy 375.123578 -399.552214) (xy 375.137944 -399.579587)
			(xy 375.145342 -399.609601) (xy 375.145808 -399.625058) (xy 375.145808 -399.701258) (xy 376.09018 -399.701258)
			(xy 376.09018 -399.625058) (xy 376.090646 -399.609601) (xy 376.098044 -399.579587) (xy 376.11241 -399.552214)
			(xy 376.132909 -399.529076) (xy 376.15835 -399.511515) (xy 376.187254 -399.500553) (xy 376.217942 -399.496827)
			(xy 376.24863 -399.500553) (xy 376.277534 -399.511515) (xy 376.302975 -399.529076) (xy 376.323474 -399.552214)
			(xy 376.33784 -399.579587) (xy 376.345238 -399.609601) (xy 376.345704 -399.625058) (xy 376.345704 -399.701258)
			(xy 377.290584 -399.701258) (xy 377.290584 -399.625058) (xy 377.291049 -399.609632) (xy 377.298432 -399.579677)
			(xy 377.312769 -399.552359) (xy 377.333228 -399.529266) (xy 377.358618 -399.51174) (xy 377.387465 -399.5008)
			(xy 377.418092 -399.497082) (xy 377.448719 -399.5008) (xy 377.477566 -399.51174) (xy 377.502956 -399.529266)
			(xy 377.523415 -399.552359) (xy 377.537752 -399.579677) (xy 377.545135 -399.609632) (xy 377.5456 -399.625058)
			(xy 377.5456 -399.701258) (xy 378.49048 -399.701258) (xy 378.49048 -399.625058) (xy 378.490945 -399.609632)
			(xy 378.498328 -399.579677) (xy 378.512665 -399.552359) (xy 378.533124 -399.529266) (xy 378.558514 -399.51174)
			(xy 378.587361 -399.5008) (xy 378.617988 -399.497082) (xy 378.648615 -399.5008) (xy 378.677462 -399.51174)
			(xy 378.702852 -399.529266) (xy 378.723311 -399.552359) (xy 378.737648 -399.579677) (xy 378.745031 -399.609632)
			(xy 378.745496 -399.625058) (xy 378.745496 -399.701258) (xy 379.690376 -399.701258) (xy 379.690376 -399.625058)
			(xy 379.690841 -399.609632) (xy 379.698224 -399.579677) (xy 379.712561 -399.552359) (xy 379.73302 -399.529266)
			(xy 379.75841 -399.51174) (xy 379.787257 -399.5008) (xy 379.817884 -399.497082) (xy 379.848511 -399.5008)
			(xy 379.877358 -399.51174) (xy 379.902748 -399.529266) (xy 379.923207 -399.552359) (xy 379.937544 -399.579677)
			(xy 379.944927 -399.609632) (xy 379.945392 -399.625058) (xy 379.945392 -399.701258) (xy 380.890272 -399.701258)
			(xy 380.890272 -399.625058) (xy 380.890738 -399.609601) (xy 380.898136 -399.579587) (xy 380.912502 -399.552214)
			(xy 380.933001 -399.529076) (xy 380.958442 -399.511515) (xy 380.987346 -399.500553) (xy 381.018034 -399.496827)
			(xy 381.048722 -399.500553) (xy 381.077626 -399.511515) (xy 381.103067 -399.529076) (xy 381.123566 -399.552214)
			(xy 381.137932 -399.579587) (xy 381.14533 -399.609601) (xy 381.145796 -399.625058) (xy 381.145796 -399.701258)
			(xy 382.090168 -399.701258) (xy 382.090168 -399.625058) (xy 382.090634 -399.609601) (xy 382.098032 -399.579587)
			(xy 382.112398 -399.552214) (xy 382.132897 -399.529076) (xy 382.158338 -399.511515) (xy 382.187242 -399.500553)
			(xy 382.21793 -399.496827) (xy 382.248618 -399.500553) (xy 382.277522 -399.511515) (xy 382.302963 -399.529076)
			(xy 382.323462 -399.552214) (xy 382.337828 -399.579587) (xy 382.345226 -399.609601) (xy 382.345692 -399.625058)
			(xy 382.345692 -399.701258) (xy 383.290572 -399.701258) (xy 383.290572 -399.625058) (xy 383.291037 -399.609632)
			(xy 383.29842 -399.579677) (xy 383.312757 -399.552359) (xy 383.333216 -399.529266) (xy 383.358606 -399.51174)
			(xy 383.387453 -399.5008) (xy 383.41808 -399.497082) (xy 383.448707 -399.5008) (xy 383.477554 -399.51174)
			(xy 383.502944 -399.529266) (xy 383.523403 -399.552359) (xy 383.53774 -399.579677) (xy 383.545123 -399.609632)
			(xy 383.545588 -399.625058) (xy 383.545588 -399.701258) (xy 384.490468 -399.701258) (xy 384.490468 -399.625058)
			(xy 384.490933 -399.609632) (xy 384.498316 -399.579677) (xy 384.512653 -399.552359) (xy 384.533112 -399.529266)
			(xy 384.558502 -399.51174) (xy 384.587349 -399.5008) (xy 384.617976 -399.497082) (xy 384.648603 -399.5008)
			(xy 384.67745 -399.51174) (xy 384.70284 -399.529266) (xy 384.723299 -399.552359) (xy 384.737636 -399.579677)
			(xy 384.745019 -399.609632) (xy 384.745484 -399.625058) (xy 384.745484 -399.701258) (xy 385.690364 -399.701258)
			(xy 385.690364 -399.625058) (xy 385.690829 -399.609632) (xy 385.698212 -399.579677) (xy 385.712549 -399.552359)
			(xy 385.733008 -399.529266) (xy 385.758398 -399.51174) (xy 385.787245 -399.5008) (xy 385.817872 -399.497082)
			(xy 385.848499 -399.5008) (xy 385.877346 -399.51174) (xy 385.902736 -399.529266) (xy 385.923195 -399.552359)
			(xy 385.937532 -399.579677) (xy 385.944915 -399.609632) (xy 385.94538 -399.625058) (xy 385.94538 -399.701258)
			(xy 386.89026 -399.701258) (xy 386.89026 -399.625058) (xy 386.890726 -399.609601) (xy 386.898124 -399.579587)
			(xy 386.91249 -399.552214) (xy 386.932989 -399.529076) (xy 386.95843 -399.511515) (xy 386.987334 -399.500553)
			(xy 387.018022 -399.496827) (xy 387.04871 -399.500553) (xy 387.077614 -399.511515) (xy 387.103055 -399.529076)
			(xy 387.123554 -399.552214) (xy 387.13792 -399.579587) (xy 387.145318 -399.609601) (xy 387.145784 -399.625058)
			(xy 387.145784 -399.701258) (xy 388.090156 -399.701258) (xy 388.090156 -399.625058) (xy 388.090622 -399.609601)
			(xy 388.09802 -399.579587) (xy 388.112386 -399.552214) (xy 388.132885 -399.529076) (xy 388.158326 -399.511515)
			(xy 388.18723 -399.500553) (xy 388.217918 -399.496827) (xy 388.248606 -399.500553) (xy 388.27751 -399.511515)
			(xy 388.302951 -399.529076) (xy 388.32345 -399.552214) (xy 388.337816 -399.579587) (xy 388.345214 -399.609601)
			(xy 388.34568 -399.625058) (xy 388.34568 -399.701258) (xy 402.61794 -399.701258) (xy 402.61794 -399.625058)
			(xy 402.618406 -399.609601) (xy 402.625804 -399.579587) (xy 402.64017 -399.552214) (xy 402.660669 -399.529076)
			(xy 402.68611 -399.511515) (xy 402.715014 -399.500553) (xy 402.745702 -399.496827) (xy 402.77639 -399.500553)
			(xy 402.805294 -399.511515) (xy 402.830735 -399.529076) (xy 402.851234 -399.552214) (xy 402.8656 -399.579587)
			(xy 402.872998 -399.609601) (xy 402.873464 -399.625058) (xy 402.873464 -399.701258) (xy 403.817836 -399.701258)
			(xy 403.817836 -399.625058) (xy 403.818302 -399.609601) (xy 403.8257 -399.579587) (xy 403.840066 -399.552214)
			(xy 403.860565 -399.529076) (xy 403.886006 -399.511515) (xy 403.91491 -399.500553) (xy 403.945598 -399.496827)
			(xy 403.976286 -399.500553) (xy 404.00519 -399.511515) (xy 404.030631 -399.529076) (xy 404.05113 -399.552214)
			(xy 404.065496 -399.579587) (xy 404.072894 -399.609601) (xy 404.07336 -399.625058) (xy 404.07336 -399.701258)
			(xy 405.01824 -399.701258) (xy 405.01824 -399.625058) (xy 405.018705 -399.609632) (xy 405.026088 -399.579677)
			(xy 405.040425 -399.552359) (xy 405.060884 -399.529266) (xy 405.086274 -399.51174) (xy 405.115121 -399.5008)
			(xy 405.145748 -399.497082) (xy 405.176375 -399.5008) (xy 405.205222 -399.51174) (xy 405.230612 -399.529266)
			(xy 405.251071 -399.552359) (xy 405.265408 -399.579677) (xy 405.272791 -399.609632) (xy 405.273256 -399.625058)
			(xy 405.273256 -399.701258) (xy 406.218136 -399.701258) (xy 406.218136 -399.625058) (xy 406.218601 -399.609632)
			(xy 406.225984 -399.579677) (xy 406.240321 -399.552359) (xy 406.26078 -399.529266) (xy 406.28617 -399.51174)
			(xy 406.315017 -399.5008) (xy 406.345644 -399.497082) (xy 406.376271 -399.5008) (xy 406.405118 -399.51174)
			(xy 406.430508 -399.529266) (xy 406.450967 -399.552359) (xy 406.465304 -399.579677) (xy 406.472687 -399.609632)
			(xy 406.473152 -399.625058) (xy 406.473152 -399.701258) (xy 407.418032 -399.701258) (xy 407.418032 -399.625058)
			(xy 407.418498 -399.609601) (xy 407.425896 -399.579587) (xy 407.440262 -399.552214) (xy 407.460761 -399.529076)
			(xy 407.486202 -399.511515) (xy 407.515106 -399.500553) (xy 407.545794 -399.496827) (xy 407.576482 -399.500553)
			(xy 407.605386 -399.511515) (xy 407.630827 -399.529076) (xy 407.651326 -399.552214) (xy 407.665692 -399.579587)
			(xy 407.67309 -399.609601) (xy 407.673556 -399.625058) (xy 407.673556 -399.701258) (xy 408.617928 -399.701258)
			(xy 408.617928 -399.625058) (xy 408.618394 -399.609601) (xy 408.625792 -399.579587) (xy 408.640158 -399.552214)
			(xy 408.660657 -399.529076) (xy 408.686098 -399.511515) (xy 408.715002 -399.500553) (xy 408.74569 -399.496827)
			(xy 408.776378 -399.500553) (xy 408.805282 -399.511515) (xy 408.830723 -399.529076) (xy 408.851222 -399.552214)
			(xy 408.865588 -399.579587) (xy 408.872986 -399.609601) (xy 408.873452 -399.625058) (xy 408.873452 -399.701258)
			(xy 409.818332 -399.701258) (xy 409.818332 -399.625058) (xy 409.818797 -399.609632) (xy 409.82618 -399.579677)
			(xy 409.840517 -399.552359) (xy 409.860976 -399.529266) (xy 409.886366 -399.51174) (xy 409.915213 -399.5008)
			(xy 409.94584 -399.497082) (xy 409.976467 -399.5008) (xy 410.005314 -399.51174) (xy 410.030704 -399.529266)
			(xy 410.051163 -399.552359) (xy 410.0655 -399.579677) (xy 410.072883 -399.609632) (xy 410.073348 -399.625058)
			(xy 410.073348 -399.701258) (xy 411.018228 -399.701258) (xy 411.018228 -399.625058) (xy 411.018693 -399.609632)
			(xy 411.026076 -399.579677) (xy 411.040413 -399.552359) (xy 411.060872 -399.529266) (xy 411.086262 -399.51174)
			(xy 411.115109 -399.5008) (xy 411.145736 -399.497082) (xy 411.176363 -399.5008) (xy 411.20521 -399.51174)
			(xy 411.2306 -399.529266) (xy 411.251059 -399.552359) (xy 411.265396 -399.579677) (xy 411.272779 -399.609632)
			(xy 411.273244 -399.625058) (xy 411.273244 -399.701258) (xy 412.218124 -399.701258) (xy 412.218124 -399.625058)
			(xy 412.218589 -399.609632) (xy 412.225972 -399.579677) (xy 412.240309 -399.552359) (xy 412.260768 -399.529266)
			(xy 412.286158 -399.51174) (xy 412.315005 -399.5008) (xy 412.345632 -399.497082) (xy 412.376259 -399.5008)
			(xy 412.405106 -399.51174) (xy 412.430496 -399.529266) (xy 412.450955 -399.552359) (xy 412.465292 -399.579677)
			(xy 412.472675 -399.609632) (xy 412.47314 -399.625058) (xy 412.47314 -399.701258) (xy 413.41802 -399.701258)
			(xy 413.41802 -399.625058) (xy 413.418486 -399.609601) (xy 413.425884 -399.579587) (xy 413.44025 -399.552214)
			(xy 413.460749 -399.529076) (xy 413.48619 -399.511515) (xy 413.515094 -399.500553) (xy 413.545782 -399.496827)
			(xy 413.57647 -399.500553) (xy 413.605374 -399.511515) (xy 413.630815 -399.529076) (xy 413.651314 -399.552214)
			(xy 413.66568 -399.579587) (xy 413.673078 -399.609601) (xy 413.673544 -399.625058) (xy 413.673544 -399.701258)
			(xy 414.617916 -399.701258) (xy 414.617916 -399.625058) (xy 414.618382 -399.609601) (xy 414.62578 -399.579587)
			(xy 414.640146 -399.552214) (xy 414.660645 -399.529076) (xy 414.686086 -399.511515) (xy 414.71499 -399.500553)
			(xy 414.745678 -399.496827) (xy 414.776366 -399.500553) (xy 414.80527 -399.511515) (xy 414.830711 -399.529076)
			(xy 414.85121 -399.552214) (xy 414.865576 -399.579587) (xy 414.872974 -399.609601) (xy 414.87344 -399.625058)
			(xy 414.87344 -399.701258) (xy 415.81832 -399.701258) (xy 415.81832 -399.625058) (xy 415.818785 -399.609632)
			(xy 415.826168 -399.579677) (xy 415.840505 -399.552359) (xy 415.860964 -399.529266) (xy 415.886354 -399.51174)
			(xy 415.915201 -399.5008) (xy 415.945828 -399.497082) (xy 415.976455 -399.5008) (xy 416.005302 -399.51174)
			(xy 416.030692 -399.529266) (xy 416.051151 -399.552359) (xy 416.065488 -399.579677) (xy 416.072871 -399.609632)
			(xy 416.073336 -399.625058) (xy 416.073336 -399.701258) (xy 417.018216 -399.701258) (xy 417.018216 -399.625058)
			(xy 417.018681 -399.609632) (xy 417.026064 -399.579677) (xy 417.040401 -399.552359) (xy 417.06086 -399.529266)
			(xy 417.08625 -399.51174) (xy 417.115097 -399.5008) (xy 417.145724 -399.497082) (xy 417.176351 -399.5008)
			(xy 417.205198 -399.51174) (xy 417.230588 -399.529266) (xy 417.251047 -399.552359) (xy 417.265384 -399.579677)
			(xy 417.272767 -399.609632) (xy 417.273232 -399.625058) (xy 417.273232 -399.701258) (xy 418.218112 -399.701258)
			(xy 418.218112 -399.625058) (xy 418.218577 -399.609632) (xy 418.22596 -399.579677) (xy 418.240297 -399.552359)
			(xy 418.260756 -399.529266) (xy 418.286146 -399.51174) (xy 418.314993 -399.5008) (xy 418.34562 -399.497082)
			(xy 418.376247 -399.5008) (xy 418.405094 -399.51174) (xy 418.430484 -399.529266) (xy 418.450943 -399.552359)
			(xy 418.46528 -399.579677) (xy 418.472663 -399.609632) (xy 418.473128 -399.625058) (xy 418.473128 -399.701258)
			(xy 419.418008 -399.701258) (xy 419.418008 -399.625058) (xy 419.418474 -399.609601) (xy 419.425872 -399.579587)
			(xy 419.440238 -399.552214) (xy 419.460737 -399.529076) (xy 419.486178 -399.511515) (xy 419.515082 -399.500553)
			(xy 419.54577 -399.496827) (xy 419.576458 -399.500553) (xy 419.605362 -399.511515) (xy 419.630803 -399.529076)
			(xy 419.651302 -399.552214) (xy 419.665668 -399.579587) (xy 419.673066 -399.609601) (xy 419.673532 -399.625058)
			(xy 419.673532 -399.701258) (xy 420.617904 -399.701258) (xy 420.617904 -399.625058) (xy 420.61837 -399.609601)
			(xy 420.625768 -399.579587) (xy 420.640134 -399.552214) (xy 420.660633 -399.529076) (xy 420.686074 -399.511515)
			(xy 420.714978 -399.500553) (xy 420.745666 -399.496827) (xy 420.776354 -399.500553) (xy 420.805258 -399.511515)
			(xy 420.830699 -399.529076) (xy 420.851198 -399.552214) (xy 420.865564 -399.579587) (xy 420.872962 -399.609601)
			(xy 420.873428 -399.625058) (xy 420.873428 -399.701258) (xy 420.872962 -399.716715) (xy 420.865564 -399.746729)
			(xy 420.851198 -399.774102) (xy 420.830699 -399.79724) (xy 420.805258 -399.814801) (xy 420.776354 -399.825763)
			(xy 420.745666 -399.829489) (xy 420.714978 -399.825763) (xy 420.686074 -399.814801) (xy 420.660633 -399.79724)
			(xy 420.640134 -399.774102) (xy 420.625768 -399.746729) (xy 420.61837 -399.716715) (xy 420.617904 -399.701258)
			(xy 419.673532 -399.701258) (xy 419.673066 -399.716715) (xy 419.665668 -399.746729) (xy 419.651302 -399.774102)
			(xy 419.630803 -399.79724) (xy 419.605362 -399.814801) (xy 419.576458 -399.825763) (xy 419.54577 -399.829489)
			(xy 419.515082 -399.825763) (xy 419.486178 -399.814801) (xy 419.460737 -399.79724) (xy 419.440238 -399.774102)
			(xy 419.425872 -399.746729) (xy 419.418474 -399.716715) (xy 419.418008 -399.701258) (xy 418.473128 -399.701258)
			(xy 418.472663 -399.716684) (xy 418.46528 -399.746639) (xy 418.450943 -399.773957) (xy 418.430484 -399.79705)
			(xy 418.405094 -399.814576) (xy 418.376247 -399.825516) (xy 418.34562 -399.829235) (xy 418.314993 -399.825516)
			(xy 418.286146 -399.814576) (xy 418.260756 -399.79705) (xy 418.240297 -399.773957) (xy 418.22596 -399.746639)
			(xy 418.218577 -399.716684) (xy 418.218112 -399.701258) (xy 417.273232 -399.701258) (xy 417.272767 -399.716684)
			(xy 417.265384 -399.746639) (xy 417.251047 -399.773957) (xy 417.230588 -399.79705) (xy 417.205198 -399.814576)
			(xy 417.176351 -399.825516) (xy 417.145724 -399.829235) (xy 417.115097 -399.825516) (xy 417.08625 -399.814576)
			(xy 417.06086 -399.79705) (xy 417.040401 -399.773957) (xy 417.026064 -399.746639) (xy 417.018681 -399.716684)
			(xy 417.018216 -399.701258) (xy 416.073336 -399.701258) (xy 416.072871 -399.716684) (xy 416.065488 -399.746639)
			(xy 416.051151 -399.773957) (xy 416.030692 -399.79705) (xy 416.005302 -399.814576) (xy 415.976455 -399.825516)
			(xy 415.945828 -399.829235) (xy 415.915201 -399.825516) (xy 415.886354 -399.814576) (xy 415.860964 -399.79705)
			(xy 415.840505 -399.773957) (xy 415.826168 -399.746639) (xy 415.818785 -399.716684) (xy 415.81832 -399.701258)
			(xy 414.87344 -399.701258) (xy 414.872974 -399.716715) (xy 414.865576 -399.746729) (xy 414.85121 -399.774102)
			(xy 414.830711 -399.79724) (xy 414.80527 -399.814801) (xy 414.776366 -399.825763) (xy 414.745678 -399.829489)
			(xy 414.71499 -399.825763) (xy 414.686086 -399.814801) (xy 414.660645 -399.79724) (xy 414.640146 -399.774102)
			(xy 414.62578 -399.746729) (xy 414.618382 -399.716715) (xy 414.617916 -399.701258) (xy 413.673544 -399.701258)
			(xy 413.673078 -399.716715) (xy 413.66568 -399.746729) (xy 413.651314 -399.774102) (xy 413.630815 -399.79724)
			(xy 413.605374 -399.814801) (xy 413.57647 -399.825763) (xy 413.545782 -399.829489) (xy 413.515094 -399.825763)
			(xy 413.48619 -399.814801) (xy 413.460749 -399.79724) (xy 413.44025 -399.774102) (xy 413.425884 -399.746729)
			(xy 413.418486 -399.716715) (xy 413.41802 -399.701258) (xy 412.47314 -399.701258) (xy 412.472675 -399.716684)
			(xy 412.465292 -399.746639) (xy 412.450955 -399.773957) (xy 412.430496 -399.79705) (xy 412.405106 -399.814576)
			(xy 412.376259 -399.825516) (xy 412.345632 -399.829235) (xy 412.315005 -399.825516) (xy 412.286158 -399.814576)
			(xy 412.260768 -399.79705) (xy 412.240309 -399.773957) (xy 412.225972 -399.746639) (xy 412.218589 -399.716684)
			(xy 412.218124 -399.701258) (xy 411.273244 -399.701258) (xy 411.272779 -399.716684) (xy 411.265396 -399.746639)
			(xy 411.251059 -399.773957) (xy 411.2306 -399.79705) (xy 411.20521 -399.814576) (xy 411.176363 -399.825516)
			(xy 411.145736 -399.829235) (xy 411.115109 -399.825516) (xy 411.086262 -399.814576) (xy 411.060872 -399.79705)
			(xy 411.040413 -399.773957) (xy 411.026076 -399.746639) (xy 411.018693 -399.716684) (xy 411.018228 -399.701258)
			(xy 410.073348 -399.701258) (xy 410.072883 -399.716684) (xy 410.0655 -399.746639) (xy 410.051163 -399.773957)
			(xy 410.030704 -399.79705) (xy 410.005314 -399.814576) (xy 409.976467 -399.825516) (xy 409.94584 -399.829235)
			(xy 409.915213 -399.825516) (xy 409.886366 -399.814576) (xy 409.860976 -399.79705) (xy 409.840517 -399.773957)
			(xy 409.82618 -399.746639) (xy 409.818797 -399.716684) (xy 409.818332 -399.701258) (xy 408.873452 -399.701258)
			(xy 408.872986 -399.716715) (xy 408.865588 -399.746729) (xy 408.851222 -399.774102) (xy 408.830723 -399.79724)
			(xy 408.805282 -399.814801) (xy 408.776378 -399.825763) (xy 408.74569 -399.829489) (xy 408.715002 -399.825763)
			(xy 408.686098 -399.814801) (xy 408.660657 -399.79724) (xy 408.640158 -399.774102) (xy 408.625792 -399.746729)
			(xy 408.618394 -399.716715) (xy 408.617928 -399.701258) (xy 407.673556 -399.701258) (xy 407.67309 -399.716715)
			(xy 407.665692 -399.746729) (xy 407.651326 -399.774102) (xy 407.630827 -399.79724) (xy 407.605386 -399.814801)
			(xy 407.576482 -399.825763) (xy 407.545794 -399.829489) (xy 407.515106 -399.825763) (xy 407.486202 -399.814801)
			(xy 407.460761 -399.79724) (xy 407.440262 -399.774102) (xy 407.425896 -399.746729) (xy 407.418498 -399.716715)
			(xy 407.418032 -399.701258) (xy 406.473152 -399.701258) (xy 406.472687 -399.716684) (xy 406.465304 -399.746639)
			(xy 406.450967 -399.773957) (xy 406.430508 -399.79705) (xy 406.405118 -399.814576) (xy 406.376271 -399.825516)
			(xy 406.345644 -399.829235) (xy 406.315017 -399.825516) (xy 406.28617 -399.814576) (xy 406.26078 -399.79705)
			(xy 406.240321 -399.773957) (xy 406.225984 -399.746639) (xy 406.218601 -399.716684) (xy 406.218136 -399.701258)
			(xy 405.273256 -399.701258) (xy 405.272791 -399.716684) (xy 405.265408 -399.746639) (xy 405.251071 -399.773957)
			(xy 405.230612 -399.79705) (xy 405.205222 -399.814576) (xy 405.176375 -399.825516) (xy 405.145748 -399.829235)
			(xy 405.115121 -399.825516) (xy 405.086274 -399.814576) (xy 405.060884 -399.79705) (xy 405.040425 -399.773957)
			(xy 405.026088 -399.746639) (xy 405.018705 -399.716684) (xy 405.01824 -399.701258) (xy 404.07336 -399.701258)
			(xy 404.072894 -399.716715) (xy 404.065496 -399.746729) (xy 404.05113 -399.774102) (xy 404.030631 -399.79724)
			(xy 404.00519 -399.814801) (xy 403.976286 -399.825763) (xy 403.945598 -399.829489) (xy 403.91491 -399.825763)
			(xy 403.886006 -399.814801) (xy 403.860565 -399.79724) (xy 403.840066 -399.774102) (xy 403.8257 -399.746729)
			(xy 403.818302 -399.716715) (xy 403.817836 -399.701258) (xy 402.873464 -399.701258) (xy 402.872998 -399.716715)
			(xy 402.8656 -399.746729) (xy 402.851234 -399.774102) (xy 402.830735 -399.79724) (xy 402.805294 -399.814801)
			(xy 402.77639 -399.825763) (xy 402.745702 -399.829489) (xy 402.715014 -399.825763) (xy 402.68611 -399.814801)
			(xy 402.660669 -399.79724) (xy 402.64017 -399.774102) (xy 402.625804 -399.746729) (xy 402.618406 -399.716715)
			(xy 402.61794 -399.701258) (xy 388.34568 -399.701258) (xy 388.345214 -399.716715) (xy 388.337816 -399.746729)
			(xy 388.32345 -399.774102) (xy 388.302951 -399.79724) (xy 388.27751 -399.814801) (xy 388.248606 -399.825763)
			(xy 388.217918 -399.829489) (xy 388.18723 -399.825763) (xy 388.158326 -399.814801) (xy 388.132885 -399.79724)
			(xy 388.112386 -399.774102) (xy 388.09802 -399.746729) (xy 388.090622 -399.716715) (xy 388.090156 -399.701258)
			(xy 387.145784 -399.701258) (xy 387.145318 -399.716715) (xy 387.13792 -399.746729) (xy 387.123554 -399.774102)
			(xy 387.103055 -399.79724) (xy 387.077614 -399.814801) (xy 387.04871 -399.825763) (xy 387.018022 -399.829489)
			(xy 386.987334 -399.825763) (xy 386.95843 -399.814801) (xy 386.932989 -399.79724) (xy 386.91249 -399.774102)
			(xy 386.898124 -399.746729) (xy 386.890726 -399.716715) (xy 386.89026 -399.701258) (xy 385.94538 -399.701258)
			(xy 385.944915 -399.716684) (xy 385.937532 -399.746639) (xy 385.923195 -399.773957) (xy 385.902736 -399.79705)
			(xy 385.877346 -399.814576) (xy 385.848499 -399.825516) (xy 385.817872 -399.829235) (xy 385.787245 -399.825516)
			(xy 385.758398 -399.814576) (xy 385.733008 -399.79705) (xy 385.712549 -399.773957) (xy 385.698212 -399.746639)
			(xy 385.690829 -399.716684) (xy 385.690364 -399.701258) (xy 384.745484 -399.701258) (xy 384.745019 -399.716684)
			(xy 384.737636 -399.746639) (xy 384.723299 -399.773957) (xy 384.70284 -399.79705) (xy 384.67745 -399.814576)
			(xy 384.648603 -399.825516) (xy 384.617976 -399.829235) (xy 384.587349 -399.825516) (xy 384.558502 -399.814576)
			(xy 384.533112 -399.79705) (xy 384.512653 -399.773957) (xy 384.498316 -399.746639) (xy 384.490933 -399.716684)
			(xy 384.490468 -399.701258) (xy 383.545588 -399.701258) (xy 383.545123 -399.716684) (xy 383.53774 -399.746639)
			(xy 383.523403 -399.773957) (xy 383.502944 -399.79705) (xy 383.477554 -399.814576) (xy 383.448707 -399.825516)
			(xy 383.41808 -399.829235) (xy 383.387453 -399.825516) (xy 383.358606 -399.814576) (xy 383.333216 -399.79705)
			(xy 383.312757 -399.773957) (xy 383.29842 -399.746639) (xy 383.291037 -399.716684) (xy 383.290572 -399.701258)
			(xy 382.345692 -399.701258) (xy 382.345226 -399.716715) (xy 382.337828 -399.746729) (xy 382.323462 -399.774102)
			(xy 382.302963 -399.79724) (xy 382.277522 -399.814801) (xy 382.248618 -399.825763) (xy 382.21793 -399.829489)
			(xy 382.187242 -399.825763) (xy 382.158338 -399.814801) (xy 382.132897 -399.79724) (xy 382.112398 -399.774102)
			(xy 382.098032 -399.746729) (xy 382.090634 -399.716715) (xy 382.090168 -399.701258) (xy 381.145796 -399.701258)
			(xy 381.14533 -399.716715) (xy 381.137932 -399.746729) (xy 381.123566 -399.774102) (xy 381.103067 -399.79724)
			(xy 381.077626 -399.814801) (xy 381.048722 -399.825763) (xy 381.018034 -399.829489) (xy 380.987346 -399.825763)
			(xy 380.958442 -399.814801) (xy 380.933001 -399.79724) (xy 380.912502 -399.774102) (xy 380.898136 -399.746729)
			(xy 380.890738 -399.716715) (xy 380.890272 -399.701258) (xy 379.945392 -399.701258) (xy 379.944927 -399.716684)
			(xy 379.937544 -399.746639) (xy 379.923207 -399.773957) (xy 379.902748 -399.79705) (xy 379.877358 -399.814576)
			(xy 379.848511 -399.825516) (xy 379.817884 -399.829235) (xy 379.787257 -399.825516) (xy 379.75841 -399.814576)
			(xy 379.73302 -399.79705) (xy 379.712561 -399.773957) (xy 379.698224 -399.746639) (xy 379.690841 -399.716684)
			(xy 379.690376 -399.701258) (xy 378.745496 -399.701258) (xy 378.745031 -399.716684) (xy 378.737648 -399.746639)
			(xy 378.723311 -399.773957) (xy 378.702852 -399.79705) (xy 378.677462 -399.814576) (xy 378.648615 -399.825516)
			(xy 378.617988 -399.829235) (xy 378.587361 -399.825516) (xy 378.558514 -399.814576) (xy 378.533124 -399.79705)
			(xy 378.512665 -399.773957) (xy 378.498328 -399.746639) (xy 378.490945 -399.716684) (xy 378.49048 -399.701258)
			(xy 377.5456 -399.701258) (xy 377.545135 -399.716684) (xy 377.537752 -399.746639) (xy 377.523415 -399.773957)
			(xy 377.502956 -399.79705) (xy 377.477566 -399.814576) (xy 377.448719 -399.825516) (xy 377.418092 -399.829235)
			(xy 377.387465 -399.825516) (xy 377.358618 -399.814576) (xy 377.333228 -399.79705) (xy 377.312769 -399.773957)
			(xy 377.298432 -399.746639) (xy 377.291049 -399.716684) (xy 377.290584 -399.701258) (xy 376.345704 -399.701258)
			(xy 376.345238 -399.716715) (xy 376.33784 -399.746729) (xy 376.323474 -399.774102) (xy 376.302975 -399.79724)
			(xy 376.277534 -399.814801) (xy 376.24863 -399.825763) (xy 376.217942 -399.829489) (xy 376.187254 -399.825763)
			(xy 376.15835 -399.814801) (xy 376.132909 -399.79724) (xy 376.11241 -399.774102) (xy 376.098044 -399.746729)
			(xy 376.090646 -399.716715) (xy 376.09018 -399.701258) (xy 375.145808 -399.701258) (xy 375.145342 -399.716715)
			(xy 375.137944 -399.746729) (xy 375.123578 -399.774102) (xy 375.103079 -399.79724) (xy 375.077638 -399.814801)
			(xy 375.048734 -399.825763) (xy 375.018046 -399.829489) (xy 374.987358 -399.825763) (xy 374.958454 -399.814801)
			(xy 374.933013 -399.79724) (xy 374.912514 -399.774102) (xy 374.898148 -399.746729) (xy 374.89075 -399.716715)
			(xy 374.890284 -399.701258) (xy 373.945404 -399.701258) (xy 373.944939 -399.716684) (xy 373.937556 -399.746639)
			(xy 373.923219 -399.773957) (xy 373.90276 -399.79705) (xy 373.87737 -399.814576) (xy 373.848523 -399.825516)
			(xy 373.817896 -399.829235) (xy 373.787269 -399.825516) (xy 373.758422 -399.814576) (xy 373.733032 -399.79705)
			(xy 373.712573 -399.773957) (xy 373.698236 -399.746639) (xy 373.690853 -399.716684) (xy 373.690388 -399.701258)
			(xy 372.745508 -399.701258) (xy 372.745043 -399.716684) (xy 372.73766 -399.746639) (xy 372.723323 -399.773957)
			(xy 372.702864 -399.79705) (xy 372.677474 -399.814576) (xy 372.648627 -399.825516) (xy 372.618 -399.829235)
			(xy 372.587373 -399.825516) (xy 372.558526 -399.814576) (xy 372.533136 -399.79705) (xy 372.512677 -399.773957)
			(xy 372.49834 -399.746639) (xy 372.490957 -399.716684) (xy 372.490492 -399.701258) (xy 371.545612 -399.701258)
			(xy 371.545146 -399.716715) (xy 371.537748 -399.746729) (xy 371.523382 -399.774102) (xy 371.502883 -399.79724)
			(xy 371.477442 -399.814801) (xy 371.448538 -399.825763) (xy 371.41785 -399.829489) (xy 371.387162 -399.825763)
			(xy 371.358258 -399.814801) (xy 371.332817 -399.79724) (xy 371.312318 -399.774102) (xy 371.297952 -399.746729)
			(xy 371.290554 -399.716715) (xy 371.290088 -399.701258) (xy 370.345716 -399.701258) (xy 370.34525 -399.716715)
			(xy 370.337852 -399.746729) (xy 370.323486 -399.774102) (xy 370.302987 -399.79724) (xy 370.277546 -399.814801)
			(xy 370.248642 -399.825763) (xy 370.217954 -399.829489) (xy 370.187266 -399.825763) (xy 370.158362 -399.814801)
			(xy 370.132921 -399.79724) (xy 370.112422 -399.774102) (xy 370.098056 -399.746729) (xy 370.090658 -399.716715)
			(xy 370.090192 -399.701258) (xy 353.773232 -399.701258) (xy 353.772766 -399.716715) (xy 353.765368 -399.746729)
			(xy 353.751002 -399.774102) (xy 353.730503 -399.79724) (xy 353.705062 -399.814801) (xy 353.676158 -399.825763)
			(xy 353.64547 -399.829489) (xy 353.614782 -399.825763) (xy 353.585878 -399.814801) (xy 353.560437 -399.79724)
			(xy 353.539938 -399.774102) (xy 353.525572 -399.746729) (xy 353.518174 -399.716715) (xy 353.517708 -399.701258)
			(xy 352.573336 -399.701258) (xy 352.57287 -399.716715) (xy 352.565472 -399.746729) (xy 352.551106 -399.774102)
			(xy 352.530607 -399.79724) (xy 352.505166 -399.814801) (xy 352.476262 -399.825763) (xy 352.445574 -399.829489)
			(xy 352.414886 -399.825763) (xy 352.385982 -399.814801) (xy 352.360541 -399.79724) (xy 352.340042 -399.774102)
			(xy 352.325676 -399.746729) (xy 352.318278 -399.716715) (xy 352.317812 -399.701258) (xy 351.372932 -399.701258)
			(xy 351.372467 -399.716684) (xy 351.365084 -399.746639) (xy 351.350747 -399.773957) (xy 351.330288 -399.79705)
			(xy 351.304898 -399.814576) (xy 351.276051 -399.825516) (xy 351.245424 -399.829235) (xy 351.214797 -399.825516)
			(xy 351.18595 -399.814576) (xy 351.16056 -399.79705) (xy 351.140101 -399.773957) (xy 351.125764 -399.746639)
			(xy 351.118381 -399.716684) (xy 351.117916 -399.701258) (xy 350.173036 -399.701258) (xy 350.172571 -399.716684)
			(xy 350.165188 -399.746639) (xy 350.150851 -399.773957) (xy 350.130392 -399.79705) (xy 350.105002 -399.814576)
			(xy 350.076155 -399.825516) (xy 350.045528 -399.829235) (xy 350.014901 -399.825516) (xy 349.986054 -399.814576)
			(xy 349.960664 -399.79705) (xy 349.940205 -399.773957) (xy 349.925868 -399.746639) (xy 349.918485 -399.716684)
			(xy 349.91802 -399.701258) (xy 348.97314 -399.701258) (xy 348.972675 -399.716684) (xy 348.965292 -399.746639)
			(xy 348.950955 -399.773957) (xy 348.930496 -399.79705) (xy 348.905106 -399.814576) (xy 348.876259 -399.825516)
			(xy 348.845632 -399.829235) (xy 348.815005 -399.825516) (xy 348.786158 -399.814576) (xy 348.760768 -399.79705)
			(xy 348.740309 -399.773957) (xy 348.725972 -399.746639) (xy 348.718589 -399.716684) (xy 348.718124 -399.701258)
			(xy 347.773244 -399.701258) (xy 347.772778 -399.716715) (xy 347.76538 -399.746729) (xy 347.751014 -399.774102)
			(xy 347.730515 -399.79724) (xy 347.705074 -399.814801) (xy 347.67617 -399.825763) (xy 347.645482 -399.829489)
			(xy 347.614794 -399.825763) (xy 347.58589 -399.814801) (xy 347.560449 -399.79724) (xy 347.53995 -399.774102)
			(xy 347.525584 -399.746729) (xy 347.518186 -399.716715) (xy 347.51772 -399.701258) (xy 346.573348 -399.701258)
			(xy 346.572882 -399.716715) (xy 346.565484 -399.746729) (xy 346.551118 -399.774102) (xy 346.530619 -399.79724)
			(xy 346.505178 -399.814801) (xy 346.476274 -399.825763) (xy 346.445586 -399.829489) (xy 346.414898 -399.825763)
			(xy 346.385994 -399.814801) (xy 346.360553 -399.79724) (xy 346.340054 -399.774102) (xy 346.325688 -399.746729)
			(xy 346.31829 -399.716715) (xy 346.317824 -399.701258) (xy 345.372944 -399.701258) (xy 345.372479 -399.716684)
			(xy 345.365096 -399.746639) (xy 345.350759 -399.773957) (xy 345.3303 -399.79705) (xy 345.30491 -399.814576)
			(xy 345.276063 -399.825516) (xy 345.245436 -399.829235) (xy 345.214809 -399.825516) (xy 345.185962 -399.814576)
			(xy 345.160572 -399.79705) (xy 345.140113 -399.773957) (xy 345.125776 -399.746639) (xy 345.118393 -399.716684)
			(xy 345.117928 -399.701258) (xy 344.173048 -399.701258) (xy 344.172583 -399.716684) (xy 344.1652 -399.746639)
			(xy 344.150863 -399.773957) (xy 344.130404 -399.79705) (xy 344.105014 -399.814576) (xy 344.076167 -399.825516)
			(xy 344.04554 -399.829235) (xy 344.014913 -399.825516) (xy 343.986066 -399.814576) (xy 343.960676 -399.79705)
			(xy 343.940217 -399.773957) (xy 343.92588 -399.746639) (xy 343.918497 -399.716684) (xy 343.918032 -399.701258)
			(xy 342.973152 -399.701258) (xy 342.972687 -399.716684) (xy 342.965304 -399.746639) (xy 342.950967 -399.773957)
			(xy 342.930508 -399.79705) (xy 342.905118 -399.814576) (xy 342.876271 -399.825516) (xy 342.845644 -399.829235)
			(xy 342.815017 -399.825516) (xy 342.78617 -399.814576) (xy 342.76078 -399.79705) (xy 342.740321 -399.773957)
			(xy 342.725984 -399.746639) (xy 342.718601 -399.716684) (xy 342.718136 -399.701258) (xy 341.773256 -399.701258)
			(xy 341.77279 -399.716715) (xy 341.765392 -399.746729) (xy 341.751026 -399.774102) (xy 341.730527 -399.79724)
			(xy 341.705086 -399.814801) (xy 341.676182 -399.825763) (xy 341.645494 -399.829489) (xy 341.614806 -399.825763)
			(xy 341.585902 -399.814801) (xy 341.560461 -399.79724) (xy 341.539962 -399.774102) (xy 341.525596 -399.746729)
			(xy 341.518198 -399.716715) (xy 341.517732 -399.701258) (xy 340.57336 -399.701258) (xy 340.572894 -399.716715)
			(xy 340.565496 -399.746729) (xy 340.55113 -399.774102) (xy 340.530631 -399.79724) (xy 340.50519 -399.814801)
			(xy 340.476286 -399.825763) (xy 340.445598 -399.829489) (xy 340.41491 -399.825763) (xy 340.386006 -399.814801)
			(xy 340.360565 -399.79724) (xy 340.340066 -399.774102) (xy 340.3257 -399.746729) (xy 340.318302 -399.716715)
			(xy 340.317836 -399.701258) (xy 339.372956 -399.701258) (xy 339.372491 -399.716684) (xy 339.365108 -399.746639)
			(xy 339.350771 -399.773957) (xy 339.330312 -399.79705) (xy 339.304922 -399.814576) (xy 339.276075 -399.825516)
			(xy 339.245448 -399.829235) (xy 339.214821 -399.825516) (xy 339.185974 -399.814576) (xy 339.160584 -399.79705)
			(xy 339.140125 -399.773957) (xy 339.125788 -399.746639) (xy 339.118405 -399.716684) (xy 339.11794 -399.701258)
			(xy 338.17306 -399.701258) (xy 338.172595 -399.716684) (xy 338.165212 -399.746639) (xy 338.150875 -399.773957)
			(xy 338.130416 -399.79705) (xy 338.105026 -399.814576) (xy 338.076179 -399.825516) (xy 338.045552 -399.829235)
			(xy 338.014925 -399.825516) (xy 337.986078 -399.814576) (xy 337.960688 -399.79705) (xy 337.940229 -399.773957)
			(xy 337.925892 -399.746639) (xy 337.918509 -399.716684) (xy 337.918044 -399.701258) (xy 336.973164 -399.701258)
			(xy 336.972698 -399.716715) (xy 336.9653 -399.746729) (xy 336.950934 -399.774102) (xy 336.930435 -399.79724)
			(xy 336.904994 -399.814801) (xy 336.87609 -399.825763) (xy 336.845402 -399.829489) (xy 336.814714 -399.825763)
			(xy 336.78581 -399.814801) (xy 336.760369 -399.79724) (xy 336.73987 -399.774102) (xy 336.725504 -399.746729)
			(xy 336.718106 -399.716715) (xy 336.71764 -399.701258) (xy 335.773268 -399.701258) (xy 335.772802 -399.716715)
			(xy 335.765404 -399.746729) (xy 335.751038 -399.774102) (xy 335.730539 -399.79724) (xy 335.705098 -399.814801)
			(xy 335.676194 -399.825763) (xy 335.645506 -399.829489) (xy 335.614818 -399.825763) (xy 335.585914 -399.814801)
			(xy 335.560473 -399.79724) (xy 335.539974 -399.774102) (xy 335.525608 -399.746729) (xy 335.51821 -399.716715)
			(xy 335.517744 -399.701258) (xy 321.245484 -399.701258) (xy 321.245018 -399.716715) (xy 321.23762 -399.746729)
			(xy 321.223254 -399.774102) (xy 321.202755 -399.79724) (xy 321.177314 -399.814801) (xy 321.14841 -399.825763)
			(xy 321.117722 -399.829489) (xy 321.087034 -399.825763) (xy 321.05813 -399.814801) (xy 321.032689 -399.79724)
			(xy 321.01219 -399.774102) (xy 320.997824 -399.746729) (xy 320.990426 -399.716715) (xy 320.98996 -399.701258)
			(xy 320.045588 -399.701258) (xy 320.045122 -399.716715) (xy 320.037724 -399.746729) (xy 320.023358 -399.774102)
			(xy 320.002859 -399.79724) (xy 319.977418 -399.814801) (xy 319.948514 -399.825763) (xy 319.917826 -399.829489)
			(xy 319.887138 -399.825763) (xy 319.858234 -399.814801) (xy 319.832793 -399.79724) (xy 319.812294 -399.774102)
			(xy 319.797928 -399.746729) (xy 319.79053 -399.716715) (xy 319.790064 -399.701258) (xy 318.845184 -399.701258)
			(xy 318.844719 -399.716684) (xy 318.837336 -399.746639) (xy 318.822999 -399.773957) (xy 318.80254 -399.79705)
			(xy 318.77715 -399.814576) (xy 318.748303 -399.825516) (xy 318.717676 -399.829235) (xy 318.687049 -399.825516)
			(xy 318.658202 -399.814576) (xy 318.632812 -399.79705) (xy 318.612353 -399.773957) (xy 318.598016 -399.746639)
			(xy 318.590633 -399.716684) (xy 318.590168 -399.701258) (xy 317.645288 -399.701258) (xy 317.644823 -399.716684)
			(xy 317.63744 -399.746639) (xy 317.623103 -399.773957) (xy 317.602644 -399.79705) (xy 317.577254 -399.814576)
			(xy 317.548407 -399.825516) (xy 317.51778 -399.829235) (xy 317.487153 -399.825516) (xy 317.458306 -399.814576)
			(xy 317.432916 -399.79705) (xy 317.412457 -399.773957) (xy 317.39812 -399.746639) (xy 317.390737 -399.716684)
			(xy 317.390272 -399.701258) (xy 316.445392 -399.701258) (xy 316.444927 -399.716684) (xy 316.437544 -399.746639)
			(xy 316.423207 -399.773957) (xy 316.402748 -399.79705) (xy 316.377358 -399.814576) (xy 316.348511 -399.825516)
			(xy 316.317884 -399.829235) (xy 316.287257 -399.825516) (xy 316.25841 -399.814576) (xy 316.23302 -399.79705)
			(xy 316.212561 -399.773957) (xy 316.198224 -399.746639) (xy 316.190841 -399.716684) (xy 316.190376 -399.701258)
			(xy 315.245496 -399.701258) (xy 315.24503 -399.716715) (xy 315.237632 -399.746729) (xy 315.223266 -399.774102)
			(xy 315.202767 -399.79724) (xy 315.177326 -399.814801) (xy 315.148422 -399.825763) (xy 315.117734 -399.829489)
			(xy 315.087046 -399.825763) (xy 315.058142 -399.814801) (xy 315.032701 -399.79724) (xy 315.012202 -399.774102)
			(xy 314.997836 -399.746729) (xy 314.990438 -399.716715) (xy 314.989972 -399.701258) (xy 314.0456 -399.701258)
			(xy 314.045134 -399.716715) (xy 314.037736 -399.746729) (xy 314.02337 -399.774102) (xy 314.002871 -399.79724)
			(xy 313.97743 -399.814801) (xy 313.948526 -399.825763) (xy 313.917838 -399.829489) (xy 313.88715 -399.825763)
			(xy 313.858246 -399.814801) (xy 313.832805 -399.79724) (xy 313.812306 -399.774102) (xy 313.79794 -399.746729)
			(xy 313.790542 -399.716715) (xy 313.790076 -399.701258) (xy 312.845196 -399.701258) (xy 312.844731 -399.716684)
			(xy 312.837348 -399.746639) (xy 312.823011 -399.773957) (xy 312.802552 -399.79705) (xy 312.777162 -399.814576)
			(xy 312.748315 -399.825516) (xy 312.717688 -399.829235) (xy 312.687061 -399.825516) (xy 312.658214 -399.814576)
			(xy 312.632824 -399.79705) (xy 312.612365 -399.773957) (xy 312.598028 -399.746639) (xy 312.590645 -399.716684)
			(xy 312.59018 -399.701258) (xy 311.6453 -399.701258) (xy 311.644835 -399.716684) (xy 311.637452 -399.746639)
			(xy 311.623115 -399.773957) (xy 311.602656 -399.79705) (xy 311.577266 -399.814576) (xy 311.548419 -399.825516)
			(xy 311.517792 -399.829235) (xy 311.487165 -399.825516) (xy 311.458318 -399.814576) (xy 311.432928 -399.79705)
			(xy 311.412469 -399.773957) (xy 311.398132 -399.746639) (xy 311.390749 -399.716684) (xy 311.390284 -399.701258)
			(xy 310.445404 -399.701258) (xy 310.444939 -399.716684) (xy 310.437556 -399.746639) (xy 310.423219 -399.773957)
			(xy 310.40276 -399.79705) (xy 310.37737 -399.814576) (xy 310.348523 -399.825516) (xy 310.317896 -399.829235)
			(xy 310.287269 -399.825516) (xy 310.258422 -399.814576) (xy 310.233032 -399.79705) (xy 310.212573 -399.773957)
			(xy 310.198236 -399.746639) (xy 310.190853 -399.716684) (xy 310.190388 -399.701258) (xy 309.245508 -399.701258)
			(xy 309.245042 -399.716715) (xy 309.237644 -399.746729) (xy 309.223278 -399.774102) (xy 309.202779 -399.79724)
			(xy 309.177338 -399.814801) (xy 309.148434 -399.825763) (xy 309.117746 -399.829489) (xy 309.087058 -399.825763)
			(xy 309.058154 -399.814801) (xy 309.032713 -399.79724) (xy 309.012214 -399.774102) (xy 308.997848 -399.746729)
			(xy 308.99045 -399.716715) (xy 308.989984 -399.701258) (xy 308.045612 -399.701258) (xy 308.045146 -399.716715)
			(xy 308.037748 -399.746729) (xy 308.023382 -399.774102) (xy 308.002883 -399.79724) (xy 307.977442 -399.814801)
			(xy 307.948538 -399.825763) (xy 307.91785 -399.829489) (xy 307.887162 -399.825763) (xy 307.858258 -399.814801)
			(xy 307.832817 -399.79724) (xy 307.812318 -399.774102) (xy 307.797952 -399.746729) (xy 307.790554 -399.716715)
			(xy 307.790088 -399.701258) (xy 306.845208 -399.701258) (xy 306.844743 -399.716684) (xy 306.83736 -399.746639)
			(xy 306.823023 -399.773957) (xy 306.802564 -399.79705) (xy 306.777174 -399.814576) (xy 306.748327 -399.825516)
			(xy 306.7177 -399.829235) (xy 306.687073 -399.825516) (xy 306.658226 -399.814576) (xy 306.632836 -399.79705)
			(xy 306.612377 -399.773957) (xy 306.59804 -399.746639) (xy 306.590657 -399.716684) (xy 306.590192 -399.701258)
			(xy 305.645312 -399.701258) (xy 305.644847 -399.716684) (xy 305.637464 -399.746639) (xy 305.623127 -399.773957)
			(xy 305.602668 -399.79705) (xy 305.577278 -399.814576) (xy 305.548431 -399.825516) (xy 305.517804 -399.829235)
			(xy 305.487177 -399.825516) (xy 305.45833 -399.814576) (xy 305.43294 -399.79705) (xy 305.412481 -399.773957)
			(xy 305.398144 -399.746639) (xy 305.390761 -399.716684) (xy 305.390296 -399.701258) (xy 304.445416 -399.701258)
			(xy 304.44495 -399.716715) (xy 304.437552 -399.746729) (xy 304.423186 -399.774102) (xy 304.402687 -399.79724)
			(xy 304.377246 -399.814801) (xy 304.348342 -399.825763) (xy 304.317654 -399.829489) (xy 304.286966 -399.825763)
			(xy 304.258062 -399.814801) (xy 304.232621 -399.79724) (xy 304.212122 -399.774102) (xy 304.197756 -399.746729)
			(xy 304.190358 -399.716715) (xy 304.189892 -399.701258) (xy 303.24552 -399.701258) (xy 303.245054 -399.716715)
			(xy 303.237656 -399.746729) (xy 303.22329 -399.774102) (xy 303.202791 -399.79724) (xy 303.17735 -399.814801)
			(xy 303.148446 -399.825763) (xy 303.117758 -399.829489) (xy 303.08707 -399.825763) (xy 303.058166 -399.814801)
			(xy 303.032725 -399.79724) (xy 303.012226 -399.774102) (xy 302.99786 -399.746729) (xy 302.990462 -399.716715)
			(xy 302.989996 -399.701258) (xy 280.68524 -399.701258) (xy 280.68524 -401.674838) (xy 303.434496 -401.674838)
			(xy 303.434496 -400.811238) (xy 303.434982 -400.783969) (xy 303.442744 -400.729985) (xy 303.458109 -400.677655)
			(xy 303.480766 -400.628045) (xy 303.510252 -400.582164) (xy 303.545967 -400.540947) (xy 303.587184 -400.505232)
			(xy 303.633065 -400.475746) (xy 303.682675 -400.453089) (xy 303.735005 -400.437724) (xy 303.788989 -400.429962)
			(xy 303.843527 -400.429962) (xy 303.897511 -400.437724) (xy 303.949841 -400.453089) (xy 303.999451 -400.475746)
			(xy 304.045332 -400.505232) (xy 304.086549 -400.540947) (xy 304.122264 -400.582164) (xy 304.15175 -400.628045)
			(xy 304.174407 -400.677655) (xy 304.189772 -400.729985) (xy 304.197534 -400.783969) (xy 304.19802 -400.811238)
			(xy 304.19802 -401.674838) (xy 304.634392 -401.674838) (xy 304.634392 -400.811238) (xy 304.634878 -400.783969)
			(xy 304.64264 -400.729985) (xy 304.658005 -400.677655) (xy 304.680662 -400.628045) (xy 304.710148 -400.582164)
			(xy 304.745863 -400.540947) (xy 304.78708 -400.505232) (xy 304.832961 -400.475746) (xy 304.882571 -400.453089)
			(xy 304.934901 -400.437724) (xy 304.988885 -400.429962) (xy 305.043423 -400.429962) (xy 305.097407 -400.437724)
			(xy 305.149737 -400.453089) (xy 305.199347 -400.475746) (xy 305.245228 -400.505232) (xy 305.286445 -400.540947)
			(xy 305.32216 -400.582164) (xy 305.351646 -400.628045) (xy 305.374303 -400.677655) (xy 305.389668 -400.729985)
			(xy 305.39743 -400.783969) (xy 305.397916 -400.811238) (xy 305.397916 -401.674838) (xy 305.834796 -401.674838)
			(xy 305.834796 -400.811238) (xy 305.835282 -400.783987) (xy 305.843038 -400.730039) (xy 305.858393 -400.677744)
			(xy 305.881035 -400.628167) (xy 305.910501 -400.582317) (xy 305.946192 -400.541126) (xy 305.987383 -400.505435)
			(xy 306.033233 -400.475969) (xy 306.08281 -400.453327) (xy 306.135105 -400.437972) (xy 306.189053 -400.430216)
			(xy 306.243555 -400.430216) (xy 306.297503 -400.437972) (xy 306.349798 -400.453327) (xy 306.399375 -400.475969)
			(xy 306.445225 -400.505435) (xy 306.486416 -400.541126) (xy 306.522107 -400.582317) (xy 306.551573 -400.628167)
			(xy 306.574215 -400.677744) (xy 306.58957 -400.730039) (xy 306.597326 -400.783987) (xy 306.597812 -400.811238)
			(xy 306.597812 -401.674838) (xy 307.034692 -401.674838) (xy 307.034692 -400.811238) (xy 307.035178 -400.783987)
			(xy 307.042934 -400.730039) (xy 307.058289 -400.677744) (xy 307.080931 -400.628167) (xy 307.110397 -400.582317)
			(xy 307.146088 -400.541126) (xy 307.187279 -400.505435) (xy 307.233129 -400.475969) (xy 307.282706 -400.453327)
			(xy 307.335001 -400.437972) (xy 307.388949 -400.430216) (xy 307.443451 -400.430216) (xy 307.497399 -400.437972)
			(xy 307.549694 -400.453327) (xy 307.599271 -400.475969) (xy 307.645121 -400.505435) (xy 307.686312 -400.541126)
			(xy 307.722003 -400.582317) (xy 307.751469 -400.628167) (xy 307.774111 -400.677744) (xy 307.789466 -400.730039)
			(xy 307.797222 -400.783987) (xy 307.797708 -400.811238) (xy 307.797708 -401.674838) (xy 308.234588 -401.674838)
			(xy 308.234588 -400.811238) (xy 308.235074 -400.783969) (xy 308.242836 -400.729985) (xy 308.258201 -400.677655)
			(xy 308.280858 -400.628045) (xy 308.310344 -400.582164) (xy 308.346059 -400.540947) (xy 308.387276 -400.505232)
			(xy 308.433157 -400.475746) (xy 308.482767 -400.453089) (xy 308.535097 -400.437724) (xy 308.589081 -400.429962)
			(xy 308.643619 -400.429962) (xy 308.697603 -400.437724) (xy 308.749933 -400.453089) (xy 308.799543 -400.475746)
			(xy 308.845424 -400.505232) (xy 308.886641 -400.540947) (xy 308.922356 -400.582164) (xy 308.951842 -400.628045)
			(xy 308.974499 -400.677655) (xy 308.989864 -400.729985) (xy 308.997626 -400.783969) (xy 308.998112 -400.811238)
			(xy 308.998112 -401.674838) (xy 309.434484 -401.674838) (xy 309.434484 -400.811238) (xy 309.43497 -400.783969)
			(xy 309.442732 -400.729985) (xy 309.458097 -400.677655) (xy 309.480754 -400.628045) (xy 309.51024 -400.582164)
			(xy 309.545955 -400.540947) (xy 309.587172 -400.505232) (xy 309.633053 -400.475746) (xy 309.682663 -400.453089)
			(xy 309.734993 -400.437724) (xy 309.788977 -400.429962) (xy 309.843515 -400.429962) (xy 309.897499 -400.437724)
			(xy 309.949829 -400.453089) (xy 309.999439 -400.475746) (xy 310.04532 -400.505232) (xy 310.086537 -400.540947)
			(xy 310.122252 -400.582164) (xy 310.151738 -400.628045) (xy 310.174395 -400.677655) (xy 310.18976 -400.729985)
			(xy 310.197522 -400.783969) (xy 310.198008 -400.811238) (xy 310.198008 -401.674838) (xy 310.634888 -401.674838)
			(xy 310.634888 -400.811238) (xy 310.635374 -400.783987) (xy 310.64313 -400.730039) (xy 310.658485 -400.677744)
			(xy 310.681127 -400.628167) (xy 310.710593 -400.582317) (xy 310.746284 -400.541126) (xy 310.787475 -400.505435)
			(xy 310.833325 -400.475969) (xy 310.882902 -400.453327) (xy 310.935197 -400.437972) (xy 310.989145 -400.430216)
			(xy 311.043647 -400.430216) (xy 311.097595 -400.437972) (xy 311.14989 -400.453327) (xy 311.199467 -400.475969)
			(xy 311.245317 -400.505435) (xy 311.286508 -400.541126) (xy 311.322199 -400.582317) (xy 311.351665 -400.628167)
			(xy 311.374307 -400.677744) (xy 311.389662 -400.730039) (xy 311.397418 -400.783987) (xy 311.397904 -400.811238)
			(xy 311.397904 -401.674838) (xy 311.834784 -401.674838) (xy 311.834784 -400.811238) (xy 311.83527 -400.783987)
			(xy 311.843026 -400.730039) (xy 311.858381 -400.677744) (xy 311.881023 -400.628167) (xy 311.910489 -400.582317)
			(xy 311.94618 -400.541126) (xy 311.987371 -400.505435) (xy 312.033221 -400.475969) (xy 312.082798 -400.453327)
			(xy 312.135093 -400.437972) (xy 312.189041 -400.430216) (xy 312.243543 -400.430216) (xy 312.297491 -400.437972)
			(xy 312.349786 -400.453327) (xy 312.399363 -400.475969) (xy 312.445213 -400.505435) (xy 312.486404 -400.541126)
			(xy 312.522095 -400.582317) (xy 312.551561 -400.628167) (xy 312.574203 -400.677744) (xy 312.589558 -400.730039)
			(xy 312.597314 -400.783987) (xy 312.5978 -400.811238) (xy 312.5978 -401.674838) (xy 313.03468 -401.674838)
			(xy 313.03468 -400.811238) (xy 313.035166 -400.783969) (xy 313.042928 -400.729985) (xy 313.058293 -400.677655)
			(xy 313.08095 -400.628045) (xy 313.110436 -400.582164) (xy 313.146151 -400.540947) (xy 313.187368 -400.505232)
			(xy 313.233249 -400.475746) (xy 313.282859 -400.453089) (xy 313.335189 -400.437724) (xy 313.389173 -400.429962)
			(xy 313.443711 -400.429962) (xy 313.497695 -400.437724) (xy 313.550025 -400.453089) (xy 313.599635 -400.475746)
			(xy 313.645516 -400.505232) (xy 313.686733 -400.540947) (xy 313.722448 -400.582164) (xy 313.751934 -400.628045)
			(xy 313.774591 -400.677655) (xy 313.789956 -400.729985) (xy 313.797718 -400.783969) (xy 313.798204 -400.811238)
			(xy 313.798204 -401.674838) (xy 314.234576 -401.674838) (xy 314.234576 -400.811238) (xy 314.235062 -400.783969)
			(xy 314.242824 -400.729985) (xy 314.258189 -400.677655) (xy 314.280846 -400.628045) (xy 314.310332 -400.582164)
			(xy 314.346047 -400.540947) (xy 314.387264 -400.505232) (xy 314.433145 -400.475746) (xy 314.482755 -400.453089)
			(xy 314.535085 -400.437724) (xy 314.589069 -400.429962) (xy 314.643607 -400.429962) (xy 314.697591 -400.437724)
			(xy 314.749921 -400.453089) (xy 314.799531 -400.475746) (xy 314.845412 -400.505232) (xy 314.886629 -400.540947)
			(xy 314.922344 -400.582164) (xy 314.95183 -400.628045) (xy 314.974487 -400.677655) (xy 314.989852 -400.729985)
			(xy 314.997614 -400.783969) (xy 314.9981 -400.811238) (xy 314.9981 -401.674838) (xy 315.43498 -401.674838)
			(xy 315.43498 -400.811238) (xy 315.435466 -400.783987) (xy 315.443222 -400.730039) (xy 315.458577 -400.677744)
			(xy 315.481219 -400.628167) (xy 315.510685 -400.582317) (xy 315.546376 -400.541126) (xy 315.587567 -400.505435)
			(xy 315.633417 -400.475969) (xy 315.682994 -400.453327) (xy 315.735289 -400.437972) (xy 315.789237 -400.430216)
			(xy 315.843739 -400.430216) (xy 315.897687 -400.437972) (xy 315.949982 -400.453327) (xy 315.999559 -400.475969)
			(xy 316.045409 -400.505435) (xy 316.0866 -400.541126) (xy 316.122291 -400.582317) (xy 316.151757 -400.628167)
			(xy 316.174399 -400.677744) (xy 316.189754 -400.730039) (xy 316.19751 -400.783987) (xy 316.197996 -400.811238)
			(xy 316.197996 -401.674838) (xy 316.634876 -401.674838) (xy 316.634876 -400.811238) (xy 316.635362 -400.783987)
			(xy 316.643118 -400.730039) (xy 316.658473 -400.677744) (xy 316.681115 -400.628167) (xy 316.710581 -400.582317)
			(xy 316.746272 -400.541126) (xy 316.787463 -400.505435) (xy 316.833313 -400.475969) (xy 316.88289 -400.453327)
			(xy 316.935185 -400.437972) (xy 316.989133 -400.430216) (xy 317.043635 -400.430216) (xy 317.097583 -400.437972)
			(xy 317.149878 -400.453327) (xy 317.199455 -400.475969) (xy 317.245305 -400.505435) (xy 317.286496 -400.541126)
			(xy 317.322187 -400.582317) (xy 317.351653 -400.628167) (xy 317.374295 -400.677744) (xy 317.38965 -400.730039)
			(xy 317.397406 -400.783987) (xy 317.397892 -400.811238) (xy 317.397892 -401.674838) (xy 317.834772 -401.674838)
			(xy 317.834772 -400.811238) (xy 317.835258 -400.783987) (xy 317.843014 -400.730039) (xy 317.858369 -400.677744)
			(xy 317.881011 -400.628167) (xy 317.910477 -400.582317) (xy 317.946168 -400.541126) (xy 317.987359 -400.505435)
			(xy 318.033209 -400.475969) (xy 318.082786 -400.453327) (xy 318.135081 -400.437972) (xy 318.189029 -400.430216)
			(xy 318.243531 -400.430216) (xy 318.297479 -400.437972) (xy 318.349774 -400.453327) (xy 318.399351 -400.475969)
			(xy 318.445201 -400.505435) (xy 318.486392 -400.541126) (xy 318.522083 -400.582317) (xy 318.551549 -400.628167)
			(xy 318.574191 -400.677744) (xy 318.589546 -400.730039) (xy 318.597302 -400.783987) (xy 318.597788 -400.811238)
			(xy 318.597788 -401.674838) (xy 319.034668 -401.674838) (xy 319.034668 -400.811238) (xy 319.035154 -400.783987)
			(xy 319.04291 -400.730039) (xy 319.058265 -400.677744) (xy 319.080907 -400.628167) (xy 319.110373 -400.582317)
			(xy 319.146064 -400.541126) (xy 319.187255 -400.505435) (xy 319.233105 -400.475969) (xy 319.282682 -400.453327)
			(xy 319.334977 -400.437972) (xy 319.388925 -400.430216) (xy 319.443427 -400.430216) (xy 319.497375 -400.437972)
			(xy 319.54967 -400.453327) (xy 319.599247 -400.475969) (xy 319.645097 -400.505435) (xy 319.686288 -400.541126)
			(xy 319.721979 -400.582317) (xy 319.751445 -400.628167) (xy 319.774087 -400.677744) (xy 319.789442 -400.730039)
			(xy 319.797198 -400.783987) (xy 319.797684 -400.811238) (xy 319.797684 -401.674838) (xy 320.234564 -401.674838)
			(xy 320.234564 -400.811238) (xy 320.23505 -400.783969) (xy 320.242812 -400.729985) (xy 320.258177 -400.677655)
			(xy 320.280834 -400.628045) (xy 320.31032 -400.582164) (xy 320.346035 -400.540947) (xy 320.387252 -400.505232)
			(xy 320.433133 -400.475746) (xy 320.482743 -400.453089) (xy 320.535073 -400.437724) (xy 320.589057 -400.429962)
			(xy 320.643595 -400.429962) (xy 320.697579 -400.437724) (xy 320.749909 -400.453089) (xy 320.799519 -400.475746)
			(xy 320.8454 -400.505232) (xy 320.886617 -400.540947) (xy 320.922332 -400.582164) (xy 320.951818 -400.628045)
			(xy 320.974475 -400.677655) (xy 320.98984 -400.729985) (xy 320.997602 -400.783969) (xy 320.998088 -400.811238)
			(xy 320.998088 -401.674838) (xy 321.43446 -401.674838) (xy 321.43446 -400.811238) (xy 321.434946 -400.783969)
			(xy 321.442708 -400.729985) (xy 321.458073 -400.677655) (xy 321.48073 -400.628045) (xy 321.510216 -400.582164)
			(xy 321.545931 -400.540947) (xy 321.587148 -400.505232) (xy 321.633029 -400.475746) (xy 321.682639 -400.453089)
			(xy 321.734969 -400.437724) (xy 321.788953 -400.429962) (xy 321.843491 -400.429962) (xy 321.897475 -400.437724)
			(xy 321.949805 -400.453089) (xy 321.999415 -400.475746) (xy 322.045296 -400.505232) (xy 322.086513 -400.540947)
			(xy 322.122228 -400.582164) (xy 322.151714 -400.628045) (xy 322.174371 -400.677655) (xy 322.189736 -400.729985)
			(xy 322.197498 -400.783969) (xy 322.197984 -400.811238) (xy 322.197984 -401.674838) (xy 335.962244 -401.674838)
			(xy 335.962244 -400.811238) (xy 335.96273 -400.783969) (xy 335.970492 -400.729985) (xy 335.985857 -400.677655)
			(xy 336.008514 -400.628045) (xy 336.038 -400.582164) (xy 336.073715 -400.540947) (xy 336.114932 -400.505232)
			(xy 336.160813 -400.475746) (xy 336.210423 -400.453089) (xy 336.262753 -400.437724) (xy 336.316737 -400.429962)
			(xy 336.371275 -400.429962) (xy 336.425259 -400.437724) (xy 336.477589 -400.453089) (xy 336.527199 -400.475746)
			(xy 336.57308 -400.505232) (xy 336.614297 -400.540947) (xy 336.650012 -400.582164) (xy 336.679498 -400.628045)
			(xy 336.702155 -400.677655) (xy 336.71752 -400.729985) (xy 336.725282 -400.783969) (xy 336.725768 -400.811238)
			(xy 336.725768 -401.674838) (xy 337.16214 -401.674838) (xy 337.16214 -400.811238) (xy 337.162626 -400.783969)
			(xy 337.170388 -400.729985) (xy 337.185753 -400.677655) (xy 337.20841 -400.628045) (xy 337.237896 -400.582164)
			(xy 337.273611 -400.540947) (xy 337.314828 -400.505232) (xy 337.360709 -400.475746) (xy 337.410319 -400.453089)
			(xy 337.462649 -400.437724) (xy 337.516633 -400.429962) (xy 337.571171 -400.429962) (xy 337.625155 -400.437724)
			(xy 337.677485 -400.453089) (xy 337.727095 -400.475746) (xy 337.772976 -400.505232) (xy 337.814193 -400.540947)
			(xy 337.849908 -400.582164) (xy 337.879394 -400.628045) (xy 337.902051 -400.677655) (xy 337.917416 -400.729985)
			(xy 337.925178 -400.783969) (xy 337.925664 -400.811238) (xy 337.925664 -401.674838) (xy 338.362544 -401.674838)
			(xy 338.362544 -400.811238) (xy 338.36303 -400.783987) (xy 338.370786 -400.730039) (xy 338.386141 -400.677744)
			(xy 338.408783 -400.628167) (xy 338.438249 -400.582317) (xy 338.47394 -400.541126) (xy 338.515131 -400.505435)
			(xy 338.560981 -400.475969) (xy 338.610558 -400.453327) (xy 338.662853 -400.437972) (xy 338.716801 -400.430216)
			(xy 338.771303 -400.430216) (xy 338.825251 -400.437972) (xy 338.877546 -400.453327) (xy 338.927123 -400.475969)
			(xy 338.972973 -400.505435) (xy 339.014164 -400.541126) (xy 339.049855 -400.582317) (xy 339.079321 -400.628167)
			(xy 339.101963 -400.677744) (xy 339.117318 -400.730039) (xy 339.125074 -400.783987) (xy 339.12556 -400.811238)
			(xy 339.12556 -401.674838) (xy 339.56244 -401.674838) (xy 339.56244 -400.811238) (xy 339.562926 -400.783987)
			(xy 339.570682 -400.730039) (xy 339.586037 -400.677744) (xy 339.608679 -400.628167) (xy 339.638145 -400.582317)
			(xy 339.673836 -400.541126) (xy 339.715027 -400.505435) (xy 339.760877 -400.475969) (xy 339.810454 -400.453327)
			(xy 339.862749 -400.437972) (xy 339.916697 -400.430216) (xy 339.971199 -400.430216) (xy 340.025147 -400.437972)
			(xy 340.077442 -400.453327) (xy 340.127019 -400.475969) (xy 340.172869 -400.505435) (xy 340.21406 -400.541126)
			(xy 340.249751 -400.582317) (xy 340.279217 -400.628167) (xy 340.301859 -400.677744) (xy 340.317214 -400.730039)
			(xy 340.32497 -400.783987) (xy 340.325456 -400.811238) (xy 340.325456 -401.674838) (xy 340.762336 -401.674838)
			(xy 340.762336 -400.811238) (xy 340.762822 -400.783969) (xy 340.770584 -400.729985) (xy 340.785949 -400.677655)
			(xy 340.808606 -400.628045) (xy 340.838092 -400.582164) (xy 340.873807 -400.540947) (xy 340.915024 -400.505232)
			(xy 340.960905 -400.475746) (xy 341.010515 -400.453089) (xy 341.062845 -400.437724) (xy 341.116829 -400.429962)
			(xy 341.171367 -400.429962) (xy 341.225351 -400.437724) (xy 341.277681 -400.453089) (xy 341.327291 -400.475746)
			(xy 341.373172 -400.505232) (xy 341.414389 -400.540947) (xy 341.450104 -400.582164) (xy 341.47959 -400.628045)
			(xy 341.502247 -400.677655) (xy 341.517612 -400.729985) (xy 341.525374 -400.783969) (xy 341.52586 -400.811238)
			(xy 341.52586 -401.674838) (xy 341.962232 -401.674838) (xy 341.962232 -400.811238) (xy 341.962718 -400.783969)
			(xy 341.97048 -400.729985) (xy 341.985845 -400.677655) (xy 342.008502 -400.628045) (xy 342.037988 -400.582164)
			(xy 342.073703 -400.540947) (xy 342.11492 -400.505232) (xy 342.160801 -400.475746) (xy 342.210411 -400.453089)
			(xy 342.262741 -400.437724) (xy 342.316725 -400.429962) (xy 342.371263 -400.429962) (xy 342.425247 -400.437724)
			(xy 342.477577 -400.453089) (xy 342.527187 -400.475746) (xy 342.573068 -400.505232) (xy 342.614285 -400.540947)
			(xy 342.65 -400.582164) (xy 342.679486 -400.628045) (xy 342.702143 -400.677655) (xy 342.717508 -400.729985)
			(xy 342.72527 -400.783969) (xy 342.725756 -400.811238) (xy 342.725756 -401.674838) (xy 343.162636 -401.674838)
			(xy 343.162636 -400.811238) (xy 343.163122 -400.783987) (xy 343.170878 -400.730039) (xy 343.186233 -400.677744)
			(xy 343.208875 -400.628167) (xy 343.238341 -400.582317) (xy 343.274032 -400.541126) (xy 343.315223 -400.505435)
			(xy 343.361073 -400.475969) (xy 343.41065 -400.453327) (xy 343.462945 -400.437972) (xy 343.516893 -400.430216)
			(xy 343.571395 -400.430216) (xy 343.625343 -400.437972) (xy 343.677638 -400.453327) (xy 343.727215 -400.475969)
			(xy 343.773065 -400.505435) (xy 343.814256 -400.541126) (xy 343.849947 -400.582317) (xy 343.879413 -400.628167)
			(xy 343.902055 -400.677744) (xy 343.91741 -400.730039) (xy 343.925166 -400.783987) (xy 343.925652 -400.811238)
			(xy 343.925652 -401.674838) (xy 344.362532 -401.674838) (xy 344.362532 -400.811238) (xy 344.363018 -400.783987)
			(xy 344.370774 -400.730039) (xy 344.386129 -400.677744) (xy 344.408771 -400.628167) (xy 344.438237 -400.582317)
			(xy 344.473928 -400.541126) (xy 344.515119 -400.505435) (xy 344.560969 -400.475969) (xy 344.610546 -400.453327)
			(xy 344.662841 -400.437972) (xy 344.716789 -400.430216) (xy 344.771291 -400.430216) (xy 344.825239 -400.437972)
			(xy 344.877534 -400.453327) (xy 344.927111 -400.475969) (xy 344.972961 -400.505435) (xy 345.014152 -400.541126)
			(xy 345.049843 -400.582317) (xy 345.079309 -400.628167) (xy 345.101951 -400.677744) (xy 345.117306 -400.730039)
			(xy 345.125062 -400.783987) (xy 345.125548 -400.811238) (xy 345.125548 -401.674838) (xy 345.562428 -401.674838)
			(xy 345.562428 -400.811238) (xy 345.562914 -400.783969) (xy 345.570676 -400.729985) (xy 345.586041 -400.677655)
			(xy 345.608698 -400.628045) (xy 345.638184 -400.582164) (xy 345.673899 -400.540947) (xy 345.715116 -400.505232)
			(xy 345.760997 -400.475746) (xy 345.810607 -400.453089) (xy 345.862937 -400.437724) (xy 345.916921 -400.429962)
			(xy 345.971459 -400.429962) (xy 346.025443 -400.437724) (xy 346.077773 -400.453089) (xy 346.127383 -400.475746)
			(xy 346.173264 -400.505232) (xy 346.214481 -400.540947) (xy 346.250196 -400.582164) (xy 346.279682 -400.628045)
			(xy 346.302339 -400.677655) (xy 346.317704 -400.729985) (xy 346.325466 -400.783969) (xy 346.325952 -400.811238)
			(xy 346.325952 -401.674838) (xy 346.762324 -401.674838) (xy 346.762324 -400.811238) (xy 346.76281 -400.783969)
			(xy 346.770572 -400.729985) (xy 346.785937 -400.677655) (xy 346.808594 -400.628045) (xy 346.83808 -400.582164)
			(xy 346.873795 -400.540947) (xy 346.915012 -400.505232) (xy 346.960893 -400.475746) (xy 347.010503 -400.453089)
			(xy 347.062833 -400.437724) (xy 347.116817 -400.429962) (xy 347.171355 -400.429962) (xy 347.225339 -400.437724)
			(xy 347.277669 -400.453089) (xy 347.327279 -400.475746) (xy 347.37316 -400.505232) (xy 347.414377 -400.540947)
			(xy 347.450092 -400.582164) (xy 347.479578 -400.628045) (xy 347.502235 -400.677655) (xy 347.5176 -400.729985)
			(xy 347.525362 -400.783969) (xy 347.525848 -400.811238) (xy 347.525848 -401.674838) (xy 347.962728 -401.674838)
			(xy 347.962728 -400.811238) (xy 347.963214 -400.783987) (xy 347.97097 -400.730039) (xy 347.986325 -400.677744)
			(xy 348.008967 -400.628167) (xy 348.038433 -400.582317) (xy 348.074124 -400.541126) (xy 348.115315 -400.505435)
			(xy 348.161165 -400.475969) (xy 348.210742 -400.453327) (xy 348.263037 -400.437972) (xy 348.316985 -400.430216)
			(xy 348.371487 -400.430216) (xy 348.425435 -400.437972) (xy 348.47773 -400.453327) (xy 348.527307 -400.475969)
			(xy 348.573157 -400.505435) (xy 348.614348 -400.541126) (xy 348.650039 -400.582317) (xy 348.679505 -400.628167)
			(xy 348.702147 -400.677744) (xy 348.717502 -400.730039) (xy 348.725258 -400.783987) (xy 348.725744 -400.811238)
			(xy 348.725744 -401.674838) (xy 349.162624 -401.674838) (xy 349.162624 -400.811238) (xy 349.16311 -400.783987)
			(xy 349.170866 -400.730039) (xy 349.186221 -400.677744) (xy 349.208863 -400.628167) (xy 349.238329 -400.582317)
			(xy 349.27402 -400.541126) (xy 349.315211 -400.505435) (xy 349.361061 -400.475969) (xy 349.410638 -400.453327)
			(xy 349.462933 -400.437972) (xy 349.516881 -400.430216) (xy 349.571383 -400.430216) (xy 349.625331 -400.437972)
			(xy 349.677626 -400.453327) (xy 349.727203 -400.475969) (xy 349.773053 -400.505435) (xy 349.814244 -400.541126)
			(xy 349.849935 -400.582317) (xy 349.879401 -400.628167) (xy 349.902043 -400.677744) (xy 349.917398 -400.730039)
			(xy 349.925154 -400.783987) (xy 349.92564 -400.811238) (xy 349.92564 -401.674838) (xy 350.36252 -401.674838)
			(xy 350.36252 -400.811238) (xy 350.363006 -400.783987) (xy 350.370762 -400.730039) (xy 350.386117 -400.677744)
			(xy 350.408759 -400.628167) (xy 350.438225 -400.582317) (xy 350.473916 -400.541126) (xy 350.515107 -400.505435)
			(xy 350.560957 -400.475969) (xy 350.610534 -400.453327) (xy 350.662829 -400.437972) (xy 350.716777 -400.430216)
			(xy 350.771279 -400.430216) (xy 350.825227 -400.437972) (xy 350.877522 -400.453327) (xy 350.927099 -400.475969)
			(xy 350.972949 -400.505435) (xy 351.01414 -400.541126) (xy 351.049831 -400.582317) (xy 351.079297 -400.628167)
			(xy 351.101939 -400.677744) (xy 351.117294 -400.730039) (xy 351.12505 -400.783987) (xy 351.125536 -400.811238)
			(xy 351.125536 -401.674838) (xy 351.562416 -401.674838) (xy 351.562416 -400.811238) (xy 351.562902 -400.783987)
			(xy 351.570658 -400.730039) (xy 351.586013 -400.677744) (xy 351.608655 -400.628167) (xy 351.638121 -400.582317)
			(xy 351.673812 -400.541126) (xy 351.715003 -400.505435) (xy 351.760853 -400.475969) (xy 351.81043 -400.453327)
			(xy 351.862725 -400.437972) (xy 351.916673 -400.430216) (xy 351.971175 -400.430216) (xy 352.025123 -400.437972)
			(xy 352.077418 -400.453327) (xy 352.126995 -400.475969) (xy 352.172845 -400.505435) (xy 352.214036 -400.541126)
			(xy 352.249727 -400.582317) (xy 352.279193 -400.628167) (xy 352.301835 -400.677744) (xy 352.31719 -400.730039)
			(xy 352.324946 -400.783987) (xy 352.325432 -400.811238) (xy 352.325432 -401.674838) (xy 352.762312 -401.674838)
			(xy 352.762312 -400.811238) (xy 352.762798 -400.783969) (xy 352.77056 -400.729985) (xy 352.785925 -400.677655)
			(xy 352.808582 -400.628045) (xy 352.838068 -400.582164) (xy 352.873783 -400.540947) (xy 352.915 -400.505232)
			(xy 352.960881 -400.475746) (xy 353.010491 -400.453089) (xy 353.062821 -400.437724) (xy 353.116805 -400.429962)
			(xy 353.171343 -400.429962) (xy 353.225327 -400.437724) (xy 353.277657 -400.453089) (xy 353.327267 -400.475746)
			(xy 353.373148 -400.505232) (xy 353.414365 -400.540947) (xy 353.45008 -400.582164) (xy 353.479566 -400.628045)
			(xy 353.502223 -400.677655) (xy 353.517588 -400.729985) (xy 353.52535 -400.783969) (xy 353.525836 -400.811238)
			(xy 353.525836 -401.674838) (xy 353.962208 -401.674838) (xy 353.962208 -400.811238) (xy 353.962694 -400.783969)
			(xy 353.970456 -400.729985) (xy 353.985821 -400.677655) (xy 354.008478 -400.628045) (xy 354.037964 -400.582164)
			(xy 354.073679 -400.540947) (xy 354.114896 -400.505232) (xy 354.160777 -400.475746) (xy 354.210387 -400.453089)
			(xy 354.262717 -400.437724) (xy 354.316701 -400.429962) (xy 354.371239 -400.429962) (xy 354.425223 -400.437724)
			(xy 354.477553 -400.453089) (xy 354.527163 -400.475746) (xy 354.573044 -400.505232) (xy 354.614261 -400.540947)
			(xy 354.649976 -400.582164) (xy 354.679462 -400.628045) (xy 354.702119 -400.677655) (xy 354.717484 -400.729985)
			(xy 354.725246 -400.783969) (xy 354.725732 -400.811238) (xy 354.725732 -401.674838) (xy 370.534692 -401.674838)
			(xy 370.534692 -400.811238) (xy 370.535178 -400.783969) (xy 370.54294 -400.729985) (xy 370.558305 -400.677655)
			(xy 370.580962 -400.628045) (xy 370.610448 -400.582164) (xy 370.646163 -400.540947) (xy 370.68738 -400.505232)
			(xy 370.733261 -400.475746) (xy 370.782871 -400.453089) (xy 370.835201 -400.437724) (xy 370.889185 -400.429962)
			(xy 370.943723 -400.429962) (xy 370.997707 -400.437724) (xy 371.050037 -400.453089) (xy 371.099647 -400.475746)
			(xy 371.145528 -400.505232) (xy 371.186745 -400.540947) (xy 371.22246 -400.582164) (xy 371.251946 -400.628045)
			(xy 371.274603 -400.677655) (xy 371.289968 -400.729985) (xy 371.29773 -400.783969) (xy 371.298216 -400.811238)
			(xy 371.298216 -401.674838) (xy 371.734588 -401.674838) (xy 371.734588 -400.811238) (xy 371.735074 -400.783969)
			(xy 371.742836 -400.729985) (xy 371.758201 -400.677655) (xy 371.780858 -400.628045) (xy 371.810344 -400.582164)
			(xy 371.846059 -400.540947) (xy 371.887276 -400.505232) (xy 371.933157 -400.475746) (xy 371.982767 -400.453089)
			(xy 372.035097 -400.437724) (xy 372.089081 -400.429962) (xy 372.143619 -400.429962) (xy 372.197603 -400.437724)
			(xy 372.249933 -400.453089) (xy 372.299543 -400.475746) (xy 372.345424 -400.505232) (xy 372.386641 -400.540947)
			(xy 372.422356 -400.582164) (xy 372.451842 -400.628045) (xy 372.474499 -400.677655) (xy 372.489864 -400.729985)
			(xy 372.497626 -400.783969) (xy 372.498112 -400.811238) (xy 372.498112 -401.674838) (xy 372.934992 -401.674838)
			(xy 372.934992 -400.811238) (xy 372.935478 -400.783987) (xy 372.943234 -400.730039) (xy 372.958589 -400.677744)
			(xy 372.981231 -400.628167) (xy 373.010697 -400.582317) (xy 373.046388 -400.541126) (xy 373.087579 -400.505435)
			(xy 373.133429 -400.475969) (xy 373.183006 -400.453327) (xy 373.235301 -400.437972) (xy 373.289249 -400.430216)
			(xy 373.343751 -400.430216) (xy 373.397699 -400.437972) (xy 373.449994 -400.453327) (xy 373.499571 -400.475969)
			(xy 373.545421 -400.505435) (xy 373.586612 -400.541126) (xy 373.622303 -400.582317) (xy 373.651769 -400.628167)
			(xy 373.674411 -400.677744) (xy 373.689766 -400.730039) (xy 373.697522 -400.783987) (xy 373.698008 -400.811238)
			(xy 373.698008 -401.674838) (xy 374.134888 -401.674838) (xy 374.134888 -400.811238) (xy 374.135374 -400.783987)
			(xy 374.14313 -400.730039) (xy 374.158485 -400.677744) (xy 374.181127 -400.628167) (xy 374.210593 -400.582317)
			(xy 374.246284 -400.541126) (xy 374.287475 -400.505435) (xy 374.333325 -400.475969) (xy 374.382902 -400.453327)
			(xy 374.435197 -400.437972) (xy 374.489145 -400.430216) (xy 374.543647 -400.430216) (xy 374.597595 -400.437972)
			(xy 374.64989 -400.453327) (xy 374.699467 -400.475969) (xy 374.745317 -400.505435) (xy 374.786508 -400.541126)
			(xy 374.822199 -400.582317) (xy 374.851665 -400.628167) (xy 374.874307 -400.677744) (xy 374.889662 -400.730039)
			(xy 374.897418 -400.783987) (xy 374.897904 -400.811238) (xy 374.897904 -401.674838) (xy 375.334784 -401.674838)
			(xy 375.334784 -400.811238) (xy 375.33527 -400.783969) (xy 375.343032 -400.729985) (xy 375.358397 -400.677655)
			(xy 375.381054 -400.628045) (xy 375.41054 -400.582164) (xy 375.446255 -400.540947) (xy 375.487472 -400.505232)
			(xy 375.533353 -400.475746) (xy 375.582963 -400.453089) (xy 375.635293 -400.437724) (xy 375.689277 -400.429962)
			(xy 375.743815 -400.429962) (xy 375.797799 -400.437724) (xy 375.850129 -400.453089) (xy 375.899739 -400.475746)
			(xy 375.94562 -400.505232) (xy 375.986837 -400.540947) (xy 376.022552 -400.582164) (xy 376.052038 -400.628045)
			(xy 376.074695 -400.677655) (xy 376.09006 -400.729985) (xy 376.097822 -400.783969) (xy 376.098308 -400.811238)
			(xy 376.098308 -401.674838) (xy 376.53468 -401.674838) (xy 376.53468 -400.811238) (xy 376.535166 -400.783969)
			(xy 376.542928 -400.729985) (xy 376.558293 -400.677655) (xy 376.58095 -400.628045) (xy 376.610436 -400.582164)
			(xy 376.646151 -400.540947) (xy 376.687368 -400.505232) (xy 376.733249 -400.475746) (xy 376.782859 -400.453089)
			(xy 376.835189 -400.437724) (xy 376.889173 -400.429962) (xy 376.943711 -400.429962) (xy 376.997695 -400.437724)
			(xy 377.050025 -400.453089) (xy 377.099635 -400.475746) (xy 377.145516 -400.505232) (xy 377.186733 -400.540947)
			(xy 377.222448 -400.582164) (xy 377.251934 -400.628045) (xy 377.274591 -400.677655) (xy 377.289956 -400.729985)
			(xy 377.297718 -400.783969) (xy 377.298204 -400.811238) (xy 377.298204 -401.674838) (xy 377.735084 -401.674838)
			(xy 377.735084 -400.811238) (xy 377.73557 -400.783987) (xy 377.743326 -400.730039) (xy 377.758681 -400.677744)
			(xy 377.781323 -400.628167) (xy 377.810789 -400.582317) (xy 377.84648 -400.541126) (xy 377.887671 -400.505435)
			(xy 377.933521 -400.475969) (xy 377.983098 -400.453327) (xy 378.035393 -400.437972) (xy 378.089341 -400.430216)
			(xy 378.143843 -400.430216) (xy 378.197791 -400.437972) (xy 378.250086 -400.453327) (xy 378.299663 -400.475969)
			(xy 378.345513 -400.505435) (xy 378.386704 -400.541126) (xy 378.422395 -400.582317) (xy 378.451861 -400.628167)
			(xy 378.474503 -400.677744) (xy 378.489858 -400.730039) (xy 378.497614 -400.783987) (xy 378.4981 -400.811238)
			(xy 378.4981 -401.674838) (xy 378.93498 -401.674838) (xy 378.93498 -400.811238) (xy 378.935466 -400.783987)
			(xy 378.943222 -400.730039) (xy 378.958577 -400.677744) (xy 378.981219 -400.628167) (xy 379.010685 -400.582317)
			(xy 379.046376 -400.541126) (xy 379.087567 -400.505435) (xy 379.133417 -400.475969) (xy 379.182994 -400.453327)
			(xy 379.235289 -400.437972) (xy 379.289237 -400.430216) (xy 379.343739 -400.430216) (xy 379.397687 -400.437972)
			(xy 379.449982 -400.453327) (xy 379.499559 -400.475969) (xy 379.545409 -400.505435) (xy 379.5866 -400.541126)
			(xy 379.622291 -400.582317) (xy 379.651757 -400.628167) (xy 379.674399 -400.677744) (xy 379.689754 -400.730039)
			(xy 379.69751 -400.783987) (xy 379.697996 -400.811238) (xy 379.697996 -401.674838) (xy 380.134876 -401.674838)
			(xy 380.134876 -400.811238) (xy 380.135362 -400.783969) (xy 380.143124 -400.729985) (xy 380.158489 -400.677655)
			(xy 380.181146 -400.628045) (xy 380.210632 -400.582164) (xy 380.246347 -400.540947) (xy 380.287564 -400.505232)
			(xy 380.333445 -400.475746) (xy 380.383055 -400.453089) (xy 380.435385 -400.437724) (xy 380.489369 -400.429962)
			(xy 380.543907 -400.429962) (xy 380.597891 -400.437724) (xy 380.650221 -400.453089) (xy 380.699831 -400.475746)
			(xy 380.745712 -400.505232) (xy 380.786929 -400.540947) (xy 380.822644 -400.582164) (xy 380.85213 -400.628045)
			(xy 380.874787 -400.677655) (xy 380.890152 -400.729985) (xy 380.897914 -400.783969) (xy 380.8984 -400.811238)
			(xy 380.8984 -401.674838) (xy 381.334772 -401.674838) (xy 381.334772 -400.811238) (xy 381.335258 -400.783969)
			(xy 381.34302 -400.729985) (xy 381.358385 -400.677655) (xy 381.381042 -400.628045) (xy 381.410528 -400.582164)
			(xy 381.446243 -400.540947) (xy 381.48746 -400.505232) (xy 381.533341 -400.475746) (xy 381.582951 -400.453089)
			(xy 381.635281 -400.437724) (xy 381.689265 -400.429962) (xy 381.743803 -400.429962) (xy 381.797787 -400.437724)
			(xy 381.850117 -400.453089) (xy 381.899727 -400.475746) (xy 381.945608 -400.505232) (xy 381.986825 -400.540947)
			(xy 382.02254 -400.582164) (xy 382.052026 -400.628045) (xy 382.074683 -400.677655) (xy 382.090048 -400.729985)
			(xy 382.09781 -400.783969) (xy 382.098296 -400.811238) (xy 382.098296 -401.674838) (xy 382.535176 -401.674838)
			(xy 382.535176 -400.811238) (xy 382.535662 -400.783987) (xy 382.543418 -400.730039) (xy 382.558773 -400.677744)
			(xy 382.581415 -400.628167) (xy 382.610881 -400.582317) (xy 382.646572 -400.541126) (xy 382.687763 -400.505435)
			(xy 382.733613 -400.475969) (xy 382.78319 -400.453327) (xy 382.835485 -400.437972) (xy 382.889433 -400.430216)
			(xy 382.943935 -400.430216) (xy 382.997883 -400.437972) (xy 383.050178 -400.453327) (xy 383.099755 -400.475969)
			(xy 383.145605 -400.505435) (xy 383.186796 -400.541126) (xy 383.222487 -400.582317) (xy 383.251953 -400.628167)
			(xy 383.274595 -400.677744) (xy 383.28995 -400.730039) (xy 383.297706 -400.783987) (xy 383.298192 -400.811238)
			(xy 383.298192 -401.674838) (xy 383.735072 -401.674838) (xy 383.735072 -400.811238) (xy 383.735558 -400.783987)
			(xy 383.743314 -400.730039) (xy 383.758669 -400.677744) (xy 383.781311 -400.628167) (xy 383.810777 -400.582317)
			(xy 383.846468 -400.541126) (xy 383.887659 -400.505435) (xy 383.933509 -400.475969) (xy 383.983086 -400.453327)
			(xy 384.035381 -400.437972) (xy 384.089329 -400.430216) (xy 384.143831 -400.430216) (xy 384.197779 -400.437972)
			(xy 384.250074 -400.453327) (xy 384.299651 -400.475969) (xy 384.345501 -400.505435) (xy 384.386692 -400.541126)
			(xy 384.422383 -400.582317) (xy 384.451849 -400.628167) (xy 384.474491 -400.677744) (xy 384.489846 -400.730039)
			(xy 384.497602 -400.783987) (xy 384.498088 -400.811238) (xy 384.498088 -401.674838) (xy 384.934968 -401.674838)
			(xy 384.934968 -400.811238) (xy 384.935454 -400.783987) (xy 384.94321 -400.730039) (xy 384.958565 -400.677744)
			(xy 384.981207 -400.628167) (xy 385.010673 -400.582317) (xy 385.046364 -400.541126) (xy 385.087555 -400.505435)
			(xy 385.133405 -400.475969) (xy 385.182982 -400.453327) (xy 385.235277 -400.437972) (xy 385.289225 -400.430216)
			(xy 385.343727 -400.430216) (xy 385.397675 -400.437972) (xy 385.44997 -400.453327) (xy 385.499547 -400.475969)
			(xy 385.545397 -400.505435) (xy 385.586588 -400.541126) (xy 385.622279 -400.582317) (xy 385.651745 -400.628167)
			(xy 385.674387 -400.677744) (xy 385.689742 -400.730039) (xy 385.697498 -400.783987) (xy 385.697984 -400.811238)
			(xy 385.697984 -401.674838) (xy 386.134864 -401.674838) (xy 386.134864 -400.811238) (xy 386.13535 -400.783987)
			(xy 386.143106 -400.730039) (xy 386.158461 -400.677744) (xy 386.181103 -400.628167) (xy 386.210569 -400.582317)
			(xy 386.24626 -400.541126) (xy 386.287451 -400.505435) (xy 386.333301 -400.475969) (xy 386.382878 -400.453327)
			(xy 386.435173 -400.437972) (xy 386.489121 -400.430216) (xy 386.543623 -400.430216) (xy 386.597571 -400.437972)
			(xy 386.649866 -400.453327) (xy 386.699443 -400.475969) (xy 386.745293 -400.505435) (xy 386.786484 -400.541126)
			(xy 386.822175 -400.582317) (xy 386.851641 -400.628167) (xy 386.874283 -400.677744) (xy 386.889638 -400.730039)
			(xy 386.897394 -400.783987) (xy 386.89788 -400.811238) (xy 386.89788 -401.674838) (xy 387.33476 -401.674838)
			(xy 387.33476 -400.811238) (xy 387.335246 -400.783969) (xy 387.343008 -400.729985) (xy 387.358373 -400.677655)
			(xy 387.38103 -400.628045) (xy 387.410516 -400.582164) (xy 387.446231 -400.540947) (xy 387.487448 -400.505232)
			(xy 387.533329 -400.475746) (xy 387.582939 -400.453089) (xy 387.635269 -400.437724) (xy 387.689253 -400.429962)
			(xy 387.743791 -400.429962) (xy 387.797775 -400.437724) (xy 387.850105 -400.453089) (xy 387.899715 -400.475746)
			(xy 387.945596 -400.505232) (xy 387.986813 -400.540947) (xy 388.022528 -400.582164) (xy 388.052014 -400.628045)
			(xy 388.074671 -400.677655) (xy 388.090036 -400.729985) (xy 388.097798 -400.783969) (xy 388.098284 -400.811238)
			(xy 388.098284 -401.674838) (xy 388.534656 -401.674838) (xy 388.534656 -400.811238) (xy 388.535142 -400.783969)
			(xy 388.542904 -400.729985) (xy 388.558269 -400.677655) (xy 388.580926 -400.628045) (xy 388.610412 -400.582164)
			(xy 388.646127 -400.540947) (xy 388.687344 -400.505232) (xy 388.733225 -400.475746) (xy 388.782835 -400.453089)
			(xy 388.835165 -400.437724) (xy 388.889149 -400.429962) (xy 388.943687 -400.429962) (xy 388.997671 -400.437724)
			(xy 389.050001 -400.453089) (xy 389.099611 -400.475746) (xy 389.145492 -400.505232) (xy 389.186709 -400.540947)
			(xy 389.222424 -400.582164) (xy 389.25191 -400.628045) (xy 389.274567 -400.677655) (xy 389.289932 -400.729985)
			(xy 389.297694 -400.783969) (xy 389.29818 -400.811238) (xy 389.29818 -401.674838) (xy 403.06244 -401.674838)
			(xy 403.06244 -400.811238) (xy 403.062926 -400.783969) (xy 403.070688 -400.729985) (xy 403.086053 -400.677655)
			(xy 403.10871 -400.628045) (xy 403.138196 -400.582164) (xy 403.173911 -400.540947) (xy 403.215128 -400.505232)
			(xy 403.261009 -400.475746) (xy 403.310619 -400.453089) (xy 403.362949 -400.437724) (xy 403.416933 -400.429962)
			(xy 403.471471 -400.429962) (xy 403.525455 -400.437724) (xy 403.577785 -400.453089) (xy 403.627395 -400.475746)
			(xy 403.673276 -400.505232) (xy 403.714493 -400.540947) (xy 403.750208 -400.582164) (xy 403.779694 -400.628045)
			(xy 403.802351 -400.677655) (xy 403.817716 -400.729985) (xy 403.825478 -400.783969) (xy 403.825964 -400.811238)
			(xy 403.825964 -401.674838) (xy 404.262336 -401.674838) (xy 404.262336 -400.811238) (xy 404.262822 -400.783969)
			(xy 404.270584 -400.729985) (xy 404.285949 -400.677655) (xy 404.308606 -400.628045) (xy 404.338092 -400.582164)
			(xy 404.373807 -400.540947) (xy 404.415024 -400.505232) (xy 404.460905 -400.475746) (xy 404.510515 -400.453089)
			(xy 404.562845 -400.437724) (xy 404.616829 -400.429962) (xy 404.671367 -400.429962) (xy 404.725351 -400.437724)
			(xy 404.777681 -400.453089) (xy 404.827291 -400.475746) (xy 404.873172 -400.505232) (xy 404.914389 -400.540947)
			(xy 404.950104 -400.582164) (xy 404.97959 -400.628045) (xy 405.002247 -400.677655) (xy 405.017612 -400.729985)
			(xy 405.025374 -400.783969) (xy 405.02586 -400.811238) (xy 405.02586 -401.674838) (xy 405.46274 -401.674838)
			(xy 405.46274 -400.811238) (xy 405.463226 -400.783987) (xy 405.470982 -400.730039) (xy 405.486337 -400.677744)
			(xy 405.508979 -400.628167) (xy 405.538445 -400.582317) (xy 405.574136 -400.541126) (xy 405.615327 -400.505435)
			(xy 405.661177 -400.475969) (xy 405.710754 -400.453327) (xy 405.763049 -400.437972) (xy 405.816997 -400.430216)
			(xy 405.871499 -400.430216) (xy 405.925447 -400.437972) (xy 405.977742 -400.453327) (xy 406.027319 -400.475969)
			(xy 406.073169 -400.505435) (xy 406.11436 -400.541126) (xy 406.150051 -400.582317) (xy 406.179517 -400.628167)
			(xy 406.202159 -400.677744) (xy 406.217514 -400.730039) (xy 406.22527 -400.783987) (xy 406.225756 -400.811238)
			(xy 406.225756 -401.674838) (xy 406.662636 -401.674838) (xy 406.662636 -400.811238) (xy 406.663122 -400.783987)
			(xy 406.670878 -400.730039) (xy 406.686233 -400.677744) (xy 406.708875 -400.628167) (xy 406.738341 -400.582317)
			(xy 406.774032 -400.541126) (xy 406.815223 -400.505435) (xy 406.861073 -400.475969) (xy 406.91065 -400.453327)
			(xy 406.962945 -400.437972) (xy 407.016893 -400.430216) (xy 407.071395 -400.430216) (xy 407.125343 -400.437972)
			(xy 407.177638 -400.453327) (xy 407.227215 -400.475969) (xy 407.273065 -400.505435) (xy 407.314256 -400.541126)
			(xy 407.349947 -400.582317) (xy 407.379413 -400.628167) (xy 407.402055 -400.677744) (xy 407.41741 -400.730039)
			(xy 407.425166 -400.783987) (xy 407.425652 -400.811238) (xy 407.425652 -401.674838) (xy 407.862532 -401.674838)
			(xy 407.862532 -400.811238) (xy 407.863018 -400.783969) (xy 407.87078 -400.729985) (xy 407.886145 -400.677655)
			(xy 407.908802 -400.628045) (xy 407.938288 -400.582164) (xy 407.974003 -400.540947) (xy 408.01522 -400.505232)
			(xy 408.061101 -400.475746) (xy 408.110711 -400.453089) (xy 408.163041 -400.437724) (xy 408.217025 -400.429962)
			(xy 408.271563 -400.429962) (xy 408.325547 -400.437724) (xy 408.377877 -400.453089) (xy 408.427487 -400.475746)
			(xy 408.473368 -400.505232) (xy 408.514585 -400.540947) (xy 408.5503 -400.582164) (xy 408.579786 -400.628045)
			(xy 408.602443 -400.677655) (xy 408.617808 -400.729985) (xy 408.62557 -400.783969) (xy 408.626056 -400.811238)
			(xy 408.626056 -401.674838) (xy 409.062428 -401.674838) (xy 409.062428 -400.811238) (xy 409.062914 -400.783969)
			(xy 409.070676 -400.729985) (xy 409.086041 -400.677655) (xy 409.108698 -400.628045) (xy 409.138184 -400.582164)
			(xy 409.173899 -400.540947) (xy 409.215116 -400.505232) (xy 409.260997 -400.475746) (xy 409.310607 -400.453089)
			(xy 409.362937 -400.437724) (xy 409.416921 -400.429962) (xy 409.471459 -400.429962) (xy 409.525443 -400.437724)
			(xy 409.577773 -400.453089) (xy 409.627383 -400.475746) (xy 409.673264 -400.505232) (xy 409.714481 -400.540947)
			(xy 409.750196 -400.582164) (xy 409.779682 -400.628045) (xy 409.802339 -400.677655) (xy 409.817704 -400.729985)
			(xy 409.825466 -400.783969) (xy 409.825952 -400.811238) (xy 409.825952 -401.674838) (xy 410.262832 -401.674838)
			(xy 410.262832 -400.811238) (xy 410.263318 -400.783987) (xy 410.271074 -400.730039) (xy 410.286429 -400.677744)
			(xy 410.309071 -400.628167) (xy 410.338537 -400.582317) (xy 410.374228 -400.541126) (xy 410.415419 -400.505435)
			(xy 410.461269 -400.475969) (xy 410.510846 -400.453327) (xy 410.563141 -400.437972) (xy 410.617089 -400.430216)
			(xy 410.671591 -400.430216) (xy 410.725539 -400.437972) (xy 410.777834 -400.453327) (xy 410.827411 -400.475969)
			(xy 410.873261 -400.505435) (xy 410.914452 -400.541126) (xy 410.950143 -400.582317) (xy 410.979609 -400.628167)
			(xy 411.002251 -400.677744) (xy 411.017606 -400.730039) (xy 411.025362 -400.783987) (xy 411.025848 -400.811238)
			(xy 411.025848 -401.674838) (xy 411.462728 -401.674838) (xy 411.462728 -400.811238) (xy 411.463214 -400.783987)
			(xy 411.47097 -400.730039) (xy 411.486325 -400.677744) (xy 411.508967 -400.628167) (xy 411.538433 -400.582317)
			(xy 411.574124 -400.541126) (xy 411.615315 -400.505435) (xy 411.661165 -400.475969) (xy 411.710742 -400.453327)
			(xy 411.763037 -400.437972) (xy 411.816985 -400.430216) (xy 411.871487 -400.430216) (xy 411.925435 -400.437972)
			(xy 411.97773 -400.453327) (xy 412.027307 -400.475969) (xy 412.073157 -400.505435) (xy 412.114348 -400.541126)
			(xy 412.150039 -400.582317) (xy 412.179505 -400.628167) (xy 412.202147 -400.677744) (xy 412.217502 -400.730039)
			(xy 412.225258 -400.783987) (xy 412.225744 -400.811238) (xy 412.225744 -401.674838) (xy 412.662624 -401.674838)
			(xy 412.662624 -400.811238) (xy 412.66311 -400.783969) (xy 412.670872 -400.729985) (xy 412.686237 -400.677655)
			(xy 412.708894 -400.628045) (xy 412.73838 -400.582164) (xy 412.774095 -400.540947) (xy 412.815312 -400.505232)
			(xy 412.861193 -400.475746) (xy 412.910803 -400.453089) (xy 412.963133 -400.437724) (xy 413.017117 -400.429962)
			(xy 413.071655 -400.429962) (xy 413.125639 -400.437724) (xy 413.177969 -400.453089) (xy 413.227579 -400.475746)
			(xy 413.27346 -400.505232) (xy 413.314677 -400.540947) (xy 413.350392 -400.582164) (xy 413.379878 -400.628045)
			(xy 413.402535 -400.677655) (xy 413.4179 -400.729985) (xy 413.425662 -400.783969) (xy 413.426148 -400.811238)
			(xy 413.426148 -401.674838) (xy 413.86252 -401.674838) (xy 413.86252 -400.811238) (xy 413.863006 -400.783969)
			(xy 413.870768 -400.729985) (xy 413.886133 -400.677655) (xy 413.90879 -400.628045) (xy 413.938276 -400.582164)
			(xy 413.973991 -400.540947) (xy 414.015208 -400.505232) (xy 414.061089 -400.475746) (xy 414.110699 -400.453089)
			(xy 414.163029 -400.437724) (xy 414.217013 -400.429962) (xy 414.271551 -400.429962) (xy 414.325535 -400.437724)
			(xy 414.377865 -400.453089) (xy 414.427475 -400.475746) (xy 414.473356 -400.505232) (xy 414.514573 -400.540947)
			(xy 414.550288 -400.582164) (xy 414.579774 -400.628045) (xy 414.602431 -400.677655) (xy 414.617796 -400.729985)
			(xy 414.625558 -400.783969) (xy 414.626044 -400.811238) (xy 414.626044 -401.674838) (xy 415.062924 -401.674838)
			(xy 415.062924 -400.811238) (xy 415.06341 -400.783987) (xy 415.071166 -400.730039) (xy 415.086521 -400.677744)
			(xy 415.109163 -400.628167) (xy 415.138629 -400.582317) (xy 415.17432 -400.541126) (xy 415.215511 -400.505435)
			(xy 415.261361 -400.475969) (xy 415.310938 -400.453327) (xy 415.363233 -400.437972) (xy 415.417181 -400.430216)
			(xy 415.471683 -400.430216) (xy 415.525631 -400.437972) (xy 415.577926 -400.453327) (xy 415.627503 -400.475969)
			(xy 415.673353 -400.505435) (xy 415.714544 -400.541126) (xy 415.750235 -400.582317) (xy 415.779701 -400.628167)
			(xy 415.802343 -400.677744) (xy 415.817698 -400.730039) (xy 415.825454 -400.783987) (xy 415.82594 -400.811238)
			(xy 415.82594 -401.674838) (xy 416.26282 -401.674838) (xy 416.26282 -400.811238) (xy 416.263306 -400.783987)
			(xy 416.271062 -400.730039) (xy 416.286417 -400.677744) (xy 416.309059 -400.628167) (xy 416.338525 -400.582317)
			(xy 416.374216 -400.541126) (xy 416.415407 -400.505435) (xy 416.461257 -400.475969) (xy 416.510834 -400.453327)
			(xy 416.563129 -400.437972) (xy 416.617077 -400.430216) (xy 416.671579 -400.430216) (xy 416.725527 -400.437972)
			(xy 416.777822 -400.453327) (xy 416.827399 -400.475969) (xy 416.873249 -400.505435) (xy 416.91444 -400.541126)
			(xy 416.950131 -400.582317) (xy 416.979597 -400.628167) (xy 417.002239 -400.677744) (xy 417.017594 -400.730039)
			(xy 417.02535 -400.783987) (xy 417.025836 -400.811238) (xy 417.025836 -401.674838) (xy 417.462716 -401.674838)
			(xy 417.462716 -400.811238) (xy 417.463202 -400.783987) (xy 417.470958 -400.730039) (xy 417.486313 -400.677744)
			(xy 417.508955 -400.628167) (xy 417.538421 -400.582317) (xy 417.574112 -400.541126) (xy 417.615303 -400.505435)
			(xy 417.661153 -400.475969) (xy 417.71073 -400.453327) (xy 417.763025 -400.437972) (xy 417.816973 -400.430216)
			(xy 417.871475 -400.430216) (xy 417.925423 -400.437972) (xy 417.977718 -400.453327) (xy 418.027295 -400.475969)
			(xy 418.073145 -400.505435) (xy 418.114336 -400.541126) (xy 418.150027 -400.582317) (xy 418.179493 -400.628167)
			(xy 418.202135 -400.677744) (xy 418.21749 -400.730039) (xy 418.225246 -400.783987) (xy 418.225732 -400.811238)
			(xy 418.225732 -401.674838) (xy 418.662612 -401.674838) (xy 418.662612 -400.811238) (xy 418.663098 -400.783987)
			(xy 418.670854 -400.730039) (xy 418.686209 -400.677744) (xy 418.708851 -400.628167) (xy 418.738317 -400.582317)
			(xy 418.774008 -400.541126) (xy 418.815199 -400.505435) (xy 418.861049 -400.475969) (xy 418.910626 -400.453327)
			(xy 418.962921 -400.437972) (xy 419.016869 -400.430216) (xy 419.071371 -400.430216) (xy 419.125319 -400.437972)
			(xy 419.177614 -400.453327) (xy 419.227191 -400.475969) (xy 419.273041 -400.505435) (xy 419.314232 -400.541126)
			(xy 419.349923 -400.582317) (xy 419.379389 -400.628167) (xy 419.402031 -400.677744) (xy 419.417386 -400.730039)
			(xy 419.425142 -400.783987) (xy 419.425628 -400.811238) (xy 419.425628 -401.674838) (xy 419.862508 -401.674838)
			(xy 419.862508 -400.811238) (xy 419.862994 -400.783969) (xy 419.870756 -400.729985) (xy 419.886121 -400.677655)
			(xy 419.908778 -400.628045) (xy 419.938264 -400.582164) (xy 419.973979 -400.540947) (xy 420.015196 -400.505232)
			(xy 420.061077 -400.475746) (xy 420.110687 -400.453089) (xy 420.163017 -400.437724) (xy 420.217001 -400.429962)
			(xy 420.271539 -400.429962) (xy 420.325523 -400.437724) (xy 420.377853 -400.453089) (xy 420.427463 -400.475746)
			(xy 420.473344 -400.505232) (xy 420.514561 -400.540947) (xy 420.550276 -400.582164) (xy 420.579762 -400.628045)
			(xy 420.602419 -400.677655) (xy 420.617784 -400.729985) (xy 420.625546 -400.783969) (xy 420.626032 -400.811238)
			(xy 420.626032 -401.674838) (xy 421.062404 -401.674838) (xy 421.062404 -400.811238) (xy 421.06289 -400.783969)
			(xy 421.070652 -400.729985) (xy 421.086017 -400.677655) (xy 421.108674 -400.628045) (xy 421.13816 -400.582164)
			(xy 421.173875 -400.540947) (xy 421.215092 -400.505232) (xy 421.260973 -400.475746) (xy 421.310583 -400.453089)
			(xy 421.362913 -400.437724) (xy 421.416897 -400.429962) (xy 421.471435 -400.429962) (xy 421.525419 -400.437724)
			(xy 421.577749 -400.453089) (xy 421.627359 -400.475746) (xy 421.67324 -400.505232) (xy 421.714457 -400.540947)
			(xy 421.750172 -400.582164) (xy 421.779658 -400.628045) (xy 421.802315 -400.677655) (xy 421.81768 -400.729985)
			(xy 421.825442 -400.783969) (xy 421.825928 -400.811238) (xy 421.825928 -401.674838) (xy 421.825442 -401.702107)
			(xy 421.81768 -401.756091) (xy 421.802315 -401.808421) (xy 421.779658 -401.858031) (xy 421.750172 -401.903912)
			(xy 421.714457 -401.945129) (xy 421.67324 -401.980844) (xy 421.627359 -402.01033) (xy 421.577749 -402.032987)
			(xy 421.525419 -402.048352) (xy 421.471435 -402.056114) (xy 421.416897 -402.056114) (xy 421.362913 -402.048352)
			(xy 421.310583 -402.032987) (xy 421.260973 -402.01033) (xy 421.215092 -401.980844) (xy 421.173875 -401.945129)
			(xy 421.13816 -401.903912) (xy 421.108674 -401.858031) (xy 421.086017 -401.808421) (xy 421.070652 -401.756091)
			(xy 421.06289 -401.702107) (xy 421.062404 -401.674838) (xy 420.626032 -401.674838) (xy 420.625546 -401.702107)
			(xy 420.617784 -401.756091) (xy 420.602419 -401.808421) (xy 420.579762 -401.858031) (xy 420.550276 -401.903912)
			(xy 420.514561 -401.945129) (xy 420.473344 -401.980844) (xy 420.427463 -402.01033) (xy 420.377853 -402.032987)
			(xy 420.325523 -402.048352) (xy 420.271539 -402.056114) (xy 420.217001 -402.056114) (xy 420.163017 -402.048352)
			(xy 420.110687 -402.032987) (xy 420.061077 -402.01033) (xy 420.015196 -401.980844) (xy 419.973979 -401.945129)
			(xy 419.938264 -401.903912) (xy 419.908778 -401.858031) (xy 419.886121 -401.808421) (xy 419.870756 -401.756091)
			(xy 419.862994 -401.702107) (xy 419.862508 -401.674838) (xy 419.425628 -401.674838) (xy 419.425142 -401.702089)
			(xy 419.417386 -401.756037) (xy 419.402031 -401.808332) (xy 419.379389 -401.857909) (xy 419.349923 -401.903759)
			(xy 419.314232 -401.94495) (xy 419.273041 -401.980641) (xy 419.227191 -402.010107) (xy 419.177614 -402.032749)
			(xy 419.125319 -402.048104) (xy 419.071371 -402.05586) (xy 419.016869 -402.05586) (xy 418.962921 -402.048104)
			(xy 418.910626 -402.032749) (xy 418.861049 -402.010107) (xy 418.815199 -401.980641) (xy 418.774008 -401.94495)
			(xy 418.738317 -401.903759) (xy 418.708851 -401.857909) (xy 418.686209 -401.808332) (xy 418.670854 -401.756037)
			(xy 418.663098 -401.702089) (xy 418.662612 -401.674838) (xy 418.225732 -401.674838) (xy 418.225246 -401.702089)
			(xy 418.21749 -401.756037) (xy 418.202135 -401.808332) (xy 418.179493 -401.857909) (xy 418.150027 -401.903759)
			(xy 418.114336 -401.94495) (xy 418.073145 -401.980641) (xy 418.027295 -402.010107) (xy 417.977718 -402.032749)
			(xy 417.925423 -402.048104) (xy 417.871475 -402.05586) (xy 417.816973 -402.05586) (xy 417.763025 -402.048104)
			(xy 417.71073 -402.032749) (xy 417.661153 -402.010107) (xy 417.615303 -401.980641) (xy 417.574112 -401.94495)
			(xy 417.538421 -401.903759) (xy 417.508955 -401.857909) (xy 417.486313 -401.808332) (xy 417.470958 -401.756037)
			(xy 417.463202 -401.702089) (xy 417.462716 -401.674838) (xy 417.025836 -401.674838) (xy 417.02535 -401.702089)
			(xy 417.017594 -401.756037) (xy 417.002239 -401.808332) (xy 416.979597 -401.857909) (xy 416.950131 -401.903759)
			(xy 416.91444 -401.94495) (xy 416.873249 -401.980641) (xy 416.827399 -402.010107) (xy 416.777822 -402.032749)
			(xy 416.725527 -402.048104) (xy 416.671579 -402.05586) (xy 416.617077 -402.05586) (xy 416.563129 -402.048104)
			(xy 416.510834 -402.032749) (xy 416.461257 -402.010107) (xy 416.415407 -401.980641) (xy 416.374216 -401.94495)
			(xy 416.338525 -401.903759) (xy 416.309059 -401.857909) (xy 416.286417 -401.808332) (xy 416.271062 -401.756037)
			(xy 416.263306 -401.702089) (xy 416.26282 -401.674838) (xy 415.82594 -401.674838) (xy 415.825454 -401.702089)
			(xy 415.817698 -401.756037) (xy 415.802343 -401.808332) (xy 415.779701 -401.857909) (xy 415.750235 -401.903759)
			(xy 415.714544 -401.94495) (xy 415.673353 -401.980641) (xy 415.627503 -402.010107) (xy 415.577926 -402.032749)
			(xy 415.525631 -402.048104) (xy 415.471683 -402.05586) (xy 415.417181 -402.05586) (xy 415.363233 -402.048104)
			(xy 415.310938 -402.032749) (xy 415.261361 -402.010107) (xy 415.215511 -401.980641) (xy 415.17432 -401.94495)
			(xy 415.138629 -401.903759) (xy 415.109163 -401.857909) (xy 415.086521 -401.808332) (xy 415.071166 -401.756037)
			(xy 415.06341 -401.702089) (xy 415.062924 -401.674838) (xy 414.626044 -401.674838) (xy 414.625558 -401.702107)
			(xy 414.617796 -401.756091) (xy 414.602431 -401.808421) (xy 414.579774 -401.858031) (xy 414.550288 -401.903912)
			(xy 414.514573 -401.945129) (xy 414.473356 -401.980844) (xy 414.427475 -402.01033) (xy 414.377865 -402.032987)
			(xy 414.325535 -402.048352) (xy 414.271551 -402.056114) (xy 414.217013 -402.056114) (xy 414.163029 -402.048352)
			(xy 414.110699 -402.032987) (xy 414.061089 -402.01033) (xy 414.015208 -401.980844) (xy 413.973991 -401.945129)
			(xy 413.938276 -401.903912) (xy 413.90879 -401.858031) (xy 413.886133 -401.808421) (xy 413.870768 -401.756091)
			(xy 413.863006 -401.702107) (xy 413.86252 -401.674838) (xy 413.426148 -401.674838) (xy 413.425662 -401.702107)
			(xy 413.4179 -401.756091) (xy 413.402535 -401.808421) (xy 413.379878 -401.858031) (xy 413.350392 -401.903912)
			(xy 413.314677 -401.945129) (xy 413.27346 -401.980844) (xy 413.227579 -402.01033) (xy 413.177969 -402.032987)
			(xy 413.125639 -402.048352) (xy 413.071655 -402.056114) (xy 413.017117 -402.056114) (xy 412.963133 -402.048352)
			(xy 412.910803 -402.032987) (xy 412.861193 -402.01033) (xy 412.815312 -401.980844) (xy 412.774095 -401.945129)
			(xy 412.73838 -401.903912) (xy 412.708894 -401.858031) (xy 412.686237 -401.808421) (xy 412.670872 -401.756091)
			(xy 412.66311 -401.702107) (xy 412.662624 -401.674838) (xy 412.225744 -401.674838) (xy 412.225258 -401.702089)
			(xy 412.217502 -401.756037) (xy 412.202147 -401.808332) (xy 412.179505 -401.857909) (xy 412.150039 -401.903759)
			(xy 412.114348 -401.94495) (xy 412.073157 -401.980641) (xy 412.027307 -402.010107) (xy 411.97773 -402.032749)
			(xy 411.925435 -402.048104) (xy 411.871487 -402.05586) (xy 411.816985 -402.05586) (xy 411.763037 -402.048104)
			(xy 411.710742 -402.032749) (xy 411.661165 -402.010107) (xy 411.615315 -401.980641) (xy 411.574124 -401.94495)
			(xy 411.538433 -401.903759) (xy 411.508967 -401.857909) (xy 411.486325 -401.808332) (xy 411.47097 -401.756037)
			(xy 411.463214 -401.702089) (xy 411.462728 -401.674838) (xy 411.025848 -401.674838) (xy 411.025362 -401.702089)
			(xy 411.017606 -401.756037) (xy 411.002251 -401.808332) (xy 410.979609 -401.857909) (xy 410.950143 -401.903759)
			(xy 410.914452 -401.94495) (xy 410.873261 -401.980641) (xy 410.827411 -402.010107) (xy 410.777834 -402.032749)
			(xy 410.725539 -402.048104) (xy 410.671591 -402.05586) (xy 410.617089 -402.05586) (xy 410.563141 -402.048104)
			(xy 410.510846 -402.032749) (xy 410.461269 -402.010107) (xy 410.415419 -401.980641) (xy 410.374228 -401.94495)
			(xy 410.338537 -401.903759) (xy 410.309071 -401.857909) (xy 410.286429 -401.808332) (xy 410.271074 -401.756037)
			(xy 410.263318 -401.702089) (xy 410.262832 -401.674838) (xy 409.825952 -401.674838) (xy 409.825466 -401.702107)
			(xy 409.817704 -401.756091) (xy 409.802339 -401.808421) (xy 409.779682 -401.858031) (xy 409.750196 -401.903912)
			(xy 409.714481 -401.945129) (xy 409.673264 -401.980844) (xy 409.627383 -402.01033) (xy 409.577773 -402.032987)
			(xy 409.525443 -402.048352) (xy 409.471459 -402.056114) (xy 409.416921 -402.056114) (xy 409.362937 -402.048352)
			(xy 409.310607 -402.032987) (xy 409.260997 -402.01033) (xy 409.215116 -401.980844) (xy 409.173899 -401.945129)
			(xy 409.138184 -401.903912) (xy 409.108698 -401.858031) (xy 409.086041 -401.808421) (xy 409.070676 -401.756091)
			(xy 409.062914 -401.702107) (xy 409.062428 -401.674838) (xy 408.626056 -401.674838) (xy 408.62557 -401.702107)
			(xy 408.617808 -401.756091) (xy 408.602443 -401.808421) (xy 408.579786 -401.858031) (xy 408.5503 -401.903912)
			(xy 408.514585 -401.945129) (xy 408.473368 -401.980844) (xy 408.427487 -402.01033) (xy 408.377877 -402.032987)
			(xy 408.325547 -402.048352) (xy 408.271563 -402.056114) (xy 408.217025 -402.056114) (xy 408.163041 -402.048352)
			(xy 408.110711 -402.032987) (xy 408.061101 -402.01033) (xy 408.01522 -401.980844) (xy 407.974003 -401.945129)
			(xy 407.938288 -401.903912) (xy 407.908802 -401.858031) (xy 407.886145 -401.808421) (xy 407.87078 -401.756091)
			(xy 407.863018 -401.702107) (xy 407.862532 -401.674838) (xy 407.425652 -401.674838) (xy 407.425166 -401.702089)
			(xy 407.41741 -401.756037) (xy 407.402055 -401.808332) (xy 407.379413 -401.857909) (xy 407.349947 -401.903759)
			(xy 407.314256 -401.94495) (xy 407.273065 -401.980641) (xy 407.227215 -402.010107) (xy 407.177638 -402.032749)
			(xy 407.125343 -402.048104) (xy 407.071395 -402.05586) (xy 407.016893 -402.05586) (xy 406.962945 -402.048104)
			(xy 406.91065 -402.032749) (xy 406.861073 -402.010107) (xy 406.815223 -401.980641) (xy 406.774032 -401.94495)
			(xy 406.738341 -401.903759) (xy 406.708875 -401.857909) (xy 406.686233 -401.808332) (xy 406.670878 -401.756037)
			(xy 406.663122 -401.702089) (xy 406.662636 -401.674838) (xy 406.225756 -401.674838) (xy 406.22527 -401.702089)
			(xy 406.217514 -401.756037) (xy 406.202159 -401.808332) (xy 406.179517 -401.857909) (xy 406.150051 -401.903759)
			(xy 406.11436 -401.94495) (xy 406.073169 -401.980641) (xy 406.027319 -402.010107) (xy 405.977742 -402.032749)
			(xy 405.925447 -402.048104) (xy 405.871499 -402.05586) (xy 405.816997 -402.05586) (xy 405.763049 -402.048104)
			(xy 405.710754 -402.032749) (xy 405.661177 -402.010107) (xy 405.615327 -401.980641) (xy 405.574136 -401.94495)
			(xy 405.538445 -401.903759) (xy 405.508979 -401.857909) (xy 405.486337 -401.808332) (xy 405.470982 -401.756037)
			(xy 405.463226 -401.702089) (xy 405.46274 -401.674838) (xy 405.02586 -401.674838) (xy 405.025374 -401.702107)
			(xy 405.017612 -401.756091) (xy 405.002247 -401.808421) (xy 404.97959 -401.858031) (xy 404.950104 -401.903912)
			(xy 404.914389 -401.945129) (xy 404.873172 -401.980844) (xy 404.827291 -402.01033) (xy 404.777681 -402.032987)
			(xy 404.725351 -402.048352) (xy 404.671367 -402.056114) (xy 404.616829 -402.056114) (xy 404.562845 -402.048352)
			(xy 404.510515 -402.032987) (xy 404.460905 -402.01033) (xy 404.415024 -401.980844) (xy 404.373807 -401.945129)
			(xy 404.338092 -401.903912) (xy 404.308606 -401.858031) (xy 404.285949 -401.808421) (xy 404.270584 -401.756091)
			(xy 404.262822 -401.702107) (xy 404.262336 -401.674838) (xy 403.825964 -401.674838) (xy 403.825478 -401.702107)
			(xy 403.817716 -401.756091) (xy 403.802351 -401.808421) (xy 403.779694 -401.858031) (xy 403.750208 -401.903912)
			(xy 403.714493 -401.945129) (xy 403.673276 -401.980844) (xy 403.627395 -402.01033) (xy 403.577785 -402.032987)
			(xy 403.525455 -402.048352) (xy 403.471471 -402.056114) (xy 403.416933 -402.056114) (xy 403.362949 -402.048352)
			(xy 403.310619 -402.032987) (xy 403.261009 -402.01033) (xy 403.215128 -401.980844) (xy 403.173911 -401.945129)
			(xy 403.138196 -401.903912) (xy 403.10871 -401.858031) (xy 403.086053 -401.808421) (xy 403.070688 -401.756091)
			(xy 403.062926 -401.702107) (xy 403.06244 -401.674838) (xy 389.29818 -401.674838) (xy 389.297694 -401.702107)
			(xy 389.289932 -401.756091) (xy 389.274567 -401.808421) (xy 389.25191 -401.858031) (xy 389.222424 -401.903912)
			(xy 389.186709 -401.945129) (xy 389.145492 -401.980844) (xy 389.099611 -402.01033) (xy 389.050001 -402.032987)
			(xy 388.997671 -402.048352) (xy 388.943687 -402.056114) (xy 388.889149 -402.056114) (xy 388.835165 -402.048352)
			(xy 388.782835 -402.032987) (xy 388.733225 -402.01033) (xy 388.687344 -401.980844) (xy 388.646127 -401.945129)
			(xy 388.610412 -401.903912) (xy 388.580926 -401.858031) (xy 388.558269 -401.808421) (xy 388.542904 -401.756091)
			(xy 388.535142 -401.702107) (xy 388.534656 -401.674838) (xy 388.098284 -401.674838) (xy 388.097798 -401.702107)
			(xy 388.090036 -401.756091) (xy 388.074671 -401.808421) (xy 388.052014 -401.858031) (xy 388.022528 -401.903912)
			(xy 387.986813 -401.945129) (xy 387.945596 -401.980844) (xy 387.899715 -402.01033) (xy 387.850105 -402.032987)
			(xy 387.797775 -402.048352) (xy 387.743791 -402.056114) (xy 387.689253 -402.056114) (xy 387.635269 -402.048352)
			(xy 387.582939 -402.032987) (xy 387.533329 -402.01033) (xy 387.487448 -401.980844) (xy 387.446231 -401.945129)
			(xy 387.410516 -401.903912) (xy 387.38103 -401.858031) (xy 387.358373 -401.808421) (xy 387.343008 -401.756091)
			(xy 387.335246 -401.702107) (xy 387.33476 -401.674838) (xy 386.89788 -401.674838) (xy 386.897394 -401.702089)
			(xy 386.889638 -401.756037) (xy 386.874283 -401.808332) (xy 386.851641 -401.857909) (xy 386.822175 -401.903759)
			(xy 386.786484 -401.94495) (xy 386.745293 -401.980641) (xy 386.699443 -402.010107) (xy 386.649866 -402.032749)
			(xy 386.597571 -402.048104) (xy 386.543623 -402.05586) (xy 386.489121 -402.05586) (xy 386.435173 -402.048104)
			(xy 386.382878 -402.032749) (xy 386.333301 -402.010107) (xy 386.287451 -401.980641) (xy 386.24626 -401.94495)
			(xy 386.210569 -401.903759) (xy 386.181103 -401.857909) (xy 386.158461 -401.808332) (xy 386.143106 -401.756037)
			(xy 386.13535 -401.702089) (xy 386.134864 -401.674838) (xy 385.697984 -401.674838) (xy 385.697498 -401.702089)
			(xy 385.689742 -401.756037) (xy 385.674387 -401.808332) (xy 385.651745 -401.857909) (xy 385.622279 -401.903759)
			(xy 385.586588 -401.94495) (xy 385.545397 -401.980641) (xy 385.499547 -402.010107) (xy 385.44997 -402.032749)
			(xy 385.397675 -402.048104) (xy 385.343727 -402.05586) (xy 385.289225 -402.05586) (xy 385.235277 -402.048104)
			(xy 385.182982 -402.032749) (xy 385.133405 -402.010107) (xy 385.087555 -401.980641) (xy 385.046364 -401.94495)
			(xy 385.010673 -401.903759) (xy 384.981207 -401.857909) (xy 384.958565 -401.808332) (xy 384.94321 -401.756037)
			(xy 384.935454 -401.702089) (xy 384.934968 -401.674838) (xy 384.498088 -401.674838) (xy 384.497602 -401.702089)
			(xy 384.489846 -401.756037) (xy 384.474491 -401.808332) (xy 384.451849 -401.857909) (xy 384.422383 -401.903759)
			(xy 384.386692 -401.94495) (xy 384.345501 -401.980641) (xy 384.299651 -402.010107) (xy 384.250074 -402.032749)
			(xy 384.197779 -402.048104) (xy 384.143831 -402.05586) (xy 384.089329 -402.05586) (xy 384.035381 -402.048104)
			(xy 383.983086 -402.032749) (xy 383.933509 -402.010107) (xy 383.887659 -401.980641) (xy 383.846468 -401.94495)
			(xy 383.810777 -401.903759) (xy 383.781311 -401.857909) (xy 383.758669 -401.808332) (xy 383.743314 -401.756037)
			(xy 383.735558 -401.702089) (xy 383.735072 -401.674838) (xy 383.298192 -401.674838) (xy 383.297706 -401.702089)
			(xy 383.28995 -401.756037) (xy 383.274595 -401.808332) (xy 383.251953 -401.857909) (xy 383.222487 -401.903759)
			(xy 383.186796 -401.94495) (xy 383.145605 -401.980641) (xy 383.099755 -402.010107) (xy 383.050178 -402.032749)
			(xy 382.997883 -402.048104) (xy 382.943935 -402.05586) (xy 382.889433 -402.05586) (xy 382.835485 -402.048104)
			(xy 382.78319 -402.032749) (xy 382.733613 -402.010107) (xy 382.687763 -401.980641) (xy 382.646572 -401.94495)
			(xy 382.610881 -401.903759) (xy 382.581415 -401.857909) (xy 382.558773 -401.808332) (xy 382.543418 -401.756037)
			(xy 382.535662 -401.702089) (xy 382.535176 -401.674838) (xy 382.098296 -401.674838) (xy 382.09781 -401.702107)
			(xy 382.090048 -401.756091) (xy 382.074683 -401.808421) (xy 382.052026 -401.858031) (xy 382.02254 -401.903912)
			(xy 381.986825 -401.945129) (xy 381.945608 -401.980844) (xy 381.899727 -402.01033) (xy 381.850117 -402.032987)
			(xy 381.797787 -402.048352) (xy 381.743803 -402.056114) (xy 381.689265 -402.056114) (xy 381.635281 -402.048352)
			(xy 381.582951 -402.032987) (xy 381.533341 -402.01033) (xy 381.48746 -401.980844) (xy 381.446243 -401.945129)
			(xy 381.410528 -401.903912) (xy 381.381042 -401.858031) (xy 381.358385 -401.808421) (xy 381.34302 -401.756091)
			(xy 381.335258 -401.702107) (xy 381.334772 -401.674838) (xy 380.8984 -401.674838) (xy 380.897914 -401.702107)
			(xy 380.890152 -401.756091) (xy 380.874787 -401.808421) (xy 380.85213 -401.858031) (xy 380.822644 -401.903912)
			(xy 380.786929 -401.945129) (xy 380.745712 -401.980844) (xy 380.699831 -402.01033) (xy 380.650221 -402.032987)
			(xy 380.597891 -402.048352) (xy 380.543907 -402.056114) (xy 380.489369 -402.056114) (xy 380.435385 -402.048352)
			(xy 380.383055 -402.032987) (xy 380.333445 -402.01033) (xy 380.287564 -401.980844) (xy 380.246347 -401.945129)
			(xy 380.210632 -401.903912) (xy 380.181146 -401.858031) (xy 380.158489 -401.808421) (xy 380.143124 -401.756091)
			(xy 380.135362 -401.702107) (xy 380.134876 -401.674838) (xy 379.697996 -401.674838) (xy 379.69751 -401.702089)
			(xy 379.689754 -401.756037) (xy 379.674399 -401.808332) (xy 379.651757 -401.857909) (xy 379.622291 -401.903759)
			(xy 379.5866 -401.94495) (xy 379.545409 -401.980641) (xy 379.499559 -402.010107) (xy 379.449982 -402.032749)
			(xy 379.397687 -402.048104) (xy 379.343739 -402.05586) (xy 379.289237 -402.05586) (xy 379.235289 -402.048104)
			(xy 379.182994 -402.032749) (xy 379.133417 -402.010107) (xy 379.087567 -401.980641) (xy 379.046376 -401.94495)
			(xy 379.010685 -401.903759) (xy 378.981219 -401.857909) (xy 378.958577 -401.808332) (xy 378.943222 -401.756037)
			(xy 378.935466 -401.702089) (xy 378.93498 -401.674838) (xy 378.4981 -401.674838) (xy 378.497614 -401.702089)
			(xy 378.489858 -401.756037) (xy 378.474503 -401.808332) (xy 378.451861 -401.857909) (xy 378.422395 -401.903759)
			(xy 378.386704 -401.94495) (xy 378.345513 -401.980641) (xy 378.299663 -402.010107) (xy 378.250086 -402.032749)
			(xy 378.197791 -402.048104) (xy 378.143843 -402.05586) (xy 378.089341 -402.05586) (xy 378.035393 -402.048104)
			(xy 377.983098 -402.032749) (xy 377.933521 -402.010107) (xy 377.887671 -401.980641) (xy 377.84648 -401.94495)
			(xy 377.810789 -401.903759) (xy 377.781323 -401.857909) (xy 377.758681 -401.808332) (xy 377.743326 -401.756037)
			(xy 377.73557 -401.702089) (xy 377.735084 -401.674838) (xy 377.298204 -401.674838) (xy 377.297718 -401.702107)
			(xy 377.289956 -401.756091) (xy 377.274591 -401.808421) (xy 377.251934 -401.858031) (xy 377.222448 -401.903912)
			(xy 377.186733 -401.945129) (xy 377.145516 -401.980844) (xy 377.099635 -402.01033) (xy 377.050025 -402.032987)
			(xy 376.997695 -402.048352) (xy 376.943711 -402.056114) (xy 376.889173 -402.056114) (xy 376.835189 -402.048352)
			(xy 376.782859 -402.032987) (xy 376.733249 -402.01033) (xy 376.687368 -401.980844) (xy 376.646151 -401.945129)
			(xy 376.610436 -401.903912) (xy 376.58095 -401.858031) (xy 376.558293 -401.808421) (xy 376.542928 -401.756091)
			(xy 376.535166 -401.702107) (xy 376.53468 -401.674838) (xy 376.098308 -401.674838) (xy 376.097822 -401.702107)
			(xy 376.09006 -401.756091) (xy 376.074695 -401.808421) (xy 376.052038 -401.858031) (xy 376.022552 -401.903912)
			(xy 375.986837 -401.945129) (xy 375.94562 -401.980844) (xy 375.899739 -402.01033) (xy 375.850129 -402.032987)
			(xy 375.797799 -402.048352) (xy 375.743815 -402.056114) (xy 375.689277 -402.056114) (xy 375.635293 -402.048352)
			(xy 375.582963 -402.032987) (xy 375.533353 -402.01033) (xy 375.487472 -401.980844) (xy 375.446255 -401.945129)
			(xy 375.41054 -401.903912) (xy 375.381054 -401.858031) (xy 375.358397 -401.808421) (xy 375.343032 -401.756091)
			(xy 375.33527 -401.702107) (xy 375.334784 -401.674838) (xy 374.897904 -401.674838) (xy 374.897418 -401.702089)
			(xy 374.889662 -401.756037) (xy 374.874307 -401.808332) (xy 374.851665 -401.857909) (xy 374.822199 -401.903759)
			(xy 374.786508 -401.94495) (xy 374.745317 -401.980641) (xy 374.699467 -402.010107) (xy 374.64989 -402.032749)
			(xy 374.597595 -402.048104) (xy 374.543647 -402.05586) (xy 374.489145 -402.05586) (xy 374.435197 -402.048104)
			(xy 374.382902 -402.032749) (xy 374.333325 -402.010107) (xy 374.287475 -401.980641) (xy 374.246284 -401.94495)
			(xy 374.210593 -401.903759) (xy 374.181127 -401.857909) (xy 374.158485 -401.808332) (xy 374.14313 -401.756037)
			(xy 374.135374 -401.702089) (xy 374.134888 -401.674838) (xy 373.698008 -401.674838) (xy 373.697522 -401.702089)
			(xy 373.689766 -401.756037) (xy 373.674411 -401.808332) (xy 373.651769 -401.857909) (xy 373.622303 -401.903759)
			(xy 373.586612 -401.94495) (xy 373.545421 -401.980641) (xy 373.499571 -402.010107) (xy 373.449994 -402.032749)
			(xy 373.397699 -402.048104) (xy 373.343751 -402.05586) (xy 373.289249 -402.05586) (xy 373.235301 -402.048104)
			(xy 373.183006 -402.032749) (xy 373.133429 -402.010107) (xy 373.087579 -401.980641) (xy 373.046388 -401.94495)
			(xy 373.010697 -401.903759) (xy 372.981231 -401.857909) (xy 372.958589 -401.808332) (xy 372.943234 -401.756037)
			(xy 372.935478 -401.702089) (xy 372.934992 -401.674838) (xy 372.498112 -401.674838) (xy 372.497626 -401.702107)
			(xy 372.489864 -401.756091) (xy 372.474499 -401.808421) (xy 372.451842 -401.858031) (xy 372.422356 -401.903912)
			(xy 372.386641 -401.945129) (xy 372.345424 -401.980844) (xy 372.299543 -402.01033) (xy 372.249933 -402.032987)
			(xy 372.197603 -402.048352) (xy 372.143619 -402.056114) (xy 372.089081 -402.056114) (xy 372.035097 -402.048352)
			(xy 371.982767 -402.032987) (xy 371.933157 -402.01033) (xy 371.887276 -401.980844) (xy 371.846059 -401.945129)
			(xy 371.810344 -401.903912) (xy 371.780858 -401.858031) (xy 371.758201 -401.808421) (xy 371.742836 -401.756091)
			(xy 371.735074 -401.702107) (xy 371.734588 -401.674838) (xy 371.298216 -401.674838) (xy 371.29773 -401.702107)
			(xy 371.289968 -401.756091) (xy 371.274603 -401.808421) (xy 371.251946 -401.858031) (xy 371.22246 -401.903912)
			(xy 371.186745 -401.945129) (xy 371.145528 -401.980844) (xy 371.099647 -402.01033) (xy 371.050037 -402.032987)
			(xy 370.997707 -402.048352) (xy 370.943723 -402.056114) (xy 370.889185 -402.056114) (xy 370.835201 -402.048352)
			(xy 370.782871 -402.032987) (xy 370.733261 -402.01033) (xy 370.68738 -401.980844) (xy 370.646163 -401.945129)
			(xy 370.610448 -401.903912) (xy 370.580962 -401.858031) (xy 370.558305 -401.808421) (xy 370.54294 -401.756091)
			(xy 370.535178 -401.702107) (xy 370.534692 -401.674838) (xy 354.725732 -401.674838) (xy 354.725246 -401.702107)
			(xy 354.717484 -401.756091) (xy 354.702119 -401.808421) (xy 354.679462 -401.858031) (xy 354.649976 -401.903912)
			(xy 354.614261 -401.945129) (xy 354.573044 -401.980844) (xy 354.527163 -402.01033) (xy 354.477553 -402.032987)
			(xy 354.425223 -402.048352) (xy 354.371239 -402.056114) (xy 354.316701 -402.056114) (xy 354.262717 -402.048352)
			(xy 354.210387 -402.032987) (xy 354.160777 -402.01033) (xy 354.114896 -401.980844) (xy 354.073679 -401.945129)
			(xy 354.037964 -401.903912) (xy 354.008478 -401.858031) (xy 353.985821 -401.808421) (xy 353.970456 -401.756091)
			(xy 353.962694 -401.702107) (xy 353.962208 -401.674838) (xy 353.525836 -401.674838) (xy 353.52535 -401.702107)
			(xy 353.517588 -401.756091) (xy 353.502223 -401.808421) (xy 353.479566 -401.858031) (xy 353.45008 -401.903912)
			(xy 353.414365 -401.945129) (xy 353.373148 -401.980844) (xy 353.327267 -402.01033) (xy 353.277657 -402.032987)
			(xy 353.225327 -402.048352) (xy 353.171343 -402.056114) (xy 353.116805 -402.056114) (xy 353.062821 -402.048352)
			(xy 353.010491 -402.032987) (xy 352.960881 -402.01033) (xy 352.915 -401.980844) (xy 352.873783 -401.945129)
			(xy 352.838068 -401.903912) (xy 352.808582 -401.858031) (xy 352.785925 -401.808421) (xy 352.77056 -401.756091)
			(xy 352.762798 -401.702107) (xy 352.762312 -401.674838) (xy 352.325432 -401.674838) (xy 352.324946 -401.702089)
			(xy 352.31719 -401.756037) (xy 352.301835 -401.808332) (xy 352.279193 -401.857909) (xy 352.249727 -401.903759)
			(xy 352.214036 -401.94495) (xy 352.172845 -401.980641) (xy 352.126995 -402.010107) (xy 352.077418 -402.032749)
			(xy 352.025123 -402.048104) (xy 351.971175 -402.05586) (xy 351.916673 -402.05586) (xy 351.862725 -402.048104)
			(xy 351.81043 -402.032749) (xy 351.760853 -402.010107) (xy 351.715003 -401.980641) (xy 351.673812 -401.94495)
			(xy 351.638121 -401.903759) (xy 351.608655 -401.857909) (xy 351.586013 -401.808332) (xy 351.570658 -401.756037)
			(xy 351.562902 -401.702089) (xy 351.562416 -401.674838) (xy 351.125536 -401.674838) (xy 351.12505 -401.702089)
			(xy 351.117294 -401.756037) (xy 351.101939 -401.808332) (xy 351.079297 -401.857909) (xy 351.049831 -401.903759)
			(xy 351.01414 -401.94495) (xy 350.972949 -401.980641) (xy 350.927099 -402.010107) (xy 350.877522 -402.032749)
			(xy 350.825227 -402.048104) (xy 350.771279 -402.05586) (xy 350.716777 -402.05586) (xy 350.662829 -402.048104)
			(xy 350.610534 -402.032749) (xy 350.560957 -402.010107) (xy 350.515107 -401.980641) (xy 350.473916 -401.94495)
			(xy 350.438225 -401.903759) (xy 350.408759 -401.857909) (xy 350.386117 -401.808332) (xy 350.370762 -401.756037)
			(xy 350.363006 -401.702089) (xy 350.36252 -401.674838) (xy 349.92564 -401.674838) (xy 349.925154 -401.702089)
			(xy 349.917398 -401.756037) (xy 349.902043 -401.808332) (xy 349.879401 -401.857909) (xy 349.849935 -401.903759)
			(xy 349.814244 -401.94495) (xy 349.773053 -401.980641) (xy 349.727203 -402.010107) (xy 349.677626 -402.032749)
			(xy 349.625331 -402.048104) (xy 349.571383 -402.05586) (xy 349.516881 -402.05586) (xy 349.462933 -402.048104)
			(xy 349.410638 -402.032749) (xy 349.361061 -402.010107) (xy 349.315211 -401.980641) (xy 349.27402 -401.94495)
			(xy 349.238329 -401.903759) (xy 349.208863 -401.857909) (xy 349.186221 -401.808332) (xy 349.170866 -401.756037)
			(xy 349.16311 -401.702089) (xy 349.162624 -401.674838) (xy 348.725744 -401.674838) (xy 348.725258 -401.702089)
			(xy 348.717502 -401.756037) (xy 348.702147 -401.808332) (xy 348.679505 -401.857909) (xy 348.650039 -401.903759)
			(xy 348.614348 -401.94495) (xy 348.573157 -401.980641) (xy 348.527307 -402.010107) (xy 348.47773 -402.032749)
			(xy 348.425435 -402.048104) (xy 348.371487 -402.05586) (xy 348.316985 -402.05586) (xy 348.263037 -402.048104)
			(xy 348.210742 -402.032749) (xy 348.161165 -402.010107) (xy 348.115315 -401.980641) (xy 348.074124 -401.94495)
			(xy 348.038433 -401.903759) (xy 348.008967 -401.857909) (xy 347.986325 -401.808332) (xy 347.97097 -401.756037)
			(xy 347.963214 -401.702089) (xy 347.962728 -401.674838) (xy 347.525848 -401.674838) (xy 347.525362 -401.702107)
			(xy 347.5176 -401.756091) (xy 347.502235 -401.808421) (xy 347.479578 -401.858031) (xy 347.450092 -401.903912)
			(xy 347.414377 -401.945129) (xy 347.37316 -401.980844) (xy 347.327279 -402.01033) (xy 347.277669 -402.032987)
			(xy 347.225339 -402.048352) (xy 347.171355 -402.056114) (xy 347.116817 -402.056114) (xy 347.062833 -402.048352)
			(xy 347.010503 -402.032987) (xy 346.960893 -402.01033) (xy 346.915012 -401.980844) (xy 346.873795 -401.945129)
			(xy 346.83808 -401.903912) (xy 346.808594 -401.858031) (xy 346.785937 -401.808421) (xy 346.770572 -401.756091)
			(xy 346.76281 -401.702107) (xy 346.762324 -401.674838) (xy 346.325952 -401.674838) (xy 346.325466 -401.702107)
			(xy 346.317704 -401.756091) (xy 346.302339 -401.808421) (xy 346.279682 -401.858031) (xy 346.250196 -401.903912)
			(xy 346.214481 -401.945129) (xy 346.173264 -401.980844) (xy 346.127383 -402.01033) (xy 346.077773 -402.032987)
			(xy 346.025443 -402.048352) (xy 345.971459 -402.056114) (xy 345.916921 -402.056114) (xy 345.862937 -402.048352)
			(xy 345.810607 -402.032987) (xy 345.760997 -402.01033) (xy 345.715116 -401.980844) (xy 345.673899 -401.945129)
			(xy 345.638184 -401.903912) (xy 345.608698 -401.858031) (xy 345.586041 -401.808421) (xy 345.570676 -401.756091)
			(xy 345.562914 -401.702107) (xy 345.562428 -401.674838) (xy 345.125548 -401.674838) (xy 345.125062 -401.702089)
			(xy 345.117306 -401.756037) (xy 345.101951 -401.808332) (xy 345.079309 -401.857909) (xy 345.049843 -401.903759)
			(xy 345.014152 -401.94495) (xy 344.972961 -401.980641) (xy 344.927111 -402.010107) (xy 344.877534 -402.032749)
			(xy 344.825239 -402.048104) (xy 344.771291 -402.05586) (xy 344.716789 -402.05586) (xy 344.662841 -402.048104)
			(xy 344.610546 -402.032749) (xy 344.560969 -402.010107) (xy 344.515119 -401.980641) (xy 344.473928 -401.94495)
			(xy 344.438237 -401.903759) (xy 344.408771 -401.857909) (xy 344.386129 -401.808332) (xy 344.370774 -401.756037)
			(xy 344.363018 -401.702089) (xy 344.362532 -401.674838) (xy 343.925652 -401.674838) (xy 343.925166 -401.702089)
			(xy 343.91741 -401.756037) (xy 343.902055 -401.808332) (xy 343.879413 -401.857909) (xy 343.849947 -401.903759)
			(xy 343.814256 -401.94495) (xy 343.773065 -401.980641) (xy 343.727215 -402.010107) (xy 343.677638 -402.032749)
			(xy 343.625343 -402.048104) (xy 343.571395 -402.05586) (xy 343.516893 -402.05586) (xy 343.462945 -402.048104)
			(xy 343.41065 -402.032749) (xy 343.361073 -402.010107) (xy 343.315223 -401.980641) (xy 343.274032 -401.94495)
			(xy 343.238341 -401.903759) (xy 343.208875 -401.857909) (xy 343.186233 -401.808332) (xy 343.170878 -401.756037)
			(xy 343.163122 -401.702089) (xy 343.162636 -401.674838) (xy 342.725756 -401.674838) (xy 342.72527 -401.702107)
			(xy 342.717508 -401.756091) (xy 342.702143 -401.808421) (xy 342.679486 -401.858031) (xy 342.65 -401.903912)
			(xy 342.614285 -401.945129) (xy 342.573068 -401.980844) (xy 342.527187 -402.01033) (xy 342.477577 -402.032987)
			(xy 342.425247 -402.048352) (xy 342.371263 -402.056114) (xy 342.316725 -402.056114) (xy 342.262741 -402.048352)
			(xy 342.210411 -402.032987) (xy 342.160801 -402.01033) (xy 342.11492 -401.980844) (xy 342.073703 -401.945129)
			(xy 342.037988 -401.903912) (xy 342.008502 -401.858031) (xy 341.985845 -401.808421) (xy 341.97048 -401.756091)
			(xy 341.962718 -401.702107) (xy 341.962232 -401.674838) (xy 341.52586 -401.674838) (xy 341.525374 -401.702107)
			(xy 341.517612 -401.756091) (xy 341.502247 -401.808421) (xy 341.47959 -401.858031) (xy 341.450104 -401.903912)
			(xy 341.414389 -401.945129) (xy 341.373172 -401.980844) (xy 341.327291 -402.01033) (xy 341.277681 -402.032987)
			(xy 341.225351 -402.048352) (xy 341.171367 -402.056114) (xy 341.116829 -402.056114) (xy 341.062845 -402.048352)
			(xy 341.010515 -402.032987) (xy 340.960905 -402.01033) (xy 340.915024 -401.980844) (xy 340.873807 -401.945129)
			(xy 340.838092 -401.903912) (xy 340.808606 -401.858031) (xy 340.785949 -401.808421) (xy 340.770584 -401.756091)
			(xy 340.762822 -401.702107) (xy 340.762336 -401.674838) (xy 340.325456 -401.674838) (xy 340.32497 -401.702089)
			(xy 340.317214 -401.756037) (xy 340.301859 -401.808332) (xy 340.279217 -401.857909) (xy 340.249751 -401.903759)
			(xy 340.21406 -401.94495) (xy 340.172869 -401.980641) (xy 340.127019 -402.010107) (xy 340.077442 -402.032749)
			(xy 340.025147 -402.048104) (xy 339.971199 -402.05586) (xy 339.916697 -402.05586) (xy 339.862749 -402.048104)
			(xy 339.810454 -402.032749) (xy 339.760877 -402.010107) (xy 339.715027 -401.980641) (xy 339.673836 -401.94495)
			(xy 339.638145 -401.903759) (xy 339.608679 -401.857909) (xy 339.586037 -401.808332) (xy 339.570682 -401.756037)
			(xy 339.562926 -401.702089) (xy 339.56244 -401.674838) (xy 339.12556 -401.674838) (xy 339.125074 -401.702089)
			(xy 339.117318 -401.756037) (xy 339.101963 -401.808332) (xy 339.079321 -401.857909) (xy 339.049855 -401.903759)
			(xy 339.014164 -401.94495) (xy 338.972973 -401.980641) (xy 338.927123 -402.010107) (xy 338.877546 -402.032749)
			(xy 338.825251 -402.048104) (xy 338.771303 -402.05586) (xy 338.716801 -402.05586) (xy 338.662853 -402.048104)
			(xy 338.610558 -402.032749) (xy 338.560981 -402.010107) (xy 338.515131 -401.980641) (xy 338.47394 -401.94495)
			(xy 338.438249 -401.903759) (xy 338.408783 -401.857909) (xy 338.386141 -401.808332) (xy 338.370786 -401.756037)
			(xy 338.36303 -401.702089) (xy 338.362544 -401.674838) (xy 337.925664 -401.674838) (xy 337.925178 -401.702107)
			(xy 337.917416 -401.756091) (xy 337.902051 -401.808421) (xy 337.879394 -401.858031) (xy 337.849908 -401.903912)
			(xy 337.814193 -401.945129) (xy 337.772976 -401.980844) (xy 337.727095 -402.01033) (xy 337.677485 -402.032987)
			(xy 337.625155 -402.048352) (xy 337.571171 -402.056114) (xy 337.516633 -402.056114) (xy 337.462649 -402.048352)
			(xy 337.410319 -402.032987) (xy 337.360709 -402.01033) (xy 337.314828 -401.980844) (xy 337.273611 -401.945129)
			(xy 337.237896 -401.903912) (xy 337.20841 -401.858031) (xy 337.185753 -401.808421) (xy 337.170388 -401.756091)
			(xy 337.162626 -401.702107) (xy 337.16214 -401.674838) (xy 336.725768 -401.674838) (xy 336.725282 -401.702107)
			(xy 336.71752 -401.756091) (xy 336.702155 -401.808421) (xy 336.679498 -401.858031) (xy 336.650012 -401.903912)
			(xy 336.614297 -401.945129) (xy 336.57308 -401.980844) (xy 336.527199 -402.01033) (xy 336.477589 -402.032987)
			(xy 336.425259 -402.048352) (xy 336.371275 -402.056114) (xy 336.316737 -402.056114) (xy 336.262753 -402.048352)
			(xy 336.210423 -402.032987) (xy 336.160813 -402.01033) (xy 336.114932 -401.980844) (xy 336.073715 -401.945129)
			(xy 336.038 -401.903912) (xy 336.008514 -401.858031) (xy 335.985857 -401.808421) (xy 335.970492 -401.756091)
			(xy 335.96273 -401.702107) (xy 335.962244 -401.674838) (xy 322.197984 -401.674838) (xy 322.197498 -401.702107)
			(xy 322.189736 -401.756091) (xy 322.174371 -401.808421) (xy 322.151714 -401.858031) (xy 322.122228 -401.903912)
			(xy 322.086513 -401.945129) (xy 322.045296 -401.980844) (xy 321.999415 -402.01033) (xy 321.949805 -402.032987)
			(xy 321.897475 -402.048352) (xy 321.843491 -402.056114) (xy 321.788953 -402.056114) (xy 321.734969 -402.048352)
			(xy 321.682639 -402.032987) (xy 321.633029 -402.01033) (xy 321.587148 -401.980844) (xy 321.545931 -401.945129)
			(xy 321.510216 -401.903912) (xy 321.48073 -401.858031) (xy 321.458073 -401.808421) (xy 321.442708 -401.756091)
			(xy 321.434946 -401.702107) (xy 321.43446 -401.674838) (xy 320.998088 -401.674838) (xy 320.997602 -401.702107)
			(xy 320.98984 -401.756091) (xy 320.974475 -401.808421) (xy 320.951818 -401.858031) (xy 320.922332 -401.903912)
			(xy 320.886617 -401.945129) (xy 320.8454 -401.980844) (xy 320.799519 -402.01033) (xy 320.749909 -402.032987)
			(xy 320.697579 -402.048352) (xy 320.643595 -402.056114) (xy 320.589057 -402.056114) (xy 320.535073 -402.048352)
			(xy 320.482743 -402.032987) (xy 320.433133 -402.01033) (xy 320.387252 -401.980844) (xy 320.346035 -401.945129)
			(xy 320.31032 -401.903912) (xy 320.280834 -401.858031) (xy 320.258177 -401.808421) (xy 320.242812 -401.756091)
			(xy 320.23505 -401.702107) (xy 320.234564 -401.674838) (xy 319.797684 -401.674838) (xy 319.797198 -401.702089)
			(xy 319.789442 -401.756037) (xy 319.774087 -401.808332) (xy 319.751445 -401.857909) (xy 319.721979 -401.903759)
			(xy 319.686288 -401.94495) (xy 319.645097 -401.980641) (xy 319.599247 -402.010107) (xy 319.54967 -402.032749)
			(xy 319.497375 -402.048104) (xy 319.443427 -402.05586) (xy 319.388925 -402.05586) (xy 319.334977 -402.048104)
			(xy 319.282682 -402.032749) (xy 319.233105 -402.010107) (xy 319.187255 -401.980641) (xy 319.146064 -401.94495)
			(xy 319.110373 -401.903759) (xy 319.080907 -401.857909) (xy 319.058265 -401.808332) (xy 319.04291 -401.756037)
			(xy 319.035154 -401.702089) (xy 319.034668 -401.674838) (xy 318.597788 -401.674838) (xy 318.597302 -401.702089)
			(xy 318.589546 -401.756037) (xy 318.574191 -401.808332) (xy 318.551549 -401.857909) (xy 318.522083 -401.903759)
			(xy 318.486392 -401.94495) (xy 318.445201 -401.980641) (xy 318.399351 -402.010107) (xy 318.349774 -402.032749)
			(xy 318.297479 -402.048104) (xy 318.243531 -402.05586) (xy 318.189029 -402.05586) (xy 318.135081 -402.048104)
			(xy 318.082786 -402.032749) (xy 318.033209 -402.010107) (xy 317.987359 -401.980641) (xy 317.946168 -401.94495)
			(xy 317.910477 -401.903759) (xy 317.881011 -401.857909) (xy 317.858369 -401.808332) (xy 317.843014 -401.756037)
			(xy 317.835258 -401.702089) (xy 317.834772 -401.674838) (xy 317.397892 -401.674838) (xy 317.397406 -401.702089)
			(xy 317.38965 -401.756037) (xy 317.374295 -401.808332) (xy 317.351653 -401.857909) (xy 317.322187 -401.903759)
			(xy 317.286496 -401.94495) (xy 317.245305 -401.980641) (xy 317.199455 -402.010107) (xy 317.149878 -402.032749)
			(xy 317.097583 -402.048104) (xy 317.043635 -402.05586) (xy 316.989133 -402.05586) (xy 316.935185 -402.048104)
			(xy 316.88289 -402.032749) (xy 316.833313 -402.010107) (xy 316.787463 -401.980641) (xy 316.746272 -401.94495)
			(xy 316.710581 -401.903759) (xy 316.681115 -401.857909) (xy 316.658473 -401.808332) (xy 316.643118 -401.756037)
			(xy 316.635362 -401.702089) (xy 316.634876 -401.674838) (xy 316.197996 -401.674838) (xy 316.19751 -401.702089)
			(xy 316.189754 -401.756037) (xy 316.174399 -401.808332) (xy 316.151757 -401.857909) (xy 316.122291 -401.903759)
			(xy 316.0866 -401.94495) (xy 316.045409 -401.980641) (xy 315.999559 -402.010107) (xy 315.949982 -402.032749)
			(xy 315.897687 -402.048104) (xy 315.843739 -402.05586) (xy 315.789237 -402.05586) (xy 315.735289 -402.048104)
			(xy 315.682994 -402.032749) (xy 315.633417 -402.010107) (xy 315.587567 -401.980641) (xy 315.546376 -401.94495)
			(xy 315.510685 -401.903759) (xy 315.481219 -401.857909) (xy 315.458577 -401.808332) (xy 315.443222 -401.756037)
			(xy 315.435466 -401.702089) (xy 315.43498 -401.674838) (xy 314.9981 -401.674838) (xy 314.997614 -401.702107)
			(xy 314.989852 -401.756091) (xy 314.974487 -401.808421) (xy 314.95183 -401.858031) (xy 314.922344 -401.903912)
			(xy 314.886629 -401.945129) (xy 314.845412 -401.980844) (xy 314.799531 -402.01033) (xy 314.749921 -402.032987)
			(xy 314.697591 -402.048352) (xy 314.643607 -402.056114) (xy 314.589069 -402.056114) (xy 314.535085 -402.048352)
			(xy 314.482755 -402.032987) (xy 314.433145 -402.01033) (xy 314.387264 -401.980844) (xy 314.346047 -401.945129)
			(xy 314.310332 -401.903912) (xy 314.280846 -401.858031) (xy 314.258189 -401.808421) (xy 314.242824 -401.756091)
			(xy 314.235062 -401.702107) (xy 314.234576 -401.674838) (xy 313.798204 -401.674838) (xy 313.797718 -401.702107)
			(xy 313.789956 -401.756091) (xy 313.774591 -401.808421) (xy 313.751934 -401.858031) (xy 313.722448 -401.903912)
			(xy 313.686733 -401.945129) (xy 313.645516 -401.980844) (xy 313.599635 -402.01033) (xy 313.550025 -402.032987)
			(xy 313.497695 -402.048352) (xy 313.443711 -402.056114) (xy 313.389173 -402.056114) (xy 313.335189 -402.048352)
			(xy 313.282859 -402.032987) (xy 313.233249 -402.01033) (xy 313.187368 -401.980844) (xy 313.146151 -401.945129)
			(xy 313.110436 -401.903912) (xy 313.08095 -401.858031) (xy 313.058293 -401.808421) (xy 313.042928 -401.756091)
			(xy 313.035166 -401.702107) (xy 313.03468 -401.674838) (xy 312.5978 -401.674838) (xy 312.597314 -401.702089)
			(xy 312.589558 -401.756037) (xy 312.574203 -401.808332) (xy 312.551561 -401.857909) (xy 312.522095 -401.903759)
			(xy 312.486404 -401.94495) (xy 312.445213 -401.980641) (xy 312.399363 -402.010107) (xy 312.349786 -402.032749)
			(xy 312.297491 -402.048104) (xy 312.243543 -402.05586) (xy 312.189041 -402.05586) (xy 312.135093 -402.048104)
			(xy 312.082798 -402.032749) (xy 312.033221 -402.010107) (xy 311.987371 -401.980641) (xy 311.94618 -401.94495)
			(xy 311.910489 -401.903759) (xy 311.881023 -401.857909) (xy 311.858381 -401.808332) (xy 311.843026 -401.756037)
			(xy 311.83527 -401.702089) (xy 311.834784 -401.674838) (xy 311.397904 -401.674838) (xy 311.397418 -401.702089)
			(xy 311.389662 -401.756037) (xy 311.374307 -401.808332) (xy 311.351665 -401.857909) (xy 311.322199 -401.903759)
			(xy 311.286508 -401.94495) (xy 311.245317 -401.980641) (xy 311.199467 -402.010107) (xy 311.14989 -402.032749)
			(xy 311.097595 -402.048104) (xy 311.043647 -402.05586) (xy 310.989145 -402.05586) (xy 310.935197 -402.048104)
			(xy 310.882902 -402.032749) (xy 310.833325 -402.010107) (xy 310.787475 -401.980641) (xy 310.746284 -401.94495)
			(xy 310.710593 -401.903759) (xy 310.681127 -401.857909) (xy 310.658485 -401.808332) (xy 310.64313 -401.756037)
			(xy 310.635374 -401.702089) (xy 310.634888 -401.674838) (xy 310.198008 -401.674838) (xy 310.197522 -401.702107)
			(xy 310.18976 -401.756091) (xy 310.174395 -401.808421) (xy 310.151738 -401.858031) (xy 310.122252 -401.903912)
			(xy 310.086537 -401.945129) (xy 310.04532 -401.980844) (xy 309.999439 -402.01033) (xy 309.949829 -402.032987)
			(xy 309.897499 -402.048352) (xy 309.843515 -402.056114) (xy 309.788977 -402.056114) (xy 309.734993 -402.048352)
			(xy 309.682663 -402.032987) (xy 309.633053 -402.01033) (xy 309.587172 -401.980844) (xy 309.545955 -401.945129)
			(xy 309.51024 -401.903912) (xy 309.480754 -401.858031) (xy 309.458097 -401.808421) (xy 309.442732 -401.756091)
			(xy 309.43497 -401.702107) (xy 309.434484 -401.674838) (xy 308.998112 -401.674838) (xy 308.997626 -401.702107)
			(xy 308.989864 -401.756091) (xy 308.974499 -401.808421) (xy 308.951842 -401.858031) (xy 308.922356 -401.903912)
			(xy 308.886641 -401.945129) (xy 308.845424 -401.980844) (xy 308.799543 -402.01033) (xy 308.749933 -402.032987)
			(xy 308.697603 -402.048352) (xy 308.643619 -402.056114) (xy 308.589081 -402.056114) (xy 308.535097 -402.048352)
			(xy 308.482767 -402.032987) (xy 308.433157 -402.01033) (xy 308.387276 -401.980844) (xy 308.346059 -401.945129)
			(xy 308.310344 -401.903912) (xy 308.280858 -401.858031) (xy 308.258201 -401.808421) (xy 308.242836 -401.756091)
			(xy 308.235074 -401.702107) (xy 308.234588 -401.674838) (xy 307.797708 -401.674838) (xy 307.797222 -401.702089)
			(xy 307.789466 -401.756037) (xy 307.774111 -401.808332) (xy 307.751469 -401.857909) (xy 307.722003 -401.903759)
			(xy 307.686312 -401.94495) (xy 307.645121 -401.980641) (xy 307.599271 -402.010107) (xy 307.549694 -402.032749)
			(xy 307.497399 -402.048104) (xy 307.443451 -402.05586) (xy 307.388949 -402.05586) (xy 307.335001 -402.048104)
			(xy 307.282706 -402.032749) (xy 307.233129 -402.010107) (xy 307.187279 -401.980641) (xy 307.146088 -401.94495)
			(xy 307.110397 -401.903759) (xy 307.080931 -401.857909) (xy 307.058289 -401.808332) (xy 307.042934 -401.756037)
			(xy 307.035178 -401.702089) (xy 307.034692 -401.674838) (xy 306.597812 -401.674838) (xy 306.597326 -401.702089)
			(xy 306.58957 -401.756037) (xy 306.574215 -401.808332) (xy 306.551573 -401.857909) (xy 306.522107 -401.903759)
			(xy 306.486416 -401.94495) (xy 306.445225 -401.980641) (xy 306.399375 -402.010107) (xy 306.349798 -402.032749)
			(xy 306.297503 -402.048104) (xy 306.243555 -402.05586) (xy 306.189053 -402.05586) (xy 306.135105 -402.048104)
			(xy 306.08281 -402.032749) (xy 306.033233 -402.010107) (xy 305.987383 -401.980641) (xy 305.946192 -401.94495)
			(xy 305.910501 -401.903759) (xy 305.881035 -401.857909) (xy 305.858393 -401.808332) (xy 305.843038 -401.756037)
			(xy 305.835282 -401.702089) (xy 305.834796 -401.674838) (xy 305.397916 -401.674838) (xy 305.39743 -401.702107)
			(xy 305.389668 -401.756091) (xy 305.374303 -401.808421) (xy 305.351646 -401.858031) (xy 305.32216 -401.903912)
			(xy 305.286445 -401.945129) (xy 305.245228 -401.980844) (xy 305.199347 -402.01033) (xy 305.149737 -402.032987)
			(xy 305.097407 -402.048352) (xy 305.043423 -402.056114) (xy 304.988885 -402.056114) (xy 304.934901 -402.048352)
			(xy 304.882571 -402.032987) (xy 304.832961 -402.01033) (xy 304.78708 -401.980844) (xy 304.745863 -401.945129)
			(xy 304.710148 -401.903912) (xy 304.680662 -401.858031) (xy 304.658005 -401.808421) (xy 304.64264 -401.756091)
			(xy 304.634878 -401.702107) (xy 304.634392 -401.674838) (xy 304.19802 -401.674838) (xy 304.197534 -401.702107)
			(xy 304.189772 -401.756091) (xy 304.174407 -401.808421) (xy 304.15175 -401.858031) (xy 304.122264 -401.903912)
			(xy 304.086549 -401.945129) (xy 304.045332 -401.980844) (xy 303.999451 -402.01033) (xy 303.949841 -402.032987)
			(xy 303.897511 -402.048352) (xy 303.843527 -402.056114) (xy 303.788989 -402.056114) (xy 303.735005 -402.048352)
			(xy 303.682675 -402.032987) (xy 303.633065 -402.01033) (xy 303.587184 -401.980844) (xy 303.545967 -401.945129)
			(xy 303.510252 -401.903912) (xy 303.480766 -401.858031) (xy 303.458109 -401.808421) (xy 303.442744 -401.756091)
			(xy 303.434982 -401.702107) (xy 303.434496 -401.674838) (xy 280.68524 -401.674838) (xy 280.68524 -404.215092)
			(xy 283.62402 -404.215092) (xy 283.62402 -403.351492) (xy 283.624506 -403.324223) (xy 283.632268 -403.270239)
			(xy 283.647633 -403.217909) (xy 283.67029 -403.168299) (xy 283.699776 -403.122418) (xy 283.735491 -403.081201)
			(xy 283.776708 -403.045486) (xy 283.822589 -403.016) (xy 283.872199 -402.993343) (xy 283.924529 -402.977978)
			(xy 283.978513 -402.970216) (xy 284.033051 -402.970216) (xy 284.087035 -402.977978) (xy 284.139365 -402.993343)
			(xy 284.188975 -403.016) (xy 284.203533 -403.025356) (xy 289.919156 -403.025356) (xy 289.919156 -402.161756)
			(xy 289.919642 -402.134487) (xy 289.927404 -402.080503) (xy 289.942769 -402.028173) (xy 289.965426 -401.978563)
			(xy 289.994912 -401.932682) (xy 290.030627 -401.891465) (xy 290.071844 -401.85575) (xy 290.117725 -401.826264)
			(xy 290.167335 -401.803607) (xy 290.219665 -401.788242) (xy 290.273649 -401.78048) (xy 290.328187 -401.78048)
			(xy 290.382171 -401.788242) (xy 290.434501 -401.803607) (xy 290.484111 -401.826264) (xy 290.529992 -401.85575)
			(xy 290.571209 -401.891465) (xy 290.606924 -401.932682) (xy 290.63641 -401.978563) (xy 290.659067 -402.028173)
			(xy 290.674432 -402.080503) (xy 290.682194 -402.134487) (xy 290.68268 -402.161756) (xy 290.68268 -403.025356)
			(xy 290.682194 -403.052625) (xy 290.674432 -403.106609) (xy 290.659067 -403.158939) (xy 290.63641 -403.208549)
			(xy 290.606924 -403.25443) (xy 290.571209 -403.295647) (xy 290.529992 -403.331362) (xy 290.484111 -403.360848)
			(xy 290.434501 -403.383505) (xy 290.382171 -403.39887) (xy 290.328187 -403.406632) (xy 290.273649 -403.406632)
			(xy 290.219665 -403.39887) (xy 290.167335 -403.383505) (xy 290.117725 -403.360848) (xy 290.071844 -403.331362)
			(xy 290.030627 -403.295647) (xy 289.994912 -403.25443) (xy 289.965426 -403.208549) (xy 289.942769 -403.158939)
			(xy 289.927404 -403.106609) (xy 289.919642 -403.052625) (xy 289.919156 -403.025356) (xy 284.203533 -403.025356)
			(xy 284.234856 -403.045486) (xy 284.276073 -403.081201) (xy 284.311788 -403.122418) (xy 284.341274 -403.168299)
			(xy 284.363931 -403.217909) (xy 284.379296 -403.270239) (xy 284.387058 -403.324223) (xy 284.387544 -403.351492)
			(xy 284.387544 -404.215092) (xy 284.387058 -404.242361) (xy 284.379296 -404.296345) (xy 284.363931 -404.348675)
			(xy 284.341274 -404.398285) (xy 284.311788 -404.444166) (xy 284.276073 -404.485383) (xy 284.234856 -404.521098)
			(xy 284.188975 -404.550584) (xy 284.139365 -404.573241) (xy 284.087035 -404.588606) (xy 284.033051 -404.596368)
			(xy 283.978513 -404.596368) (xy 283.924529 -404.588606) (xy 283.872199 -404.573241) (xy 283.822589 -404.550584)
			(xy 283.776708 -404.521098) (xy 283.735491 -404.485383) (xy 283.699776 -404.444166) (xy 283.67029 -404.398285)
			(xy 283.647633 -404.348675) (xy 283.632268 -404.296345) (xy 283.624506 -404.242361) (xy 283.62402 -404.215092)
			(xy 280.68524 -404.215092) (xy 280.68524 -407.583953) (xy 282.536071 -407.583953) (xy 282.536071 -407.529447)
			(xy 282.543829 -407.475495) (xy 282.559186 -407.423196) (xy 282.581831 -407.373615) (xy 282.611301 -407.327762)
			(xy 282.646997 -407.28657) (xy 282.688193 -407.250878) (xy 282.734049 -407.221412) (xy 282.783632 -407.198773)
			(xy 282.835932 -407.183421) (xy 282.889885 -407.175669) (xy 282.917138 -407.175208) (xy 283.780738 -407.175208)
			(xy 283.807989 -407.175664) (xy 283.861934 -407.183426) (xy 283.914227 -407.198785) (xy 283.963801 -407.221429)
			(xy 284.009649 -407.250898) (xy 284.050836 -407.286591) (xy 284.086525 -407.327782) (xy 284.115989 -407.373632)
			(xy 284.134525 -407.414222) (xy 287.101788 -407.414222) (xy 287.101788 -406.550622) (xy 287.102274 -406.523371)
			(xy 287.11003 -406.469423) (xy 287.125385 -406.417128) (xy 287.148027 -406.367551) (xy 287.177493 -406.321701)
			(xy 287.213184 -406.28051) (xy 287.254375 -406.244819) (xy 287.300225 -406.215353) (xy 287.349802 -406.192711)
			(xy 287.402097 -406.177356) (xy 287.456045 -406.1696) (xy 287.510547 -406.1696) (xy 287.564495 -406.177356)
			(xy 287.61679 -406.192711) (xy 287.666367 -406.215353) (xy 287.712217 -406.244819) (xy 287.753408 -406.28051)
			(xy 287.789099 -406.321701) (xy 287.818565 -406.367551) (xy 287.841207 -406.417128) (xy 287.856562 -406.469423)
			(xy 287.864318 -406.523371) (xy 287.864804 -406.550622) (xy 287.864804 -407.414222) (xy 287.864318 -407.441473)
			(xy 287.856562 -407.495421) (xy 287.841207 -407.547716) (xy 287.818565 -407.597293) (xy 287.789099 -407.643143)
			(xy 287.753408 -407.684334) (xy 287.712217 -407.720025) (xy 287.666367 -407.749491) (xy 287.61679 -407.772133)
			(xy 287.564495 -407.787488) (xy 287.510547 -407.795244) (xy 287.456045 -407.795244) (xy 287.402097 -407.787488)
			(xy 287.349802 -407.772133) (xy 287.300225 -407.749491) (xy 287.254375 -407.720025) (xy 287.213184 -407.684334)
			(xy 287.177493 -407.643143) (xy 287.148027 -407.597293) (xy 287.125385 -407.547716) (xy 287.11003 -407.495421)
			(xy 287.102274 -407.441473) (xy 287.101788 -407.414222) (xy 284.134525 -407.414222) (xy 284.138629 -407.423209)
			(xy 284.153982 -407.475503) (xy 284.161738 -407.529449) (xy 284.161738 -407.583951) (xy 284.153982 -407.637897)
			(xy 284.138629 -407.690191) (xy 284.115989 -407.739768) (xy 284.086525 -407.785619) (xy 284.050836 -407.826809)
			(xy 284.009649 -407.862502) (xy 283.963801 -407.891971) (xy 283.914227 -407.914615) (xy 283.861934 -407.929974)
			(xy 283.807989 -407.937736) (xy 283.780738 -407.938224) (xy 282.917138 -407.938224) (xy 282.889885 -407.937731)
			(xy 282.835932 -407.929979) (xy 282.783632 -407.914627) (xy 282.734049 -407.891988) (xy 282.688193 -407.862522)
			(xy 282.646997 -407.82683) (xy 282.611301 -407.785638) (xy 282.581831 -407.739785) (xy 282.559186 -407.690204)
			(xy 282.543829 -407.637905) (xy 282.536071 -407.583953) (xy 280.68524 -407.583953) (xy 280.68524 -409.10256)
			(xy 280.684766 -409.12751) (xy 280.676946 -409.176794) (xy 280.661524 -409.224251) (xy 280.638877 -409.268716)
			(xy 280.609563 -409.309098) (xy 280.592276 -409.327096) (xy 276.749256 -413.170116) (xy 293.568894 -413.170116)
			(xy 293.572866 -412.991873) (xy 293.584774 -412.813984) (xy 293.604595 -412.636802) (xy 293.632289 -412.460678)
			(xy 293.667801 -412.285963) (xy 293.711061 -412.113004) (xy 293.761983 -411.942143) (xy 293.820466 -411.773721)
			(xy 293.886393 -411.608071) (xy 293.959634 -411.445522) (xy 294.040044 -411.286397) (xy 294.127462 -411.131012)
			(xy 294.221715 -410.979676) (xy 294.322616 -410.832688) (xy 294.429965 -410.690341) (xy 294.543548 -410.552918)
			(xy 294.663141 -410.420691) (xy 294.788505 -410.293922) (xy 294.919392 -410.172864) (xy 295.055541 -410.057757)
			(xy 295.196683 -409.948829) (xy 295.342538 -409.846297) (xy 295.492815 -409.750363) (xy 295.647216 -409.66122)
			(xy 295.805435 -409.579043) (xy 295.967158 -409.503995) (xy 296.132063 -409.436227) (xy 296.299824 -409.375871)
			(xy 296.470107 -409.323049) (xy 296.642574 -409.277865) (xy 296.816882 -409.240408) (xy 296.992686 -409.210754)
			(xy 297.169636 -409.188961) (xy 297.347382 -409.175071) (xy 297.525569 -409.169114) (xy 297.703846 -409.1711)
			(xy 297.881857 -409.181026) (xy 298.059249 -409.198872) (xy 298.235669 -409.224602) (xy 298.410769 -409.258166)
			(xy 298.5842 -409.299496) (xy 298.755617 -409.348512) (xy 298.92468 -409.405114) (xy 299.091055 -409.469192)
			(xy 299.254409 -409.540618) (xy 299.41442 -409.61925) (xy 299.570769 -409.704931) (xy 299.723146 -409.797493)
			(xy 299.871249 -409.89675) (xy 300.014783 -410.002507) (xy 300.153463 -410.114552) (xy 300.287014 -410.232664)
			(xy 300.415171 -410.356608) (xy 300.53768 -410.486138) (xy 300.654297 -410.620997) (xy 300.76479 -410.760917)
			(xy 300.868941 -410.90562) (xy 300.966543 -411.054819) (xy 301.057401 -411.208218) (xy 301.141335 -411.365512)
			(xy 301.21818 -411.526388) (xy 301.287781 -411.690529) (xy 301.350002 -411.857606) (xy 301.404718 -412.02729)
			(xy 301.45182 -412.199243) (xy 301.491216 -412.373123) (xy 301.522827 -412.548586) (xy 301.546591 -412.725282)
			(xy 301.559858 -412.873752) (xy 303.412875 -412.873752) (xy 303.412875 -412.819248) (xy 303.420632 -412.7653)
			(xy 303.435988 -412.713004) (xy 303.458629 -412.663426) (xy 303.488096 -412.617575) (xy 303.523789 -412.576384)
			(xy 303.56498 -412.540693) (xy 303.610831 -412.511226) (xy 303.66041 -412.488585) (xy 303.712706 -412.473231)
			(xy 303.766654 -412.465475) (xy 303.793906 -412.465012) (xy 304.657506 -412.465012) (xy 304.684758 -412.465458)
			(xy 304.738708 -412.473216) (xy 304.791005 -412.488572) (xy 304.840584 -412.511215) (xy 304.886436 -412.540683)
			(xy 304.927628 -412.576376) (xy 304.963321 -412.617569) (xy 304.992788 -412.663421) (xy 305.01543 -412.713001)
			(xy 305.030785 -412.765298) (xy 305.038542 -412.819248) (xy 305.038542 -412.873752) (xy 305.038542 -412.873754)
			(xy 306.476075 -412.873754) (xy 306.476075 -412.819246) (xy 306.483833 -412.765294) (xy 306.499191 -412.712996)
			(xy 306.521835 -412.663415) (xy 306.551306 -412.617562) (xy 306.587003 -412.57637) (xy 306.628199 -412.540679)
			(xy 306.674055 -412.511213) (xy 306.723639 -412.488575) (xy 306.775939 -412.473223) (xy 306.829892 -412.465472)
			(xy 306.857146 -412.465012) (xy 307.720746 -412.465012) (xy 307.747997 -412.465461) (xy 307.801942 -412.473223)
			(xy 307.854234 -412.488583) (xy 307.903808 -412.511228) (xy 307.949655 -412.540697) (xy 307.990842 -412.576391)
			(xy 308.02653 -412.617582) (xy 308.055994 -412.663432) (xy 308.078633 -412.713009) (xy 308.093987 -412.765303)
			(xy 308.101742 -412.819249) (xy 308.101742 -412.873749) (xy 309.539398 -412.873749) (xy 309.539398 -412.819251)
			(xy 309.547154 -412.765307) (xy 309.562508 -412.713016) (xy 309.585146 -412.663443) (xy 309.61461 -412.617596)
			(xy 309.650298 -412.576408) (xy 309.691484 -412.540718) (xy 309.73733 -412.511253) (xy 309.786903 -412.488612)
			(xy 309.839194 -412.473257) (xy 309.893137 -412.465499) (xy 309.920386 -412.465012) (xy 310.783986 -412.465012)
			(xy 310.811241 -412.465434) (xy 310.865196 -412.47319) (xy 310.917499 -412.488545) (xy 310.967083 -412.511188)
			(xy 311.012941 -412.540657) (xy 311.054137 -412.576353) (xy 311.089834 -412.617548) (xy 311.119305 -412.663405)
			(xy 311.14195 -412.712988) (xy 311.157307 -412.76529) (xy 311.165065 -412.819245) (xy 311.165065 -412.873753)
			(xy 312.602575 -412.873753) (xy 312.602575 -412.819247) (xy 312.610333 -412.765297) (xy 312.625689 -412.713)
			(xy 312.648332 -412.663421) (xy 312.677801 -412.617569) (xy 312.713496 -412.576377) (xy 312.754689 -412.540686)
			(xy 312.800543 -412.51122) (xy 312.850124 -412.48858) (xy 312.902422 -412.473227) (xy 312.956373 -412.465474)
			(xy 312.983626 -412.465012) (xy 313.847226 -412.465012) (xy 313.874477 -412.46546) (xy 313.928425 -412.47322)
			(xy 313.98072 -412.488578) (xy 314.030296 -412.511222) (xy 314.076146 -412.54069) (xy 314.117335 -412.576383)
			(xy 314.153026 -412.617575) (xy 314.182491 -412.663427) (xy 314.205131 -412.713005) (xy 314.220486 -412.7653)
			(xy 314.228242 -412.819249) (xy 314.228242 -412.873748) (xy 315.665898 -412.873748) (xy 315.665898 -412.819252)
			(xy 315.673653 -412.76531) (xy 315.689006 -412.713021) (xy 315.711643 -412.663448) (xy 315.741105 -412.617602)
			(xy 315.776791 -412.576415) (xy 315.817975 -412.540725) (xy 315.863818 -412.51126) (xy 315.913389 -412.488618)
			(xy 315.965677 -412.473261) (xy 316.019618 -412.465501) (xy 316.046866 -412.465012) (xy 316.910466 -412.465012)
			(xy 316.937722 -412.465433) (xy 316.991679 -412.473186) (xy 317.043984 -412.48854) (xy 317.093571 -412.511182)
			(xy 317.139431 -412.54065) (xy 317.18063 -412.576346) (xy 317.216329 -412.617542) (xy 317.245802 -412.663399)
			(xy 317.268448 -412.712984) (xy 317.283807 -412.765287) (xy 317.291565 -412.819244) (xy 317.291565 -412.873752)
			(xy 318.729075 -412.873752) (xy 318.729075 -412.819248) (xy 318.736832 -412.7653) (xy 318.752188 -412.713004)
			(xy 318.774829 -412.663426) (xy 318.804296 -412.617575) (xy 318.839989 -412.576384) (xy 318.88118 -412.540693)
			(xy 318.927031 -412.511226) (xy 318.97661 -412.488585) (xy 319.028906 -412.473231) (xy 319.082854 -412.465475)
			(xy 319.110106 -412.465012) (xy 319.973706 -412.465012) (xy 320.000958 -412.465458) (xy 320.054908 -412.473216)
			(xy 320.107205 -412.488572) (xy 320.156784 -412.511215) (xy 320.202636 -412.540683) (xy 320.243828 -412.576376)
			(xy 320.279521 -412.617569) (xy 320.308988 -412.663421) (xy 320.33163 -412.713001) (xy 320.346985 -412.765298)
			(xy 320.354742 -412.819248) (xy 320.354742 -412.873752) (xy 320.354742 -412.873754) (xy 321.792275 -412.873754)
			(xy 321.792275 -412.819246) (xy 321.800033 -412.765294) (xy 321.815391 -412.712996) (xy 321.838035 -412.663415)
			(xy 321.867506 -412.617562) (xy 321.903203 -412.57637) (xy 321.944399 -412.540679) (xy 321.990255 -412.511213)
			(xy 322.039839 -412.488575) (xy 322.092139 -412.473223) (xy 322.146092 -412.465472) (xy 322.173346 -412.465012)
			(xy 323.036946 -412.465012) (xy 323.064197 -412.465461) (xy 323.118142 -412.473223) (xy 323.170434 -412.488583)
			(xy 323.220008 -412.511228) (xy 323.265855 -412.540697) (xy 323.307042 -412.576391) (xy 323.34273 -412.617582)
			(xy 323.372194 -412.663432) (xy 323.394833 -412.713009) (xy 323.410187 -412.765303) (xy 323.417942 -412.819249)
			(xy 323.417942 -412.873749) (xy 324.855598 -412.873749) (xy 324.855598 -412.819251) (xy 324.863354 -412.765307)
			(xy 324.878708 -412.713016) (xy 324.901346 -412.663443) (xy 324.93081 -412.617596) (xy 324.966498 -412.576408)
			(xy 325.007684 -412.540718) (xy 325.05353 -412.511253) (xy 325.103103 -412.488612) (xy 325.155394 -412.473257)
			(xy 325.209337 -412.465499) (xy 325.236586 -412.465012) (xy 326.100186 -412.465012) (xy 326.127441 -412.465434)
			(xy 326.181396 -412.47319) (xy 326.233699 -412.488545) (xy 326.283283 -412.511188) (xy 326.329141 -412.540657)
			(xy 326.370337 -412.576353) (xy 326.406034 -412.617548) (xy 326.435505 -412.663405) (xy 326.45815 -412.712988)
			(xy 326.473507 -412.76529) (xy 326.481265 -412.819245) (xy 326.481265 -412.873753) (xy 327.918775 -412.873753)
			(xy 327.918775 -412.819247) (xy 327.926533 -412.765297) (xy 327.941889 -412.713) (xy 327.964532 -412.663421)
			(xy 327.994001 -412.617569) (xy 328.029696 -412.576377) (xy 328.070889 -412.540686) (xy 328.116743 -412.51122)
			(xy 328.166324 -412.48858) (xy 328.218622 -412.473227) (xy 328.272573 -412.465474) (xy 328.299826 -412.465012)
			(xy 329.163426 -412.465012) (xy 329.190677 -412.46546) (xy 329.244625 -412.47322) (xy 329.29692 -412.488578)
			(xy 329.346496 -412.511222) (xy 329.392346 -412.54069) (xy 329.433535 -412.576383) (xy 329.469226 -412.617575)
			(xy 329.498691 -412.663427) (xy 329.521331 -412.713005) (xy 329.536686 -412.7653) (xy 329.544442 -412.819249)
			(xy 329.544442 -412.873748) (xy 330.982098 -412.873748) (xy 330.982098 -412.819252) (xy 330.989853 -412.76531)
			(xy 331.005206 -412.713021) (xy 331.027843 -412.663448) (xy 331.057305 -412.617602) (xy 331.092991 -412.576415)
			(xy 331.134175 -412.540725) (xy 331.180018 -412.51126) (xy 331.229589 -412.488618) (xy 331.281877 -412.473261)
			(xy 331.335818 -412.465501) (xy 331.363066 -412.465012) (xy 332.226666 -412.465012) (xy 332.253922 -412.465433)
			(xy 332.307879 -412.473186) (xy 332.360184 -412.48854) (xy 332.409771 -412.511182) (xy 332.455631 -412.54065)
			(xy 332.49683 -412.576346) (xy 332.532529 -412.617542) (xy 332.562002 -412.663399) (xy 332.584648 -412.712984)
			(xy 332.600007 -412.765287) (xy 332.607765 -412.819244) (xy 332.607765 -412.873752) (xy 334.045275 -412.873752)
			(xy 334.045275 -412.819248) (xy 334.053032 -412.7653) (xy 334.068388 -412.713004) (xy 334.091029 -412.663426)
			(xy 334.120496 -412.617575) (xy 334.156189 -412.576384) (xy 334.19738 -412.540693) (xy 334.243231 -412.511226)
			(xy 334.29281 -412.488585) (xy 334.345106 -412.473231) (xy 334.399054 -412.465475) (xy 334.426306 -412.465012)
			(xy 335.289906 -412.465012) (xy 335.317158 -412.465458) (xy 335.371108 -412.473216) (xy 335.423405 -412.488572)
			(xy 335.472984 -412.511215) (xy 335.518836 -412.540683) (xy 335.560028 -412.576376) (xy 335.595721 -412.617569)
			(xy 335.625188 -412.663421) (xy 335.64783 -412.713001) (xy 335.663185 -412.765298) (xy 335.670942 -412.819248)
			(xy 335.670942 -412.873752) (xy 335.670942 -412.873754) (xy 337.108475 -412.873754) (xy 337.108475 -412.819246)
			(xy 337.116233 -412.765294) (xy 337.131591 -412.712996) (xy 337.154235 -412.663415) (xy 337.183706 -412.617562)
			(xy 337.219403 -412.57637) (xy 337.260599 -412.540679) (xy 337.306455 -412.511213) (xy 337.356039 -412.488575)
			(xy 337.408339 -412.473223) (xy 337.462292 -412.465472) (xy 337.489546 -412.465012) (xy 338.353146 -412.465012)
			(xy 338.380397 -412.465461) (xy 338.434342 -412.473223) (xy 338.486634 -412.488583) (xy 338.536208 -412.511228)
			(xy 338.582055 -412.540697) (xy 338.623242 -412.576391) (xy 338.65893 -412.617582) (xy 338.688394 -412.663432)
			(xy 338.711033 -412.713009) (xy 338.726387 -412.765303) (xy 338.734142 -412.819249) (xy 338.734142 -412.873749)
			(xy 340.171798 -412.873749) (xy 340.171798 -412.819251) (xy 340.179554 -412.765307) (xy 340.194908 -412.713016)
			(xy 340.217546 -412.663443) (xy 340.24701 -412.617596) (xy 340.282698 -412.576408) (xy 340.323884 -412.540718)
			(xy 340.36973 -412.511253) (xy 340.419303 -412.488612) (xy 340.471594 -412.473257) (xy 340.525537 -412.465499)
			(xy 340.552786 -412.465012) (xy 341.416386 -412.465012) (xy 341.443641 -412.465434) (xy 341.497596 -412.47319)
			(xy 341.549899 -412.488545) (xy 341.599483 -412.511188) (xy 341.645341 -412.540657) (xy 341.686537 -412.576353)
			(xy 341.722234 -412.617548) (xy 341.751705 -412.663405) (xy 341.77435 -412.712988) (xy 341.789707 -412.76529)
			(xy 341.797465 -412.819245) (xy 341.797465 -412.873753) (xy 343.234975 -412.873753) (xy 343.234975 -412.819247)
			(xy 343.242733 -412.765297) (xy 343.258089 -412.713) (xy 343.280732 -412.663421) (xy 343.310201 -412.617569)
			(xy 343.345896 -412.576377) (xy 343.387089 -412.540686) (xy 343.432943 -412.51122) (xy 343.482524 -412.48858)
			(xy 343.534822 -412.473227) (xy 343.588773 -412.465474) (xy 343.616026 -412.465012) (xy 344.479626 -412.465012)
			(xy 344.506877 -412.46546) (xy 344.560825 -412.47322) (xy 344.61312 -412.488578) (xy 344.662696 -412.511222)
			(xy 344.708546 -412.54069) (xy 344.749735 -412.576383) (xy 344.785426 -412.617575) (xy 344.814891 -412.663427)
			(xy 344.837531 -412.713005) (xy 344.852886 -412.7653) (xy 344.860642 -412.819249) (xy 344.860642 -412.873748)
			(xy 346.298298 -412.873748) (xy 346.298298 -412.819252) (xy 346.306053 -412.76531) (xy 346.321406 -412.713021)
			(xy 346.344043 -412.663448) (xy 346.373505 -412.617602) (xy 346.409191 -412.576415) (xy 346.450375 -412.540725)
			(xy 346.496218 -412.51126) (xy 346.545789 -412.488618) (xy 346.598077 -412.473261) (xy 346.652018 -412.465501)
			(xy 346.679266 -412.465012) (xy 347.542866 -412.465012) (xy 347.570122 -412.465433) (xy 347.624079 -412.473186)
			(xy 347.676384 -412.48854) (xy 347.725971 -412.511182) (xy 347.771831 -412.54065) (xy 347.81303 -412.576346)
			(xy 347.848729 -412.617542) (xy 347.878202 -412.663399) (xy 347.900848 -412.712984) (xy 347.916207 -412.765287)
			(xy 347.923965 -412.819244) (xy 347.923965 -412.873752) (xy 349.361475 -412.873752) (xy 349.361475 -412.819248)
			(xy 349.369232 -412.7653) (xy 349.384588 -412.713004) (xy 349.407229 -412.663426) (xy 349.436696 -412.617575)
			(xy 349.472389 -412.576384) (xy 349.51358 -412.540693) (xy 349.559431 -412.511226) (xy 349.60901 -412.488585)
			(xy 349.661306 -412.473231) (xy 349.715254 -412.465475) (xy 349.742506 -412.465012) (xy 350.606106 -412.465012)
			(xy 350.633358 -412.465458) (xy 350.687308 -412.473216) (xy 350.739605 -412.488572) (xy 350.789184 -412.511215)
			(xy 350.835036 -412.540683) (xy 350.876228 -412.576376) (xy 350.911921 -412.617569) (xy 350.941388 -412.663421)
			(xy 350.96403 -412.713001) (xy 350.979385 -412.765298) (xy 350.987142 -412.819248) (xy 350.987142 -412.873752)
			(xy 370.513075 -412.873752) (xy 370.513075 -412.819248) (xy 370.520832 -412.7653) (xy 370.536187 -412.713005)
			(xy 370.558829 -412.663427) (xy 370.588295 -412.617576) (xy 370.623987 -412.576386) (xy 370.665178 -412.540694)
			(xy 370.711029 -412.511228) (xy 370.760607 -412.488587) (xy 370.812902 -412.473231) (xy 370.86685 -412.465475)
			(xy 370.894102 -412.465012) (xy 371.757702 -412.465012) (xy 371.784955 -412.465458) (xy 371.838905 -412.473215)
			(xy 371.891202 -412.488571) (xy 371.940782 -412.511214) (xy 371.986634 -412.540682) (xy 372.027826 -412.576375)
			(xy 372.06352 -412.617567) (xy 372.092987 -412.66342) (xy 372.115629 -412.713) (xy 372.130985 -412.765297)
			(xy 372.138742 -412.819247) (xy 372.138742 -412.873753) (xy 373.576275 -412.873753) (xy 373.576275 -412.819247)
			(xy 373.584033 -412.765295) (xy 373.59939 -412.712996) (xy 373.622035 -412.663416) (xy 373.651505 -412.617563)
			(xy 373.687201 -412.576372) (xy 373.728397 -412.54068) (xy 373.774253 -412.511215) (xy 373.823836 -412.488576)
			(xy 373.876136 -412.473224) (xy 373.930089 -412.465472) (xy 373.957342 -412.465012) (xy 374.820942 -412.465012)
			(xy 374.848193 -412.465461) (xy 374.902139 -412.473222) (xy 374.954431 -412.488582) (xy 375.004006 -412.511227)
			(xy 375.049853 -412.540696) (xy 375.091041 -412.576389) (xy 375.126729 -412.61758) (xy 375.156193 -412.663431)
			(xy 375.178833 -412.713008) (xy 375.194186 -412.765302) (xy 375.201942 -412.819249) (xy 375.201942 -412.873749)
			(xy 376.639598 -412.873749) (xy 376.639598 -412.819251) (xy 376.647354 -412.765308) (xy 376.662707 -412.713017)
			(xy 376.685346 -412.663444) (xy 376.714809 -412.617597) (xy 376.750497 -412.576409) (xy 376.791682 -412.54072)
			(xy 376.837528 -412.511254) (xy 376.8871 -412.488613) (xy 376.93939 -412.473258) (xy 376.993333 -412.465499)
			(xy 377.020582 -412.465012) (xy 377.884182 -412.465012) (xy 377.911437 -412.465434) (xy 377.965393 -412.473189)
			(xy 378.017696 -412.488544) (xy 378.067281 -412.511187) (xy 378.113139 -412.540656) (xy 378.154336 -412.576352)
			(xy 378.190033 -412.617547) (xy 378.219504 -412.663403) (xy 378.242149 -412.712987) (xy 378.257507 -412.765289)
			(xy 378.265265 -412.819245) (xy 378.265265 -412.873752) (xy 379.702775 -412.873752) (xy 379.702775 -412.819248)
			(xy 379.710532 -412.765298) (xy 379.725889 -412.713001) (xy 379.748532 -412.663422) (xy 379.778 -412.61757)
			(xy 379.813694 -412.576379) (xy 379.854888 -412.540687) (xy 379.900741 -412.511221) (xy 379.950321 -412.488581)
			(xy 380.002619 -412.473228) (xy 380.05657 -412.465474) (xy 380.083822 -412.465012) (xy 380.947422 -412.465012)
			(xy 380.974674 -412.465459) (xy 381.028622 -412.473219) (xy 381.080917 -412.488577) (xy 381.130494 -412.51122)
			(xy 381.176344 -412.540689) (xy 381.217534 -412.576382) (xy 381.253225 -412.617574) (xy 381.28269 -412.663426)
			(xy 381.305331 -412.713004) (xy 381.320686 -412.7653) (xy 381.328442 -412.819248) (xy 381.328442 -412.873748)
			(xy 382.766098 -412.873748) (xy 382.766098 -412.819252) (xy 382.773853 -412.76531) (xy 382.789206 -412.713022)
			(xy 382.811843 -412.663449) (xy 382.841304 -412.617603) (xy 382.876989 -412.576416) (xy 382.918173 -412.540727)
			(xy 382.964016 -412.511261) (xy 383.013586 -412.488619) (xy 383.065873 -412.473261) (xy 383.119814 -412.465501)
			(xy 383.147062 -412.465012) (xy 384.010662 -412.465012) (xy 384.037918 -412.465432) (xy 384.091876 -412.473185)
			(xy 384.144181 -412.488539) (xy 384.193769 -412.51118) (xy 384.239629 -412.540649) (xy 384.280829 -412.576345)
			(xy 384.316528 -412.61754) (xy 384.346001 -412.663398) (xy 384.368648 -412.712983) (xy 384.384007 -412.765287)
			(xy 384.391765 -412.819244) (xy 384.391765 -412.873752) (xy 385.829275 -412.873752) (xy 385.829275 -412.819248)
			(xy 385.837032 -412.7653) (xy 385.852387 -412.713005) (xy 385.875029 -412.663427) (xy 385.904495 -412.617576)
			(xy 385.940187 -412.576386) (xy 385.981378 -412.540694) (xy 386.027229 -412.511228) (xy 386.076807 -412.488587)
			(xy 386.129102 -412.473231) (xy 386.18305 -412.465475) (xy 386.210302 -412.465012) (xy 387.073902 -412.465012)
			(xy 387.101155 -412.465458) (xy 387.155105 -412.473215) (xy 387.207402 -412.488571) (xy 387.256982 -412.511214)
			(xy 387.302834 -412.540682) (xy 387.344026 -412.576375) (xy 387.37972 -412.617567) (xy 387.409187 -412.66342)
			(xy 387.431829 -412.713) (xy 387.447185 -412.765297) (xy 387.454942 -412.819247) (xy 387.454942 -412.873753)
			(xy 388.892475 -412.873753) (xy 388.892475 -412.819247) (xy 388.900233 -412.765295) (xy 388.91559 -412.712996)
			(xy 388.938235 -412.663416) (xy 388.967705 -412.617563) (xy 389.003401 -412.576372) (xy 389.044597 -412.54068)
			(xy 389.090453 -412.511215) (xy 389.140036 -412.488576) (xy 389.192336 -412.473224) (xy 389.246289 -412.465472)
			(xy 389.273542 -412.465012) (xy 390.137142 -412.465012) (xy 390.164393 -412.465461) (xy 390.218339 -412.473222)
			(xy 390.270631 -412.488582) (xy 390.320206 -412.511227) (xy 390.366053 -412.540696) (xy 390.407241 -412.576389)
			(xy 390.442929 -412.61758) (xy 390.472393 -412.663431) (xy 390.495033 -412.713008) (xy 390.510386 -412.765302)
			(xy 390.518142 -412.819249) (xy 390.518142 -412.873749) (xy 391.955798 -412.873749) (xy 391.955798 -412.819251)
			(xy 391.963554 -412.765308) (xy 391.978907 -412.713017) (xy 392.001546 -412.663444) (xy 392.031009 -412.617597)
			(xy 392.066697 -412.576409) (xy 392.107882 -412.54072) (xy 392.153728 -412.511254) (xy 392.2033 -412.488613)
			(xy 392.25559 -412.473258) (xy 392.309533 -412.465499) (xy 392.336782 -412.465012) (xy 393.200382 -412.465012)
			(xy 393.227637 -412.465434) (xy 393.281593 -412.473189) (xy 393.333896 -412.488544) (xy 393.383481 -412.511187)
			(xy 393.429339 -412.540656) (xy 393.470536 -412.576352) (xy 393.506233 -412.617547) (xy 393.535704 -412.663403)
			(xy 393.558349 -412.712987) (xy 393.573707 -412.765289) (xy 393.581465 -412.819245) (xy 393.581465 -412.873752)
			(xy 395.018975 -412.873752) (xy 395.018975 -412.819248) (xy 395.026732 -412.765298) (xy 395.042089 -412.713001)
			(xy 395.064732 -412.663422) (xy 395.0942 -412.61757) (xy 395.129894 -412.576379) (xy 395.171088 -412.540687)
			(xy 395.216941 -412.511221) (xy 395.266521 -412.488581) (xy 395.318819 -412.473228) (xy 395.37277 -412.465474)
			(xy 395.400022 -412.465012) (xy 396.263622 -412.465012) (xy 396.290874 -412.465459) (xy 396.344822 -412.473219)
			(xy 396.397117 -412.488577) (xy 396.446694 -412.51122) (xy 396.492544 -412.540689) (xy 396.533734 -412.576382)
			(xy 396.569425 -412.617574) (xy 396.59889 -412.663426) (xy 396.621531 -412.713004) (xy 396.636886 -412.7653)
			(xy 396.644642 -412.819248) (xy 396.644642 -412.873748) (xy 398.082298 -412.873748) (xy 398.082298 -412.819252)
			(xy 398.090053 -412.76531) (xy 398.105406 -412.713022) (xy 398.128043 -412.663449) (xy 398.157504 -412.617603)
			(xy 398.193189 -412.576416) (xy 398.234373 -412.540727) (xy 398.280216 -412.511261) (xy 398.329786 -412.488619)
			(xy 398.382073 -412.473261) (xy 398.436014 -412.465501) (xy 398.463262 -412.465012) (xy 399.326862 -412.465012)
			(xy 399.354118 -412.465432) (xy 399.408076 -412.473185) (xy 399.460381 -412.488539) (xy 399.509969 -412.51118)
			(xy 399.555829 -412.540649) (xy 399.597029 -412.576345) (xy 399.632728 -412.61754) (xy 399.662201 -412.663398)
			(xy 399.684848 -412.712983) (xy 399.700207 -412.765287) (xy 399.707965 -412.819244) (xy 399.707965 -412.873752)
			(xy 401.145475 -412.873752) (xy 401.145475 -412.819248) (xy 401.153232 -412.7653) (xy 401.168587 -412.713005)
			(xy 401.191229 -412.663427) (xy 401.220695 -412.617576) (xy 401.256387 -412.576386) (xy 401.297578 -412.540694)
			(xy 401.343429 -412.511228) (xy 401.393007 -412.488587) (xy 401.445302 -412.473231) (xy 401.49925 -412.465475)
			(xy 401.526502 -412.465012) (xy 402.390102 -412.465012) (xy 402.417355 -412.465458) (xy 402.471305 -412.473215)
			(xy 402.523602 -412.488571) (xy 402.573182 -412.511214) (xy 402.619034 -412.540682) (xy 402.660226 -412.576375)
			(xy 402.69592 -412.617567) (xy 402.725387 -412.66342) (xy 402.748029 -412.713) (xy 402.763385 -412.765297)
			(xy 402.771142 -412.819247) (xy 402.771142 -412.873753) (xy 404.208675 -412.873753) (xy 404.208675 -412.819247)
			(xy 404.216433 -412.765295) (xy 404.23179 -412.712996) (xy 404.254435 -412.663416) (xy 404.283905 -412.617563)
			(xy 404.319601 -412.576372) (xy 404.360797 -412.54068) (xy 404.406653 -412.511215) (xy 404.456236 -412.488576)
			(xy 404.508536 -412.473224) (xy 404.562489 -412.465472) (xy 404.589742 -412.465012) (xy 405.453342 -412.465012)
			(xy 405.480593 -412.465461) (xy 405.534539 -412.473222) (xy 405.586831 -412.488582) (xy 405.636406 -412.511227)
			(xy 405.682253 -412.540696) (xy 405.723441 -412.576389) (xy 405.759129 -412.61758) (xy 405.788593 -412.663431)
			(xy 405.811233 -412.713008) (xy 405.826586 -412.765302) (xy 405.834342 -412.819249) (xy 405.834342 -412.873749)
			(xy 407.271998 -412.873749) (xy 407.271998 -412.819251) (xy 407.279754 -412.765308) (xy 407.295107 -412.713017)
			(xy 407.317746 -412.663444) (xy 407.347209 -412.617597) (xy 407.382897 -412.576409) (xy 407.424082 -412.54072)
			(xy 407.469928 -412.511254) (xy 407.5195 -412.488613) (xy 407.57179 -412.473258) (xy 407.625733 -412.465499)
			(xy 407.652982 -412.465012) (xy 408.516582 -412.465012) (xy 408.543837 -412.465434) (xy 408.597793 -412.473189)
			(xy 408.650096 -412.488544) (xy 408.699681 -412.511187) (xy 408.745539 -412.540656) (xy 408.786736 -412.576352)
			(xy 408.822433 -412.617547) (xy 408.851904 -412.663403) (xy 408.874549 -412.712987) (xy 408.889907 -412.765289)
			(xy 408.897665 -412.819245) (xy 408.897665 -412.873752) (xy 410.335175 -412.873752) (xy 410.335175 -412.819248)
			(xy 410.342932 -412.765298) (xy 410.358289 -412.713001) (xy 410.380932 -412.663422) (xy 410.4104 -412.61757)
			(xy 410.446094 -412.576379) (xy 410.487288 -412.540687) (xy 410.533141 -412.511221) (xy 410.582721 -412.488581)
			(xy 410.635019 -412.473228) (xy 410.68897 -412.465474) (xy 410.716222 -412.465012) (xy 411.579822 -412.465012)
			(xy 411.607074 -412.465459) (xy 411.661022 -412.473219) (xy 411.713317 -412.488577) (xy 411.762894 -412.51122)
			(xy 411.808744 -412.540689) (xy 411.849934 -412.576382) (xy 411.885625 -412.617574) (xy 411.91509 -412.663426)
			(xy 411.937731 -412.713004) (xy 411.953086 -412.7653) (xy 411.960842 -412.819248) (xy 411.960842 -412.873748)
			(xy 413.398498 -412.873748) (xy 413.398498 -412.819252) (xy 413.406253 -412.76531) (xy 413.421606 -412.713022)
			(xy 413.444243 -412.663449) (xy 413.473704 -412.617603) (xy 413.509389 -412.576416) (xy 413.550573 -412.540727)
			(xy 413.596416 -412.511261) (xy 413.645986 -412.488619) (xy 413.698273 -412.473261) (xy 413.752214 -412.465501)
			(xy 413.779462 -412.465012) (xy 414.643062 -412.465012) (xy 414.670318 -412.465432) (xy 414.724276 -412.473185)
			(xy 414.776581 -412.488539) (xy 414.826169 -412.51118) (xy 414.872029 -412.540649) (xy 414.913229 -412.576345)
			(xy 414.948928 -412.61754) (xy 414.978401 -412.663398) (xy 415.001048 -412.712983) (xy 415.016407 -412.765287)
			(xy 415.024165 -412.819244) (xy 415.024165 -412.873752) (xy 416.461675 -412.873752) (xy 416.461675 -412.819248)
			(xy 416.469432 -412.7653) (xy 416.484787 -412.713005) (xy 416.507429 -412.663427) (xy 416.536895 -412.617576)
			(xy 416.572587 -412.576386) (xy 416.613778 -412.540694) (xy 416.659629 -412.511228) (xy 416.709207 -412.488587)
			(xy 416.761502 -412.473231) (xy 416.81545 -412.465475) (xy 416.842702 -412.465012) (xy 417.706302 -412.465012)
			(xy 417.733555 -412.465458) (xy 417.787505 -412.473215) (xy 417.839802 -412.488571) (xy 417.889382 -412.511214)
			(xy 417.935234 -412.540682) (xy 417.976426 -412.576375) (xy 418.01212 -412.617567) (xy 418.041587 -412.66342)
			(xy 418.064229 -412.713) (xy 418.079585 -412.765297) (xy 418.087342 -412.819247) (xy 418.087342 -412.873753)
			(xy 418.079585 -412.927703) (xy 418.064229 -412.98) (xy 418.041587 -413.02958) (xy 418.01212 -413.075433)
			(xy 417.976426 -413.116625) (xy 417.935234 -413.152318) (xy 417.90754 -413.170116) (xy 422.998658 -413.170116)
			(xy 423.00263 -412.991873) (xy 423.014538 -412.813984) (xy 423.034359 -412.636802) (xy 423.062053 -412.460678)
			(xy 423.097565 -412.285963) (xy 423.140825 -412.113004) (xy 423.191747 -411.942143) (xy 423.25023 -411.773721)
			(xy 423.316157 -411.608071) (xy 423.389398 -411.445522) (xy 423.469808 -411.286397) (xy 423.557226 -411.131012)
			(xy 423.651479 -410.979676) (xy 423.75238 -410.832688) (xy 423.859729 -410.690341) (xy 423.973312 -410.552918)
			(xy 424.092905 -410.420691) (xy 424.218269 -410.293922) (xy 424.349156 -410.172864) (xy 424.485305 -410.057757)
			(xy 424.626447 -409.948829) (xy 424.772302 -409.846297) (xy 424.922579 -409.750363) (xy 425.07698 -409.66122)
			(xy 425.235199 -409.579043) (xy 425.396922 -409.503995) (xy 425.561827 -409.436227) (xy 425.729588 -409.375871)
			(xy 425.899871 -409.323049) (xy 426.072338 -409.277865) (xy 426.246646 -409.240408) (xy 426.42245 -409.210754)
			(xy 426.5994 -409.188961) (xy 426.777146 -409.175071) (xy 426.955333 -409.169114) (xy 427.13361 -409.1711)
			(xy 427.311621 -409.181026) (xy 427.489013 -409.198872) (xy 427.665433 -409.224602) (xy 427.840533 -409.258166)
			(xy 428.013964 -409.299496) (xy 428.185381 -409.348512) (xy 428.354444 -409.405114) (xy 428.520819 -409.469192)
			(xy 428.684173 -409.540618) (xy 428.844184 -409.61925) (xy 429.000533 -409.704931) (xy 429.15291 -409.797493)
			(xy 429.301013 -409.89675) (xy 429.444547 -410.002507) (xy 429.583227 -410.114552) (xy 429.716778 -410.232664)
			(xy 429.844935 -410.356608) (xy 429.967444 -410.486138) (xy 430.084061 -410.620997) (xy 430.194554 -410.760917)
			(xy 430.298705 -410.90562) (xy 430.396307 -411.054819) (xy 430.487165 -411.208218) (xy 430.571099 -411.365512)
			(xy 430.647944 -411.526388) (xy 430.717545 -411.690529) (xy 430.779766 -411.857606) (xy 430.834482 -412.02729)
			(xy 430.881584 -412.199243) (xy 430.92098 -412.373123) (xy 430.952591 -412.548586) (xy 430.976355 -412.725282)
			(xy 430.992223 -412.902862) (xy 431.000165 -413.080972) (xy 431.000662 -413.170116) (xy 431.000165 -413.25926)
			(xy 430.992223 -413.43737) (xy 430.976355 -413.61495) (xy 430.952591 -413.791646) (xy 430.92098 -413.967109)
			(xy 430.881584 -414.140989) (xy 430.834482 -414.312942) (xy 430.779766 -414.482626) (xy 430.717545 -414.649703)
			(xy 430.647944 -414.813844) (xy 430.571099 -414.97472) (xy 430.487165 -415.132014) (xy 430.396307 -415.285413)
			(xy 430.298705 -415.434612) (xy 430.194554 -415.579315) (xy 430.084061 -415.719235) (xy 429.967444 -415.854094)
			(xy 429.844935 -415.983624) (xy 429.716778 -416.107568) (xy 429.583227 -416.22568) (xy 429.444547 -416.337725)
			(xy 429.301013 -416.443482) (xy 429.15291 -416.542739) (xy 429.000533 -416.635301) (xy 428.844184 -416.720982)
			(xy 428.684173 -416.799614) (xy 428.520819 -416.87104) (xy 428.354444 -416.935118) (xy 428.185381 -416.99172)
			(xy 428.013964 -417.040736) (xy 427.840533 -417.082066) (xy 427.665433 -417.11563) (xy 427.489013 -417.14136)
			(xy 427.311621 -417.159206) (xy 427.13361 -417.169132) (xy 426.955333 -417.171118) (xy 426.777146 -417.165161)
			(xy 426.5994 -417.151271) (xy 426.42245 -417.129478) (xy 426.246646 -417.099824) (xy 426.072338 -417.062367)
			(xy 425.899871 -417.017183) (xy 425.729588 -416.964361) (xy 425.561827 -416.904005) (xy 425.396922 -416.836237)
			(xy 425.235199 -416.761189) (xy 425.07698 -416.679012) (xy 424.922579 -416.589869) (xy 424.772302 -416.493935)
			(xy 424.626447 -416.391403) (xy 424.485305 -416.282475) (xy 424.349156 -416.167368) (xy 424.218269 -416.04631)
			(xy 424.092905 -415.919541) (xy 423.973312 -415.787314) (xy 423.859729 -415.649891) (xy 423.75238 -415.507544)
			(xy 423.651479 -415.360556) (xy 423.557226 -415.20922) (xy 423.469808 -415.053835) (xy 423.389398 -414.89471)
			(xy 423.316157 -414.732161) (xy 423.25023 -414.566511) (xy 423.191747 -414.398089) (xy 423.140825 -414.227228)
			(xy 423.097565 -414.054269) (xy 423.062053 -413.879554) (xy 423.034359 -413.70343) (xy 423.014538 -413.526248)
			(xy 423.00263 -413.348359) (xy 422.998658 -413.170116) (xy 417.90754 -413.170116) (xy 417.889382 -413.181786)
			(xy 417.839802 -413.204429) (xy 417.787505 -413.219785) (xy 417.733555 -413.227542) (xy 417.706302 -413.228028)
			(xy 416.842702 -413.228028) (xy 416.81545 -413.227525) (xy 416.761502 -413.219769) (xy 416.709207 -413.204413)
			(xy 416.659629 -413.181772) (xy 416.613778 -413.152306) (xy 416.572587 -413.116614) (xy 416.536895 -413.075424)
			(xy 416.507429 -413.029573) (xy 416.484787 -412.979995) (xy 416.469432 -412.9277) (xy 416.461675 -412.873752)
			(xy 415.024165 -412.873752) (xy 415.024165 -412.873756) (xy 415.016407 -412.927713) (xy 415.001048 -412.980017)
			(xy 414.978401 -413.029602) (xy 414.948928 -413.07546) (xy 414.913229 -413.116655) (xy 414.872029 -413.152351)
			(xy 414.826169 -413.18182) (xy 414.776581 -413.204461) (xy 414.724276 -413.219815) (xy 414.670318 -413.227568)
			(xy 414.643062 -413.228028) (xy 413.779462 -413.228028) (xy 413.752214 -413.227499) (xy 413.698273 -413.219739)
			(xy 413.645986 -413.204381) (xy 413.596416 -413.181739) (xy 413.550573 -413.152273) (xy 413.509389 -413.116584)
			(xy 413.473704 -413.075397) (xy 413.444243 -413.029551) (xy 413.421606 -412.979978) (xy 413.406253 -412.92769)
			(xy 413.398498 -412.873748) (xy 411.960842 -412.873748) (xy 411.960842 -412.873752) (xy 411.953086 -412.9277)
			(xy 411.937731 -412.979996) (xy 411.91509 -413.029574) (xy 411.885625 -413.075426) (xy 411.849934 -413.116618)
			(xy 411.808744 -413.152311) (xy 411.762894 -413.18178) (xy 411.713317 -413.204423) (xy 411.661022 -413.219781)
			(xy 411.607074 -413.227541) (xy 411.579822 -413.228028) (xy 410.716222 -413.228028) (xy 410.68897 -413.227526)
			(xy 410.635019 -413.219772) (xy 410.582721 -413.204419) (xy 410.533141 -413.181779) (xy 410.487288 -413.152313)
			(xy 410.446094 -413.116621) (xy 410.4104 -413.07543) (xy 410.380932 -413.029578) (xy 410.358289 -412.979999)
			(xy 410.342932 -412.927702) (xy 410.335175 -412.873752) (xy 408.897665 -412.873752) (xy 408.897665 -412.873755)
			(xy 408.889907 -412.927711) (xy 408.874549 -412.980013) (xy 408.851904 -413.029597) (xy 408.822433 -413.075453)
			(xy 408.786736 -413.116648) (xy 408.745539 -413.152344) (xy 408.699681 -413.181813) (xy 408.650096 -413.204456)
			(xy 408.597793 -413.219811) (xy 408.543837 -413.227566) (xy 408.516582 -413.228028) (xy 407.652982 -413.228028)
			(xy 407.625733 -413.227501) (xy 407.57179 -413.219742) (xy 407.5195 -413.204387) (xy 407.469928 -413.181746)
			(xy 407.424082 -413.15228) (xy 407.382897 -413.116591) (xy 407.347209 -413.075403) (xy 407.317746 -413.029556)
			(xy 407.295107 -412.979983) (xy 407.279754 -412.927692) (xy 407.271998 -412.873749) (xy 405.834342 -412.873749)
			(xy 405.834342 -412.873751) (xy 405.826586 -412.927698) (xy 405.811233 -412.979992) (xy 405.788593 -413.029569)
			(xy 405.759129 -413.07542) (xy 405.723441 -413.116611) (xy 405.682253 -413.152304) (xy 405.636406 -413.181773)
			(xy 405.586831 -413.204418) (xy 405.534539 -413.219778) (xy 405.480593 -413.227539) (xy 405.453342 -413.228028)
			(xy 404.589742 -413.228028) (xy 404.562489 -413.227528) (xy 404.508536 -413.219776) (xy 404.456236 -413.204424)
			(xy 404.406653 -413.181785) (xy 404.360797 -413.15232) (xy 404.319601 -413.116628) (xy 404.283905 -413.075437)
			(xy 404.254435 -413.029584) (xy 404.23179 -412.980004) (xy 404.216433 -412.927705) (xy 404.208675 -412.873753)
			(xy 402.771142 -412.873753) (xy 402.763385 -412.927703) (xy 402.748029 -412.98) (xy 402.725387 -413.02958)
			(xy 402.69592 -413.075433) (xy 402.660226 -413.116625) (xy 402.619034 -413.152318) (xy 402.573182 -413.181786)
			(xy 402.523602 -413.204429) (xy 402.471305 -413.219785) (xy 402.417355 -413.227542) (xy 402.390102 -413.228028)
			(xy 401.526502 -413.228028) (xy 401.49925 -413.227525) (xy 401.445302 -413.219769) (xy 401.393007 -413.204413)
			(xy 401.343429 -413.181772) (xy 401.297578 -413.152306) (xy 401.256387 -413.116614) (xy 401.220695 -413.075424)
			(xy 401.191229 -413.029573) (xy 401.168587 -412.979995) (xy 401.153232 -412.9277) (xy 401.145475 -412.873752)
			(xy 399.707965 -412.873752) (xy 399.707965 -412.873756) (xy 399.700207 -412.927713) (xy 399.684848 -412.980017)
			(xy 399.662201 -413.029602) (xy 399.632728 -413.07546) (xy 399.597029 -413.116655) (xy 399.555829 -413.152351)
			(xy 399.509969 -413.18182) (xy 399.460381 -413.204461) (xy 399.408076 -413.219815) (xy 399.354118 -413.227568)
			(xy 399.326862 -413.228028) (xy 398.463262 -413.228028) (xy 398.436014 -413.227499) (xy 398.382073 -413.219739)
			(xy 398.329786 -413.204381) (xy 398.280216 -413.181739) (xy 398.234373 -413.152273) (xy 398.193189 -413.116584)
			(xy 398.157504 -413.075397) (xy 398.128043 -413.029551) (xy 398.105406 -412.979978) (xy 398.090053 -412.92769)
			(xy 398.082298 -412.873748) (xy 396.644642 -412.873748) (xy 396.644642 -412.873752) (xy 396.636886 -412.9277)
			(xy 396.621531 -412.979996) (xy 396.59889 -413.029574) (xy 396.569425 -413.075426) (xy 396.533734 -413.116618)
			(xy 396.492544 -413.152311) (xy 396.446694 -413.18178) (xy 396.397117 -413.204423) (xy 396.344822 -413.219781)
			(xy 396.290874 -413.227541) (xy 396.263622 -413.228028) (xy 395.400022 -413.228028) (xy 395.37277 -413.227526)
			(xy 395.318819 -413.219772) (xy 395.266521 -413.204419) (xy 395.216941 -413.181779) (xy 395.171088 -413.152313)
			(xy 395.129894 -413.116621) (xy 395.0942 -413.07543) (xy 395.064732 -413.029578) (xy 395.042089 -412.979999)
			(xy 395.026732 -412.927702) (xy 395.018975 -412.873752) (xy 393.581465 -412.873752) (xy 393.581465 -412.873755)
			(xy 393.573707 -412.927711) (xy 393.558349 -412.980013) (xy 393.535704 -413.029597) (xy 393.506233 -413.075453)
			(xy 393.470536 -413.116648) (xy 393.429339 -413.152344) (xy 393.383481 -413.181813) (xy 393.333896 -413.204456)
			(xy 393.281593 -413.219811) (xy 393.227637 -413.227566) (xy 393.200382 -413.228028) (xy 392.336782 -413.228028)
			(xy 392.309533 -413.227501) (xy 392.25559 -413.219742) (xy 392.2033 -413.204387) (xy 392.153728 -413.181746)
			(xy 392.107882 -413.15228) (xy 392.066697 -413.116591) (xy 392.031009 -413.075403) (xy 392.001546 -413.029556)
			(xy 391.978907 -412.979983) (xy 391.963554 -412.927692) (xy 391.955798 -412.873749) (xy 390.518142 -412.873749)
			(xy 390.518142 -412.873751) (xy 390.510386 -412.927698) (xy 390.495033 -412.979992) (xy 390.472393 -413.029569)
			(xy 390.442929 -413.07542) (xy 390.407241 -413.116611) (xy 390.366053 -413.152304) (xy 390.320206 -413.181773)
			(xy 390.270631 -413.204418) (xy 390.218339 -413.219778) (xy 390.164393 -413.227539) (xy 390.137142 -413.228028)
			(xy 389.273542 -413.228028) (xy 389.246289 -413.227528) (xy 389.192336 -413.219776) (xy 389.140036 -413.204424)
			(xy 389.090453 -413.181785) (xy 389.044597 -413.15232) (xy 389.003401 -413.116628) (xy 388.967705 -413.075437)
			(xy 388.938235 -413.029584) (xy 388.91559 -412.980004) (xy 388.900233 -412.927705) (xy 388.892475 -412.873753)
			(xy 387.454942 -412.873753) (xy 387.447185 -412.927703) (xy 387.431829 -412.98) (xy 387.409187 -413.02958)
			(xy 387.37972 -413.075433) (xy 387.344026 -413.116625) (xy 387.302834 -413.152318) (xy 387.256982 -413.181786)
			(xy 387.207402 -413.204429) (xy 387.155105 -413.219785) (xy 387.101155 -413.227542) (xy 387.073902 -413.228028)
			(xy 386.210302 -413.228028) (xy 386.18305 -413.227525) (xy 386.129102 -413.219769) (xy 386.076807 -413.204413)
			(xy 386.027229 -413.181772) (xy 385.981378 -413.152306) (xy 385.940187 -413.116614) (xy 385.904495 -413.075424)
			(xy 385.875029 -413.029573) (xy 385.852387 -412.979995) (xy 385.837032 -412.9277) (xy 385.829275 -412.873752)
			(xy 384.391765 -412.873752) (xy 384.391765 -412.873756) (xy 384.384007 -412.927713) (xy 384.368648 -412.980017)
			(xy 384.346001 -413.029602) (xy 384.316528 -413.07546) (xy 384.280829 -413.116655) (xy 384.239629 -413.152351)
			(xy 384.193769 -413.18182) (xy 384.144181 -413.204461) (xy 384.091876 -413.219815) (xy 384.037918 -413.227568)
			(xy 384.010662 -413.228028) (xy 383.147062 -413.228028) (xy 383.119814 -413.227499) (xy 383.065873 -413.219739)
			(xy 383.013586 -413.204381) (xy 382.964016 -413.181739) (xy 382.918173 -413.152273) (xy 382.876989 -413.116584)
			(xy 382.841304 -413.075397) (xy 382.811843 -413.029551) (xy 382.789206 -412.979978) (xy 382.773853 -412.92769)
			(xy 382.766098 -412.873748) (xy 381.328442 -412.873748) (xy 381.328442 -412.873752) (xy 381.320686 -412.9277)
			(xy 381.305331 -412.979996) (xy 381.28269 -413.029574) (xy 381.253225 -413.075426) (xy 381.217534 -413.116618)
			(xy 381.176344 -413.152311) (xy 381.130494 -413.18178) (xy 381.080917 -413.204423) (xy 381.028622 -413.219781)
			(xy 380.974674 -413.227541) (xy 380.947422 -413.228028) (xy 380.083822 -413.228028) (xy 380.05657 -413.227526)
			(xy 380.002619 -413.219772) (xy 379.950321 -413.204419) (xy 379.900741 -413.181779) (xy 379.854888 -413.152313)
			(xy 379.813694 -413.116621) (xy 379.778 -413.07543) (xy 379.748532 -413.029578) (xy 379.725889 -412.979999)
			(xy 379.710532 -412.927702) (xy 379.702775 -412.873752) (xy 378.265265 -412.873752) (xy 378.265265 -412.873755)
			(xy 378.257507 -412.927711) (xy 378.242149 -412.980013) (xy 378.219504 -413.029597) (xy 378.190033 -413.075453)
			(xy 378.154336 -413.116648) (xy 378.113139 -413.152344) (xy 378.067281 -413.181813) (xy 378.017696 -413.204456)
			(xy 377.965393 -413.219811) (xy 377.911437 -413.227566) (xy 377.884182 -413.228028) (xy 377.020582 -413.228028)
			(xy 376.993333 -413.227501) (xy 376.93939 -413.219742) (xy 376.8871 -413.204387) (xy 376.837528 -413.181746)
			(xy 376.791682 -413.15228) (xy 376.750497 -413.116591) (xy 376.714809 -413.075403) (xy 376.685346 -413.029556)
			(xy 376.662707 -412.979983) (xy 376.647354 -412.927692) (xy 376.639598 -412.873749) (xy 375.201942 -412.873749)
			(xy 375.201942 -412.873751) (xy 375.194186 -412.927698) (xy 375.178833 -412.979992) (xy 375.156193 -413.029569)
			(xy 375.126729 -413.07542) (xy 375.091041 -413.116611) (xy 375.049853 -413.152304) (xy 375.004006 -413.181773)
			(xy 374.954431 -413.204418) (xy 374.902139 -413.219778) (xy 374.848193 -413.227539) (xy 374.820942 -413.228028)
			(xy 373.957342 -413.228028) (xy 373.930089 -413.227528) (xy 373.876136 -413.219776) (xy 373.823836 -413.204424)
			(xy 373.774253 -413.181785) (xy 373.728397 -413.15232) (xy 373.687201 -413.116628) (xy 373.651505 -413.075437)
			(xy 373.622035 -413.029584) (xy 373.59939 -412.980004) (xy 373.584033 -412.927705) (xy 373.576275 -412.873753)
			(xy 372.138742 -412.873753) (xy 372.130985 -412.927703) (xy 372.115629 -412.98) (xy 372.092987 -413.02958)
			(xy 372.06352 -413.075433) (xy 372.027826 -413.116625) (xy 371.986634 -413.152318) (xy 371.940782 -413.181786)
			(xy 371.891202 -413.204429) (xy 371.838905 -413.219785) (xy 371.784955 -413.227542) (xy 371.757702 -413.228028)
			(xy 370.894102 -413.228028) (xy 370.86685 -413.227525) (xy 370.812902 -413.219769) (xy 370.760607 -413.204413)
			(xy 370.711029 -413.181772) (xy 370.665178 -413.152306) (xy 370.623987 -413.116614) (xy 370.588295 -413.075424)
			(xy 370.558829 -413.029573) (xy 370.536187 -412.979995) (xy 370.520832 -412.9277) (xy 370.513075 -412.873752)
			(xy 350.987142 -412.873752) (xy 350.979385 -412.927702) (xy 350.96403 -412.979999) (xy 350.941388 -413.029579)
			(xy 350.911921 -413.075431) (xy 350.876228 -413.116624) (xy 350.835036 -413.152317) (xy 350.789184 -413.181785)
			(xy 350.739605 -413.204428) (xy 350.687308 -413.219784) (xy 350.633358 -413.227542) (xy 350.606106 -413.228028)
			(xy 349.742506 -413.228028) (xy 349.715254 -413.227525) (xy 349.661306 -413.219769) (xy 349.60901 -413.204415)
			(xy 349.559431 -413.181774) (xy 349.51358 -413.152307) (xy 349.472389 -413.116616) (xy 349.436696 -413.075425)
			(xy 349.407229 -413.029574) (xy 349.384588 -412.979996) (xy 349.369232 -412.9277) (xy 349.361475 -412.873752)
			(xy 347.923965 -412.873752) (xy 347.923965 -412.873756) (xy 347.916207 -412.927713) (xy 347.900848 -412.980016)
			(xy 347.878202 -413.029601) (xy 347.848729 -413.075458) (xy 347.81303 -413.116654) (xy 347.771831 -413.15235)
			(xy 347.725971 -413.181818) (xy 347.676384 -413.20446) (xy 347.624079 -413.219814) (xy 347.570122 -413.227567)
			(xy 347.542866 -413.228028) (xy 346.679266 -413.228028) (xy 346.652018 -413.227499) (xy 346.598077 -413.219739)
			(xy 346.545789 -413.204382) (xy 346.496218 -413.18174) (xy 346.450375 -413.152275) (xy 346.409191 -413.116585)
			(xy 346.373505 -413.075398) (xy 346.344043 -413.029552) (xy 346.321406 -412.979979) (xy 346.306053 -412.92769)
			(xy 346.298298 -412.873748) (xy 344.860642 -412.873748) (xy 344.860642 -412.873751) (xy 344.852886 -412.9277)
			(xy 344.837531 -412.979995) (xy 344.814891 -413.029573) (xy 344.785426 -413.075425) (xy 344.749735 -413.116617)
			(xy 344.708546 -413.15231) (xy 344.662696 -413.181778) (xy 344.61312 -413.204422) (xy 344.560825 -413.21978)
			(xy 344.506877 -413.22754) (xy 344.479626 -413.228028) (xy 343.616026 -413.228028) (xy 343.588773 -413.227526)
			(xy 343.534822 -413.219773) (xy 343.482524 -413.20442) (xy 343.432943 -413.18178) (xy 343.387089 -413.152314)
			(xy 343.345896 -413.116623) (xy 343.310201 -413.075431) (xy 343.280732 -413.029579) (xy 343.258089 -412.98)
			(xy 343.242733 -412.927703) (xy 343.234975 -412.873753) (xy 341.797465 -412.873753) (xy 341.797465 -412.873755)
			(xy 341.789707 -412.92771) (xy 341.77435 -412.980012) (xy 341.751705 -413.029595) (xy 341.722234 -413.075452)
			(xy 341.686537 -413.116647) (xy 341.645341 -413.152343) (xy 341.599483 -413.181812) (xy 341.549899 -413.204455)
			(xy 341.497596 -413.21981) (xy 341.443641 -413.227566) (xy 341.416386 -413.228028) (xy 340.552786 -413.228028)
			(xy 340.525537 -413.227501) (xy 340.471594 -413.219743) (xy 340.419303 -413.204388) (xy 340.36973 -413.181747)
			(xy 340.323884 -413.152282) (xy 340.282698 -413.116592) (xy 340.24701 -413.075404) (xy 340.217546 -413.029557)
			(xy 340.194908 -412.979984) (xy 340.179554 -412.927693) (xy 340.171798 -412.873749) (xy 338.734142 -412.873749)
			(xy 338.734142 -412.873751) (xy 338.726387 -412.927697) (xy 338.711033 -412.979991) (xy 338.688394 -413.029568)
			(xy 338.65893 -413.075418) (xy 338.623242 -413.116609) (xy 338.582055 -413.152303) (xy 338.536208 -413.181772)
			(xy 338.486634 -413.204417) (xy 338.434342 -413.219777) (xy 338.380397 -413.227539) (xy 338.353146 -413.228028)
			(xy 337.489546 -413.228028) (xy 337.462292 -413.227528) (xy 337.408339 -413.219777) (xy 337.356039 -413.204425)
			(xy 337.306455 -413.181787) (xy 337.260599 -413.152321) (xy 337.219403 -413.11663) (xy 337.183706 -413.075438)
			(xy 337.154235 -413.029585) (xy 337.131591 -412.980004) (xy 337.116233 -412.927706) (xy 337.108475 -412.873754)
			(xy 335.670942 -412.873754) (xy 335.663185 -412.927702) (xy 335.64783 -412.979999) (xy 335.625188 -413.029579)
			(xy 335.595721 -413.075431) (xy 335.560028 -413.116624) (xy 335.518836 -413.152317) (xy 335.472984 -413.181785)
			(xy 335.423405 -413.204428) (xy 335.371108 -413.219784) (xy 335.317158 -413.227542) (xy 335.289906 -413.228028)
			(xy 334.426306 -413.228028) (xy 334.399054 -413.227525) (xy 334.345106 -413.219769) (xy 334.29281 -413.204415)
			(xy 334.243231 -413.181774) (xy 334.19738 -413.152307) (xy 334.156189 -413.116616) (xy 334.120496 -413.075425)
			(xy 334.091029 -413.029574) (xy 334.068388 -412.979996) (xy 334.053032 -412.9277) (xy 334.045275 -412.873752)
			(xy 332.607765 -412.873752) (xy 332.607765 -412.873756) (xy 332.600007 -412.927713) (xy 332.584648 -412.980016)
			(xy 332.562002 -413.029601) (xy 332.532529 -413.075458) (xy 332.49683 -413.116654) (xy 332.455631 -413.15235)
			(xy 332.409771 -413.181818) (xy 332.360184 -413.20446) (xy 332.307879 -413.219814) (xy 332.253922 -413.227567)
			(xy 332.226666 -413.228028) (xy 331.363066 -413.228028) (xy 331.335818 -413.227499) (xy 331.281877 -413.219739)
			(xy 331.229589 -413.204382) (xy 331.180018 -413.18174) (xy 331.134175 -413.152275) (xy 331.092991 -413.116585)
			(xy 331.057305 -413.075398) (xy 331.027843 -413.029552) (xy 331.005206 -412.979979) (xy 330.989853 -412.92769)
			(xy 330.982098 -412.873748) (xy 329.544442 -412.873748) (xy 329.544442 -412.873751) (xy 329.536686 -412.9277)
			(xy 329.521331 -412.979995) (xy 329.498691 -413.029573) (xy 329.469226 -413.075425) (xy 329.433535 -413.116617)
			(xy 329.392346 -413.15231) (xy 329.346496 -413.181778) (xy 329.29692 -413.204422) (xy 329.244625 -413.21978)
			(xy 329.190677 -413.22754) (xy 329.163426 -413.228028) (xy 328.299826 -413.228028) (xy 328.272573 -413.227526)
			(xy 328.218622 -413.219773) (xy 328.166324 -413.20442) (xy 328.116743 -413.18178) (xy 328.070889 -413.152314)
			(xy 328.029696 -413.116623) (xy 327.994001 -413.075431) (xy 327.964532 -413.029579) (xy 327.941889 -412.98)
			(xy 327.926533 -412.927703) (xy 327.918775 -412.873753) (xy 326.481265 -412.873753) (xy 326.481265 -412.873755)
			(xy 326.473507 -412.92771) (xy 326.45815 -412.980012) (xy 326.435505 -413.029595) (xy 326.406034 -413.075452)
			(xy 326.370337 -413.116647) (xy 326.329141 -413.152343) (xy 326.283283 -413.181812) (xy 326.233699 -413.204455)
			(xy 326.181396 -413.21981) (xy 326.127441 -413.227566) (xy 326.100186 -413.228028) (xy 325.236586 -413.228028)
			(xy 325.209337 -413.227501) (xy 325.155394 -413.219743) (xy 325.103103 -413.204388) (xy 325.05353 -413.181747)
			(xy 325.007684 -413.152282) (xy 324.966498 -413.116592) (xy 324.93081 -413.075404) (xy 324.901346 -413.029557)
			(xy 324.878708 -412.979984) (xy 324.863354 -412.927693) (xy 324.855598 -412.873749) (xy 323.417942 -412.873749)
			(xy 323.417942 -412.873751) (xy 323.410187 -412.927697) (xy 323.394833 -412.979991) (xy 323.372194 -413.029568)
			(xy 323.34273 -413.075418) (xy 323.307042 -413.116609) (xy 323.265855 -413.152303) (xy 323.220008 -413.181772)
			(xy 323.170434 -413.204417) (xy 323.118142 -413.219777) (xy 323.064197 -413.227539) (xy 323.036946 -413.228028)
			(xy 322.173346 -413.228028) (xy 322.146092 -413.227528) (xy 322.092139 -413.219777) (xy 322.039839 -413.204425)
			(xy 321.990255 -413.181787) (xy 321.944399 -413.152321) (xy 321.903203 -413.11663) (xy 321.867506 -413.075438)
			(xy 321.838035 -413.029585) (xy 321.815391 -412.980004) (xy 321.800033 -412.927706) (xy 321.792275 -412.873754)
			(xy 320.354742 -412.873754) (xy 320.346985 -412.927702) (xy 320.33163 -412.979999) (xy 320.308988 -413.029579)
			(xy 320.279521 -413.075431) (xy 320.243828 -413.116624) (xy 320.202636 -413.152317) (xy 320.156784 -413.181785)
			(xy 320.107205 -413.204428) (xy 320.054908 -413.219784) (xy 320.000958 -413.227542) (xy 319.973706 -413.228028)
			(xy 319.110106 -413.228028) (xy 319.082854 -413.227525) (xy 319.028906 -413.219769) (xy 318.97661 -413.204415)
			(xy 318.927031 -413.181774) (xy 318.88118 -413.152307) (xy 318.839989 -413.116616) (xy 318.804296 -413.075425)
			(xy 318.774829 -413.029574) (xy 318.752188 -412.979996) (xy 318.736832 -412.9277) (xy 318.729075 -412.873752)
			(xy 317.291565 -412.873752) (xy 317.291565 -412.873756) (xy 317.283807 -412.927713) (xy 317.268448 -412.980016)
			(xy 317.245802 -413.029601) (xy 317.216329 -413.075458) (xy 317.18063 -413.116654) (xy 317.139431 -413.15235)
			(xy 317.093571 -413.181818) (xy 317.043984 -413.20446) (xy 316.991679 -413.219814) (xy 316.937722 -413.227567)
			(xy 316.910466 -413.228028) (xy 316.046866 -413.228028) (xy 316.019618 -413.227499) (xy 315.965677 -413.219739)
			(xy 315.913389 -413.204382) (xy 315.863818 -413.18174) (xy 315.817975 -413.152275) (xy 315.776791 -413.116585)
			(xy 315.741105 -413.075398) (xy 315.711643 -413.029552) (xy 315.689006 -412.979979) (xy 315.673653 -412.92769)
			(xy 315.665898 -412.873748) (xy 314.228242 -412.873748) (xy 314.228242 -412.873751) (xy 314.220486 -412.9277)
			(xy 314.205131 -412.979995) (xy 314.182491 -413.029573) (xy 314.153026 -413.075425) (xy 314.117335 -413.116617)
			(xy 314.076146 -413.15231) (xy 314.030296 -413.181778) (xy 313.98072 -413.204422) (xy 313.928425 -413.21978)
			(xy 313.874477 -413.22754) (xy 313.847226 -413.228028) (xy 312.983626 -413.228028) (xy 312.956373 -413.227526)
			(xy 312.902422 -413.219773) (xy 312.850124 -413.20442) (xy 312.800543 -413.18178) (xy 312.754689 -413.152314)
			(xy 312.713496 -413.116623) (xy 312.677801 -413.075431) (xy 312.648332 -413.029579) (xy 312.625689 -412.98)
			(xy 312.610333 -412.927703) (xy 312.602575 -412.873753) (xy 311.165065 -412.873753) (xy 311.165065 -412.873755)
			(xy 311.157307 -412.92771) (xy 311.14195 -412.980012) (xy 311.119305 -413.029595) (xy 311.089834 -413.075452)
			(xy 311.054137 -413.116647) (xy 311.012941 -413.152343) (xy 310.967083 -413.181812) (xy 310.917499 -413.204455)
			(xy 310.865196 -413.21981) (xy 310.811241 -413.227566) (xy 310.783986 -413.228028) (xy 309.920386 -413.228028)
			(xy 309.893137 -413.227501) (xy 309.839194 -413.219743) (xy 309.786903 -413.204388) (xy 309.73733 -413.181747)
			(xy 309.691484 -413.152282) (xy 309.650298 -413.116592) (xy 309.61461 -413.075404) (xy 309.585146 -413.029557)
			(xy 309.562508 -412.979984) (xy 309.547154 -412.927693) (xy 309.539398 -412.873749) (xy 308.101742 -412.873749)
			(xy 308.101742 -412.873751) (xy 308.093987 -412.927697) (xy 308.078633 -412.979991) (xy 308.055994 -413.029568)
			(xy 308.02653 -413.075418) (xy 307.990842 -413.116609) (xy 307.949655 -413.152303) (xy 307.903808 -413.181772)
			(xy 307.854234 -413.204417) (xy 307.801942 -413.219777) (xy 307.747997 -413.227539) (xy 307.720746 -413.228028)
			(xy 306.857146 -413.228028) (xy 306.829892 -413.227528) (xy 306.775939 -413.219777) (xy 306.723639 -413.204425)
			(xy 306.674055 -413.181787) (xy 306.628199 -413.152321) (xy 306.587003 -413.11663) (xy 306.551306 -413.075438)
			(xy 306.521835 -413.029585) (xy 306.499191 -412.980004) (xy 306.483833 -412.927706) (xy 306.476075 -412.873754)
			(xy 305.038542 -412.873754) (xy 305.030785 -412.927702) (xy 305.01543 -412.979999) (xy 304.992788 -413.029579)
			(xy 304.963321 -413.075431) (xy 304.927628 -413.116624) (xy 304.886436 -413.152317) (xy 304.840584 -413.181785)
			(xy 304.791005 -413.204428) (xy 304.738708 -413.219784) (xy 304.684758 -413.227542) (xy 304.657506 -413.228028)
			(xy 303.793906 -413.228028) (xy 303.766654 -413.227525) (xy 303.712706 -413.219769) (xy 303.66041 -413.204415)
			(xy 303.610831 -413.181774) (xy 303.56498 -413.152307) (xy 303.523789 -413.116616) (xy 303.488096 -413.075425)
			(xy 303.458629 -413.029574) (xy 303.435988 -412.979996) (xy 303.420632 -412.9277) (xy 303.412875 -412.873752)
			(xy 301.559858 -412.873752) (xy 301.562459 -412.902862) (xy 301.570401 -413.080972) (xy 301.570898 -413.170116)
			(xy 301.570401 -413.25926) (xy 301.562459 -413.43737) (xy 301.546591 -413.61495) (xy 301.522827 -413.791646)
			(xy 301.491216 -413.967109) (xy 301.45182 -414.140989) (xy 301.404718 -414.312942) (xy 301.350002 -414.482626)
			(xy 301.287781 -414.649703) (xy 301.21818 -414.813844) (xy 301.141335 -414.97472) (xy 301.138725 -414.979612)
			(xy 370.574824 -414.979612) (xy 370.574824 -414.293558) (xy 370.575271 -414.281468) (xy 370.582738 -414.258469)
			(xy 370.59693 -414.238891) (xy 370.616466 -414.224641) (xy 370.639443 -414.217107) (xy 370.651532 -414.216596)
			(xy 370.846096 -414.216596) (xy 370.857219 -414.217035) (xy 370.878516 -414.223478) (xy 370.888006 -414.229296)
			(xy 371.18163 -414.421828) (xy 371.190989 -414.427575) (xy 371.212013 -414.433899) (xy 371.233968 -414.43396)
			(xy 371.255028 -414.427753) (xy 371.264434 -414.422082) (xy 371.560598 -414.229296) (xy 371.570098 -414.223499)
			(xy 371.591388 -414.217043) (xy 371.602508 -414.216596) (xy 371.797072 -414.216596) (xy 371.809154 -414.217037)
			(xy 371.832136 -414.224497) (xy 371.851687 -414.238696) (xy 371.865892 -414.258242) (xy 371.87336 -414.281222)
			(xy 371.87378 -414.293304) (xy 371.87378 -414.979358) (xy 371.873257 -414.991443) (xy 371.865815 -415.014439)
			(xy 371.851642 -415.034018) (xy 371.832121 -415.048271) (xy 371.809155 -415.055807) (xy 371.797072 -415.05632)
			(xy 371.602508 -415.05632) (xy 371.591383 -415.055892) (xy 371.570086 -415.049443) (xy 371.560598 -415.04362)
			(xy 371.265704 -414.851088) (xy 371.256317 -414.845385) (xy 371.235279 -414.839112) (xy 371.213325 -414.839112)
			(xy 371.192287 -414.845385) (xy 371.1829 -414.851088) (xy 370.889276 -415.04362) (xy 370.879782 -415.049429)
			(xy 370.858488 -415.055877) (xy 370.847366 -415.05632) (xy 370.651532 -415.05632) (xy 370.639452 -415.05586)
			(xy 370.616473 -415.048403) (xy 370.596923 -415.034209) (xy 370.582717 -415.014667) (xy 370.575247 -414.991692)
			(xy 370.574824 -414.979612) (xy 301.138725 -414.979612) (xy 301.057401 -415.132014) (xy 300.966543 -415.285413)
			(xy 300.882586 -415.413753) (xy 304.944475 -415.413753) (xy 304.944475 -415.359247) (xy 304.952233 -415.305297)
			(xy 304.967589 -415.253) (xy 304.990232 -415.203421) (xy 305.019701 -415.157569) (xy 305.055396 -415.116377)
			(xy 305.096589 -415.080686) (xy 305.142443 -415.05122) (xy 305.192024 -415.02858) (xy 305.244322 -415.013227)
			(xy 305.298273 -415.005474) (xy 305.325526 -415.005012) (xy 306.189126 -415.005012) (xy 306.216377 -415.00546)
			(xy 306.270325 -415.01322) (xy 306.32262 -415.028578) (xy 306.372196 -415.051222) (xy 306.418046 -415.08069)
			(xy 306.459235 -415.116383) (xy 306.494926 -415.157575) (xy 306.524391 -415.203427) (xy 306.547031 -415.253005)
			(xy 306.562386 -415.3053) (xy 306.570142 -415.359249) (xy 306.570142 -415.413748) (xy 308.007798 -415.413748)
			(xy 308.007798 -415.359252) (xy 308.015553 -415.30531) (xy 308.030906 -415.253021) (xy 308.053543 -415.203448)
			(xy 308.083005 -415.157602) (xy 308.118691 -415.116415) (xy 308.159875 -415.080725) (xy 308.205718 -415.05126)
			(xy 308.255289 -415.028618) (xy 308.307577 -415.013261) (xy 308.361518 -415.005501) (xy 308.388766 -415.005012)
			(xy 309.252366 -415.005012) (xy 309.279622 -415.005433) (xy 309.333579 -415.013186) (xy 309.385884 -415.02854)
			(xy 309.435471 -415.051182) (xy 309.481331 -415.08065) (xy 309.52253 -415.116346) (xy 309.558229 -415.157542)
			(xy 309.587702 -415.203399) (xy 309.610348 -415.252984) (xy 309.625707 -415.305287) (xy 309.633465 -415.359244)
			(xy 309.633465 -415.413752) (xy 311.070975 -415.413752) (xy 311.070975 -415.359248) (xy 311.078732 -415.3053)
			(xy 311.094088 -415.253004) (xy 311.116729 -415.203426) (xy 311.146196 -415.157575) (xy 311.181889 -415.116384)
			(xy 311.22308 -415.080693) (xy 311.268931 -415.051226) (xy 311.31851 -415.028585) (xy 311.370806 -415.013231)
			(xy 311.424754 -415.005475) (xy 311.452006 -415.005012) (xy 312.315606 -415.005012) (xy 312.342858 -415.005458)
			(xy 312.396808 -415.013216) (xy 312.449105 -415.028572) (xy 312.498684 -415.051215) (xy 312.544536 -415.080683)
			(xy 312.585728 -415.116376) (xy 312.621421 -415.157569) (xy 312.650888 -415.203421) (xy 312.67353 -415.253001)
			(xy 312.688885 -415.305298) (xy 312.696642 -415.359248) (xy 312.696642 -415.413752) (xy 312.696642 -415.413754)
			(xy 314.134175 -415.413754) (xy 314.134175 -415.359246) (xy 314.141933 -415.305294) (xy 314.157291 -415.252996)
			(xy 314.179935 -415.203415) (xy 314.209406 -415.157562) (xy 314.245103 -415.11637) (xy 314.286299 -415.080679)
			(xy 314.332155 -415.051213) (xy 314.381739 -415.028575) (xy 314.434039 -415.013223) (xy 314.487992 -415.005472)
			(xy 314.515246 -415.005012) (xy 315.378846 -415.005012) (xy 315.406097 -415.005461) (xy 315.460042 -415.013223)
			(xy 315.512334 -415.028583) (xy 315.561908 -415.051228) (xy 315.607755 -415.080697) (xy 315.648942 -415.116391)
			(xy 315.68463 -415.157582) (xy 315.714094 -415.203432) (xy 315.736733 -415.253009) (xy 315.752087 -415.305303)
			(xy 315.759842 -415.359249) (xy 315.759842 -415.413749) (xy 317.197498 -415.413749) (xy 317.197498 -415.359251)
			(xy 317.205254 -415.305307) (xy 317.220608 -415.253016) (xy 317.243246 -415.203443) (xy 317.27271 -415.157596)
			(xy 317.308398 -415.116408) (xy 317.349584 -415.080718) (xy 317.39543 -415.051253) (xy 317.445003 -415.028612)
			(xy 317.497294 -415.013257) (xy 317.551237 -415.005499) (xy 317.578486 -415.005012) (xy 318.442086 -415.005012)
			(xy 318.469341 -415.005434) (xy 318.523296 -415.01319) (xy 318.575599 -415.028545) (xy 318.625183 -415.051188)
			(xy 318.671041 -415.080657) (xy 318.712237 -415.116353) (xy 318.747934 -415.157548) (xy 318.777405 -415.203405)
			(xy 318.80005 -415.252988) (xy 318.815407 -415.30529) (xy 318.823165 -415.359245) (xy 318.823165 -415.413753)
			(xy 320.260675 -415.413753) (xy 320.260675 -415.359247) (xy 320.268433 -415.305297) (xy 320.283789 -415.253)
			(xy 320.306432 -415.203421) (xy 320.335901 -415.157569) (xy 320.371596 -415.116377) (xy 320.412789 -415.080686)
			(xy 320.458643 -415.05122) (xy 320.508224 -415.02858) (xy 320.560522 -415.013227) (xy 320.614473 -415.005474)
			(xy 320.641726 -415.005012) (xy 321.505326 -415.005012) (xy 321.532577 -415.00546) (xy 321.586525 -415.01322)
			(xy 321.63882 -415.028578) (xy 321.688396 -415.051222) (xy 321.734246 -415.08069) (xy 321.775435 -415.116383)
			(xy 321.811126 -415.157575) (xy 321.840591 -415.203427) (xy 321.863231 -415.253005) (xy 321.878586 -415.3053)
			(xy 321.886342 -415.359249) (xy 321.886342 -415.413748) (xy 323.323998 -415.413748) (xy 323.323998 -415.359252)
			(xy 323.331753 -415.30531) (xy 323.347106 -415.253021) (xy 323.369743 -415.203448) (xy 323.399205 -415.157602)
			(xy 323.434891 -415.116415) (xy 323.476075 -415.080725) (xy 323.521918 -415.05126) (xy 323.571489 -415.028618)
			(xy 323.623777 -415.013261) (xy 323.677718 -415.005501) (xy 323.704966 -415.005012) (xy 324.568566 -415.005012)
			(xy 324.595822 -415.005433) (xy 324.649779 -415.013186) (xy 324.702084 -415.02854) (xy 324.751671 -415.051182)
			(xy 324.797531 -415.08065) (xy 324.83873 -415.116346) (xy 324.874429 -415.157542) (xy 324.903902 -415.203399)
			(xy 324.926548 -415.252984) (xy 324.941907 -415.305287) (xy 324.949665 -415.359244) (xy 324.949665 -415.413752)
			(xy 326.387175 -415.413752) (xy 326.387175 -415.359248) (xy 326.394932 -415.3053) (xy 326.410288 -415.253004)
			(xy 326.432929 -415.203426) (xy 326.462396 -415.157575) (xy 326.498089 -415.116384) (xy 326.53928 -415.080693)
			(xy 326.585131 -415.051226) (xy 326.63471 -415.028585) (xy 326.687006 -415.013231) (xy 326.740954 -415.005475)
			(xy 326.768206 -415.005012) (xy 327.631806 -415.005012) (xy 327.659058 -415.005458) (xy 327.713008 -415.013216)
			(xy 327.765305 -415.028572) (xy 327.814884 -415.051215) (xy 327.860736 -415.080683) (xy 327.901928 -415.116376)
			(xy 327.937621 -415.157569) (xy 327.967088 -415.203421) (xy 327.98973 -415.253001) (xy 328.005085 -415.305298)
			(xy 328.012842 -415.359248) (xy 328.012842 -415.413752) (xy 328.012842 -415.413754) (xy 329.450375 -415.413754)
			(xy 329.450375 -415.359246) (xy 329.458133 -415.305294) (xy 329.473491 -415.252996) (xy 329.496135 -415.203415)
			(xy 329.525606 -415.157562) (xy 329.561303 -415.11637) (xy 329.602499 -415.080679) (xy 329.648355 -415.051213)
			(xy 329.697939 -415.028575) (xy 329.750239 -415.013223) (xy 329.804192 -415.005472) (xy 329.831446 -415.005012)
			(xy 330.695046 -415.005012) (xy 330.722297 -415.005461) (xy 330.776242 -415.013223) (xy 330.828534 -415.028583)
			(xy 330.878108 -415.051228) (xy 330.923955 -415.080697) (xy 330.965142 -415.116391) (xy 331.00083 -415.157582)
			(xy 331.030294 -415.203432) (xy 331.052933 -415.253009) (xy 331.068287 -415.305303) (xy 331.076042 -415.359249)
			(xy 331.076042 -415.413749) (xy 332.513698 -415.413749) (xy 332.513698 -415.359251) (xy 332.521454 -415.305307)
			(xy 332.536808 -415.253016) (xy 332.559446 -415.203443) (xy 332.58891 -415.157596) (xy 332.624598 -415.116408)
			(xy 332.665784 -415.080718) (xy 332.71163 -415.051253) (xy 332.761203 -415.028612) (xy 332.813494 -415.013257)
			(xy 332.867437 -415.005499) (xy 332.894686 -415.005012) (xy 333.758286 -415.005012) (xy 333.785541 -415.005434)
			(xy 333.839496 -415.01319) (xy 333.891799 -415.028545) (xy 333.941383 -415.051188) (xy 333.987241 -415.080657)
			(xy 334.028437 -415.116353) (xy 334.064134 -415.157548) (xy 334.093605 -415.203405) (xy 334.11625 -415.252988)
			(xy 334.131607 -415.30529) (xy 334.139365 -415.359245) (xy 334.139365 -415.413753) (xy 335.576875 -415.413753)
			(xy 335.576875 -415.359247) (xy 335.584633 -415.305297) (xy 335.599989 -415.253) (xy 335.622632 -415.203421)
			(xy 335.652101 -415.157569) (xy 335.687796 -415.116377) (xy 335.728989 -415.080686) (xy 335.774843 -415.05122)
			(xy 335.824424 -415.02858) (xy 335.876722 -415.013227) (xy 335.930673 -415.005474) (xy 335.957926 -415.005012)
			(xy 336.821526 -415.005012) (xy 336.848777 -415.00546) (xy 336.902725 -415.01322) (xy 336.95502 -415.028578)
			(xy 337.004596 -415.051222) (xy 337.050446 -415.08069) (xy 337.091635 -415.116383) (xy 337.127326 -415.157575)
			(xy 337.156791 -415.203427) (xy 337.179431 -415.253005) (xy 337.194786 -415.3053) (xy 337.202542 -415.359249)
			(xy 337.202542 -415.413748) (xy 338.640198 -415.413748) (xy 338.640198 -415.359252) (xy 338.647953 -415.30531)
			(xy 338.663306 -415.253021) (xy 338.685943 -415.203448) (xy 338.715405 -415.157602) (xy 338.751091 -415.116415)
			(xy 338.792275 -415.080725) (xy 338.838118 -415.05126) (xy 338.887689 -415.028618) (xy 338.939977 -415.013261)
			(xy 338.993918 -415.005501) (xy 339.021166 -415.005012) (xy 339.884766 -415.005012) (xy 339.912022 -415.005433)
			(xy 339.965979 -415.013186) (xy 340.018284 -415.02854) (xy 340.067871 -415.051182) (xy 340.113731 -415.08065)
			(xy 340.15493 -415.116346) (xy 340.190629 -415.157542) (xy 340.220102 -415.203399) (xy 340.242748 -415.252984)
			(xy 340.258107 -415.305287) (xy 340.265865 -415.359244) (xy 340.265865 -415.413752) (xy 341.703375 -415.413752)
			(xy 341.703375 -415.359248) (xy 341.711132 -415.3053) (xy 341.726488 -415.253004) (xy 341.749129 -415.203426)
			(xy 341.778596 -415.157575) (xy 341.814289 -415.116384) (xy 341.85548 -415.080693) (xy 341.901331 -415.051226)
			(xy 341.95091 -415.028585) (xy 342.003206 -415.013231) (xy 342.057154 -415.005475) (xy 342.084406 -415.005012)
			(xy 342.948006 -415.005012) (xy 342.975258 -415.005458) (xy 343.029208 -415.013216) (xy 343.081505 -415.028572)
			(xy 343.131084 -415.051215) (xy 343.176936 -415.080683) (xy 343.218128 -415.116376) (xy 343.253821 -415.157569)
			(xy 343.283288 -415.203421) (xy 343.30593 -415.253001) (xy 343.321285 -415.305298) (xy 343.329042 -415.359248)
			(xy 343.329042 -415.413752) (xy 343.329042 -415.413754) (xy 344.766575 -415.413754) (xy 344.766575 -415.359246)
			(xy 344.774333 -415.305294) (xy 344.789691 -415.252996) (xy 344.812335 -415.203415) (xy 344.841806 -415.157562)
			(xy 344.877503 -415.11637) (xy 344.918699 -415.080679) (xy 344.964555 -415.051213) (xy 345.014139 -415.028575)
			(xy 345.066439 -415.013223) (xy 345.120392 -415.005472) (xy 345.147646 -415.005012) (xy 346.011246 -415.005012)
			(xy 346.038497 -415.005461) (xy 346.092442 -415.013223) (xy 346.144734 -415.028583) (xy 346.194308 -415.051228)
			(xy 346.240155 -415.080697) (xy 346.281342 -415.116391) (xy 346.31703 -415.157582) (xy 346.346494 -415.203432)
			(xy 346.369133 -415.253009) (xy 346.384487 -415.305303) (xy 346.392242 -415.359249) (xy 346.392242 -415.413749)
			(xy 347.829898 -415.413749) (xy 347.829898 -415.359251) (xy 347.837654 -415.305307) (xy 347.853008 -415.253016)
			(xy 347.875646 -415.203443) (xy 347.90511 -415.157596) (xy 347.940798 -415.116408) (xy 347.981984 -415.080718)
			(xy 348.02783 -415.051253) (xy 348.077403 -415.028612) (xy 348.129694 -415.013257) (xy 348.183637 -415.005499)
			(xy 348.210886 -415.005012) (xy 349.074486 -415.005012) (xy 349.101741 -415.005434) (xy 349.155696 -415.01319)
			(xy 349.207999 -415.028545) (xy 349.257583 -415.051188) (xy 349.303441 -415.080657) (xy 349.344637 -415.116353)
			(xy 349.380334 -415.157548) (xy 349.409805 -415.203405) (xy 349.43245 -415.252988) (xy 349.447807 -415.30529)
			(xy 349.455565 -415.359245) (xy 349.455565 -415.413753) (xy 350.893075 -415.413753) (xy 350.893075 -415.359247)
			(xy 350.900833 -415.305297) (xy 350.916189 -415.253) (xy 350.938832 -415.203421) (xy 350.968301 -415.157569)
			(xy 351.003996 -415.116377) (xy 351.045189 -415.080686) (xy 351.091043 -415.05122) (xy 351.140624 -415.02858)
			(xy 351.192922 -415.013227) (xy 351.246873 -415.005474) (xy 351.274126 -415.005012) (xy 352.137726 -415.005012)
			(xy 352.164977 -415.00546) (xy 352.218925 -415.01322) (xy 352.27122 -415.028578) (xy 352.320796 -415.051222)
			(xy 352.366646 -415.08069) (xy 352.407835 -415.116383) (xy 352.443526 -415.157575) (xy 352.472991 -415.203427)
			(xy 352.495631 -415.253005) (xy 352.510986 -415.3053) (xy 352.518742 -415.359249) (xy 352.518742 -415.413751)
			(xy 352.518742 -415.413752) (xy 372.044675 -415.413752) (xy 372.044675 -415.359248) (xy 372.052432 -415.305298)
			(xy 372.067789 -415.253001) (xy 372.090432 -415.203422) (xy 372.1199 -415.15757) (xy 372.155594 -415.116379)
			(xy 372.196788 -415.080687) (xy 372.242641 -415.051221) (xy 372.292221 -415.028581) (xy 372.344519 -415.013228)
			(xy 372.39847 -415.005474) (xy 372.425722 -415.005012) (xy 373.289322 -415.005012) (xy 373.316574 -415.005459)
			(xy 373.370522 -415.013219) (xy 373.422817 -415.028577) (xy 373.472394 -415.05122) (xy 373.518244 -415.080689)
			(xy 373.559434 -415.116382) (xy 373.595125 -415.157574) (xy 373.62459 -415.203426) (xy 373.647231 -415.253004)
			(xy 373.662586 -415.3053) (xy 373.670342 -415.359248) (xy 373.670342 -415.413748) (xy 375.107998 -415.413748)
			(xy 375.107998 -415.359252) (xy 375.115753 -415.30531) (xy 375.131106 -415.253022) (xy 375.153743 -415.203449)
			(xy 375.183204 -415.157603) (xy 375.218889 -415.116416) (xy 375.260073 -415.080727) (xy 375.305916 -415.051261)
			(xy 375.355486 -415.028619) (xy 375.407773 -415.013261) (xy 375.461714 -415.005501) (xy 375.488962 -415.005012)
			(xy 376.352562 -415.005012) (xy 376.379818 -415.005432) (xy 376.433776 -415.013185) (xy 376.486081 -415.028539)
			(xy 376.535669 -415.05118) (xy 376.581529 -415.080649) (xy 376.622729 -415.116345) (xy 376.658428 -415.15754)
			(xy 376.687901 -415.203398) (xy 376.710548 -415.252983) (xy 376.725907 -415.305287) (xy 376.733665 -415.359244)
			(xy 376.733665 -415.413752) (xy 378.171175 -415.413752) (xy 378.171175 -415.359248) (xy 378.178932 -415.3053)
			(xy 378.194287 -415.253005) (xy 378.216929 -415.203427) (xy 378.246395 -415.157576) (xy 378.282087 -415.116386)
			(xy 378.323278 -415.080694) (xy 378.369129 -415.051228) (xy 378.418707 -415.028587) (xy 378.471002 -415.013231)
			(xy 378.52495 -415.005475) (xy 378.552202 -415.005012) (xy 379.415802 -415.005012) (xy 379.443055 -415.005458)
			(xy 379.497005 -415.013215) (xy 379.549302 -415.028571) (xy 379.598882 -415.051214) (xy 379.644734 -415.080682)
			(xy 379.685926 -415.116375) (xy 379.72162 -415.157567) (xy 379.751087 -415.20342) (xy 379.773729 -415.253)
			(xy 379.789085 -415.305297) (xy 379.796842 -415.359247) (xy 379.796842 -415.413753) (xy 381.234375 -415.413753)
			(xy 381.234375 -415.359247) (xy 381.242133 -415.305295) (xy 381.25749 -415.252996) (xy 381.280135 -415.203416)
			(xy 381.309605 -415.157563) (xy 381.345301 -415.116372) (xy 381.386497 -415.08068) (xy 381.432353 -415.051215)
			(xy 381.481936 -415.028576) (xy 381.534236 -415.013224) (xy 381.588189 -415.005472) (xy 381.615442 -415.005012)
			(xy 382.479042 -415.005012) (xy 382.506293 -415.005461) (xy 382.560239 -415.013222) (xy 382.612531 -415.028582)
			(xy 382.662106 -415.051227) (xy 382.707953 -415.080696) (xy 382.749141 -415.116389) (xy 382.784829 -415.15758)
			(xy 382.814293 -415.203431) (xy 382.836933 -415.253008) (xy 382.852286 -415.305302) (xy 382.860042 -415.359249)
			(xy 382.860042 -415.413749) (xy 384.297698 -415.413749) (xy 384.297698 -415.359251) (xy 384.305454 -415.305308)
			(xy 384.320807 -415.253017) (xy 384.343446 -415.203444) (xy 384.372909 -415.157597) (xy 384.408597 -415.116409)
			(xy 384.449782 -415.08072) (xy 384.495628 -415.051254) (xy 384.5452 -415.028613) (xy 384.59749 -415.013258)
			(xy 384.651433 -415.005499) (xy 384.678682 -415.005012) (xy 385.542282 -415.005012) (xy 385.569537 -415.005434)
			(xy 385.623493 -415.013189) (xy 385.675796 -415.028544) (xy 385.725381 -415.051187) (xy 385.771239 -415.080656)
			(xy 385.812436 -415.116352) (xy 385.848133 -415.157547) (xy 385.877604 -415.203403) (xy 385.900249 -415.252987)
			(xy 385.915607 -415.305289) (xy 385.923365 -415.359245) (xy 385.923365 -415.413752) (xy 387.360875 -415.413752)
			(xy 387.360875 -415.359248) (xy 387.368632 -415.305298) (xy 387.383989 -415.253001) (xy 387.406632 -415.203422)
			(xy 387.4361 -415.15757) (xy 387.471794 -415.116379) (xy 387.512988 -415.080687) (xy 387.558841 -415.051221)
			(xy 387.608421 -415.028581) (xy 387.660719 -415.013228) (xy 387.71467 -415.005474) (xy 387.741922 -415.005012)
			(xy 388.605522 -415.005012) (xy 388.632774 -415.005459) (xy 388.686722 -415.013219) (xy 388.739017 -415.028577)
			(xy 388.788594 -415.05122) (xy 388.834444 -415.080689) (xy 388.875634 -415.116382) (xy 388.911325 -415.157574)
			(xy 388.94079 -415.203426) (xy 388.963431 -415.253004) (xy 388.978786 -415.3053) (xy 388.986542 -415.359248)
			(xy 388.986542 -415.413748) (xy 390.424198 -415.413748) (xy 390.424198 -415.359252) (xy 390.431953 -415.30531)
			(xy 390.447306 -415.253022) (xy 390.469943 -415.203449) (xy 390.499404 -415.157603) (xy 390.535089 -415.116416)
			(xy 390.576273 -415.080727) (xy 390.622116 -415.051261) (xy 390.671686 -415.028619) (xy 390.723973 -415.013261)
			(xy 390.777914 -415.005501) (xy 390.805162 -415.005012) (xy 391.668762 -415.005012) (xy 391.696018 -415.005432)
			(xy 391.749976 -415.013185) (xy 391.802281 -415.028539) (xy 391.851869 -415.05118) (xy 391.897729 -415.080649)
			(xy 391.938929 -415.116345) (xy 391.974628 -415.15754) (xy 392.004101 -415.203398) (xy 392.026748 -415.252983)
			(xy 392.042107 -415.305287) (xy 392.049865 -415.359244) (xy 392.049865 -415.413752) (xy 393.487375 -415.413752)
			(xy 393.487375 -415.359248) (xy 393.495132 -415.3053) (xy 393.510487 -415.253005) (xy 393.533129 -415.203427)
			(xy 393.562595 -415.157576) (xy 393.598287 -415.116386) (xy 393.639478 -415.080694) (xy 393.685329 -415.051228)
			(xy 393.734907 -415.028587) (xy 393.787202 -415.013231) (xy 393.84115 -415.005475) (xy 393.868402 -415.005012)
			(xy 394.732002 -415.005012) (xy 394.759255 -415.005458) (xy 394.813205 -415.013215) (xy 394.865502 -415.028571)
			(xy 394.915082 -415.051214) (xy 394.960934 -415.080682) (xy 395.002126 -415.116375) (xy 395.03782 -415.157567)
			(xy 395.067287 -415.20342) (xy 395.089929 -415.253) (xy 395.105285 -415.305297) (xy 395.113042 -415.359247)
			(xy 395.113042 -415.413753) (xy 396.550575 -415.413753) (xy 396.550575 -415.359247) (xy 396.558333 -415.305295)
			(xy 396.57369 -415.252996) (xy 396.596335 -415.203416) (xy 396.625805 -415.157563) (xy 396.661501 -415.116372)
			(xy 396.702697 -415.08068) (xy 396.748553 -415.051215) (xy 396.798136 -415.028576) (xy 396.850436 -415.013224)
			(xy 396.904389 -415.005472) (xy 396.931642 -415.005012) (xy 397.795242 -415.005012) (xy 397.822493 -415.005461)
			(xy 397.876439 -415.013222) (xy 397.928731 -415.028582) (xy 397.978306 -415.051227) (xy 398.024153 -415.080696)
			(xy 398.065341 -415.116389) (xy 398.101029 -415.15758) (xy 398.130493 -415.203431) (xy 398.153133 -415.253008)
			(xy 398.168486 -415.305302) (xy 398.176242 -415.359249) (xy 398.176242 -415.413749) (xy 399.613898 -415.413749)
			(xy 399.613898 -415.359251) (xy 399.621654 -415.305308) (xy 399.637007 -415.253017) (xy 399.659646 -415.203444)
			(xy 399.689109 -415.157597) (xy 399.724797 -415.116409) (xy 399.765982 -415.08072) (xy 399.811828 -415.051254)
			(xy 399.8614 -415.028613) (xy 399.91369 -415.013258) (xy 399.967633 -415.005499) (xy 399.994882 -415.005012)
			(xy 400.858482 -415.005012) (xy 400.885737 -415.005434) (xy 400.939693 -415.013189) (xy 400.991996 -415.028544)
			(xy 401.041581 -415.051187) (xy 401.087439 -415.080656) (xy 401.128636 -415.116352) (xy 401.164333 -415.157547)
			(xy 401.193804 -415.203403) (xy 401.216449 -415.252987) (xy 401.231807 -415.305289) (xy 401.239565 -415.359245)
			(xy 401.239565 -415.413752) (xy 402.677075 -415.413752) (xy 402.677075 -415.359248) (xy 402.684832 -415.305298)
			(xy 402.700189 -415.253001) (xy 402.722832 -415.203422) (xy 402.7523 -415.15757) (xy 402.787994 -415.116379)
			(xy 402.829188 -415.080687) (xy 402.875041 -415.051221) (xy 402.924621 -415.028581) (xy 402.976919 -415.013228)
			(xy 403.03087 -415.005474) (xy 403.058122 -415.005012) (xy 403.921722 -415.005012) (xy 403.948974 -415.005459)
			(xy 404.002922 -415.013219) (xy 404.055217 -415.028577) (xy 404.104794 -415.05122) (xy 404.150644 -415.080689)
			(xy 404.191834 -415.116382) (xy 404.227525 -415.157574) (xy 404.25699 -415.203426) (xy 404.279631 -415.253004)
			(xy 404.294986 -415.3053) (xy 404.302742 -415.359248) (xy 404.302742 -415.413748) (xy 405.740398 -415.413748)
			(xy 405.740398 -415.359252) (xy 405.748153 -415.30531) (xy 405.763506 -415.253022) (xy 405.786143 -415.203449)
			(xy 405.815604 -415.157603) (xy 405.851289 -415.116416) (xy 405.892473 -415.080727) (xy 405.938316 -415.051261)
			(xy 405.987886 -415.028619) (xy 406.040173 -415.013261) (xy 406.094114 -415.005501) (xy 406.121362 -415.005012)
			(xy 406.984962 -415.005012) (xy 407.012218 -415.005432) (xy 407.066176 -415.013185) (xy 407.118481 -415.028539)
			(xy 407.168069 -415.05118) (xy 407.213929 -415.080649) (xy 407.255129 -415.116345) (xy 407.290828 -415.15754)
			(xy 407.320301 -415.203398) (xy 407.342948 -415.252983) (xy 407.358307 -415.305287) (xy 407.366065 -415.359244)
			(xy 407.366065 -415.413752) (xy 408.803575 -415.413752) (xy 408.803575 -415.359248) (xy 408.811332 -415.3053)
			(xy 408.826687 -415.253005) (xy 408.849329 -415.203427) (xy 408.878795 -415.157576) (xy 408.914487 -415.116386)
			(xy 408.955678 -415.080694) (xy 409.001529 -415.051228) (xy 409.051107 -415.028587) (xy 409.103402 -415.013231)
			(xy 409.15735 -415.005475) (xy 409.184602 -415.005012) (xy 410.048202 -415.005012) (xy 410.075455 -415.005458)
			(xy 410.129405 -415.013215) (xy 410.181702 -415.028571) (xy 410.231282 -415.051214) (xy 410.277134 -415.080682)
			(xy 410.318326 -415.116375) (xy 410.35402 -415.157567) (xy 410.383487 -415.20342) (xy 410.406129 -415.253)
			(xy 410.421485 -415.305297) (xy 410.429242 -415.359247) (xy 410.429242 -415.413753) (xy 411.866775 -415.413753)
			(xy 411.866775 -415.359247) (xy 411.874533 -415.305295) (xy 411.88989 -415.252996) (xy 411.912535 -415.203416)
			(xy 411.942005 -415.157563) (xy 411.977701 -415.116372) (xy 412.018897 -415.08068) (xy 412.064753 -415.051215)
			(xy 412.114336 -415.028576) (xy 412.166636 -415.013224) (xy 412.220589 -415.005472) (xy 412.247842 -415.005012)
			(xy 413.111442 -415.005012) (xy 413.138693 -415.005461) (xy 413.192639 -415.013222) (xy 413.244931 -415.028582)
			(xy 413.294506 -415.051227) (xy 413.340353 -415.080696) (xy 413.381541 -415.116389) (xy 413.417229 -415.15758)
			(xy 413.446693 -415.203431) (xy 413.469333 -415.253008) (xy 413.484686 -415.305302) (xy 413.492442 -415.359249)
			(xy 413.492442 -415.413749) (xy 414.930098 -415.413749) (xy 414.930098 -415.359251) (xy 414.937854 -415.305308)
			(xy 414.953207 -415.253017) (xy 414.975846 -415.203444) (xy 415.005309 -415.157597) (xy 415.040997 -415.116409)
			(xy 415.082182 -415.08072) (xy 415.128028 -415.051254) (xy 415.1776 -415.028613) (xy 415.22989 -415.013258)
			(xy 415.283833 -415.005499) (xy 415.311082 -415.005012) (xy 416.174682 -415.005012) (xy 416.201937 -415.005434)
			(xy 416.255893 -415.013189) (xy 416.308196 -415.028544) (xy 416.357781 -415.051187) (xy 416.403639 -415.080656)
			(xy 416.444836 -415.116352) (xy 416.480533 -415.157547) (xy 416.510004 -415.203403) (xy 416.532649 -415.252987)
			(xy 416.548007 -415.305289) (xy 416.555765 -415.359245) (xy 416.555765 -415.413752) (xy 417.993275 -415.413752)
			(xy 417.993275 -415.359248) (xy 418.001032 -415.305298) (xy 418.016389 -415.253001) (xy 418.039032 -415.203422)
			(xy 418.0685 -415.15757) (xy 418.104194 -415.116379) (xy 418.145388 -415.080687) (xy 418.191241 -415.051221)
			(xy 418.240821 -415.028581) (xy 418.293119 -415.013228) (xy 418.34707 -415.005474) (xy 418.374322 -415.005012)
			(xy 419.237922 -415.005012) (xy 419.265174 -415.005459) (xy 419.319122 -415.013219) (xy 419.371417 -415.028577)
			(xy 419.420994 -415.05122) (xy 419.466844 -415.080689) (xy 419.508034 -415.116382) (xy 419.543725 -415.157574)
			(xy 419.57319 -415.203426) (xy 419.595831 -415.253004) (xy 419.611186 -415.3053) (xy 419.618942 -415.359248)
			(xy 419.618942 -415.413752) (xy 419.611186 -415.4677) (xy 419.595831 -415.519996) (xy 419.57319 -415.569574)
			(xy 419.543725 -415.615426) (xy 419.508034 -415.656618) (xy 419.466844 -415.692311) (xy 419.420994 -415.72178)
			(xy 419.371417 -415.744423) (xy 419.319122 -415.759781) (xy 419.265174 -415.767541) (xy 419.237922 -415.768028)
			(xy 418.374322 -415.768028) (xy 418.34707 -415.767526) (xy 418.293119 -415.759772) (xy 418.240821 -415.744419)
			(xy 418.191241 -415.721779) (xy 418.145388 -415.692313) (xy 418.104194 -415.656621) (xy 418.0685 -415.61543)
			(xy 418.039032 -415.569578) (xy 418.016389 -415.519999) (xy 418.001032 -415.467702) (xy 417.993275 -415.413752)
			(xy 416.555765 -415.413752) (xy 416.555765 -415.413755) (xy 416.548007 -415.467711) (xy 416.532649 -415.520013)
			(xy 416.510004 -415.569597) (xy 416.480533 -415.615453) (xy 416.444836 -415.656648) (xy 416.403639 -415.692344)
			(xy 416.357781 -415.721813) (xy 416.308196 -415.744456) (xy 416.255893 -415.759811) (xy 416.201937 -415.767566)
			(xy 416.174682 -415.768028) (xy 415.311082 -415.768028) (xy 415.283833 -415.767501) (xy 415.22989 -415.759742)
			(xy 415.1776 -415.744387) (xy 415.128028 -415.721746) (xy 415.082182 -415.69228) (xy 415.040997 -415.656591)
			(xy 415.005309 -415.615403) (xy 414.975846 -415.569556) (xy 414.953207 -415.519983) (xy 414.937854 -415.467692)
			(xy 414.930098 -415.413749) (xy 413.492442 -415.413749) (xy 413.492442 -415.413751) (xy 413.484686 -415.467698)
			(xy 413.469333 -415.519992) (xy 413.446693 -415.569569) (xy 413.417229 -415.61542) (xy 413.381541 -415.656611)
			(xy 413.340353 -415.692304) (xy 413.294506 -415.721773) (xy 413.244931 -415.744418) (xy 413.192639 -415.759778)
			(xy 413.138693 -415.767539) (xy 413.111442 -415.768028) (xy 412.247842 -415.768028) (xy 412.220589 -415.767528)
			(xy 412.166636 -415.759776) (xy 412.114336 -415.744424) (xy 412.064753 -415.721785) (xy 412.018897 -415.69232)
			(xy 411.977701 -415.656628) (xy 411.942005 -415.615437) (xy 411.912535 -415.569584) (xy 411.88989 -415.520004)
			(xy 411.874533 -415.467705) (xy 411.866775 -415.413753) (xy 410.429242 -415.413753) (xy 410.421485 -415.467703)
			(xy 410.406129 -415.52) (xy 410.383487 -415.56958) (xy 410.35402 -415.615433) (xy 410.318326 -415.656625)
			(xy 410.277134 -415.692318) (xy 410.231282 -415.721786) (xy 410.181702 -415.744429) (xy 410.129405 -415.759785)
			(xy 410.075455 -415.767542) (xy 410.048202 -415.768028) (xy 409.184602 -415.768028) (xy 409.15735 -415.767525)
			(xy 409.103402 -415.759769) (xy 409.051107 -415.744413) (xy 409.001529 -415.721772) (xy 408.955678 -415.692306)
			(xy 408.914487 -415.656614) (xy 408.878795 -415.615424) (xy 408.849329 -415.569573) (xy 408.826687 -415.519995)
			(xy 408.811332 -415.4677) (xy 408.803575 -415.413752) (xy 407.366065 -415.413752) (xy 407.366065 -415.413756)
			(xy 407.358307 -415.467713) (xy 407.342948 -415.520017) (xy 407.320301 -415.569602) (xy 407.290828 -415.61546)
			(xy 407.255129 -415.656655) (xy 407.213929 -415.692351) (xy 407.168069 -415.72182) (xy 407.118481 -415.744461)
			(xy 407.066176 -415.759815) (xy 407.012218 -415.767568) (xy 406.984962 -415.768028) (xy 406.121362 -415.768028)
			(xy 406.094114 -415.767499) (xy 406.040173 -415.759739) (xy 405.987886 -415.744381) (xy 405.938316 -415.721739)
			(xy 405.892473 -415.692273) (xy 405.851289 -415.656584) (xy 405.815604 -415.615397) (xy 405.786143 -415.569551)
			(xy 405.763506 -415.519978) (xy 405.748153 -415.46769) (xy 405.740398 -415.413748) (xy 404.302742 -415.413748)
			(xy 404.302742 -415.413752) (xy 404.294986 -415.4677) (xy 404.279631 -415.519996) (xy 404.25699 -415.569574)
			(xy 404.227525 -415.615426) (xy 404.191834 -415.656618) (xy 404.150644 -415.692311) (xy 404.104794 -415.72178)
			(xy 404.055217 -415.744423) (xy 404.002922 -415.759781) (xy 403.948974 -415.767541) (xy 403.921722 -415.768028)
			(xy 403.058122 -415.768028) (xy 403.03087 -415.767526) (xy 402.976919 -415.759772) (xy 402.924621 -415.744419)
			(xy 402.875041 -415.721779) (xy 402.829188 -415.692313) (xy 402.787994 -415.656621) (xy 402.7523 -415.61543)
			(xy 402.722832 -415.569578) (xy 402.700189 -415.519999) (xy 402.684832 -415.467702) (xy 402.677075 -415.413752)
			(xy 401.239565 -415.413752) (xy 401.239565 -415.413755) (xy 401.231807 -415.467711) (xy 401.216449 -415.520013)
			(xy 401.193804 -415.569597) (xy 401.164333 -415.615453) (xy 401.128636 -415.656648) (xy 401.087439 -415.692344)
			(xy 401.041581 -415.721813) (xy 400.991996 -415.744456) (xy 400.939693 -415.759811) (xy 400.885737 -415.767566)
			(xy 400.858482 -415.768028) (xy 399.994882 -415.768028) (xy 399.967633 -415.767501) (xy 399.91369 -415.759742)
			(xy 399.8614 -415.744387) (xy 399.811828 -415.721746) (xy 399.765982 -415.69228) (xy 399.724797 -415.656591)
			(xy 399.689109 -415.615403) (xy 399.659646 -415.569556) (xy 399.637007 -415.519983) (xy 399.621654 -415.467692)
			(xy 399.613898 -415.413749) (xy 398.176242 -415.413749) (xy 398.176242 -415.413751) (xy 398.168486 -415.467698)
			(xy 398.153133 -415.519992) (xy 398.130493 -415.569569) (xy 398.101029 -415.61542) (xy 398.065341 -415.656611)
			(xy 398.024153 -415.692304) (xy 397.978306 -415.721773) (xy 397.928731 -415.744418) (xy 397.876439 -415.759778)
			(xy 397.822493 -415.767539) (xy 397.795242 -415.768028) (xy 396.931642 -415.768028) (xy 396.904389 -415.767528)
			(xy 396.850436 -415.759776) (xy 396.798136 -415.744424) (xy 396.748553 -415.721785) (xy 396.702697 -415.69232)
			(xy 396.661501 -415.656628) (xy 396.625805 -415.615437) (xy 396.596335 -415.569584) (xy 396.57369 -415.520004)
			(xy 396.558333 -415.467705) (xy 396.550575 -415.413753) (xy 395.113042 -415.413753) (xy 395.105285 -415.467703)
			(xy 395.089929 -415.52) (xy 395.067287 -415.56958) (xy 395.03782 -415.615433) (xy 395.002126 -415.656625)
			(xy 394.960934 -415.692318) (xy 394.915082 -415.721786) (xy 394.865502 -415.744429) (xy 394.813205 -415.759785)
			(xy 394.759255 -415.767542) (xy 394.732002 -415.768028) (xy 393.868402 -415.768028) (xy 393.84115 -415.767525)
			(xy 393.787202 -415.759769) (xy 393.734907 -415.744413) (xy 393.685329 -415.721772) (xy 393.639478 -415.692306)
			(xy 393.598287 -415.656614) (xy 393.562595 -415.615424) (xy 393.533129 -415.569573) (xy 393.510487 -415.519995)
			(xy 393.495132 -415.4677) (xy 393.487375 -415.413752) (xy 392.049865 -415.413752) (xy 392.049865 -415.413756)
			(xy 392.042107 -415.467713) (xy 392.026748 -415.520017) (xy 392.004101 -415.569602) (xy 391.974628 -415.61546)
			(xy 391.938929 -415.656655) (xy 391.897729 -415.692351) (xy 391.851869 -415.72182) (xy 391.802281 -415.744461)
			(xy 391.749976 -415.759815) (xy 391.696018 -415.767568) (xy 391.668762 -415.768028) (xy 390.805162 -415.768028)
			(xy 390.777914 -415.767499) (xy 390.723973 -415.759739) (xy 390.671686 -415.744381) (xy 390.622116 -415.721739)
			(xy 390.576273 -415.692273) (xy 390.535089 -415.656584) (xy 390.499404 -415.615397) (xy 390.469943 -415.569551)
			(xy 390.447306 -415.519978) (xy 390.431953 -415.46769) (xy 390.424198 -415.413748) (xy 388.986542 -415.413748)
			(xy 388.986542 -415.413752) (xy 388.978786 -415.4677) (xy 388.963431 -415.519996) (xy 388.94079 -415.569574)
			(xy 388.911325 -415.615426) (xy 388.875634 -415.656618) (xy 388.834444 -415.692311) (xy 388.788594 -415.72178)
			(xy 388.739017 -415.744423) (xy 388.686722 -415.759781) (xy 388.632774 -415.767541) (xy 388.605522 -415.768028)
			(xy 387.741922 -415.768028) (xy 387.71467 -415.767526) (xy 387.660719 -415.759772) (xy 387.608421 -415.744419)
			(xy 387.558841 -415.721779) (xy 387.512988 -415.692313) (xy 387.471794 -415.656621) (xy 387.4361 -415.61543)
			(xy 387.406632 -415.569578) (xy 387.383989 -415.519999) (xy 387.368632 -415.467702) (xy 387.360875 -415.413752)
			(xy 385.923365 -415.413752) (xy 385.923365 -415.413755) (xy 385.915607 -415.467711) (xy 385.900249 -415.520013)
			(xy 385.877604 -415.569597) (xy 385.848133 -415.615453) (xy 385.812436 -415.656648) (xy 385.771239 -415.692344)
			(xy 385.725381 -415.721813) (xy 385.675796 -415.744456) (xy 385.623493 -415.759811) (xy 385.569537 -415.767566)
			(xy 385.542282 -415.768028) (xy 384.678682 -415.768028) (xy 384.651433 -415.767501) (xy 384.59749 -415.759742)
			(xy 384.5452 -415.744387) (xy 384.495628 -415.721746) (xy 384.449782 -415.69228) (xy 384.408597 -415.656591)
			(xy 384.372909 -415.615403) (xy 384.343446 -415.569556) (xy 384.320807 -415.519983) (xy 384.305454 -415.467692)
			(xy 384.297698 -415.413749) (xy 382.860042 -415.413749) (xy 382.860042 -415.413751) (xy 382.852286 -415.467698)
			(xy 382.836933 -415.519992) (xy 382.814293 -415.569569) (xy 382.784829 -415.61542) (xy 382.749141 -415.656611)
			(xy 382.707953 -415.692304) (xy 382.662106 -415.721773) (xy 382.612531 -415.744418) (xy 382.560239 -415.759778)
			(xy 382.506293 -415.767539) (xy 382.479042 -415.768028) (xy 381.615442 -415.768028) (xy 381.588189 -415.767528)
			(xy 381.534236 -415.759776) (xy 381.481936 -415.744424) (xy 381.432353 -415.721785) (xy 381.386497 -415.69232)
			(xy 381.345301 -415.656628) (xy 381.309605 -415.615437) (xy 381.280135 -415.569584) (xy 381.25749 -415.520004)
			(xy 381.242133 -415.467705) (xy 381.234375 -415.413753) (xy 379.796842 -415.413753) (xy 379.789085 -415.467703)
			(xy 379.773729 -415.52) (xy 379.751087 -415.56958) (xy 379.72162 -415.615433) (xy 379.685926 -415.656625)
			(xy 379.644734 -415.692318) (xy 379.598882 -415.721786) (xy 379.549302 -415.744429) (xy 379.497005 -415.759785)
			(xy 379.443055 -415.767542) (xy 379.415802 -415.768028) (xy 378.552202 -415.768028) (xy 378.52495 -415.767525)
			(xy 378.471002 -415.759769) (xy 378.418707 -415.744413) (xy 378.369129 -415.721772) (xy 378.323278 -415.692306)
			(xy 378.282087 -415.656614) (xy 378.246395 -415.615424) (xy 378.216929 -415.569573) (xy 378.194287 -415.519995)
			(xy 378.178932 -415.4677) (xy 378.171175 -415.413752) (xy 376.733665 -415.413752) (xy 376.733665 -415.413756)
			(xy 376.725907 -415.467713) (xy 376.710548 -415.520017) (xy 376.687901 -415.569602) (xy 376.658428 -415.61546)
			(xy 376.622729 -415.656655) (xy 376.581529 -415.692351) (xy 376.535669 -415.72182) (xy 376.486081 -415.744461)
			(xy 376.433776 -415.759815) (xy 376.379818 -415.767568) (xy 376.352562 -415.768028) (xy 375.488962 -415.768028)
			(xy 375.461714 -415.767499) (xy 375.407773 -415.759739) (xy 375.355486 -415.744381) (xy 375.305916 -415.721739)
			(xy 375.260073 -415.692273) (xy 375.218889 -415.656584) (xy 375.183204 -415.615397) (xy 375.153743 -415.569551)
			(xy 375.131106 -415.519978) (xy 375.115753 -415.46769) (xy 375.107998 -415.413748) (xy 373.670342 -415.413748)
			(xy 373.670342 -415.413752) (xy 373.662586 -415.4677) (xy 373.647231 -415.519996) (xy 373.62459 -415.569574)
			(xy 373.595125 -415.615426) (xy 373.559434 -415.656618) (xy 373.518244 -415.692311) (xy 373.472394 -415.72178)
			(xy 373.422817 -415.744423) (xy 373.370522 -415.759781) (xy 373.316574 -415.767541) (xy 373.289322 -415.768028)
			(xy 372.425722 -415.768028) (xy 372.39847 -415.767526) (xy 372.344519 -415.759772) (xy 372.292221 -415.744419)
			(xy 372.242641 -415.721779) (xy 372.196788 -415.692313) (xy 372.155594 -415.656621) (xy 372.1199 -415.61543)
			(xy 372.090432 -415.569578) (xy 372.067789 -415.519999) (xy 372.052432 -415.467702) (xy 372.044675 -415.413752)
			(xy 352.518742 -415.413752) (xy 352.510986 -415.4677) (xy 352.495631 -415.519995) (xy 352.472991 -415.569573)
			(xy 352.443526 -415.615425) (xy 352.407835 -415.656617) (xy 352.366646 -415.69231) (xy 352.320796 -415.721778)
			(xy 352.27122 -415.744422) (xy 352.218925 -415.75978) (xy 352.164977 -415.76754) (xy 352.137726 -415.768028)
			(xy 351.274126 -415.768028) (xy 351.246873 -415.767526) (xy 351.192922 -415.759773) (xy 351.140624 -415.74442)
			(xy 351.091043 -415.72178) (xy 351.045189 -415.692314) (xy 351.003996 -415.656623) (xy 350.968301 -415.615431)
			(xy 350.938832 -415.569579) (xy 350.916189 -415.52) (xy 350.900833 -415.467703) (xy 350.893075 -415.413753)
			(xy 349.455565 -415.413753) (xy 349.455565 -415.413755) (xy 349.447807 -415.46771) (xy 349.43245 -415.520012)
			(xy 349.409805 -415.569595) (xy 349.380334 -415.615452) (xy 349.344637 -415.656647) (xy 349.303441 -415.692343)
			(xy 349.257583 -415.721812) (xy 349.207999 -415.744455) (xy 349.155696 -415.75981) (xy 349.101741 -415.767566)
			(xy 349.074486 -415.768028) (xy 348.210886 -415.768028) (xy 348.183637 -415.767501) (xy 348.129694 -415.759743)
			(xy 348.077403 -415.744388) (xy 348.02783 -415.721747) (xy 347.981984 -415.692282) (xy 347.940798 -415.656592)
			(xy 347.90511 -415.615404) (xy 347.875646 -415.569557) (xy 347.853008 -415.519984) (xy 347.837654 -415.467693)
			(xy 347.829898 -415.413749) (xy 346.392242 -415.413749) (xy 346.392242 -415.413751) (xy 346.384487 -415.467697)
			(xy 346.369133 -415.519991) (xy 346.346494 -415.569568) (xy 346.31703 -415.615418) (xy 346.281342 -415.656609)
			(xy 346.240155 -415.692303) (xy 346.194308 -415.721772) (xy 346.144734 -415.744417) (xy 346.092442 -415.759777)
			(xy 346.038497 -415.767539) (xy 346.011246 -415.768028) (xy 345.147646 -415.768028) (xy 345.120392 -415.767528)
			(xy 345.066439 -415.759777) (xy 345.014139 -415.744425) (xy 344.964555 -415.721787) (xy 344.918699 -415.692321)
			(xy 344.877503 -415.65663) (xy 344.841806 -415.615438) (xy 344.812335 -415.569585) (xy 344.789691 -415.520004)
			(xy 344.774333 -415.467706) (xy 344.766575 -415.413754) (xy 343.329042 -415.413754) (xy 343.321285 -415.467702)
			(xy 343.30593 -415.519999) (xy 343.283288 -415.569579) (xy 343.253821 -415.615431) (xy 343.218128 -415.656624)
			(xy 343.176936 -415.692317) (xy 343.131084 -415.721785) (xy 343.081505 -415.744428) (xy 343.029208 -415.759784)
			(xy 342.975258 -415.767542) (xy 342.948006 -415.768028) (xy 342.084406 -415.768028) (xy 342.057154 -415.767525)
			(xy 342.003206 -415.759769) (xy 341.95091 -415.744415) (xy 341.901331 -415.721774) (xy 341.85548 -415.692307)
			(xy 341.814289 -415.656616) (xy 341.778596 -415.615425) (xy 341.749129 -415.569574) (xy 341.726488 -415.519996)
			(xy 341.711132 -415.4677) (xy 341.703375 -415.413752) (xy 340.265865 -415.413752) (xy 340.265865 -415.413756)
			(xy 340.258107 -415.467713) (xy 340.242748 -415.520016) (xy 340.220102 -415.569601) (xy 340.190629 -415.615458)
			(xy 340.15493 -415.656654) (xy 340.113731 -415.69235) (xy 340.067871 -415.721818) (xy 340.018284 -415.74446)
			(xy 339.965979 -415.759814) (xy 339.912022 -415.767567) (xy 339.884766 -415.768028) (xy 339.021166 -415.768028)
			(xy 338.993918 -415.767499) (xy 338.939977 -415.759739) (xy 338.887689 -415.744382) (xy 338.838118 -415.72174)
			(xy 338.792275 -415.692275) (xy 338.751091 -415.656585) (xy 338.715405 -415.615398) (xy 338.685943 -415.569552)
			(xy 338.663306 -415.519979) (xy 338.647953 -415.46769) (xy 338.640198 -415.413748) (xy 337.202542 -415.413748)
			(xy 337.202542 -415.413751) (xy 337.194786 -415.4677) (xy 337.179431 -415.519995) (xy 337.156791 -415.569573)
			(xy 337.127326 -415.615425) (xy 337.091635 -415.656617) (xy 337.050446 -415.69231) (xy 337.004596 -415.721778)
			(xy 336.95502 -415.744422) (xy 336.902725 -415.75978) (xy 336.848777 -415.76754) (xy 336.821526 -415.768028)
			(xy 335.957926 -415.768028) (xy 335.930673 -415.767526) (xy 335.876722 -415.759773) (xy 335.824424 -415.74442)
			(xy 335.774843 -415.72178) (xy 335.728989 -415.692314) (xy 335.687796 -415.656623) (xy 335.652101 -415.615431)
			(xy 335.622632 -415.569579) (xy 335.599989 -415.52) (xy 335.584633 -415.467703) (xy 335.576875 -415.413753)
			(xy 334.139365 -415.413753) (xy 334.139365 -415.413755) (xy 334.131607 -415.46771) (xy 334.11625 -415.520012)
			(xy 334.093605 -415.569595) (xy 334.064134 -415.615452) (xy 334.028437 -415.656647) (xy 333.987241 -415.692343)
			(xy 333.941383 -415.721812) (xy 333.891799 -415.744455) (xy 333.839496 -415.75981) (xy 333.785541 -415.767566)
			(xy 333.758286 -415.768028) (xy 332.894686 -415.768028) (xy 332.867437 -415.767501) (xy 332.813494 -415.759743)
			(xy 332.761203 -415.744388) (xy 332.71163 -415.721747) (xy 332.665784 -415.692282) (xy 332.624598 -415.656592)
			(xy 332.58891 -415.615404) (xy 332.559446 -415.569557) (xy 332.536808 -415.519984) (xy 332.521454 -415.467693)
			(xy 332.513698 -415.413749) (xy 331.076042 -415.413749) (xy 331.076042 -415.413751) (xy 331.068287 -415.467697)
			(xy 331.052933 -415.519991) (xy 331.030294 -415.569568) (xy 331.00083 -415.615418) (xy 330.965142 -415.656609)
			(xy 330.923955 -415.692303) (xy 330.878108 -415.721772) (xy 330.828534 -415.744417) (xy 330.776242 -415.759777)
			(xy 330.722297 -415.767539) (xy 330.695046 -415.768028) (xy 329.831446 -415.768028) (xy 329.804192 -415.767528)
			(xy 329.750239 -415.759777) (xy 329.697939 -415.744425) (xy 329.648355 -415.721787) (xy 329.602499 -415.692321)
			(xy 329.561303 -415.65663) (xy 329.525606 -415.615438) (xy 329.496135 -415.569585) (xy 329.473491 -415.520004)
			(xy 329.458133 -415.467706) (xy 329.450375 -415.413754) (xy 328.012842 -415.413754) (xy 328.005085 -415.467702)
			(xy 327.98973 -415.519999) (xy 327.967088 -415.569579) (xy 327.937621 -415.615431) (xy 327.901928 -415.656624)
			(xy 327.860736 -415.692317) (xy 327.814884 -415.721785) (xy 327.765305 -415.744428) (xy 327.713008 -415.759784)
			(xy 327.659058 -415.767542) (xy 327.631806 -415.768028) (xy 326.768206 -415.768028) (xy 326.740954 -415.767525)
			(xy 326.687006 -415.759769) (xy 326.63471 -415.744415) (xy 326.585131 -415.721774) (xy 326.53928 -415.692307)
			(xy 326.498089 -415.656616) (xy 326.462396 -415.615425) (xy 326.432929 -415.569574) (xy 326.410288 -415.519996)
			(xy 326.394932 -415.4677) (xy 326.387175 -415.413752) (xy 324.949665 -415.413752) (xy 324.949665 -415.413756)
			(xy 324.941907 -415.467713) (xy 324.926548 -415.520016) (xy 324.903902 -415.569601) (xy 324.874429 -415.615458)
			(xy 324.83873 -415.656654) (xy 324.797531 -415.69235) (xy 324.751671 -415.721818) (xy 324.702084 -415.74446)
			(xy 324.649779 -415.759814) (xy 324.595822 -415.767567) (xy 324.568566 -415.768028) (xy 323.704966 -415.768028)
			(xy 323.677718 -415.767499) (xy 323.623777 -415.759739) (xy 323.571489 -415.744382) (xy 323.521918 -415.72174)
			(xy 323.476075 -415.692275) (xy 323.434891 -415.656585) (xy 323.399205 -415.615398) (xy 323.369743 -415.569552)
			(xy 323.347106 -415.519979) (xy 323.331753 -415.46769) (xy 323.323998 -415.413748) (xy 321.886342 -415.413748)
			(xy 321.886342 -415.413751) (xy 321.878586 -415.4677) (xy 321.863231 -415.519995) (xy 321.840591 -415.569573)
			(xy 321.811126 -415.615425) (xy 321.775435 -415.656617) (xy 321.734246 -415.69231) (xy 321.688396 -415.721778)
			(xy 321.63882 -415.744422) (xy 321.586525 -415.75978) (xy 321.532577 -415.76754) (xy 321.505326 -415.768028)
			(xy 320.641726 -415.768028) (xy 320.614473 -415.767526) (xy 320.560522 -415.759773) (xy 320.508224 -415.74442)
			(xy 320.458643 -415.72178) (xy 320.412789 -415.692314) (xy 320.371596 -415.656623) (xy 320.335901 -415.615431)
			(xy 320.306432 -415.569579) (xy 320.283789 -415.52) (xy 320.268433 -415.467703) (xy 320.260675 -415.413753)
			(xy 318.823165 -415.413753) (xy 318.823165 -415.413755) (xy 318.815407 -415.46771) (xy 318.80005 -415.520012)
			(xy 318.777405 -415.569595) (xy 318.747934 -415.615452) (xy 318.712237 -415.656647) (xy 318.671041 -415.692343)
			(xy 318.625183 -415.721812) (xy 318.575599 -415.744455) (xy 318.523296 -415.75981) (xy 318.469341 -415.767566)
			(xy 318.442086 -415.768028) (xy 317.578486 -415.768028) (xy 317.551237 -415.767501) (xy 317.497294 -415.759743)
			(xy 317.445003 -415.744388) (xy 317.39543 -415.721747) (xy 317.349584 -415.692282) (xy 317.308398 -415.656592)
			(xy 317.27271 -415.615404) (xy 317.243246 -415.569557) (xy 317.220608 -415.519984) (xy 317.205254 -415.467693)
			(xy 317.197498 -415.413749) (xy 315.759842 -415.413749) (xy 315.759842 -415.413751) (xy 315.752087 -415.467697)
			(xy 315.736733 -415.519991) (xy 315.714094 -415.569568) (xy 315.68463 -415.615418) (xy 315.648942 -415.656609)
			(xy 315.607755 -415.692303) (xy 315.561908 -415.721772) (xy 315.512334 -415.744417) (xy 315.460042 -415.759777)
			(xy 315.406097 -415.767539) (xy 315.378846 -415.768028) (xy 314.515246 -415.768028) (xy 314.487992 -415.767528)
			(xy 314.434039 -415.759777) (xy 314.381739 -415.744425) (xy 314.332155 -415.721787) (xy 314.286299 -415.692321)
			(xy 314.245103 -415.65663) (xy 314.209406 -415.615438) (xy 314.179935 -415.569585) (xy 314.157291 -415.520004)
			(xy 314.141933 -415.467706) (xy 314.134175 -415.413754) (xy 312.696642 -415.413754) (xy 312.688885 -415.467702)
			(xy 312.67353 -415.519999) (xy 312.650888 -415.569579) (xy 312.621421 -415.615431) (xy 312.585728 -415.656624)
			(xy 312.544536 -415.692317) (xy 312.498684 -415.721785) (xy 312.449105 -415.744428) (xy 312.396808 -415.759784)
			(xy 312.342858 -415.767542) (xy 312.315606 -415.768028) (xy 311.452006 -415.768028) (xy 311.424754 -415.767525)
			(xy 311.370806 -415.759769) (xy 311.31851 -415.744415) (xy 311.268931 -415.721774) (xy 311.22308 -415.692307)
			(xy 311.181889 -415.656616) (xy 311.146196 -415.615425) (xy 311.116729 -415.569574) (xy 311.094088 -415.519996)
			(xy 311.078732 -415.4677) (xy 311.070975 -415.413752) (xy 309.633465 -415.413752) (xy 309.633465 -415.413756)
			(xy 309.625707 -415.467713) (xy 309.610348 -415.520016) (xy 309.587702 -415.569601) (xy 309.558229 -415.615458)
			(xy 309.52253 -415.656654) (xy 309.481331 -415.69235) (xy 309.435471 -415.721818) (xy 309.385884 -415.74446)
			(xy 309.333579 -415.759814) (xy 309.279622 -415.767567) (xy 309.252366 -415.768028) (xy 308.388766 -415.768028)
			(xy 308.361518 -415.767499) (xy 308.307577 -415.759739) (xy 308.255289 -415.744382) (xy 308.205718 -415.72174)
			(xy 308.159875 -415.692275) (xy 308.118691 -415.656585) (xy 308.083005 -415.615398) (xy 308.053543 -415.569552)
			(xy 308.030906 -415.519979) (xy 308.015553 -415.46769) (xy 308.007798 -415.413748) (xy 306.570142 -415.413748)
			(xy 306.570142 -415.413751) (xy 306.562386 -415.4677) (xy 306.547031 -415.519995) (xy 306.524391 -415.569573)
			(xy 306.494926 -415.615425) (xy 306.459235 -415.656617) (xy 306.418046 -415.69231) (xy 306.372196 -415.721778)
			(xy 306.32262 -415.744422) (xy 306.270325 -415.75978) (xy 306.216377 -415.76754) (xy 306.189126 -415.768028)
			(xy 305.325526 -415.768028) (xy 305.298273 -415.767526) (xy 305.244322 -415.759773) (xy 305.192024 -415.74442)
			(xy 305.142443 -415.72178) (xy 305.096589 -415.692314) (xy 305.055396 -415.656623) (xy 305.019701 -415.615431)
			(xy 304.990232 -415.569579) (xy 304.967589 -415.52) (xy 304.952233 -415.467703) (xy 304.944475 -415.413753)
			(xy 300.882586 -415.413753) (xy 300.868941 -415.434612) (xy 300.76479 -415.579315) (xy 300.654297 -415.719235)
			(xy 300.53768 -415.854094) (xy 300.415171 -415.983624) (xy 300.287014 -416.107568) (xy 300.153463 -416.22568)
			(xy 300.014783 -416.337725) (xy 299.871249 -416.443482) (xy 299.723146 -416.542739) (xy 299.570769 -416.635301)
			(xy 299.41442 -416.720982) (xy 299.254409 -416.799614) (xy 299.091055 -416.87104) (xy 298.92468 -416.935118)
			(xy 298.755617 -416.99172) (xy 298.5842 -417.040736) (xy 298.410769 -417.082066) (xy 298.235669 -417.11563)
			(xy 298.059249 -417.14136) (xy 297.881857 -417.159206) (xy 297.703846 -417.169132) (xy 297.525569 -417.171118)
			(xy 297.347382 -417.165161) (xy 297.169636 -417.151271) (xy 296.992686 -417.129478) (xy 296.816882 -417.099824)
			(xy 296.642574 -417.062367) (xy 296.470107 -417.017183) (xy 296.299824 -416.964361) (xy 296.132063 -416.904005)
			(xy 295.967158 -416.836237) (xy 295.805435 -416.761189) (xy 295.647216 -416.679012) (xy 295.492815 -416.589869)
			(xy 295.342538 -416.493935) (xy 295.196683 -416.391403) (xy 295.055541 -416.282475) (xy 294.919392 -416.167368)
			(xy 294.788505 -416.04631) (xy 294.663141 -415.919541) (xy 294.543548 -415.787314) (xy 294.429965 -415.649891)
			(xy 294.322616 -415.507544) (xy 294.221715 -415.360556) (xy 294.127462 -415.20922) (xy 294.040044 -415.053835)
			(xy 293.959634 -414.89471) (xy 293.886393 -414.732161) (xy 293.820466 -414.566511) (xy 293.761983 -414.398089)
			(xy 293.711061 -414.227228) (xy 293.667801 -414.054269) (xy 293.632289 -413.879554) (xy 293.604595 -413.70343)
			(xy 293.584774 -413.526248) (xy 293.572866 -413.348359) (xy 293.568894 -413.170116) (xy 276.749256 -413.170116)
			(xy 272.414746 -417.504626) (xy 272.396783 -417.521953) (xy 272.356401 -417.55128) (xy 272.311928 -417.573928)
			(xy 272.264459 -417.589339) (xy 272.215164 -417.597133) (xy 272.19021 -417.59759) (xy 235.05033 -417.59759)
			(xy 235.040259 -417.598007) (xy 235.02166 -417.605731) (xy 235.014262 -417.612576) (xy 233.545126 -419.081712)
			(xy 276.721824 -419.081712) (xy 276.721824 -418.218112) (xy 276.72231 -418.190861) (xy 276.730066 -418.136913)
			(xy 276.745421 -418.084618) (xy 276.768063 -418.035041) (xy 276.797529 -417.989191) (xy 276.83322 -417.948)
			(xy 276.874411 -417.912309) (xy 276.920261 -417.882843) (xy 276.969838 -417.860201) (xy 277.022133 -417.844846)
			(xy 277.076081 -417.83709) (xy 277.130583 -417.83709) (xy 277.184531 -417.844846) (xy 277.236826 -417.860201)
			(xy 277.286403 -417.882843) (xy 277.332253 -417.912309) (xy 277.373444 -417.948) (xy 277.409135 -417.989191)
			(xy 277.438601 -418.035041) (xy 277.461243 -418.084618) (xy 277.476598 -418.136913) (xy 277.484354 -418.190861)
			(xy 277.48484 -418.218112) (xy 277.48484 -418.254688) (xy 289.453828 -418.254688) (xy 289.453828 -417.391088)
			(xy 289.454314 -417.363837) (xy 289.46207 -417.309889) (xy 289.477425 -417.257594) (xy 289.500067 -417.208017)
			(xy 289.529533 -417.162167) (xy 289.565224 -417.120976) (xy 289.606415 -417.085285) (xy 289.652265 -417.055819)
			(xy 289.701842 -417.033177) (xy 289.754137 -417.017822) (xy 289.808085 -417.010066) (xy 289.862587 -417.010066)
			(xy 289.916535 -417.017822) (xy 289.96883 -417.033177) (xy 290.018407 -417.055819) (xy 290.064257 -417.085285)
			(xy 290.105448 -417.120976) (xy 290.141139 -417.162167) (xy 290.170605 -417.208017) (xy 290.186237 -417.242244)
			(xy 303.576228 -417.242244) (xy 303.576228 -416.556444) (xy 303.576651 -416.54436) (xy 303.58411 -416.521373)
			(xy 303.598313 -416.501818) (xy 303.617865 -416.487614) (xy 303.640852 -416.480152) (xy 303.652936 -416.479736)
			(xy 303.8475 -416.479736) (xy 303.858603 -416.480135) (xy 303.879895 -416.486446) (xy 303.88941 -416.492182)
			(xy 304.183034 -416.684714) (xy 304.192391 -416.690465) (xy 304.213416 -416.69679) (xy 304.235372 -416.69685)
			(xy 304.256432 -416.69064) (xy 304.265838 -416.684968) (xy 304.562002 -416.492182) (xy 304.571504 -416.486418)
			(xy 304.592804 -416.480103) (xy 304.603912 -416.479736) (xy 304.798476 -416.479736) (xy 304.810562 -416.480134)
			(xy 304.833551 -416.4876) (xy 304.853106 -416.501809) (xy 304.867309 -416.521367) (xy 304.874769 -416.544358)
			(xy 304.875184 -416.556444) (xy 304.875184 -417.242244) (xy 306.639468 -417.242244) (xy 306.639468 -416.556444)
			(xy 306.63995 -416.544366) (xy 306.647402 -416.521389) (xy 306.661591 -416.50184) (xy 306.681128 -416.487633)
			(xy 306.704098 -416.48016) (xy 306.716176 -416.479736) (xy 306.91074 -416.479736) (xy 306.921845 -416.480118)
			(xy 306.943137 -416.486441) (xy 306.95265 -416.492182) (xy 307.246274 -416.684714) (xy 307.255659 -416.690414)
			(xy 307.276671 -416.69675) (xy 307.298618 -416.696825) (xy 307.319672 -416.690632) (xy 307.329078 -416.684968)
			(xy 307.625242 -416.492182) (xy 307.634756 -416.48644) (xy 307.656047 -416.480111) (xy 307.667152 -416.479736)
			(xy 307.861716 -416.479736) (xy 307.873804 -416.4801) (xy 307.896795 -416.487577) (xy 307.916349 -416.501794)
			(xy 307.930551 -416.521359) (xy 307.93801 -416.544356) (xy 307.938424 -416.556444) (xy 307.938424 -417.242244)
			(xy 309.702708 -417.242244) (xy 309.702708 -416.556444) (xy 309.70315 -416.544362) (xy 309.710608 -416.521378)
			(xy 309.724806 -416.501826) (xy 309.744353 -416.487621) (xy 309.767334 -416.480155) (xy 309.779416 -416.479736)
			(xy 309.97398 -416.479736) (xy 309.985086 -416.480103) (xy 310.006378 -416.486436) (xy 310.01589 -416.492182)
			(xy 310.309514 -416.684714) (xy 310.31888 -416.690448) (xy 310.339901 -416.696777) (xy 310.361854 -416.696842)
			(xy 310.382912 -416.690638) (xy 310.392318 -416.684968) (xy 310.688482 -416.492182) (xy 310.697988 -416.486426)
			(xy 310.719285 -416.480105) (xy 310.730392 -416.479736) (xy 310.924956 -416.479736) (xy 310.937041 -416.480151)
			(xy 310.96003 -416.487612) (xy 310.979584 -416.501816) (xy 310.993788 -416.52137) (xy 311.001249 -416.544359)
			(xy 311.001664 -416.556444) (xy 311.001664 -417.242244) (xy 312.765948 -417.242244) (xy 312.765948 -416.556444)
			(xy 312.766501 -416.544376) (xy 312.773946 -416.521418) (xy 312.788121 -416.501884) (xy 312.807639 -416.487686)
			(xy 312.830589 -416.480215) (xy 312.842656 -416.479736) (xy 313.03722 -416.479736) (xy 313.048324 -416.480126)
			(xy 313.069616 -416.486443) (xy 313.07913 -416.492182) (xy 313.372754 -416.684714) (xy 313.382149 -416.690397)
			(xy 313.403156 -416.696736) (xy 313.425099 -416.696816) (xy 313.446152 -416.690629) (xy 313.455558 -416.684968)
			(xy 313.751722 -416.492182) (xy 313.76124 -416.486448) (xy 313.782527 -416.480114) (xy 313.793632 -416.479736)
			(xy 313.988196 -416.479736) (xy 314.000283 -416.480116) (xy 314.023273 -416.487588) (xy 314.042827 -416.501801)
			(xy 314.05703 -416.521363) (xy 314.06449 -416.544357) (xy 314.064904 -416.556444) (xy 314.064904 -417.242244)
			(xy 315.829188 -417.242244) (xy 315.829188 -416.556444) (xy 315.82965 -416.544364) (xy 315.837105 -416.521383)
			(xy 315.851299 -416.501833) (xy 315.87084 -416.487627) (xy 315.893816 -416.480158) (xy 315.905896 -416.479736)
			(xy 316.10046 -416.479736) (xy 316.111565 -416.48011) (xy 316.132857 -416.486438) (xy 316.14237 -416.492182)
			(xy 316.435994 -416.684714) (xy 316.44537 -416.690431) (xy 316.466386 -416.696763) (xy 316.488336 -416.696833)
			(xy 316.509392 -416.690635) (xy 316.518798 -416.684968) (xy 316.814962 -416.492182) (xy 316.824472 -416.486433)
			(xy 316.845766 -416.480108) (xy 316.856872 -416.479736) (xy 317.051436 -416.479736) (xy 317.063525 -416.480083)
			(xy 317.086516 -416.487565) (xy 317.10607 -416.501787) (xy 317.120271 -416.521355) (xy 317.12773 -416.544355)
			(xy 317.128144 -416.556444) (xy 317.128144 -417.242244) (xy 318.892428 -417.242244) (xy 318.892428 -416.556444)
			(xy 318.892851 -416.54436) (xy 318.90031 -416.521373) (xy 318.914513 -416.501818) (xy 318.934065 -416.487614)
			(xy 318.957052 -416.480152) (xy 318.969136 -416.479736) (xy 319.1637 -416.479736) (xy 319.174803 -416.480135)
			(xy 319.196095 -416.486446) (xy 319.20561 -416.492182) (xy 319.499234 -416.684714) (xy 319.508591 -416.690465)
			(xy 319.529616 -416.69679) (xy 319.551572 -416.69685) (xy 319.572632 -416.69064) (xy 319.582038 -416.684968)
			(xy 319.878202 -416.492182) (xy 319.887704 -416.486418) (xy 319.909004 -416.480103) (xy 319.920112 -416.479736)
			(xy 320.114676 -416.479736) (xy 320.126762 -416.480134) (xy 320.149751 -416.4876) (xy 320.169306 -416.501809)
			(xy 320.183509 -416.521367) (xy 320.190969 -416.544358) (xy 320.191384 -416.556444) (xy 320.191384 -417.242244)
			(xy 321.955668 -417.242244) (xy 321.955668 -416.556444) (xy 321.95615 -416.544366) (xy 321.963602 -416.521389)
			(xy 321.977791 -416.50184) (xy 321.997328 -416.487633) (xy 322.020298 -416.48016) (xy 322.032376 -416.479736)
			(xy 322.22694 -416.479736) (xy 322.238045 -416.480118) (xy 322.259337 -416.486441) (xy 322.26885 -416.492182)
			(xy 322.562474 -416.684714) (xy 322.571859 -416.690414) (xy 322.592871 -416.69675) (xy 322.614818 -416.696825)
			(xy 322.635872 -416.690632) (xy 322.645278 -416.684968) (xy 322.941442 -416.492182) (xy 322.950956 -416.48644)
			(xy 322.972247 -416.480111) (xy 322.983352 -416.479736) (xy 323.177916 -416.479736) (xy 323.190004 -416.4801)
			(xy 323.212995 -416.487577) (xy 323.232549 -416.501794) (xy 323.246751 -416.521359) (xy 323.25421 -416.544356)
			(xy 323.254624 -416.556444) (xy 323.254624 -417.242244) (xy 325.018908 -417.242244) (xy 325.018908 -416.556444)
			(xy 325.01935 -416.544362) (xy 325.026808 -416.521378) (xy 325.041006 -416.501826) (xy 325.060553 -416.487621)
			(xy 325.083534 -416.480155) (xy 325.095616 -416.479736) (xy 325.29018 -416.479736) (xy 325.301286 -416.480103)
			(xy 325.322578 -416.486436) (xy 325.33209 -416.492182) (xy 325.625714 -416.684714) (xy 325.63508 -416.690448)
			(xy 325.656101 -416.696777) (xy 325.678054 -416.696842) (xy 325.699112 -416.690638) (xy 325.708518 -416.684968)
			(xy 326.004682 -416.492182) (xy 326.014188 -416.486426) (xy 326.035485 -416.480105) (xy 326.046592 -416.479736)
			(xy 326.241156 -416.479736) (xy 326.253241 -416.480151) (xy 326.27623 -416.487612) (xy 326.295784 -416.501816)
			(xy 326.309988 -416.52137) (xy 326.317449 -416.544359) (xy 326.317864 -416.556444) (xy 326.317864 -417.242244)
			(xy 328.082148 -417.242244) (xy 328.082148 -416.556444) (xy 328.082701 -416.544376) (xy 328.090146 -416.521418)
			(xy 328.104321 -416.501884) (xy 328.123839 -416.487686) (xy 328.146789 -416.480215) (xy 328.158856 -416.479736)
			(xy 328.35342 -416.479736) (xy 328.364524 -416.480126) (xy 328.385816 -416.486443) (xy 328.39533 -416.492182)
			(xy 328.688954 -416.684714) (xy 328.698349 -416.690397) (xy 328.719356 -416.696736) (xy 328.741299 -416.696816)
			(xy 328.762352 -416.690629) (xy 328.771758 -416.684968) (xy 329.067922 -416.492182) (xy 329.07744 -416.486448)
			(xy 329.098727 -416.480114) (xy 329.109832 -416.479736) (xy 329.304396 -416.479736) (xy 329.316483 -416.480116)
			(xy 329.339473 -416.487588) (xy 329.359027 -416.501801) (xy 329.37323 -416.521363) (xy 329.38069 -416.544357)
			(xy 329.381104 -416.556444) (xy 329.381104 -417.242244) (xy 331.145388 -417.242244) (xy 331.145388 -416.556444)
			(xy 331.14585 -416.544364) (xy 331.153305 -416.521383) (xy 331.167499 -416.501833) (xy 331.18704 -416.487627)
			(xy 331.210016 -416.480158) (xy 331.222096 -416.479736) (xy 331.41666 -416.479736) (xy 331.427765 -416.48011)
			(xy 331.449057 -416.486438) (xy 331.45857 -416.492182) (xy 331.752194 -416.684714) (xy 331.76157 -416.690431)
			(xy 331.782586 -416.696763) (xy 331.804536 -416.696833) (xy 331.825592 -416.690635) (xy 331.834998 -416.684968)
			(xy 332.131162 -416.492182) (xy 332.140672 -416.486433) (xy 332.161966 -416.480108) (xy 332.173072 -416.479736)
			(xy 332.367636 -416.479736) (xy 332.379725 -416.480083) (xy 332.402716 -416.487565) (xy 332.42227 -416.501787)
			(xy 332.436471 -416.521355) (xy 332.44393 -416.544355) (xy 332.444344 -416.556444) (xy 332.444344 -417.242244)
			(xy 334.208628 -417.242244) (xy 334.208628 -416.556444) (xy 334.209051 -416.54436) (xy 334.21651 -416.521373)
			(xy 334.230713 -416.501818) (xy 334.250265 -416.487614) (xy 334.273252 -416.480152) (xy 334.285336 -416.479736)
			(xy 334.4799 -416.479736) (xy 334.491003 -416.480135) (xy 334.512295 -416.486446) (xy 334.52181 -416.492182)
			(xy 334.815434 -416.684714) (xy 334.824791 -416.690465) (xy 334.845816 -416.69679) (xy 334.867772 -416.69685)
			(xy 334.888832 -416.69064) (xy 334.898238 -416.684968) (xy 335.194402 -416.492182) (xy 335.203904 -416.486418)
			(xy 335.225204 -416.480103) (xy 335.236312 -416.479736) (xy 335.430876 -416.479736) (xy 335.442962 -416.480134)
			(xy 335.465951 -416.4876) (xy 335.485506 -416.501809) (xy 335.499709 -416.521367) (xy 335.507169 -416.544358)
			(xy 335.507584 -416.556444) (xy 335.507584 -417.242244) (xy 337.271868 -417.242244) (xy 337.271868 -416.556444)
			(xy 337.27235 -416.544366) (xy 337.279802 -416.521389) (xy 337.293991 -416.50184) (xy 337.313528 -416.487633)
			(xy 337.336498 -416.48016) (xy 337.348576 -416.479736) (xy 337.54314 -416.479736) (xy 337.554245 -416.480118)
			(xy 337.575537 -416.486441) (xy 337.58505 -416.492182) (xy 337.878674 -416.684714) (xy 337.888059 -416.690414)
			(xy 337.909071 -416.69675) (xy 337.931018 -416.696825) (xy 337.952072 -416.690632) (xy 337.961478 -416.684968)
			(xy 338.257642 -416.492182) (xy 338.267156 -416.48644) (xy 338.288447 -416.480111) (xy 338.299552 -416.479736)
			(xy 338.494116 -416.479736) (xy 338.506204 -416.4801) (xy 338.529195 -416.487577) (xy 338.548749 -416.501794)
			(xy 338.562951 -416.521359) (xy 338.57041 -416.544356) (xy 338.570824 -416.556444) (xy 338.570824 -417.242244)
			(xy 340.335108 -417.242244) (xy 340.335108 -416.556444) (xy 340.33555 -416.544362) (xy 340.343008 -416.521378)
			(xy 340.357206 -416.501826) (xy 340.376753 -416.487621) (xy 340.399734 -416.480155) (xy 340.411816 -416.479736)
			(xy 340.60638 -416.479736) (xy 340.617486 -416.480103) (xy 340.638778 -416.486436) (xy 340.64829 -416.492182)
			(xy 340.941914 -416.684714) (xy 340.95128 -416.690448) (xy 340.972301 -416.696777) (xy 340.994254 -416.696842)
			(xy 341.015312 -416.690638) (xy 341.024718 -416.684968) (xy 341.320882 -416.492182) (xy 341.330388 -416.486426)
			(xy 341.351685 -416.480105) (xy 341.362792 -416.479736) (xy 341.557356 -416.479736) (xy 341.569441 -416.480151)
			(xy 341.59243 -416.487612) (xy 341.611984 -416.501816) (xy 341.626188 -416.52137) (xy 341.633649 -416.544359)
			(xy 341.634064 -416.556444) (xy 341.634064 -417.242244) (xy 343.398348 -417.242244) (xy 343.398348 -416.556444)
			(xy 343.398901 -416.544376) (xy 343.406346 -416.521418) (xy 343.420521 -416.501884) (xy 343.440039 -416.487686)
			(xy 343.462989 -416.480215) (xy 343.475056 -416.479736) (xy 343.66962 -416.479736) (xy 343.680724 -416.480126)
			(xy 343.702016 -416.486443) (xy 343.71153 -416.492182) (xy 344.005154 -416.684714) (xy 344.014549 -416.690397)
			(xy 344.035556 -416.696736) (xy 344.057499 -416.696816) (xy 344.078552 -416.690629) (xy 344.087958 -416.684968)
			(xy 344.384122 -416.492182) (xy 344.39364 -416.486448) (xy 344.414927 -416.480114) (xy 344.426032 -416.479736)
			(xy 344.620596 -416.479736) (xy 344.632683 -416.480116) (xy 344.655673 -416.487588) (xy 344.675227 -416.501801)
			(xy 344.68943 -416.521363) (xy 344.69689 -416.544357) (xy 344.697304 -416.556444) (xy 344.697304 -417.242244)
			(xy 346.461588 -417.242244) (xy 346.461588 -416.556444) (xy 346.46205 -416.544364) (xy 346.469505 -416.521383)
			(xy 346.483699 -416.501833) (xy 346.50324 -416.487627) (xy 346.526216 -416.480158) (xy 346.538296 -416.479736)
			(xy 346.73286 -416.479736) (xy 346.743965 -416.48011) (xy 346.765257 -416.486438) (xy 346.77477 -416.492182)
			(xy 347.068394 -416.684714) (xy 347.07777 -416.690431) (xy 347.098786 -416.696763) (xy 347.120736 -416.696833)
			(xy 347.141792 -416.690635) (xy 347.151198 -416.684968) (xy 347.447362 -416.492182) (xy 347.456872 -416.486433)
			(xy 347.478166 -416.480108) (xy 347.489272 -416.479736) (xy 347.683836 -416.479736) (xy 347.695925 -416.480083)
			(xy 347.718916 -416.487565) (xy 347.73847 -416.501787) (xy 347.752671 -416.521355) (xy 347.76013 -416.544355)
			(xy 347.760544 -416.556444) (xy 347.760544 -417.242244) (xy 349.524828 -417.242244) (xy 349.524828 -416.556444)
			(xy 349.525251 -416.54436) (xy 349.53271 -416.521373) (xy 349.546913 -416.501818) (xy 349.566465 -416.487614)
			(xy 349.589452 -416.480152) (xy 349.601536 -416.479736) (xy 349.7961 -416.479736) (xy 349.807203 -416.480135)
			(xy 349.828495 -416.486446) (xy 349.83801 -416.492182) (xy 350.131634 -416.684714) (xy 350.140991 -416.690465)
			(xy 350.162016 -416.69679) (xy 350.183972 -416.69685) (xy 350.205032 -416.69064) (xy 350.214438 -416.684968)
			(xy 350.510602 -416.492182) (xy 350.520104 -416.486418) (xy 350.541404 -416.480103) (xy 350.552512 -416.479736)
			(xy 350.747076 -416.479736) (xy 350.759162 -416.480134) (xy 350.782151 -416.4876) (xy 350.801706 -416.501809)
			(xy 350.815909 -416.521367) (xy 350.823369 -416.544358) (xy 350.823784 -416.556444) (xy 350.823784 -417.242244)
			(xy 350.823373 -417.254323) (xy 350.815896 -417.277296) (xy 350.801686 -417.296834) (xy 350.782135 -417.311027)
			(xy 350.759156 -417.318484) (xy 350.747076 -417.318952) (xy 350.552512 -417.318952) (xy 350.541405 -417.318571)
			(xy 350.520109 -417.312259) (xy 350.510602 -417.306506) (xy 350.215708 -417.113974) (xy 350.206321 -417.108271)
			(xy 350.185283 -417.101998) (xy 350.163329 -417.101998) (xy 350.142291 -417.108271) (xy 350.132904 -417.113974)
			(xy 349.83928 -417.306506) (xy 349.829761 -417.312239) (xy 349.808474 -417.318574) (xy 349.79737 -417.318952)
			(xy 349.601536 -417.318952) (xy 349.589468 -417.318406) (xy 349.566509 -417.310959) (xy 349.546975 -417.296782)
			(xy 349.532778 -417.277263) (xy 349.525307 -417.254312) (xy 349.524828 -417.242244) (xy 347.760544 -417.242244)
			(xy 347.760074 -417.254317) (xy 347.752604 -417.27728) (xy 347.738407 -417.296813) (xy 347.718873 -417.311007)
			(xy 347.695909 -417.318475) (xy 347.683836 -417.318952) (xy 347.489272 -417.318952) (xy 347.478164 -417.318588)
			(xy 347.456868 -417.312264) (xy 347.447362 -417.306506) (xy 347.152468 -417.113974) (xy 347.143081 -417.108271)
			(xy 347.122043 -417.101998) (xy 347.100089 -417.101998) (xy 347.079051 -417.108271) (xy 347.069664 -417.113974)
			(xy 346.77604 -417.306506) (xy 346.766529 -417.312253) (xy 346.745236 -417.318579) (xy 346.73413 -417.318952)
			(xy 346.538296 -417.318952) (xy 346.526226 -417.31844) (xy 346.503266 -417.310982) (xy 346.483733 -417.296796)
			(xy 346.469537 -417.27727) (xy 346.462067 -417.254314) (xy 346.461588 -417.242244) (xy 344.697304 -417.242244)
			(xy 344.696873 -417.254321) (xy 344.689398 -417.277291) (xy 344.675193 -417.296827) (xy 344.655648 -417.31102)
			(xy 344.632674 -417.318481) (xy 344.620596 -417.318952) (xy 344.426032 -417.318952) (xy 344.414923 -417.318604)
			(xy 344.393627 -417.312269) (xy 344.384122 -417.306506) (xy 344.089228 -417.113974) (xy 344.079841 -417.108271)
			(xy 344.058803 -417.101998) (xy 344.036849 -417.101998) (xy 344.015811 -417.108271) (xy 344.006424 -417.113974)
			(xy 343.7128 -417.306506) (xy 343.703297 -417.312268) (xy 343.681998 -417.318585) (xy 343.67089 -417.318952)
			(xy 343.475056 -417.318952) (xy 343.462984 -417.318474) (xy 343.440022 -417.311005) (xy 343.42049 -417.29681)
			(xy 343.406295 -417.277278) (xy 343.398826 -417.254316) (xy 343.398348 -417.242244) (xy 341.634064 -417.242244)
			(xy 341.633673 -417.254325) (xy 341.626193 -417.277301) (xy 341.611979 -417.296842) (xy 341.592422 -417.311033)
			(xy 341.569438 -417.318487) (xy 341.557356 -417.318952) (xy 341.362792 -417.318952) (xy 341.351685 -417.31858)
			(xy 341.330388 -417.312262) (xy 341.320882 -417.306506) (xy 341.025988 -417.113974) (xy 341.016601 -417.108271)
			(xy 340.995563 -417.101998) (xy 340.973609 -417.101998) (xy 340.952571 -417.108271) (xy 340.943184 -417.113974)
			(xy 340.64956 -417.306506) (xy 340.640045 -417.312246) (xy 340.618755 -417.318577) (xy 340.60765 -417.318952)
			(xy 340.411816 -417.318952) (xy 340.399747 -417.318423) (xy 340.376787 -417.31097) (xy 340.357254 -417.296789)
			(xy 340.343057 -417.277266) (xy 340.335587 -417.254313) (xy 340.335108 -417.242244) (xy 338.570824 -417.242244)
			(xy 338.570374 -417.254319) (xy 338.562901 -417.277285) (xy 338.5487 -417.29682) (xy 338.52916 -417.311014)
			(xy 338.506191 -417.318478) (xy 338.494116 -417.318952) (xy 338.299552 -417.318952) (xy 338.288443 -417.318596)
			(xy 338.267147 -417.312267) (xy 338.257642 -417.306506) (xy 337.962748 -417.113974) (xy 337.953361 -417.108271)
			(xy 337.932323 -417.101998) (xy 337.910369 -417.101998) (xy 337.889331 -417.108271) (xy 337.879944 -417.113974)
			(xy 337.58632 -417.306506) (xy 337.576813 -417.312261) (xy 337.555517 -417.318582) (xy 337.54441 -417.318952)
			(xy 337.348576 -417.318952) (xy 337.336505 -417.318457) (xy 337.313544 -417.310993) (xy 337.294011 -417.296803)
			(xy 337.279816 -417.277274) (xy 337.272346 -417.254315) (xy 337.271868 -417.242244) (xy 335.507584 -417.242244)
			(xy 335.507173 -417.254323) (xy 335.499696 -417.277296) (xy 335.485486 -417.296834) (xy 335.465935 -417.311027)
			(xy 335.442956 -417.318484) (xy 335.430876 -417.318952) (xy 335.236312 -417.318952) (xy 335.225205 -417.318571)
			(xy 335.203909 -417.312259) (xy 335.194402 -417.306506) (xy 334.899508 -417.113974) (xy 334.890121 -417.108271)
			(xy 334.869083 -417.101998) (xy 334.847129 -417.101998) (xy 334.826091 -417.108271) (xy 334.816704 -417.113974)
			(xy 334.52308 -417.306506) (xy 334.513561 -417.312239) (xy 334.492274 -417.318574) (xy 334.48117 -417.318952)
			(xy 334.285336 -417.318952) (xy 334.273268 -417.318406) (xy 334.250309 -417.310959) (xy 334.230775 -417.296782)
			(xy 334.216578 -417.277263) (xy 334.209107 -417.254312) (xy 334.208628 -417.242244) (xy 332.444344 -417.242244)
			(xy 332.443874 -417.254317) (xy 332.436404 -417.27728) (xy 332.422207 -417.296813) (xy 332.402673 -417.311007)
			(xy 332.379709 -417.318475) (xy 332.367636 -417.318952) (xy 332.173072 -417.318952) (xy 332.161964 -417.318588)
			(xy 332.140668 -417.312264) (xy 332.131162 -417.306506) (xy 331.836268 -417.113974) (xy 331.826881 -417.108271)
			(xy 331.805843 -417.101998) (xy 331.783889 -417.101998) (xy 331.762851 -417.108271) (xy 331.753464 -417.113974)
			(xy 331.45984 -417.306506) (xy 331.450329 -417.312253) (xy 331.429036 -417.318579) (xy 331.41793 -417.318952)
			(xy 331.222096 -417.318952) (xy 331.210026 -417.31844) (xy 331.187066 -417.310982) (xy 331.167533 -417.296796)
			(xy 331.153337 -417.27727) (xy 331.145867 -417.254314) (xy 331.145388 -417.242244) (xy 329.381104 -417.242244)
			(xy 329.380673 -417.254321) (xy 329.373198 -417.277291) (xy 329.358993 -417.296827) (xy 329.339448 -417.31102)
			(xy 329.316474 -417.318481) (xy 329.304396 -417.318952) (xy 329.109832 -417.318952) (xy 329.098723 -417.318604)
			(xy 329.077427 -417.312269) (xy 329.067922 -417.306506) (xy 328.773028 -417.113974) (xy 328.763641 -417.108271)
			(xy 328.742603 -417.101998) (xy 328.720649 -417.101998) (xy 328.699611 -417.108271) (xy 328.690224 -417.113974)
			(xy 328.3966 -417.306506) (xy 328.387097 -417.312268) (xy 328.365798 -417.318585) (xy 328.35469 -417.318952)
			(xy 328.158856 -417.318952) (xy 328.146784 -417.318474) (xy 328.123822 -417.311005) (xy 328.10429 -417.29681)
			(xy 328.090095 -417.277278) (xy 328.082626 -417.254316) (xy 328.082148 -417.242244) (xy 326.317864 -417.242244)
			(xy 326.317473 -417.254325) (xy 326.309993 -417.277301) (xy 326.295779 -417.296842) (xy 326.276222 -417.311033)
			(xy 326.253238 -417.318487) (xy 326.241156 -417.318952) (xy 326.046592 -417.318952) (xy 326.035485 -417.31858)
			(xy 326.014188 -417.312262) (xy 326.004682 -417.306506) (xy 325.709788 -417.113974) (xy 325.700401 -417.108271)
			(xy 325.679363 -417.101998) (xy 325.657409 -417.101998) (xy 325.636371 -417.108271) (xy 325.626984 -417.113974)
			(xy 325.33336 -417.306506) (xy 325.323845 -417.312246) (xy 325.302555 -417.318577) (xy 325.29145 -417.318952)
			(xy 325.095616 -417.318952) (xy 325.083547 -417.318423) (xy 325.060587 -417.31097) (xy 325.041054 -417.296789)
			(xy 325.026857 -417.277266) (xy 325.019387 -417.254313) (xy 325.018908 -417.242244) (xy 323.254624 -417.242244)
			(xy 323.254174 -417.254319) (xy 323.246701 -417.277285) (xy 323.2325 -417.29682) (xy 323.21296 -417.311014)
			(xy 323.189991 -417.318478) (xy 323.177916 -417.318952) (xy 322.983352 -417.318952) (xy 322.972243 -417.318596)
			(xy 322.950947 -417.312267) (xy 322.941442 -417.306506) (xy 322.646548 -417.113974) (xy 322.637161 -417.108271)
			(xy 322.616123 -417.101998) (xy 322.594169 -417.101998) (xy 322.573131 -417.108271) (xy 322.563744 -417.113974)
			(xy 322.27012 -417.306506) (xy 322.260613 -417.312261) (xy 322.239317 -417.318582) (xy 322.22821 -417.318952)
			(xy 322.032376 -417.318952) (xy 322.020305 -417.318457) (xy 321.997344 -417.310993) (xy 321.977811 -417.296803)
			(xy 321.963616 -417.277274) (xy 321.956146 -417.254315) (xy 321.955668 -417.242244) (xy 320.191384 -417.242244)
			(xy 320.190973 -417.254323) (xy 320.183496 -417.277296) (xy 320.169286 -417.296834) (xy 320.149735 -417.311027)
			(xy 320.126756 -417.318484) (xy 320.114676 -417.318952) (xy 319.920112 -417.318952) (xy 319.909005 -417.318571)
			(xy 319.887709 -417.312259) (xy 319.878202 -417.306506) (xy 319.583308 -417.113974) (xy 319.573921 -417.108271)
			(xy 319.552883 -417.101998) (xy 319.530929 -417.101998) (xy 319.509891 -417.108271) (xy 319.500504 -417.113974)
			(xy 319.20688 -417.306506) (xy 319.197361 -417.312239) (xy 319.176074 -417.318574) (xy 319.16497 -417.318952)
			(xy 318.969136 -417.318952) (xy 318.957068 -417.318406) (xy 318.934109 -417.310959) (xy 318.914575 -417.296782)
			(xy 318.900378 -417.277263) (xy 318.892907 -417.254312) (xy 318.892428 -417.242244) (xy 317.128144 -417.242244)
			(xy 317.127674 -417.254317) (xy 317.120204 -417.27728) (xy 317.106007 -417.296813) (xy 317.086473 -417.311007)
			(xy 317.063509 -417.318475) (xy 317.051436 -417.318952) (xy 316.856872 -417.318952) (xy 316.845764 -417.318588)
			(xy 316.824468 -417.312264) (xy 316.814962 -417.306506) (xy 316.520068 -417.113974) (xy 316.510681 -417.108271)
			(xy 316.489643 -417.101998) (xy 316.467689 -417.101998) (xy 316.446651 -417.108271) (xy 316.437264 -417.113974)
			(xy 316.14364 -417.306506) (xy 316.134129 -417.312253) (xy 316.112836 -417.318579) (xy 316.10173 -417.318952)
			(xy 315.905896 -417.318952) (xy 315.893826 -417.31844) (xy 315.870866 -417.310982) (xy 315.851333 -417.296796)
			(xy 315.837137 -417.27727) (xy 315.829667 -417.254314) (xy 315.829188 -417.242244) (xy 314.064904 -417.242244)
			(xy 314.064473 -417.254321) (xy 314.056998 -417.277291) (xy 314.042793 -417.296827) (xy 314.023248 -417.31102)
			(xy 314.000274 -417.318481) (xy 313.988196 -417.318952) (xy 313.793632 -417.318952) (xy 313.782523 -417.318604)
			(xy 313.761227 -417.312269) (xy 313.751722 -417.306506) (xy 313.456828 -417.113974) (xy 313.447441 -417.108271)
			(xy 313.426403 -417.101998) (xy 313.404449 -417.101998) (xy 313.383411 -417.108271) (xy 313.374024 -417.113974)
			(xy 313.0804 -417.306506) (xy 313.070897 -417.312268) (xy 313.049598 -417.318585) (xy 313.03849 -417.318952)
			(xy 312.842656 -417.318952) (xy 312.830584 -417.318474) (xy 312.807622 -417.311005) (xy 312.78809 -417.29681)
			(xy 312.773895 -417.277278) (xy 312.766426 -417.254316) (xy 312.765948 -417.242244) (xy 311.001664 -417.242244)
			(xy 311.001273 -417.254325) (xy 310.993793 -417.277301) (xy 310.979579 -417.296842) (xy 310.960022 -417.311033)
			(xy 310.937038 -417.318487) (xy 310.924956 -417.318952) (xy 310.730392 -417.318952) (xy 310.719285 -417.31858)
			(xy 310.697988 -417.312262) (xy 310.688482 -417.306506) (xy 310.393588 -417.113974) (xy 310.384201 -417.108271)
			(xy 310.363163 -417.101998) (xy 310.341209 -417.101998) (xy 310.320171 -417.108271) (xy 310.310784 -417.113974)
			(xy 310.01716 -417.306506) (xy 310.007645 -417.312246) (xy 309.986355 -417.318577) (xy 309.97525 -417.318952)
			(xy 309.779416 -417.318952) (xy 309.767347 -417.318423) (xy 309.744387 -417.31097) (xy 309.724854 -417.296789)
			(xy 309.710657 -417.277266) (xy 309.703187 -417.254313) (xy 309.702708 -417.242244) (xy 307.938424 -417.242244)
			(xy 307.937974 -417.254319) (xy 307.930501 -417.277285) (xy 307.9163 -417.29682) (xy 307.89676 -417.311014)
			(xy 307.873791 -417.318478) (xy 307.861716 -417.318952) (xy 307.667152 -417.318952) (xy 307.656043 -417.318596)
			(xy 307.634747 -417.312267) (xy 307.625242 -417.306506) (xy 307.330348 -417.113974) (xy 307.320961 -417.108271)
			(xy 307.299923 -417.101998) (xy 307.277969 -417.101998) (xy 307.256931 -417.108271) (xy 307.247544 -417.113974)
			(xy 306.95392 -417.306506) (xy 306.944413 -417.312261) (xy 306.923117 -417.318582) (xy 306.91201 -417.318952)
			(xy 306.716176 -417.318952) (xy 306.704105 -417.318457) (xy 306.681144 -417.310993) (xy 306.661611 -417.296803)
			(xy 306.647416 -417.277274) (xy 306.639946 -417.254315) (xy 306.639468 -417.242244) (xy 304.875184 -417.242244)
			(xy 304.874773 -417.254323) (xy 304.867296 -417.277296) (xy 304.853086 -417.296834) (xy 304.833535 -417.311027)
			(xy 304.810556 -417.318484) (xy 304.798476 -417.318952) (xy 304.603912 -417.318952) (xy 304.592805 -417.318571)
			(xy 304.571509 -417.312259) (xy 304.562002 -417.306506) (xy 304.267108 -417.113974) (xy 304.257721 -417.108271)
			(xy 304.236683 -417.101998) (xy 304.214729 -417.101998) (xy 304.193691 -417.108271) (xy 304.184304 -417.113974)
			(xy 303.89068 -417.306506) (xy 303.881161 -417.312239) (xy 303.859874 -417.318574) (xy 303.84877 -417.318952)
			(xy 303.652936 -417.318952) (xy 303.640868 -417.318406) (xy 303.617909 -417.310959) (xy 303.598375 -417.296782)
			(xy 303.584178 -417.277263) (xy 303.576707 -417.254312) (xy 303.576228 -417.242244) (xy 290.186237 -417.242244)
			(xy 290.193247 -417.257594) (xy 290.208602 -417.309889) (xy 290.216358 -417.363837) (xy 290.216844 -417.391088)
			(xy 290.216844 -418.254688) (xy 290.216358 -418.281939) (xy 290.208602 -418.335887) (xy 290.193247 -418.388182)
			(xy 290.170605 -418.437759) (xy 290.169514 -418.439456) (xy 304.944423 -418.439456) (xy 304.944423 -418.384944)
			(xy 304.952181 -418.330986) (xy 304.96754 -418.278681) (xy 304.990186 -418.229095) (xy 305.019659 -418.183237)
			(xy 305.055359 -418.14204) (xy 305.096558 -418.106344) (xy 305.142418 -418.076874) (xy 305.192006 -418.054231)
			(xy 305.244311 -418.038876) (xy 305.29827 -418.031121) (xy 305.325526 -418.03066) (xy 306.189126 -418.03066)
			(xy 306.216374 -418.031212) (xy 306.270314 -418.038971) (xy 306.322601 -418.054327) (xy 306.372171 -418.076968)
			(xy 306.418014 -418.106432) (xy 306.459198 -418.142121) (xy 306.494884 -418.183307) (xy 306.524345 -418.229152)
			(xy 306.546982 -418.278723) (xy 306.562335 -418.331011) (xy 306.57009 -418.384952) (xy 306.57009 -418.439448)
			(xy 306.570089 -418.439452) (xy 308.007746 -418.439452) (xy 308.007746 -418.384948) (xy 308.015502 -418.330999)
			(xy 308.030857 -418.278702) (xy 308.053497 -418.229123) (xy 308.082963 -418.183271) (xy 308.118654 -418.142078)
			(xy 308.159843 -418.106383) (xy 308.205693 -418.076914) (xy 308.25527 -418.054269) (xy 308.307565 -418.038909)
			(xy 308.361514 -418.031148) (xy 308.388766 -418.03066) (xy 309.252366 -418.03066) (xy 309.279618 -418.031185)
			(xy 309.333568 -418.038937) (xy 309.385866 -418.054289) (xy 309.435446 -418.076928) (xy 309.4813 -418.106392)
			(xy 309.522493 -418.142083) (xy 309.558187 -418.183273) (xy 309.587656 -418.229124) (xy 309.610299 -418.278702)
			(xy 309.625655 -418.330999) (xy 309.633413 -418.384948) (xy 309.633413 -418.439452) (xy 309.633413 -418.439455)
			(xy 311.070923 -418.439455) (xy 311.070923 -418.384945) (xy 311.078681 -418.330989) (xy 311.094038 -418.278686)
			(xy 311.116683 -418.229101) (xy 311.146154 -418.183244) (xy 311.181852 -418.142047) (xy 311.223049 -418.106351)
			(xy 311.268906 -418.07688) (xy 311.318491 -418.054236) (xy 311.370794 -418.038879) (xy 311.424751 -418.031123)
			(xy 311.452006 -418.03066) (xy 312.315606 -418.03066) (xy 312.342855 -418.031211) (xy 312.396797 -418.038967)
			(xy 312.449087 -418.054321) (xy 312.498659 -418.076961) (xy 312.544505 -418.106425) (xy 312.585691 -418.142113)
			(xy 312.621379 -418.1833) (xy 312.650842 -418.229146) (xy 312.673481 -418.278719) (xy 312.688834 -418.331009)
			(xy 312.69659 -418.384951) (xy 312.69659 -418.439449) (xy 312.696589 -418.439457) (xy 314.134123 -418.439457)
			(xy 314.134123 -418.384943) (xy 314.141882 -418.330983) (xy 314.157242 -418.278677) (xy 314.179889 -418.22909)
			(xy 314.209364 -418.183231) (xy 314.245066 -418.142033) (xy 314.286267 -418.106337) (xy 314.33213 -418.076867)
			(xy 314.38172 -418.054225) (xy 314.434028 -418.038872) (xy 314.487989 -418.03112) (xy 314.515246 -418.03066)
			(xy 315.378846 -418.03066) (xy 315.406093 -418.031213) (xy 315.460031 -418.038975) (xy 315.512316 -418.054332)
			(xy 315.561883 -418.076974) (xy 315.607724 -418.106439) (xy 315.648905 -418.142128) (xy 315.684588 -418.183313)
			(xy 315.714048 -418.229157) (xy 315.736684 -418.278727) (xy 315.752035 -418.331014) (xy 315.75979 -418.384953)
			(xy 315.75979 -418.439447) (xy 315.759789 -418.439453) (xy 317.197446 -418.439453) (xy 317.197446 -418.384947)
			(xy 317.205203 -418.330996) (xy 317.220558 -418.278698) (xy 317.2432 -418.229118) (xy 317.272668 -418.183264)
			(xy 317.308361 -418.142071) (xy 317.349553 -418.106376) (xy 317.395405 -418.076907) (xy 317.444985 -418.054263)
			(xy 317.497282 -418.038906) (xy 317.551233 -418.031147) (xy 317.578486 -418.03066) (xy 318.442086 -418.03066)
			(xy 318.469337 -418.031186) (xy 318.523285 -418.038941) (xy 318.57558 -418.054295) (xy 318.625158 -418.076934)
			(xy 318.671009 -418.106399) (xy 318.7122 -418.14209) (xy 318.747892 -418.18328) (xy 318.777359 -418.22913)
			(xy 318.800001 -418.278707) (xy 318.815356 -418.331001) (xy 318.823113 -418.384949) (xy 318.823113 -418.439451)
			(xy 318.823112 -418.439456) (xy 320.260623 -418.439456) (xy 320.260623 -418.384944) (xy 320.268381 -418.330986)
			(xy 320.28374 -418.278681) (xy 320.306386 -418.229095) (xy 320.335859 -418.183237) (xy 320.371559 -418.14204)
			(xy 320.412758 -418.106344) (xy 320.458618 -418.076874) (xy 320.508206 -418.054231) (xy 320.560511 -418.038876)
			(xy 320.61447 -418.031121) (xy 320.641726 -418.03066) (xy 321.505326 -418.03066) (xy 321.532574 -418.031212)
			(xy 321.586514 -418.038971) (xy 321.638801 -418.054327) (xy 321.688371 -418.076968) (xy 321.734214 -418.106432)
			(xy 321.775398 -418.142121) (xy 321.811084 -418.183307) (xy 321.840545 -418.229152) (xy 321.863182 -418.278723)
			(xy 321.878535 -418.331011) (xy 321.88629 -418.384952) (xy 321.88629 -418.439448) (xy 321.886289 -418.439452)
			(xy 323.323946 -418.439452) (xy 323.323946 -418.384948) (xy 323.331702 -418.330999) (xy 323.347057 -418.278702)
			(xy 323.369697 -418.229123) (xy 323.399163 -418.183271) (xy 323.434854 -418.142078) (xy 323.476043 -418.106383)
			(xy 323.521893 -418.076914) (xy 323.57147 -418.054269) (xy 323.623765 -418.038909) (xy 323.677714 -418.031148)
			(xy 323.704966 -418.03066) (xy 324.568566 -418.03066) (xy 324.595818 -418.031185) (xy 324.649768 -418.038937)
			(xy 324.702066 -418.054289) (xy 324.751646 -418.076928) (xy 324.7975 -418.106392) (xy 324.838693 -418.142083)
			(xy 324.874387 -418.183273) (xy 324.903856 -418.229124) (xy 324.926499 -418.278702) (xy 324.941855 -418.330999)
			(xy 324.949613 -418.384948) (xy 324.949613 -418.439452) (xy 324.949613 -418.439455) (xy 326.387123 -418.439455)
			(xy 326.387123 -418.384945) (xy 326.394881 -418.330989) (xy 326.410238 -418.278686) (xy 326.432883 -418.229101)
			(xy 326.462354 -418.183244) (xy 326.498052 -418.142047) (xy 326.539249 -418.106351) (xy 326.585106 -418.07688)
			(xy 326.634691 -418.054236) (xy 326.686994 -418.038879) (xy 326.740951 -418.031123) (xy 326.768206 -418.03066)
			(xy 327.631806 -418.03066) (xy 327.659055 -418.031211) (xy 327.712997 -418.038967) (xy 327.765287 -418.054321)
			(xy 327.814859 -418.076961) (xy 327.860705 -418.106425) (xy 327.901891 -418.142113) (xy 327.937579 -418.1833)
			(xy 327.967042 -418.229146) (xy 327.989681 -418.278719) (xy 328.005034 -418.331009) (xy 328.01279 -418.384951)
			(xy 328.01279 -418.439449) (xy 328.012789 -418.439457) (xy 329.450323 -418.439457) (xy 329.450323 -418.384943)
			(xy 329.458082 -418.330983) (xy 329.473442 -418.278677) (xy 329.496089 -418.22909) (xy 329.525564 -418.183231)
			(xy 329.561266 -418.142033) (xy 329.602467 -418.106337) (xy 329.64833 -418.076867) (xy 329.69792 -418.054225)
			(xy 329.750228 -418.038872) (xy 329.804189 -418.03112) (xy 329.831446 -418.03066) (xy 330.695046 -418.03066)
			(xy 330.722293 -418.031213) (xy 330.776231 -418.038975) (xy 330.828516 -418.054332) (xy 330.878083 -418.076974)
			(xy 330.923924 -418.106439) (xy 330.965105 -418.142128) (xy 331.000788 -418.183313) (xy 331.030248 -418.229157)
			(xy 331.052884 -418.278727) (xy 331.068235 -418.331014) (xy 331.07599 -418.384953) (xy 331.07599 -418.439447)
			(xy 331.075989 -418.439453) (xy 332.513646 -418.439453) (xy 332.513646 -418.384947) (xy 332.521403 -418.330996)
			(xy 332.536758 -418.278698) (xy 332.5594 -418.229118) (xy 332.588868 -418.183264) (xy 332.624561 -418.142071)
			(xy 332.665753 -418.106376) (xy 332.711605 -418.076907) (xy 332.761185 -418.054263) (xy 332.813482 -418.038906)
			(xy 332.867433 -418.031147) (xy 332.894686 -418.03066) (xy 333.758286 -418.03066) (xy 333.785537 -418.031186)
			(xy 333.839485 -418.038941) (xy 333.89178 -418.054295) (xy 333.941358 -418.076934) (xy 333.987209 -418.106399)
			(xy 334.0284 -418.14209) (xy 334.064092 -418.18328) (xy 334.093559 -418.22913) (xy 334.116201 -418.278707)
			(xy 334.131556 -418.331001) (xy 334.139313 -418.384949) (xy 334.139313 -418.439451) (xy 334.139312 -418.439456)
			(xy 335.576823 -418.439456) (xy 335.576823 -418.384944) (xy 335.584581 -418.330986) (xy 335.59994 -418.278681)
			(xy 335.622586 -418.229095) (xy 335.652059 -418.183237) (xy 335.687759 -418.14204) (xy 335.728958 -418.106344)
			(xy 335.774818 -418.076874) (xy 335.824406 -418.054231) (xy 335.876711 -418.038876) (xy 335.93067 -418.031121)
			(xy 335.957926 -418.03066) (xy 336.821526 -418.03066) (xy 336.848774 -418.031212) (xy 336.902714 -418.038971)
			(xy 336.955001 -418.054327) (xy 337.004571 -418.076968) (xy 337.050414 -418.106432) (xy 337.091598 -418.142121)
			(xy 337.127284 -418.183307) (xy 337.156745 -418.229152) (xy 337.179382 -418.278723) (xy 337.194735 -418.331011)
			(xy 337.20249 -418.384952) (xy 337.20249 -418.439448) (xy 337.202489 -418.439452) (xy 338.640146 -418.439452)
			(xy 338.640146 -418.384948) (xy 338.647902 -418.330999) (xy 338.663257 -418.278702) (xy 338.685897 -418.229123)
			(xy 338.715363 -418.183271) (xy 338.751054 -418.142078) (xy 338.792243 -418.106383) (xy 338.838093 -418.076914)
			(xy 338.88767 -418.054269) (xy 338.939965 -418.038909) (xy 338.993914 -418.031148) (xy 339.021166 -418.03066)
			(xy 339.884766 -418.03066) (xy 339.912018 -418.031185) (xy 339.965968 -418.038937) (xy 340.018266 -418.054289)
			(xy 340.067846 -418.076928) (xy 340.1137 -418.106392) (xy 340.154893 -418.142083) (xy 340.190587 -418.183273)
			(xy 340.220056 -418.229124) (xy 340.242699 -418.278702) (xy 340.258055 -418.330999) (xy 340.265813 -418.384948)
			(xy 340.265813 -418.439452) (xy 340.265813 -418.439455) (xy 341.703323 -418.439455) (xy 341.703323 -418.384945)
			(xy 341.711081 -418.330989) (xy 341.726438 -418.278686) (xy 341.749083 -418.229101) (xy 341.778554 -418.183244)
			(xy 341.814252 -418.142047) (xy 341.855449 -418.106351) (xy 341.901306 -418.07688) (xy 341.950891 -418.054236)
			(xy 342.003194 -418.038879) (xy 342.057151 -418.031123) (xy 342.084406 -418.03066) (xy 342.948006 -418.03066)
			(xy 342.975255 -418.031211) (xy 343.029197 -418.038967) (xy 343.081487 -418.054321) (xy 343.131059 -418.076961)
			(xy 343.176905 -418.106425) (xy 343.218091 -418.142113) (xy 343.253779 -418.1833) (xy 343.283242 -418.229146)
			(xy 343.305881 -418.278719) (xy 343.321234 -418.331009) (xy 343.32899 -418.384951) (xy 343.32899 -418.439449)
			(xy 343.328989 -418.439457) (xy 344.766523 -418.439457) (xy 344.766523 -418.384943) (xy 344.774282 -418.330983)
			(xy 344.789642 -418.278677) (xy 344.812289 -418.22909) (xy 344.841764 -418.183231) (xy 344.877466 -418.142033)
			(xy 344.918667 -418.106337) (xy 344.96453 -418.076867) (xy 345.01412 -418.054225) (xy 345.066428 -418.038872)
			(xy 345.120389 -418.03112) (xy 345.147646 -418.03066) (xy 346.011246 -418.03066) (xy 346.038493 -418.031213)
			(xy 346.092431 -418.038975) (xy 346.144716 -418.054332) (xy 346.194283 -418.076974) (xy 346.240124 -418.106439)
			(xy 346.281305 -418.142128) (xy 346.316988 -418.183313) (xy 346.346448 -418.229157) (xy 346.369084 -418.278727)
			(xy 346.384435 -418.331014) (xy 346.39219 -418.384953) (xy 346.39219 -418.439447) (xy 346.392189 -418.439453)
			(xy 347.829846 -418.439453) (xy 347.829846 -418.384947) (xy 347.837603 -418.330996) (xy 347.852958 -418.278698)
			(xy 347.8756 -418.229118) (xy 347.905068 -418.183264) (xy 347.940761 -418.142071) (xy 347.981953 -418.106376)
			(xy 348.027805 -418.076907) (xy 348.077385 -418.054263) (xy 348.129682 -418.038906) (xy 348.183633 -418.031147)
			(xy 348.210886 -418.03066) (xy 349.074486 -418.03066) (xy 349.101737 -418.031186) (xy 349.155685 -418.038941)
			(xy 349.20798 -418.054295) (xy 349.257558 -418.076934) (xy 349.303409 -418.106399) (xy 349.3446 -418.14209)
			(xy 349.380292 -418.18328) (xy 349.409759 -418.22913) (xy 349.432401 -418.278707) (xy 349.447756 -418.331001)
			(xy 349.455513 -418.384949) (xy 349.455513 -418.439451) (xy 349.455512 -418.439456) (xy 350.893023 -418.439456)
			(xy 350.893023 -418.384944) (xy 350.900781 -418.330986) (xy 350.91614 -418.278681) (xy 350.938786 -418.229095)
			(xy 350.968259 -418.183237) (xy 351.003959 -418.14204) (xy 351.045158 -418.106344) (xy 351.091018 -418.076874)
			(xy 351.140606 -418.054231) (xy 351.192911 -418.038876) (xy 351.24687 -418.031121) (xy 351.274126 -418.03066)
			(xy 352.137726 -418.03066) (xy 352.164974 -418.031212) (xy 352.218914 -418.038971) (xy 352.271201 -418.054327)
			(xy 352.320771 -418.076968) (xy 352.366614 -418.106432) (xy 352.407798 -418.142121) (xy 352.443484 -418.183307)
			(xy 352.472945 -418.229152) (xy 352.495582 -418.278723) (xy 352.510935 -418.331011) (xy 352.51869 -418.384952)
			(xy 352.51869 -418.439448) (xy 352.510935 -418.493389) (xy 352.495582 -418.545677) (xy 352.472945 -418.595248)
			(xy 352.443484 -418.641093) (xy 352.407798 -418.682279) (xy 352.366614 -418.717968) (xy 352.320771 -418.747432)
			(xy 352.271201 -418.770073) (xy 352.218914 -418.785429) (xy 352.164974 -418.793188) (xy 352.137726 -418.793676)
			(xy 351.274126 -418.793676) (xy 351.24687 -418.793279) (xy 351.192911 -418.785524) (xy 351.140606 -418.770169)
			(xy 351.091018 -418.747526) (xy 351.045158 -418.718056) (xy 351.003959 -418.68236) (xy 350.968259 -418.641163)
			(xy 350.938786 -418.595305) (xy 350.91614 -418.545719) (xy 350.900781 -418.493414) (xy 350.893023 -418.439456)
			(xy 349.455512 -418.439456) (xy 349.447756 -418.493399) (xy 349.432401 -418.545693) (xy 349.409759 -418.59527)
			(xy 349.380292 -418.64112) (xy 349.3446 -418.68231) (xy 349.303409 -418.718001) (xy 349.257558 -418.747466)
			(xy 349.20798 -418.770105) (xy 349.155685 -418.785459) (xy 349.101737 -418.793214) (xy 349.074486 -418.793676)
			(xy 348.210886 -418.793676) (xy 348.183633 -418.793253) (xy 348.129682 -418.785494) (xy 348.077385 -418.770137)
			(xy 348.027805 -418.747493) (xy 347.981953 -418.718024) (xy 347.940761 -418.682329) (xy 347.905068 -418.641136)
			(xy 347.8756 -418.595282) (xy 347.852958 -418.545702) (xy 347.837603 -418.493404) (xy 347.829846 -418.439453)
			(xy 346.392189 -418.439453) (xy 346.384435 -418.493386) (xy 346.369084 -418.545673) (xy 346.346448 -418.595243)
			(xy 346.316988 -418.641087) (xy 346.281305 -418.682272) (xy 346.240124 -418.717961) (xy 346.194283 -418.747426)
			(xy 346.144716 -418.770068) (xy 346.092431 -418.785425) (xy 346.038493 -418.793187) (xy 346.011246 -418.793676)
			(xy 345.147646 -418.793676) (xy 345.120389 -418.79328) (xy 345.066428 -418.785528) (xy 345.01412 -418.770175)
			(xy 344.96453 -418.747533) (xy 344.918667 -418.718063) (xy 344.877466 -418.682367) (xy 344.841764 -418.641169)
			(xy 344.812289 -418.59531) (xy 344.789642 -418.545723) (xy 344.774282 -418.493417) (xy 344.766523 -418.439457)
			(xy 343.328989 -418.439457) (xy 343.321234 -418.493391) (xy 343.305881 -418.545681) (xy 343.283242 -418.595254)
			(xy 343.253779 -418.6411) (xy 343.218091 -418.682287) (xy 343.176905 -418.717975) (xy 343.131059 -418.747439)
			(xy 343.081487 -418.770079) (xy 343.029197 -418.785433) (xy 342.975255 -418.793189) (xy 342.948006 -418.793676)
			(xy 342.084406 -418.793676) (xy 342.057151 -418.793277) (xy 342.003194 -418.785521) (xy 341.950891 -418.770164)
			(xy 341.901306 -418.74752) (xy 341.855449 -418.718049) (xy 341.814252 -418.682353) (xy 341.778554 -418.641156)
			(xy 341.749083 -418.595299) (xy 341.726438 -418.545714) (xy 341.711081 -418.493411) (xy 341.703323 -418.439455)
			(xy 340.265813 -418.439455) (xy 340.258055 -418.493402) (xy 340.242699 -418.545698) (xy 340.220056 -418.595276)
			(xy 340.190587 -418.641127) (xy 340.154893 -418.682317) (xy 340.1137 -418.718008) (xy 340.067846 -418.747472)
			(xy 340.018266 -418.770111) (xy 339.965968 -418.785463) (xy 339.912018 -418.793215) (xy 339.884766 -418.793676)
			(xy 339.021166 -418.793676) (xy 338.993914 -418.793252) (xy 338.939965 -418.785491) (xy 338.88767 -418.770131)
			(xy 338.838093 -418.747486) (xy 338.792243 -418.718017) (xy 338.751054 -418.682322) (xy 338.715363 -418.641129)
			(xy 338.685897 -418.595277) (xy 338.663257 -418.545698) (xy 338.647902 -418.493401) (xy 338.640146 -418.439452)
			(xy 337.202489 -418.439452) (xy 337.194735 -418.493389) (xy 337.179382 -418.545677) (xy 337.156745 -418.595248)
			(xy 337.127284 -418.641093) (xy 337.091598 -418.682279) (xy 337.050414 -418.717968) (xy 337.004571 -418.747432)
			(xy 336.955001 -418.770073) (xy 336.902714 -418.785429) (xy 336.848774 -418.793188) (xy 336.821526 -418.793676)
			(xy 335.957926 -418.793676) (xy 335.93067 -418.793279) (xy 335.876711 -418.785524) (xy 335.824406 -418.770169)
			(xy 335.774818 -418.747526) (xy 335.728958 -418.718056) (xy 335.687759 -418.68236) (xy 335.652059 -418.641163)
			(xy 335.622586 -418.595305) (xy 335.59994 -418.545719) (xy 335.584581 -418.493414) (xy 335.576823 -418.439456)
			(xy 334.139312 -418.439456) (xy 334.131556 -418.493399) (xy 334.116201 -418.545693) (xy 334.093559 -418.59527)
			(xy 334.064092 -418.64112) (xy 334.0284 -418.68231) (xy 333.987209 -418.718001) (xy 333.941358 -418.747466)
			(xy 333.89178 -418.770105) (xy 333.839485 -418.785459) (xy 333.785537 -418.793214) (xy 333.758286 -418.793676)
			(xy 332.894686 -418.793676) (xy 332.867433 -418.793253) (xy 332.813482 -418.785494) (xy 332.761185 -418.770137)
			(xy 332.711605 -418.747493) (xy 332.665753 -418.718024) (xy 332.624561 -418.682329) (xy 332.588868 -418.641136)
			(xy 332.5594 -418.595282) (xy 332.536758 -418.545702) (xy 332.521403 -418.493404) (xy 332.513646 -418.439453)
			(xy 331.075989 -418.439453) (xy 331.068235 -418.493386) (xy 331.052884 -418.545673) (xy 331.030248 -418.595243)
			(xy 331.000788 -418.641087) (xy 330.965105 -418.682272) (xy 330.923924 -418.717961) (xy 330.878083 -418.747426)
			(xy 330.828516 -418.770068) (xy 330.776231 -418.785425) (xy 330.722293 -418.793187) (xy 330.695046 -418.793676)
			(xy 329.831446 -418.793676) (xy 329.804189 -418.79328) (xy 329.750228 -418.785528) (xy 329.69792 -418.770175)
			(xy 329.64833 -418.747533) (xy 329.602467 -418.718063) (xy 329.561266 -418.682367) (xy 329.525564 -418.641169)
			(xy 329.496089 -418.59531) (xy 329.473442 -418.545723) (xy 329.458082 -418.493417) (xy 329.450323 -418.439457)
			(xy 328.012789 -418.439457) (xy 328.005034 -418.493391) (xy 327.989681 -418.545681) (xy 327.967042 -418.595254)
			(xy 327.937579 -418.6411) (xy 327.901891 -418.682287) (xy 327.860705 -418.717975) (xy 327.814859 -418.747439)
			(xy 327.765287 -418.770079) (xy 327.712997 -418.785433) (xy 327.659055 -418.793189) (xy 327.631806 -418.793676)
			(xy 326.768206 -418.793676) (xy 326.740951 -418.793277) (xy 326.686994 -418.785521) (xy 326.634691 -418.770164)
			(xy 326.585106 -418.74752) (xy 326.539249 -418.718049) (xy 326.498052 -418.682353) (xy 326.462354 -418.641156)
			(xy 326.432883 -418.595299) (xy 326.410238 -418.545714) (xy 326.394881 -418.493411) (xy 326.387123 -418.439455)
			(xy 324.949613 -418.439455) (xy 324.941855 -418.493402) (xy 324.926499 -418.545698) (xy 324.903856 -418.595276)
			(xy 324.874387 -418.641127) (xy 324.838693 -418.682317) (xy 324.7975 -418.718008) (xy 324.751646 -418.747472)
			(xy 324.702066 -418.770111) (xy 324.649768 -418.785463) (xy 324.595818 -418.793215) (xy 324.568566 -418.793676)
			(xy 323.704966 -418.793676) (xy 323.677714 -418.793252) (xy 323.623765 -418.785491) (xy 323.57147 -418.770131)
			(xy 323.521893 -418.747486) (xy 323.476043 -418.718017) (xy 323.434854 -418.682322) (xy 323.399163 -418.641129)
			(xy 323.369697 -418.595277) (xy 323.347057 -418.545698) (xy 323.331702 -418.493401) (xy 323.323946 -418.439452)
			(xy 321.886289 -418.439452) (xy 321.878535 -418.493389) (xy 321.863182 -418.545677) (xy 321.840545 -418.595248)
			(xy 321.811084 -418.641093) (xy 321.775398 -418.682279) (xy 321.734214 -418.717968) (xy 321.688371 -418.747432)
			(xy 321.638801 -418.770073) (xy 321.586514 -418.785429) (xy 321.532574 -418.793188) (xy 321.505326 -418.793676)
			(xy 320.641726 -418.793676) (xy 320.61447 -418.793279) (xy 320.560511 -418.785524) (xy 320.508206 -418.770169)
			(xy 320.458618 -418.747526) (xy 320.412758 -418.718056) (xy 320.371559 -418.68236) (xy 320.335859 -418.641163)
			(xy 320.306386 -418.595305) (xy 320.28374 -418.545719) (xy 320.268381 -418.493414) (xy 320.260623 -418.439456)
			(xy 318.823112 -418.439456) (xy 318.815356 -418.493399) (xy 318.800001 -418.545693) (xy 318.777359 -418.59527)
			(xy 318.747892 -418.64112) (xy 318.7122 -418.68231) (xy 318.671009 -418.718001) (xy 318.625158 -418.747466)
			(xy 318.57558 -418.770105) (xy 318.523285 -418.785459) (xy 318.469337 -418.793214) (xy 318.442086 -418.793676)
			(xy 317.578486 -418.793676) (xy 317.551233 -418.793253) (xy 317.497282 -418.785494) (xy 317.444985 -418.770137)
			(xy 317.395405 -418.747493) (xy 317.349553 -418.718024) (xy 317.308361 -418.682329) (xy 317.272668 -418.641136)
			(xy 317.2432 -418.595282) (xy 317.220558 -418.545702) (xy 317.205203 -418.493404) (xy 317.197446 -418.439453)
			(xy 315.759789 -418.439453) (xy 315.752035 -418.493386) (xy 315.736684 -418.545673) (xy 315.714048 -418.595243)
			(xy 315.684588 -418.641087) (xy 315.648905 -418.682272) (xy 315.607724 -418.717961) (xy 315.561883 -418.747426)
			(xy 315.512316 -418.770068) (xy 315.460031 -418.785425) (xy 315.406093 -418.793187) (xy 315.378846 -418.793676)
			(xy 314.515246 -418.793676) (xy 314.487989 -418.79328) (xy 314.434028 -418.785528) (xy 314.38172 -418.770175)
			(xy 314.33213 -418.747533) (xy 314.286267 -418.718063) (xy 314.245066 -418.682367) (xy 314.209364 -418.641169)
			(xy 314.179889 -418.59531) (xy 314.157242 -418.545723) (xy 314.141882 -418.493417) (xy 314.134123 -418.439457)
			(xy 312.696589 -418.439457) (xy 312.688834 -418.493391) (xy 312.673481 -418.545681) (xy 312.650842 -418.595254)
			(xy 312.621379 -418.6411) (xy 312.585691 -418.682287) (xy 312.544505 -418.717975) (xy 312.498659 -418.747439)
			(xy 312.449087 -418.770079) (xy 312.396797 -418.785433) (xy 312.342855 -418.793189) (xy 312.315606 -418.793676)
			(xy 311.452006 -418.793676) (xy 311.424751 -418.793277) (xy 311.370794 -418.785521) (xy 311.318491 -418.770164)
			(xy 311.268906 -418.74752) (xy 311.223049 -418.718049) (xy 311.181852 -418.682353) (xy 311.146154 -418.641156)
			(xy 311.116683 -418.595299) (xy 311.094038 -418.545714) (xy 311.078681 -418.493411) (xy 311.070923 -418.439455)
			(xy 309.633413 -418.439455) (xy 309.625655 -418.493402) (xy 309.610299 -418.545698) (xy 309.587656 -418.595276)
			(xy 309.558187 -418.641127) (xy 309.522493 -418.682317) (xy 309.4813 -418.718008) (xy 309.435446 -418.747472)
			(xy 309.385866 -418.770111) (xy 309.333568 -418.785463) (xy 309.279618 -418.793215) (xy 309.252366 -418.793676)
			(xy 308.388766 -418.793676) (xy 308.361514 -418.793252) (xy 308.307565 -418.785491) (xy 308.25527 -418.770131)
			(xy 308.205693 -418.747486) (xy 308.159843 -418.718017) (xy 308.118654 -418.682322) (xy 308.082963 -418.641129)
			(xy 308.053497 -418.595277) (xy 308.030857 -418.545698) (xy 308.015502 -418.493401) (xy 308.007746 -418.439452)
			(xy 306.570089 -418.439452) (xy 306.562335 -418.493389) (xy 306.546982 -418.545677) (xy 306.524345 -418.595248)
			(xy 306.494884 -418.641093) (xy 306.459198 -418.682279) (xy 306.418014 -418.717968) (xy 306.372171 -418.747432)
			(xy 306.322601 -418.770073) (xy 306.270314 -418.785429) (xy 306.216374 -418.793188) (xy 306.189126 -418.793676)
			(xy 305.325526 -418.793676) (xy 305.29827 -418.793279) (xy 305.244311 -418.785524) (xy 305.192006 -418.770169)
			(xy 305.142418 -418.747526) (xy 305.096558 -418.718056) (xy 305.055359 -418.68236) (xy 305.019659 -418.641163)
			(xy 304.990186 -418.595305) (xy 304.96754 -418.545719) (xy 304.952181 -418.493414) (xy 304.944423 -418.439456)
			(xy 290.169514 -418.439456) (xy 290.141139 -418.483609) (xy 290.105448 -418.5248) (xy 290.064257 -418.560491)
			(xy 290.018407 -418.589957) (xy 289.96883 -418.612599) (xy 289.916535 -418.627954) (xy 289.862587 -418.63571)
			(xy 289.808085 -418.63571) (xy 289.754137 -418.627954) (xy 289.701842 -418.612599) (xy 289.652265 -418.589957)
			(xy 289.606415 -418.560491) (xy 289.565224 -418.5248) (xy 289.529533 -418.483609) (xy 289.500067 -418.437759)
			(xy 289.477425 -418.388182) (xy 289.46207 -418.335887) (xy 289.454314 -418.281939) (xy 289.453828 -418.254688)
			(xy 277.48484 -418.254688) (xy 277.48484 -419.081712) (xy 277.484354 -419.108963) (xy 277.476598 -419.162911)
			(xy 277.461243 -419.215206) (xy 277.438601 -419.264783) (xy 277.409135 -419.310633) (xy 277.373444 -419.351824)
			(xy 277.332253 -419.387515) (xy 277.286403 -419.416981) (xy 277.236826 -419.439623) (xy 277.184531 -419.454978)
			(xy 277.130583 -419.462734) (xy 277.076081 -419.462734) (xy 277.022133 -419.454978) (xy 276.969838 -419.439623)
			(xy 276.920261 -419.416981) (xy 276.874411 -419.387515) (xy 276.83322 -419.351824) (xy 276.797529 -419.310633)
			(xy 276.768063 -419.264783) (xy 276.745421 -419.215206) (xy 276.730066 -419.162911) (xy 276.72231 -419.108963)
			(xy 276.721824 -419.081712) (xy 233.545126 -419.081712) (xy 232.102406 -420.524432) (xy 290.829492 -420.524432)
			(xy 290.829492 -419.660832) (xy 290.829978 -419.633563) (xy 290.83774 -419.579579) (xy 290.853105 -419.527249)
			(xy 290.875762 -419.477639) (xy 290.905248 -419.431758) (xy 290.940963 -419.390541) (xy 290.98218 -419.354826)
			(xy 291.028061 -419.32534) (xy 291.077671 -419.302683) (xy 291.130001 -419.287318) (xy 291.183985 -419.279556)
			(xy 291.238523 -419.279556) (xy 291.292507 -419.287318) (xy 291.344837 -419.302683) (xy 291.394447 -419.32534)
			(xy 291.440328 -419.354826) (xy 291.481545 -419.390541) (xy 291.51726 -419.431758) (xy 291.546746 -419.477639)
			(xy 291.569403 -419.527249) (xy 291.584768 -419.579579) (xy 291.59253 -419.633563) (xy 291.593016 -419.660832)
			(xy 291.593016 -420.524432) (xy 291.59253 -420.551701) (xy 291.584768 -420.605685) (xy 291.569403 -420.658015)
			(xy 291.546746 -420.707625) (xy 291.51726 -420.753506) (xy 291.481545 -420.794723) (xy 291.440328 -420.830438)
			(xy 291.394447 -420.859924) (xy 291.344837 -420.882581) (xy 291.292507 -420.897946) (xy 291.238523 -420.905708)
			(xy 291.183985 -420.905708) (xy 291.130001 -420.897946) (xy 291.077671 -420.882581) (xy 291.028061 -420.859924)
			(xy 290.98218 -420.830438) (xy 290.940963 -420.794723) (xy 290.905248 -420.753506) (xy 290.875762 -420.707625)
			(xy 290.853105 -420.658015) (xy 290.83774 -420.605685) (xy 290.829978 -420.551701) (xy 290.829492 -420.524432)
			(xy 232.102406 -420.524432) (xy 231.647383 -420.979455) (xy 303.412823 -420.979455) (xy 303.412823 -420.924945)
			(xy 303.420581 -420.870989) (xy 303.435938 -420.818686) (xy 303.458583 -420.769101) (xy 303.488054 -420.723244)
			(xy 303.523752 -420.682047) (xy 303.564949 -420.646351) (xy 303.610806 -420.61688) (xy 303.660391 -420.594236)
			(xy 303.712694 -420.578879) (xy 303.766651 -420.571123) (xy 303.793906 -420.57066) (xy 304.657506 -420.57066)
			(xy 304.684755 -420.571211) (xy 304.738697 -420.578967) (xy 304.790987 -420.594321) (xy 304.840559 -420.616961)
			(xy 304.886405 -420.646425) (xy 304.927591 -420.682113) (xy 304.963279 -420.7233) (xy 304.992742 -420.769146)
			(xy 305.015381 -420.818719) (xy 305.030734 -420.871009) (xy 305.03849 -420.924951) (xy 305.03849 -420.979449)
			(xy 305.038489 -420.979457) (xy 306.476023 -420.979457) (xy 306.476023 -420.924943) (xy 306.483782 -420.870983)
			(xy 306.499142 -420.818677) (xy 306.521789 -420.76909) (xy 306.551264 -420.723231) (xy 306.586966 -420.682033)
			(xy 306.628167 -420.646337) (xy 306.67403 -420.616867) (xy 306.72362 -420.594225) (xy 306.775928 -420.578872)
			(xy 306.829889 -420.57112) (xy 306.857146 -420.57066) (xy 307.720746 -420.57066) (xy 307.747993 -420.571213)
			(xy 307.801931 -420.578975) (xy 307.854216 -420.594332) (xy 307.903783 -420.616974) (xy 307.949624 -420.646439)
			(xy 307.990805 -420.682128) (xy 308.026488 -420.723313) (xy 308.055948 -420.769157) (xy 308.078584 -420.818727)
			(xy 308.093935 -420.871014) (xy 308.10169 -420.924953) (xy 308.10169 -420.979447) (xy 308.101689 -420.979453)
			(xy 309.539346 -420.979453) (xy 309.539346 -420.924947) (xy 309.547103 -420.870996) (xy 309.562458 -420.818698)
			(xy 309.5851 -420.769118) (xy 309.614568 -420.723264) (xy 309.650261 -420.682071) (xy 309.691453 -420.646376)
			(xy 309.737305 -420.616907) (xy 309.786885 -420.594263) (xy 309.839182 -420.578906) (xy 309.893133 -420.571147)
			(xy 309.920386 -420.57066) (xy 310.783986 -420.57066) (xy 310.811237 -420.571186) (xy 310.865185 -420.578941)
			(xy 310.91748 -420.594295) (xy 310.967058 -420.616934) (xy 311.012909 -420.646399) (xy 311.0541 -420.68209)
			(xy 311.089792 -420.72328) (xy 311.119259 -420.76913) (xy 311.141901 -420.818707) (xy 311.157256 -420.871001)
			(xy 311.165013 -420.924949) (xy 311.165013 -420.979451) (xy 311.165012 -420.979456) (xy 312.602523 -420.979456)
			(xy 312.602523 -420.924944) (xy 312.610281 -420.870986) (xy 312.62564 -420.818681) (xy 312.648286 -420.769095)
			(xy 312.677759 -420.723237) (xy 312.713459 -420.68204) (xy 312.754658 -420.646344) (xy 312.800518 -420.616874)
			(xy 312.850106 -420.594231) (xy 312.902411 -420.578876) (xy 312.95637 -420.571121) (xy 312.983626 -420.57066)
			(xy 313.847226 -420.57066) (xy 313.874474 -420.571212) (xy 313.928414 -420.578971) (xy 313.980701 -420.594327)
			(xy 314.030271 -420.616968) (xy 314.076114 -420.646432) (xy 314.117298 -420.682121) (xy 314.152984 -420.723307)
			(xy 314.182445 -420.769152) (xy 314.205082 -420.818723) (xy 314.220435 -420.871011) (xy 314.22819 -420.924952)
			(xy 314.22819 -420.979448) (xy 314.228189 -420.979452) (xy 315.665846 -420.979452) (xy 315.665846 -420.924948)
			(xy 315.673602 -420.870999) (xy 315.688957 -420.818702) (xy 315.711597 -420.769123) (xy 315.741063 -420.723271)
			(xy 315.776754 -420.682078) (xy 315.817943 -420.646383) (xy 315.863793 -420.616914) (xy 315.91337 -420.594269)
			(xy 315.965665 -420.578909) (xy 316.019614 -420.571148) (xy 316.046866 -420.57066) (xy 316.910466 -420.57066)
			(xy 316.937718 -420.571185) (xy 316.991668 -420.578937) (xy 317.043966 -420.594289) (xy 317.093546 -420.616928)
			(xy 317.1394 -420.646392) (xy 317.180593 -420.682083) (xy 317.216287 -420.723273) (xy 317.245756 -420.769124)
			(xy 317.268399 -420.818702) (xy 317.283755 -420.870999) (xy 317.291513 -420.924948) (xy 317.291513 -420.979452)
			(xy 317.291513 -420.979455) (xy 318.729023 -420.979455) (xy 318.729023 -420.924945) (xy 318.736781 -420.870989)
			(xy 318.752138 -420.818686) (xy 318.774783 -420.769101) (xy 318.804254 -420.723244) (xy 318.839952 -420.682047)
			(xy 318.881149 -420.646351) (xy 318.927006 -420.61688) (xy 318.976591 -420.594236) (xy 319.028894 -420.578879)
			(xy 319.082851 -420.571123) (xy 319.110106 -420.57066) (xy 319.973706 -420.57066) (xy 320.000955 -420.571211)
			(xy 320.054897 -420.578967) (xy 320.107187 -420.594321) (xy 320.156759 -420.616961) (xy 320.202605 -420.646425)
			(xy 320.243791 -420.682113) (xy 320.279479 -420.7233) (xy 320.308942 -420.769146) (xy 320.331581 -420.818719)
			(xy 320.346934 -420.871009) (xy 320.35469 -420.924951) (xy 320.35469 -420.979449) (xy 320.354689 -420.979457)
			(xy 321.792223 -420.979457) (xy 321.792223 -420.924943) (xy 321.799982 -420.870983) (xy 321.815342 -420.818677)
			(xy 321.837989 -420.76909) (xy 321.867464 -420.723231) (xy 321.903166 -420.682033) (xy 321.944367 -420.646337)
			(xy 321.99023 -420.616867) (xy 322.03982 -420.594225) (xy 322.092128 -420.578872) (xy 322.146089 -420.57112)
			(xy 322.173346 -420.57066) (xy 323.036946 -420.57066) (xy 323.064193 -420.571213) (xy 323.118131 -420.578975)
			(xy 323.170416 -420.594332) (xy 323.219983 -420.616974) (xy 323.265824 -420.646439) (xy 323.307005 -420.682128)
			(xy 323.342688 -420.723313) (xy 323.372148 -420.769157) (xy 323.394784 -420.818727) (xy 323.410135 -420.871014)
			(xy 323.41789 -420.924953) (xy 323.41789 -420.979447) (xy 323.417889 -420.979453) (xy 324.855546 -420.979453)
			(xy 324.855546 -420.924947) (xy 324.863303 -420.870996) (xy 324.878658 -420.818698) (xy 324.9013 -420.769118)
			(xy 324.930768 -420.723264) (xy 324.966461 -420.682071) (xy 325.007653 -420.646376) (xy 325.053505 -420.616907)
			(xy 325.103085 -420.594263) (xy 325.155382 -420.578906) (xy 325.209333 -420.571147) (xy 325.236586 -420.57066)
			(xy 326.100186 -420.57066) (xy 326.127437 -420.571186) (xy 326.181385 -420.578941) (xy 326.23368 -420.594295)
			(xy 326.283258 -420.616934) (xy 326.329109 -420.646399) (xy 326.3703 -420.68209) (xy 326.405992 -420.72328)
			(xy 326.435459 -420.76913) (xy 326.458101 -420.818707) (xy 326.473456 -420.871001) (xy 326.481213 -420.924949)
			(xy 326.481213 -420.979451) (xy 326.481212 -420.979456) (xy 327.918723 -420.979456) (xy 327.918723 -420.924944)
			(xy 327.926481 -420.870986) (xy 327.94184 -420.818681) (xy 327.964486 -420.769095) (xy 327.993959 -420.723237)
			(xy 328.029659 -420.68204) (xy 328.070858 -420.646344) (xy 328.116718 -420.616874) (xy 328.166306 -420.594231)
			(xy 328.218611 -420.578876) (xy 328.27257 -420.571121) (xy 328.299826 -420.57066) (xy 329.163426 -420.57066)
			(xy 329.190674 -420.571212) (xy 329.244614 -420.578971) (xy 329.296901 -420.594327) (xy 329.346471 -420.616968)
			(xy 329.392314 -420.646432) (xy 329.433498 -420.682121) (xy 329.469184 -420.723307) (xy 329.498645 -420.769152)
			(xy 329.521282 -420.818723) (xy 329.536635 -420.871011) (xy 329.54439 -420.924952) (xy 329.54439 -420.979448)
			(xy 329.544389 -420.979452) (xy 330.982046 -420.979452) (xy 330.982046 -420.924948) (xy 330.989802 -420.870999)
			(xy 331.005157 -420.818702) (xy 331.027797 -420.769123) (xy 331.057263 -420.723271) (xy 331.092954 -420.682078)
			(xy 331.134143 -420.646383) (xy 331.179993 -420.616914) (xy 331.22957 -420.594269) (xy 331.281865 -420.578909)
			(xy 331.335814 -420.571148) (xy 331.363066 -420.57066) (xy 332.226666 -420.57066) (xy 332.253918 -420.571185)
			(xy 332.307868 -420.578937) (xy 332.360166 -420.594289) (xy 332.409746 -420.616928) (xy 332.4556 -420.646392)
			(xy 332.496793 -420.682083) (xy 332.532487 -420.723273) (xy 332.561956 -420.769124) (xy 332.584599 -420.818702)
			(xy 332.599955 -420.870999) (xy 332.607713 -420.924948) (xy 332.607713 -420.979452) (xy 332.607713 -420.979455)
			(xy 334.045223 -420.979455) (xy 334.045223 -420.924945) (xy 334.052981 -420.870989) (xy 334.068338 -420.818686)
			(xy 334.090983 -420.769101) (xy 334.120454 -420.723244) (xy 334.156152 -420.682047) (xy 334.197349 -420.646351)
			(xy 334.243206 -420.61688) (xy 334.292791 -420.594236) (xy 334.345094 -420.578879) (xy 334.399051 -420.571123)
			(xy 334.426306 -420.57066) (xy 335.289906 -420.57066) (xy 335.317155 -420.571211) (xy 335.371097 -420.578967)
			(xy 335.423387 -420.594321) (xy 335.472959 -420.616961) (xy 335.518805 -420.646425) (xy 335.559991 -420.682113)
			(xy 335.595679 -420.7233) (xy 335.625142 -420.769146) (xy 335.647781 -420.818719) (xy 335.663134 -420.871009)
			(xy 335.67089 -420.924951) (xy 335.67089 -420.979449) (xy 335.670889 -420.979457) (xy 337.108423 -420.979457)
			(xy 337.108423 -420.924943) (xy 337.116182 -420.870983) (xy 337.131542 -420.818677) (xy 337.154189 -420.76909)
			(xy 337.183664 -420.723231) (xy 337.219366 -420.682033) (xy 337.260567 -420.646337) (xy 337.30643 -420.616867)
			(xy 337.35602 -420.594225) (xy 337.408328 -420.578872) (xy 337.462289 -420.57112) (xy 337.489546 -420.57066)
			(xy 338.353146 -420.57066) (xy 338.380393 -420.571213) (xy 338.434331 -420.578975) (xy 338.486616 -420.594332)
			(xy 338.536183 -420.616974) (xy 338.582024 -420.646439) (xy 338.623205 -420.682128) (xy 338.658888 -420.723313)
			(xy 338.688348 -420.769157) (xy 338.710984 -420.818727) (xy 338.726335 -420.871014) (xy 338.73409 -420.924953)
			(xy 338.73409 -420.979447) (xy 338.734089 -420.979453) (xy 340.171746 -420.979453) (xy 340.171746 -420.924947)
			(xy 340.179503 -420.870996) (xy 340.194858 -420.818698) (xy 340.2175 -420.769118) (xy 340.246968 -420.723264)
			(xy 340.282661 -420.682071) (xy 340.323853 -420.646376) (xy 340.369705 -420.616907) (xy 340.419285 -420.594263)
			(xy 340.471582 -420.578906) (xy 340.525533 -420.571147) (xy 340.552786 -420.57066) (xy 341.416386 -420.57066)
			(xy 341.443637 -420.571186) (xy 341.497585 -420.578941) (xy 341.54988 -420.594295) (xy 341.599458 -420.616934)
			(xy 341.645309 -420.646399) (xy 341.6865 -420.68209) (xy 341.722192 -420.72328) (xy 341.751659 -420.76913)
			(xy 341.774301 -420.818707) (xy 341.789656 -420.871001) (xy 341.797413 -420.924949) (xy 341.797413 -420.979451)
			(xy 341.797412 -420.979456) (xy 343.234923 -420.979456) (xy 343.234923 -420.924944) (xy 343.242681 -420.870986)
			(xy 343.25804 -420.818681) (xy 343.280686 -420.769095) (xy 343.310159 -420.723237) (xy 343.345859 -420.68204)
			(xy 343.387058 -420.646344) (xy 343.432918 -420.616874) (xy 343.482506 -420.594231) (xy 343.534811 -420.578876)
			(xy 343.58877 -420.571121) (xy 343.616026 -420.57066) (xy 344.479626 -420.57066) (xy 344.506874 -420.571212)
			(xy 344.560814 -420.578971) (xy 344.613101 -420.594327) (xy 344.662671 -420.616968) (xy 344.708514 -420.646432)
			(xy 344.749698 -420.682121) (xy 344.785384 -420.723307) (xy 344.814845 -420.769152) (xy 344.837482 -420.818723)
			(xy 344.852835 -420.871011) (xy 344.86059 -420.924952) (xy 344.86059 -420.979448) (xy 344.860589 -420.979452)
			(xy 346.298246 -420.979452) (xy 346.298246 -420.924948) (xy 346.306002 -420.870999) (xy 346.321357 -420.818702)
			(xy 346.343997 -420.769123) (xy 346.373463 -420.723271) (xy 346.409154 -420.682078) (xy 346.450343 -420.646383)
			(xy 346.496193 -420.616914) (xy 346.54577 -420.594269) (xy 346.598065 -420.578909) (xy 346.652014 -420.571148)
			(xy 346.679266 -420.57066) (xy 347.542866 -420.57066) (xy 347.570118 -420.571185) (xy 347.624068 -420.578937)
			(xy 347.676366 -420.594289) (xy 347.725946 -420.616928) (xy 347.7718 -420.646392) (xy 347.812993 -420.682083)
			(xy 347.848687 -420.723273) (xy 347.878156 -420.769124) (xy 347.900799 -420.818702) (xy 347.916155 -420.870999)
			(xy 347.923913 -420.924948) (xy 347.923913 -420.979452) (xy 347.923913 -420.979455) (xy 349.361423 -420.979455)
			(xy 349.361423 -420.924945) (xy 349.369181 -420.870989) (xy 349.384538 -420.818686) (xy 349.407183 -420.769101)
			(xy 349.436654 -420.723244) (xy 349.472352 -420.682047) (xy 349.513549 -420.646351) (xy 349.559406 -420.61688)
			(xy 349.608991 -420.594236) (xy 349.661294 -420.578879) (xy 349.715251 -420.571123) (xy 349.742506 -420.57066)
			(xy 350.606106 -420.57066) (xy 350.633355 -420.571211) (xy 350.687297 -420.578967) (xy 350.739587 -420.594321)
			(xy 350.789159 -420.616961) (xy 350.835005 -420.646425) (xy 350.876191 -420.682113) (xy 350.911879 -420.7233)
			(xy 350.941342 -420.769146) (xy 350.963981 -420.818719) (xy 350.979334 -420.871009) (xy 350.98709 -420.924951)
			(xy 350.98709 -420.979449) (xy 350.979334 -421.033391) (xy 350.963981 -421.085681) (xy 350.941342 -421.135254)
			(xy 350.911879 -421.1811) (xy 350.876191 -421.222287) (xy 350.835005 -421.257975) (xy 350.789159 -421.287439)
			(xy 350.739587 -421.310079) (xy 350.687297 -421.325433) (xy 350.633355 -421.333189) (xy 350.606106 -421.333676)
			(xy 349.742506 -421.333676) (xy 349.715251 -421.333277) (xy 349.661294 -421.325521) (xy 349.608991 -421.310164)
			(xy 349.559406 -421.28752) (xy 349.513549 -421.258049) (xy 349.472352 -421.222353) (xy 349.436654 -421.181156)
			(xy 349.407183 -421.135299) (xy 349.384538 -421.085714) (xy 349.369181 -421.033411) (xy 349.361423 -420.979455)
			(xy 347.923913 -420.979455) (xy 347.916155 -421.033402) (xy 347.900799 -421.085698) (xy 347.878156 -421.135276)
			(xy 347.848687 -421.181127) (xy 347.812993 -421.222317) (xy 347.7718 -421.258008) (xy 347.725946 -421.287472)
			(xy 347.676366 -421.310111) (xy 347.624068 -421.325463) (xy 347.570118 -421.333215) (xy 347.542866 -421.333676)
			(xy 346.679266 -421.333676) (xy 346.652014 -421.333252) (xy 346.598065 -421.325491) (xy 346.54577 -421.310131)
			(xy 346.496193 -421.287486) (xy 346.450343 -421.258017) (xy 346.409154 -421.222322) (xy 346.373463 -421.181129)
			(xy 346.343997 -421.135277) (xy 346.321357 -421.085698) (xy 346.306002 -421.033401) (xy 346.298246 -420.979452)
			(xy 344.860589 -420.979452) (xy 344.852835 -421.033389) (xy 344.837482 -421.085677) (xy 344.814845 -421.135248)
			(xy 344.785384 -421.181093) (xy 344.749698 -421.222279) (xy 344.708514 -421.257968) (xy 344.662671 -421.287432)
			(xy 344.613101 -421.310073) (xy 344.560814 -421.325429) (xy 344.506874 -421.333188) (xy 344.479626 -421.333676)
			(xy 343.616026 -421.333676) (xy 343.58877 -421.333279) (xy 343.534811 -421.325524) (xy 343.482506 -421.310169)
			(xy 343.432918 -421.287526) (xy 343.387058 -421.258056) (xy 343.345859 -421.22236) (xy 343.310159 -421.181163)
			(xy 343.280686 -421.135305) (xy 343.25804 -421.085719) (xy 343.242681 -421.033414) (xy 343.234923 -420.979456)
			(xy 341.797412 -420.979456) (xy 341.789656 -421.033399) (xy 341.774301 -421.085693) (xy 341.751659 -421.13527)
			(xy 341.722192 -421.18112) (xy 341.6865 -421.22231) (xy 341.645309 -421.258001) (xy 341.599458 -421.287466)
			(xy 341.54988 -421.310105) (xy 341.497585 -421.325459) (xy 341.443637 -421.333214) (xy 341.416386 -421.333676)
			(xy 340.552786 -421.333676) (xy 340.525533 -421.333253) (xy 340.471582 -421.325494) (xy 340.419285 -421.310137)
			(xy 340.369705 -421.287493) (xy 340.323853 -421.258024) (xy 340.282661 -421.222329) (xy 340.246968 -421.181136)
			(xy 340.2175 -421.135282) (xy 340.194858 -421.085702) (xy 340.179503 -421.033404) (xy 340.171746 -420.979453)
			(xy 338.734089 -420.979453) (xy 338.726335 -421.033386) (xy 338.710984 -421.085673) (xy 338.688348 -421.135243)
			(xy 338.658888 -421.181087) (xy 338.623205 -421.222272) (xy 338.582024 -421.257961) (xy 338.536183 -421.287426)
			(xy 338.486616 -421.310068) (xy 338.434331 -421.325425) (xy 338.380393 -421.333187) (xy 338.353146 -421.333676)
			(xy 337.489546 -421.333676) (xy 337.462289 -421.33328) (xy 337.408328 -421.325528) (xy 337.35602 -421.310175)
			(xy 337.30643 -421.287533) (xy 337.260567 -421.258063) (xy 337.219366 -421.222367) (xy 337.183664 -421.181169)
			(xy 337.154189 -421.13531) (xy 337.131542 -421.085723) (xy 337.116182 -421.033417) (xy 337.108423 -420.979457)
			(xy 335.670889 -420.979457) (xy 335.663134 -421.033391) (xy 335.647781 -421.085681) (xy 335.625142 -421.135254)
			(xy 335.595679 -421.1811) (xy 335.559991 -421.222287) (xy 335.518805 -421.257975) (xy 335.472959 -421.287439)
			(xy 335.423387 -421.310079) (xy 335.371097 -421.325433) (xy 335.317155 -421.333189) (xy 335.289906 -421.333676)
			(xy 334.426306 -421.333676) (xy 334.399051 -421.333277) (xy 334.345094 -421.325521) (xy 334.292791 -421.310164)
			(xy 334.243206 -421.28752) (xy 334.197349 -421.258049) (xy 334.156152 -421.222353) (xy 334.120454 -421.181156)
			(xy 334.090983 -421.135299) (xy 334.068338 -421.085714) (xy 334.052981 -421.033411) (xy 334.045223 -420.979455)
			(xy 332.607713 -420.979455) (xy 332.599955 -421.033402) (xy 332.584599 -421.085698) (xy 332.561956 -421.135276)
			(xy 332.532487 -421.181127) (xy 332.496793 -421.222317) (xy 332.4556 -421.258008) (xy 332.409746 -421.287472)
			(xy 332.360166 -421.310111) (xy 332.307868 -421.325463) (xy 332.253918 -421.333215) (xy 332.226666 -421.333676)
			(xy 331.363066 -421.333676) (xy 331.335814 -421.333252) (xy 331.281865 -421.325491) (xy 331.22957 -421.310131)
			(xy 331.179993 -421.287486) (xy 331.134143 -421.258017) (xy 331.092954 -421.222322) (xy 331.057263 -421.181129)
			(xy 331.027797 -421.135277) (xy 331.005157 -421.085698) (xy 330.989802 -421.033401) (xy 330.982046 -420.979452)
			(xy 329.544389 -420.979452) (xy 329.536635 -421.033389) (xy 329.521282 -421.085677) (xy 329.498645 -421.135248)
			(xy 329.469184 -421.181093) (xy 329.433498 -421.222279) (xy 329.392314 -421.257968) (xy 329.346471 -421.287432)
			(xy 329.296901 -421.310073) (xy 329.244614 -421.325429) (xy 329.190674 -421.333188) (xy 329.163426 -421.333676)
			(xy 328.299826 -421.333676) (xy 328.27257 -421.333279) (xy 328.218611 -421.325524) (xy 328.166306 -421.310169)
			(xy 328.116718 -421.287526) (xy 328.070858 -421.258056) (xy 328.029659 -421.22236) (xy 327.993959 -421.181163)
			(xy 327.964486 -421.135305) (xy 327.94184 -421.085719) (xy 327.926481 -421.033414) (xy 327.918723 -420.979456)
			(xy 326.481212 -420.979456) (xy 326.473456 -421.033399) (xy 326.458101 -421.085693) (xy 326.435459 -421.13527)
			(xy 326.405992 -421.18112) (xy 326.3703 -421.22231) (xy 326.329109 -421.258001) (xy 326.283258 -421.287466)
			(xy 326.23368 -421.310105) (xy 326.181385 -421.325459) (xy 326.127437 -421.333214) (xy 326.100186 -421.333676)
			(xy 325.236586 -421.333676) (xy 325.209333 -421.333253) (xy 325.155382 -421.325494) (xy 325.103085 -421.310137)
			(xy 325.053505 -421.287493) (xy 325.007653 -421.258024) (xy 324.966461 -421.222329) (xy 324.930768 -421.181136)
			(xy 324.9013 -421.135282) (xy 324.878658 -421.085702) (xy 324.863303 -421.033404) (xy 324.855546 -420.979453)
			(xy 323.417889 -420.979453) (xy 323.410135 -421.033386) (xy 323.394784 -421.085673) (xy 323.372148 -421.135243)
			(xy 323.342688 -421.181087) (xy 323.307005 -421.222272) (xy 323.265824 -421.257961) (xy 323.219983 -421.287426)
			(xy 323.170416 -421.310068) (xy 323.118131 -421.325425) (xy 323.064193 -421.333187) (xy 323.036946 -421.333676)
			(xy 322.173346 -421.333676) (xy 322.146089 -421.33328) (xy 322.092128 -421.325528) (xy 322.03982 -421.310175)
			(xy 321.99023 -421.287533) (xy 321.944367 -421.258063) (xy 321.903166 -421.222367) (xy 321.867464 -421.181169)
			(xy 321.837989 -421.13531) (xy 321.815342 -421.085723) (xy 321.799982 -421.033417) (xy 321.792223 -420.979457)
			(xy 320.354689 -420.979457) (xy 320.346934 -421.033391) (xy 320.331581 -421.085681) (xy 320.308942 -421.135254)
			(xy 320.279479 -421.1811) (xy 320.243791 -421.222287) (xy 320.202605 -421.257975) (xy 320.156759 -421.287439)
			(xy 320.107187 -421.310079) (xy 320.054897 -421.325433) (xy 320.000955 -421.333189) (xy 319.973706 -421.333676)
			(xy 319.110106 -421.333676) (xy 319.082851 -421.333277) (xy 319.028894 -421.325521) (xy 318.976591 -421.310164)
			(xy 318.927006 -421.28752) (xy 318.881149 -421.258049) (xy 318.839952 -421.222353) (xy 318.804254 -421.181156)
			(xy 318.774783 -421.135299) (xy 318.752138 -421.085714) (xy 318.736781 -421.033411) (xy 318.729023 -420.979455)
			(xy 317.291513 -420.979455) (xy 317.283755 -421.033402) (xy 317.268399 -421.085698) (xy 317.245756 -421.135276)
			(xy 317.216287 -421.181127) (xy 317.180593 -421.222317) (xy 317.1394 -421.258008) (xy 317.093546 -421.287472)
			(xy 317.043966 -421.310111) (xy 316.991668 -421.325463) (xy 316.937718 -421.333215) (xy 316.910466 -421.333676)
			(xy 316.046866 -421.333676) (xy 316.019614 -421.333252) (xy 315.965665 -421.325491) (xy 315.91337 -421.310131)
			(xy 315.863793 -421.287486) (xy 315.817943 -421.258017) (xy 315.776754 -421.222322) (xy 315.741063 -421.181129)
			(xy 315.711597 -421.135277) (xy 315.688957 -421.085698) (xy 315.673602 -421.033401) (xy 315.665846 -420.979452)
			(xy 314.228189 -420.979452) (xy 314.220435 -421.033389) (xy 314.205082 -421.085677) (xy 314.182445 -421.135248)
			(xy 314.152984 -421.181093) (xy 314.117298 -421.222279) (xy 314.076114 -421.257968) (xy 314.030271 -421.287432)
			(xy 313.980701 -421.310073) (xy 313.928414 -421.325429) (xy 313.874474 -421.333188) (xy 313.847226 -421.333676)
			(xy 312.983626 -421.333676) (xy 312.95637 -421.333279) (xy 312.902411 -421.325524) (xy 312.850106 -421.310169)
			(xy 312.800518 -421.287526) (xy 312.754658 -421.258056) (xy 312.713459 -421.22236) (xy 312.677759 -421.181163)
			(xy 312.648286 -421.135305) (xy 312.62564 -421.085719) (xy 312.610281 -421.033414) (xy 312.602523 -420.979456)
			(xy 311.165012 -420.979456) (xy 311.157256 -421.033399) (xy 311.141901 -421.085693) (xy 311.119259 -421.13527)
			(xy 311.089792 -421.18112) (xy 311.0541 -421.22231) (xy 311.012909 -421.258001) (xy 310.967058 -421.287466)
			(xy 310.91748 -421.310105) (xy 310.865185 -421.325459) (xy 310.811237 -421.333214) (xy 310.783986 -421.333676)
			(xy 309.920386 -421.333676) (xy 309.893133 -421.333253) (xy 309.839182 -421.325494) (xy 309.786885 -421.310137)
			(xy 309.737305 -421.287493) (xy 309.691453 -421.258024) (xy 309.650261 -421.222329) (xy 309.614568 -421.181136)
			(xy 309.5851 -421.135282) (xy 309.562458 -421.085702) (xy 309.547103 -421.033404) (xy 309.539346 -420.979453)
			(xy 308.101689 -420.979453) (xy 308.093935 -421.033386) (xy 308.078584 -421.085673) (xy 308.055948 -421.135243)
			(xy 308.026488 -421.181087) (xy 307.990805 -421.222272) (xy 307.949624 -421.257961) (xy 307.903783 -421.287426)
			(xy 307.854216 -421.310068) (xy 307.801931 -421.325425) (xy 307.747993 -421.333187) (xy 307.720746 -421.333676)
			(xy 306.857146 -421.333676) (xy 306.829889 -421.33328) (xy 306.775928 -421.325528) (xy 306.72362 -421.310175)
			(xy 306.67403 -421.287533) (xy 306.628167 -421.258063) (xy 306.586966 -421.222367) (xy 306.551264 -421.181169)
			(xy 306.521789 -421.13531) (xy 306.499142 -421.085723) (xy 306.483782 -421.033417) (xy 306.476023 -420.979457)
			(xy 305.038489 -420.979457) (xy 305.030734 -421.033391) (xy 305.015381 -421.085681) (xy 304.992742 -421.135254)
			(xy 304.963279 -421.1811) (xy 304.927591 -421.222287) (xy 304.886405 -421.257975) (xy 304.840559 -421.287439)
			(xy 304.790987 -421.310079) (xy 304.738697 -421.325433) (xy 304.684755 -421.333189) (xy 304.657506 -421.333676)
			(xy 303.793906 -421.333676) (xy 303.766651 -421.333277) (xy 303.712694 -421.325521) (xy 303.660391 -421.310164)
			(xy 303.610806 -421.28752) (xy 303.564949 -421.258049) (xy 303.523752 -421.222353) (xy 303.488054 -421.181156)
			(xy 303.458583 -421.135299) (xy 303.435938 -421.085714) (xy 303.420581 -421.033411) (xy 303.412823 -420.979455)
			(xy 231.647383 -420.979455) (xy 230.329486 -422.297352) (xy 230.322673 -422.304773) (xy 230.314938 -422.323356)
			(xy 230.3145 -422.33342) (xy 230.3145 -422.354375) (xy 285.567772 -422.354375) (xy 285.567772 -422.299825)
			(xy 285.575535 -422.245831) (xy 285.590905 -422.193491) (xy 285.613567 -422.143872) (xy 285.64306 -422.097983)
			(xy 285.678784 -422.056759) (xy 285.720012 -422.021038) (xy 285.765903 -421.991549) (xy 285.815525 -421.968892)
			(xy 285.867866 -421.953528) (xy 285.921861 -421.945769) (xy 285.949136 -421.945308) (xy 286.812736 -421.945308)
			(xy 286.840002 -421.945857) (xy 286.893977 -421.953622) (xy 286.946298 -421.968989) (xy 286.9959 -421.991646)
			(xy 287.041773 -422.02113) (xy 287.082983 -422.056843) (xy 287.118691 -422.098056) (xy 287.148172 -422.143932)
			(xy 287.170823 -422.193536) (xy 287.186186 -422.245858) (xy 287.193946 -422.299834) (xy 287.193946 -422.354366)
			(xy 287.186186 -422.408342) (xy 287.170823 -422.460664) (xy 287.148172 -422.510268) (xy 287.118691 -422.556144)
			(xy 287.082983 -422.597357) (xy 287.041773 -422.63307) (xy 286.9959 -422.662554) (xy 286.946298 -422.685211)
			(xy 286.893977 -422.700578) (xy 286.840002 -422.708343) (xy 286.812736 -422.708832) (xy 285.949136 -422.708832)
			(xy 285.921861 -422.708431) (xy 285.867866 -422.700672) (xy 285.815525 -422.685308) (xy 285.765903 -422.662651)
			(xy 285.720012 -422.633162) (xy 285.678784 -422.597441) (xy 285.64306 -422.556217) (xy 285.613567 -422.510328)
			(xy 285.590905 -422.460709) (xy 285.575535 -422.408369) (xy 285.567772 -422.354375) (xy 230.3145 -422.354375)
			(xy 230.3145 -424.80464) (xy 357.679233 -424.80464) (xy 357.679233 -424.6755) (xy 357.687183 -424.546605)
			(xy 357.703053 -424.418445) (xy 357.726782 -424.291504) (xy 357.758281 -424.166265) (xy 357.79743 -424.043202)
			(xy 357.844081 -423.922783) (xy 357.898056 -423.805464) (xy 357.959151 -423.69169) (xy 358.027134 -423.581893)
			(xy 358.101748 -423.47649) (xy 358.182709 -423.37588) (xy 358.269709 -423.280445) (xy 358.36242 -423.190546)
			(xy 358.46049 -423.106525) (xy 358.563545 -423.028701) (xy 358.671196 -422.957369) (xy 358.783035 -422.892799)
			(xy 358.898636 -422.835237) (xy 359.017561 -422.7849) (xy 359.13936 -422.74198) (xy 359.26357 -422.706639)
			(xy 359.389719 -422.679012) (xy 359.517331 -422.659203) (xy 359.64592 -422.647287) (xy 359.774998 -422.643311)
			(xy 359.904076 -422.647287) (xy 360.032665 -422.659203) (xy 360.160277 -422.679012) (xy 360.222212 -422.692576)
			(xy 365.310928 -422.692576) (xy 365.310928 -415.898584) (xy 365.3113 -415.888356) (xy 365.319137 -415.86946)
			(xy 365.33361 -415.855003) (xy 365.352515 -415.847188) (xy 365.362744 -415.846768) (xy 370.261388 -415.846768)
			(xy 370.271593 -415.847291) (xy 370.290451 -415.855097) (xy 370.304887 -415.869525) (xy 370.312703 -415.888379)
			(xy 370.313204 -415.898584) (xy 370.313204 -417.242244) (xy 373.739664 -417.242244) (xy 373.739664 -416.556444)
			(xy 373.74015 -416.544366) (xy 373.747602 -416.52139) (xy 373.76179 -416.501841) (xy 373.781325 -416.487635)
			(xy 373.804295 -416.480161) (xy 373.816372 -416.479736) (xy 374.010936 -416.479736) (xy 374.022041 -416.48012)
			(xy 374.043333 -416.486441) (xy 374.052846 -416.492182) (xy 374.34647 -416.684714) (xy 374.355857 -416.690411)
			(xy 374.376868 -416.696748) (xy 374.398814 -416.696823) (xy 374.419868 -416.690631) (xy 374.429274 -416.684968)
			(xy 374.725438 -416.492182) (xy 374.734953 -416.486442) (xy 374.756243 -416.480111) (xy 374.767348 -416.479736)
			(xy 374.961912 -416.479736) (xy 374.974 -416.480103) (xy 374.99699 -416.487579) (xy 375.016544 -416.501796)
			(xy 375.030746 -416.52136) (xy 375.038206 -416.544356) (xy 375.03862 -416.556444) (xy 375.03862 -417.242244)
			(xy 376.802904 -417.242244) (xy 376.802904 -416.556444) (xy 376.80335 -416.544362) (xy 376.810807 -416.521379)
			(xy 376.825004 -416.501827) (xy 376.84455 -416.487622) (xy 376.867531 -416.480155) (xy 376.879612 -416.479736)
			(xy 377.074176 -416.479736) (xy 377.085282 -416.480104) (xy 377.106574 -416.486437) (xy 377.116086 -416.492182)
			(xy 377.40971 -416.684714) (xy 377.419078 -416.690445) (xy 377.440098 -416.696774) (xy 377.46205 -416.69684)
			(xy 377.483108 -416.690637) (xy 377.492514 -416.684968) (xy 377.788678 -416.492182) (xy 377.798185 -416.486427)
			(xy 377.819481 -416.480106) (xy 377.830588 -416.479736) (xy 378.025152 -416.479736) (xy 378.037237 -416.480154)
			(xy 378.060225 -416.487614) (xy 378.07978 -416.501817) (xy 378.093984 -416.521371) (xy 378.101445 -416.544359)
			(xy 378.10186 -416.556444) (xy 378.10186 -417.242244) (xy 379.866144 -417.242244) (xy 379.866144 -416.556444)
			(xy 379.866701 -416.544376) (xy 379.874145 -416.521419) (xy 379.88832 -416.501885) (xy 379.907836 -416.487687)
			(xy 379.930785 -416.480215) (xy 379.942852 -416.479736) (xy 380.137416 -416.479736) (xy 380.14852 -416.480128)
			(xy 380.169812 -416.486444) (xy 380.179326 -416.492182) (xy 380.47295 -416.684714) (xy 380.482299 -416.690479)
			(xy 380.503328 -416.696801) (xy 380.525287 -416.696857) (xy 380.546348 -416.690643) (xy 380.555754 -416.684968)
			(xy 380.851918 -416.492182) (xy 380.861417 -416.486412) (xy 380.882719 -416.4801) (xy 380.893828 -416.479736)
			(xy 381.088392 -416.479736) (xy 381.100479 -416.48012) (xy 381.123469 -416.487591) (xy 381.143023 -416.501803)
			(xy 381.157226 -416.521364) (xy 381.164686 -416.544357) (xy 381.1651 -416.556444) (xy 381.1651 -417.242244)
			(xy 382.929384 -417.242244) (xy 382.929384 -416.556444) (xy 382.92985 -416.544364) (xy 382.937304 -416.521384)
			(xy 382.951497 -416.501834) (xy 382.971038 -416.487628) (xy 382.994013 -416.480158) (xy 383.006092 -416.479736)
			(xy 383.200656 -416.479736) (xy 383.211761 -416.480112) (xy 383.233053 -416.486439) (xy 383.242566 -416.492182)
			(xy 383.53619 -416.684714) (xy 383.545567 -416.690428) (xy 383.566583 -416.696761) (xy 383.588532 -416.696831)
			(xy 383.609588 -416.690634) (xy 383.618994 -416.684968) (xy 383.915158 -416.492182) (xy 383.924669 -416.486434)
			(xy 383.945962 -416.480109) (xy 383.957068 -416.479736) (xy 384.151632 -416.479736) (xy 384.163721 -416.480086)
			(xy 384.186712 -416.487568) (xy 384.206266 -416.501789) (xy 384.220467 -416.521356) (xy 384.227926 -416.544355)
			(xy 384.22834 -416.556444) (xy 384.22834 -417.242244) (xy 385.992624 -417.242244) (xy 385.992624 -416.556444)
			(xy 385.993051 -416.54436) (xy 386.00051 -416.521374) (xy 386.014711 -416.50182) (xy 386.034263 -416.487615)
			(xy 386.057248 -416.480153) (xy 386.069332 -416.479736) (xy 386.263896 -416.479736) (xy 386.275003 -416.480096)
			(xy 386.296294 -416.486434) (xy 386.305806 -416.492182) (xy 386.59943 -416.684714) (xy 386.608789 -416.690462)
			(xy 386.629813 -416.696787) (xy 386.651769 -416.696848) (xy 386.672828 -416.69064) (xy 386.682234 -416.684968)
			(xy 386.978398 -416.492182) (xy 386.987901 -416.48642) (xy 387.0092 -416.480103) (xy 387.020308 -416.479736)
			(xy 387.214872 -416.479736) (xy 387.226958 -416.480137) (xy 387.249947 -416.487602) (xy 387.269501 -416.50181)
			(xy 387.283705 -416.521367) (xy 387.291165 -416.544358) (xy 387.29158 -416.556444) (xy 387.29158 -417.242244)
			(xy 389.055864 -417.242244) (xy 389.055864 -416.556444) (xy 389.05635 -416.544366) (xy 389.063802 -416.52139)
			(xy 389.07799 -416.501841) (xy 389.097525 -416.487635) (xy 389.120495 -416.480161) (xy 389.132572 -416.479736)
			(xy 389.327136 -416.479736) (xy 389.338241 -416.48012) (xy 389.359533 -416.486441) (xy 389.369046 -416.492182)
			(xy 389.66267 -416.684714) (xy 389.672057 -416.690411) (xy 389.693068 -416.696748) (xy 389.715014 -416.696823)
			(xy 389.736068 -416.690631) (xy 389.745474 -416.684968) (xy 390.041638 -416.492182) (xy 390.051153 -416.486442)
			(xy 390.072443 -416.480111) (xy 390.083548 -416.479736) (xy 390.278112 -416.479736) (xy 390.2902 -416.480103)
			(xy 390.31319 -416.487579) (xy 390.332744 -416.501796) (xy 390.346946 -416.52136) (xy 390.354406 -416.544356)
			(xy 390.35482 -416.556444) (xy 390.35482 -417.242244) (xy 392.119104 -417.242244) (xy 392.119104 -416.556444)
			(xy 392.11955 -416.544362) (xy 392.127007 -416.521379) (xy 392.141204 -416.501827) (xy 392.16075 -416.487622)
			(xy 392.183731 -416.480155) (xy 392.195812 -416.479736) (xy 392.390376 -416.479736) (xy 392.401482 -416.480104)
			(xy 392.422774 -416.486437) (xy 392.432286 -416.492182) (xy 392.72591 -416.684714) (xy 392.735278 -416.690445)
			(xy 392.756298 -416.696774) (xy 392.77825 -416.69684) (xy 392.799308 -416.690637) (xy 392.808714 -416.684968)
			(xy 393.104878 -416.492182) (xy 393.114385 -416.486427) (xy 393.135681 -416.480106) (xy 393.146788 -416.479736)
			(xy 393.341352 -416.479736) (xy 393.353437 -416.480154) (xy 393.376425 -416.487614) (xy 393.39598 -416.501817)
			(xy 393.410184 -416.521371) (xy 393.417645 -416.544359) (xy 393.41806 -416.556444) (xy 393.41806 -417.242244)
			(xy 395.182344 -417.242244) (xy 395.182344 -416.556444) (xy 395.182901 -416.544376) (xy 395.190345 -416.521419)
			(xy 395.20452 -416.501885) (xy 395.224036 -416.487687) (xy 395.246985 -416.480215) (xy 395.259052 -416.479736)
			(xy 395.453616 -416.479736) (xy 395.46472 -416.480128) (xy 395.486012 -416.486444) (xy 395.495526 -416.492182)
			(xy 395.78915 -416.684714) (xy 395.798499 -416.690479) (xy 395.819528 -416.696801) (xy 395.841487 -416.696857)
			(xy 395.862548 -416.690643) (xy 395.871954 -416.684968) (xy 396.168118 -416.492182) (xy 396.177617 -416.486412)
			(xy 396.198919 -416.4801) (xy 396.210028 -416.479736) (xy 396.404592 -416.479736) (xy 396.416679 -416.48012)
			(xy 396.439669 -416.487591) (xy 396.459223 -416.501803) (xy 396.473426 -416.521364) (xy 396.480886 -416.544357)
			(xy 396.4813 -416.556444) (xy 396.4813 -417.242244) (xy 398.245584 -417.242244) (xy 398.245584 -416.556444)
			(xy 398.24605 -416.544364) (xy 398.253504 -416.521384) (xy 398.267697 -416.501834) (xy 398.287238 -416.487628)
			(xy 398.310213 -416.480158) (xy 398.322292 -416.479736) (xy 398.516856 -416.479736) (xy 398.527961 -416.480112)
			(xy 398.549253 -416.486439) (xy 398.558766 -416.492182) (xy 398.85239 -416.684714) (xy 398.861767 -416.690428)
			(xy 398.882783 -416.696761) (xy 398.904732 -416.696831) (xy 398.925788 -416.690634) (xy 398.935194 -416.684968)
			(xy 399.231358 -416.492182) (xy 399.240869 -416.486434) (xy 399.262162 -416.480109) (xy 399.273268 -416.479736)
			(xy 399.467832 -416.479736) (xy 399.479921 -416.480086) (xy 399.502912 -416.487568) (xy 399.522466 -416.501789)
			(xy 399.536667 -416.521356) (xy 399.544126 -416.544355) (xy 399.54454 -416.556444) (xy 399.54454 -417.242244)
			(xy 401.308824 -417.242244) (xy 401.308824 -416.556444) (xy 401.309251 -416.54436) (xy 401.31671 -416.521374)
			(xy 401.330911 -416.50182) (xy 401.350463 -416.487615) (xy 401.373448 -416.480153) (xy 401.385532 -416.479736)
			(xy 401.580096 -416.479736) (xy 401.591203 -416.480096) (xy 401.612494 -416.486434) (xy 401.622006 -416.492182)
			(xy 401.91563 -416.684714) (xy 401.924989 -416.690462) (xy 401.946013 -416.696787) (xy 401.967969 -416.696848)
			(xy 401.989028 -416.69064) (xy 401.998434 -416.684968) (xy 402.294598 -416.492182) (xy 402.304101 -416.48642)
			(xy 402.3254 -416.480103) (xy 402.336508 -416.479736) (xy 402.531072 -416.479736) (xy 402.543158 -416.480137)
			(xy 402.566147 -416.487602) (xy 402.585701 -416.50181) (xy 402.599905 -416.521367) (xy 402.607365 -416.544358)
			(xy 402.60778 -416.556444) (xy 402.60778 -417.242244) (xy 404.372064 -417.242244) (xy 404.372064 -416.556444)
			(xy 404.37255 -416.544366) (xy 404.380002 -416.52139) (xy 404.39419 -416.501841) (xy 404.413725 -416.487635)
			(xy 404.436695 -416.480161) (xy 404.448772 -416.479736) (xy 404.643336 -416.479736) (xy 404.654441 -416.48012)
			(xy 404.675733 -416.486441) (xy 404.685246 -416.492182) (xy 404.97887 -416.684714) (xy 404.988257 -416.690411)
			(xy 405.009268 -416.696748) (xy 405.031214 -416.696823) (xy 405.052268 -416.690631) (xy 405.061674 -416.684968)
			(xy 405.357838 -416.492182) (xy 405.367353 -416.486442) (xy 405.388643 -416.480111) (xy 405.399748 -416.479736)
			(xy 405.594312 -416.479736) (xy 405.6064 -416.480103) (xy 405.62939 -416.487579) (xy 405.648944 -416.501796)
			(xy 405.663146 -416.52136) (xy 405.670606 -416.544356) (xy 405.67102 -416.556444) (xy 405.67102 -417.242244)
			(xy 407.435304 -417.242244) (xy 407.435304 -416.556444) (xy 407.43575 -416.544362) (xy 407.443207 -416.521379)
			(xy 407.457404 -416.501827) (xy 407.47695 -416.487622) (xy 407.499931 -416.480155) (xy 407.512012 -416.479736)
			(xy 407.706576 -416.479736) (xy 407.717682 -416.480104) (xy 407.738974 -416.486437) (xy 407.748486 -416.492182)
			(xy 408.04211 -416.684714) (xy 408.051478 -416.690445) (xy 408.072498 -416.696774) (xy 408.09445 -416.69684)
			(xy 408.115508 -416.690637) (xy 408.124914 -416.684968) (xy 408.421078 -416.492182) (xy 408.430585 -416.486427)
			(xy 408.451881 -416.480106) (xy 408.462988 -416.479736) (xy 408.657552 -416.479736) (xy 408.669637 -416.480154)
			(xy 408.692625 -416.487614) (xy 408.71218 -416.501817) (xy 408.726384 -416.521371) (xy 408.733845 -416.544359)
			(xy 408.73426 -416.556444) (xy 408.73426 -417.242244) (xy 410.498544 -417.242244) (xy 410.498544 -416.556444)
			(xy 410.499101 -416.544376) (xy 410.506545 -416.521419) (xy 410.52072 -416.501885) (xy 410.540236 -416.487687)
			(xy 410.563185 -416.480215) (xy 410.575252 -416.479736) (xy 410.769816 -416.479736) (xy 410.78092 -416.480128)
			(xy 410.802212 -416.486444) (xy 410.811726 -416.492182) (xy 411.10535 -416.684714) (xy 411.114699 -416.690479)
			(xy 411.135728 -416.696801) (xy 411.157687 -416.696857) (xy 411.178748 -416.690643) (xy 411.188154 -416.684968)
			(xy 411.484318 -416.492182) (xy 411.493817 -416.486412) (xy 411.515119 -416.4801) (xy 411.526228 -416.479736)
			(xy 411.720792 -416.479736) (xy 411.732879 -416.48012) (xy 411.755869 -416.487591) (xy 411.775423 -416.501803)
			(xy 411.789626 -416.521364) (xy 411.797086 -416.544357) (xy 411.7975 -416.556444) (xy 411.7975 -417.242244)
			(xy 413.561784 -417.242244) (xy 413.561784 -416.556444) (xy 413.56225 -416.544364) (xy 413.569704 -416.521384)
			(xy 413.583897 -416.501834) (xy 413.603438 -416.487628) (xy 413.626413 -416.480158) (xy 413.638492 -416.479736)
			(xy 413.833056 -416.479736) (xy 413.844161 -416.480112) (xy 413.865453 -416.486439) (xy 413.874966 -416.492182)
			(xy 414.16859 -416.684714) (xy 414.177967 -416.690428) (xy 414.198983 -416.696761) (xy 414.220932 -416.696831)
			(xy 414.241988 -416.690634) (xy 414.251394 -416.684968) (xy 414.547558 -416.492182) (xy 414.557069 -416.486434)
			(xy 414.578362 -416.480109) (xy 414.589468 -416.479736) (xy 414.784032 -416.479736) (xy 414.796121 -416.480086)
			(xy 414.819112 -416.487568) (xy 414.838666 -416.501789) (xy 414.852867 -416.521356) (xy 414.860326 -416.544355)
			(xy 414.86074 -416.556444) (xy 414.86074 -417.242244) (xy 416.625024 -417.242244) (xy 416.625024 -416.556444)
			(xy 416.625451 -416.54436) (xy 416.63291 -416.521374) (xy 416.647111 -416.50182) (xy 416.666663 -416.487615)
			(xy 416.689648 -416.480153) (xy 416.701732 -416.479736) (xy 416.896296 -416.479736) (xy 416.907403 -416.480096)
			(xy 416.928694 -416.486434) (xy 416.938206 -416.492182) (xy 417.23183 -416.684714) (xy 417.241189 -416.690462)
			(xy 417.262213 -416.696787) (xy 417.284169 -416.696848) (xy 417.305228 -416.69064) (xy 417.314634 -416.684968)
			(xy 417.610798 -416.492182) (xy 417.620301 -416.48642) (xy 417.6416 -416.480103) (xy 417.652708 -416.479736)
			(xy 417.847272 -416.479736) (xy 417.859358 -416.480137) (xy 417.882347 -416.487602) (xy 417.901901 -416.50181)
			(xy 417.916105 -416.521367) (xy 417.923565 -416.544358) (xy 417.92398 -416.556444) (xy 417.92398 -417.242244)
			(xy 417.923573 -417.254324) (xy 417.916095 -417.277297) (xy 417.901885 -417.296836) (xy 417.882332 -417.311028)
			(xy 417.859352 -417.318484) (xy 417.847272 -417.318952) (xy 417.652708 -417.318952) (xy 417.641601 -417.318573)
			(xy 417.620305 -417.312259) (xy 417.610798 -417.306506) (xy 417.315904 -417.113974) (xy 417.306517 -417.108271)
			(xy 417.285479 -417.101998) (xy 417.263525 -417.101998) (xy 417.242487 -417.108271) (xy 417.2331 -417.113974)
			(xy 416.939476 -417.306506) (xy 416.929958 -417.31224) (xy 416.908671 -417.318574) (xy 416.897566 -417.318952)
			(xy 416.701732 -417.318952) (xy 416.689663 -417.318409) (xy 416.666705 -417.310961) (xy 416.647171 -417.296783)
			(xy 416.632974 -417.277263) (xy 416.625503 -417.254312) (xy 416.625024 -417.242244) (xy 414.86074 -417.242244)
			(xy 414.860274 -417.254318) (xy 414.852803 -417.277281) (xy 414.838606 -417.296814) (xy 414.81907 -417.311009)
			(xy 414.796106 -417.318476) (xy 414.784032 -417.318952) (xy 414.589468 -417.318952) (xy 414.57836 -417.31859)
			(xy 414.557064 -417.312265) (xy 414.547558 -417.306506) (xy 414.252664 -417.113974) (xy 414.243277 -417.108271)
			(xy 414.222239 -417.101998) (xy 414.200285 -417.101998) (xy 414.179247 -417.108271) (xy 414.16986 -417.113974)
			(xy 413.876236 -417.306506) (xy 413.866726 -417.312255) (xy 413.845432 -417.31858) (xy 413.834326 -417.318952)
			(xy 413.638492 -417.318952) (xy 413.626421 -417.318443) (xy 413.603461 -417.310984) (xy 413.583928 -417.296797)
			(xy 413.569733 -417.277271) (xy 413.562262 -417.254314) (xy 413.561784 -417.242244) (xy 411.7975 -417.242244)
			(xy 411.797073 -417.254322) (xy 411.789598 -417.277292) (xy 411.775392 -417.296829) (xy 411.755845 -417.311021)
			(xy 411.73287 -417.318481) (xy 411.720792 -417.318952) (xy 411.526228 -417.318952) (xy 411.515119 -417.318606)
			(xy 411.493822 -417.31227) (xy 411.484318 -417.306506) (xy 411.189424 -417.113974) (xy 411.180037 -417.108271)
			(xy 411.158999 -417.101998) (xy 411.137045 -417.101998) (xy 411.116007 -417.108271) (xy 411.10662 -417.113974)
			(xy 410.812996 -417.306506) (xy 410.803494 -417.31227) (xy 410.782194 -417.318586) (xy 410.771086 -417.318952)
			(xy 410.575252 -417.318952) (xy 410.563179 -417.318478) (xy 410.540218 -417.311007) (xy 410.520686 -417.296812)
			(xy 410.506491 -417.277278) (xy 410.499022 -417.254317) (xy 410.498544 -417.242244) (xy 408.73426 -417.242244)
			(xy 408.733924 -417.254334) (xy 408.726439 -417.277326) (xy 408.712214 -417.29688) (xy 408.692644 -417.311081)
			(xy 408.669642 -417.318539) (xy 408.657552 -417.318952) (xy 408.462988 -417.318952) (xy 408.451881 -417.318582)
			(xy 408.430584 -417.312262) (xy 408.421078 -417.306506) (xy 408.126184 -417.113974) (xy 408.116797 -417.108271)
			(xy 408.095759 -417.101998) (xy 408.073805 -417.101998) (xy 408.052767 -417.108271) (xy 408.04338 -417.113974)
			(xy 407.749756 -417.306506) (xy 407.740242 -417.312247) (xy 407.718951 -417.318577) (xy 407.707846 -417.318952)
			(xy 407.512012 -417.318952) (xy 407.499942 -417.318426) (xy 407.476983 -417.310972) (xy 407.45745 -417.29679)
			(xy 407.443253 -417.277267) (xy 407.435783 -417.254313) (xy 407.435304 -417.242244) (xy 405.67102 -417.242244)
			(xy 405.670574 -417.25432) (xy 405.6631 -417.277286) (xy 405.648899 -417.296822) (xy 405.629358 -417.311015)
			(xy 405.606388 -417.318479) (xy 405.594312 -417.318952) (xy 405.399748 -417.318952) (xy 405.388639 -417.318598)
			(xy 405.367343 -417.312267) (xy 405.357838 -417.306506) (xy 405.062944 -417.113974) (xy 405.053557 -417.108271)
			(xy 405.032519 -417.101998) (xy 405.010565 -417.101998) (xy 404.989527 -417.108271) (xy 404.98014 -417.113974)
			(xy 404.686516 -417.306506) (xy 404.67701 -417.312262) (xy 404.655713 -417.318583) (xy 404.644606 -417.318952)
			(xy 404.448772 -417.318952) (xy 404.4367 -417.318461) (xy 404.41374 -417.310996) (xy 404.394207 -417.296805)
			(xy 404.380012 -417.277275) (xy 404.372542 -417.254316) (xy 404.372064 -417.242244) (xy 402.60778 -417.242244)
			(xy 402.607373 -417.254324) (xy 402.599895 -417.277297) (xy 402.585685 -417.296836) (xy 402.566132 -417.311028)
			(xy 402.543152 -417.318484) (xy 402.531072 -417.318952) (xy 402.336508 -417.318952) (xy 402.325401 -417.318573)
			(xy 402.304105 -417.312259) (xy 402.294598 -417.306506) (xy 401.999704 -417.113974) (xy 401.990317 -417.108271)
			(xy 401.969279 -417.101998) (xy 401.947325 -417.101998) (xy 401.926287 -417.108271) (xy 401.9169 -417.113974)
			(xy 401.623276 -417.306506) (xy 401.613758 -417.31224) (xy 401.592471 -417.318574) (xy 401.581366 -417.318952)
			(xy 401.385532 -417.318952) (xy 401.373463 -417.318409) (xy 401.350505 -417.310961) (xy 401.330971 -417.296783)
			(xy 401.316774 -417.277263) (xy 401.309303 -417.254312) (xy 401.308824 -417.242244) (xy 399.54454 -417.242244)
			(xy 399.544074 -417.254318) (xy 399.536603 -417.277281) (xy 399.522406 -417.296814) (xy 399.50287 -417.311009)
			(xy 399.479906 -417.318476) (xy 399.467832 -417.318952) (xy 399.273268 -417.318952) (xy 399.26216 -417.31859)
			(xy 399.240864 -417.312265) (xy 399.231358 -417.306506) (xy 398.936464 -417.113974) (xy 398.927077 -417.108271)
			(xy 398.906039 -417.101998) (xy 398.884085 -417.101998) (xy 398.863047 -417.108271) (xy 398.85366 -417.113974)
			(xy 398.560036 -417.306506) (xy 398.550526 -417.312255) (xy 398.529232 -417.31858) (xy 398.518126 -417.318952)
			(xy 398.322292 -417.318952) (xy 398.310221 -417.318443) (xy 398.287261 -417.310984) (xy 398.267728 -417.296797)
			(xy 398.253533 -417.277271) (xy 398.246062 -417.254314) (xy 398.245584 -417.242244) (xy 396.4813 -417.242244)
			(xy 396.480873 -417.254322) (xy 396.473398 -417.277292) (xy 396.459192 -417.296829) (xy 396.439645 -417.311021)
			(xy 396.41667 -417.318481) (xy 396.404592 -417.318952) (xy 396.210028 -417.318952) (xy 396.198919 -417.318606)
			(xy 396.177622 -417.31227) (xy 396.168118 -417.306506) (xy 395.873224 -417.113974) (xy 395.863837 -417.108271)
			(xy 395.842799 -417.101998) (xy 395.820845 -417.101998) (xy 395.799807 -417.108271) (xy 395.79042 -417.113974)
			(xy 395.496796 -417.306506) (xy 395.487294 -417.31227) (xy 395.465994 -417.318586) (xy 395.454886 -417.318952)
			(xy 395.259052 -417.318952) (xy 395.246979 -417.318478) (xy 395.224018 -417.311007) (xy 395.204486 -417.296812)
			(xy 395.190291 -417.277278) (xy 395.182822 -417.254317) (xy 395.182344 -417.242244) (xy 393.41806 -417.242244)
			(xy 393.417724 -417.254334) (xy 393.410239 -417.277326) (xy 393.396014 -417.29688) (xy 393.376444 -417.311081)
			(xy 393.353442 -417.318539) (xy 393.341352 -417.318952) (xy 393.146788 -417.318952) (xy 393.135681 -417.318582)
			(xy 393.114384 -417.312262) (xy 393.104878 -417.306506) (xy 392.809984 -417.113974) (xy 392.800597 -417.108271)
			(xy 392.779559 -417.101998) (xy 392.757605 -417.101998) (xy 392.736567 -417.108271) (xy 392.72718 -417.113974)
			(xy 392.433556 -417.306506) (xy 392.424042 -417.312247) (xy 392.402751 -417.318577) (xy 392.391646 -417.318952)
			(xy 392.195812 -417.318952) (xy 392.183742 -417.318426) (xy 392.160783 -417.310972) (xy 392.14125 -417.29679)
			(xy 392.127053 -417.277267) (xy 392.119583 -417.254313) (xy 392.119104 -417.242244) (xy 390.35482 -417.242244)
			(xy 390.354374 -417.25432) (xy 390.3469 -417.277286) (xy 390.332699 -417.296822) (xy 390.313158 -417.311015)
			(xy 390.290188 -417.318479) (xy 390.278112 -417.318952) (xy 390.083548 -417.318952) (xy 390.072439 -417.318598)
			(xy 390.051143 -417.312267) (xy 390.041638 -417.306506) (xy 389.746744 -417.113974) (xy 389.737357 -417.108271)
			(xy 389.716319 -417.101998) (xy 389.694365 -417.101998) (xy 389.673327 -417.108271) (xy 389.66394 -417.113974)
			(xy 389.370316 -417.306506) (xy 389.36081 -417.312262) (xy 389.339513 -417.318583) (xy 389.328406 -417.318952)
			(xy 389.132572 -417.318952) (xy 389.1205 -417.318461) (xy 389.09754 -417.310996) (xy 389.078007 -417.296805)
			(xy 389.063812 -417.277275) (xy 389.056342 -417.254316) (xy 389.055864 -417.242244) (xy 387.29158 -417.242244)
			(xy 387.291173 -417.254324) (xy 387.283695 -417.277297) (xy 387.269485 -417.296836) (xy 387.249932 -417.311028)
			(xy 387.226952 -417.318484) (xy 387.214872 -417.318952) (xy 387.020308 -417.318952) (xy 387.009201 -417.318573)
			(xy 386.987905 -417.312259) (xy 386.978398 -417.306506) (xy 386.683504 -417.113974) (xy 386.674117 -417.108271)
			(xy 386.653079 -417.101998) (xy 386.631125 -417.101998) (xy 386.610087 -417.108271) (xy 386.6007 -417.113974)
			(xy 386.307076 -417.306506) (xy 386.297558 -417.31224) (xy 386.276271 -417.318574) (xy 386.265166 -417.318952)
			(xy 386.069332 -417.318952) (xy 386.057263 -417.318409) (xy 386.034305 -417.310961) (xy 386.014771 -417.296783)
			(xy 386.000574 -417.277263) (xy 385.993103 -417.254312) (xy 385.992624 -417.242244) (xy 384.22834 -417.242244)
			(xy 384.227874 -417.254318) (xy 384.220403 -417.277281) (xy 384.206206 -417.296814) (xy 384.18667 -417.311009)
			(xy 384.163706 -417.318476) (xy 384.151632 -417.318952) (xy 383.957068 -417.318952) (xy 383.94596 -417.31859)
			(xy 383.924664 -417.312265) (xy 383.915158 -417.306506) (xy 383.620264 -417.113974) (xy 383.610877 -417.108271)
			(xy 383.589839 -417.101998) (xy 383.567885 -417.101998) (xy 383.546847 -417.108271) (xy 383.53746 -417.113974)
			(xy 383.243836 -417.306506) (xy 383.234326 -417.312255) (xy 383.213032 -417.31858) (xy 383.201926 -417.318952)
			(xy 383.006092 -417.318952) (xy 382.994021 -417.318443) (xy 382.971061 -417.310984) (xy 382.951528 -417.296797)
			(xy 382.937333 -417.277271) (xy 382.929862 -417.254314) (xy 382.929384 -417.242244) (xy 381.1651 -417.242244)
			(xy 381.164673 -417.254322) (xy 381.157198 -417.277292) (xy 381.142992 -417.296829) (xy 381.123445 -417.311021)
			(xy 381.10047 -417.318481) (xy 381.088392 -417.318952) (xy 380.893828 -417.318952) (xy 380.882719 -417.318606)
			(xy 380.861422 -417.31227) (xy 380.851918 -417.306506) (xy 380.557024 -417.113974) (xy 380.547637 -417.108271)
			(xy 380.526599 -417.101998) (xy 380.504645 -417.101998) (xy 380.483607 -417.108271) (xy 380.47422 -417.113974)
			(xy 380.180596 -417.306506) (xy 380.171094 -417.31227) (xy 380.149794 -417.318586) (xy 380.138686 -417.318952)
			(xy 379.942852 -417.318952) (xy 379.930779 -417.318478) (xy 379.907818 -417.311007) (xy 379.888286 -417.296812)
			(xy 379.874091 -417.277278) (xy 379.866622 -417.254317) (xy 379.866144 -417.242244) (xy 378.10186 -417.242244)
			(xy 378.101524 -417.254334) (xy 378.094039 -417.277326) (xy 378.079814 -417.29688) (xy 378.060244 -417.311081)
			(xy 378.037242 -417.318539) (xy 378.025152 -417.318952) (xy 377.830588 -417.318952) (xy 377.819481 -417.318582)
			(xy 377.798184 -417.312262) (xy 377.788678 -417.306506) (xy 377.493784 -417.113974) (xy 377.484397 -417.108271)
			(xy 377.463359 -417.101998) (xy 377.441405 -417.101998) (xy 377.420367 -417.108271) (xy 377.41098 -417.113974)
			(xy 377.117356 -417.306506) (xy 377.107842 -417.312247) (xy 377.086551 -417.318577) (xy 377.075446 -417.318952)
			(xy 376.879612 -417.318952) (xy 376.867542 -417.318426) (xy 376.844583 -417.310972) (xy 376.82505 -417.29679)
			(xy 376.810853 -417.277267) (xy 376.803383 -417.254313) (xy 376.802904 -417.242244) (xy 375.03862 -417.242244)
			(xy 375.038174 -417.25432) (xy 375.0307 -417.277286) (xy 375.016499 -417.296822) (xy 374.996958 -417.311015)
			(xy 374.973988 -417.318479) (xy 374.961912 -417.318952) (xy 374.767348 -417.318952) (xy 374.756239 -417.318598)
			(xy 374.734943 -417.312267) (xy 374.725438 -417.306506) (xy 374.430544 -417.113974) (xy 374.421157 -417.108271)
			(xy 374.400119 -417.101998) (xy 374.378165 -417.101998) (xy 374.357127 -417.108271) (xy 374.34774 -417.113974)
			(xy 374.054116 -417.306506) (xy 374.04461 -417.312262) (xy 374.023313 -417.318583) (xy 374.012206 -417.318952)
			(xy 373.816372 -417.318952) (xy 373.8043 -417.318461) (xy 373.78134 -417.310996) (xy 373.761807 -417.296805)
			(xy 373.747612 -417.277275) (xy 373.740142 -417.254316) (xy 373.739664 -417.242244) (xy 370.313204 -417.242244)
			(xy 370.313204 -418.439456) (xy 372.044623 -418.439456) (xy 372.044623 -418.384944) (xy 372.052381 -418.330986)
			(xy 372.06774 -418.278682) (xy 372.090386 -418.229097) (xy 372.119858 -418.183238) (xy 372.155557 -418.142042)
			(xy 372.196756 -418.106345) (xy 372.242616 -418.076875) (xy 372.292203 -418.054232) (xy 372.344508 -418.038877)
			(xy 372.398466 -418.031121) (xy 372.425722 -418.03066) (xy 373.289322 -418.03066) (xy 373.31657 -418.031212)
			(xy 373.370511 -418.03897) (xy 373.422798 -418.054326) (xy 373.472369 -418.076966) (xy 373.518212 -418.106431)
			(xy 373.559396 -418.142119) (xy 373.595083 -418.183305) (xy 373.624544 -418.229151) (xy 373.647182 -418.278722)
			(xy 373.662535 -418.331011) (xy 373.67029 -418.384952) (xy 373.67029 -418.439448) (xy 373.670289 -418.439452)
			(xy 375.107946 -418.439452) (xy 375.107946 -418.384948) (xy 375.115702 -418.330999) (xy 375.131056 -418.278703)
			(xy 375.153697 -418.229124) (xy 375.183162 -418.183272) (xy 375.218852 -418.142079) (xy 375.260041 -418.106385)
			(xy 375.305891 -418.076915) (xy 375.355468 -418.05427) (xy 375.407762 -418.03891) (xy 375.46171 -418.031148)
			(xy 375.488962 -418.03066) (xy 376.352562 -418.03066) (xy 376.379814 -418.031185) (xy 376.433765 -418.038937)
			(xy 376.486063 -418.054288) (xy 376.535644 -418.076926) (xy 376.581498 -418.106391) (xy 376.622691 -418.142082)
			(xy 376.658386 -418.183272) (xy 376.687855 -418.229123) (xy 376.710499 -418.278701) (xy 376.725855 -418.330998)
			(xy 376.733613 -418.384948) (xy 376.733613 -418.439452) (xy 376.733613 -418.439455) (xy 378.171123 -418.439455)
			(xy 378.171123 -418.384945) (xy 378.178881 -418.330989) (xy 378.194238 -418.278687) (xy 378.216883 -418.229102)
			(xy 378.246353 -418.183245) (xy 378.28205 -418.142049) (xy 378.323247 -418.106352) (xy 378.369104 -418.076882)
			(xy 378.418688 -418.054237) (xy 378.470991 -418.03888) (xy 378.524947 -418.031123) (xy 378.552202 -418.03066)
			(xy 379.415802 -418.03066) (xy 379.443051 -418.03121) (xy 379.496994 -418.038966) (xy 379.549284 -418.05432)
			(xy 379.598857 -418.07696) (xy 379.644703 -418.106424) (xy 379.685889 -418.142112) (xy 379.721578 -418.183299)
			(xy 379.751041 -418.229145) (xy 379.77368 -418.278718) (xy 379.789034 -418.331008) (xy 379.79679 -418.384951)
			(xy 379.79679 -418.439449) (xy 379.796789 -418.439457) (xy 381.234323 -418.439457) (xy 381.234323 -418.384943)
			(xy 381.242082 -418.330984) (xy 381.257441 -418.278678) (xy 381.280089 -418.229091) (xy 381.309563 -418.183232)
			(xy 381.345264 -418.142035) (xy 381.386466 -418.106338) (xy 381.432328 -418.076869) (xy 381.481917 -418.054227)
			(xy 381.534225 -418.038873) (xy 381.588185 -418.03112) (xy 381.615442 -418.03066) (xy 382.479042 -418.03066)
			(xy 382.506289 -418.031213) (xy 382.560228 -418.038974) (xy 382.612513 -418.054331) (xy 382.662081 -418.076973)
			(xy 382.707922 -418.106438) (xy 382.749103 -418.142126) (xy 382.784787 -418.183312) (xy 382.814247 -418.229156)
			(xy 382.836883 -418.278727) (xy 382.852235 -418.331014) (xy 382.85999 -418.384953) (xy 382.85999 -418.439447)
			(xy 382.859989 -418.439453) (xy 384.297646 -418.439453) (xy 384.297646 -418.384947) (xy 384.305403 -418.330997)
			(xy 384.320758 -418.278699) (xy 384.3434 -418.229119) (xy 384.372867 -418.183265) (xy 384.408559 -418.142072)
			(xy 384.449751 -418.106378) (xy 384.495603 -418.076908) (xy 384.545182 -418.054264) (xy 384.597479 -418.038906)
			(xy 384.651429 -418.031147) (xy 384.678682 -418.03066) (xy 385.542282 -418.03066) (xy 385.569533 -418.031186)
			(xy 385.623482 -418.03894) (xy 385.675777 -418.054293) (xy 385.725356 -418.076933) (xy 385.771207 -418.106398)
			(xy 385.812399 -418.142089) (xy 385.848091 -418.183278) (xy 385.877558 -418.229129) (xy 385.9002 -418.278706)
			(xy 385.915556 -418.331001) (xy 385.923313 -418.384949) (xy 385.923313 -418.439451) (xy 385.923312 -418.439456)
			(xy 387.360823 -418.439456) (xy 387.360823 -418.384944) (xy 387.368581 -418.330986) (xy 387.38394 -418.278682)
			(xy 387.406586 -418.229097) (xy 387.436058 -418.183238) (xy 387.471757 -418.142042) (xy 387.512956 -418.106345)
			(xy 387.558816 -418.076875) (xy 387.608403 -418.054232) (xy 387.660708 -418.038877) (xy 387.714666 -418.031121)
			(xy 387.741922 -418.03066) (xy 388.605522 -418.03066) (xy 388.63277 -418.031212) (xy 388.686711 -418.03897)
			(xy 388.738998 -418.054326) (xy 388.788569 -418.076966) (xy 388.834412 -418.106431) (xy 388.875596 -418.142119)
			(xy 388.911283 -418.183305) (xy 388.940744 -418.229151) (xy 388.963382 -418.278722) (xy 388.978735 -418.331011)
			(xy 388.98649 -418.384952) (xy 388.98649 -418.439448) (xy 388.986489 -418.439452) (xy 390.424146 -418.439452)
			(xy 390.424146 -418.384948) (xy 390.431902 -418.330999) (xy 390.447256 -418.278703) (xy 390.469897 -418.229124)
			(xy 390.499362 -418.183272) (xy 390.535052 -418.142079) (xy 390.576241 -418.106385) (xy 390.622091 -418.076915)
			(xy 390.671668 -418.05427) (xy 390.723962 -418.03891) (xy 390.77791 -418.031148) (xy 390.805162 -418.03066)
			(xy 391.668762 -418.03066) (xy 391.696014 -418.031185) (xy 391.749965 -418.038937) (xy 391.802263 -418.054288)
			(xy 391.851844 -418.076926) (xy 391.897698 -418.106391) (xy 391.938891 -418.142082) (xy 391.974586 -418.183272)
			(xy 392.004055 -418.229123) (xy 392.026699 -418.278701) (xy 392.042055 -418.330998) (xy 392.049813 -418.384948)
			(xy 392.049813 -418.439452) (xy 392.049813 -418.439455) (xy 393.487323 -418.439455) (xy 393.487323 -418.384945)
			(xy 393.495081 -418.330989) (xy 393.510438 -418.278687) (xy 393.533083 -418.229102) (xy 393.562553 -418.183245)
			(xy 393.59825 -418.142049) (xy 393.639447 -418.106352) (xy 393.685304 -418.076882) (xy 393.734888 -418.054237)
			(xy 393.787191 -418.03888) (xy 393.841147 -418.031123) (xy 393.868402 -418.03066) (xy 394.732002 -418.03066)
			(xy 394.759251 -418.03121) (xy 394.813194 -418.038966) (xy 394.865484 -418.05432) (xy 394.915057 -418.07696)
			(xy 394.960903 -418.106424) (xy 395.002089 -418.142112) (xy 395.037778 -418.183299) (xy 395.067241 -418.229145)
			(xy 395.08988 -418.278718) (xy 395.105234 -418.331008) (xy 395.11299 -418.384951) (xy 395.11299 -418.439449)
			(xy 395.112989 -418.439457) (xy 396.550523 -418.439457) (xy 396.550523 -418.384943) (xy 396.558282 -418.330984)
			(xy 396.573641 -418.278678) (xy 396.596289 -418.229091) (xy 396.625763 -418.183232) (xy 396.661464 -418.142035)
			(xy 396.702666 -418.106338) (xy 396.748528 -418.076869) (xy 396.798117 -418.054227) (xy 396.850425 -418.038873)
			(xy 396.904385 -418.03112) (xy 396.931642 -418.03066) (xy 397.795242 -418.03066) (xy 397.822489 -418.031213)
			(xy 397.876428 -418.038974) (xy 397.928713 -418.054331) (xy 397.978281 -418.076973) (xy 398.024122 -418.106438)
			(xy 398.065303 -418.142126) (xy 398.100987 -418.183312) (xy 398.130447 -418.229156) (xy 398.153083 -418.278727)
			(xy 398.168435 -418.331014) (xy 398.17619 -418.384953) (xy 398.17619 -418.439447) (xy 398.176189 -418.439453)
			(xy 399.613846 -418.439453) (xy 399.613846 -418.384947) (xy 399.621603 -418.330997) (xy 399.636958 -418.278699)
			(xy 399.6596 -418.229119) (xy 399.689067 -418.183265) (xy 399.724759 -418.142072) (xy 399.765951 -418.106378)
			(xy 399.811803 -418.076908) (xy 399.861382 -418.054264) (xy 399.913679 -418.038906) (xy 399.967629 -418.031147)
			(xy 399.994882 -418.03066) (xy 400.858482 -418.03066) (xy 400.885733 -418.031186) (xy 400.939682 -418.03894)
			(xy 400.991977 -418.054293) (xy 401.041556 -418.076933) (xy 401.087407 -418.106398) (xy 401.128599 -418.142089)
			(xy 401.164291 -418.183278) (xy 401.193758 -418.229129) (xy 401.2164 -418.278706) (xy 401.231756 -418.331001)
			(xy 401.239513 -418.384949) (xy 401.239513 -418.439451) (xy 401.239512 -418.439456) (xy 402.677023 -418.439456)
			(xy 402.677023 -418.384944) (xy 402.684781 -418.330986) (xy 402.70014 -418.278682) (xy 402.722786 -418.229097)
			(xy 402.752258 -418.183238) (xy 402.787957 -418.142042) (xy 402.829156 -418.106345) (xy 402.875016 -418.076875)
			(xy 402.924603 -418.054232) (xy 402.976908 -418.038877) (xy 403.030866 -418.031121) (xy 403.058122 -418.03066)
			(xy 403.921722 -418.03066) (xy 403.94897 -418.031212) (xy 404.002911 -418.03897) (xy 404.055198 -418.054326)
			(xy 404.104769 -418.076966) (xy 404.150612 -418.106431) (xy 404.191796 -418.142119) (xy 404.227483 -418.183305)
			(xy 404.256944 -418.229151) (xy 404.279582 -418.278722) (xy 404.294935 -418.331011) (xy 404.30269 -418.384952)
			(xy 404.30269 -418.439448) (xy 404.302689 -418.439452) (xy 405.740346 -418.439452) (xy 405.740346 -418.384948)
			(xy 405.748102 -418.330999) (xy 405.763456 -418.278703) (xy 405.786097 -418.229124) (xy 405.815562 -418.183272)
			(xy 405.851252 -418.142079) (xy 405.892441 -418.106385) (xy 405.938291 -418.076915) (xy 405.987868 -418.05427)
			(xy 406.040162 -418.03891) (xy 406.09411 -418.031148) (xy 406.121362 -418.03066) (xy 406.984962 -418.03066)
			(xy 407.012214 -418.031185) (xy 407.066165 -418.038937) (xy 407.118463 -418.054288) (xy 407.168044 -418.076926)
			(xy 407.213898 -418.106391) (xy 407.255091 -418.142082) (xy 407.290786 -418.183272) (xy 407.320255 -418.229123)
			(xy 407.342899 -418.278701) (xy 407.358255 -418.330998) (xy 407.366013 -418.384948) (xy 407.366013 -418.439452)
			(xy 407.366013 -418.439455) (xy 408.803523 -418.439455) (xy 408.803523 -418.384945) (xy 408.811281 -418.330989)
			(xy 408.826638 -418.278687) (xy 408.849283 -418.229102) (xy 408.878753 -418.183245) (xy 408.91445 -418.142049)
			(xy 408.955647 -418.106352) (xy 409.001504 -418.076882) (xy 409.051088 -418.054237) (xy 409.103391 -418.03888)
			(xy 409.157347 -418.031123) (xy 409.184602 -418.03066) (xy 410.048202 -418.03066) (xy 410.075451 -418.03121)
			(xy 410.129394 -418.038966) (xy 410.181684 -418.05432) (xy 410.231257 -418.07696) (xy 410.277103 -418.106424)
			(xy 410.318289 -418.142112) (xy 410.353978 -418.183299) (xy 410.383441 -418.229145) (xy 410.40608 -418.278718)
			(xy 410.421434 -418.331008) (xy 410.42919 -418.384951) (xy 410.42919 -418.439449) (xy 410.429189 -418.439457)
			(xy 411.866723 -418.439457) (xy 411.866723 -418.384943) (xy 411.874482 -418.330984) (xy 411.889841 -418.278678)
			(xy 411.912489 -418.229091) (xy 411.941963 -418.183232) (xy 411.977664 -418.142035) (xy 412.018866 -418.106338)
			(xy 412.064728 -418.076869) (xy 412.114317 -418.054227) (xy 412.166625 -418.038873) (xy 412.220585 -418.03112)
			(xy 412.247842 -418.03066) (xy 413.111442 -418.03066) (xy 413.138689 -418.031213) (xy 413.192628 -418.038974)
			(xy 413.244913 -418.054331) (xy 413.294481 -418.076973) (xy 413.340322 -418.106438) (xy 413.381503 -418.142126)
			(xy 413.417187 -418.183312) (xy 413.446647 -418.229156) (xy 413.469283 -418.278727) (xy 413.484635 -418.331014)
			(xy 413.49239 -418.384953) (xy 413.49239 -418.439447) (xy 413.492389 -418.439453) (xy 414.930046 -418.439453)
			(xy 414.930046 -418.384947) (xy 414.937803 -418.330997) (xy 414.953158 -418.278699) (xy 414.9758 -418.229119)
			(xy 415.005267 -418.183265) (xy 415.040959 -418.142072) (xy 415.082151 -418.106378) (xy 415.128003 -418.076908)
			(xy 415.177582 -418.054264) (xy 415.229879 -418.038906) (xy 415.283829 -418.031147) (xy 415.311082 -418.03066)
			(xy 416.174682 -418.03066) (xy 416.201933 -418.031186) (xy 416.255882 -418.03894) (xy 416.308177 -418.054293)
			(xy 416.357756 -418.076933) (xy 416.403607 -418.106398) (xy 416.444799 -418.142089) (xy 416.480491 -418.183278)
			(xy 416.509958 -418.229129) (xy 416.5326 -418.278706) (xy 416.547956 -418.331001) (xy 416.555713 -418.384949)
			(xy 416.555713 -418.439451) (xy 416.555712 -418.439456) (xy 417.993223 -418.439456) (xy 417.993223 -418.384944)
			(xy 418.000981 -418.330986) (xy 418.01634 -418.278682) (xy 418.038986 -418.229097) (xy 418.068458 -418.183238)
			(xy 418.104157 -418.142042) (xy 418.145356 -418.106345) (xy 418.191216 -418.076875) (xy 418.240803 -418.054232)
			(xy 418.293108 -418.038877) (xy 418.347066 -418.031121) (xy 418.374322 -418.03066) (xy 419.237922 -418.03066)
			(xy 419.26517 -418.031212) (xy 419.319111 -418.03897) (xy 419.371398 -418.054326) (xy 419.420969 -418.076966)
			(xy 419.466812 -418.106431) (xy 419.507996 -418.142119) (xy 419.543683 -418.183305) (xy 419.573144 -418.229151)
			(xy 419.595782 -418.278722) (xy 419.611135 -418.331011) (xy 419.61889 -418.384952) (xy 419.61889 -418.439448)
			(xy 419.611135 -418.493389) (xy 419.595782 -418.545678) (xy 419.573144 -418.595249) (xy 419.543683 -418.641095)
			(xy 419.507996 -418.682281) (xy 419.466812 -418.717969) (xy 419.420969 -418.747434) (xy 419.371398 -418.770074)
			(xy 419.319111 -418.78543) (xy 419.26517 -418.793188) (xy 419.237922 -418.793676) (xy 418.374322 -418.793676)
			(xy 418.347066 -418.793279) (xy 418.293108 -418.785523) (xy 418.240803 -418.770168) (xy 418.191216 -418.747525)
			(xy 418.145356 -418.718055) (xy 418.104157 -418.682358) (xy 418.068458 -418.641162) (xy 418.038986 -418.595303)
			(xy 418.01634 -418.545718) (xy 418.000981 -418.493414) (xy 417.993223 -418.439456) (xy 416.555712 -418.439456)
			(xy 416.547956 -418.493399) (xy 416.5326 -418.545694) (xy 416.509958 -418.595271) (xy 416.480491 -418.641122)
			(xy 416.444799 -418.682311) (xy 416.403607 -418.718002) (xy 416.357756 -418.747467) (xy 416.308177 -418.770107)
			(xy 416.255882 -418.78546) (xy 416.201933 -418.793214) (xy 416.174682 -418.793676) (xy 415.311082 -418.793676)
			(xy 415.283829 -418.793253) (xy 415.229879 -418.785494) (xy 415.177582 -418.770136) (xy 415.128003 -418.747492)
			(xy 415.082151 -418.718022) (xy 415.040959 -418.682328) (xy 415.005267 -418.641135) (xy 414.9758 -418.595281)
			(xy 414.953158 -418.545701) (xy 414.937803 -418.493403) (xy 414.930046 -418.439453) (xy 413.492389 -418.439453)
			(xy 413.484635 -418.493386) (xy 413.469283 -418.545673) (xy 413.446647 -418.595244) (xy 413.417187 -418.641088)
			(xy 413.381503 -418.682274) (xy 413.340322 -418.717962) (xy 413.294481 -418.747427) (xy 413.244913 -418.770069)
			(xy 413.192628 -418.785426) (xy 413.138689 -418.793187) (xy 413.111442 -418.793676) (xy 412.247842 -418.793676)
			(xy 412.220585 -418.79328) (xy 412.166625 -418.785527) (xy 412.114317 -418.770173) (xy 412.064728 -418.747531)
			(xy 412.018866 -418.718062) (xy 411.977664 -418.682365) (xy 411.941963 -418.641168) (xy 411.912489 -418.595309)
			(xy 411.889841 -418.545722) (xy 411.874482 -418.493416) (xy 411.866723 -418.439457) (xy 410.429189 -418.439457)
			(xy 410.421434 -418.493392) (xy 410.40608 -418.545682) (xy 410.383441 -418.595255) (xy 410.353978 -418.641101)
			(xy 410.318289 -418.682288) (xy 410.277103 -418.717976) (xy 410.231257 -418.74744) (xy 410.181684 -418.77008)
			(xy 410.129394 -418.785434) (xy 410.075451 -418.79319) (xy 410.048202 -418.793676) (xy 409.184602 -418.793676)
			(xy 409.157347 -418.793277) (xy 409.103391 -418.78552) (xy 409.051088 -418.770163) (xy 409.001504 -418.747518)
			(xy 408.955647 -418.718048) (xy 408.91445 -418.682351) (xy 408.878753 -418.641155) (xy 408.849283 -418.595298)
			(xy 408.826638 -418.545713) (xy 408.811281 -418.493411) (xy 408.803523 -418.439455) (xy 407.366013 -418.439455)
			(xy 407.358255 -418.493402) (xy 407.342899 -418.545699) (xy 407.320255 -418.595277) (xy 407.290786 -418.641128)
			(xy 407.255091 -418.682318) (xy 407.213898 -418.718009) (xy 407.168044 -418.747474) (xy 407.118463 -418.770112)
			(xy 407.066165 -418.785463) (xy 407.012214 -418.793215) (xy 406.984962 -418.793676) (xy 406.121362 -418.793676)
			(xy 406.09411 -418.793252) (xy 406.040162 -418.78549) (xy 405.987868 -418.77013) (xy 405.938291 -418.747485)
			(xy 405.892441 -418.718015) (xy 405.851252 -418.682321) (xy 405.815562 -418.641128) (xy 405.786097 -418.595276)
			(xy 405.763456 -418.545697) (xy 405.748102 -418.493401) (xy 405.740346 -418.439452) (xy 404.302689 -418.439452)
			(xy 404.294935 -418.493389) (xy 404.279582 -418.545678) (xy 404.256944 -418.595249) (xy 404.227483 -418.641095)
			(xy 404.191796 -418.682281) (xy 404.150612 -418.717969) (xy 404.104769 -418.747434) (xy 404.055198 -418.770074)
			(xy 404.002911 -418.78543) (xy 403.94897 -418.793188) (xy 403.921722 -418.793676) (xy 403.058122 -418.793676)
			(xy 403.030866 -418.793279) (xy 402.976908 -418.785523) (xy 402.924603 -418.770168) (xy 402.875016 -418.747525)
			(xy 402.829156 -418.718055) (xy 402.787957 -418.682358) (xy 402.752258 -418.641162) (xy 402.722786 -418.595303)
			(xy 402.70014 -418.545718) (xy 402.684781 -418.493414) (xy 402.677023 -418.439456) (xy 401.239512 -418.439456)
			(xy 401.231756 -418.493399) (xy 401.2164 -418.545694) (xy 401.193758 -418.595271) (xy 401.164291 -418.641122)
			(xy 401.128599 -418.682311) (xy 401.087407 -418.718002) (xy 401.041556 -418.747467) (xy 400.991977 -418.770107)
			(xy 400.939682 -418.78546) (xy 400.885733 -418.793214) (xy 400.858482 -418.793676) (xy 399.994882 -418.793676)
			(xy 399.967629 -418.793253) (xy 399.913679 -418.785494) (xy 399.861382 -418.770136) (xy 399.811803 -418.747492)
			(xy 399.765951 -418.718022) (xy 399.724759 -418.682328) (xy 399.689067 -418.641135) (xy 399.6596 -418.595281)
			(xy 399.636958 -418.545701) (xy 399.621603 -418.493403) (xy 399.613846 -418.439453) (xy 398.176189 -418.439453)
			(xy 398.168435 -418.493386) (xy 398.153083 -418.545673) (xy 398.130447 -418.595244) (xy 398.100987 -418.641088)
			(xy 398.065303 -418.682274) (xy 398.024122 -418.717962) (xy 397.978281 -418.747427) (xy 397.928713 -418.770069)
			(xy 397.876428 -418.785426) (xy 397.822489 -418.793187) (xy 397.795242 -418.793676) (xy 396.931642 -418.793676)
			(xy 396.904385 -418.79328) (xy 396.850425 -418.785527) (xy 396.798117 -418.770173) (xy 396.748528 -418.747531)
			(xy 396.702666 -418.718062) (xy 396.661464 -418.682365) (xy 396.625763 -418.641168) (xy 396.596289 -418.595309)
			(xy 396.573641 -418.545722) (xy 396.558282 -418.493416) (xy 396.550523 -418.439457) (xy 395.112989 -418.439457)
			(xy 395.105234 -418.493392) (xy 395.08988 -418.545682) (xy 395.067241 -418.595255) (xy 395.037778 -418.641101)
			(xy 395.002089 -418.682288) (xy 394.960903 -418.717976) (xy 394.915057 -418.74744) (xy 394.865484 -418.77008)
			(xy 394.813194 -418.785434) (xy 394.759251 -418.79319) (xy 394.732002 -418.793676) (xy 393.868402 -418.793676)
			(xy 393.841147 -418.793277) (xy 393.787191 -418.78552) (xy 393.734888 -418.770163) (xy 393.685304 -418.747518)
			(xy 393.639447 -418.718048) (xy 393.59825 -418.682351) (xy 393.562553 -418.641155) (xy 393.533083 -418.595298)
			(xy 393.510438 -418.545713) (xy 393.495081 -418.493411) (xy 393.487323 -418.439455) (xy 392.049813 -418.439455)
			(xy 392.042055 -418.493402) (xy 392.026699 -418.545699) (xy 392.004055 -418.595277) (xy 391.974586 -418.641128)
			(xy 391.938891 -418.682318) (xy 391.897698 -418.718009) (xy 391.851844 -418.747474) (xy 391.802263 -418.770112)
			(xy 391.749965 -418.785463) (xy 391.696014 -418.793215) (xy 391.668762 -418.793676) (xy 390.805162 -418.793676)
			(xy 390.77791 -418.793252) (xy 390.723962 -418.78549) (xy 390.671668 -418.77013) (xy 390.622091 -418.747485)
			(xy 390.576241 -418.718015) (xy 390.535052 -418.682321) (xy 390.499362 -418.641128) (xy 390.469897 -418.595276)
			(xy 390.447256 -418.545697) (xy 390.431902 -418.493401) (xy 390.424146 -418.439452) (xy 388.986489 -418.439452)
			(xy 388.978735 -418.493389) (xy 388.963382 -418.545678) (xy 388.940744 -418.595249) (xy 388.911283 -418.641095)
			(xy 388.875596 -418.682281) (xy 388.834412 -418.717969) (xy 388.788569 -418.747434) (xy 388.738998 -418.770074)
			(xy 388.686711 -418.78543) (xy 388.63277 -418.793188) (xy 388.605522 -418.793676) (xy 387.741922 -418.793676)
			(xy 387.714666 -418.793279) (xy 387.660708 -418.785523) (xy 387.608403 -418.770168) (xy 387.558816 -418.747525)
			(xy 387.512956 -418.718055) (xy 387.471757 -418.682358) (xy 387.436058 -418.641162) (xy 387.406586 -418.595303)
			(xy 387.38394 -418.545718) (xy 387.368581 -418.493414) (xy 387.360823 -418.439456) (xy 385.923312 -418.439456)
			(xy 385.915556 -418.493399) (xy 385.9002 -418.545694) (xy 385.877558 -418.595271) (xy 385.848091 -418.641122)
			(xy 385.812399 -418.682311) (xy 385.771207 -418.718002) (xy 385.725356 -418.747467) (xy 385.675777 -418.770107)
			(xy 385.623482 -418.78546) (xy 385.569533 -418.793214) (xy 385.542282 -418.793676) (xy 384.678682 -418.793676)
			(xy 384.651429 -418.793253) (xy 384.597479 -418.785494) (xy 384.545182 -418.770136) (xy 384.495603 -418.747492)
			(xy 384.449751 -418.718022) (xy 384.408559 -418.682328) (xy 384.372867 -418.641135) (xy 384.3434 -418.595281)
			(xy 384.320758 -418.545701) (xy 384.305403 -418.493403) (xy 384.297646 -418.439453) (xy 382.859989 -418.439453)
			(xy 382.852235 -418.493386) (xy 382.836883 -418.545673) (xy 382.814247 -418.595244) (xy 382.784787 -418.641088)
			(xy 382.749103 -418.682274) (xy 382.707922 -418.717962) (xy 382.662081 -418.747427) (xy 382.612513 -418.770069)
			(xy 382.560228 -418.785426) (xy 382.506289 -418.793187) (xy 382.479042 -418.793676) (xy 381.615442 -418.793676)
			(xy 381.588185 -418.79328) (xy 381.534225 -418.785527) (xy 381.481917 -418.770173) (xy 381.432328 -418.747531)
			(xy 381.386466 -418.718062) (xy 381.345264 -418.682365) (xy 381.309563 -418.641168) (xy 381.280089 -418.595309)
			(xy 381.257441 -418.545722) (xy 381.242082 -418.493416) (xy 381.234323 -418.439457) (xy 379.796789 -418.439457)
			(xy 379.789034 -418.493392) (xy 379.77368 -418.545682) (xy 379.751041 -418.595255) (xy 379.721578 -418.641101)
			(xy 379.685889 -418.682288) (xy 379.644703 -418.717976) (xy 379.598857 -418.74744) (xy 379.549284 -418.77008)
			(xy 379.496994 -418.785434) (xy 379.443051 -418.79319) (xy 379.415802 -418.793676) (xy 378.552202 -418.793676)
			(xy 378.524947 -418.793277) (xy 378.470991 -418.78552) (xy 378.418688 -418.770163) (xy 378.369104 -418.747518)
			(xy 378.323247 -418.718048) (xy 378.28205 -418.682351) (xy 378.246353 -418.641155) (xy 378.216883 -418.595298)
			(xy 378.194238 -418.545713) (xy 378.178881 -418.493411) (xy 378.171123 -418.439455) (xy 376.733613 -418.439455)
			(xy 376.725855 -418.493402) (xy 376.710499 -418.545699) (xy 376.687855 -418.595277) (xy 376.658386 -418.641128)
			(xy 376.622691 -418.682318) (xy 376.581498 -418.718009) (xy 376.535644 -418.747474) (xy 376.486063 -418.770112)
			(xy 376.433765 -418.785463) (xy 376.379814 -418.793215) (xy 376.352562 -418.793676) (xy 375.488962 -418.793676)
			(xy 375.46171 -418.793252) (xy 375.407762 -418.78549) (xy 375.355468 -418.77013) (xy 375.305891 -418.747485)
			(xy 375.260041 -418.718015) (xy 375.218852 -418.682321) (xy 375.183162 -418.641128) (xy 375.153697 -418.595276)
			(xy 375.131056 -418.545697) (xy 375.115702 -418.493401) (xy 375.107946 -418.439452) (xy 373.670289 -418.439452)
			(xy 373.662535 -418.493389) (xy 373.647182 -418.545678) (xy 373.624544 -418.595249) (xy 373.595083 -418.641095)
			(xy 373.559396 -418.682281) (xy 373.518212 -418.717969) (xy 373.472369 -418.747434) (xy 373.422798 -418.770074)
			(xy 373.370511 -418.78543) (xy 373.31657 -418.793188) (xy 373.289322 -418.793676) (xy 372.425722 -418.793676)
			(xy 372.398466 -418.793279) (xy 372.344508 -418.785523) (xy 372.292203 -418.770168) (xy 372.242616 -418.747525)
			(xy 372.196756 -418.718055) (xy 372.155557 -418.682358) (xy 372.119858 -418.641162) (xy 372.090386 -418.595303)
			(xy 372.06774 -418.545718) (xy 372.052381 -418.493414) (xy 372.044623 -418.439456) (xy 370.313204 -418.439456)
			(xy 370.313204 -420.692072) (xy 370.313204 -420.739316) (xy 370.262404 -420.739316) (xy 370.16182 -420.739316)
			(xy 370.150438 -420.74117) (xy 370.131001 -420.753543) (xy 370.118864 -420.773128) (xy 370.117116 -420.784528)
			(xy 370.117116 -420.979455) (xy 370.513023 -420.979455) (xy 370.513023 -420.924945) (xy 370.520781 -420.870989)
			(xy 370.536138 -420.818687) (xy 370.558783 -420.769102) (xy 370.588253 -420.723245) (xy 370.62395 -420.682049)
			(xy 370.665147 -420.646352) (xy 370.711004 -420.616882) (xy 370.760588 -420.594237) (xy 370.812891 -420.57888)
			(xy 370.866847 -420.571123) (xy 370.894102 -420.57066) (xy 371.757702 -420.57066) (xy 371.784951 -420.57121)
			(xy 371.838894 -420.578966) (xy 371.891184 -420.59432) (xy 371.940757 -420.61696) (xy 371.986603 -420.646424)
			(xy 372.027789 -420.682112) (xy 372.063478 -420.723299) (xy 372.092941 -420.769145) (xy 372.11558 -420.818718)
			(xy 372.130934 -420.871008) (xy 372.13869 -420.924951) (xy 372.13869 -420.979449) (xy 372.138689 -420.979457)
			(xy 373.576223 -420.979457) (xy 373.576223 -420.924943) (xy 373.583982 -420.870984) (xy 373.599341 -420.818678)
			(xy 373.621989 -420.769091) (xy 373.651463 -420.723232) (xy 373.687164 -420.682035) (xy 373.728366 -420.646338)
			(xy 373.774228 -420.616869) (xy 373.823817 -420.594227) (xy 373.876125 -420.578873) (xy 373.930085 -420.57112)
			(xy 373.957342 -420.57066) (xy 374.820942 -420.57066) (xy 374.848189 -420.571213) (xy 374.902128 -420.578974)
			(xy 374.954413 -420.594331) (xy 375.003981 -420.616973) (xy 375.049822 -420.646438) (xy 375.091003 -420.682126)
			(xy 375.126687 -420.723312) (xy 375.156147 -420.769156) (xy 375.178783 -420.818727) (xy 375.194135 -420.871014)
			(xy 375.20189 -420.924953) (xy 375.20189 -420.979447) (xy 375.201889 -420.979453) (xy 376.639546 -420.979453)
			(xy 376.639546 -420.924947) (xy 376.647303 -420.870997) (xy 376.662658 -420.818699) (xy 376.6853 -420.769119)
			(xy 376.714767 -420.723265) (xy 376.750459 -420.682072) (xy 376.791651 -420.646378) (xy 376.837503 -420.616908)
			(xy 376.887082 -420.594264) (xy 376.939379 -420.578906) (xy 376.993329 -420.571147) (xy 377.020582 -420.57066)
			(xy 377.884182 -420.57066) (xy 377.911433 -420.571186) (xy 377.965382 -420.57894) (xy 378.017677 -420.594293)
			(xy 378.067256 -420.616933) (xy 378.113107 -420.646398) (xy 378.154299 -420.682089) (xy 378.189991 -420.723278)
			(xy 378.219458 -420.769129) (xy 378.2421 -420.818706) (xy 378.257456 -420.871001) (xy 378.265213 -420.924949)
			(xy 378.265213 -420.979451) (xy 378.265212 -420.979456) (xy 379.702723 -420.979456) (xy 379.702723 -420.924944)
			(xy 379.710481 -420.870986) (xy 379.72584 -420.818682) (xy 379.748486 -420.769097) (xy 379.777958 -420.723238)
			(xy 379.813657 -420.682042) (xy 379.854856 -420.646345) (xy 379.900716 -420.616875) (xy 379.950303 -420.594232)
			(xy 380.002608 -420.578877) (xy 380.056566 -420.571121) (xy 380.083822 -420.57066) (xy 380.947422 -420.57066)
			(xy 380.97467 -420.571212) (xy 381.028611 -420.57897) (xy 381.080898 -420.594326) (xy 381.130469 -420.616966)
			(xy 381.176312 -420.646431) (xy 381.217496 -420.682119) (xy 381.253183 -420.723305) (xy 381.282644 -420.769151)
			(xy 381.305282 -420.818722) (xy 381.320635 -420.871011) (xy 381.32839 -420.924952) (xy 381.32839 -420.979448)
			(xy 381.328389 -420.979452) (xy 382.766046 -420.979452) (xy 382.766046 -420.924948) (xy 382.773802 -420.870999)
			(xy 382.789156 -420.818703) (xy 382.811797 -420.769124) (xy 382.841262 -420.723272) (xy 382.876952 -420.682079)
			(xy 382.918141 -420.646385) (xy 382.963991 -420.616915) (xy 383.013568 -420.59427) (xy 383.065862 -420.57891)
			(xy 383.11981 -420.571148) (xy 383.147062 -420.57066) (xy 384.010662 -420.57066) (xy 384.037914 -420.571185)
			(xy 384.091865 -420.578937) (xy 384.144163 -420.594288) (xy 384.193744 -420.616926) (xy 384.239598 -420.646391)
			(xy 384.280791 -420.682082) (xy 384.316486 -420.723272) (xy 384.345955 -420.769123) (xy 384.368599 -420.818701)
			(xy 384.383955 -420.870998) (xy 384.391713 -420.924948) (xy 384.391713 -420.979452) (xy 384.391713 -420.979455)
			(xy 385.829223 -420.979455) (xy 385.829223 -420.924945) (xy 385.836981 -420.870989) (xy 385.852338 -420.818687)
			(xy 385.874983 -420.769102) (xy 385.904453 -420.723245) (xy 385.94015 -420.682049) (xy 385.981347 -420.646352)
			(xy 386.027204 -420.616882) (xy 386.076788 -420.594237) (xy 386.129091 -420.57888) (xy 386.183047 -420.571123)
			(xy 386.210302 -420.57066) (xy 387.073902 -420.57066) (xy 387.101151 -420.57121) (xy 387.155094 -420.578966)
			(xy 387.207384 -420.59432) (xy 387.256957 -420.61696) (xy 387.302803 -420.646424) (xy 387.343989 -420.682112)
			(xy 387.379678 -420.723299) (xy 387.409141 -420.769145) (xy 387.43178 -420.818718) (xy 387.447134 -420.871008)
			(xy 387.45489 -420.924951) (xy 387.45489 -420.979449) (xy 387.454889 -420.979457) (xy 388.892423 -420.979457)
			(xy 388.892423 -420.924943) (xy 388.900182 -420.870984) (xy 388.915541 -420.818678) (xy 388.938189 -420.769091)
			(xy 388.967663 -420.723232) (xy 389.003364 -420.682035) (xy 389.044566 -420.646338) (xy 389.090428 -420.616869)
			(xy 389.140017 -420.594227) (xy 389.192325 -420.578873) (xy 389.246285 -420.57112) (xy 389.273542 -420.57066)
			(xy 390.137142 -420.57066) (xy 390.164389 -420.571213) (xy 390.218328 -420.578974) (xy 390.270613 -420.594331)
			(xy 390.320181 -420.616973) (xy 390.366022 -420.646438) (xy 390.407203 -420.682126) (xy 390.442887 -420.723312)
			(xy 390.472347 -420.769156) (xy 390.494983 -420.818727) (xy 390.510335 -420.871014) (xy 390.51809 -420.924953)
			(xy 390.51809 -420.979447) (xy 390.518089 -420.979453) (xy 391.955746 -420.979453) (xy 391.955746 -420.924947)
			(xy 391.963503 -420.870997) (xy 391.978858 -420.818699) (xy 392.0015 -420.769119) (xy 392.030967 -420.723265)
			(xy 392.066659 -420.682072) (xy 392.107851 -420.646378) (xy 392.153703 -420.616908) (xy 392.203282 -420.594264)
			(xy 392.255579 -420.578906) (xy 392.309529 -420.571147) (xy 392.336782 -420.57066) (xy 393.200382 -420.57066)
			(xy 393.227633 -420.571186) (xy 393.281582 -420.57894) (xy 393.333877 -420.594293) (xy 393.383456 -420.616933)
			(xy 393.429307 -420.646398) (xy 393.470499 -420.682089) (xy 393.506191 -420.723278) (xy 393.535658 -420.769129)
			(xy 393.5583 -420.818706) (xy 393.573656 -420.871001) (xy 393.581413 -420.924949) (xy 393.581413 -420.979451)
			(xy 393.581412 -420.979456) (xy 395.018923 -420.979456) (xy 395.018923 -420.924944) (xy 395.026681 -420.870986)
			(xy 395.04204 -420.818682) (xy 395.064686 -420.769097) (xy 395.094158 -420.723238) (xy 395.129857 -420.682042)
			(xy 395.171056 -420.646345) (xy 395.216916 -420.616875) (xy 395.266503 -420.594232) (xy 395.318808 -420.578877)
			(xy 395.372766 -420.571121) (xy 395.400022 -420.57066) (xy 396.263622 -420.57066) (xy 396.29087 -420.571212)
			(xy 396.344811 -420.57897) (xy 396.397098 -420.594326) (xy 396.446669 -420.616966) (xy 396.492512 -420.646431)
			(xy 396.533696 -420.682119) (xy 396.569383 -420.723305) (xy 396.598844 -420.769151) (xy 396.621482 -420.818722)
			(xy 396.636835 -420.871011) (xy 396.64459 -420.924952) (xy 396.64459 -420.979448) (xy 396.644589 -420.979452)
			(xy 398.082246 -420.979452) (xy 398.082246 -420.924948) (xy 398.090002 -420.870999) (xy 398.105356 -420.818703)
			(xy 398.127997 -420.769124) (xy 398.157462 -420.723272) (xy 398.193152 -420.682079) (xy 398.234341 -420.646385)
			(xy 398.280191 -420.616915) (xy 398.329768 -420.59427) (xy 398.382062 -420.57891) (xy 398.43601 -420.571148)
			(xy 398.463262 -420.57066) (xy 399.326862 -420.57066) (xy 399.354114 -420.571185) (xy 399.408065 -420.578937)
			(xy 399.460363 -420.594288) (xy 399.509944 -420.616926) (xy 399.555798 -420.646391) (xy 399.596991 -420.682082)
			(xy 399.632686 -420.723272) (xy 399.662155 -420.769123) (xy 399.684799 -420.818701) (xy 399.700155 -420.870998)
			(xy 399.707913 -420.924948) (xy 399.707913 -420.979452) (xy 399.707913 -420.979455) (xy 401.145423 -420.979455)
			(xy 401.145423 -420.924945) (xy 401.153181 -420.870989) (xy 401.168538 -420.818687) (xy 401.191183 -420.769102)
			(xy 401.220653 -420.723245) (xy 401.25635 -420.682049) (xy 401.297547 -420.646352) (xy 401.343404 -420.616882)
			(xy 401.392988 -420.594237) (xy 401.445291 -420.57888) (xy 401.499247 -420.571123) (xy 401.526502 -420.57066)
			(xy 402.390102 -420.57066) (xy 402.417351 -420.57121) (xy 402.471294 -420.578966) (xy 402.523584 -420.59432)
			(xy 402.573157 -420.61696) (xy 402.619003 -420.646424) (xy 402.660189 -420.682112) (xy 402.695878 -420.723299)
			(xy 402.725341 -420.769145) (xy 402.74798 -420.818718) (xy 402.763334 -420.871008) (xy 402.77109 -420.924951)
			(xy 402.77109 -420.979449) (xy 402.771089 -420.979457) (xy 404.208623 -420.979457) (xy 404.208623 -420.924943)
			(xy 404.216382 -420.870984) (xy 404.231741 -420.818678) (xy 404.254389 -420.769091) (xy 404.283863 -420.723232)
			(xy 404.319564 -420.682035) (xy 404.360766 -420.646338) (xy 404.406628 -420.616869) (xy 404.456217 -420.594227)
			(xy 404.508525 -420.578873) (xy 404.562485 -420.57112) (xy 404.589742 -420.57066) (xy 405.453342 -420.57066)
			(xy 405.480589 -420.571213) (xy 405.534528 -420.578974) (xy 405.586813 -420.594331) (xy 405.636381 -420.616973)
			(xy 405.682222 -420.646438) (xy 405.723403 -420.682126) (xy 405.759087 -420.723312) (xy 405.788547 -420.769156)
			(xy 405.811183 -420.818727) (xy 405.826535 -420.871014) (xy 405.83429 -420.924953) (xy 405.83429 -420.979447)
			(xy 405.834289 -420.979453) (xy 407.271946 -420.979453) (xy 407.271946 -420.924947) (xy 407.279703 -420.870997)
			(xy 407.295058 -420.818699) (xy 407.3177 -420.769119) (xy 407.347167 -420.723265) (xy 407.382859 -420.682072)
			(xy 407.424051 -420.646378) (xy 407.469903 -420.616908) (xy 407.519482 -420.594264) (xy 407.571779 -420.578906)
			(xy 407.625729 -420.571147) (xy 407.652982 -420.57066) (xy 408.516582 -420.57066) (xy 408.543833 -420.571186)
			(xy 408.597782 -420.57894) (xy 408.650077 -420.594293) (xy 408.699656 -420.616933) (xy 408.745507 -420.646398)
			(xy 408.786699 -420.682089) (xy 408.822391 -420.723278) (xy 408.851858 -420.769129) (xy 408.8745 -420.818706)
			(xy 408.889856 -420.871001) (xy 408.897613 -420.924949) (xy 408.897613 -420.979451) (xy 408.897612 -420.979456)
			(xy 410.335123 -420.979456) (xy 410.335123 -420.924944) (xy 410.342881 -420.870986) (xy 410.35824 -420.818682)
			(xy 410.380886 -420.769097) (xy 410.410358 -420.723238) (xy 410.446057 -420.682042) (xy 410.487256 -420.646345)
			(xy 410.533116 -420.616875) (xy 410.582703 -420.594232) (xy 410.635008 -420.578877) (xy 410.688966 -420.571121)
			(xy 410.716222 -420.57066) (xy 411.579822 -420.57066) (xy 411.60707 -420.571212) (xy 411.661011 -420.57897)
			(xy 411.713298 -420.594326) (xy 411.762869 -420.616966) (xy 411.808712 -420.646431) (xy 411.849896 -420.682119)
			(xy 411.885583 -420.723305) (xy 411.915044 -420.769151) (xy 411.937682 -420.818722) (xy 411.953035 -420.871011)
			(xy 411.96079 -420.924952) (xy 411.96079 -420.979448) (xy 411.960789 -420.979452) (xy 413.398446 -420.979452)
			(xy 413.398446 -420.924948) (xy 413.406202 -420.870999) (xy 413.421556 -420.818703) (xy 413.444197 -420.769124)
			(xy 413.473662 -420.723272) (xy 413.509352 -420.682079) (xy 413.550541 -420.646385) (xy 413.596391 -420.616915)
			(xy 413.645968 -420.59427) (xy 413.698262 -420.57891) (xy 413.75221 -420.571148) (xy 413.779462 -420.57066)
			(xy 414.643062 -420.57066) (xy 414.670314 -420.571185) (xy 414.724265 -420.578937) (xy 414.776563 -420.594288)
			(xy 414.826144 -420.616926) (xy 414.871998 -420.646391) (xy 414.913191 -420.682082) (xy 414.948886 -420.723272)
			(xy 414.978355 -420.769123) (xy 415.000999 -420.818701) (xy 415.016355 -420.870998) (xy 415.024113 -420.924948)
			(xy 415.024113 -420.979452) (xy 415.024113 -420.979455) (xy 416.461623 -420.979455) (xy 416.461623 -420.924945)
			(xy 416.469381 -420.870989) (xy 416.484738 -420.818687) (xy 416.507383 -420.769102) (xy 416.536853 -420.723245)
			(xy 416.57255 -420.682049) (xy 416.613747 -420.646352) (xy 416.659604 -420.616882) (xy 416.709188 -420.594237)
			(xy 416.761491 -420.57888) (xy 416.815447 -420.571123) (xy 416.842702 -420.57066) (xy 417.706302 -420.57066)
			(xy 417.733551 -420.57121) (xy 417.787494 -420.578966) (xy 417.839784 -420.59432) (xy 417.889357 -420.61696)
			(xy 417.935203 -420.646424) (xy 417.976389 -420.682112) (xy 418.012078 -420.723299) (xy 418.041541 -420.769145)
			(xy 418.06418 -420.818718) (xy 418.079534 -420.871008) (xy 418.08729 -420.924951) (xy 418.08729 -420.979449)
			(xy 418.079534 -421.033392) (xy 418.06418 -421.085682) (xy 418.041541 -421.135255) (xy 418.012078 -421.181101)
			(xy 417.976389 -421.222288) (xy 417.935203 -421.257976) (xy 417.889357 -421.28744) (xy 417.839784 -421.31008)
			(xy 417.787494 -421.325434) (xy 417.733551 -421.33319) (xy 417.706302 -421.333676) (xy 416.842702 -421.333676)
			(xy 416.815447 -421.333277) (xy 416.761491 -421.32552) (xy 416.709188 -421.310163) (xy 416.659604 -421.287518)
			(xy 416.613747 -421.258048) (xy 416.57255 -421.222351) (xy 416.536853 -421.181155) (xy 416.507383 -421.135298)
			(xy 416.484738 -421.085713) (xy 416.469381 -421.033411) (xy 416.461623 -420.979455) (xy 415.024113 -420.979455)
			(xy 415.016355 -421.033402) (xy 415.000999 -421.085699) (xy 414.978355 -421.135277) (xy 414.948886 -421.181128)
			(xy 414.913191 -421.222318) (xy 414.871998 -421.258009) (xy 414.826144 -421.287474) (xy 414.776563 -421.310112)
			(xy 414.724265 -421.325463) (xy 414.670314 -421.333215) (xy 414.643062 -421.333676) (xy 413.779462 -421.333676)
			(xy 413.75221 -421.333252) (xy 413.698262 -421.32549) (xy 413.645968 -421.31013) (xy 413.596391 -421.287485)
			(xy 413.550541 -421.258015) (xy 413.509352 -421.222321) (xy 413.473662 -421.181128) (xy 413.444197 -421.135276)
			(xy 413.421556 -421.085697) (xy 413.406202 -421.033401) (xy 413.398446 -420.979452) (xy 411.960789 -420.979452)
			(xy 411.953035 -421.033389) (xy 411.937682 -421.085678) (xy 411.915044 -421.135249) (xy 411.885583 -421.181095)
			(xy 411.849896 -421.222281) (xy 411.808712 -421.257969) (xy 411.762869 -421.287434) (xy 411.713298 -421.310074)
			(xy 411.661011 -421.32543) (xy 411.60707 -421.333188) (xy 411.579822 -421.333676) (xy 410.716222 -421.333676)
			(xy 410.688966 -421.333279) (xy 410.635008 -421.325523) (xy 410.582703 -421.310168) (xy 410.533116 -421.287525)
			(xy 410.487256 -421.258055) (xy 410.446057 -421.222358) (xy 410.410358 -421.181162) (xy 410.380886 -421.135303)
			(xy 410.35824 -421.085718) (xy 410.342881 -421.033414) (xy 410.335123 -420.979456) (xy 408.897612 -420.979456)
			(xy 408.889856 -421.033399) (xy 408.8745 -421.085694) (xy 408.851858 -421.135271) (xy 408.822391 -421.181122)
			(xy 408.786699 -421.222311) (xy 408.745507 -421.258002) (xy 408.699656 -421.287467) (xy 408.650077 -421.310107)
			(xy 408.597782 -421.32546) (xy 408.543833 -421.333214) (xy 408.516582 -421.333676) (xy 407.652982 -421.333676)
			(xy 407.625729 -421.333253) (xy 407.571779 -421.325494) (xy 407.519482 -421.310136) (xy 407.469903 -421.287492)
			(xy 407.424051 -421.258022) (xy 407.382859 -421.222328) (xy 407.347167 -421.181135) (xy 407.3177 -421.135281)
			(xy 407.295058 -421.085701) (xy 407.279703 -421.033403) (xy 407.271946 -420.979453) (xy 405.834289 -420.979453)
			(xy 405.826535 -421.033386) (xy 405.811183 -421.085673) (xy 405.788547 -421.135244) (xy 405.759087 -421.181088)
			(xy 405.723403 -421.222274) (xy 405.682222 -421.257962) (xy 405.636381 -421.287427) (xy 405.586813 -421.310069)
			(xy 405.534528 -421.325426) (xy 405.480589 -421.333187) (xy 405.453342 -421.333676) (xy 404.589742 -421.333676)
			(xy 404.562485 -421.33328) (xy 404.508525 -421.325527) (xy 404.456217 -421.310173) (xy 404.406628 -421.287531)
			(xy 404.360766 -421.258062) (xy 404.319564 -421.222365) (xy 404.283863 -421.181168) (xy 404.254389 -421.135309)
			(xy 404.231741 -421.085722) (xy 404.216382 -421.033416) (xy 404.208623 -420.979457) (xy 402.771089 -420.979457)
			(xy 402.763334 -421.033392) (xy 402.74798 -421.085682) (xy 402.725341 -421.135255) (xy 402.695878 -421.181101)
			(xy 402.660189 -421.222288) (xy 402.619003 -421.257976) (xy 402.573157 -421.28744) (xy 402.523584 -421.31008)
			(xy 402.471294 -421.325434) (xy 402.417351 -421.33319) (xy 402.390102 -421.333676) (xy 401.526502 -421.333676)
			(xy 401.499247 -421.333277) (xy 401.445291 -421.32552) (xy 401.392988 -421.310163) (xy 401.343404 -421.287518)
			(xy 401.297547 -421.258048) (xy 401.25635 -421.222351) (xy 401.220653 -421.181155) (xy 401.191183 -421.135298)
			(xy 401.168538 -421.085713) (xy 401.153181 -421.033411) (xy 401.145423 -420.979455) (xy 399.707913 -420.979455)
			(xy 399.700155 -421.033402) (xy 399.684799 -421.085699) (xy 399.662155 -421.135277) (xy 399.632686 -421.181128)
			(xy 399.596991 -421.222318) (xy 399.555798 -421.258009) (xy 399.509944 -421.287474) (xy 399.460363 -421.310112)
			(xy 399.408065 -421.325463) (xy 399.354114 -421.333215) (xy 399.326862 -421.333676) (xy 398.463262 -421.333676)
			(xy 398.43601 -421.333252) (xy 398.382062 -421.32549) (xy 398.329768 -421.31013) (xy 398.280191 -421.287485)
			(xy 398.234341 -421.258015) (xy 398.193152 -421.222321) (xy 398.157462 -421.181128) (xy 398.127997 -421.135276)
			(xy 398.105356 -421.085697) (xy 398.090002 -421.033401) (xy 398.082246 -420.979452) (xy 396.644589 -420.979452)
			(xy 396.636835 -421.033389) (xy 396.621482 -421.085678) (xy 396.598844 -421.135249) (xy 396.569383 -421.181095)
			(xy 396.533696 -421.222281) (xy 396.492512 -421.257969) (xy 396.446669 -421.287434) (xy 396.397098 -421.310074)
			(xy 396.344811 -421.32543) (xy 396.29087 -421.333188) (xy 396.263622 -421.333676) (xy 395.400022 -421.333676)
			(xy 395.372766 -421.333279) (xy 395.318808 -421.325523) (xy 395.266503 -421.310168) (xy 395.216916 -421.287525)
			(xy 395.171056 -421.258055) (xy 395.129857 -421.222358) (xy 395.094158 -421.181162) (xy 395.064686 -421.135303)
			(xy 395.04204 -421.085718) (xy 395.026681 -421.033414) (xy 395.018923 -420.979456) (xy 393.581412 -420.979456)
			(xy 393.573656 -421.033399) (xy 393.5583 -421.085694) (xy 393.535658 -421.135271) (xy 393.506191 -421.181122)
			(xy 393.470499 -421.222311) (xy 393.429307 -421.258002) (xy 393.383456 -421.287467) (xy 393.333877 -421.310107)
			(xy 393.281582 -421.32546) (xy 393.227633 -421.333214) (xy 393.200382 -421.333676) (xy 392.336782 -421.333676)
			(xy 392.309529 -421.333253) (xy 392.255579 -421.325494) (xy 392.203282 -421.310136) (xy 392.153703 -421.287492)
			(xy 392.107851 -421.258022) (xy 392.066659 -421.222328) (xy 392.030967 -421.181135) (xy 392.0015 -421.135281)
			(xy 391.978858 -421.085701) (xy 391.963503 -421.033403) (xy 391.955746 -420.979453) (xy 390.518089 -420.979453)
			(xy 390.510335 -421.033386) (xy 390.494983 -421.085673) (xy 390.472347 -421.135244) (xy 390.442887 -421.181088)
			(xy 390.407203 -421.222274) (xy 390.366022 -421.257962) (xy 390.320181 -421.287427) (xy 390.270613 -421.310069)
			(xy 390.218328 -421.325426) (xy 390.164389 -421.333187) (xy 390.137142 -421.333676) (xy 389.273542 -421.333676)
			(xy 389.246285 -421.33328) (xy 389.192325 -421.325527) (xy 389.140017 -421.310173) (xy 389.090428 -421.287531)
			(xy 389.044566 -421.258062) (xy 389.003364 -421.222365) (xy 388.967663 -421.181168) (xy 388.938189 -421.135309)
			(xy 388.915541 -421.085722) (xy 388.900182 -421.033416) (xy 388.892423 -420.979457) (xy 387.454889 -420.979457)
			(xy 387.447134 -421.033392) (xy 387.43178 -421.085682) (xy 387.409141 -421.135255) (xy 387.379678 -421.181101)
			(xy 387.343989 -421.222288) (xy 387.302803 -421.257976) (xy 387.256957 -421.28744) (xy 387.207384 -421.31008)
			(xy 387.155094 -421.325434) (xy 387.101151 -421.33319) (xy 387.073902 -421.333676) (xy 386.210302 -421.333676)
			(xy 386.183047 -421.333277) (xy 386.129091 -421.32552) (xy 386.076788 -421.310163) (xy 386.027204 -421.287518)
			(xy 385.981347 -421.258048) (xy 385.94015 -421.222351) (xy 385.904453 -421.181155) (xy 385.874983 -421.135298)
			(xy 385.852338 -421.085713) (xy 385.836981 -421.033411) (xy 385.829223 -420.979455) (xy 384.391713 -420.979455)
			(xy 384.383955 -421.033402) (xy 384.368599 -421.085699) (xy 384.345955 -421.135277) (xy 384.316486 -421.181128)
			(xy 384.280791 -421.222318) (xy 384.239598 -421.258009) (xy 384.193744 -421.287474) (xy 384.144163 -421.310112)
			(xy 384.091865 -421.325463) (xy 384.037914 -421.333215) (xy 384.010662 -421.333676) (xy 383.147062 -421.333676)
			(xy 383.11981 -421.333252) (xy 383.065862 -421.32549) (xy 383.013568 -421.31013) (xy 382.963991 -421.287485)
			(xy 382.918141 -421.258015) (xy 382.876952 -421.222321) (xy 382.841262 -421.181128) (xy 382.811797 -421.135276)
			(xy 382.789156 -421.085697) (xy 382.773802 -421.033401) (xy 382.766046 -420.979452) (xy 381.328389 -420.979452)
			(xy 381.320635 -421.033389) (xy 381.305282 -421.085678) (xy 381.282644 -421.135249) (xy 381.253183 -421.181095)
			(xy 381.217496 -421.222281) (xy 381.176312 -421.257969) (xy 381.130469 -421.287434) (xy 381.080898 -421.310074)
			(xy 381.028611 -421.32543) (xy 380.97467 -421.333188) (xy 380.947422 -421.333676) (xy 380.083822 -421.333676)
			(xy 380.056566 -421.333279) (xy 380.002608 -421.325523) (xy 379.950303 -421.310168) (xy 379.900716 -421.287525)
			(xy 379.854856 -421.258055) (xy 379.813657 -421.222358) (xy 379.777958 -421.181162) (xy 379.748486 -421.135303)
			(xy 379.72584 -421.085718) (xy 379.710481 -421.033414) (xy 379.702723 -420.979456) (xy 378.265212 -420.979456)
			(xy 378.257456 -421.033399) (xy 378.2421 -421.085694) (xy 378.219458 -421.135271) (xy 378.189991 -421.181122)
			(xy 378.154299 -421.222311) (xy 378.113107 -421.258002) (xy 378.067256 -421.287467) (xy 378.017677 -421.310107)
			(xy 377.965382 -421.32546) (xy 377.911433 -421.333214) (xy 377.884182 -421.333676) (xy 377.020582 -421.333676)
			(xy 376.993329 -421.333253) (xy 376.939379 -421.325494) (xy 376.887082 -421.310136) (xy 376.837503 -421.287492)
			(xy 376.791651 -421.258022) (xy 376.750459 -421.222328) (xy 376.714767 -421.181135) (xy 376.6853 -421.135281)
			(xy 376.662658 -421.085701) (xy 376.647303 -421.033403) (xy 376.639546 -420.979453) (xy 375.201889 -420.979453)
			(xy 375.194135 -421.033386) (xy 375.178783 -421.085673) (xy 375.156147 -421.135244) (xy 375.126687 -421.181088)
			(xy 375.091003 -421.222274) (xy 375.049822 -421.257962) (xy 375.003981 -421.287427) (xy 374.954413 -421.310069)
			(xy 374.902128 -421.325426) (xy 374.848189 -421.333187) (xy 374.820942 -421.333676) (xy 373.957342 -421.333676)
			(xy 373.930085 -421.33328) (xy 373.876125 -421.325527) (xy 373.823817 -421.310173) (xy 373.774228 -421.287531)
			(xy 373.728366 -421.258062) (xy 373.687164 -421.222365) (xy 373.651463 -421.181168) (xy 373.621989 -421.135309)
			(xy 373.599341 -421.085722) (xy 373.583982 -421.033416) (xy 373.576223 -420.979457) (xy 372.138689 -420.979457)
			(xy 372.130934 -421.033392) (xy 372.11558 -421.085682) (xy 372.092941 -421.135255) (xy 372.063478 -421.181101)
			(xy 372.027789 -421.222288) (xy 371.986603 -421.257976) (xy 371.940757 -421.28744) (xy 371.891184 -421.31008)
			(xy 371.838894 -421.325434) (xy 371.784951 -421.33319) (xy 371.757702 -421.333676) (xy 370.894102 -421.333676)
			(xy 370.866847 -421.333277) (xy 370.812891 -421.32552) (xy 370.760588 -421.310163) (xy 370.711004 -421.287518)
			(xy 370.665147 -421.258048) (xy 370.62395 -421.222351) (xy 370.588253 -421.181155) (xy 370.558783 -421.135298)
			(xy 370.536138 -421.085713) (xy 370.520781 -421.033411) (xy 370.513023 -420.979455) (xy 370.117116 -420.979455)
			(xy 370.117116 -421.134032) (xy 370.118827 -421.145443) (xy 370.130963 -421.165042) (xy 370.150431 -421.17739)
			(xy 370.16182 -421.179244) (xy 370.26596 -421.179244) (xy 370.313204 -421.179244) (xy 370.313204 -421.230044)
			(xy 370.313204 -422.692576) (xy 370.312768 -422.702798) (xy 370.30495 -422.721687) (xy 370.290497 -422.736144)
			(xy 370.27161 -422.743966) (xy 370.261388 -422.744392) (xy 365.362744 -422.744392) (xy 365.352522 -422.743952)
			(xy 365.333631 -422.736138) (xy 365.319173 -422.721686) (xy 365.311352 -422.702798) (xy 365.310928 -422.692576)
			(xy 360.222212 -422.692576) (xy 360.286426 -422.706639) (xy 360.410636 -422.74198) (xy 360.532435 -422.7849)
			(xy 360.65136 -422.835237) (xy 360.766961 -422.892799) (xy 360.8788 -422.957369) (xy 360.986451 -423.028701)
			(xy 361.089506 -423.106525) (xy 361.187576 -423.190546) (xy 361.280287 -423.280445) (xy 361.367287 -423.37588)
			(xy 361.448248 -423.47649) (xy 361.505055 -423.556738) (xy 456.285335 -423.556738) (xy 456.285335 -423.427598)
			(xy 456.293285 -423.298703) (xy 456.309155 -423.170543) (xy 456.332884 -423.043602) (xy 456.364383 -422.918363)
			(xy 456.403532 -422.7953) (xy 456.450183 -422.674881) (xy 456.504158 -422.557562) (xy 456.565253 -422.443788)
			(xy 456.633236 -422.333991) (xy 456.70785 -422.228588) (xy 456.788811 -422.127978) (xy 456.875811 -422.032543)
			(xy 456.968522 -421.942644) (xy 457.066592 -421.858623) (xy 457.169647 -421.780799) (xy 457.277298 -421.709467)
			(xy 457.389137 -421.644897) (xy 457.504738 -421.587335) (xy 457.623663 -421.536998) (xy 457.745462 -421.494078)
			(xy 457.869672 -421.458737) (xy 457.995821 -421.43111) (xy 458.123433 -421.411301) (xy 458.252022 -421.399385)
			(xy 458.3811 -421.395409) (xy 458.510178 -421.399385) (xy 458.638767 -421.411301) (xy 458.766379 -421.43111)
			(xy 458.892528 -421.458737) (xy 459.016738 -421.494078) (xy 459.138537 -421.536998) (xy 459.257462 -421.587335)
			(xy 459.373063 -421.644897) (xy 459.484902 -421.709467) (xy 459.592553 -421.780799) (xy 459.695608 -421.858623)
			(xy 459.793678 -421.942644) (xy 459.886389 -422.032543) (xy 459.973389 -422.127978) (xy 460.05435 -422.228588)
			(xy 460.128964 -422.333991) (xy 460.196947 -422.443788) (xy 460.258042 -422.557562) (xy 460.312017 -422.674881)
			(xy 460.358668 -422.7953) (xy 460.397817 -422.918363) (xy 460.429316 -423.043602) (xy 460.453045 -423.170543)
			(xy 460.468915 -423.298703) (xy 460.476865 -423.427598) (xy 460.477362 -423.492168) (xy 460.476865 -423.556738)
			(xy 460.468915 -423.685633) (xy 460.453045 -423.813793) (xy 460.429316 -423.940734) (xy 460.397817 -424.065973)
			(xy 460.358668 -424.189036) (xy 460.312017 -424.309455) (xy 460.258042 -424.426774) (xy 460.196947 -424.540548)
			(xy 460.128964 -424.650345) (xy 460.05435 -424.755748) (xy 459.973389 -424.856358) (xy 459.886389 -424.951793)
			(xy 459.793678 -425.041692) (xy 459.695608 -425.125713) (xy 459.592553 -425.203537) (xy 459.484902 -425.274869)
			(xy 459.373063 -425.339439) (xy 459.257462 -425.397001) (xy 459.138537 -425.447338) (xy 459.016738 -425.490258)
			(xy 458.892528 -425.525599) (xy 458.766379 -425.553226) (xy 458.638767 -425.573035) (xy 458.510178 -425.584951)
			(xy 458.3811 -425.588928) (xy 458.252022 -425.584951) (xy 458.123433 -425.573035) (xy 457.995821 -425.553226)
			(xy 457.869672 -425.525599) (xy 457.745462 -425.490258) (xy 457.623663 -425.447338) (xy 457.504738 -425.397001)
			(xy 457.389137 -425.339439) (xy 457.277298 -425.274869) (xy 457.169647 -425.203537) (xy 457.066592 -425.125713)
			(xy 456.968522 -425.041692) (xy 456.875811 -424.951793) (xy 456.788811 -424.856358) (xy 456.70785 -424.755748)
			(xy 456.633236 -424.650345) (xy 456.565253 -424.540548) (xy 456.504158 -424.426774) (xy 456.450183 -424.309455)
			(xy 456.403532 -424.189036) (xy 456.364383 -424.065973) (xy 456.332884 -423.940734) (xy 456.309155 -423.813793)
			(xy 456.293285 -423.685633) (xy 456.285335 -423.556738) (xy 361.505055 -423.556738) (xy 361.522862 -423.581893)
			(xy 361.590845 -423.69169) (xy 361.65194 -423.805464) (xy 361.705915 -423.922783) (xy 361.752566 -424.043202)
			(xy 361.791715 -424.166265) (xy 361.823214 -424.291504) (xy 361.846943 -424.418445) (xy 361.862813 -424.546605)
			(xy 361.870763 -424.6755) (xy 361.87126 -424.74007) (xy 361.870763 -424.80464) (xy 361.862813 -424.933535)
			(xy 361.846943 -425.061695) (xy 361.823214 -425.188636) (xy 361.791715 -425.313875) (xy 361.752566 -425.436938)
			(xy 361.705915 -425.557357) (xy 361.65194 -425.674676) (xy 361.590845 -425.78845) (xy 361.522862 -425.898247)
			(xy 361.448248 -426.00365) (xy 361.367287 -426.10426) (xy 361.280287 -426.199695) (xy 361.187576 -426.289594)
			(xy 361.089506 -426.373615) (xy 360.986451 -426.451439) (xy 360.8788 -426.522771) (xy 360.766961 -426.587341)
			(xy 360.65136 -426.644903) (xy 360.532435 -426.69524) (xy 360.410636 -426.73816) (xy 360.286426 -426.773501)
			(xy 360.160277 -426.801128) (xy 360.032665 -426.820937) (xy 359.904076 -426.832853) (xy 359.774998 -426.83683)
			(xy 359.64592 -426.832853) (xy 359.517331 -426.820937) (xy 359.389719 -426.801128) (xy 359.26357 -426.773501)
			(xy 359.13936 -426.73816) (xy 359.017561 -426.69524) (xy 358.898636 -426.644903) (xy 358.783035 -426.587341)
			(xy 358.671196 -426.522771) (xy 358.563545 -426.451439) (xy 358.46049 -426.373615) (xy 358.36242 -426.289594)
			(xy 358.269709 -426.199695) (xy 358.182709 -426.10426) (xy 358.101748 -426.00365) (xy 358.027134 -425.898247)
			(xy 357.959151 -425.78845) (xy 357.898056 -425.674676) (xy 357.844081 -425.557357) (xy 357.79743 -425.436938)
			(xy 357.758281 -425.313875) (xy 357.726782 -425.188636) (xy 357.703053 -425.061695) (xy 357.687183 -424.933535)
			(xy 357.679233 -424.80464) (xy 230.3145 -424.80464) (xy 230.3145 -427.960536) (xy 314.141104 -427.960536)
			(xy 314.141104 -425.419012) (xy 314.14157 -425.406962) (xy 314.149 -425.384036) (xy 314.163139 -425.36452)
			(xy 314.182609 -425.350316) (xy 314.20551 -425.342811) (xy 314.217558 -425.342304) (xy 315.157866 -425.342304)
			(xy 315.16995 -425.342836) (xy 315.192944 -425.350279) (xy 315.212521 -425.36445) (xy 315.226774 -425.383968)
			(xy 315.234313 -425.40693) (xy 315.234828 -425.419012) (xy 315.234828 -427.960536) (xy 315.234371 -427.972585)
			(xy 315.226932 -427.995507) (xy 315.21279 -428.01502) (xy 315.193321 -428.029223) (xy 315.170422 -428.036734)
			(xy 315.158374 -428.037244) (xy 314.218066 -428.037244) (xy 314.205973 -428.036821) (xy 314.182969 -428.029353)
			(xy 314.163388 -428.015156) (xy 314.149139 -427.995612) (xy 314.141611 -427.972628) (xy 314.141104 -427.960536)
			(xy 230.3145 -427.960536) (xy 230.3145 -433.130695) (xy 266.885917 -433.130695) (xy 266.885917 -432.953425)
			(xy 266.89387 -432.776334) (xy 266.909761 -432.599778) (xy 266.933556 -432.424113) (xy 266.965209 -432.249692)
			(xy 267.004655 -432.076867) (xy 267.051815 -431.905986) (xy 267.106594 -431.737392) (xy 267.168882 -431.571427)
			(xy 267.238554 -431.408422) (xy 267.315468 -431.248708) (xy 267.399471 -431.092605) (xy 267.490392 -430.940428)
			(xy 267.588049 -430.792484) (xy 267.692246 -430.64907) (xy 267.802772 -430.510475) (xy 267.919404 -430.376978)
			(xy 268.041909 -430.248849) (xy 268.170038 -430.126344) (xy 268.303535 -430.009712) (xy 268.44213 -429.899186)
			(xy 268.585544 -429.794989) (xy 268.733488 -429.697332) (xy 268.885665 -429.606411) (xy 269.041768 -429.522408)
			(xy 269.201482 -429.445494) (xy 269.364487 -429.375822) (xy 269.530452 -429.313534) (xy 269.699046 -429.258755)
			(xy 269.869927 -429.211595) (xy 270.042752 -429.172149) (xy 270.217173 -429.140496) (xy 270.392838 -429.116701)
			(xy 270.569394 -429.10081) (xy 270.746485 -429.092857) (xy 270.923755 -429.092857) (xy 271.100846 -429.10081)
			(xy 271.277402 -429.116701) (xy 271.453067 -429.140496) (xy 271.627488 -429.172149) (xy 271.800313 -429.211595)
			(xy 271.971194 -429.258755) (xy 272.139788 -429.313534) (xy 272.305753 -429.375822) (xy 272.468758 -429.445494)
			(xy 272.628472 -429.522408) (xy 272.784575 -429.606411) (xy 272.936752 -429.697332) (xy 273.084696 -429.794989)
			(xy 273.22811 -429.899186) (xy 273.366705 -430.009712) (xy 273.500202 -430.126344) (xy 273.628331 -430.248849)
			(xy 273.750836 -430.376978) (xy 273.867468 -430.510475) (xy 273.977994 -430.64907) (xy 274.082191 -430.792484)
			(xy 274.179848 -430.940428) (xy 274.270769 -431.092605) (xy 274.354772 -431.248708) (xy 274.431686 -431.408422)
			(xy 274.496678 -431.560478) (xy 314.141104 -431.560478) (xy 314.141104 -429.018954) (xy 314.141572 -429.00684)
			(xy 314.149068 -428.983801) (xy 314.163312 -428.964203) (xy 314.182912 -428.949962) (xy 314.205952 -428.94247)
			(xy 314.218066 -428.941992) (xy 315.157866 -428.941992) (xy 315.169974 -428.94254) (xy 315.193009 -428.950012)
			(xy 315.207506 -428.960534) (xy 316.1411 -428.960534) (xy 316.1411 -426.41901) (xy 316.14162 -426.4069)
			(xy 316.1491 -426.383863) (xy 316.163331 -426.364265) (xy 316.18292 -426.350022) (xy 316.205952 -426.342527)
			(xy 316.218062 -426.342048) (xy 317.157862 -426.342048) (xy 317.169984 -426.342492) (xy 317.193043 -426.349975)
			(xy 317.21266 -426.36422) (xy 317.226912 -426.383832) (xy 317.234403 -426.406888) (xy 317.234824 -426.41901)
			(xy 317.234824 -427.960536) (xy 318.141096 -427.960536) (xy 318.141096 -425.419012) (xy 318.14157 -425.406963)
			(xy 318.148999 -425.384038) (xy 318.163136 -425.364523) (xy 318.182604 -425.350319) (xy 318.205503 -425.342812)
			(xy 318.21755 -425.342304) (xy 319.157858 -425.342304) (xy 319.169942 -425.342842) (xy 319.192935 -425.350283)
			(xy 319.212513 -425.364453) (xy 319.226766 -425.383969) (xy 319.234305 -425.40693) (xy 319.23482 -425.419012)
			(xy 319.23482 -427.960536) (xy 319.234371 -427.972586) (xy 319.226931 -427.99551) (xy 319.212787 -428.015023)
			(xy 319.193316 -428.029226) (xy 319.170415 -428.036735) (xy 319.158366 -428.037244) (xy 318.218058 -428.037244)
			(xy 318.205965 -428.036828) (xy 318.18296 -428.029358) (xy 318.163379 -428.015159) (xy 318.149131 -427.995614)
			(xy 318.141603 -427.972628) (xy 318.141096 -427.960536) (xy 317.234824 -427.960536) (xy 317.234824 -428.960534)
			(xy 317.234469 -428.972662) (xy 317.226962 -428.995729) (xy 317.212695 -429.015347) (xy 317.193064 -429.029595)
			(xy 317.169991 -429.03708) (xy 317.157862 -429.037496) (xy 316.218062 -429.037496) (xy 316.205949 -429.037021)
			(xy 316.18291 -429.029528) (xy 316.163312 -429.015285) (xy 316.14907 -428.995686) (xy 316.141578 -428.972647)
			(xy 316.1411 -428.960534) (xy 315.207506 -428.960534) (xy 315.212607 -428.964236) (xy 315.226851 -428.98382)
			(xy 315.234347 -429.006846) (xy 315.234828 -429.018954) (xy 315.234828 -431.560478) (xy 315.234421 -431.572603)
			(xy 315.22693 -431.595667) (xy 315.212677 -431.615285) (xy 315.193056 -431.629536) (xy 315.169991 -431.637023)
			(xy 315.157866 -431.63744) (xy 314.218066 -431.63744) (xy 314.205947 -431.637017) (xy 314.182899 -431.629518)
			(xy 314.163296 -431.615264) (xy 314.149057 -431.59565) (xy 314.141574 -431.572597) (xy 314.141104 -431.560478)
			(xy 274.496678 -431.560478) (xy 274.501358 -431.571427) (xy 274.563646 -431.737392) (xy 274.618425 -431.905986)
			(xy 274.665585 -432.076867) (xy 274.705031 -432.249692) (xy 274.736684 -432.424113) (xy 274.760479 -432.599778)
			(xy 274.77637 -432.776334) (xy 274.784323 -432.953425) (xy 274.78482 -433.04206) (xy 274.784323 -433.130695)
			(xy 274.77637 -433.307786) (xy 274.760479 -433.484342) (xy 274.736684 -433.660007) (xy 274.705031 -433.834428)
			(xy 274.665585 -434.007253) (xy 274.618425 -434.178134) (xy 274.563646 -434.346728) (xy 274.501358 -434.512693)
			(xy 274.431686 -434.675698) (xy 274.354772 -434.835412) (xy 274.270769 -434.991515) (xy 274.179848 -435.143692)
			(xy 274.168806 -435.16042) (xy 314.141104 -435.16042) (xy 314.141104 -432.618896) (xy 314.141557 -432.606845)
			(xy 314.148991 -432.583919) (xy 314.163134 -432.564403) (xy 314.182606 -432.5502) (xy 314.205509 -432.542694)
			(xy 314.217558 -432.542188) (xy 315.157866 -432.542188) (xy 315.169959 -432.542637) (xy 315.192966 -432.55009)
			(xy 315.207301 -432.560476) (xy 316.1411 -432.560476) (xy 316.1411 -430.018952) (xy 316.141519 -430.006899)
			(xy 316.148965 -429.983972) (xy 316.163116 -429.964457) (xy 316.182595 -429.950255) (xy 316.205503 -429.94275)
			(xy 316.217554 -429.942244) (xy 317.157862 -429.942244) (xy 317.16995 -429.94274) (xy 317.19295 -429.950187)
			(xy 317.212531 -429.964366) (xy 317.226783 -429.983894) (xy 317.234315 -430.006866) (xy 317.234824 -430.018952)
			(xy 317.234824 -431.560478) (xy 318.141096 -431.560478) (xy 318.141096 -429.018954) (xy 318.141572 -429.006841)
			(xy 318.149067 -428.983804) (xy 318.163309 -428.964206) (xy 318.182907 -428.949965) (xy 318.205945 -428.942471)
			(xy 318.218058 -428.941992) (xy 319.157858 -428.941992) (xy 319.169966 -428.942547) (xy 319.193 -428.950017)
			(xy 319.207492 -428.960534) (xy 320.141092 -428.960534) (xy 320.141092 -426.41901) (xy 320.14162 -426.406901)
			(xy 320.149099 -426.383865) (xy 320.163328 -426.364268) (xy 320.182915 -426.350024) (xy 320.205945 -426.342528)
			(xy 320.218054 -426.342048) (xy 321.157854 -426.342048) (xy 321.169975 -426.342499) (xy 321.193034 -426.34998)
			(xy 321.212651 -426.364223) (xy 321.226904 -426.383833) (xy 321.234395 -426.406889) (xy 321.234816 -426.41901)
			(xy 321.234816 -427.960536) (xy 322.141088 -427.960536) (xy 322.141088 -425.419012) (xy 322.14157 -425.406964)
			(xy 322.148998 -425.38404) (xy 322.163133 -425.364526) (xy 322.182598 -425.350321) (xy 322.205495 -425.342813)
			(xy 322.217542 -425.342304) (xy 323.15785 -425.342304) (xy 323.169933 -425.342849) (xy 323.192926 -425.350288)
			(xy 323.212504 -425.364455) (xy 323.226758 -425.383971) (xy 323.234297 -425.406931) (xy 323.234812 -425.419012)
			(xy 323.234812 -427.960536) (xy 323.234371 -427.972587) (xy 323.22693 -427.995512) (xy 323.212784 -428.015026)
			(xy 323.193311 -428.029228) (xy 323.170407 -428.036736) (xy 323.158358 -428.037244) (xy 322.21805 -428.037244)
			(xy 322.205961 -428.03675) (xy 322.18296 -428.029305) (xy 322.163378 -428.015126) (xy 322.149126 -427.995597)
			(xy 322.141595 -427.972623) (xy 322.141088 -427.960536) (xy 321.234816 -427.960536) (xy 321.234816 -428.960534)
			(xy 321.234468 -428.972663) (xy 321.226961 -428.995731) (xy 321.212692 -429.015349) (xy 321.193059 -429.029598)
			(xy 321.169984 -429.037081) (xy 321.157854 -429.037496) (xy 320.218054 -429.037496) (xy 320.20594 -429.037028)
			(xy 320.182901 -429.029532) (xy 320.163303 -429.015288) (xy 320.149062 -428.995688) (xy 320.14157 -428.972648)
			(xy 320.141092 -428.960534) (xy 319.207492 -428.960534) (xy 319.212598 -428.964239) (xy 319.226843 -428.983821)
			(xy 319.234339 -429.006847) (xy 319.23482 -429.018954) (xy 319.23482 -431.560478) (xy 319.234421 -431.572604)
			(xy 319.226929 -431.595669) (xy 319.212674 -431.615288) (xy 319.193051 -431.629538) (xy 319.169984 -431.637024)
			(xy 319.157858 -431.63744) (xy 318.218058 -431.63744) (xy 318.205939 -431.637024) (xy 318.182891 -431.629522)
			(xy 318.163288 -431.615267) (xy 318.149048 -431.595652) (xy 318.141566 -431.572597) (xy 318.141096 -431.560478)
			(xy 317.234824 -431.560478) (xy 317.234824 -432.560476) (xy 317.23432 -432.572523) (xy 317.226897 -432.595443)
			(xy 317.212767 -432.614957) (xy 317.193307 -432.629162) (xy 317.170415 -432.636673) (xy 317.15837 -432.637184)
			(xy 316.218062 -432.637184) (xy 316.205973 -432.636726) (xy 316.182975 -432.629261) (xy 316.163398 -432.615072)
			(xy 316.149148 -432.595538) (xy 316.141612 -432.572564) (xy 316.1411 -432.560476) (xy 315.207301 -432.560476)
			(xy 315.212551 -432.56428) (xy 315.226801 -432.583821) (xy 315.234325 -432.606805) (xy 315.234828 -432.618896)
			(xy 315.234828 -435.16042) (xy 315.234357 -435.172468) (xy 315.226923 -435.19539) (xy 315.212784 -435.214903)
			(xy 315.193317 -435.229106) (xy 315.170421 -435.236617) (xy 315.158374 -435.237128) (xy 314.218066 -435.237128)
			(xy 314.205971 -435.236721) (xy 314.182964 -435.229251) (xy 314.163382 -435.21505) (xy 314.149134 -435.195502)
			(xy 314.141608 -435.172513) (xy 314.141104 -435.16042) (xy 274.168806 -435.16042) (xy 274.082191 -435.291636)
			(xy 273.977994 -435.43505) (xy 273.867468 -435.573645) (xy 273.750836 -435.707142) (xy 273.628331 -435.835271)
			(xy 273.500202 -435.957776) (xy 273.366705 -436.074408) (xy 273.22811 -436.184934) (xy 273.084696 -436.289131)
			(xy 272.936752 -436.386788) (xy 272.784575 -436.477709) (xy 272.628472 -436.561712) (xy 272.468758 -436.638626)
			(xy 272.305753 -436.708298) (xy 272.139788 -436.770586) (xy 271.971194 -436.825365) (xy 271.800313 -436.872525)
			(xy 271.627488 -436.911971) (xy 271.453067 -436.943624) (xy 271.277402 -436.967419) (xy 271.100846 -436.98331)
			(xy 270.923755 -436.991263) (xy 270.746485 -436.991263) (xy 270.569394 -436.98331) (xy 270.392838 -436.967419)
			(xy 270.217173 -436.943624) (xy 270.042752 -436.911971) (xy 269.869927 -436.872525) (xy 269.699046 -436.825365)
			(xy 269.530452 -436.770586) (xy 269.364487 -436.708298) (xy 269.201482 -436.638626) (xy 269.041768 -436.561712)
			(xy 268.885665 -436.477709) (xy 268.733488 -436.386788) (xy 268.585544 -436.289131) (xy 268.44213 -436.184934)
			(xy 268.303535 -436.074408) (xy 268.170038 -435.957776) (xy 268.041909 -435.835271) (xy 267.919404 -435.707142)
			(xy 267.802772 -435.573645) (xy 267.692246 -435.43505) (xy 267.588049 -435.291636) (xy 267.490392 -435.143692)
			(xy 267.399471 -434.991515) (xy 267.315468 -434.835412) (xy 267.238554 -434.675698) (xy 267.168882 -434.512693)
			(xy 267.106594 -434.346728) (xy 267.051815 -434.178134) (xy 267.004655 -434.007253) (xy 266.965209 -433.834428)
			(xy 266.933556 -433.660007) (xy 266.909761 -433.484342) (xy 266.89387 -433.307786) (xy 266.885917 -433.130695)
			(xy 230.3145 -433.130695) (xy 230.3145 -435.873652) (xy 230.314033 -435.898602) (xy 230.306213 -435.947887)
			(xy 230.29079 -435.995345) (xy 230.268141 -436.03981) (xy 230.238824 -436.080191) (xy 230.221536 -436.098188)
			(xy 229.299008 -437.020716) (xy 229.281016 -437.03801) (xy 229.240639 -437.067332) (xy 229.196172 -437.089979)
			(xy 229.148711 -437.105393) (xy 229.099423 -437.113193) (xy 229.074472 -437.11368) (xy 207.302608 -437.11368)
			(xy 207.27766 -437.113152) (xy 207.22838 -437.105344) (xy 207.180923 -437.089933) (xy 207.136457 -437.067299)
			(xy 207.096072 -437.037997) (xy 207.078072 -437.020716) (xy 205.512924 -435.455568) (xy 205.495618 -435.437587)
			(xy 205.466295 -435.397208) (xy 205.44365 -435.352738) (xy 205.42824 -435.305274) (xy 205.420444 -435.255984)
			(xy 205.41996 -435.231032) (xy 205.41996 -431.16881) (xy 205.41954 -431.15874) (xy 205.411817 -431.140141)
			(xy 205.404974 -431.132742) (xy 196.207888 -421.935656) (xy 196.19057 -421.917686) (xy 196.16125 -421.877303)
			(xy 196.138608 -421.832831) (xy 196.1232 -421.785364) (xy 196.115407 -421.736072) (xy 196.114924 -421.71112)
			(xy 196.114924 -413.329374) (xy 196.114532 -413.319301) (xy 196.10679 -413.300702) (xy 196.099938 -413.293306)
			(xy 195.154296 -412.347664) (xy 195.146896 -412.340825) (xy 195.128296 -412.333106) (xy 195.118228 -412.332678)
			(xy 188.720222 -412.332678) (xy 188.695275 -412.332142) (xy 188.645994 -412.324336) (xy 188.598538 -412.308927)
			(xy 188.554072 -412.286295) (xy 188.513686 -412.256994) (xy 188.495686 -412.239714) (xy 187.848748 -411.592776)
			(xy 187.841328 -411.585961) (xy 187.822744 -411.578227) (xy 187.81268 -411.57779) (xy 184.8104 -411.57779)
			(xy 184.785451 -411.577293) (xy 184.736167 -411.569481) (xy 184.68871 -411.554065) (xy 184.644244 -411.531423)
			(xy 184.603862 -411.502111) (xy 184.585864 -411.484826) (xy 184.033922 -410.932884) (xy 184.016624 -410.914896)
			(xy 183.9873 -410.874519) (xy 183.964653 -410.830051) (xy 183.949241 -410.782588) (xy 183.941443 -410.733299)
			(xy 183.940958 -410.708348) (xy 7.00913 -410.708348) (xy 7.00913 -413.4485) (xy 38.974268 -413.4485)
			(xy 38.974268 -412.5849) (xy 38.974754 -412.557631) (xy 38.982516 -412.503647) (xy 38.997881 -412.451317)
			(xy 39.020538 -412.401707) (xy 39.050024 -412.355826) (xy 39.085739 -412.314609) (xy 39.126956 -412.278894)
			(xy 39.172837 -412.249408) (xy 39.222447 -412.226751) (xy 39.274777 -412.211386) (xy 39.328761 -412.203624)
			(xy 39.383299 -412.203624) (xy 39.437283 -412.211386) (xy 39.489613 -412.226751) (xy 39.539223 -412.249408)
			(xy 39.585104 -412.278894) (xy 39.626321 -412.314609) (xy 39.662036 -412.355826) (xy 39.691522 -412.401707)
			(xy 39.714179 -412.451317) (xy 39.729544 -412.503647) (xy 39.737306 -412.557631) (xy 39.737792 -412.5849)
			(xy 39.737792 -412.597452) (xy 47.413146 -412.597452) (xy 47.413146 -412.542948) (xy 47.420902 -412.488999)
			(xy 47.436257 -412.436703) (xy 47.458897 -412.387124) (xy 47.488362 -412.341271) (xy 47.524053 -412.300079)
			(xy 47.565242 -412.264384) (xy 47.611092 -412.234914) (xy 47.660669 -412.212269) (xy 47.712964 -412.19691)
			(xy 47.766912 -412.189148) (xy 47.794164 -412.18866) (xy 48.657764 -412.18866) (xy 48.685016 -412.189185)
			(xy 48.738967 -412.196937) (xy 48.791264 -412.212289) (xy 48.840845 -412.234927) (xy 48.886699 -412.264392)
			(xy 48.927892 -412.300082) (xy 48.963587 -412.341273) (xy 48.993056 -412.387124) (xy 49.015699 -412.436702)
			(xy 49.031055 -412.488998) (xy 49.038813 -412.542948) (xy 49.038813 -412.597452) (xy 49.038813 -412.597455)
			(xy 50.476323 -412.597455) (xy 50.476323 -412.542945) (xy 50.484081 -412.488989) (xy 50.499438 -412.436686)
			(xy 50.522083 -412.387102) (xy 50.551554 -412.341244) (xy 50.587251 -412.300048) (xy 50.628448 -412.264351)
			(xy 50.674305 -412.234881) (xy 50.72389 -412.212237) (xy 50.776193 -412.19688) (xy 50.830149 -412.189123)
			(xy 50.857404 -412.18866) (xy 51.721004 -412.18866) (xy 51.748253 -412.18921) (xy 51.802195 -412.196967)
			(xy 51.854485 -412.212321) (xy 51.904058 -412.23496) (xy 51.949904 -412.264424) (xy 51.99109 -412.300113)
			(xy 52.026778 -412.341299) (xy 52.056242 -412.387146) (xy 52.07888 -412.436718) (xy 52.094234 -412.489008)
			(xy 52.10199 -412.542951) (xy 52.10199 -412.597449) (xy 52.101989 -412.597457) (xy 53.539523 -412.597457)
			(xy 53.539523 -412.542943) (xy 53.547282 -412.488983) (xy 53.562641 -412.436678) (xy 53.585289 -412.38709)
			(xy 53.614764 -412.341231) (xy 53.650465 -412.300034) (xy 53.691667 -412.264337) (xy 53.737529 -412.234868)
			(xy 53.787119 -412.212226) (xy 53.839427 -412.196872) (xy 53.893387 -412.18912) (xy 53.920644 -412.18866)
			(xy 54.784244 -412.18866) (xy 54.811491 -412.189213) (xy 54.865429 -412.196974) (xy 54.917714 -412.212332)
			(xy 54.967282 -412.234973) (xy 55.013123 -412.264438) (xy 55.054304 -412.300127) (xy 55.089988 -412.341313)
			(xy 55.119448 -412.387157) (xy 55.142084 -412.436727) (xy 55.157435 -412.489014) (xy 55.16519 -412.542953)
			(xy 55.16519 -412.597447) (xy 55.165189 -412.597453) (xy 56.602846 -412.597453) (xy 56.602846 -412.542947)
			(xy 56.610603 -412.488996) (xy 56.625958 -412.436698) (xy 56.6486 -412.387118) (xy 56.678067 -412.341265)
			(xy 56.71376 -412.300071) (xy 56.754952 -412.264377) (xy 56.800804 -412.234908) (xy 56.850383 -412.212264)
			(xy 56.902681 -412.196906) (xy 56.956631 -412.189147) (xy 56.983884 -412.18866) (xy 57.847484 -412.18866)
			(xy 57.874735 -412.189186) (xy 57.928683 -412.196941) (xy 57.980979 -412.212294) (xy 58.030557 -412.234934)
			(xy 58.076408 -412.264399) (xy 58.117599 -412.300089) (xy 58.153292 -412.341279) (xy 58.182759 -412.387129)
			(xy 58.2054 -412.436706) (xy 58.220756 -412.489001) (xy 58.228513 -412.542949) (xy 58.228513 -412.597451)
			(xy 58.228512 -412.597456) (xy 59.666023 -412.597456) (xy 59.666023 -412.542944) (xy 59.673781 -412.488986)
			(xy 59.68914 -412.436682) (xy 59.711786 -412.387096) (xy 59.741259 -412.341238) (xy 59.776958 -412.300041)
			(xy 59.818157 -412.264344) (xy 59.864017 -412.234874) (xy 59.913604 -412.212231) (xy 59.96591 -412.196876)
			(xy 60.019868 -412.189121) (xy 60.047124 -412.18866) (xy 60.910724 -412.18866) (xy 60.937972 -412.189212)
			(xy 60.991912 -412.19697) (xy 61.0442 -412.212326) (xy 61.09377 -412.234967) (xy 61.139613 -412.264431)
			(xy 61.180797 -412.30012) (xy 61.216483 -412.341306) (xy 61.245945 -412.387151) (xy 61.268582 -412.436723)
			(xy 61.283935 -412.489011) (xy 61.29169 -412.542952) (xy 61.29169 -412.597448) (xy 61.291689 -412.597452)
			(xy 62.729346 -412.597452) (xy 62.729346 -412.542948) (xy 62.737102 -412.488999) (xy 62.752457 -412.436703)
			(xy 62.775097 -412.387124) (xy 62.804562 -412.341271) (xy 62.840253 -412.300079) (xy 62.881442 -412.264384)
			(xy 62.927292 -412.234914) (xy 62.976869 -412.212269) (xy 63.029164 -412.19691) (xy 63.083112 -412.189148)
			(xy 63.110364 -412.18866) (xy 63.973964 -412.18866) (xy 64.001216 -412.189185) (xy 64.055167 -412.196937)
			(xy 64.107464 -412.212289) (xy 64.157045 -412.234927) (xy 64.202899 -412.264392) (xy 64.244092 -412.300082)
			(xy 64.279787 -412.341273) (xy 64.309256 -412.387124) (xy 64.331899 -412.436702) (xy 64.347255 -412.488998)
			(xy 64.355013 -412.542948) (xy 64.355013 -412.597452) (xy 64.355013 -412.597455) (xy 65.792523 -412.597455)
			(xy 65.792523 -412.542945) (xy 65.800281 -412.488989) (xy 65.815638 -412.436686) (xy 65.838283 -412.387102)
			(xy 65.867754 -412.341244) (xy 65.903451 -412.300048) (xy 65.944648 -412.264351) (xy 65.990505 -412.234881)
			(xy 66.04009 -412.212237) (xy 66.092393 -412.19688) (xy 66.146349 -412.189123) (xy 66.173604 -412.18866)
			(xy 67.037204 -412.18866) (xy 67.064453 -412.18921) (xy 67.118395 -412.196967) (xy 67.170685 -412.212321)
			(xy 67.220258 -412.23496) (xy 67.266104 -412.264424) (xy 67.30729 -412.300113) (xy 67.342978 -412.341299)
			(xy 67.372442 -412.387146) (xy 67.39508 -412.436718) (xy 67.410434 -412.489008) (xy 67.41819 -412.542951)
			(xy 67.41819 -412.597449) (xy 67.418189 -412.597457) (xy 68.855723 -412.597457) (xy 68.855723 -412.542943)
			(xy 68.863482 -412.488983) (xy 68.878841 -412.436678) (xy 68.901489 -412.38709) (xy 68.930964 -412.341231)
			(xy 68.966665 -412.300034) (xy 69.007867 -412.264337) (xy 69.053729 -412.234868) (xy 69.103319 -412.212226)
			(xy 69.155627 -412.196872) (xy 69.209587 -412.18912) (xy 69.236844 -412.18866) (xy 70.100444 -412.18866)
			(xy 70.127691 -412.189213) (xy 70.181629 -412.196974) (xy 70.233914 -412.212332) (xy 70.283482 -412.234973)
			(xy 70.329323 -412.264438) (xy 70.370504 -412.300127) (xy 70.406188 -412.341313) (xy 70.435648 -412.387157)
			(xy 70.458284 -412.436727) (xy 70.473635 -412.489014) (xy 70.48139 -412.542953) (xy 70.48139 -412.597447)
			(xy 70.481389 -412.597453) (xy 71.919046 -412.597453) (xy 71.919046 -412.542947) (xy 71.926803 -412.488996)
			(xy 71.942158 -412.436698) (xy 71.9648 -412.387118) (xy 71.994267 -412.341265) (xy 72.02996 -412.300071)
			(xy 72.071152 -412.264377) (xy 72.117004 -412.234908) (xy 72.166583 -412.212264) (xy 72.218881 -412.196906)
			(xy 72.272831 -412.189147) (xy 72.300084 -412.18866) (xy 73.163684 -412.18866) (xy 73.190935 -412.189186)
			(xy 73.244883 -412.196941) (xy 73.297179 -412.212294) (xy 73.346757 -412.234934) (xy 73.392608 -412.264399)
			(xy 73.433799 -412.300089) (xy 73.469492 -412.341279) (xy 73.498959 -412.387129) (xy 73.5216 -412.436706)
			(xy 73.536956 -412.489001) (xy 73.544713 -412.542949) (xy 73.544713 -412.597451) (xy 73.544712 -412.597456)
			(xy 74.982223 -412.597456) (xy 74.982223 -412.542944) (xy 74.989981 -412.488986) (xy 75.00534 -412.436682)
			(xy 75.027986 -412.387096) (xy 75.057459 -412.341238) (xy 75.093158 -412.300041) (xy 75.134357 -412.264344)
			(xy 75.180217 -412.234874) (xy 75.229804 -412.212231) (xy 75.28211 -412.196876) (xy 75.336068 -412.189121)
			(xy 75.363324 -412.18866) (xy 76.226924 -412.18866) (xy 76.254172 -412.189212) (xy 76.308112 -412.19697)
			(xy 76.3604 -412.212326) (xy 76.40997 -412.234967) (xy 76.455813 -412.264431) (xy 76.496997 -412.30012)
			(xy 76.532683 -412.341306) (xy 76.562145 -412.387151) (xy 76.584782 -412.436723) (xy 76.600135 -412.489011)
			(xy 76.60789 -412.542952) (xy 76.60789 -412.597448) (xy 76.607889 -412.597452) (xy 78.045546 -412.597452)
			(xy 78.045546 -412.542948) (xy 78.053302 -412.488999) (xy 78.068657 -412.436703) (xy 78.091297 -412.387124)
			(xy 78.120762 -412.341271) (xy 78.156453 -412.300079) (xy 78.197642 -412.264384) (xy 78.243492 -412.234914)
			(xy 78.293069 -412.212269) (xy 78.345364 -412.19691) (xy 78.399312 -412.189148) (xy 78.426564 -412.18866)
			(xy 79.290164 -412.18866) (xy 79.317416 -412.189185) (xy 79.371367 -412.196937) (xy 79.423664 -412.212289)
			(xy 79.473245 -412.234927) (xy 79.519099 -412.264392) (xy 79.560292 -412.300082) (xy 79.595987 -412.341273)
			(xy 79.625456 -412.387124) (xy 79.648099 -412.436702) (xy 79.663455 -412.488998) (xy 79.671213 -412.542948)
			(xy 79.671213 -412.597452) (xy 79.671213 -412.597455) (xy 81.108723 -412.597455) (xy 81.108723 -412.542945)
			(xy 81.116481 -412.488989) (xy 81.131838 -412.436686) (xy 81.154483 -412.387102) (xy 81.183954 -412.341244)
			(xy 81.219651 -412.300048) (xy 81.260848 -412.264351) (xy 81.306705 -412.234881) (xy 81.35629 -412.212237)
			(xy 81.408593 -412.19688) (xy 81.462549 -412.189123) (xy 81.489804 -412.18866) (xy 82.353404 -412.18866)
			(xy 82.380653 -412.18921) (xy 82.434595 -412.196967) (xy 82.486885 -412.212321) (xy 82.536458 -412.23496)
			(xy 82.582304 -412.264424) (xy 82.62349 -412.300113) (xy 82.659178 -412.341299) (xy 82.688642 -412.387146)
			(xy 82.71128 -412.436718) (xy 82.726634 -412.489008) (xy 82.73439 -412.542951) (xy 82.73439 -412.597449)
			(xy 82.734389 -412.597457) (xy 84.171923 -412.597457) (xy 84.171923 -412.542943) (xy 84.179682 -412.488983)
			(xy 84.195041 -412.436678) (xy 84.217689 -412.38709) (xy 84.247164 -412.341231) (xy 84.282865 -412.300034)
			(xy 84.324067 -412.264337) (xy 84.369929 -412.234868) (xy 84.419519 -412.212226) (xy 84.471827 -412.196872)
			(xy 84.525787 -412.18912) (xy 84.553044 -412.18866) (xy 85.416644 -412.18866) (xy 85.443891 -412.189213)
			(xy 85.497829 -412.196974) (xy 85.550114 -412.212332) (xy 85.599682 -412.234973) (xy 85.645523 -412.264438)
			(xy 85.686704 -412.300127) (xy 85.722388 -412.341313) (xy 85.751848 -412.387157) (xy 85.774484 -412.436727)
			(xy 85.789835 -412.489014) (xy 85.79759 -412.542953) (xy 85.79759 -412.597447) (xy 85.797589 -412.597453)
			(xy 87.235246 -412.597453) (xy 87.235246 -412.542947) (xy 87.243003 -412.488996) (xy 87.258358 -412.436698)
			(xy 87.281 -412.387118) (xy 87.310467 -412.341265) (xy 87.34616 -412.300071) (xy 87.387352 -412.264377)
			(xy 87.433204 -412.234908) (xy 87.482783 -412.212264) (xy 87.535081 -412.196906) (xy 87.589031 -412.189147)
			(xy 87.616284 -412.18866) (xy 88.479884 -412.18866) (xy 88.507135 -412.189186) (xy 88.561083 -412.196941)
			(xy 88.613379 -412.212294) (xy 88.662957 -412.234934) (xy 88.708808 -412.264399) (xy 88.749999 -412.300089)
			(xy 88.785692 -412.341279) (xy 88.815159 -412.387129) (xy 88.8378 -412.436706) (xy 88.853156 -412.489001)
			(xy 88.860913 -412.542949) (xy 88.860913 -412.597451) (xy 88.860912 -412.597456) (xy 90.298423 -412.597456)
			(xy 90.298423 -412.542944) (xy 90.306181 -412.488986) (xy 90.32154 -412.436682) (xy 90.344186 -412.387096)
			(xy 90.373659 -412.341238) (xy 90.409358 -412.300041) (xy 90.450557 -412.264344) (xy 90.496417 -412.234874)
			(xy 90.546004 -412.212231) (xy 90.59831 -412.196876) (xy 90.652268 -412.189121) (xy 90.679524 -412.18866)
			(xy 91.543124 -412.18866) (xy 91.570372 -412.189212) (xy 91.624312 -412.19697) (xy 91.6766 -412.212326)
			(xy 91.72617 -412.234967) (xy 91.772013 -412.264431) (xy 91.813197 -412.30012) (xy 91.848883 -412.341306)
			(xy 91.878345 -412.387151) (xy 91.900982 -412.436723) (xy 91.916335 -412.489011) (xy 91.92409 -412.542952)
			(xy 91.92409 -412.597448) (xy 91.924089 -412.597452) (xy 93.361746 -412.597452) (xy 93.361746 -412.542948)
			(xy 93.369502 -412.488999) (xy 93.384857 -412.436703) (xy 93.407497 -412.387124) (xy 93.436962 -412.341271)
			(xy 93.472653 -412.300079) (xy 93.513842 -412.264384) (xy 93.559692 -412.234914) (xy 93.609269 -412.212269)
			(xy 93.661564 -412.19691) (xy 93.715512 -412.189148) (xy 93.742764 -412.18866) (xy 94.606364 -412.18866)
			(xy 94.633616 -412.189185) (xy 94.687567 -412.196937) (xy 94.739864 -412.212289) (xy 94.789445 -412.234927)
			(xy 94.835299 -412.264392) (xy 94.876492 -412.300082) (xy 94.912187 -412.341273) (xy 94.941656 -412.387124)
			(xy 94.964299 -412.436702) (xy 94.979655 -412.488998) (xy 94.987413 -412.542948) (xy 94.987413 -412.597452)
			(xy 94.987413 -412.597455) (xy 114.513023 -412.597455) (xy 114.513023 -412.542945) (xy 114.520781 -412.488989)
			(xy 114.536138 -412.436686) (xy 114.558783 -412.387101) (xy 114.588254 -412.341244) (xy 114.623952 -412.300047)
			(xy 114.665149 -412.264351) (xy 114.711006 -412.23488) (xy 114.760591 -412.212236) (xy 114.812894 -412.196879)
			(xy 114.866851 -412.189123) (xy 114.894106 -412.18866) (xy 115.757706 -412.18866) (xy 115.784955 -412.189211)
			(xy 115.838897 -412.196967) (xy 115.891187 -412.212321) (xy 115.940759 -412.234961) (xy 115.986605 -412.264425)
			(xy 116.027791 -412.300113) (xy 116.063479 -412.3413) (xy 116.092942 -412.387146) (xy 116.115581 -412.436719)
			(xy 116.130934 -412.489009) (xy 116.13869 -412.542951) (xy 116.13869 -412.597449) (xy 116.138689 -412.597457)
			(xy 117.576223 -412.597457) (xy 117.576223 -412.542943) (xy 117.583982 -412.488983) (xy 117.599342 -412.436677)
			(xy 117.621989 -412.38709) (xy 117.651464 -412.341231) (xy 117.687166 -412.300033) (xy 117.728367 -412.264337)
			(xy 117.77423 -412.234867) (xy 117.82382 -412.212225) (xy 117.876128 -412.196872) (xy 117.930089 -412.18912)
			(xy 117.957346 -412.18866) (xy 118.820946 -412.18866) (xy 118.848193 -412.189213) (xy 118.902131 -412.196975)
			(xy 118.954416 -412.212332) (xy 119.003983 -412.234974) (xy 119.049824 -412.264439) (xy 119.091005 -412.300128)
			(xy 119.126688 -412.341313) (xy 119.156148 -412.387157) (xy 119.178784 -412.436727) (xy 119.194135 -412.489014)
			(xy 119.20189 -412.542953) (xy 119.20189 -412.597447) (xy 119.201889 -412.597453) (xy 120.639546 -412.597453)
			(xy 120.639546 -412.542947) (xy 120.647303 -412.488996) (xy 120.662658 -412.436698) (xy 120.6853 -412.387118)
			(xy 120.714768 -412.341264) (xy 120.750461 -412.300071) (xy 120.791653 -412.264376) (xy 120.837505 -412.234907)
			(xy 120.887085 -412.212263) (xy 120.939382 -412.196906) (xy 120.993333 -412.189147) (xy 121.020586 -412.18866)
			(xy 121.884186 -412.18866) (xy 121.911437 -412.189186) (xy 121.965385 -412.196941) (xy 122.01768 -412.212295)
			(xy 122.067258 -412.234934) (xy 122.113109 -412.264399) (xy 122.1543 -412.30009) (xy 122.189992 -412.34128)
			(xy 122.219459 -412.38713) (xy 122.242101 -412.436707) (xy 122.257456 -412.489001) (xy 122.265213 -412.542949)
			(xy 122.265213 -412.597451) (xy 122.265212 -412.597456) (xy 123.702723 -412.597456) (xy 123.702723 -412.542944)
			(xy 123.710481 -412.488986) (xy 123.72584 -412.436681) (xy 123.748486 -412.387095) (xy 123.777959 -412.341237)
			(xy 123.813659 -412.30004) (xy 123.854858 -412.264344) (xy 123.900718 -412.234874) (xy 123.950306 -412.212231)
			(xy 124.002611 -412.196876) (xy 124.05657 -412.189121) (xy 124.083826 -412.18866) (xy 124.947426 -412.18866)
			(xy 124.974674 -412.189212) (xy 125.028614 -412.196971) (xy 125.080901 -412.212327) (xy 125.130471 -412.234968)
			(xy 125.176314 -412.264432) (xy 125.217498 -412.300121) (xy 125.253184 -412.341307) (xy 125.282645 -412.387152)
			(xy 125.305282 -412.436723) (xy 125.320635 -412.489011) (xy 125.32839 -412.542952) (xy 125.32839 -412.597448)
			(xy 125.328389 -412.597452) (xy 126.766046 -412.597452) (xy 126.766046 -412.542948) (xy 126.773802 -412.488999)
			(xy 126.789157 -412.436702) (xy 126.811797 -412.387123) (xy 126.841263 -412.341271) (xy 126.876954 -412.300078)
			(xy 126.918143 -412.264383) (xy 126.963993 -412.234914) (xy 127.01357 -412.212269) (xy 127.065865 -412.196909)
			(xy 127.119814 -412.189148) (xy 127.147066 -412.18866) (xy 128.010666 -412.18866) (xy 128.037918 -412.189185)
			(xy 128.091868 -412.196937) (xy 128.144166 -412.212289) (xy 128.193746 -412.234928) (xy 128.2396 -412.264392)
			(xy 128.280793 -412.300083) (xy 128.316487 -412.341273) (xy 128.345956 -412.387124) (xy 128.368599 -412.436702)
			(xy 128.383955 -412.488999) (xy 128.391713 -412.542948) (xy 128.391713 -412.597452) (xy 128.391713 -412.597455)
			(xy 129.829223 -412.597455) (xy 129.829223 -412.542945) (xy 129.836981 -412.488989) (xy 129.852338 -412.436686)
			(xy 129.874983 -412.387101) (xy 129.904454 -412.341244) (xy 129.940152 -412.300047) (xy 129.981349 -412.264351)
			(xy 130.027206 -412.23488) (xy 130.076791 -412.212236) (xy 130.129094 -412.196879) (xy 130.183051 -412.189123)
			(xy 130.210306 -412.18866) (xy 131.073906 -412.18866) (xy 131.101155 -412.189211) (xy 131.155097 -412.196967)
			(xy 131.207387 -412.212321) (xy 131.256959 -412.234961) (xy 131.302805 -412.264425) (xy 131.343991 -412.300113)
			(xy 131.379679 -412.3413) (xy 131.409142 -412.387146) (xy 131.431781 -412.436719) (xy 131.447134 -412.489009)
			(xy 131.45489 -412.542951) (xy 131.45489 -412.597449) (xy 131.454889 -412.597457) (xy 132.892423 -412.597457)
			(xy 132.892423 -412.542943) (xy 132.900182 -412.488983) (xy 132.915542 -412.436677) (xy 132.938189 -412.38709)
			(xy 132.967664 -412.341231) (xy 133.003366 -412.300033) (xy 133.044567 -412.264337) (xy 133.09043 -412.234867)
			(xy 133.14002 -412.212225) (xy 133.192328 -412.196872) (xy 133.246289 -412.18912) (xy 133.273546 -412.18866)
			(xy 134.137146 -412.18866) (xy 134.164393 -412.189213) (xy 134.218331 -412.196975) (xy 134.270616 -412.212332)
			(xy 134.320183 -412.234974) (xy 134.366024 -412.264439) (xy 134.407205 -412.300128) (xy 134.442888 -412.341313)
			(xy 134.472348 -412.387157) (xy 134.494984 -412.436727) (xy 134.510335 -412.489014) (xy 134.51809 -412.542953)
			(xy 134.51809 -412.597447) (xy 134.518089 -412.597453) (xy 135.955746 -412.597453) (xy 135.955746 -412.542947)
			(xy 135.963503 -412.488996) (xy 135.978858 -412.436698) (xy 136.0015 -412.387118) (xy 136.030968 -412.341264)
			(xy 136.066661 -412.300071) (xy 136.107853 -412.264376) (xy 136.153705 -412.234907) (xy 136.203285 -412.212263)
			(xy 136.255582 -412.196906) (xy 136.309533 -412.189147) (xy 136.336786 -412.18866) (xy 137.200386 -412.18866)
			(xy 137.227637 -412.189186) (xy 137.281585 -412.196941) (xy 137.33388 -412.212295) (xy 137.383458 -412.234934)
			(xy 137.429309 -412.264399) (xy 137.4705 -412.30009) (xy 137.506192 -412.34128) (xy 137.535659 -412.38713)
			(xy 137.558301 -412.436707) (xy 137.573656 -412.489001) (xy 137.581413 -412.542949) (xy 137.581413 -412.597451)
			(xy 137.581412 -412.597456) (xy 139.018923 -412.597456) (xy 139.018923 -412.542944) (xy 139.026681 -412.488986)
			(xy 139.04204 -412.436681) (xy 139.064686 -412.387095) (xy 139.094159 -412.341237) (xy 139.129859 -412.30004)
			(xy 139.171058 -412.264344) (xy 139.216918 -412.234874) (xy 139.266506 -412.212231) (xy 139.318811 -412.196876)
			(xy 139.37277 -412.189121) (xy 139.400026 -412.18866) (xy 140.263626 -412.18866) (xy 140.290874 -412.189212)
			(xy 140.344814 -412.196971) (xy 140.397101 -412.212327) (xy 140.446671 -412.234968) (xy 140.492514 -412.264432)
			(xy 140.533698 -412.300121) (xy 140.569384 -412.341307) (xy 140.598845 -412.387152) (xy 140.621482 -412.436723)
			(xy 140.636835 -412.489011) (xy 140.64459 -412.542952) (xy 140.64459 -412.597448) (xy 140.644589 -412.597452)
			(xy 142.082246 -412.597452) (xy 142.082246 -412.542948) (xy 142.090002 -412.488999) (xy 142.105357 -412.436702)
			(xy 142.127997 -412.387123) (xy 142.157463 -412.341271) (xy 142.193154 -412.300078) (xy 142.234343 -412.264383)
			(xy 142.280193 -412.234914) (xy 142.32977 -412.212269) (xy 142.382065 -412.196909) (xy 142.436014 -412.189148)
			(xy 142.463266 -412.18866) (xy 143.326866 -412.18866) (xy 143.354118 -412.189185) (xy 143.408068 -412.196937)
			(xy 143.460366 -412.212289) (xy 143.509946 -412.234928) (xy 143.5558 -412.264392) (xy 143.596993 -412.300083)
			(xy 143.632687 -412.341273) (xy 143.662156 -412.387124) (xy 143.684799 -412.436702) (xy 143.700155 -412.488999)
			(xy 143.707913 -412.542948) (xy 143.707913 -412.597452) (xy 143.707913 -412.597455) (xy 145.145423 -412.597455)
			(xy 145.145423 -412.542945) (xy 145.153181 -412.488989) (xy 145.168538 -412.436686) (xy 145.191183 -412.387101)
			(xy 145.220654 -412.341244) (xy 145.256352 -412.300047) (xy 145.297549 -412.264351) (xy 145.343406 -412.23488)
			(xy 145.392991 -412.212236) (xy 145.445294 -412.196879) (xy 145.499251 -412.189123) (xy 145.526506 -412.18866)
			(xy 146.390106 -412.18866) (xy 146.417355 -412.189211) (xy 146.471297 -412.196967) (xy 146.523587 -412.212321)
			(xy 146.573159 -412.234961) (xy 146.619005 -412.264425) (xy 146.660191 -412.300113) (xy 146.695879 -412.3413)
			(xy 146.725342 -412.387146) (xy 146.747981 -412.436719) (xy 146.763334 -412.489009) (xy 146.77109 -412.542951)
			(xy 146.77109 -412.597449) (xy 146.771089 -412.597457) (xy 148.208623 -412.597457) (xy 148.208623 -412.542943)
			(xy 148.216382 -412.488983) (xy 148.231742 -412.436677) (xy 148.254389 -412.38709) (xy 148.283864 -412.341231)
			(xy 148.319566 -412.300033) (xy 148.360767 -412.264337) (xy 148.40663 -412.234867) (xy 148.45622 -412.212225)
			(xy 148.508528 -412.196872) (xy 148.562489 -412.18912) (xy 148.589746 -412.18866) (xy 149.453346 -412.18866)
			(xy 149.480593 -412.189213) (xy 149.534531 -412.196975) (xy 149.586816 -412.212332) (xy 149.636383 -412.234974)
			(xy 149.682224 -412.264439) (xy 149.723405 -412.300128) (xy 149.759088 -412.341313) (xy 149.788548 -412.387157)
			(xy 149.811184 -412.436727) (xy 149.826535 -412.489014) (xy 149.83429 -412.542953) (xy 149.83429 -412.597447)
			(xy 149.834289 -412.597453) (xy 151.271946 -412.597453) (xy 151.271946 -412.542947) (xy 151.279703 -412.488996)
			(xy 151.295058 -412.436698) (xy 151.3177 -412.387118) (xy 151.347168 -412.341264) (xy 151.382861 -412.300071)
			(xy 151.424053 -412.264376) (xy 151.469905 -412.234907) (xy 151.519485 -412.212263) (xy 151.571782 -412.196906)
			(xy 151.625733 -412.189147) (xy 151.652986 -412.18866) (xy 152.516586 -412.18866) (xy 152.543837 -412.189186)
			(xy 152.597785 -412.196941) (xy 152.65008 -412.212295) (xy 152.699658 -412.234934) (xy 152.745509 -412.264399)
			(xy 152.7867 -412.30009) (xy 152.822392 -412.34128) (xy 152.851859 -412.38713) (xy 152.874501 -412.436707)
			(xy 152.889856 -412.489001) (xy 152.897613 -412.542949) (xy 152.897613 -412.597451) (xy 152.897612 -412.597456)
			(xy 154.335123 -412.597456) (xy 154.335123 -412.542944) (xy 154.342881 -412.488986) (xy 154.35824 -412.436681)
			(xy 154.380886 -412.387095) (xy 154.410359 -412.341237) (xy 154.446059 -412.30004) (xy 154.487258 -412.264344)
			(xy 154.533118 -412.234874) (xy 154.582706 -412.212231) (xy 154.635011 -412.196876) (xy 154.68897 -412.189121)
			(xy 154.716226 -412.18866) (xy 155.579826 -412.18866) (xy 155.607074 -412.189212) (xy 155.661014 -412.196971)
			(xy 155.713301 -412.212327) (xy 155.762871 -412.234968) (xy 155.808714 -412.264432) (xy 155.849898 -412.300121)
			(xy 155.885584 -412.341307) (xy 155.915045 -412.387152) (xy 155.937682 -412.436723) (xy 155.953035 -412.489011)
			(xy 155.96079 -412.542952) (xy 155.96079 -412.597448) (xy 155.960789 -412.597452) (xy 157.398446 -412.597452)
			(xy 157.398446 -412.542948) (xy 157.406202 -412.488999) (xy 157.421557 -412.436702) (xy 157.444197 -412.387123)
			(xy 157.473663 -412.341271) (xy 157.509354 -412.300078) (xy 157.550543 -412.264383) (xy 157.596393 -412.234914)
			(xy 157.64597 -412.212269) (xy 157.698265 -412.196909) (xy 157.752214 -412.189148) (xy 157.779466 -412.18866)
			(xy 158.643066 -412.18866) (xy 158.670318 -412.189185) (xy 158.724268 -412.196937) (xy 158.776566 -412.212289)
			(xy 158.826146 -412.234928) (xy 158.872 -412.264392) (xy 158.913193 -412.300083) (xy 158.948887 -412.341273)
			(xy 158.978356 -412.387124) (xy 159.000999 -412.436702) (xy 159.016355 -412.488999) (xy 159.024113 -412.542948)
			(xy 159.024113 -412.597452) (xy 159.024113 -412.597455) (xy 160.461623 -412.597455) (xy 160.461623 -412.542945)
			(xy 160.469381 -412.488989) (xy 160.484738 -412.436686) (xy 160.507383 -412.387101) (xy 160.536854 -412.341244)
			(xy 160.572552 -412.300047) (xy 160.613749 -412.264351) (xy 160.659606 -412.23488) (xy 160.709191 -412.212236)
			(xy 160.761494 -412.196879) (xy 160.815451 -412.189123) (xy 160.842706 -412.18866) (xy 161.706306 -412.18866)
			(xy 161.733555 -412.189211) (xy 161.787497 -412.196967) (xy 161.839787 -412.212321) (xy 161.889359 -412.234961)
			(xy 161.935205 -412.264425) (xy 161.976391 -412.300113) (xy 162.012079 -412.3413) (xy 162.041542 -412.387146)
			(xy 162.064181 -412.436719) (xy 162.079534 -412.489009) (xy 162.08729 -412.542951) (xy 162.08729 -412.597449)
			(xy 162.079534 -412.651391) (xy 162.064181 -412.703681) (xy 162.041542 -412.753254) (xy 162.012079 -412.7991)
			(xy 161.976391 -412.840287) (xy 161.935205 -412.875975) (xy 161.889359 -412.905439) (xy 161.839787 -412.928079)
			(xy 161.787497 -412.943433) (xy 161.733555 -412.951189) (xy 161.706306 -412.951676) (xy 160.842706 -412.951676)
			(xy 160.815451 -412.951277) (xy 160.761494 -412.943521) (xy 160.709191 -412.928164) (xy 160.659606 -412.90552)
			(xy 160.613749 -412.876049) (xy 160.572552 -412.840353) (xy 160.536854 -412.799156) (xy 160.507383 -412.753299)
			(xy 160.484738 -412.703714) (xy 160.469381 -412.651411) (xy 160.461623 -412.597455) (xy 159.024113 -412.597455)
			(xy 159.016355 -412.651402) (xy 159.000999 -412.703698) (xy 158.978356 -412.753276) (xy 158.948887 -412.799127)
			(xy 158.913193 -412.840317) (xy 158.872 -412.876008) (xy 158.826146 -412.905472) (xy 158.776566 -412.928111)
			(xy 158.724268 -412.943463) (xy 158.670318 -412.951215) (xy 158.643066 -412.951676) (xy 157.779466 -412.951676)
			(xy 157.752214 -412.951252) (xy 157.698265 -412.943491) (xy 157.64597 -412.928131) (xy 157.596393 -412.905486)
			(xy 157.550543 -412.876017) (xy 157.509354 -412.840322) (xy 157.473663 -412.799129) (xy 157.444197 -412.753277)
			(xy 157.421557 -412.703698) (xy 157.406202 -412.651401) (xy 157.398446 -412.597452) (xy 155.960789 -412.597452)
			(xy 155.953035 -412.651389) (xy 155.937682 -412.703677) (xy 155.915045 -412.753248) (xy 155.885584 -412.799093)
			(xy 155.849898 -412.840279) (xy 155.808714 -412.875968) (xy 155.762871 -412.905432) (xy 155.713301 -412.928073)
			(xy 155.661014 -412.943429) (xy 155.607074 -412.951188) (xy 155.579826 -412.951676) (xy 154.716226 -412.951676)
			(xy 154.68897 -412.951279) (xy 154.635011 -412.943524) (xy 154.582706 -412.928169) (xy 154.533118 -412.905526)
			(xy 154.487258 -412.876056) (xy 154.446059 -412.84036) (xy 154.410359 -412.799163) (xy 154.380886 -412.753305)
			(xy 154.35824 -412.703719) (xy 154.342881 -412.651414) (xy 154.335123 -412.597456) (xy 152.897612 -412.597456)
			(xy 152.889856 -412.651399) (xy 152.874501 -412.703693) (xy 152.851859 -412.75327) (xy 152.822392 -412.79912)
			(xy 152.7867 -412.84031) (xy 152.745509 -412.876001) (xy 152.699658 -412.905466) (xy 152.65008 -412.928105)
			(xy 152.597785 -412.943459) (xy 152.543837 -412.951214) (xy 152.516586 -412.951676) (xy 151.652986 -412.951676)
			(xy 151.625733 -412.951253) (xy 151.571782 -412.943494) (xy 151.519485 -412.928137) (xy 151.469905 -412.905493)
			(xy 151.424053 -412.876024) (xy 151.382861 -412.840329) (xy 151.347168 -412.799136) (xy 151.3177 -412.753282)
			(xy 151.295058 -412.703702) (xy 151.279703 -412.651404) (xy 151.271946 -412.597453) (xy 149.834289 -412.597453)
			(xy 149.826535 -412.651386) (xy 149.811184 -412.703673) (xy 149.788548 -412.753243) (xy 149.759088 -412.799087)
			(xy 149.723405 -412.840272) (xy 149.682224 -412.875961) (xy 149.636383 -412.905426) (xy 149.586816 -412.928068)
			(xy 149.534531 -412.943425) (xy 149.480593 -412.951187) (xy 149.453346 -412.951676) (xy 148.589746 -412.951676)
			(xy 148.562489 -412.95128) (xy 148.508528 -412.943528) (xy 148.45622 -412.928175) (xy 148.40663 -412.905533)
			(xy 148.360767 -412.876063) (xy 148.319566 -412.840367) (xy 148.283864 -412.799169) (xy 148.254389 -412.75331)
			(xy 148.231742 -412.703723) (xy 148.216382 -412.651417) (xy 148.208623 -412.597457) (xy 146.771089 -412.597457)
			(xy 146.763334 -412.651391) (xy 146.747981 -412.703681) (xy 146.725342 -412.753254) (xy 146.695879 -412.7991)
			(xy 146.660191 -412.840287) (xy 146.619005 -412.875975) (xy 146.573159 -412.905439) (xy 146.523587 -412.928079)
			(xy 146.471297 -412.943433) (xy 146.417355 -412.951189) (xy 146.390106 -412.951676) (xy 145.526506 -412.951676)
			(xy 145.499251 -412.951277) (xy 145.445294 -412.943521) (xy 145.392991 -412.928164) (xy 145.343406 -412.90552)
			(xy 145.297549 -412.876049) (xy 145.256352 -412.840353) (xy 145.220654 -412.799156) (xy 145.191183 -412.753299)
			(xy 145.168538 -412.703714) (xy 145.153181 -412.651411) (xy 145.145423 -412.597455) (xy 143.707913 -412.597455)
			(xy 143.700155 -412.651402) (xy 143.684799 -412.703698) (xy 143.662156 -412.753276) (xy 143.632687 -412.799127)
			(xy 143.596993 -412.840317) (xy 143.5558 -412.876008) (xy 143.509946 -412.905472) (xy 143.460366 -412.928111)
			(xy 143.408068 -412.943463) (xy 143.354118 -412.951215) (xy 143.326866 -412.951676) (xy 142.463266 -412.951676)
			(xy 142.436014 -412.951252) (xy 142.382065 -412.943491) (xy 142.32977 -412.928131) (xy 142.280193 -412.905486)
			(xy 142.234343 -412.876017) (xy 142.193154 -412.840322) (xy 142.157463 -412.799129) (xy 142.127997 -412.753277)
			(xy 142.105357 -412.703698) (xy 142.090002 -412.651401) (xy 142.082246 -412.597452) (xy 140.644589 -412.597452)
			(xy 140.636835 -412.651389) (xy 140.621482 -412.703677) (xy 140.598845 -412.753248) (xy 140.569384 -412.799093)
			(xy 140.533698 -412.840279) (xy 140.492514 -412.875968) (xy 140.446671 -412.905432) (xy 140.397101 -412.928073)
			(xy 140.344814 -412.943429) (xy 140.290874 -412.951188) (xy 140.263626 -412.951676) (xy 139.400026 -412.951676)
			(xy 139.37277 -412.951279) (xy 139.318811 -412.943524) (xy 139.266506 -412.928169) (xy 139.216918 -412.905526)
			(xy 139.171058 -412.876056) (xy 139.129859 -412.84036) (xy 139.094159 -412.799163) (xy 139.064686 -412.753305)
			(xy 139.04204 -412.703719) (xy 139.026681 -412.651414) (xy 139.018923 -412.597456) (xy 137.581412 -412.597456)
			(xy 137.573656 -412.651399) (xy 137.558301 -412.703693) (xy 137.535659 -412.75327) (xy 137.506192 -412.79912)
			(xy 137.4705 -412.84031) (xy 137.429309 -412.876001) (xy 137.383458 -412.905466) (xy 137.33388 -412.928105)
			(xy 137.281585 -412.943459) (xy 137.227637 -412.951214) (xy 137.200386 -412.951676) (xy 136.336786 -412.951676)
			(xy 136.309533 -412.951253) (xy 136.255582 -412.943494) (xy 136.203285 -412.928137) (xy 136.153705 -412.905493)
			(xy 136.107853 -412.876024) (xy 136.066661 -412.840329) (xy 136.030968 -412.799136) (xy 136.0015 -412.753282)
			(xy 135.978858 -412.703702) (xy 135.963503 -412.651404) (xy 135.955746 -412.597453) (xy 134.518089 -412.597453)
			(xy 134.510335 -412.651386) (xy 134.494984 -412.703673) (xy 134.472348 -412.753243) (xy 134.442888 -412.799087)
			(xy 134.407205 -412.840272) (xy 134.366024 -412.875961) (xy 134.320183 -412.905426) (xy 134.270616 -412.928068)
			(xy 134.218331 -412.943425) (xy 134.164393 -412.951187) (xy 134.137146 -412.951676) (xy 133.273546 -412.951676)
			(xy 133.246289 -412.95128) (xy 133.192328 -412.943528) (xy 133.14002 -412.928175) (xy 133.09043 -412.905533)
			(xy 133.044567 -412.876063) (xy 133.003366 -412.840367) (xy 132.967664 -412.799169) (xy 132.938189 -412.75331)
			(xy 132.915542 -412.703723) (xy 132.900182 -412.651417) (xy 132.892423 -412.597457) (xy 131.454889 -412.597457)
			(xy 131.447134 -412.651391) (xy 131.431781 -412.703681) (xy 131.409142 -412.753254) (xy 131.379679 -412.7991)
			(xy 131.343991 -412.840287) (xy 131.302805 -412.875975) (xy 131.256959 -412.905439) (xy 131.207387 -412.928079)
			(xy 131.155097 -412.943433) (xy 131.101155 -412.951189) (xy 131.073906 -412.951676) (xy 130.210306 -412.951676)
			(xy 130.183051 -412.951277) (xy 130.129094 -412.943521) (xy 130.076791 -412.928164) (xy 130.027206 -412.90552)
			(xy 129.981349 -412.876049) (xy 129.940152 -412.840353) (xy 129.904454 -412.799156) (xy 129.874983 -412.753299)
			(xy 129.852338 -412.703714) (xy 129.836981 -412.651411) (xy 129.829223 -412.597455) (xy 128.391713 -412.597455)
			(xy 128.383955 -412.651402) (xy 128.368599 -412.703698) (xy 128.345956 -412.753276) (xy 128.316487 -412.799127)
			(xy 128.280793 -412.840317) (xy 128.2396 -412.876008) (xy 128.193746 -412.905472) (xy 128.144166 -412.928111)
			(xy 128.091868 -412.943463) (xy 128.037918 -412.951215) (xy 128.010666 -412.951676) (xy 127.147066 -412.951676)
			(xy 127.119814 -412.951252) (xy 127.065865 -412.943491) (xy 127.01357 -412.928131) (xy 126.963993 -412.905486)
			(xy 126.918143 -412.876017) (xy 126.876954 -412.840322) (xy 126.841263 -412.799129) (xy 126.811797 -412.753277)
			(xy 126.789157 -412.703698) (xy 126.773802 -412.651401) (xy 126.766046 -412.597452) (xy 125.328389 -412.597452)
			(xy 125.320635 -412.651389) (xy 125.305282 -412.703677) (xy 125.282645 -412.753248) (xy 125.253184 -412.799093)
			(xy 125.217498 -412.840279) (xy 125.176314 -412.875968) (xy 125.130471 -412.905432) (xy 125.080901 -412.928073)
			(xy 125.028614 -412.943429) (xy 124.974674 -412.951188) (xy 124.947426 -412.951676) (xy 124.083826 -412.951676)
			(xy 124.05657 -412.951279) (xy 124.002611 -412.943524) (xy 123.950306 -412.928169) (xy 123.900718 -412.905526)
			(xy 123.854858 -412.876056) (xy 123.813659 -412.84036) (xy 123.777959 -412.799163) (xy 123.748486 -412.753305)
			(xy 123.72584 -412.703719) (xy 123.710481 -412.651414) (xy 123.702723 -412.597456) (xy 122.265212 -412.597456)
			(xy 122.257456 -412.651399) (xy 122.242101 -412.703693) (xy 122.219459 -412.75327) (xy 122.189992 -412.79912)
			(xy 122.1543 -412.84031) (xy 122.113109 -412.876001) (xy 122.067258 -412.905466) (xy 122.01768 -412.928105)
			(xy 121.965385 -412.943459) (xy 121.911437 -412.951214) (xy 121.884186 -412.951676) (xy 121.020586 -412.951676)
			(xy 120.993333 -412.951253) (xy 120.939382 -412.943494) (xy 120.887085 -412.928137) (xy 120.837505 -412.905493)
			(xy 120.791653 -412.876024) (xy 120.750461 -412.840329) (xy 120.714768 -412.799136) (xy 120.6853 -412.753282)
			(xy 120.662658 -412.703702) (xy 120.647303 -412.651404) (xy 120.639546 -412.597453) (xy 119.201889 -412.597453)
			(xy 119.194135 -412.651386) (xy 119.178784 -412.703673) (xy 119.156148 -412.753243) (xy 119.126688 -412.799087)
			(xy 119.091005 -412.840272) (xy 119.049824 -412.875961) (xy 119.003983 -412.905426) (xy 118.954416 -412.928068)
			(xy 118.902131 -412.943425) (xy 118.848193 -412.951187) (xy 118.820946 -412.951676) (xy 117.957346 -412.951676)
			(xy 117.930089 -412.95128) (xy 117.876128 -412.943528) (xy 117.82382 -412.928175) (xy 117.77423 -412.905533)
			(xy 117.728367 -412.876063) (xy 117.687166 -412.840367) (xy 117.651464 -412.799169) (xy 117.621989 -412.75331)
			(xy 117.599342 -412.703723) (xy 117.583982 -412.651417) (xy 117.576223 -412.597457) (xy 116.138689 -412.597457)
			(xy 116.130934 -412.651391) (xy 116.115581 -412.703681) (xy 116.092942 -412.753254) (xy 116.063479 -412.7991)
			(xy 116.027791 -412.840287) (xy 115.986605 -412.875975) (xy 115.940759 -412.905439) (xy 115.891187 -412.928079)
			(xy 115.838897 -412.943433) (xy 115.784955 -412.951189) (xy 115.757706 -412.951676) (xy 114.894106 -412.951676)
			(xy 114.866851 -412.951277) (xy 114.812894 -412.943521) (xy 114.760591 -412.928164) (xy 114.711006 -412.90552)
			(xy 114.665149 -412.876049) (xy 114.623952 -412.840353) (xy 114.588254 -412.799156) (xy 114.558783 -412.753299)
			(xy 114.536138 -412.703714) (xy 114.520781 -412.651411) (xy 114.513023 -412.597455) (xy 94.987413 -412.597455)
			(xy 94.979655 -412.651402) (xy 94.964299 -412.703698) (xy 94.941656 -412.753276) (xy 94.912187 -412.799127)
			(xy 94.876492 -412.840318) (xy 94.835299 -412.876008) (xy 94.789445 -412.905473) (xy 94.739864 -412.928111)
			(xy 94.687567 -412.943463) (xy 94.633616 -412.951215) (xy 94.606364 -412.951676) (xy 93.742764 -412.951676)
			(xy 93.715512 -412.951252) (xy 93.661564 -412.94349) (xy 93.609269 -412.928131) (xy 93.559692 -412.905486)
			(xy 93.513842 -412.876016) (xy 93.472653 -412.840321) (xy 93.436962 -412.799129) (xy 93.407497 -412.753276)
			(xy 93.384857 -412.703697) (xy 93.369502 -412.651401) (xy 93.361746 -412.597452) (xy 91.924089 -412.597452)
			(xy 91.916335 -412.651389) (xy 91.900982 -412.703677) (xy 91.878345 -412.753249) (xy 91.848883 -412.799094)
			(xy 91.813197 -412.84028) (xy 91.772013 -412.875969) (xy 91.72617 -412.905433) (xy 91.6766 -412.928074)
			(xy 91.624312 -412.94343) (xy 91.570372 -412.951188) (xy 91.543124 -412.951676) (xy 90.679524 -412.951676)
			(xy 90.652268 -412.951279) (xy 90.59831 -412.943524) (xy 90.546004 -412.928169) (xy 90.496417 -412.905526)
			(xy 90.450557 -412.876056) (xy 90.409358 -412.840359) (xy 90.373659 -412.799162) (xy 90.344186 -412.753304)
			(xy 90.32154 -412.703718) (xy 90.306181 -412.651414) (xy 90.298423 -412.597456) (xy 88.860912 -412.597456)
			(xy 88.853156 -412.651399) (xy 88.8378 -412.703694) (xy 88.815159 -412.753271) (xy 88.785692 -412.799121)
			(xy 88.749999 -412.840311) (xy 88.708808 -412.876001) (xy 88.662957 -412.905466) (xy 88.613379 -412.928106)
			(xy 88.561083 -412.943459) (xy 88.507135 -412.951214) (xy 88.479884 -412.951676) (xy 87.616284 -412.951676)
			(xy 87.589031 -412.951253) (xy 87.535081 -412.943494) (xy 87.482783 -412.928136) (xy 87.433204 -412.905492)
			(xy 87.387352 -412.876023) (xy 87.34616 -412.840329) (xy 87.310467 -412.799135) (xy 87.281 -412.753282)
			(xy 87.258358 -412.703702) (xy 87.243003 -412.651404) (xy 87.235246 -412.597453) (xy 85.797589 -412.597453)
			(xy 85.789835 -412.651386) (xy 85.774484 -412.703673) (xy 85.751848 -412.753243) (xy 85.722388 -412.799087)
			(xy 85.686704 -412.840273) (xy 85.645523 -412.875962) (xy 85.599682 -412.905427) (xy 85.550114 -412.928068)
			(xy 85.497829 -412.943426) (xy 85.443891 -412.951187) (xy 85.416644 -412.951676) (xy 84.553044 -412.951676)
			(xy 84.525787 -412.95128) (xy 84.471827 -412.943528) (xy 84.419519 -412.928174) (xy 84.369929 -412.905532)
			(xy 84.324067 -412.876063) (xy 84.282865 -412.840366) (xy 84.247164 -412.799169) (xy 84.217689 -412.75331)
			(xy 84.195041 -412.703722) (xy 84.179682 -412.651417) (xy 84.171923 -412.597457) (xy 82.734389 -412.597457)
			(xy 82.726634 -412.651392) (xy 82.71128 -412.703682) (xy 82.688642 -412.753254) (xy 82.659178 -412.799101)
			(xy 82.62349 -412.840287) (xy 82.582304 -412.875976) (xy 82.536458 -412.90544) (xy 82.486885 -412.928079)
			(xy 82.434595 -412.943433) (xy 82.380653 -412.95119) (xy 82.353404 -412.951676) (xy 81.489804 -412.951676)
			(xy 81.462549 -412.951277) (xy 81.408593 -412.94352) (xy 81.35629 -412.928163) (xy 81.306705 -412.905519)
			(xy 81.260848 -412.876049) (xy 81.219651 -412.840352) (xy 81.183954 -412.799156) (xy 81.154483 -412.753298)
			(xy 81.131838 -412.703714) (xy 81.116481 -412.651411) (xy 81.108723 -412.597455) (xy 79.671213 -412.597455)
			(xy 79.663455 -412.651402) (xy 79.648099 -412.703698) (xy 79.625456 -412.753276) (xy 79.595987 -412.799127)
			(xy 79.560292 -412.840318) (xy 79.519099 -412.876008) (xy 79.473245 -412.905473) (xy 79.423664 -412.928111)
			(xy 79.371367 -412.943463) (xy 79.317416 -412.951215) (xy 79.290164 -412.951676) (xy 78.426564 -412.951676)
			(xy 78.399312 -412.951252) (xy 78.345364 -412.94349) (xy 78.293069 -412.928131) (xy 78.243492 -412.905486)
			(xy 78.197642 -412.876016) (xy 78.156453 -412.840321) (xy 78.120762 -412.799129) (xy 78.091297 -412.753276)
			(xy 78.068657 -412.703697) (xy 78.053302 -412.651401) (xy 78.045546 -412.597452) (xy 76.607889 -412.597452)
			(xy 76.600135 -412.651389) (xy 76.584782 -412.703677) (xy 76.562145 -412.753249) (xy 76.532683 -412.799094)
			(xy 76.496997 -412.84028) (xy 76.455813 -412.875969) (xy 76.40997 -412.905433) (xy 76.3604 -412.928074)
			(xy 76.308112 -412.94343) (xy 76.254172 -412.951188) (xy 76.226924 -412.951676) (xy 75.363324 -412.951676)
			(xy 75.336068 -412.951279) (xy 75.28211 -412.943524) (xy 75.229804 -412.928169) (xy 75.180217 -412.905526)
			(xy 75.134357 -412.876056) (xy 75.093158 -412.840359) (xy 75.057459 -412.799162) (xy 75.027986 -412.753304)
			(xy 75.00534 -412.703718) (xy 74.989981 -412.651414) (xy 74.982223 -412.597456) (xy 73.544712 -412.597456)
			(xy 73.536956 -412.651399) (xy 73.5216 -412.703694) (xy 73.498959 -412.753271) (xy 73.469492 -412.799121)
			(xy 73.433799 -412.840311) (xy 73.392608 -412.876001) (xy 73.346757 -412.905466) (xy 73.297179 -412.928106)
			(xy 73.244883 -412.943459) (xy 73.190935 -412.951214) (xy 73.163684 -412.951676) (xy 72.300084 -412.951676)
			(xy 72.272831 -412.951253) (xy 72.218881 -412.943494) (xy 72.166583 -412.928136) (xy 72.117004 -412.905492)
			(xy 72.071152 -412.876023) (xy 72.02996 -412.840329) (xy 71.994267 -412.799135) (xy 71.9648 -412.753282)
			(xy 71.942158 -412.703702) (xy 71.926803 -412.651404) (xy 71.919046 -412.597453) (xy 70.481389 -412.597453)
			(xy 70.473635 -412.651386) (xy 70.458284 -412.703673) (xy 70.435648 -412.753243) (xy 70.406188 -412.799087)
			(xy 70.370504 -412.840273) (xy 70.329323 -412.875962) (xy 70.283482 -412.905427) (xy 70.233914 -412.928068)
			(xy 70.181629 -412.943426) (xy 70.127691 -412.951187) (xy 70.100444 -412.951676) (xy 69.236844 -412.951676)
			(xy 69.209587 -412.95128) (xy 69.155627 -412.943528) (xy 69.103319 -412.928174) (xy 69.053729 -412.905532)
			(xy 69.007867 -412.876063) (xy 68.966665 -412.840366) (xy 68.930964 -412.799169) (xy 68.901489 -412.75331)
			(xy 68.878841 -412.703722) (xy 68.863482 -412.651417) (xy 68.855723 -412.597457) (xy 67.418189 -412.597457)
			(xy 67.410434 -412.651392) (xy 67.39508 -412.703682) (xy 67.372442 -412.753254) (xy 67.342978 -412.799101)
			(xy 67.30729 -412.840287) (xy 67.266104 -412.875976) (xy 67.220258 -412.90544) (xy 67.170685 -412.928079)
			(xy 67.118395 -412.943433) (xy 67.064453 -412.95119) (xy 67.037204 -412.951676) (xy 66.173604 -412.951676)
			(xy 66.146349 -412.951277) (xy 66.092393 -412.94352) (xy 66.04009 -412.928163) (xy 65.990505 -412.905519)
			(xy 65.944648 -412.876049) (xy 65.903451 -412.840352) (xy 65.867754 -412.799156) (xy 65.838283 -412.753298)
			(xy 65.815638 -412.703714) (xy 65.800281 -412.651411) (xy 65.792523 -412.597455) (xy 64.355013 -412.597455)
			(xy 64.347255 -412.651402) (xy 64.331899 -412.703698) (xy 64.309256 -412.753276) (xy 64.279787 -412.799127)
			(xy 64.244092 -412.840318) (xy 64.202899 -412.876008) (xy 64.157045 -412.905473) (xy 64.107464 -412.928111)
			(xy 64.055167 -412.943463) (xy 64.001216 -412.951215) (xy 63.973964 -412.951676) (xy 63.110364 -412.951676)
			(xy 63.083112 -412.951252) (xy 63.029164 -412.94349) (xy 62.976869 -412.928131) (xy 62.927292 -412.905486)
			(xy 62.881442 -412.876016) (xy 62.840253 -412.840321) (xy 62.804562 -412.799129) (xy 62.775097 -412.753276)
			(xy 62.752457 -412.703697) (xy 62.737102 -412.651401) (xy 62.729346 -412.597452) (xy 61.291689 -412.597452)
			(xy 61.283935 -412.651389) (xy 61.268582 -412.703677) (xy 61.245945 -412.753249) (xy 61.216483 -412.799094)
			(xy 61.180797 -412.84028) (xy 61.139613 -412.875969) (xy 61.09377 -412.905433) (xy 61.0442 -412.928074)
			(xy 60.991912 -412.94343) (xy 60.937972 -412.951188) (xy 60.910724 -412.951676) (xy 60.047124 -412.951676)
			(xy 60.019868 -412.951279) (xy 59.96591 -412.943524) (xy 59.913604 -412.928169) (xy 59.864017 -412.905526)
			(xy 59.818157 -412.876056) (xy 59.776958 -412.840359) (xy 59.741259 -412.799162) (xy 59.711786 -412.753304)
			(xy 59.68914 -412.703718) (xy 59.673781 -412.651414) (xy 59.666023 -412.597456) (xy 58.228512 -412.597456)
			(xy 58.220756 -412.651399) (xy 58.2054 -412.703694) (xy 58.182759 -412.753271) (xy 58.153292 -412.799121)
			(xy 58.117599 -412.840311) (xy 58.076408 -412.876001) (xy 58.030557 -412.905466) (xy 57.980979 -412.928106)
			(xy 57.928683 -412.943459) (xy 57.874735 -412.951214) (xy 57.847484 -412.951676) (xy 56.983884 -412.951676)
			(xy 56.956631 -412.951253) (xy 56.902681 -412.943494) (xy 56.850383 -412.928136) (xy 56.800804 -412.905492)
			(xy 56.754952 -412.876023) (xy 56.71376 -412.840329) (xy 56.678067 -412.799135) (xy 56.6486 -412.753282)
			(xy 56.625958 -412.703702) (xy 56.610603 -412.651404) (xy 56.602846 -412.597453) (xy 55.165189 -412.597453)
			(xy 55.157435 -412.651386) (xy 55.142084 -412.703673) (xy 55.119448 -412.753243) (xy 55.089988 -412.799087)
			(xy 55.054304 -412.840273) (xy 55.013123 -412.875962) (xy 54.967282 -412.905427) (xy 54.917714 -412.928068)
			(xy 54.865429 -412.943426) (xy 54.811491 -412.951187) (xy 54.784244 -412.951676) (xy 53.920644 -412.951676)
			(xy 53.893387 -412.95128) (xy 53.839427 -412.943528) (xy 53.787119 -412.928174) (xy 53.737529 -412.905532)
			(xy 53.691667 -412.876063) (xy 53.650465 -412.840366) (xy 53.614764 -412.799169) (xy 53.585289 -412.75331)
			(xy 53.562641 -412.703722) (xy 53.547282 -412.651417) (xy 53.539523 -412.597457) (xy 52.101989 -412.597457)
			(xy 52.094234 -412.651392) (xy 52.07888 -412.703682) (xy 52.056242 -412.753254) (xy 52.026778 -412.799101)
			(xy 51.99109 -412.840287) (xy 51.949904 -412.875976) (xy 51.904058 -412.90544) (xy 51.854485 -412.928079)
			(xy 51.802195 -412.943433) (xy 51.748253 -412.95119) (xy 51.721004 -412.951676) (xy 50.857404 -412.951676)
			(xy 50.830149 -412.951277) (xy 50.776193 -412.94352) (xy 50.72389 -412.928163) (xy 50.674305 -412.905519)
			(xy 50.628448 -412.876049) (xy 50.587251 -412.840352) (xy 50.551554 -412.799156) (xy 50.522083 -412.753298)
			(xy 50.499438 -412.703714) (xy 50.484081 -412.651411) (xy 50.476323 -412.597455) (xy 49.038813 -412.597455)
			(xy 49.031055 -412.651402) (xy 49.015699 -412.703698) (xy 48.993056 -412.753276) (xy 48.963587 -412.799127)
			(xy 48.927892 -412.840318) (xy 48.886699 -412.876008) (xy 48.840845 -412.905473) (xy 48.791264 -412.928111)
			(xy 48.738967 -412.943463) (xy 48.685016 -412.951215) (xy 48.657764 -412.951676) (xy 47.794164 -412.951676)
			(xy 47.766912 -412.951252) (xy 47.712964 -412.94349) (xy 47.660669 -412.928131) (xy 47.611092 -412.905486)
			(xy 47.565242 -412.876016) (xy 47.524053 -412.840321) (xy 47.488362 -412.799129) (xy 47.458897 -412.753276)
			(xy 47.436257 -412.703697) (xy 47.420902 -412.651401) (xy 47.413146 -412.597452) (xy 39.737792 -412.597452)
			(xy 39.737792 -413.4485) (xy 39.737556 -413.461769) (xy 105.629431 -413.461769) (xy 105.629431 -413.407231)
			(xy 105.637193 -413.353247) (xy 105.652559 -413.300918) (xy 105.675215 -413.251308) (xy 105.704702 -413.205427)
			(xy 105.740417 -413.16421) (xy 105.781635 -413.128496) (xy 105.827517 -413.099011) (xy 105.877127 -413.076355)
			(xy 105.929457 -413.060991) (xy 105.983441 -413.053231) (xy 106.01071 -413.052768) (xy 106.87431 -413.052768)
			(xy 106.901581 -413.053195) (xy 106.955568 -413.060959) (xy 107.0079 -413.076326) (xy 107.057513 -413.098985)
			(xy 107.103396 -413.128473) (xy 107.144616 -413.164191) (xy 107.180333 -413.205412) (xy 107.20982 -413.251296)
			(xy 107.232477 -413.300909) (xy 107.247844 -413.353242) (xy 107.255606 -413.407229) (xy 107.255606 -413.461771)
			(xy 107.247844 -413.515758) (xy 107.232477 -413.568091) (xy 107.20982 -413.617704) (xy 107.180333 -413.663588)
			(xy 107.144616 -413.704809) (xy 107.103396 -413.740527) (xy 107.057513 -413.770015) (xy 107.0079 -413.792674)
			(xy 106.955568 -413.808041) (xy 106.901581 -413.815805) (xy 106.87431 -413.816292) (xy 106.01071 -413.816292)
			(xy 105.983441 -413.815769) (xy 105.929457 -413.808009) (xy 105.877127 -413.792645) (xy 105.827517 -413.769989)
			(xy 105.781635 -413.740504) (xy 105.740417 -413.70479) (xy 105.704702 -413.663573) (xy 105.675215 -413.617692)
			(xy 105.652559 -413.568082) (xy 105.637193 -413.515753) (xy 105.629431 -413.461769) (xy 39.737556 -413.461769)
			(xy 39.737306 -413.475769) (xy 39.729544 -413.529753) (xy 39.714179 -413.582083) (xy 39.691522 -413.631693)
			(xy 39.662036 -413.677574) (xy 39.626321 -413.718791) (xy 39.585104 -413.754506) (xy 39.539223 -413.783992)
			(xy 39.489613 -413.806649) (xy 39.437283 -413.822014) (xy 39.383299 -413.829776) (xy 39.328761 -413.829776)
			(xy 39.274777 -413.822014) (xy 39.222447 -413.806649) (xy 39.172837 -413.783992) (xy 39.126956 -413.754506)
			(xy 39.085739 -413.718791) (xy 39.050024 -413.677574) (xy 39.020538 -413.631693) (xy 38.997881 -413.582083)
			(xy 38.982516 -413.529753) (xy 38.974754 -413.475769) (xy 38.974268 -413.4485) (xy 7.00913 -413.4485)
			(xy 7.00913 -415.383726) (xy 41.206928 -415.383726) (xy 41.206928 -414.520126) (xy 41.207414 -414.492857)
			(xy 41.215176 -414.438873) (xy 41.230541 -414.386543) (xy 41.253198 -414.336933) (xy 41.282684 -414.291052)
			(xy 41.318399 -414.249835) (xy 41.359616 -414.21412) (xy 41.405497 -414.184634) (xy 41.455107 -414.161977)
			(xy 41.507437 -414.146612) (xy 41.561421 -414.13885) (xy 41.615959 -414.13885) (xy 41.669943 -414.146612)
			(xy 41.722273 -414.161977) (xy 41.771883 -414.184634) (xy 41.817764 -414.21412) (xy 41.858981 -414.249835)
			(xy 41.894696 -414.291052) (xy 41.924182 -414.336933) (xy 41.946839 -414.386543) (xy 41.962204 -414.438873)
			(xy 41.969966 -414.492857) (xy 41.970452 -414.520126) (xy 41.970452 -415.383726) (xy 41.969966 -415.410995)
			(xy 41.962204 -415.464979) (xy 41.946839 -415.517309) (xy 41.924182 -415.566919) (xy 41.894696 -415.6128)
			(xy 41.858981 -415.654017) (xy 41.817764 -415.689732) (xy 41.771883 -415.719218) (xy 41.722273 -415.741875)
			(xy 41.669943 -415.75724) (xy 41.615959 -415.765002) (xy 41.561421 -415.765002) (xy 41.507437 -415.75724)
			(xy 41.455107 -415.741875) (xy 41.405497 -415.719218) (xy 41.359616 -415.689732) (xy 41.318399 -415.654017)
			(xy 41.282684 -415.6128) (xy 41.253198 -415.566919) (xy 41.230541 -415.517309) (xy 41.215176 -415.464979)
			(xy 41.207414 -415.410995) (xy 41.206928 -415.383726) (xy 7.00913 -415.383726) (xy 7.00913 -417.465002)
			(xy 35.832796 -417.465002) (xy 35.832796 -416.601402) (xy 35.833282 -416.574151) (xy 35.841038 -416.520203)
			(xy 35.856393 -416.467908) (xy 35.879035 -416.418331) (xy 35.908501 -416.372481) (xy 35.944192 -416.33129)
			(xy 35.985383 -416.295599) (xy 36.031233 -416.266133) (xy 36.08081 -416.243491) (xy 36.133105 -416.228136)
			(xy 36.187053 -416.22038) (xy 36.241555 -416.22038) (xy 36.295503 -416.228136) (xy 36.347798 -416.243491)
			(xy 36.397375 -416.266133) (xy 36.443225 -416.295599) (xy 36.484416 -416.33129) (xy 36.520107 -416.372481)
			(xy 36.549573 -416.418331) (xy 36.572215 -416.467908) (xy 36.58757 -416.520203) (xy 36.595326 -416.574151)
			(xy 36.595812 -416.601402) (xy 36.595812 -417.436808) (xy 48.812704 -417.436808) (xy 48.812704 -416.573208)
			(xy 48.81319 -416.545939) (xy 48.820952 -416.491955) (xy 48.836317 -416.439625) (xy 48.858974 -416.390015)
			(xy 48.88846 -416.344134) (xy 48.924175 -416.302917) (xy 48.965392 -416.267202) (xy 49.011273 -416.237716)
			(xy 49.060883 -416.215059) (xy 49.113213 -416.199694) (xy 49.167197 -416.191932) (xy 49.221735 -416.191932)
			(xy 49.275719 -416.199694) (xy 49.328049 -416.215059) (xy 49.377659 -416.237716) (xy 49.42354 -416.267202)
			(xy 49.464757 -416.302917) (xy 49.500472 -416.344134) (xy 49.529958 -416.390015) (xy 49.552615 -416.439625)
			(xy 49.56798 -416.491955) (xy 49.575742 -416.545939) (xy 49.576228 -416.573208) (xy 49.576228 -417.436808)
			(xy 49.575742 -417.464077) (xy 49.56798 -417.518061) (xy 49.552615 -417.570391) (xy 49.529958 -417.620001)
			(xy 49.500472 -417.665882) (xy 49.464757 -417.707099) (xy 49.42354 -417.742814) (xy 49.377659 -417.7723)
			(xy 49.328049 -417.794957) (xy 49.275719 -417.810322) (xy 49.221735 -417.818084) (xy 49.167197 -417.818084)
			(xy 49.113213 -417.810322) (xy 49.060883 -417.794957) (xy 49.011273 -417.7723) (xy 48.965392 -417.742814)
			(xy 48.924175 -417.707099) (xy 48.88846 -417.665882) (xy 48.858974 -417.620001) (xy 48.836317 -417.570391)
			(xy 48.820952 -417.518061) (xy 48.81319 -417.464077) (xy 48.812704 -417.436808) (xy 36.595812 -417.436808)
			(xy 36.595812 -417.465002) (xy 36.595326 -417.492253) (xy 36.58757 -417.546201) (xy 36.572215 -417.598496)
			(xy 36.549573 -417.648073) (xy 36.520107 -417.693923) (xy 36.484416 -417.735114) (xy 36.443225 -417.770805)
			(xy 36.397375 -417.800271) (xy 36.347798 -417.822913) (xy 36.295503 -417.838268) (xy 36.241555 -417.846024)
			(xy 36.187053 -417.846024) (xy 36.133105 -417.838268) (xy 36.08081 -417.822913) (xy 36.031233 -417.800271)
			(xy 35.985383 -417.770805) (xy 35.944192 -417.735114) (xy 35.908501 -417.693923) (xy 35.879035 -417.648073)
			(xy 35.856393 -417.598496) (xy 35.841038 -417.546201) (xy 35.833282 -417.492253) (xy 35.832796 -417.465002)
			(xy 7.00913 -417.465002) (xy 7.00913 -419.64102) (xy 51.809904 -419.64102) (xy 51.809904 -418.77742)
			(xy 51.81039 -418.750151) (xy 51.818152 -418.696167) (xy 51.833517 -418.643837) (xy 51.856174 -418.594227)
			(xy 51.88566 -418.548346) (xy 51.921375 -418.507129) (xy 51.962592 -418.471414) (xy 52.008473 -418.441928)
			(xy 52.058083 -418.419271) (xy 52.110413 -418.403906) (xy 52.164397 -418.396144) (xy 52.218935 -418.396144)
			(xy 52.272919 -418.403906) (xy 52.325249 -418.419271) (xy 52.374859 -418.441928) (xy 52.42074 -418.471414)
			(xy 52.461957 -418.507129) (xy 52.497672 -418.548346) (xy 52.527158 -418.594227) (xy 52.549815 -418.643837)
			(xy 52.56518 -418.696167) (xy 52.572942 -418.750151) (xy 52.573428 -418.77742) (xy 52.573428 -419.64102)
			(xy 52.572942 -419.668289) (xy 52.56518 -419.722273) (xy 52.549815 -419.774603) (xy 52.527158 -419.824213)
			(xy 52.497672 -419.870094) (xy 52.461957 -419.911311) (xy 52.42074 -419.947026) (xy 52.374859 -419.976512)
			(xy 52.325249 -419.999169) (xy 52.272919 -420.014534) (xy 52.218935 -420.022296) (xy 52.164397 -420.022296)
			(xy 52.110413 -420.014534) (xy 52.058083 -419.999169) (xy 52.008473 -419.976512) (xy 51.962592 -419.947026)
			(xy 51.921375 -419.911311) (xy 51.88566 -419.870094) (xy 51.856174 -419.824213) (xy 51.833517 -419.774603)
			(xy 51.818152 -419.722273) (xy 51.81039 -419.668289) (xy 51.809904 -419.64102) (xy 7.00913 -419.64102)
			(xy 7.00913 -421.200326) (xy 10.01268 -421.200326) (xy 10.01268 -420.336726) (xy 10.013166 -420.309475)
			(xy 10.020922 -420.255527) (xy 10.036277 -420.203232) (xy 10.058919 -420.153655) (xy 10.088385 -420.107805)
			(xy 10.124076 -420.066614) (xy 10.165267 -420.030923) (xy 10.211117 -420.001457) (xy 10.260694 -419.978815)
			(xy 10.312989 -419.96346) (xy 10.366937 -419.955704) (xy 10.421439 -419.955704) (xy 10.475387 -419.96346)
			(xy 10.527682 -419.978815) (xy 10.577259 -420.001457) (xy 10.623109 -420.030923) (xy 10.6643 -420.066614)
			(xy 10.699991 -420.107805) (xy 10.729457 -420.153655) (xy 10.752099 -420.203232) (xy 10.767454 -420.255527)
			(xy 10.77521 -420.309475) (xy 10.775696 -420.336726) (xy 10.775696 -421.200326) (xy 10.77521 -421.227577)
			(xy 10.769122 -421.269922) (xy 21.420836 -421.269922) (xy 21.420836 -420.406322) (xy 21.421322 -420.379071)
			(xy 21.429078 -420.325123) (xy 21.444433 -420.272828) (xy 21.467075 -420.223251) (xy 21.496541 -420.177401)
			(xy 21.532232 -420.13621) (xy 21.573423 -420.100519) (xy 21.619273 -420.071053) (xy 21.66885 -420.048411)
			(xy 21.721145 -420.033056) (xy 21.775093 -420.0253) (xy 21.829595 -420.0253) (xy 21.883543 -420.033056)
			(xy 21.935838 -420.048411) (xy 21.985415 -420.071053) (xy 22.031265 -420.100519) (xy 22.072456 -420.13621)
			(xy 22.108147 -420.177401) (xy 22.137613 -420.223251) (xy 22.160255 -420.272828) (xy 22.17561 -420.325123)
			(xy 22.183366 -420.379071) (xy 22.183852 -420.406322) (xy 22.183852 -420.760398) (xy 58.141108 -420.760398)
			(xy 58.141108 -418.218874) (xy 58.141589 -418.206761) (xy 58.14908 -418.183722) (xy 58.16332 -418.164123)
			(xy 58.182918 -418.149882) (xy 58.205957 -418.14239) (xy 58.21807 -418.141912) (xy 59.15787 -418.141912)
			(xy 59.169989 -418.142385) (xy 59.193042 -418.149866) (xy 59.212655 -418.164105) (xy 59.226908 -418.183708)
			(xy 59.234406 -418.206756) (xy 59.234832 -418.218874) (xy 59.234832 -420.760398) (xy 59.234438 -420.772524)
			(xy 59.226942 -420.795587) (xy 59.212685 -420.815205) (xy 59.193062 -420.829455) (xy 59.169996 -420.836942)
			(xy 59.15787 -420.83736) (xy 58.21807 -420.83736) (xy 58.205954 -420.836914) (xy 58.182909 -420.829418)
			(xy 58.163308 -420.81517) (xy 58.149067 -420.795562) (xy 58.141581 -420.772515) (xy 58.141108 -420.760398)
			(xy 22.183852 -420.760398) (xy 22.183852 -421.269922) (xy 22.183366 -421.297173) (xy 22.17561 -421.351121)
			(xy 22.160255 -421.403416) (xy 22.137613 -421.452993) (xy 22.108147 -421.498843) (xy 22.072456 -421.540034)
			(xy 22.031265 -421.575725) (xy 21.985415 -421.605191) (xy 21.935838 -421.627833) (xy 21.883543 -421.643188)
			(xy 21.829595 -421.650944) (xy 21.775093 -421.650944) (xy 21.721145 -421.643188) (xy 21.66885 -421.627833)
			(xy 21.619273 -421.605191) (xy 21.573423 -421.575725) (xy 21.532232 -421.540034) (xy 21.496541 -421.498843)
			(xy 21.467075 -421.452993) (xy 21.444433 -421.403416) (xy 21.429078 -421.351121) (xy 21.421322 -421.297173)
			(xy 21.420836 -421.269922) (xy 10.769122 -421.269922) (xy 10.767454 -421.281525) (xy 10.752099 -421.33382)
			(xy 10.729457 -421.383397) (xy 10.699991 -421.429247) (xy 10.6643 -421.470438) (xy 10.623109 -421.506129)
			(xy 10.577259 -421.535595) (xy 10.527682 -421.558237) (xy 10.475387 -421.573592) (xy 10.421439 -421.581348)
			(xy 10.366937 -421.581348) (xy 10.312989 -421.573592) (xy 10.260694 -421.558237) (xy 10.211117 -421.535595)
			(xy 10.165267 -421.506129) (xy 10.124076 -421.470438) (xy 10.088385 -421.429247) (xy 10.058919 -421.383397)
			(xy 10.036277 -421.33382) (xy 10.020922 -421.281525) (xy 10.013166 -421.227577) (xy 10.01268 -421.200326)
			(xy 7.00913 -421.200326) (xy 7.00913 -422.461944) (xy 14.418056 -422.461944) (xy 14.418056 -421.805354)
			(xy 14.418489 -421.795222) (xy 14.426235 -421.776497) (xy 14.440538 -421.762142) (xy 14.459234 -421.754327)
			(xy 14.469364 -421.753792) (xy 14.977364 -421.753792) (xy 14.987483 -421.754245) (xy 15.006184 -421.76198)
			(xy 15.0205 -421.776285) (xy 15.028247 -421.794981) (xy 15.028672 -421.8051) (xy 15.028672 -422.46169)
			(xy 18.217896 -422.46169) (xy 18.217896 -421.805354) (xy 18.218388 -421.79523) (xy 18.226122 -421.776516)
			(xy 18.240406 -421.762163) (xy 18.259082 -421.754338) (xy 18.269204 -421.753792) (xy 18.777204 -421.753792)
			(xy 18.787357 -421.754218) (xy 18.806108 -421.762014) (xy 18.820431 -421.776409) (xy 18.828132 -421.795199)
			(xy 18.828512 -421.805354) (xy 18.828512 -422.130474) (xy 24.87676 -422.130474) (xy 24.87676 -421.266874)
			(xy 24.877246 -421.239605) (xy 24.885008 -421.185621) (xy 24.900373 -421.133291) (xy 24.92303 -421.083681)
			(xy 24.952516 -421.0378) (xy 24.988231 -420.996583) (xy 25.029448 -420.960868) (xy 25.075329 -420.931382)
			(xy 25.124939 -420.908725) (xy 25.177269 -420.89336) (xy 25.231253 -420.885598) (xy 25.285791 -420.885598)
			(xy 25.339775 -420.89336) (xy 25.392105 -420.908725) (xy 25.441715 -420.931382) (xy 25.487596 -420.960868)
			(xy 25.528813 -420.996583) (xy 25.564528 -421.0378) (xy 25.594014 -421.083681) (xy 25.616671 -421.133291)
			(xy 25.632036 -421.185621) (xy 25.639798 -421.239605) (xy 25.640284 -421.266874) (xy 25.640284 -421.726974)
			(xy 27.323192 -421.726974) (xy 27.323192 -421.672426) (xy 27.330955 -421.618434) (xy 27.346324 -421.566097)
			(xy 27.368985 -421.51648) (xy 27.398477 -421.470593) (xy 27.4342 -421.429371) (xy 27.475427 -421.393652)
			(xy 27.521317 -421.364165) (xy 27.570936 -421.341509) (xy 27.623276 -421.326146) (xy 27.677268 -421.318389)
			(xy 27.704542 -421.317928) (xy 28.568142 -421.317928) (xy 28.595409 -421.318437) (xy 28.649386 -421.326204)
			(xy 28.701709 -421.341572) (xy 28.751313 -421.36423) (xy 28.797187 -421.393716) (xy 28.838399 -421.429431)
			(xy 28.874109 -421.470646) (xy 28.90359 -421.516524) (xy 28.926243 -421.56613) (xy 28.941605 -421.618455)
			(xy 28.949366 -421.672433) (xy 28.949366 -421.726967) (xy 28.941605 -421.780945) (xy 28.926243 -421.83327)
			(xy 28.90359 -421.882876) (xy 28.874109 -421.928754) (xy 28.838399 -421.969969) (xy 28.797187 -422.005684)
			(xy 28.751313 -422.03517) (xy 28.701709 -422.057828) (xy 28.649386 -422.073196) (xy 28.595409 -422.080963)
			(xy 28.568142 -422.081452) (xy 27.704542 -422.081452) (xy 27.677268 -422.081011) (xy 27.623276 -422.073254)
			(xy 27.570936 -422.057891) (xy 27.521317 -422.035235) (xy 27.475427 -422.005748) (xy 27.4342 -421.970029)
			(xy 27.398477 -421.928807) (xy 27.368985 -421.88292) (xy 27.346324 -421.833303) (xy 27.330955 -421.780966)
			(xy 27.323192 -421.726974) (xy 25.640284 -421.726974) (xy 25.640284 -422.130474) (xy 25.639798 -422.157743)
			(xy 25.632036 -422.211727) (xy 25.616671 -422.264057) (xy 25.594014 -422.313667) (xy 25.564528 -422.359548)
			(xy 25.528813 -422.400765) (xy 25.487596 -422.43648) (xy 25.441715 -422.465966) (xy 25.392105 -422.488623)
			(xy 25.339775 -422.503988) (xy 25.285791 -422.51175) (xy 25.231253 -422.51175) (xy 25.177269 -422.503988)
			(xy 25.124939 -422.488623) (xy 25.075329 -422.465966) (xy 25.029448 -422.43648) (xy 24.988231 -422.400765)
			(xy 24.952516 -422.359548) (xy 24.92303 -422.313667) (xy 24.900373 -422.264057) (xy 24.885008 -422.211727)
			(xy 24.877246 -422.157743) (xy 24.87676 -422.130474) (xy 18.828512 -422.130474) (xy 18.828512 -422.46169)
			(xy 18.827967 -422.47181) (xy 18.820252 -422.490521) (xy 18.805984 -422.504876) (xy 18.787321 -422.512704)
			(xy 18.777204 -422.513252) (xy 18.269204 -422.513252) (xy 18.259057 -422.512776) (xy 18.240314 -422.504992)
			(xy 18.225993 -422.490612) (xy 18.218284 -422.471839) (xy 18.217896 -422.46169) (xy 15.028672 -422.46169)
			(xy 15.028166 -422.471815) (xy 15.020443 -422.490533) (xy 15.006163 -422.504889) (xy 14.987486 -422.512711)
			(xy 14.977364 -422.513252) (xy 14.469364 -422.513252) (xy 14.459259 -422.512746) (xy 14.44059 -422.505006)
			(xy 14.426299 -422.490716) (xy 14.418556 -422.472049) (xy 14.418056 -422.461944) (xy 7.00913 -422.461944)
			(xy 7.00913 -422.638988) (xy 38.761852 -422.638988) (xy 38.766091 -422.582249) (xy 38.778708 -422.52677)
			(xy 38.799426 -422.473779) (xy 38.827783 -422.424453) (xy 38.863151 -422.379885) (xy 38.88359 -422.36009)
			(xy 38.890194 -422.353994) (xy 38.898322 -422.337738) (xy 38.907974 -422.254172) (xy 38.903402 -422.236646)
			(xy 38.898322 -422.229026) (xy 38.894218 -422.222503) (xy 38.88971 -422.207773) (xy 38.889432 -422.20007)
			(xy 38.889432 -421.92067) (xy 38.889909 -421.910511) (xy 38.897692 -421.891742) (xy 38.912062 -421.877378)
			(xy 38.930835 -421.869604) (xy 38.940994 -421.869108) (xy 40.210994 -421.869108) (xy 40.221148 -421.869638)
			(xy 40.239911 -421.877404) (xy 40.254275 -421.891759) (xy 40.262055 -421.910517) (xy 40.262556 -421.92067)
			(xy 40.262556 -422.20007) (xy 40.262283 -422.207772) (xy 40.257758 -422.222495) (xy 40.253666 -422.229026)
			(xy 40.248586 -422.236646) (xy 40.244014 -422.254172) (xy 40.253666 -422.337738) (xy 40.261794 -422.353994)
			(xy 40.268398 -422.36009) (xy 40.288813 -422.379905) (xy 40.324171 -422.424472) (xy 40.35252 -422.473796)
			(xy 40.373231 -422.526782) (xy 40.385845 -422.582256) (xy 40.390082 -422.638988) (xy 40.385848 -422.69572)
			(xy 40.373238 -422.751194) (xy 40.352531 -422.804182) (xy 40.324185 -422.853507) (xy 40.28883 -422.898077)
			(xy 40.268398 -422.917874) (xy 40.261794 -422.92397) (xy 40.253666 -422.940226) (xy 40.244268 -423.024046)
			(xy 40.248586 -423.041318) (xy 40.253666 -423.048938) (xy 40.257728 -423.055411) (xy 40.258476 -423.057828)
			(xy 41.652952 -423.057828) (xy 41.652952 -422.194228) (xy 41.653438 -422.166959) (xy 41.6612 -422.112975)
			(xy 41.676565 -422.060645) (xy 41.699222 -422.011035) (xy 41.728708 -421.965154) (xy 41.764423 -421.923937)
			(xy 41.80564 -421.888222) (xy 41.851521 -421.858736) (xy 41.901131 -421.836079) (xy 41.953461 -421.820714)
			(xy 42.007445 -421.812952) (xy 42.061983 -421.812952) (xy 42.115967 -421.820714) (xy 42.168297 -421.836079)
			(xy 42.217907 -421.858736) (xy 42.263788 -421.888222) (xy 42.305005 -421.923937) (xy 42.34072 -421.965154)
			(xy 42.370206 -422.011035) (xy 42.392863 -422.060645) (xy 42.408228 -422.112975) (xy 42.41599 -422.166959)
			(xy 42.416476 -422.194228) (xy 42.416476 -423.057828) (xy 42.41599 -423.085097) (xy 42.408228 -423.139081)
			(xy 42.392863 -423.191411) (xy 42.370206 -423.241021) (xy 42.34072 -423.286902) (xy 42.305005 -423.328119)
			(xy 42.263788 -423.363834) (xy 42.217907 -423.39332) (xy 42.168297 -423.415977) (xy 42.115967 -423.431342)
			(xy 42.061983 -423.439104) (xy 42.007445 -423.439104) (xy 41.953461 -423.431342) (xy 41.901131 -423.415977)
			(xy 41.851521 -423.39332) (xy 41.80564 -423.363834) (xy 41.764423 -423.328119) (xy 41.728708 -423.286902)
			(xy 41.699222 -423.241021) (xy 41.676565 -423.191411) (xy 41.6612 -423.139081) (xy 41.653438 -423.085097)
			(xy 41.652952 -423.057828) (xy 40.258476 -423.057828) (xy 40.262245 -423.070004) (xy 40.262556 -423.07764)
			(xy 40.262556 -423.35704) (xy 40.262112 -423.36719) (xy 40.254314 -423.385932) (xy 40.239925 -423.400252)
			(xy 40.221146 -423.40796) (xy 40.210994 -423.408348) (xy 38.940994 -423.408348) (xy 38.930865 -423.407878)
			(xy 38.912142 -423.400146) (xy 38.897785 -423.385854) (xy 38.889969 -423.367166) (xy 38.889432 -423.35704)
			(xy 38.889432 -423.07764) (xy 38.88972 -423.070002) (xy 38.894253 -423.05541) (xy 38.898322 -423.048938)
			(xy 38.903053 -423.0413) (xy 38.907343 -423.023864) (xy 38.906704 -423.014902) (xy 38.898322 -422.940226)
			(xy 38.890194 -422.92397) (xy 38.88359 -422.917874) (xy 38.863134 -422.898097) (xy 38.827769 -422.853527)
			(xy 38.799415 -422.804199) (xy 38.778701 -422.751207) (xy 38.766087 -422.695726) (xy 38.761852 -422.638988)
			(xy 7.00913 -422.638988) (xy 7.00913 -423.7482) (xy 32.69742 -423.7482) (xy 32.69742 -423.27195)
			(xy 32.697967 -423.261829) (xy 32.705675 -423.243113) (xy 32.719943 -423.228755) (xy 32.73861 -423.220931)
			(xy 32.748728 -423.220388) (xy 33.256728 -423.220388) (xy 33.266837 -423.220862) (xy 33.285514 -423.228606)
			(xy 33.299807 -423.242907) (xy 33.307543 -423.261587) (xy 33.308036 -423.271696) (xy 33.308036 -423.7482)
			(xy 35.197288 -423.7482) (xy 35.197288 -423.27195) (xy 35.197866 -423.261833) (xy 35.205568 -423.243123)
			(xy 35.219826 -423.228767) (xy 35.238482 -423.220936) (xy 35.248596 -423.220388) (xy 35.756596 -423.220388)
			(xy 35.766703 -423.220888) (xy 35.785379 -423.228622) (xy 35.799673 -423.242914) (xy 35.80741 -423.261589)
			(xy 35.807904 -423.271696) (xy 35.807904 -423.7482) (xy 35.807484 -423.758322) (xy 35.799737 -423.777025)
			(xy 35.785421 -423.791339) (xy 35.766718 -423.799085) (xy 35.756596 -423.799508) (xy 35.248596 -423.799508)
			(xy 35.238488 -423.799018) (xy 35.219811 -423.791281) (xy 35.205517 -423.776985) (xy 35.197781 -423.758308)
			(xy 35.197288 -423.7482) (xy 33.308036 -423.7482) (xy 33.307516 -423.758304) (xy 33.299785 -423.776976)
			(xy 33.285499 -423.791269) (xy 33.266832 -423.79901) (xy 33.256728 -423.799508) (xy 32.748728 -423.799508)
			(xy 32.738608 -423.799061) (xy 32.719907 -423.791324) (xy 32.705592 -423.777017) (xy 32.697844 -423.758319)
			(xy 32.69742 -423.7482) (xy 7.00913 -423.7482) (xy 7.00913 -424.46194) (xy 14.418056 -424.46194)
			(xy 14.418056 -423.80535) (xy 14.418568 -423.795225) (xy 14.426282 -423.776501) (xy 14.440561 -423.762143)
			(xy 14.459241 -423.754325) (xy 14.469364 -423.753788) (xy 14.977364 -423.753788) (xy 14.987483 -423.754245)
			(xy 15.006183 -423.761979) (xy 15.020498 -423.776283) (xy 15.028247 -423.794978) (xy 15.028672 -423.805096)
			(xy 15.028672 -424.461686) (xy 18.217896 -424.461686) (xy 18.217896 -423.80535) (xy 18.218466 -423.795232)
			(xy 18.22617 -423.77652) (xy 18.24043 -423.762164) (xy 18.259089 -423.754335) (xy 18.269204 -423.753788)
			(xy 18.777204 -423.753788) (xy 18.787357 -423.754218) (xy 18.806107 -423.762013) (xy 18.82043 -423.776407)
			(xy 18.828131 -423.795195) (xy 18.828512 -423.80535) (xy 18.828512 -424.461686) (xy 18.827964 -424.471805)
			(xy 18.82025 -424.490516) (xy 18.805983 -424.504871) (xy 18.78732 -424.5127) (xy 18.777204 -424.513248)
			(xy 18.269204 -424.513248) (xy 18.259056 -424.512776) (xy 18.240313 -424.504991) (xy 18.225991 -424.49061)
			(xy 18.218283 -424.471836) (xy 18.217896 -424.461686) (xy 15.028672 -424.461686) (xy 15.028162 -424.47181)
			(xy 15.020441 -424.490529) (xy 15.006162 -424.504885) (xy 14.987486 -424.512707) (xy 14.977364 -424.513248)
			(xy 14.469364 -424.513248) (xy 14.459259 -424.512746) (xy 14.440589 -424.505005) (xy 14.426297 -424.490714)
			(xy 14.418555 -424.472045) (xy 14.418056 -424.46194) (xy 7.00913 -424.46194) (xy 7.00913 -425.887642)
			(xy 10.204704 -425.887642) (xy 10.204704 -425.024042) (xy 10.20519 -424.996773) (xy 10.212952 -424.942789)
			(xy 10.228317 -424.890459) (xy 10.250974 -424.840849) (xy 10.28046 -424.794968) (xy 10.316175 -424.753751)
			(xy 10.357392 -424.718036) (xy 10.403273 -424.68855) (xy 10.452883 -424.665893) (xy 10.505213 -424.650528)
			(xy 10.559197 -424.642766) (xy 10.613735 -424.642766) (xy 10.667719 -424.650528) (xy 10.720049 -424.665893)
			(xy 10.769659 -424.68855) (xy 10.81554 -424.718036) (xy 10.856757 -424.753751) (xy 10.892472 -424.794968)
			(xy 10.921958 -424.840849) (xy 10.944615 -424.890459) (xy 10.95998 -424.942789) (xy 10.967742 -424.996773)
			(xy 10.968228 -425.024042) (xy 10.968228 -425.328334) (xy 21.942552 -425.328334) (xy 21.942552 -424.464734)
			(xy 21.943038 -424.437465) (xy 21.9508 -424.383481) (xy 21.966165 -424.331151) (xy 21.988822 -424.281541)
			(xy 22.018308 -424.23566) (xy 22.054023 -424.194443) (xy 22.09524 -424.158728) (xy 22.141121 -424.129242)
			(xy 22.190731 -424.106585) (xy 22.243061 -424.09122) (xy 22.297045 -424.083458) (xy 22.351583 -424.083458)
			(xy 22.405567 -424.09122) (xy 22.457897 -424.106585) (xy 22.507507 -424.129242) (xy 22.553388 -424.158728)
			(xy 22.594605 -424.194443) (xy 22.63032 -424.23566) (xy 22.659806 -424.281541) (xy 22.682463 -424.331151)
			(xy 22.691108 -424.360594) (xy 58.141108 -424.360594) (xy 58.141108 -421.81907) (xy 58.141586 -421.806957)
			(xy 58.149077 -421.783918) (xy 58.163319 -421.764319) (xy 58.182918 -421.750077) (xy 58.205957 -421.742586)
			(xy 58.21807 -421.742108) (xy 59.15787 -421.742108) (xy 59.16998 -421.742637) (xy 59.193017 -421.750112)
			(xy 59.207184 -421.760396) (xy 60.141104 -421.760396) (xy 60.141104 -419.218872) (xy 60.141536 -419.20682)
			(xy 60.148977 -419.183893) (xy 60.163125 -419.164377) (xy 60.182601 -419.150175) (xy 60.205507 -419.14267)
			(xy 60.217558 -419.142164) (xy 61.157866 -419.142164) (xy 61.169956 -419.142637) (xy 61.19296 -419.150087)
			(xy 61.212542 -419.164271) (xy 61.226793 -419.183805) (xy 61.234322 -419.206783) (xy 61.234828 -419.218872)
			(xy 61.234828 -421.760396) (xy 61.234337 -421.772443) (xy 61.226909 -421.795364) (xy 61.212775 -421.814877)
			(xy 61.193313 -421.829082) (xy 61.170419 -421.836593) (xy 61.158374 -421.837104) (xy 60.218066 -421.837104)
			(xy 60.205979 -421.836623) (xy 60.182985 -421.829162) (xy 60.163409 -421.814977) (xy 60.149158 -421.79545)
			(xy 60.141619 -421.772481) (xy 60.141104 -421.760396) (xy 59.207184 -421.760396) (xy 59.212617 -421.76434)
			(xy 59.22686 -421.783929) (xy 59.234354 -421.80696) (xy 59.234832 -421.81907) (xy 59.234832 -424.360594)
			(xy 62.1411 -424.360594) (xy 62.1411 -421.81907) (xy 62.141585 -421.806958) (xy 62.149076 -421.78392)
			(xy 62.163316 -421.764322) (xy 62.182913 -421.75008) (xy 62.20595 -421.742587) (xy 62.218062 -421.742108)
			(xy 63.157862 -421.742108) (xy 63.16998 -421.742592) (xy 63.193032 -421.75007) (xy 63.207258 -421.760396)
			(xy 68.141088 -421.760396) (xy 68.141088 -419.218872) (xy 68.141536 -419.206822) (xy 68.148975 -419.183897)
			(xy 68.163119 -419.164383) (xy 68.182591 -419.15018) (xy 68.205493 -419.142672) (xy 68.217542 -419.142164)
			(xy 69.15785 -419.142164) (xy 69.169939 -419.14265) (xy 69.192942 -419.150096) (xy 69.212525 -419.164277)
			(xy 69.226777 -419.183808) (xy 69.234306 -419.206784) (xy 69.234812 -419.218872) (xy 69.234812 -420.760398)
			(xy 70.141084 -420.760398) (xy 70.141084 -418.218874) (xy 70.141438 -418.206745) (xy 70.148943 -418.183678)
			(xy 70.16321 -418.164059) (xy 70.182842 -418.14981) (xy 70.205917 -418.142327) (xy 70.218046 -418.141912)
			(xy 71.157846 -418.141912) (xy 71.16996 -418.142372) (xy 71.193001 -418.149869) (xy 71.212599 -418.164115)
			(xy 71.22684 -418.183717) (xy 71.234331 -418.20676) (xy 71.234808 -418.218874) (xy 71.234808 -418.3761)
			(xy 77.661008 -418.3761) (xy 77.661008 -417.5125) (xy 77.661494 -417.485231) (xy 77.669256 -417.431247)
			(xy 77.684621 -417.378917) (xy 77.707278 -417.329307) (xy 77.736764 -417.283426) (xy 77.772479 -417.242209)
			(xy 77.813696 -417.206494) (xy 77.859577 -417.177008) (xy 77.909187 -417.154351) (xy 77.961517 -417.138986)
			(xy 78.015501 -417.131224) (xy 78.070039 -417.131224) (xy 78.124023 -417.138986) (xy 78.176353 -417.154351)
			(xy 78.225963 -417.177008) (xy 78.271844 -417.206494) (xy 78.313061 -417.242209) (xy 78.348776 -417.283426)
			(xy 78.378262 -417.329307) (xy 78.400919 -417.378917) (xy 78.416284 -417.431247) (xy 78.424046 -417.485231)
			(xy 78.424532 -417.5125) (xy 78.424532 -418.3761) (xy 78.424046 -418.403369) (xy 78.416284 -418.457353)
			(xy 78.400919 -418.509683) (xy 78.378262 -418.559293) (xy 78.348776 -418.605174) (xy 78.313061 -418.646391)
			(xy 78.271844 -418.682106) (xy 78.225963 -418.711592) (xy 78.176353 -418.734249) (xy 78.124023 -418.749614)
			(xy 78.070039 -418.757376) (xy 78.015501 -418.757376) (xy 77.961517 -418.749614) (xy 77.909187 -418.734249)
			(xy 77.859577 -418.711592) (xy 77.813696 -418.682106) (xy 77.772479 -418.646391) (xy 77.736764 -418.605174)
			(xy 77.707278 -418.559293) (xy 77.684621 -418.509683) (xy 77.669256 -418.457353) (xy 77.661494 -418.403369)
			(xy 77.661008 -418.3761) (xy 71.234808 -418.3761) (xy 71.234808 -420.760398) (xy 71.234287 -420.772508)
			(xy 71.226806 -420.795543) (xy 71.212575 -420.815141) (xy 71.192986 -420.829384) (xy 71.169956 -420.83688)
			(xy 71.157846 -420.83736) (xy 70.218046 -420.83736) (xy 70.205925 -420.836901) (xy 70.182868 -420.829421)
			(xy 70.163252 -420.81518) (xy 70.148999 -420.795572) (xy 70.141506 -420.772518) (xy 70.141084 -420.760398)
			(xy 69.234812 -420.760398) (xy 69.234812 -421.760396) (xy 69.234337 -421.772445) (xy 69.226907 -421.795368)
			(xy 69.212769 -421.814883) (xy 69.193303 -421.829087) (xy 69.170405 -421.836595) (xy 69.158358 -421.837104)
			(xy 68.21805 -421.837104) (xy 68.205967 -421.836551) (xy 68.182976 -421.829113) (xy 68.163399 -421.814947)
			(xy 68.149145 -421.795434) (xy 68.141604 -421.772476) (xy 68.141088 -421.760396) (xy 63.207258 -421.760396)
			(xy 63.212645 -421.764306) (xy 63.226899 -421.783907) (xy 63.234398 -421.806953) (xy 63.234824 -421.81907)
			(xy 63.234824 -424.360594) (xy 63.234434 -424.37272) (xy 63.226939 -424.395785) (xy 63.212681 -424.415404)
			(xy 63.193057 -424.429654) (xy 63.169988 -424.437139) (xy 63.157862 -424.437556) (xy 62.218062 -424.437556)
			(xy 62.205945 -424.437121) (xy 62.182899 -424.429622) (xy 62.163298 -424.415371) (xy 62.149058 -424.395761)
			(xy 62.141572 -424.372711) (xy 62.1411 -424.360594) (xy 59.234832 -424.360594) (xy 59.234434 -424.372719)
			(xy 59.22694 -424.395783) (xy 59.212684 -424.415401) (xy 59.193062 -424.429651) (xy 59.169996 -424.437138)
			(xy 59.15787 -424.437556) (xy 58.21807 -424.437556) (xy 58.205953 -424.437114) (xy 58.182908 -424.429618)
			(xy 58.163306 -424.415368) (xy 58.149066 -424.39576) (xy 58.14158 -424.372711) (xy 58.141108 -424.360594)
			(xy 22.691108 -424.360594) (xy 22.697828 -424.383481) (xy 22.70559 -424.437465) (xy 22.706076 -424.464734)
			(xy 22.706076 -425.328334) (xy 22.70559 -425.355603) (xy 22.697828 -425.409587) (xy 22.682463 -425.461917)
			(xy 22.659806 -425.511527) (xy 22.63032 -425.557408) (xy 22.594605 -425.598625) (xy 22.553388 -425.63434)
			(xy 22.507507 -425.663826) (xy 22.457897 -425.686483) (xy 22.405567 -425.701848) (xy 22.351583 -425.70961)
			(xy 22.297045 -425.70961) (xy 22.243061 -425.701848) (xy 22.190731 -425.686483) (xy 22.141121 -425.663826)
			(xy 22.09524 -425.63434) (xy 22.054023 -425.598625) (xy 22.018308 -425.557408) (xy 21.988822 -425.511527)
			(xy 21.966165 -425.461917) (xy 21.9508 -425.409587) (xy 21.943038 -425.355603) (xy 21.942552 -425.328334)
			(xy 10.968228 -425.328334) (xy 10.968228 -425.887642) (xy 10.967742 -425.914911) (xy 10.95998 -425.968895)
			(xy 10.944615 -426.021225) (xy 10.921958 -426.070835) (xy 10.892472 -426.116716) (xy 10.864931 -426.1485)
			(xy 32.69742 -426.1485) (xy 32.69742 -425.671996) (xy 32.697813 -425.661871) (xy 32.705566 -425.643163)
			(xy 32.71989 -425.628849) (xy 32.738603 -425.621107) (xy 32.748728 -425.620688) (xy 33.256728 -425.620688)
			(xy 33.266837 -425.621162) (xy 33.285514 -425.628906) (xy 33.299807 -425.643207) (xy 33.307543 -425.661887)
			(xy 33.308036 -425.671996) (xy 33.308036 -426.148246) (xy 33.308025 -426.1485) (xy 35.197288 -426.1485)
			(xy 35.197288 -425.671996) (xy 35.197782 -425.661889) (xy 35.205518 -425.643213) (xy 35.219813 -425.628918)
			(xy 35.238489 -425.621182) (xy 35.248596 -425.620688) (xy 35.756596 -425.620688) (xy 35.766703 -425.621188)
			(xy 35.785379 -425.628922) (xy 35.799673 -425.643214) (xy 35.80741 -425.661889) (xy 35.807904 -425.671996)
			(xy 35.807904 -426.148246) (xy 35.807412 -426.15837) (xy 35.799678 -426.177084) (xy 35.785394 -426.191437)
			(xy 35.766718 -426.199262) (xy 35.756596 -426.199808) (xy 35.248596 -426.199808) (xy 35.238488 -426.199318)
			(xy 35.219811 -426.191581) (xy 35.205517 -426.177285) (xy 35.197781 -426.158608) (xy 35.197288 -426.1485)
			(xy 33.308025 -426.1485) (xy 33.30761 -426.158379) (xy 33.299863 -426.177105) (xy 33.285558 -426.191461)
			(xy 33.266859 -426.199274) (xy 33.256728 -426.199808) (xy 32.748728 -426.199808) (xy 32.738608 -426.199361)
			(xy 32.719907 -426.191624) (xy 32.705592 -426.177317) (xy 32.697844 -426.158619) (xy 32.69742 -426.1485)
			(xy 10.864931 -426.1485) (xy 10.856757 -426.157933) (xy 10.81554 -426.193648) (xy 10.769659 -426.223134)
			(xy 10.720049 -426.245791) (xy 10.667719 -426.261156) (xy 10.613735 -426.268918) (xy 10.559197 -426.268918)
			(xy 10.505213 -426.261156) (xy 10.452883 -426.245791) (xy 10.403273 -426.223134) (xy 10.357392 -426.193648)
			(xy 10.316175 -426.157933) (xy 10.28046 -426.116716) (xy 10.250974 -426.070835) (xy 10.228317 -426.021225)
			(xy 10.212952 -425.968895) (xy 10.20519 -425.914911) (xy 10.204704 -425.887642) (xy 7.00913 -425.887642)
			(xy 7.00913 -426.741336) (xy 38.521132 -426.741336) (xy 38.521132 -426.385736) (xy 38.521544 -426.373651)
			(xy 38.529006 -426.350663) (xy 38.543211 -426.331109) (xy 38.562766 -426.316905) (xy 38.585755 -426.309443)
			(xy 38.59784 -426.309028) (xy 38.73754 -426.309028) (xy 38.747038 -426.308635) (xy 38.764753 -426.301788)
			(xy 38.778741 -426.288941) (xy 38.78326 -426.28058) (xy 38.823392 -426.19803) (xy 38.827224 -426.189429)
			(xy 38.828822 -426.170678) (xy 38.823507 -426.152625) (xy 38.818058 -426.144944) (xy 38.817804 -426.144944)
			(xy 38.817804 -426.144436) (xy 38.802581 -426.124268) (xy 38.777019 -426.08068) (xy 38.757434 -426.0341)
			(xy 38.744171 -425.985341) (xy 38.737461 -425.935259) (xy 38.737032 -425.909994) (xy 38.737032 -425.909486)
			(xy 38.737436 -425.884254) (xy 38.744119 -425.834235) (xy 38.757341 -425.785534) (xy 38.776869 -425.739002)
			(xy 38.802364 -425.695452) (xy 38.81755 -425.675298) (xy 38.82644 -425.663868) (xy 38.829488 -425.634912)
			(xy 38.783006 -425.539916) (xy 38.778469 -425.531571) (xy 38.764466 -425.518753) (xy 38.746777 -425.511863)
			(xy 38.737286 -425.511468) (xy 38.59784 -425.511468) (xy 38.58573 -425.511049) (xy 38.562699 -425.503557)
			(xy 38.543122 -425.489297) (xy 38.528927 -425.469673) (xy 38.521511 -425.446617) (xy 38.521132 -425.434506)
			(xy 38.521132 -425.078906) (xy 38.521612 -425.066818) (xy 38.529067 -425.043819) (xy 38.54325 -425.024239)
			(xy 38.56278 -425.009988) (xy 38.585753 -425.002455) (xy 38.59784 -425.001944) (xy 40.50284 -425.001944)
			(xy 40.514945 -425.002382) (xy 40.537964 -425.009885) (xy 40.557532 -425.024143) (xy 40.571727 -425.043756)
			(xy 40.579157 -425.066799) (xy 40.579548 -425.078906) (xy 40.579548 -425.434506) (xy 40.579097 -425.446597)
			(xy 40.571638 -425.4696) (xy 40.557447 -425.489181) (xy 40.53791 -425.50343) (xy 40.51493 -425.51096)
			(xy 40.50284 -425.511468) (xy 40.363394 -425.511468) (xy 40.353892 -425.511815) (xy 40.336176 -425.518684)
			(xy 40.32219 -425.531548) (xy 40.317674 -425.539916) (xy 40.271192 -425.634912) (xy 40.27424 -425.663868)
			(xy 40.28313 -425.675298) (xy 40.298295 -425.695466) (xy 40.323781 -425.739017) (xy 40.343306 -425.785546)
			(xy 40.35653 -425.834242) (xy 40.36322 -425.884256) (xy 40.363648 -425.909486) (xy 40.363648 -425.909994)
			(xy 40.363243 -425.935286) (xy 40.356564 -425.985426) (xy 40.343311 -426.034242) (xy 40.323715 -426.080875)
			(xy 40.298121 -426.124505) (xy 40.282876 -426.14469) (xy 40.282622 -426.144944) (xy 40.277323 -426.152695)
			(xy 40.272072 -426.170702) (xy 40.273606 -426.189395) (xy 40.277288 -426.19803) (xy 40.31742 -426.28058)
			(xy 40.321941 -426.288936) (xy 40.335951 -426.301752) (xy 40.353646 -426.308637) (xy 40.36314 -426.309028)
			(xy 40.50284 -426.309028) (xy 40.51492 -426.309431) (xy 40.537895 -426.316908) (xy 40.557434 -426.33112)
			(xy 40.558913 -426.333158) (xy 41.613836 -426.333158) (xy 41.613836 -425.469558) (xy 41.614322 -425.442307)
			(xy 41.622078 -425.388359) (xy 41.637433 -425.336064) (xy 41.660075 -425.286487) (xy 41.689541 -425.240637)
			(xy 41.725232 -425.199446) (xy 41.766423 -425.163755) (xy 41.812273 -425.134289) (xy 41.86185 -425.111647)
			(xy 41.914145 -425.096292) (xy 41.968093 -425.088536) (xy 42.022595 -425.088536) (xy 42.076543 -425.096292)
			(xy 42.128838 -425.111647) (xy 42.178415 -425.134289) (xy 42.224265 -425.163755) (xy 42.265456 -425.199446)
			(xy 42.301147 -425.240637) (xy 42.330613 -425.286487) (xy 42.353255 -425.336064) (xy 42.36861 -425.388359)
			(xy 42.376366 -425.442307) (xy 42.376852 -425.469558) (xy 42.376852 -426.333158) (xy 42.376366 -426.360409)
			(xy 42.36861 -426.414357) (xy 42.353255 -426.466652) (xy 42.330613 -426.516229) (xy 42.301147 -426.562079)
			(xy 42.265456 -426.60327) (xy 42.224265 -426.638961) (xy 42.178415 -426.668427) (xy 42.128838 -426.691069)
			(xy 42.076543 -426.706424) (xy 42.022595 -426.71418) (xy 41.968093 -426.71418) (xy 41.914145 -426.706424)
			(xy 41.86185 -426.691069) (xy 41.812273 -426.668427) (xy 41.766423 -426.638961) (xy 41.725232 -426.60327)
			(xy 41.689541 -426.562079) (xy 41.660075 -426.516229) (xy 41.637433 -426.466652) (xy 41.622078 -426.414357)
			(xy 41.614322 -426.360409) (xy 41.613836 -426.333158) (xy 40.558913 -426.333158) (xy 40.571626 -426.350673)
			(xy 40.579081 -426.373655) (xy 40.579548 -426.385736) (xy 40.579548 -426.741336) (xy 40.579067 -426.753408)
			(xy 40.5716 -426.77637) (xy 40.557406 -426.795903) (xy 40.537874 -426.810098) (xy 40.514912 -426.817567)
			(xy 40.50284 -426.818044) (xy 38.59784 -426.818044) (xy 38.585763 -426.817554) (xy 38.562788 -426.810102)
			(xy 38.54324 -426.795914) (xy 38.529033 -426.776381) (xy 38.521558 -426.753413) (xy 38.521132 -426.741336)
			(xy 7.00913 -426.741336) (xy 7.00913 -428.615602) (xy 25.13076 -428.615602) (xy 25.13076 -427.752002)
			(xy 25.131246 -427.724733) (xy 25.139008 -427.670749) (xy 25.154373 -427.618419) (xy 25.17703 -427.568809)
			(xy 25.206516 -427.522928) (xy 25.242231 -427.481711) (xy 25.283448 -427.445996) (xy 25.329329 -427.41651)
			(xy 25.378939 -427.393853) (xy 25.431269 -427.378488) (xy 25.485253 -427.370726) (xy 25.539791 -427.370726)
			(xy 25.593775 -427.378488) (xy 25.646105 -427.393853) (xy 25.695715 -427.41651) (xy 25.741596 -427.445996)
			(xy 25.782813 -427.481711) (xy 25.818528 -427.522928) (xy 25.848014 -427.568809) (xy 25.870671 -427.618419)
			(xy 25.886036 -427.670749) (xy 25.893798 -427.724733) (xy 25.894284 -427.752002) (xy 25.894284 -428.211072)
			(xy 26.941204 -428.211072) (xy 26.941204 -428.156528) (xy 26.948966 -428.102539) (xy 26.964334 -428.050205)
			(xy 26.986993 -428.00059) (xy 27.016483 -427.954705) (xy 27.052203 -427.913485) (xy 27.093426 -427.877767)
			(xy 27.139313 -427.848281) (xy 27.188929 -427.825625) (xy 27.241265 -427.810261) (xy 27.295254 -427.802502)
			(xy 27.322526 -427.80204) (xy 28.186126 -427.80204) (xy 28.213394 -427.802524) (xy 28.267375 -427.810289)
			(xy 28.319702 -427.825657) (xy 28.369309 -427.848314) (xy 28.415187 -427.877801) (xy 28.456402 -427.913517)
			(xy 28.492114 -427.954734) (xy 28.495843 -427.960536) (xy 58.141108 -427.960536) (xy 58.141108 -425.419012)
			(xy 58.14157 -425.406962) (xy 58.149001 -425.384035) (xy 58.163141 -425.364518) (xy 58.182611 -425.350315)
			(xy 58.205513 -425.34281) (xy 58.217562 -425.342304) (xy 59.15787 -425.342304) (xy 59.169954 -425.342832)
			(xy 59.192948 -425.350276) (xy 59.212525 -425.364448) (xy 59.226778 -425.383967) (xy 59.234317 -425.40693)
			(xy 59.234832 -425.419012) (xy 59.234832 -427.960536) (xy 59.234372 -427.972585) (xy 59.226933 -427.995506)
			(xy 59.212791 -428.015019) (xy 59.193323 -428.029222) (xy 59.170425 -428.036733) (xy 59.158378 -428.037244)
			(xy 58.21807 -428.037244) (xy 58.205977 -428.036818) (xy 58.182973 -428.029351) (xy 58.163392 -428.015154)
			(xy 58.149143 -427.995612) (xy 58.141615 -427.972627) (xy 58.141108 -427.960536) (xy 28.495843 -427.960536)
			(xy 28.521598 -428.000614) (xy 28.544253 -428.050222) (xy 28.559617 -428.10255) (xy 28.567378 -428.156532)
			(xy 28.567378 -428.211068) (xy 28.559617 -428.26505) (xy 28.544253 -428.317378) (xy 28.521598 -428.366986)
			(xy 28.492114 -428.412866) (xy 28.456402 -428.454083) (xy 28.415187 -428.489799) (xy 28.369309 -428.519286)
			(xy 28.319702 -428.541943) (xy 28.267375 -428.557311) (xy 28.213394 -428.565076) (xy 28.186126 -428.565564)
			(xy 27.322526 -428.565564) (xy 27.295254 -428.565098) (xy 27.241265 -428.557339) (xy 27.188929 -428.541975)
			(xy 27.139313 -428.519319) (xy 27.093426 -428.489833) (xy 27.052203 -428.454115) (xy 27.016483 -428.412895)
			(xy 26.986993 -428.36701) (xy 26.964334 -428.317395) (xy 26.948966 -428.265061) (xy 26.941204 -428.211072)
			(xy 25.894284 -428.211072) (xy 25.894284 -428.615602) (xy 25.893798 -428.642871) (xy 25.886036 -428.696855)
			(xy 25.870671 -428.749185) (xy 25.848014 -428.798795) (xy 25.818528 -428.844676) (xy 25.782813 -428.885893)
			(xy 25.741596 -428.921608) (xy 25.695715 -428.951094) (xy 25.646105 -428.973751) (xy 25.593775 -428.989116)
			(xy 25.539791 -428.996878) (xy 25.485253 -428.996878) (xy 25.431269 -428.989116) (xy 25.378939 -428.973751)
			(xy 25.329329 -428.951094) (xy 25.283448 -428.921608) (xy 25.242231 -428.885893) (xy 25.206516 -428.844676)
			(xy 25.17703 -428.798795) (xy 25.154373 -428.749185) (xy 25.139008 -428.696855) (xy 25.131246 -428.642871)
			(xy 25.13076 -428.615602) (xy 7.00913 -428.615602) (xy 7.00913 -431.560478) (xy 58.141108 -431.560478)
			(xy 58.141108 -429.018954) (xy 58.141572 -429.00684) (xy 58.149068 -428.9838) (xy 58.163313 -428.964202)
			(xy 58.182915 -428.949961) (xy 58.205956 -428.94247) (xy 58.21807 -428.941992) (xy 59.15787 -428.941992)
			(xy 59.169978 -428.942537) (xy 59.193013 -428.95001) (xy 59.207512 -428.960534) (xy 60.141104 -428.960534)
			(xy 60.141104 -426.41901) (xy 60.14162 -426.406899) (xy 60.1491 -426.383862) (xy 60.163332 -426.364263)
			(xy 60.182923 -426.35002) (xy 60.205956 -426.342527) (xy 60.218066 -426.342048) (xy 61.157866 -426.342048)
			(xy 61.169988 -426.342489) (xy 61.193047 -426.349973) (xy 61.212664 -426.364219) (xy 61.226916 -426.383831)
			(xy 61.234407 -426.406888) (xy 61.234828 -426.41901) (xy 61.234828 -427.960536) (xy 62.1411 -427.960536)
			(xy 62.1411 -425.419012) (xy 62.14157 -425.406962) (xy 62.149 -425.384037) (xy 62.163138 -425.364521)
			(xy 62.182606 -425.350318) (xy 62.205506 -425.342811) (xy 62.217554 -425.342304) (xy 63.157862 -425.342304)
			(xy 63.169946 -425.342839) (xy 63.192939 -425.350281) (xy 63.207185 -425.360592) (xy 64.141096 -425.360592)
			(xy 64.141096 -422.819068) (xy 64.141532 -422.807017) (xy 64.148973 -422.784091) (xy 64.16312 -422.764576)
			(xy 64.182595 -422.750373) (xy 64.2055 -422.742867) (xy 64.21755 -422.74236) (xy 65.157858 -422.74236)
			(xy 65.169947 -422.742843) (xy 65.19295 -422.750291) (xy 65.212532 -422.764473) (xy 65.226784 -422.784004)
			(xy 65.234313 -422.80698) (xy 65.23482 -422.819068) (xy 65.23482 -425.360592) (xy 65.234334 -425.37264)
			(xy 65.226905 -425.395562) (xy 65.212771 -425.415076) (xy 65.193307 -425.42928) (xy 65.170412 -425.43679)
			(xy 65.158366 -425.4373) (xy 64.218058 -425.4373) (xy 64.20597 -425.436829) (xy 64.182975 -425.429366)
			(xy 64.163399 -425.415179) (xy 64.149149 -425.395649) (xy 64.141611 -425.372678) (xy 64.141096 -425.360592)
			(xy 63.207185 -425.360592) (xy 63.212517 -425.364451) (xy 63.22677 -425.383968) (xy 63.234309 -425.40693)
			(xy 63.234824 -425.419012) (xy 63.234824 -427.960536) (xy 63.234371 -427.972586) (xy 63.226932 -427.995508)
			(xy 63.212788 -428.015022) (xy 63.193318 -428.029225) (xy 63.170418 -428.036734) (xy 63.15837 -428.037244)
			(xy 62.218062 -428.037244) (xy 62.205969 -428.036825) (xy 62.182964 -428.029356) (xy 62.163384 -428.015157)
			(xy 62.149135 -427.995613) (xy 62.141607 -427.972628) (xy 62.1411 -427.960536) (xy 61.234828 -427.960536)
			(xy 61.234828 -428.960534) (xy 61.234417 -428.972654) (xy 61.226916 -428.995704) (xy 61.21266 -429.015308)
			(xy 61.193043 -429.029547) (xy 61.169986 -429.037027) (xy 61.157866 -429.037496) (xy 60.218066 -429.037496)
			(xy 60.205953 -429.037018) (xy 60.182914 -429.029525) (xy 60.163316 -429.015284) (xy 60.149075 -428.995686)
			(xy 60.141582 -428.972647) (xy 60.141104 -428.960534) (xy 59.207512 -428.960534) (xy 59.212611 -428.964235)
			(xy 59.226855 -428.983819) (xy 59.234351 -429.006846) (xy 59.234832 -429.018954) (xy 59.234832 -431.560478)
			(xy 59.234421 -431.572603) (xy 59.226931 -431.595666) (xy 59.212678 -431.615284) (xy 59.193059 -431.629535)
			(xy 59.169995 -431.637022) (xy 59.15787 -431.63744) (xy 58.21807 -431.63744) (xy 58.205952 -431.637014)
			(xy 58.182904 -431.629515) (xy 58.163301 -431.615262) (xy 58.149061 -431.59565) (xy 58.141578 -431.572597)
			(xy 58.141108 -431.560478) (xy 7.00913 -431.560478) (xy 7.00913 -435.16042) (xy 58.141108 -435.16042)
			(xy 58.141108 -432.618896) (xy 58.141557 -432.606845) (xy 58.148992 -432.583918) (xy 58.163135 -432.564401)
			(xy 58.182608 -432.550199) (xy 58.205512 -432.542694) (xy 58.217562 -432.542188) (xy 59.15787 -432.542188)
			(xy 59.169963 -432.542634) (xy 59.19297 -432.550088) (xy 59.207307 -432.560476) (xy 60.141104 -432.560476)
			(xy 60.141104 -430.018952) (xy 60.141519 -430.006899) (xy 60.148965 -429.983971) (xy 60.163118 -429.964456)
			(xy 60.182597 -429.950254) (xy 60.205506 -429.94275) (xy 60.217558 -429.942244) (xy 61.157866 -429.942244)
			(xy 61.169954 -429.942736) (xy 61.192954 -429.950184) (xy 61.212535 -429.964364) (xy 61.226787 -429.983893)
			(xy 61.234319 -430.006866) (xy 61.234828 -430.018952) (xy 61.234828 -431.560478) (xy 62.1411 -431.560478)
			(xy 62.1411 -429.018954) (xy 62.141572 -429.006841) (xy 62.149067 -428.983803) (xy 62.163311 -428.964205)
			(xy 62.18291 -428.949964) (xy 62.205949 -428.942471) (xy 62.218062 -428.941992) (xy 63.157862 -428.941992)
			(xy 63.16997 -428.942543) (xy 63.193004 -428.950015) (xy 63.207499 -428.960534) (xy 64.141096 -428.960534)
			(xy 64.141096 -426.41901) (xy 64.14162 -426.4069) (xy 64.149099 -426.383864) (xy 64.163329 -426.364266)
			(xy 64.182918 -426.350023) (xy 64.205948 -426.342528) (xy 64.218058 -426.342048) (xy 65.157858 -426.342048)
			(xy 65.16998 -426.342496) (xy 65.193039 -426.349978) (xy 65.212655 -426.364222) (xy 65.226908 -426.383833)
			(xy 65.234399 -426.406889) (xy 65.23482 -426.41901) (xy 65.23482 -427.960536) (xy 66.141092 -427.960536)
			(xy 66.141092 -425.419012) (xy 66.14157 -425.406963) (xy 66.148998 -425.384039) (xy 66.163135 -425.364524)
			(xy 66.182601 -425.35032) (xy 66.205499 -425.342812) (xy 66.217546 -425.342304) (xy 67.157854 -425.342304)
			(xy 67.169938 -425.342846) (xy 67.192931 -425.350286) (xy 67.207172 -425.360592) (xy 68.141088 -425.360592)
			(xy 68.141088 -422.819068) (xy 68.141532 -422.807017) (xy 68.148972 -422.784093) (xy 68.163118 -422.764578)
			(xy 68.18259 -422.750376) (xy 68.205493 -422.742868) (xy 68.217542 -422.74236) (xy 69.15785 -422.74236)
			(xy 69.169939 -422.74285) (xy 69.192941 -422.750296) (xy 69.212524 -422.764475) (xy 69.226775 -422.784006)
			(xy 69.234305 -422.806981) (xy 69.234812 -422.819068) (xy 69.234812 -424.360594) (xy 70.141084 -424.360594)
			(xy 70.141084 -421.81907) (xy 70.141435 -421.806941) (xy 70.148941 -421.783873) (xy 70.163209 -421.764255)
			(xy 70.182842 -421.750006) (xy 70.205917 -421.742523) (xy 70.218046 -421.742108) (xy 71.157846 -421.742108)
			(xy 71.16996 -421.742572) (xy 71.193 -421.750068) (xy 71.207209 -421.760396) (xy 72.14108 -421.760396)
			(xy 72.14108 -419.218872) (xy 72.141535 -419.206822) (xy 72.148973 -419.183899) (xy 72.163116 -419.164386)
			(xy 72.182586 -419.150182) (xy 72.205486 -419.142673) (xy 72.217534 -419.142164) (xy 73.157842 -419.142164)
			(xy 73.169936 -419.142572) (xy 73.192942 -419.150043) (xy 73.212524 -419.164244) (xy 73.226772 -419.183791)
			(xy 73.234298 -419.206779) (xy 73.234804 -419.218872) (xy 73.234804 -420.921688) (xy 75.13828 -420.921688)
			(xy 75.13828 -420.058088) (xy 75.138766 -420.030819) (xy 75.146528 -419.976835) (xy 75.161893 -419.924505)
			(xy 75.18455 -419.874895) (xy 75.214036 -419.829014) (xy 75.249751 -419.787797) (xy 75.290968 -419.752082)
			(xy 75.336849 -419.722596) (xy 75.386459 -419.699939) (xy 75.438789 -419.684574) (xy 75.492773 -419.676812)
			(xy 75.547311 -419.676812) (xy 75.601295 -419.684574) (xy 75.653625 -419.699939) (xy 75.703235 -419.722596)
			(xy 75.749116 -419.752082) (xy 75.790333 -419.787797) (xy 75.826048 -419.829014) (xy 75.855534 -419.874895)
			(xy 75.878191 -419.924505) (xy 75.893556 -419.976835) (xy 75.901318 -420.030819) (xy 75.901804 -420.058088)
			(xy 75.901804 -420.921688) (xy 75.901318 -420.948957) (xy 75.893556 -421.002941) (xy 75.878191 -421.055271)
			(xy 75.855534 -421.104881) (xy 75.844472 -421.122094) (xy 97.149412 -421.122094) (xy 97.149412 -414.328102)
			(xy 97.149934 -414.317948) (xy 97.157703 -414.299183) (xy 97.17206 -414.284819) (xy 97.19082 -414.27704)
			(xy 97.200974 -414.27654) (xy 102.099618 -414.27654) (xy 102.109777 -414.277018) (xy 102.128547 -414.284799)
			(xy 102.142912 -414.29917) (xy 102.150685 -414.317943) (xy 102.15118 -414.328102) (xy 102.15118 -421.122094)
			(xy 102.150662 -421.132249) (xy 102.142893 -421.151015) (xy 102.128535 -421.16538) (xy 102.109773 -421.173157)
			(xy 102.099618 -421.173656) (xy 97.200974 -421.173656) (xy 97.190814 -421.173188) (xy 97.172043 -421.165404)
			(xy 97.157678 -421.15103) (xy 97.149906 -421.132255) (xy 97.149412 -421.122094) (xy 75.844472 -421.122094)
			(xy 75.826048 -421.150762) (xy 75.790333 -421.191979) (xy 75.749116 -421.227694) (xy 75.703235 -421.25718)
			(xy 75.653625 -421.279837) (xy 75.601295 -421.295202) (xy 75.547311 -421.302964) (xy 75.492773 -421.302964)
			(xy 75.438789 -421.295202) (xy 75.386459 -421.279837) (xy 75.336849 -421.25718) (xy 75.290968 -421.227694)
			(xy 75.249751 -421.191979) (xy 75.214036 -421.150762) (xy 75.18455 -421.104881) (xy 75.161893 -421.055271)
			(xy 75.146528 -421.002941) (xy 75.138766 -420.948957) (xy 75.13828 -420.921688) (xy 73.234804 -420.921688)
			(xy 73.234804 -421.760396) (xy 73.234337 -421.772446) (xy 73.226906 -421.79537) (xy 73.212766 -421.814886)
			(xy 73.193298 -421.829089) (xy 73.170398 -421.836596) (xy 73.15835 -421.837104) (xy 72.218042 -421.837104)
			(xy 72.205959 -421.836558) (xy 72.182967 -421.829118) (xy 72.16339 -421.81495) (xy 72.149137 -421.795436)
			(xy 72.141596 -421.772477) (xy 72.14108 -421.760396) (xy 71.207209 -421.760396) (xy 71.212598 -421.764313)
			(xy 71.226839 -421.783915) (xy 71.23433 -421.806956) (xy 71.234808 -421.81907) (xy 71.234808 -424.360594)
			(xy 71.234284 -424.372704) (xy 71.226804 -424.395739) (xy 71.212574 -424.415337) (xy 71.192985 -424.42958)
			(xy 71.169955 -424.437076) (xy 71.157846 -424.437556) (xy 70.218046 -424.437556) (xy 70.205925 -424.437101)
			(xy 70.182867 -424.429621) (xy 70.16325 -424.415378) (xy 70.148998 -424.395769) (xy 70.141505 -424.372715)
			(xy 70.141084 -424.360594) (xy 69.234812 -424.360594) (xy 69.234812 -425.360592) (xy 69.234333 -425.372641)
			(xy 69.226904 -425.395564) (xy 69.212768 -425.415079) (xy 69.193302 -425.429283) (xy 69.170405 -425.436791)
			(xy 69.158358 -425.4373) (xy 68.21805 -425.4373) (xy 68.205967 -425.436751) (xy 68.182975 -425.429313)
			(xy 68.163397 -425.415146) (xy 68.149144 -425.395632) (xy 68.141603 -425.372673) (xy 68.141088 -425.360592)
			(xy 67.207172 -425.360592) (xy 67.212508 -425.364454) (xy 67.226762 -425.38397) (xy 67.234301 -425.40693)
			(xy 67.234816 -425.419012) (xy 67.234816 -427.960536) (xy 67.234371 -427.972587) (xy 67.226931 -427.995511)
			(xy 67.212785 -428.015024) (xy 67.193313 -428.029227) (xy 67.170411 -428.036735) (xy 67.158362 -428.037244)
			(xy 66.218054 -428.037244) (xy 66.20596 -428.036832) (xy 66.182956 -428.02936) (xy 66.163375 -428.01516)
			(xy 66.149127 -427.995615) (xy 66.141599 -427.972628) (xy 66.141092 -427.960536) (xy 65.23482 -427.960536)
			(xy 65.23482 -428.960534) (xy 65.234469 -428.972663) (xy 65.226962 -428.99573) (xy 65.212694 -429.015348)
			(xy 65.193062 -429.029597) (xy 65.169987 -429.03708) (xy 65.157858 -429.037496) (xy 64.218058 -429.037496)
			(xy 64.205945 -429.037025) (xy 64.182906 -429.02953) (xy 64.163308 -429.015287) (xy 64.149066 -428.995687)
			(xy 64.141574 -428.972647) (xy 64.141096 -428.960534) (xy 63.207499 -428.960534) (xy 63.212603 -428.964238)
			(xy 63.226847 -428.98382) (xy 63.234343 -429.006847) (xy 63.234824 -429.018954) (xy 63.234824 -431.560478)
			(xy 63.234421 -431.572603) (xy 63.22693 -431.595668) (xy 63.212675 -431.615287) (xy 63.193054 -431.629537)
			(xy 63.169987 -431.637023) (xy 63.157862 -431.63744) (xy 62.218062 -431.63744) (xy 62.205943 -431.63702)
			(xy 62.182895 -431.62952) (xy 62.163292 -431.615265) (xy 62.149053 -431.595651) (xy 62.14157 -431.572597)
			(xy 62.1411 -431.560478) (xy 61.234828 -431.560478) (xy 61.234828 -432.560476) (xy 61.23432 -432.572522)
			(xy 61.226897 -432.595442) (xy 61.212768 -432.614956) (xy 61.193309 -432.629161) (xy 61.170418 -432.636673)
			(xy 61.158374 -432.637184) (xy 60.218066 -432.637184) (xy 60.205977 -432.636722) (xy 60.182979 -432.629259)
			(xy 60.163402 -432.61507) (xy 60.149152 -432.595538) (xy 60.141616 -432.572563) (xy 60.141104 -432.560476)
			(xy 59.207307 -432.560476) (xy 59.212555 -432.564278) (xy 59.226805 -432.58382) (xy 59.234329 -432.606805)
			(xy 59.234832 -432.618896) (xy 59.234832 -435.16042) (xy 59.234358 -435.172468) (xy 59.226923 -435.195389)
			(xy 59.212785 -435.214901) (xy 59.19332 -435.229105) (xy 59.170424 -435.236616) (xy 59.158378 -435.237128)
			(xy 58.21807 -435.237128) (xy 58.205976 -435.236718) (xy 58.182969 -435.229249) (xy 58.163386 -435.215049)
			(xy 58.149138 -435.195502) (xy 58.141612 -435.172513) (xy 58.141108 -435.16042) (xy 7.00913 -435.16042)
			(xy 7.00913 -438.760616) (xy 58.141108 -438.760616) (xy 58.141108 -436.219092) (xy 58.141553 -436.207041)
			(xy 58.148989 -436.184113) (xy 58.163134 -436.164597) (xy 58.182607 -436.150394) (xy 58.205512 -436.14289)
			(xy 58.217562 -436.142384) (xy 59.15787 -436.142384) (xy 59.169962 -436.142834) (xy 59.192969 -436.150288)
			(xy 59.206951 -436.160418) (xy 60.141104 -436.160418) (xy 60.141104 -433.618894) (xy 60.141606 -433.606783)
			(xy 60.149091 -433.583745) (xy 60.163326 -433.564146) (xy 60.18292 -433.549904) (xy 60.205955 -433.542411)
			(xy 60.218066 -433.541932) (xy 61.157866 -433.541932) (xy 61.169986 -433.542389) (xy 61.193043 -433.549871)
			(xy 61.212658 -433.564113) (xy 61.226911 -433.583721) (xy 61.234405 -433.606774) (xy 61.234828 -433.618894)
			(xy 61.234828 -435.16042) (xy 62.1411 -435.16042) (xy 62.1411 -432.618896) (xy 62.141557 -432.606846)
			(xy 62.14899 -432.58392) (xy 62.163132 -432.564404) (xy 62.182603 -432.550201) (xy 62.205505 -432.542695)
			(xy 62.217554 -432.542188) (xy 63.157862 -432.542188) (xy 63.169954 -432.542641) (xy 63.192962 -432.550093)
			(xy 63.207295 -432.560476) (xy 64.141096 -432.560476) (xy 64.141096 -430.018952) (xy 64.141519 -430.0069)
			(xy 64.148964 -429.983973) (xy 64.163115 -429.964459) (xy 64.182592 -429.950257) (xy 64.205499 -429.942751)
			(xy 64.21755 -429.942244) (xy 65.157858 -429.942244) (xy 65.169946 -429.942743) (xy 65.192946 -429.950189)
			(xy 65.212527 -429.964367) (xy 65.226779 -429.983894) (xy 65.234311 -430.006866) (xy 65.23482 -430.018952)
			(xy 65.23482 -431.560478) (xy 66.141092 -431.560478) (xy 66.141092 -429.018954) (xy 66.141572 -429.006842)
			(xy 66.149066 -428.983805) (xy 66.163308 -428.964208) (xy 66.182905 -428.949966) (xy 66.205942 -428.942472)
			(xy 66.218054 -428.941992) (xy 67.157854 -428.941992) (xy 67.169962 -428.94255) (xy 67.192996 -428.950019)
			(xy 67.207487 -428.960534) (xy 68.141088 -428.960534) (xy 68.141088 -426.41901) (xy 68.14162 -426.406901)
			(xy 68.149098 -426.383867) (xy 68.163326 -426.364269) (xy 68.182913 -426.350025) (xy 68.205941 -426.342529)
			(xy 68.21805 -426.342048) (xy 69.15785 -426.342048) (xy 69.169968 -426.342469) (xy 69.193015 -426.349972)
			(xy 69.212616 -426.364226) (xy 69.226856 -426.383839) (xy 69.23434 -426.406891) (xy 69.234812 -426.41901)
			(xy 69.234812 -427.960536) (xy 70.141084 -427.960536) (xy 70.141084 -425.419012) (xy 70.14157 -425.406964)
			(xy 70.148997 -425.384042) (xy 70.163132 -425.364527) (xy 70.182596 -425.350323) (xy 70.205492 -425.342813)
			(xy 70.217538 -425.342304) (xy 71.157846 -425.342304) (xy 71.169934 -425.342767) (xy 71.19293 -425.350232)
			(xy 71.207224 -425.360592) (xy 72.14108 -425.360592) (xy 72.14108 -422.819068) (xy 72.141532 -422.807018)
			(xy 72.148971 -422.784095) (xy 72.163115 -422.764581) (xy 72.182585 -422.750378) (xy 72.205486 -422.742869)
			(xy 72.217534 -422.74236) (xy 73.157842 -422.74236) (xy 73.169936 -422.742772) (xy 73.192941 -422.750243)
			(xy 73.212522 -422.764443) (xy 73.226771 -422.783989) (xy 73.234298 -422.806975) (xy 73.234804 -422.819068)
			(xy 73.234804 -424.80464) (xy 109.929157 -424.80464) (xy 109.929157 -424.6755) (xy 109.937107 -424.546605)
			(xy 109.952977 -424.418445) (xy 109.976706 -424.291504) (xy 110.008205 -424.166265) (xy 110.047354 -424.043202)
			(xy 110.094005 -423.922783) (xy 110.14798 -423.805464) (xy 110.209075 -423.69169) (xy 110.277058 -423.581893)
			(xy 110.351672 -423.47649) (xy 110.432633 -423.37588) (xy 110.519633 -423.280445) (xy 110.612344 -423.190546)
			(xy 110.710414 -423.106525) (xy 110.813469 -423.028701) (xy 110.92112 -422.957369) (xy 111.032959 -422.892799)
			(xy 111.14856 -422.835237) (xy 111.267485 -422.7849) (xy 111.389284 -422.74198) (xy 111.513494 -422.706639)
			(xy 111.639643 -422.679012) (xy 111.767255 -422.659203) (xy 111.895844 -422.647287) (xy 112.024922 -422.643311)
			(xy 112.154 -422.647287) (xy 112.282589 -422.659203) (xy 112.410201 -422.679012) (xy 112.53635 -422.706639)
			(xy 112.66056 -422.74198) (xy 112.782359 -422.7849) (xy 112.901284 -422.835237) (xy 113.016885 -422.892799)
			(xy 113.128724 -422.957369) (xy 113.236375 -423.028701) (xy 113.33943 -423.106525) (xy 113.4375 -423.190546)
			(xy 113.530211 -423.280445) (xy 113.617211 -423.37588) (xy 113.698172 -423.47649) (xy 113.772786 -423.581893)
			(xy 113.840769 -423.69169) (xy 113.901864 -423.805464) (xy 113.955839 -423.922783) (xy 114.00249 -424.043202)
			(xy 114.041639 -424.166265) (xy 114.073138 -424.291504) (xy 114.096867 -424.418445) (xy 114.112737 -424.546605)
			(xy 114.120687 -424.6755) (xy 114.121184 -424.74007) (xy 114.120687 -424.80464) (xy 114.112737 -424.933535)
			(xy 114.096867 -425.061695) (xy 114.073138 -425.188636) (xy 114.041639 -425.313875) (xy 114.00249 -425.436938)
			(xy 113.955839 -425.557357) (xy 113.901864 -425.674676) (xy 113.840769 -425.78845) (xy 113.772786 -425.898247)
			(xy 113.698172 -426.00365) (xy 113.617211 -426.10426) (xy 113.530211 -426.199695) (xy 113.4375 -426.289594)
			(xy 113.33943 -426.373615) (xy 113.236375 -426.451439) (xy 113.128724 -426.522771) (xy 113.016885 -426.587341)
			(xy 112.901284 -426.644903) (xy 112.782359 -426.69524) (xy 112.66056 -426.73816) (xy 112.53635 -426.773501)
			(xy 112.410201 -426.801128) (xy 112.282589 -426.820937) (xy 112.154 -426.832853) (xy 112.024922 -426.83683)
			(xy 111.895844 -426.832853) (xy 111.767255 -426.820937) (xy 111.639643 -426.801128) (xy 111.513494 -426.773501)
			(xy 111.389284 -426.73816) (xy 111.267485 -426.69524) (xy 111.14856 -426.644903) (xy 111.032959 -426.587341)
			(xy 110.92112 -426.522771) (xy 110.813469 -426.451439) (xy 110.710414 -426.373615) (xy 110.612344 -426.289594)
			(xy 110.519633 -426.199695) (xy 110.432633 -426.10426) (xy 110.351672 -426.00365) (xy 110.277058 -425.898247)
			(xy 110.209075 -425.78845) (xy 110.14798 -425.674676) (xy 110.094005 -425.557357) (xy 110.047354 -425.436938)
			(xy 110.008205 -425.313875) (xy 109.976706 -425.188636) (xy 109.952977 -425.061695) (xy 109.937107 -424.933535)
			(xy 109.929157 -424.80464) (xy 73.234804 -424.80464) (xy 73.234804 -425.360592) (xy 73.234333 -425.372641)
			(xy 73.226903 -425.395566) (xy 73.212765 -425.415082) (xy 73.193297 -425.429285) (xy 73.170398 -425.436792)
			(xy 73.15835 -425.4373) (xy 72.218042 -425.4373) (xy 72.205959 -425.436758) (xy 72.182966 -425.429317)
			(xy 72.163389 -425.415149) (xy 72.149135 -425.395633) (xy 72.141595 -425.372673) (xy 72.14108 -425.360592)
			(xy 71.207224 -425.360592) (xy 71.212507 -425.364421) (xy 71.226757 -425.383953) (xy 71.234294 -425.406925)
			(xy 71.234808 -425.419012) (xy 71.234808 -427.960536) (xy 71.234371 -427.972587) (xy 71.226929 -427.995513)
			(xy 71.212782 -428.015027) (xy 71.193308 -428.02923) (xy 71.170404 -428.036736) (xy 71.158354 -428.037244)
			(xy 70.218046 -428.037244) (xy 70.205957 -428.036753) (xy 70.182955 -428.029307) (xy 70.163373 -428.015127)
			(xy 70.149122 -427.995597) (xy 70.141591 -427.972623) (xy 70.141084 -427.960536) (xy 69.234812 -427.960536)
			(xy 69.234812 -428.960534) (xy 69.234318 -428.972645) (xy 69.226828 -428.995681) (xy 69.21259 -429.015278)
			(xy 69.192996 -429.02952) (xy 69.169961 -429.037016) (xy 69.15785 -429.037496) (xy 68.21805 -429.037496)
			(xy 68.205936 -429.037031) (xy 68.182897 -429.029535) (xy 68.163299 -429.015289) (xy 68.149058 -428.995689)
			(xy 68.141566 -428.972648) (xy 68.141088 -428.960534) (xy 67.207487 -428.960534) (xy 67.212594 -428.96424)
			(xy 67.226839 -428.983822) (xy 67.234335 -429.006847) (xy 67.234816 -429.018954) (xy 67.234816 -431.560478)
			(xy 67.234421 -431.572604) (xy 67.226929 -431.59567) (xy 67.212672 -431.61529) (xy 67.193049 -431.62954)
			(xy 67.16998 -431.637024) (xy 67.157854 -431.63744) (xy 66.218054 -431.63744) (xy 66.205935 -431.637027)
			(xy 66.182886 -431.629525) (xy 66.163284 -431.615268) (xy 66.149044 -431.595653) (xy 66.141562 -431.572598)
			(xy 66.141092 -431.560478) (xy 65.23482 -431.560478) (xy 65.23482 -432.560476) (xy 65.23432 -432.572523)
			(xy 65.226896 -432.595444) (xy 65.212765 -432.614959) (xy 65.193304 -432.629164) (xy 65.170411 -432.636674)
			(xy 65.158366 -432.637184) (xy 64.218058 -432.637184) (xy 64.205969 -432.636729) (xy 64.182971 -432.629264)
			(xy 64.163393 -432.615073) (xy 64.149143 -432.595539) (xy 64.141608 -432.572564) (xy 64.141096 -432.560476)
			(xy 63.207295 -432.560476) (xy 63.212547 -432.564281) (xy 63.226797 -432.583821) (xy 63.234321 -432.606805)
			(xy 63.234824 -432.618896) (xy 63.234824 -435.16042) (xy 63.234357 -435.172469) (xy 63.226922 -435.195391)
			(xy 63.212782 -435.214904) (xy 63.193315 -435.229108) (xy 63.170417 -435.236618) (xy 63.15837 -435.237128)
			(xy 62.218062 -435.237128) (xy 62.205967 -435.236724) (xy 62.18296 -435.229253) (xy 62.163378 -435.215052)
			(xy 62.14913 -435.195503) (xy 62.141604 -435.172514) (xy 62.1411 -435.16042) (xy 61.234828 -435.16042)
			(xy 61.234828 -436.160418) (xy 61.234455 -436.172545) (xy 61.226953 -436.19561) (xy 61.212691 -436.215228)
			(xy 61.193064 -436.229477) (xy 61.169993 -436.236963) (xy 61.157866 -436.23738) (xy 60.218066 -436.23738)
			(xy 60.205951 -436.236918) (xy 60.18291 -436.229423) (xy 60.16331 -436.215178) (xy 60.149069 -436.195576)
			(xy 60.14158 -436.172533) (xy 60.141104 -436.160418) (xy 59.206951 -436.160418) (xy 59.212554 -436.164477)
			(xy 59.226804 -436.184017) (xy 59.234329 -436.207001) (xy 59.234832 -436.219092) (xy 59.234832 -438.760616)
			(xy 59.234354 -438.772664) (xy 59.226921 -438.795584) (xy 59.212784 -438.815097) (xy 59.193319 -438.829301)
			(xy 59.170424 -438.836812) (xy 59.158378 -438.837324) (xy 58.21807 -438.837324) (xy 58.205975 -438.836918)
			(xy 58.182968 -438.829448) (xy 58.163385 -438.815247) (xy 58.149137 -438.795699) (xy 58.141612 -438.77271)
			(xy 58.141108 -438.760616) (xy 7.00913 -438.760616) (xy 7.00913 -439.760614) (xy 60.141104 -439.760614)
			(xy 60.141104 -437.21909) (xy 60.141603 -437.206978) (xy 60.149089 -437.183941) (xy 60.163325 -437.164342)
			(xy 60.182919 -437.1501) (xy 60.205954 -437.142607) (xy 60.218066 -437.142128) (xy 61.157866 -437.142128)
			(xy 61.169986 -437.142589) (xy 61.193042 -437.15007) (xy 61.212657 -437.164312) (xy 61.22691 -437.183918)
			(xy 61.234404 -437.20697) (xy 61.234828 -437.21909) (xy 61.234828 -438.760616) (xy 62.1411 -438.760616)
			(xy 62.1411 -436.219092) (xy 62.141553 -436.207041) (xy 62.148988 -436.184116) (xy 62.163131 -436.1646)
			(xy 62.182602 -436.150397) (xy 62.205505 -436.142891) (xy 62.217554 -436.142384) (xy 63.157862 -436.142384)
			(xy 63.169954 -436.142841) (xy 63.192961 -436.150292) (xy 63.206938 -436.160418) (xy 64.141096 -436.160418)
			(xy 64.141096 -433.618894) (xy 64.141606 -433.606783) (xy 64.14909 -433.583747) (xy 64.163324 -433.564149)
			(xy 64.182915 -433.549906) (xy 64.205948 -433.542412) (xy 64.218058 -433.541932) (xy 65.157858 -433.541932)
			(xy 65.169978 -433.542396) (xy 65.193034 -433.549876) (xy 65.21265 -433.564116) (xy 65.226903 -433.583722)
			(xy 65.234397 -433.606774) (xy 65.23482 -433.618894) (xy 65.23482 -435.16042) (xy 66.141092 -435.16042)
			(xy 66.141092 -432.618896) (xy 66.141556 -432.606846) (xy 66.148989 -432.583922) (xy 66.163129 -432.564407)
			(xy 66.182598 -432.550204) (xy 66.205498 -432.542696) (xy 66.217546 -432.542188) (xy 67.157854 -432.542188)
			(xy 67.169946 -432.542647) (xy 67.192953 -432.550097) (xy 67.207281 -432.560476) (xy 68.141088 -432.560476)
			(xy 68.141088 -430.018952) (xy 68.141519 -430.0069) (xy 68.148963 -429.983975) (xy 68.163112 -429.964461)
			(xy 68.182587 -429.950259) (xy 68.205492 -429.942752) (xy 68.217542 -429.942244) (xy 69.15785 -429.942244)
			(xy 69.169937 -429.94275) (xy 69.192937 -429.950193) (xy 69.212518 -429.96437) (xy 69.22677 -429.983896)
			(xy 69.234303 -430.006866) (xy 69.234812 -430.018952) (xy 69.234812 -431.560478) (xy 70.141084 -431.560478)
			(xy 70.141084 -429.018954) (xy 70.141473 -429.006832) (xy 70.148979 -428.98378) (xy 70.16324 -428.964175)
			(xy 70.182862 -428.949937) (xy 70.205924 -428.942459) (xy 70.218046 -428.941992) (xy 71.157846 -428.941992)
			(xy 71.169958 -428.942472) (xy 71.192995 -428.949966) (xy 71.207537 -428.960534) (xy 72.14108 -428.960534)
			(xy 72.14108 -426.41901) (xy 72.141469 -426.406884) (xy 72.148964 -426.383818) (xy 72.163222 -426.364199)
			(xy 72.182847 -426.349949) (xy 72.205915 -426.342464) (xy 72.218042 -426.342048) (xy 73.157842 -426.342048)
			(xy 73.16996 -426.342476) (xy 73.193006 -426.349976) (xy 73.212608 -426.364229) (xy 73.226848 -426.383841)
			(xy 73.234332 -426.406892) (xy 73.234804 -426.41901) (xy 73.234804 -427.960536) (xy 75.141328 -427.960536)
			(xy 75.141328 -425.419012) (xy 75.141724 -425.406926) (xy 75.149192 -425.383938) (xy 75.163402 -425.364384)
			(xy 75.18296 -425.350181) (xy 75.20595 -425.34272) (xy 75.218036 -425.342304) (xy 76.157836 -425.342304)
			(xy 76.169914 -425.342734) (xy 76.192884 -425.350207) (xy 76.212422 -425.364413) (xy 76.226615 -425.383959)
			(xy 76.234074 -425.406934) (xy 76.234544 -425.419012) (xy 76.234544 -427.960536) (xy 76.234067 -427.972609)
			(xy 76.226599 -427.995571) (xy 76.212405 -428.015105) (xy 76.192871 -428.029299) (xy 76.169909 -428.036767)
			(xy 76.157836 -428.037244) (xy 75.218036 -428.037244) (xy 75.205967 -428.036706) (xy 75.183007 -428.029258)
			(xy 75.163472 -428.015079) (xy 75.149275 -427.995558) (xy 75.141806 -427.972605) (xy 75.141328 -427.960536)
			(xy 73.234804 -427.960536) (xy 73.234804 -428.960534) (xy 73.234318 -428.972646) (xy 73.226827 -428.995683)
			(xy 73.212587 -429.015281) (xy 73.192991 -429.029523) (xy 73.169954 -429.037017) (xy 73.157842 -429.037496)
			(xy 72.218042 -429.037496) (xy 72.205925 -429.037005) (xy 72.182873 -429.029528) (xy 72.16326 -429.015294)
			(xy 72.149006 -428.995695) (xy 72.141507 -428.972651) (xy 72.14108 -428.960534) (xy 71.207537 -428.960534)
			(xy 71.212592 -428.964208) (xy 71.226834 -428.983805) (xy 71.234328 -429.006842) (xy 71.234808 -429.018954)
			(xy 71.234808 -431.560478) (xy 71.23427 -431.572587) (xy 71.226795 -431.595622) (xy 71.212568 -431.61522)
			(xy 71.192983 -431.629464) (xy 71.169954 -431.636959) (xy 71.157846 -431.63744) (xy 70.218046 -431.63744)
			(xy 70.205923 -431.637001) (xy 70.182862 -431.629518) (xy 70.163245 -431.615273) (xy 70.148993 -431.595659)
			(xy 70.141503 -431.5726) (xy 70.141084 -431.560478) (xy 69.234812 -431.560478) (xy 69.234812 -432.560476)
			(xy 69.23432 -432.572524) (xy 69.226895 -432.595447) (xy 69.212762 -432.614962) (xy 69.193299 -432.629166)
			(xy 69.170404 -432.636675) (xy 69.158358 -432.637184) (xy 68.21805 -432.637184) (xy 68.205965 -432.636651)
			(xy 68.18297 -432.62921) (xy 68.163392 -432.61504) (xy 68.149139 -432.595522) (xy 68.141601 -432.572559)
			(xy 68.141088 -432.560476) (xy 67.207281 -432.560476) (xy 67.212538 -432.564284) (xy 67.226788 -432.583823)
			(xy 67.234313 -432.606806) (xy 67.234816 -432.618896) (xy 67.234816 -435.16042) (xy 67.234357 -435.17247)
			(xy 67.226921 -435.195393) (xy 67.212779 -435.214907) (xy 67.19331 -435.22911) (xy 67.17041 -435.236619)
			(xy 67.158362 -435.237128) (xy 66.218054 -435.237128) (xy 66.205959 -435.236731) (xy 66.182951 -435.229258)
			(xy 66.163369 -435.215054) (xy 66.149122 -435.195505) (xy 66.141596 -435.172514) (xy 66.141092 -435.16042)
			(xy 65.23482 -435.16042) (xy 65.23482 -436.160418) (xy 65.234454 -436.172546) (xy 65.226952 -436.195612)
			(xy 65.212688 -436.215231) (xy 65.193058 -436.22948) (xy 65.169986 -436.236964) (xy 65.157858 -436.23738)
			(xy 64.218058 -436.23738) (xy 64.205943 -436.236924) (xy 64.182901 -436.229428) (xy 64.163302 -436.215181)
			(xy 64.149061 -436.195577) (xy 64.141572 -436.172533) (xy 64.141096 -436.160418) (xy 63.206938 -436.160418)
			(xy 63.212545 -436.16448) (xy 63.226795 -436.184019) (xy 63.234321 -436.207002) (xy 63.234824 -436.219092)
			(xy 63.234824 -438.760616) (xy 63.234354 -438.772665) (xy 63.22692 -438.795587) (xy 63.212781 -438.8151)
			(xy 63.193314 -438.829304) (xy 63.170417 -438.836814) (xy 63.15837 -438.837324) (xy 62.218062 -438.837324)
			(xy 62.205967 -438.836924) (xy 62.182959 -438.829453) (xy 62.163377 -438.81525) (xy 62.149129 -438.795701)
			(xy 62.141604 -438.77271) (xy 62.1411 -438.760616) (xy 61.234828 -438.760616) (xy 61.234828 -439.760614)
			(xy 64.141096 -439.760614) (xy 64.141096 -437.21909) (xy 64.141603 -437.206979) (xy 64.149088 -437.183943)
			(xy 64.163322 -437.164345) (xy 64.182914 -437.150102) (xy 64.205947 -437.142608) (xy 64.218058 -437.142128)
			(xy 65.157858 -437.142128) (xy 65.169978 -437.142595) (xy 65.193033 -437.150075) (xy 65.212648 -437.164315)
			(xy 65.226901 -437.18392) (xy 65.234396 -437.206971) (xy 65.23482 -437.21909) (xy 65.23482 -438.760616)
			(xy 66.141092 -438.760616) (xy 66.141092 -436.219092) (xy 66.141553 -436.207042) (xy 66.148987 -436.184118)
			(xy 66.163128 -436.164603) (xy 66.182597 -436.1504) (xy 66.205498 -436.142892) (xy 66.217546 -436.142384)
			(xy 67.157854 -436.142384) (xy 67.169946 -436.142847) (xy 67.192952 -436.150297) (xy 67.206925 -436.160418)
			(xy 68.141088 -436.160418) (xy 68.141088 -433.618894) (xy 68.141606 -433.606784) (xy 68.149089 -433.583749)
			(xy 68.163321 -433.564152) (xy 68.18291 -433.549909) (xy 68.20594 -433.542413) (xy 68.21805 -433.541932)
			(xy 69.15785 -433.541932) (xy 69.169967 -433.542369) (xy 69.19301 -433.549869) (xy 69.212611 -433.564121)
			(xy 69.226851 -433.583729) (xy 69.234338 -433.606777) (xy 69.234812 -433.618894) (xy 69.234812 -435.16042)
			(xy 70.141084 -435.16042) (xy 70.141084 -432.618896) (xy 70.141556 -432.606847) (xy 70.148988 -432.583924)
			(xy 70.163126 -432.56441) (xy 70.182593 -432.550206) (xy 70.205491 -432.542697) (xy 70.217538 -432.542188)
			(xy 71.157846 -432.542188) (xy 71.169943 -432.542569) (xy 71.192953 -432.550044) (xy 71.207333 -432.560476)
			(xy 72.14108 -432.560476) (xy 72.14108 -430.018952) (xy 72.141519 -430.006901) (xy 72.148962 -429.983977)
			(xy 72.163109 -429.964464) (xy 72.182582 -429.950262) (xy 72.205485 -429.942753) (xy 72.217534 -429.942244)
			(xy 73.157842 -429.942244) (xy 73.169934 -429.942672) (xy 73.192937 -429.95014) (xy 73.212516 -429.964337)
			(xy 73.226765 -429.983879) (xy 73.234296 -430.006861) (xy 73.234804 -430.018952) (xy 73.234804 -431.560478)
			(xy 75.141328 -431.560478) (xy 75.141328 -429.018954) (xy 75.141768 -429.006863) (xy 75.149236 -428.983863)
			(xy 75.16343 -428.964285) (xy 75.182968 -428.950036) (xy 75.205947 -428.942503) (xy 75.218036 -428.941992)
			(xy 76.157836 -428.941992) (xy 76.169946 -428.942386) (xy 76.192973 -428.949894) (xy 76.207568 -428.960534)
			(xy 77.141324 -428.960534) (xy 77.141324 -426.41901) (xy 77.141816 -426.406923) (xy 77.149268 -426.383925)
			(xy 77.163449 -426.364346) (xy 77.182976 -426.350095) (xy 77.205946 -426.34256) (xy 77.218032 -426.342048)
			(xy 78.157832 -426.342048) (xy 78.169937 -426.342488) (xy 78.192957 -426.34999) (xy 78.212525 -426.364248)
			(xy 78.22672 -426.38386) (xy 78.234149 -426.406903) (xy 78.23454 -426.41901) (xy 78.23454 -427.960536)
			(xy 79.14132 -427.960536) (xy 79.14132 -425.419012) (xy 79.141724 -425.406927) (xy 79.149191 -425.38394)
			(xy 79.163399 -425.364387) (xy 79.182954 -425.350184) (xy 79.205943 -425.342721) (xy 79.218028 -425.342304)
			(xy 80.157828 -425.342304) (xy 80.169905 -425.34274) (xy 80.192875 -425.350212) (xy 80.212413 -425.364415)
			(xy 80.226606 -425.38396) (xy 80.234066 -425.406935) (xy 80.234536 -425.419012) (xy 80.234536 -427.960536)
			(xy 80.234067 -427.97261) (xy 80.226598 -427.995573) (xy 80.212402 -428.015107) (xy 80.192866 -428.029302)
			(xy 80.169902 -428.036768) (xy 80.157828 -428.037244) (xy 79.218028 -428.037244) (xy 79.205958 -428.036713)
			(xy 79.182998 -428.029262) (xy 79.163464 -428.015082) (xy 79.149267 -427.995559) (xy 79.141797 -427.972605)
			(xy 79.14132 -427.960536) (xy 78.23454 -427.960536) (xy 78.23454 -428.960534) (xy 78.234121 -428.972627)
			(xy 78.226653 -428.995632) (xy 78.212454 -429.015214) (xy 78.19291 -429.029462) (xy 78.169924 -429.03699)
			(xy 78.157832 -429.037496) (xy 77.218032 -429.037496) (xy 77.205924 -429.037056) (xy 77.182898 -429.029565)
			(xy 77.163324 -429.01531) (xy 77.149128 -428.995692) (xy 77.141707 -428.972643) (xy 77.141324 -428.960534)
			(xy 76.207568 -428.960534) (xy 76.212545 -428.964162) (xy 76.226738 -428.983787) (xy 76.23416 -429.006843)
			(xy 76.234544 -429.018954) (xy 76.234544 -431.560478) (xy 76.234074 -431.572568) (xy 76.226621 -431.595571)
			(xy 76.212436 -431.615152) (xy 76.192902 -431.629403) (xy 76.169924 -431.636933) (xy 76.157836 -431.63744)
			(xy 75.218036 -431.63744) (xy 75.205933 -431.636953) (xy 75.182914 -431.629469) (xy 75.163344 -431.615224)
			(xy 75.149146 -431.595619) (xy 75.141718 -431.572582) (xy 75.141328 -431.560478) (xy 73.234804 -431.560478)
			(xy 73.234804 -432.560476) (xy 73.23432 -432.572525) (xy 73.226894 -432.595449) (xy 73.212759 -432.614964)
			(xy 73.193294 -432.629169) (xy 73.170397 -432.636676) (xy 73.15835 -432.637184) (xy 72.218042 -432.637184)
			(xy 72.205957 -432.636657) (xy 72.182962 -432.629215) (xy 72.163383 -432.615043) (xy 72.14913 -432.595523)
			(xy 72.141593 -432.572559) (xy 72.14108 -432.560476) (xy 71.207333 -432.560476) (xy 71.212536 -432.564251)
			(xy 71.226784 -432.583805) (xy 71.234306 -432.6068) (xy 71.234808 -432.618896) (xy 71.234808 -435.16042)
			(xy 71.234357 -435.17247) (xy 71.22692 -435.195395) (xy 71.212776 -435.21491) (xy 71.193305 -435.229113)
			(xy 71.170403 -435.23662) (xy 71.158354 -435.237128) (xy 70.218046 -435.237128) (xy 70.205956 -435.236653)
			(xy 70.182951 -435.229205) (xy 70.163368 -435.215022) (xy 70.149117 -435.195487) (xy 70.141589 -435.172509)
			(xy 70.141084 -435.16042) (xy 69.234812 -435.16042) (xy 69.234812 -436.160418) (xy 69.234305 -436.172529)
			(xy 69.226818 -436.195564) (xy 69.212584 -436.215161) (xy 69.192993 -436.229404) (xy 69.16996 -436.2369)
			(xy 69.15785 -436.23738) (xy 68.21805 -436.23738) (xy 68.205935 -436.236931) (xy 68.182893 -436.229432)
			(xy 68.163293 -436.215184) (xy 68.149053 -436.195578) (xy 68.141564 -436.172534) (xy 68.141088 -436.160418)
			(xy 67.206925 -436.160418) (xy 67.212537 -436.164483) (xy 67.226787 -436.18402) (xy 67.234312 -436.207002)
			(xy 67.234816 -436.219092) (xy 67.234816 -438.760616) (xy 67.234354 -438.772665) (xy 67.226919 -438.795589)
			(xy 67.212778 -438.815103) (xy 67.193309 -438.829306) (xy 67.17041 -438.836815) (xy 67.158362 -438.837324)
			(xy 66.218054 -438.837324) (xy 66.205958 -438.836931) (xy 66.18295 -438.829457) (xy 66.163368 -438.815253)
			(xy 66.14912 -438.795702) (xy 66.141596 -438.77271) (xy 66.141092 -438.760616) (xy 65.23482 -438.760616)
			(xy 65.23482 -439.760614) (xy 68.141088 -439.760614) (xy 68.141088 -437.21909) (xy 68.141603 -437.20698)
			(xy 68.149087 -437.183945) (xy 68.163319 -437.164348) (xy 68.182909 -437.150105) (xy 68.20594 -437.142609)
			(xy 68.21805 -437.142128) (xy 69.15785 -437.142128) (xy 69.169966 -437.142569) (xy 69.193009 -437.150069)
			(xy 69.212609 -437.164319) (xy 69.22685 -437.183927) (xy 69.234337 -437.206974) (xy 69.234812 -437.21909)
			(xy 69.234812 -438.760616) (xy 70.141084 -438.760616) (xy 70.141084 -436.219092) (xy 70.141553 -436.207043)
			(xy 70.148986 -436.18412) (xy 70.163125 -436.164606) (xy 70.182592 -436.150402) (xy 70.205491 -436.142893)
			(xy 70.217538 -436.142384) (xy 71.157846 -436.142384) (xy 71.169942 -436.142769) (xy 71.192952 -436.150244)
			(xy 71.206977 -436.160418) (xy 72.14108 -436.160418) (xy 72.14108 -433.618894) (xy 72.141456 -433.606767)
			(xy 72.148955 -433.583701) (xy 72.163216 -433.564082) (xy 72.182844 -433.549833) (xy 72.205915 -433.542348)
			(xy 72.218042 -433.541932) (xy 73.157842 -433.541932) (xy 73.169958 -433.542376) (xy 73.193002 -433.549874)
			(xy 73.212602 -433.564123) (xy 73.226843 -433.583731) (xy 73.23433 -433.606778) (xy 73.234804 -433.618894)
			(xy 73.234804 -435.16042) (xy 75.141328 -435.16042) (xy 75.141328 -432.618896) (xy 75.14171 -432.606809)
			(xy 75.149183 -432.58382) (xy 75.163396 -432.564267) (xy 75.182956 -432.550064) (xy 75.205949 -432.542603)
			(xy 75.218036 -432.542188) (xy 76.157836 -432.542188) (xy 76.169912 -432.542633) (xy 76.19288 -432.550105)
			(xy 76.207146 -432.560476) (xy 77.141324 -432.560476) (xy 77.141324 -430.018952) (xy 77.141724 -430.006872)
			(xy 77.149203 -429.983898) (xy 77.163415 -429.964358) (xy 77.182969 -429.950167) (xy 77.205951 -429.942711)
			(xy 77.218032 -429.942244) (xy 78.157832 -429.942244) (xy 78.169903 -429.942736) (xy 78.192864 -429.950201)
			(xy 78.212396 -429.964393) (xy 78.226591 -429.983922) (xy 78.234062 -430.006881) (xy 78.23454 -430.018952)
			(xy 78.23454 -431.560478) (xy 79.14132 -431.560478) (xy 79.14132 -429.018954) (xy 79.141768 -429.006864)
			(xy 79.149235 -428.983865) (xy 79.163427 -428.964288) (xy 79.182963 -428.950038) (xy 79.205939 -428.942504)
			(xy 79.218028 -428.941992) (xy 80.157828 -428.941992) (xy 80.169938 -428.942392) (xy 80.192964 -428.949899)
			(xy 80.207555 -428.960534) (xy 81.141316 -428.960534) (xy 81.141316 -426.41901) (xy 81.141816 -426.406923)
			(xy 81.149267 -426.383927) (xy 81.163446 -426.364349) (xy 81.182971 -426.350097) (xy 81.205939 -426.342561)
			(xy 81.218024 -426.342048) (xy 82.157824 -426.342048) (xy 82.169929 -426.342495) (xy 82.192948 -426.349995)
			(xy 82.212516 -426.36425) (xy 82.226712 -426.383862) (xy 82.234141 -426.406904) (xy 82.234532 -426.41901)
			(xy 82.234532 -427.960536) (xy 83.141312 -427.960536) (xy 83.141312 -425.419012) (xy 83.141723 -425.406928)
			(xy 83.14919 -425.383942) (xy 83.163396 -425.36439) (xy 83.182949 -425.350186) (xy 83.205936 -425.342722)
			(xy 83.21802 -425.342304) (xy 84.15782 -425.342304) (xy 84.169897 -425.342748) (xy 84.192867 -425.350217)
			(xy 84.212404 -425.364419) (xy 84.226598 -425.383962) (xy 84.234057 -425.406935) (xy 84.234528 -425.419012)
			(xy 84.234528 -427.960536) (xy 84.234067 -427.97261) (xy 84.226597 -427.995576) (xy 84.212399 -428.01511)
			(xy 84.192861 -428.029304) (xy 84.169895 -428.036769) (xy 84.15782 -428.037244) (xy 83.21802 -428.037244)
			(xy 83.20595 -428.036719) (xy 83.18299 -428.029267) (xy 83.163455 -428.015085) (xy 83.149259 -427.995561)
			(xy 83.141789 -427.972606) (xy 83.141312 -427.960536) (xy 82.234532 -427.960536) (xy 82.234532 -428.960534)
			(xy 82.234121 -428.972628) (xy 82.226652 -428.995635) (xy 82.212452 -429.015216) (xy 82.192905 -429.029465)
			(xy 82.169917 -429.036991) (xy 82.157824 -429.037496) (xy 81.218024 -429.037496) (xy 81.205916 -429.037063)
			(xy 81.182889 -429.02957) (xy 81.163315 -429.015313) (xy 81.14912 -428.995694) (xy 81.141699 -428.972643)
			(xy 81.141316 -428.960534) (xy 80.207555 -428.960534) (xy 80.212536 -428.964165) (xy 80.22673 -428.983789)
			(xy 80.234152 -429.006843) (xy 80.234536 -429.018954) (xy 80.234536 -431.560478) (xy 80.234073 -431.572569)
			(xy 80.22662 -431.595573) (xy 80.212433 -431.615155) (xy 80.192897 -431.629405) (xy 80.169917 -431.636934)
			(xy 80.157828 -431.63744) (xy 79.218028 -431.63744) (xy 79.205925 -431.63696) (xy 79.182905 -431.629473)
			(xy 79.163335 -431.615227) (xy 79.149138 -431.595621) (xy 79.141709 -431.572582) (xy 79.14132 -431.560478)
			(xy 78.23454 -431.560478) (xy 78.23454 -432.560476) (xy 78.234016 -432.572546) (xy 78.226564 -432.595507)
			(xy 78.212382 -432.615042) (xy 78.192857 -432.629238) (xy 78.169902 -432.636707) (xy 78.157832 -432.637184)
			(xy 77.218032 -432.637184) (xy 77.205949 -432.63676) (xy 77.182963 -432.629298) (xy 77.16341 -432.615096)
			(xy 77.149206 -432.595544) (xy 77.141742 -432.572559) (xy 77.141324 -432.560476) (xy 76.207146 -432.560476)
			(xy 76.212416 -432.564307) (xy 76.226609 -432.583849) (xy 76.234072 -432.60682) (xy 76.234544 -432.618896)
			(xy 76.234544 -435.16042) (xy 76.234053 -435.172492) (xy 76.22659 -435.195454) (xy 76.212399 -435.214987)
			(xy 76.192868 -435.229182) (xy 76.169908 -435.236651) (xy 76.157836 -435.237128) (xy 75.218036 -435.237128)
			(xy 75.205957 -435.236657) (xy 75.182979 -435.229202) (xy 75.16343 -435.21501) (xy 75.149224 -435.195471)
			(xy 75.141752 -435.172499) (xy 75.141328 -435.16042) (xy 73.234804 -435.16042) (xy 73.234804 -436.160418)
			(xy 73.234304 -436.172529) (xy 73.226817 -436.195566) (xy 73.212581 -436.215164) (xy 73.192988 -436.229406)
			(xy 73.169953 -436.236901) (xy 73.157842 -436.23738) (xy 72.218042 -436.23738) (xy 72.205923 -436.236905)
			(xy 72.182869 -436.229426) (xy 72.163255 -436.215188) (xy 72.149001 -436.195585) (xy 72.141505 -436.172536)
			(xy 72.14108 -436.160418) (xy 71.206977 -436.160418) (xy 71.212535 -436.16445) (xy 71.226782 -436.184003)
			(xy 71.234305 -436.206997) (xy 71.234808 -436.219092) (xy 71.234808 -438.760616) (xy 71.234354 -438.772666)
			(xy 71.226918 -438.795591) (xy 71.212775 -438.815106) (xy 71.193304 -438.829309) (xy 71.170403 -438.836816)
			(xy 71.158354 -438.837324) (xy 70.218046 -438.837324) (xy 70.205955 -438.836853) (xy 70.18295 -438.829404)
			(xy 70.163366 -438.81522) (xy 70.149115 -438.795685) (xy 70.141589 -438.772705) (xy 70.141084 -438.760616)
			(xy 69.234812 -438.760616) (xy 69.234812 -439.760614) (xy 72.14108 -439.760614) (xy 72.14108 -437.21909)
			(xy 72.141452 -437.206963) (xy 72.148952 -437.183896) (xy 72.163215 -437.164278) (xy 72.182843 -437.150029)
			(xy 72.205914 -437.142544) (xy 72.218042 -437.142128) (xy 73.157842 -437.142128) (xy 73.169958 -437.142576)
			(xy 73.193001 -437.150073) (xy 73.212601 -437.164322) (xy 73.226841 -437.183928) (xy 73.234329 -437.206974)
			(xy 73.234804 -437.21909) (xy 73.234804 -438.760616) (xy 75.141328 -438.760616) (xy 75.141328 -436.219092)
			(xy 75.141706 -436.207005) (xy 75.14918 -436.184016) (xy 75.163394 -436.164463) (xy 75.182956 -436.15026)
			(xy 75.205949 -436.142799) (xy 75.218036 -436.142384) (xy 76.157836 -436.142384) (xy 76.169912 -436.142833)
			(xy 76.192879 -436.150305) (xy 76.206792 -436.160418) (xy 77.141324 -436.160418) (xy 77.141324 -433.618894)
			(xy 77.141802 -433.606806) (xy 77.149259 -433.583808) (xy 77.163443 -433.564229) (xy 77.182973 -433.549978)
			(xy 77.205945 -433.542444) (xy 77.218032 -433.541932) (xy 78.157832 -433.541932) (xy 78.169946 -433.542289)
			(xy 78.19298 -433.549802) (xy 78.212555 -433.564077) (xy 78.226747 -433.583713) (xy 78.234161 -433.606779)
			(xy 78.23454 -433.618894) (xy 78.23454 -435.16042) (xy 79.14132 -435.16042) (xy 79.14132 -432.618896)
			(xy 79.141709 -432.60681) (xy 79.149182 -432.583823) (xy 79.163393 -432.56427) (xy 79.182951 -432.550067)
			(xy 79.205942 -432.542604) (xy 79.218028 -432.542188) (xy 80.157828 -432.542188) (xy 80.169904 -432.54264)
			(xy 80.192871 -432.55011) (xy 80.207132 -432.560476) (xy 81.141316 -432.560476) (xy 81.141316 -430.018952)
			(xy 81.141724 -430.006873) (xy 81.149202 -429.9839) (xy 81.163413 -429.964361) (xy 81.182964 -429.950169)
			(xy 81.205944 -429.942712) (xy 81.218024 -429.942244) (xy 82.157824 -429.942244) (xy 82.169895 -429.942743)
			(xy 82.192855 -429.950206) (xy 82.212387 -429.964396) (xy 82.226583 -429.983924) (xy 82.234053 -430.006881)
			(xy 82.234532 -430.018952) (xy 82.234532 -431.560478) (xy 83.141312 -431.560478) (xy 83.141312 -429.018954)
			(xy 83.141768 -429.006865) (xy 83.149234 -428.983867) (xy 83.163424 -428.964291) (xy 83.182958 -428.950041)
			(xy 83.205932 -428.942505) (xy 83.21802 -428.941992) (xy 84.15782 -428.941992) (xy 84.169929 -428.942399)
			(xy 84.192956 -428.949903) (xy 84.207543 -428.960534) (xy 85.141308 -428.960534) (xy 85.141308 -426.41901)
			(xy 85.141815 -426.406924) (xy 85.149265 -426.383929) (xy 85.163443 -426.364352) (xy 85.182966 -426.3501)
			(xy 85.205932 -426.342562) (xy 85.218016 -426.342048) (xy 86.157816 -426.342048) (xy 86.169921 -426.342502)
			(xy 86.192939 -426.349999) (xy 86.212508 -426.364253) (xy 86.226704 -426.383863) (xy 86.234133 -426.406904)
			(xy 86.234524 -426.41901) (xy 86.234524 -427.960536) (xy 87.141304 -427.960536) (xy 87.141304 -425.419012)
			(xy 87.141723 -425.406929) (xy 87.149189 -425.383944) (xy 87.163393 -425.364393) (xy 87.182944 -425.350189)
			(xy 87.205929 -425.342723) (xy 87.218012 -425.342304) (xy 88.157812 -425.342304) (xy 88.169888 -425.342754)
			(xy 88.192858 -425.350222) (xy 88.212396 -425.364421) (xy 88.226589 -425.383964) (xy 88.234049 -425.406935)
			(xy 88.23452 -425.419012) (xy 88.23452 -427.960536) (xy 88.234067 -427.972611) (xy 88.226596 -427.995578)
			(xy 88.212396 -428.015113) (xy 88.192856 -428.029307) (xy 88.169887 -428.036771) (xy 88.157812 -428.037244)
			(xy 87.218012 -428.037244) (xy 87.205942 -428.036726) (xy 87.182981 -428.029271) (xy 87.163447 -428.015087)
			(xy 87.149251 -427.995562) (xy 87.141781 -427.972606) (xy 87.141304 -427.960536) (xy 86.234524 -427.960536)
			(xy 86.234524 -428.960534) (xy 86.234121 -428.972629) (xy 86.226651 -428.995637) (xy 86.212449 -429.015219)
			(xy 86.1929 -429.029467) (xy 86.16991 -429.036992) (xy 86.157816 -429.037496) (xy 85.218016 -429.037496)
			(xy 85.205908 -429.03707) (xy 85.18288 -429.029574) (xy 85.163307 -429.015315) (xy 85.149112 -428.995695)
			(xy 85.141691 -428.972644) (xy 85.141308 -428.960534) (xy 84.207543 -428.960534) (xy 84.212528 -428.964167)
			(xy 84.226722 -428.98379) (xy 84.234144 -429.006843) (xy 84.234528 -429.018954) (xy 84.234528 -431.560478)
			(xy 84.234073 -431.57257) (xy 84.226619 -431.595575) (xy 84.21243 -431.615158) (xy 84.192892 -431.629408)
			(xy 84.16991 -431.636935) (xy 84.15782 -431.63744) (xy 83.21802 -431.63744) (xy 83.205916 -431.636967)
			(xy 83.182896 -431.629478) (xy 83.163327 -431.61523) (xy 83.14913 -431.595622) (xy 83.141701 -431.572583)
			(xy 83.141312 -431.560478) (xy 82.234532 -431.560478) (xy 82.234532 -432.560476) (xy 82.234016 -432.572547)
			(xy 82.226563 -432.595509) (xy 82.212379 -432.615045) (xy 82.192852 -432.629241) (xy 82.169895 -432.636708)
			(xy 82.157824 -432.637184) (xy 81.218024 -432.637184) (xy 81.20594 -432.636766) (xy 81.182954 -432.629303)
			(xy 81.163401 -432.615099) (xy 81.149197 -432.595546) (xy 81.141734 -432.57256) (xy 81.141316 -432.560476)
			(xy 80.207132 -432.560476) (xy 80.212407 -432.56431) (xy 80.226601 -432.58385) (xy 80.234064 -432.60682)
			(xy 80.234536 -432.618896) (xy 80.234536 -435.16042) (xy 80.234053 -435.172493) (xy 80.226588 -435.195456)
			(xy 80.212396 -435.21499) (xy 80.192863 -435.229185) (xy 80.169901 -435.236652) (xy 80.157828 -435.237128)
			(xy 79.218028 -435.237128) (xy 79.205949 -435.236664) (xy 79.18297 -435.229206) (xy 79.163421 -435.215013)
			(xy 79.149216 -435.195473) (xy 79.141744 -435.172499) (xy 79.14132 -435.16042) (xy 78.23454 -435.16042)
			(xy 78.23454 -436.160418) (xy 78.234108 -436.172511) (xy 78.226644 -436.195515) (xy 78.212449 -436.215097)
			(xy 78.192907 -436.229346) (xy 78.169923 -436.236874) (xy 78.157832 -436.23738) (xy 77.218032 -436.23738)
			(xy 77.205923 -436.236956) (xy 77.182893 -436.229463) (xy 77.163318 -436.215204) (xy 77.149123 -436.195582)
			(xy 77.141705 -436.172528) (xy 77.141324 -436.160418) (xy 76.206792 -436.160418) (xy 76.212415 -436.164505)
			(xy 76.226608 -436.184046) (xy 76.234071 -436.207016) (xy 76.234544 -436.219092) (xy 76.234544 -438.760616)
			(xy 76.23405 -438.772688) (xy 76.226587 -438.795649) (xy 76.212397 -438.815183) (xy 76.192867 -438.829378)
			(xy 76.169908 -438.836847) (xy 76.157836 -438.837324) (xy 75.218036 -438.837324) (xy 75.205957 -438.836857)
			(xy 75.182978 -438.829401) (xy 75.163428 -438.815209) (xy 75.149223 -438.795669) (xy 75.141751 -438.772695)
			(xy 75.141328 -438.760616) (xy 73.234804 -438.760616) (xy 73.234804 -439.760614) (xy 77.141324 -439.760614)
			(xy 77.141324 -437.21909) (xy 77.141799 -437.207002) (xy 77.149256 -437.184003) (xy 77.163441 -437.164425)
			(xy 77.182972 -437.150174) (xy 77.205945 -437.14264) (xy 77.218032 -437.142128) (xy 78.157832 -437.142128)
			(xy 78.169945 -437.142489) (xy 78.192978 -437.150001) (xy 78.212553 -437.164276) (xy 78.226746 -437.183911)
			(xy 78.234161 -437.206975) (xy 78.23454 -437.21909) (xy 78.23454 -438.760616) (xy 79.14132 -438.760616)
			(xy 79.14132 -436.219092) (xy 79.141706 -436.207006) (xy 79.149179 -436.184018) (xy 79.163391 -436.164466)
			(xy 79.182951 -436.150263) (xy 79.205942 -436.1428) (xy 79.218028 -436.142384) (xy 80.157828 -436.142384)
			(xy 80.169903 -436.14284) (xy 80.19287 -436.150309) (xy 80.206779 -436.160418) (xy 81.141316 -436.160418)
			(xy 81.141316 -433.618894) (xy 81.141802 -433.606807) (xy 81.149257 -433.58381) (xy 81.16344 -433.564232)
			(xy 81.182968 -433.549981) (xy 81.205938 -433.542445) (xy 81.218024 -433.541932) (xy 82.157824 -433.541932)
			(xy 82.169937 -433.542296) (xy 82.192971 -433.549806) (xy 82.212546 -433.56408) (xy 82.226739 -433.583715)
			(xy 82.234153 -433.606779) (xy 82.234532 -433.618894) (xy 82.234532 -435.16042) (xy 83.141312 -435.16042)
			(xy 83.141312 -432.618896) (xy 83.141709 -432.606811) (xy 83.14918 -432.583825) (xy 83.16339 -432.564273)
			(xy 83.182946 -432.550069) (xy 83.205935 -432.542606) (xy 83.21802 -432.542188) (xy 84.15782 -432.542188)
			(xy 84.169895 -432.542647) (xy 84.192862 -432.550115) (xy 84.207119 -432.560476) (xy 85.141308 -432.560476)
			(xy 85.141308 -430.018952) (xy 85.141723 -430.006873) (xy 85.149201 -429.983902) (xy 85.16341 -429.964364)
			(xy 85.182959 -429.950172) (xy 85.205937 -429.942713) (xy 85.218016 -429.942244) (xy 86.157816 -429.942244)
			(xy 86.169887 -429.94275) (xy 86.192846 -429.950211) (xy 86.212379 -429.964399) (xy 86.226574 -429.983925)
			(xy 86.234045 -430.006882) (xy 86.234524 -430.018952) (xy 86.234524 -431.560478) (xy 87.141304 -431.560478)
			(xy 87.141304 -429.018954) (xy 87.141767 -429.006866) (xy 87.149232 -428.98387) (xy 87.163421 -428.964293)
			(xy 87.182953 -428.950043) (xy 87.205925 -428.942506) (xy 87.218012 -428.941992) (xy 88.157812 -428.941992)
			(xy 88.169921 -428.942406) (xy 88.192947 -428.949908) (xy 88.207529 -428.960534) (xy 89.1413 -428.960534)
			(xy 89.1413 -426.41901) (xy 89.141815 -426.406925) (xy 89.149264 -426.383931) (xy 89.16344 -426.364355)
			(xy 89.182961 -426.350103) (xy 89.205925 -426.342563) (xy 89.218008 -426.342048) (xy 90.157808 -426.342048)
			(xy 90.169912 -426.342509) (xy 90.192931 -426.350004) (xy 90.212499 -426.364256) (xy 90.226696 -426.383865)
			(xy 90.234125 -426.406905) (xy 90.234516 -426.41901) (xy 90.234516 -428.960534) (xy 90.234121 -428.97263)
			(xy 90.226649 -428.995639) (xy 90.212446 -429.015222) (xy 90.192895 -429.02947) (xy 90.169903 -429.036993)
			(xy 90.157808 -429.037496) (xy 89.218008 -429.037496) (xy 89.205899 -429.037077) (xy 89.182871 -429.029579)
			(xy 89.163298 -429.015319) (xy 89.149103 -428.995697) (xy 89.141683 -428.972644) (xy 89.1413 -428.960534)
			(xy 88.207529 -428.960534) (xy 88.212519 -428.96417) (xy 88.226714 -428.983792) (xy 88.234136 -429.006844)
			(xy 88.23452 -429.018954) (xy 88.23452 -431.560478) (xy 88.234073 -431.57257) (xy 88.226618 -431.595577)
			(xy 88.212427 -431.615161) (xy 88.192887 -431.629411) (xy 88.169903 -431.636936) (xy 88.157812 -431.63744)
			(xy 87.218012 -431.63744) (xy 87.205908 -431.636974) (xy 87.182888 -431.629483) (xy 87.163318 -431.615232)
			(xy 87.149122 -431.595624) (xy 87.141693 -431.572583) (xy 87.141304 -431.560478) (xy 86.234524 -431.560478)
			(xy 86.234524 -432.560476) (xy 86.234067 -432.572556) (xy 86.226608 -432.595535) (xy 86.212413 -432.615084)
			(xy 86.192871 -432.62929) (xy 86.169896 -432.636761) (xy 86.157816 -432.637184) (xy 85.218016 -432.637184)
			(xy 85.205932 -432.636773) (xy 85.182946 -432.629307) (xy 85.163393 -432.615101) (xy 85.149189 -432.595547)
			(xy 85.141726 -432.57256) (xy 85.141308 -432.560476) (xy 84.207119 -432.560476) (xy 84.212399 -432.564313)
			(xy 84.226593 -432.583852) (xy 84.234055 -432.606821) (xy 84.234528 -432.618896) (xy 84.234528 -435.16042)
			(xy 84.234053 -435.172494) (xy 84.226587 -435.195458) (xy 84.212393 -435.214993) (xy 84.192858 -435.229187)
			(xy 84.169894 -435.236653) (xy 84.15782 -435.237128) (xy 83.21802 -435.237128) (xy 83.205948 -435.236619)
			(xy 83.182985 -435.229165) (xy 83.16345 -435.214979) (xy 83.149254 -435.195451) (xy 83.141787 -435.172491)
			(xy 83.141312 -435.16042) (xy 82.234532 -435.16042) (xy 82.234532 -436.160418) (xy 82.234108 -436.172511)
			(xy 82.226643 -436.195517) (xy 82.212446 -436.215099) (xy 82.192902 -436.229348) (xy 82.169916 -436.236875)
			(xy 82.157824 -436.23738) (xy 81.218024 -436.23738) (xy 81.205914 -436.236963) (xy 81.182885 -436.229468)
			(xy 81.163309 -436.215207) (xy 81.149115 -436.195584) (xy 81.141697 -436.172529) (xy 81.141316 -436.160418)
			(xy 80.206779 -436.160418) (xy 80.212406 -436.164508) (xy 80.2266 -436.184048) (xy 80.234063 -436.207017)
			(xy 80.234536 -436.219092) (xy 80.234536 -438.760616) (xy 80.23405 -438.772689) (xy 80.226586 -438.795651)
			(xy 80.212394 -438.815186) (xy 80.192862 -438.829381) (xy 80.169901 -438.836848) (xy 80.157828 -438.837324)
			(xy 79.218028 -438.837324) (xy 79.205948 -438.836864) (xy 79.182969 -438.829406) (xy 79.16342 -438.815211)
			(xy 79.149214 -438.79567) (xy 79.141743 -438.772695) (xy 79.14132 -438.760616) (xy 78.23454 -438.760616)
			(xy 78.23454 -439.760614) (xy 81.141316 -439.760614) (xy 81.141316 -437.21909) (xy 81.141799 -437.207002)
			(xy 81.149255 -437.184006) (xy 81.163439 -437.164428) (xy 81.182967 -437.150177) (xy 81.205938 -437.142641)
			(xy 81.218024 -437.142128) (xy 82.157824 -437.142128) (xy 82.169937 -437.142496) (xy 82.19297 -437.150006)
			(xy 82.212545 -437.164279) (xy 82.226738 -437.183912) (xy 82.234153 -437.206975) (xy 82.234532 -437.21909)
			(xy 82.234532 -438.760616) (xy 83.141312 -438.760616) (xy 83.141312 -436.219092) (xy 83.141706 -436.207007)
			(xy 83.149178 -436.18402) (xy 83.163388 -436.164469) (xy 83.182946 -436.150265) (xy 83.205935 -436.142802)
			(xy 83.21802 -436.142384) (xy 84.15782 -436.142384) (xy 84.169895 -436.142847) (xy 84.192861 -436.150314)
			(xy 84.206765 -436.160418) (xy 85.141308 -436.160418) (xy 85.141308 -433.618894) (xy 85.141802 -433.606807)
			(xy 85.149256 -433.583812) (xy 85.163437 -433.564235) (xy 85.182963 -433.549984) (xy 85.205931 -433.542446)
			(xy 85.218016 -433.541932) (xy 86.157816 -433.541932) (xy 86.169929 -433.542303) (xy 86.192962 -433.549811)
			(xy 86.212538 -433.564083) (xy 86.226731 -433.583716) (xy 86.234145 -433.606779) (xy 86.234524 -433.618894)
			(xy 86.234524 -435.16042) (xy 87.141304 -435.16042) (xy 87.141304 -432.618896) (xy 87.141709 -432.606812)
			(xy 87.149179 -432.583827) (xy 87.163387 -432.564276) (xy 87.182941 -432.550072) (xy 87.205928 -432.542607)
			(xy 87.218012 -432.542188) (xy 88.157812 -432.542188) (xy 88.169887 -432.542654) (xy 88.192854 -432.550119)
			(xy 88.207106 -432.560476) (xy 89.1413 -432.560476) (xy 89.1413 -430.018952) (xy 89.141723 -430.006874)
			(xy 89.1492 -429.983904) (xy 89.163407 -429.964367) (xy 89.182954 -429.950174) (xy 89.20593 -429.942714)
			(xy 89.218008 -429.942244) (xy 90.157808 -429.942244) (xy 90.169878 -429.942757) (xy 90.192837 -429.950216)
			(xy 90.21237 -429.964401) (xy 90.226566 -429.983927) (xy 90.234037 -430.006882) (xy 90.234516 -430.018952)
			(xy 90.234516 -431.360072) (xy 108.40466 -431.360072) (xy 108.405158 -431.275192) (xy 108.413115 -431.105619)
			(xy 108.429011 -430.936605) (xy 108.452812 -430.768522) (xy 108.484466 -430.601739) (xy 108.523902 -430.436623)
			(xy 108.571034 -430.273538) (xy 108.625758 -430.11284) (xy 108.687955 -429.954885) (xy 108.757487 -429.800018)
			(xy 108.834202 -429.648581) (xy 108.91793 -429.500905) (xy 109.008488 -429.357317) (xy 109.105677 -429.218131)
			(xy 109.209284 -429.083654) (xy 109.319079 -428.954181) (xy 109.434823 -428.829996) (xy 109.55626 -428.711373)
			(xy 109.683124 -428.598572) (xy 109.815135 -428.491842) (xy 109.952005 -428.391417) (xy 110.09343 -428.297518)
			(xy 110.239102 -428.21035) (xy 110.3887 -428.130107) (xy 110.541894 -428.056963) (xy 110.698348 -427.991081)
			(xy 110.857718 -427.932604) (xy 111.019654 -427.881662) (xy 111.1838 -427.838366) (xy 111.349795 -427.802811)
			(xy 111.517274 -427.775076) (xy 111.685869 -427.755222) (xy 111.855209 -427.743292) (xy 112.024922 -427.739313)
			(xy 112.194635 -427.743292) (xy 112.363975 -427.755222) (xy 112.53257 -427.775076) (xy 112.700049 -427.802811)
			(xy 112.866044 -427.838366) (xy 113.03019 -427.881662) (xy 113.192126 -427.932604) (xy 113.26825 -427.960536)
			(xy 125.241304 -427.960536) (xy 125.241304 -425.419012) (xy 125.241723 -425.406929) (xy 125.249189 -425.383944)
			(xy 125.263393 -425.364393) (xy 125.282944 -425.350189) (xy 125.305929 -425.342723) (xy 125.318012 -425.342304)
			(xy 126.257812 -425.342304) (xy 126.269888 -425.342754) (xy 126.292858 -425.350222) (xy 126.312396 -425.364421)
			(xy 126.326589 -425.383964) (xy 126.334049 -425.406935) (xy 126.33452 -425.419012) (xy 126.33452 -427.960536)
			(xy 126.334067 -427.972611) (xy 126.326596 -427.995578) (xy 126.312396 -428.015113) (xy 126.292856 -428.029307)
			(xy 126.269887 -428.036771) (xy 126.257812 -428.037244) (xy 125.318012 -428.037244) (xy 125.305942 -428.036726)
			(xy 125.282981 -428.029271) (xy 125.263447 -428.015087) (xy 125.249251 -427.995562) (xy 125.241781 -427.972606)
			(xy 125.241304 -427.960536) (xy 113.26825 -427.960536) (xy 113.351496 -427.991081) (xy 113.50795 -428.056963)
			(xy 113.661144 -428.130107) (xy 113.810742 -428.21035) (xy 113.956414 -428.297518) (xy 114.097839 -428.391417)
			(xy 114.234709 -428.491842) (xy 114.36672 -428.598572) (xy 114.493584 -428.711373) (xy 114.615021 -428.829996)
			(xy 114.730765 -428.954181) (xy 114.84056 -429.083654) (xy 114.944167 -429.218131) (xy 115.041356 -429.357317)
			(xy 115.131914 -429.500905) (xy 115.215642 -429.648581) (xy 115.292357 -429.800018) (xy 115.361889 -429.954885)
			(xy 115.424086 -430.11284) (xy 115.47881 -430.273538) (xy 115.525942 -430.436623) (xy 115.565378 -430.601739)
			(xy 115.597032 -430.768522) (xy 115.620833 -430.936605) (xy 115.636729 -431.105619) (xy 115.644686 -431.275192)
			(xy 115.645184 -431.360072) (xy 115.644698 -431.445674) (xy 115.639268 -431.560478) (xy 125.241304 -431.560478)
			(xy 125.241304 -429.018954) (xy 125.241767 -429.006866) (xy 125.249232 -428.98387) (xy 125.263421 -428.964293)
			(xy 125.282953 -428.950043) (xy 125.305925 -428.942506) (xy 125.318012 -428.941992) (xy 126.257812 -428.941992)
			(xy 126.269921 -428.942406) (xy 126.292947 -428.949908) (xy 126.307529 -428.960534) (xy 127.2413 -428.960534)
			(xy 127.2413 -426.41901) (xy 127.241815 -426.406925) (xy 127.249264 -426.383931) (xy 127.26344 -426.364355)
			(xy 127.282961 -426.350103) (xy 127.305925 -426.342563) (xy 127.318008 -426.342048) (xy 128.257808 -426.342048)
			(xy 128.269912 -426.342509) (xy 128.292931 -426.350004) (xy 128.312499 -426.364256) (xy 128.326696 -426.383865)
			(xy 128.334125 -426.406905) (xy 128.334516 -426.41901) (xy 128.334516 -427.960536) (xy 129.241296 -427.960536)
			(xy 129.241296 -425.419012) (xy 129.241723 -425.40693) (xy 129.249188 -425.383947) (xy 129.26339 -425.364396)
			(xy 129.282939 -425.350191) (xy 129.305922 -425.342724) (xy 129.318004 -425.342304) (xy 130.257804 -425.342304)
			(xy 130.269888 -425.342709) (xy 130.292873 -425.350179) (xy 130.312424 -425.364387) (xy 130.326628 -425.383941)
			(xy 130.334093 -425.406928) (xy 130.334512 -425.419012) (xy 130.334512 -427.960536) (xy 130.334067 -427.972612)
			(xy 130.326595 -427.99558) (xy 130.312393 -428.015116) (xy 130.292851 -428.029309) (xy 130.26988 -428.036772)
			(xy 130.257804 -428.037244) (xy 129.318004 -428.037244) (xy 129.305933 -428.036733) (xy 129.282972 -428.029276)
			(xy 129.263438 -428.01509) (xy 129.249242 -427.995564) (xy 129.241773 -427.972607) (xy 129.241296 -427.960536)
			(xy 128.334516 -427.960536) (xy 128.334516 -428.960534) (xy 128.334121 -428.97263) (xy 128.326649 -428.995639)
			(xy 128.312446 -429.015222) (xy 128.292895 -429.02947) (xy 128.269903 -429.036993) (xy 128.257808 -429.037496)
			(xy 127.318008 -429.037496) (xy 127.305899 -429.037077) (xy 127.282871 -429.029579) (xy 127.263298 -429.015319)
			(xy 127.249103 -428.995697) (xy 127.241683 -428.972644) (xy 127.2413 -428.960534) (xy 126.307529 -428.960534)
			(xy 126.312519 -428.96417) (xy 126.326714 -428.983792) (xy 126.334136 -429.006844) (xy 126.33452 -429.018954)
			(xy 126.33452 -431.560478) (xy 126.334073 -431.57257) (xy 126.326618 -431.595577) (xy 126.312427 -431.615161)
			(xy 126.292887 -431.629411) (xy 126.269903 -431.636936) (xy 126.257812 -431.63744) (xy 125.318012 -431.63744)
			(xy 125.305908 -431.636974) (xy 125.282888 -431.629483) (xy 125.263318 -431.615232) (xy 125.249122 -431.595624)
			(xy 125.241693 -431.572583) (xy 125.241304 -431.560478) (xy 115.639268 -431.560478) (xy 115.63661 -431.616688)
			(xy 115.620446 -431.787128) (xy 115.596243 -431.956613) (xy 115.564055 -432.124765) (xy 115.523953 -432.291207)
			(xy 115.476027 -432.455567) (xy 115.420385 -432.617477) (xy 115.35715 -432.776576) (xy 115.286464 -432.932508)
			(xy 115.208486 -433.084923) (xy 115.12339 -433.233482) (xy 115.031365 -433.377851) (xy 114.932619 -433.517709)
			(xy 114.82737 -433.652742) (xy 114.715856 -433.782648) (xy 114.598325 -433.907137) (xy 114.47504 -434.02593)
			(xy 114.346277 -434.138763) (xy 114.212324 -434.245381) (xy 114.07348 -434.345548) (xy 113.930056 -434.439039)
			(xy 113.782372 -434.525645) (xy 113.630759 -434.605172) (xy 113.475556 -434.677443) (xy 113.396522 -434.710332)
			(xy 113.388621 -434.713964) (xy 113.375731 -434.725623) (xy 113.367472 -434.740915) (xy 113.365788 -434.749448)
			(xy 113.35004 -434.849016) (xy 113.359438 -434.873654) (xy 113.369852 -434.88229) (xy 113.419298 -434.924299)
			(xy 113.513487 -435.013553) (xy 113.601975 -435.108462) (xy 113.644727 -435.16042) (xy 125.241304 -435.16042)
			(xy 125.241304 -432.618896) (xy 125.241709 -432.606812) (xy 125.249179 -432.583827) (xy 125.263387 -432.564276)
			(xy 125.282941 -432.550072) (xy 125.305928 -432.542607) (xy 125.318012 -432.542188) (xy 126.257812 -432.542188)
			(xy 126.269887 -432.542654) (xy 126.292854 -432.550119) (xy 126.307106 -432.560476) (xy 127.2413 -432.560476)
			(xy 127.2413 -430.018952) (xy 127.241723 -430.006874) (xy 127.2492 -429.983904) (xy 127.263407 -429.964367)
			(xy 127.282954 -429.950174) (xy 127.30593 -429.942714) (xy 127.318008 -429.942244) (xy 128.257808 -429.942244)
			(xy 128.269878 -429.942757) (xy 128.292837 -429.950216) (xy 128.31237 -429.964401) (xy 128.326566 -429.983927)
			(xy 128.334037 -430.006882) (xy 128.334516 -430.018952) (xy 128.334516 -431.560478) (xy 129.241296 -431.560478)
			(xy 129.241296 -429.018954) (xy 129.241767 -429.006866) (xy 129.249231 -428.983872) (xy 129.263418 -428.964296)
			(xy 129.282948 -428.950046) (xy 129.305918 -428.942507) (xy 129.318004 -428.941992) (xy 130.257804 -428.941992)
			(xy 130.269912 -428.942413) (xy 130.292938 -428.949912) (xy 130.307517 -428.960534) (xy 131.241292 -428.960534)
			(xy 131.241292 -426.41901) (xy 131.241815 -426.406926) (xy 131.249263 -426.383934) (xy 131.263437 -426.364358)
			(xy 131.282956 -426.350105) (xy 131.305918 -426.342564) (xy 131.318 -426.342048) (xy 132.2578 -426.342048)
			(xy 132.269904 -426.342515) (xy 132.292922 -426.350009) (xy 132.312491 -426.364259) (xy 132.326687 -426.383866)
			(xy 132.334117 -426.406905) (xy 132.334508 -426.41901) (xy 132.334508 -427.960536) (xy 133.241288 -427.960536)
			(xy 133.241288 -425.419012) (xy 133.241723 -425.40693) (xy 133.249187 -425.383949) (xy 133.263387 -425.364399)
			(xy 133.282934 -425.350194) (xy 133.305914 -425.342726) (xy 133.317996 -425.342304) (xy 134.257796 -425.342304)
			(xy 134.26988 -425.342716) (xy 134.292864 -425.350184) (xy 134.312416 -425.36439) (xy 134.32662 -425.383943)
			(xy 134.334085 -425.406928) (xy 134.334504 -425.419012) (xy 134.334504 -427.960536) (xy 134.334067 -427.972613)
			(xy 134.326594 -427.995582) (xy 134.31239 -428.015119) (xy 134.292846 -428.029312) (xy 134.269873 -428.036773)
			(xy 134.257796 -428.037244) (xy 133.317996 -428.037244) (xy 133.305925 -428.03674) (xy 133.282964 -428.02928)
			(xy 133.26343 -428.015093) (xy 133.249234 -427.995565) (xy 133.241765 -427.972607) (xy 133.241288 -427.960536)
			(xy 132.334508 -427.960536) (xy 132.334508 -428.960534) (xy 132.334023 -428.972621) (xy 132.326562 -428.995614)
			(xy 132.312379 -429.01519) (xy 132.292853 -429.029441) (xy 132.269885 -429.03698) (xy 132.2578 -429.037496)
			(xy 131.318 -429.037496) (xy 131.305891 -429.037084) (xy 131.282863 -429.029584) (xy 131.263289 -429.015321)
			(xy 131.249095 -428.995699) (xy 131.241675 -428.972645) (xy 131.241292 -428.960534) (xy 130.307517 -428.960534)
			(xy 130.312511 -428.964173) (xy 130.326706 -428.983793) (xy 130.334128 -429.006844) (xy 130.334512 -429.018954)
			(xy 130.334512 -431.560478) (xy 130.334073 -431.572571) (xy 130.326616 -431.595579) (xy 130.312424 -431.615164)
			(xy 130.292882 -431.629413) (xy 130.269896 -431.636937) (xy 130.257804 -431.63744) (xy 129.318004 -431.63744)
			(xy 129.305899 -431.636981) (xy 129.282879 -431.629488) (xy 129.263309 -431.615236) (xy 129.249113 -431.595625)
			(xy 129.241685 -431.572584) (xy 129.241296 -431.560478) (xy 128.334516 -431.560478) (xy 128.334516 -432.560476)
			(xy 128.334067 -432.572557) (xy 128.326607 -432.595537) (xy 128.31241 -432.615087) (xy 128.292866 -432.629292)
			(xy 128.269888 -432.636762) (xy 128.257808 -432.637184) (xy 127.318008 -432.637184) (xy 127.305923 -432.63678)
			(xy 127.282937 -432.629312) (xy 127.263384 -432.615105) (xy 127.249181 -432.595549) (xy 127.241717 -432.572561)
			(xy 127.2413 -432.560476) (xy 126.307106 -432.560476) (xy 126.31239 -432.564316) (xy 126.326584 -432.583854)
			(xy 126.334047 -432.606821) (xy 126.33452 -432.618896) (xy 126.33452 -435.16042) (xy 126.334053 -435.172494)
			(xy 126.326586 -435.19546) (xy 126.31239 -435.214996) (xy 126.292853 -435.22919) (xy 126.269886 -435.236654)
			(xy 126.257812 -435.237128) (xy 125.318012 -435.237128) (xy 125.30594 -435.236626) (xy 125.282977 -435.229169)
			(xy 125.263441 -435.214982) (xy 125.249246 -435.195452) (xy 125.241779 -435.172492) (xy 125.241304 -435.16042)
			(xy 113.644727 -435.16042) (xy 113.684422 -435.208663) (xy 113.760513 -435.313772) (xy 113.829956 -435.423387)
			(xy 113.892486 -435.537087) (xy 113.947862 -435.654438) (xy 113.995874 -435.77499) (xy 114.036336 -435.89828)
			(xy 114.069094 -436.023838) (xy 114.094022 -436.151181) (xy 114.111025 -436.279823) (xy 114.120038 -436.40927)
			(xy 114.121027 -436.539027) (xy 114.113986 -436.668596) (xy 114.098945 -436.797482) (xy 114.075959 -436.92519)
			(xy 114.045118 -437.051232) (xy 114.006538 -437.175125) (xy 113.960369 -437.296394) (xy 113.906786 -437.414574)
			(xy 113.845996 -437.529214) (xy 113.77823 -437.639874) (xy 113.703749 -437.74613) (xy 113.622838 -437.847575)
			(xy 113.535806 -437.943821) (xy 113.442988 -438.034499) (xy 113.344738 -438.119261) (xy 113.241432 -438.197784)
			(xy 113.133467 -438.269766) (xy 113.021257 -438.334931) (xy 112.90523 -438.39303) (xy 112.785831 -438.443841)
			(xy 112.663518 -438.487169) (xy 112.538759 -438.522847) (xy 112.412032 -438.550739) (xy 112.283822 -438.570739)
			(xy 112.15462 -438.58277) (xy 112.024922 -438.586785) (xy 111.895224 -438.58277) (xy 111.766022 -438.570739)
			(xy 111.637812 -438.550739) (xy 111.511085 -438.522847) (xy 111.386326 -438.487169) (xy 111.264013 -438.443841)
			(xy 111.144614 -438.39303) (xy 111.028587 -438.334931) (xy 110.916377 -438.269766) (xy 110.808412 -438.197784)
			(xy 110.705106 -438.119261) (xy 110.606856 -438.034499) (xy 110.514038 -437.943821) (xy 110.427006 -437.847575)
			(xy 110.346095 -437.74613) (xy 110.271614 -437.639874) (xy 110.203848 -437.529214) (xy 110.143058 -437.414574)
			(xy 110.089475 -437.296394) (xy 110.043306 -437.175125) (xy 110.004726 -437.051232) (xy 109.973885 -436.92519)
			(xy 109.950899 -436.797482) (xy 109.935858 -436.668596) (xy 109.928817 -436.539027) (xy 109.929806 -436.40927)
			(xy 109.938819 -436.279823) (xy 109.955822 -436.151181) (xy 109.98075 -436.023838) (xy 110.013508 -435.89828)
			(xy 110.05397 -435.77499) (xy 110.101982 -435.654438) (xy 110.157358 -435.537087) (xy 110.219888 -435.423387)
			(xy 110.289331 -435.313772) (xy 110.365422 -435.208663) (xy 110.447869 -435.108462) (xy 110.536357 -435.013553)
			(xy 110.630546 -434.924299) (xy 110.679992 -434.88229) (xy 110.690406 -434.873654) (xy 110.699804 -434.849016)
			(xy 110.682024 -434.73624) (xy 110.665768 -434.715412) (xy 110.653322 -434.710332) (xy 110.574304 -434.677407)
			(xy 110.419107 -434.605131) (xy 110.267499 -434.5256) (xy 110.119821 -434.438991) (xy 109.976402 -434.345497)
			(xy 109.837562 -434.245328) (xy 109.703613 -434.138709) (xy 109.574854 -434.025876) (xy 109.451573 -433.907083)
			(xy 109.334045 -433.782595) (xy 109.222533 -433.65269) (xy 109.117287 -433.517659) (xy 109.018541 -433.377804)
			(xy 108.926517 -433.233438) (xy 108.84142 -433.084883) (xy 108.763441 -432.932471) (xy 108.692754 -432.776543)
			(xy 108.629516 -432.617449) (xy 108.57387 -432.455542) (xy 108.52594 -432.291187) (xy 108.485833 -432.124749)
			(xy 108.453638 -431.956601) (xy 108.429428 -431.78712) (xy 108.413257 -431.616683) (xy 108.405161 -431.445673)
			(xy 108.40466 -431.360072) (xy 90.234516 -431.360072) (xy 90.234516 -432.560476) (xy 90.234067 -432.572557)
			(xy 90.226607 -432.595537) (xy 90.21241 -432.615087) (xy 90.192866 -432.629292) (xy 90.169888 -432.636762)
			(xy 90.157808 -432.637184) (xy 89.218008 -432.637184) (xy 89.205923 -432.63678) (xy 89.182937 -432.629312)
			(xy 89.163384 -432.615105) (xy 89.149181 -432.595549) (xy 89.141717 -432.572561) (xy 89.1413 -432.560476)
			(xy 88.207106 -432.560476) (xy 88.21239 -432.564316) (xy 88.226584 -432.583854) (xy 88.234047 -432.606821)
			(xy 88.23452 -432.618896) (xy 88.23452 -435.16042) (xy 88.234053 -435.172494) (xy 88.226586 -435.19546)
			(xy 88.21239 -435.214996) (xy 88.192853 -435.22919) (xy 88.169886 -435.236654) (xy 88.157812 -435.237128)
			(xy 87.218012 -435.237128) (xy 87.20594 -435.236626) (xy 87.182977 -435.229169) (xy 87.163441 -435.214982)
			(xy 87.149246 -435.195452) (xy 87.141779 -435.172492) (xy 87.141304 -435.16042) (xy 86.234524 -435.16042)
			(xy 86.234524 -436.160418) (xy 86.234107 -436.172512) (xy 86.226641 -436.195519) (xy 86.212443 -436.215102)
			(xy 86.192897 -436.229351) (xy 86.169909 -436.236876) (xy 86.157816 -436.23738) (xy 85.218016 -436.23738)
			(xy 85.205906 -436.23697) (xy 85.182876 -436.229472) (xy 85.163301 -436.21521) (xy 85.149106 -436.195585)
			(xy 85.141689 -436.172529) (xy 85.141308 -436.160418) (xy 84.206765 -436.160418) (xy 84.212397 -436.164511)
			(xy 84.226591 -436.18405) (xy 84.234055 -436.207017) (xy 84.234528 -436.219092) (xy 84.234528 -438.760616)
			(xy 84.23405 -438.772689) (xy 84.226585 -438.795654) (xy 84.212391 -438.815189) (xy 84.192857 -438.829383)
			(xy 84.169893 -438.836849) (xy 84.15782 -438.837324) (xy 83.21802 -438.837324) (xy 83.20594 -438.83687)
			(xy 83.182961 -438.82941) (xy 83.163411 -438.815214) (xy 83.149206 -438.795672) (xy 83.141735 -438.772696)
			(xy 83.141312 -438.760616) (xy 82.234532 -438.760616) (xy 82.234532 -439.760614) (xy 85.141308 -439.760614)
			(xy 85.141308 -437.21909) (xy 85.141798 -437.207003) (xy 85.149254 -437.184008) (xy 85.163436 -437.164431)
			(xy 85.182962 -437.150179) (xy 85.205931 -437.142642) (xy 85.218016 -437.142128) (xy 86.157816 -437.142128)
			(xy 86.169929 -437.142503) (xy 86.192961 -437.15001) (xy 86.212536 -437.164281) (xy 86.226729 -437.183914)
			(xy 86.234145 -437.206976) (xy 86.234524 -437.21909) (xy 86.234524 -438.760616) (xy 87.141304 -438.760616)
			(xy 87.141304 -436.219092) (xy 87.141706 -436.207008) (xy 87.149177 -436.184023) (xy 87.163386 -436.164471)
			(xy 87.182941 -436.150268) (xy 87.205928 -436.142803) (xy 87.218012 -436.142384) (xy 88.157812 -436.142384)
			(xy 88.169886 -436.142854) (xy 88.192853 -436.150319) (xy 88.206752 -436.160418) (xy 89.1413 -436.160418)
			(xy 89.1413 -433.618894) (xy 89.141802 -433.606808) (xy 89.149255 -433.583814) (xy 89.163434 -433.564238)
			(xy 89.182958 -433.549986) (xy 89.205924 -433.542447) (xy 89.218008 -433.541932) (xy 90.157808 -433.541932)
			(xy 90.169921 -433.54231) (xy 90.192954 -433.549815) (xy 90.212529 -433.564086) (xy 90.226723 -433.583717)
			(xy 90.234137 -433.60678) (xy 90.234516 -433.618894) (xy 90.234516 -436.160418) (xy 90.234107 -436.172513)
			(xy 90.22664 -436.195522) (xy 90.21244 -436.215105) (xy 90.192892 -436.229353) (xy 90.169902 -436.236877)
			(xy 90.157808 -436.23738) (xy 89.218008 -436.23738) (xy 89.205898 -436.236977) (xy 89.182867 -436.229477)
			(xy 89.163292 -436.215213) (xy 89.149098 -436.195587) (xy 89.14168 -436.17253) (xy 89.1413 -436.160418)
			(xy 88.206752 -436.160418) (xy 88.212389 -436.164514) (xy 88.226583 -436.184051) (xy 88.234047 -436.207018)
			(xy 88.23452 -436.219092) (xy 88.23452 -438.760616) (xy 88.234049 -438.77269) (xy 88.226584 -438.795656)
			(xy 88.212389 -438.815191) (xy 88.192852 -438.829386) (xy 88.169886 -438.83685) (xy 88.157812 -438.837324)
			(xy 87.218012 -438.837324) (xy 87.20594 -438.836826) (xy 87.182976 -438.829369) (xy 87.16344 -438.81518)
			(xy 87.149244 -438.79565) (xy 87.141779 -438.772688) (xy 87.141304 -438.760616) (xy 86.234524 -438.760616)
			(xy 86.234524 -439.760614) (xy 89.1413 -439.760614) (xy 89.1413 -437.21909) (xy 89.141798 -437.207004)
			(xy 89.149253 -437.18401) (xy 89.163433 -437.164434) (xy 89.182957 -437.150182) (xy 89.205924 -437.142643)
			(xy 89.218008 -437.142128) (xy 90.157808 -437.142128) (xy 90.16992 -437.14251) (xy 90.192952 -437.150015)
			(xy 90.212528 -437.164284) (xy 90.226721 -437.183915) (xy 90.234137 -437.206976) (xy 90.234516 -437.21909)
			(xy 90.234516 -438.760616) (xy 125.241304 -438.760616) (xy 125.241304 -436.219092) (xy 125.241706 -436.207008)
			(xy 125.249177 -436.184023) (xy 125.263386 -436.164471) (xy 125.282941 -436.150268) (xy 125.305928 -436.142803)
			(xy 125.318012 -436.142384) (xy 126.257812 -436.142384) (xy 126.269886 -436.142854) (xy 126.292853 -436.150319)
			(xy 126.306752 -436.160418) (xy 127.2413 -436.160418) (xy 127.2413 -433.618894) (xy 127.241802 -433.606808)
			(xy 127.249255 -433.583814) (xy 127.263434 -433.564238) (xy 127.282958 -433.549986) (xy 127.305924 -433.542447)
			(xy 127.318008 -433.541932) (xy 128.257808 -433.541932) (xy 128.269921 -433.54231) (xy 128.292954 -433.549815)
			(xy 128.312529 -433.564086) (xy 128.326723 -433.583717) (xy 128.334137 -433.60678) (xy 128.334516 -433.618894)
			(xy 128.334516 -435.16042) (xy 129.241296 -435.16042) (xy 129.241296 -432.618896) (xy 129.241761 -432.606821)
			(xy 129.249225 -432.583853) (xy 129.263421 -432.564316) (xy 129.28296 -432.550121) (xy 129.305929 -432.54266)
			(xy 129.318004 -432.542188) (xy 130.257804 -432.542188) (xy 130.269878 -432.542661) (xy 130.292845 -432.550124)
			(xy 130.307094 -432.560476) (xy 131.241292 -432.560476) (xy 131.241292 -430.018952) (xy 131.241723 -430.006875)
			(xy 131.249199 -429.983906) (xy 131.263404 -429.96437) (xy 131.282949 -429.950177) (xy 131.305923 -429.942716)
			(xy 131.318 -429.942244) (xy 132.2578 -429.942244) (xy 132.26987 -429.942764) (xy 132.292829 -429.95022)
			(xy 132.312362 -429.964404) (xy 132.326558 -429.983928) (xy 132.334029 -430.006883) (xy 132.334508 -430.018952)
			(xy 132.334508 -431.560478) (xy 133.241288 -431.560478) (xy 133.241288 -429.018954) (xy 133.241669 -429.006857)
			(xy 133.249144 -428.983847) (xy 133.263351 -428.964264) (xy 133.282905 -428.950016) (xy 133.3059 -428.942494)
			(xy 133.317996 -428.941992) (xy 134.257796 -428.941992) (xy 134.269904 -428.942419) (xy 134.29293 -428.949917)
			(xy 134.307503 -428.960534) (xy 135.241284 -428.960534) (xy 135.241284 -426.41901) (xy 135.241717 -426.406917)
			(xy 135.249176 -426.383909) (xy 135.26337 -426.364325) (xy 135.282914 -426.350076) (xy 135.3059 -426.342551)
			(xy 135.317992 -426.342048) (xy 136.257792 -426.342048) (xy 136.269895 -426.342522) (xy 136.292914 -426.350013)
			(xy 136.312482 -426.364262) (xy 136.326679 -426.383868) (xy 136.334109 -426.406906) (xy 136.3345 -426.41901)
			(xy 136.3345 -427.960536) (xy 137.24128 -427.960536) (xy 137.24128 -425.419012) (xy 137.241774 -425.406939)
			(xy 137.249232 -425.383974) (xy 137.263421 -425.364438) (xy 137.282953 -425.350243) (xy 137.305915 -425.342778)
			(xy 137.317988 -425.342304) (xy 138.257788 -425.342304) (xy 138.269871 -425.342723) (xy 138.292856 -425.350189)
			(xy 138.312407 -425.364393) (xy 138.326611 -425.383944) (xy 138.334077 -425.406929) (xy 138.334496 -425.419012)
			(xy 138.334496 -427.960536) (xy 138.334066 -427.972614) (xy 138.326593 -427.995584) (xy 138.312387 -428.015122)
			(xy 138.292841 -428.029315) (xy 138.269866 -428.036774) (xy 138.257788 -428.037244) (xy 137.317988 -428.037244)
			(xy 137.305916 -428.036746) (xy 137.282955 -428.029285) (xy 137.263421 -428.015096) (xy 137.249226 -427.995567)
			(xy 137.241757 -427.972607) (xy 137.24128 -427.960536) (xy 136.3345 -427.960536) (xy 136.3345 -428.960534)
			(xy 136.334022 -428.972621) (xy 136.326561 -428.995616) (xy 136.312376 -429.015192) (xy 136.292848 -429.029443)
			(xy 136.269878 -429.036981) (xy 136.257792 -429.037496) (xy 135.317992 -429.037496) (xy 135.305882 -429.037091)
			(xy 135.282854 -429.029588) (xy 135.263281 -429.015324) (xy 135.249086 -428.9957) (xy 135.241667 -428.972645)
			(xy 135.241284 -428.960534) (xy 134.307503 -428.960534) (xy 134.312502 -428.964176) (xy 134.326697 -428.983795)
			(xy 134.33412 -429.006845) (xy 134.334504 -429.018954) (xy 134.334504 -431.560478) (xy 134.333975 -431.572562)
			(xy 134.326529 -431.595555) (xy 134.312357 -431.615131) (xy 134.29284 -431.629384) (xy 134.269878 -431.636924)
			(xy 134.257796 -431.63744) (xy 133.317996 -431.63744) (xy 133.305891 -431.636988) (xy 133.28287 -431.629492)
			(xy 133.263301 -431.615238) (xy 133.249105 -431.595627) (xy 133.241677 -431.572584) (xy 133.241288 -431.560478)
			(xy 132.334508 -431.560478) (xy 132.334508 -432.560476) (xy 132.334067 -432.572557) (xy 132.326606 -432.595539)
			(xy 132.312407 -432.61509) (xy 132.292861 -432.629295) (xy 132.269881 -432.636763) (xy 132.2578 -432.637184)
			(xy 131.318 -432.637184) (xy 131.305915 -432.636787) (xy 131.282928 -432.629317) (xy 131.263376 -432.615107)
			(xy 131.249172 -432.59555) (xy 131.241709 -432.572561) (xy 131.241292 -432.560476) (xy 130.307094 -432.560476)
			(xy 130.312382 -432.564318) (xy 130.326576 -432.583855) (xy 130.334039 -432.606822) (xy 130.334512 -432.618896)
			(xy 130.334512 -435.16042) (xy 130.334053 -435.172495) (xy 130.326585 -435.195462) (xy 130.312387 -435.214999)
			(xy 130.292848 -435.229193) (xy 130.269879 -435.236655) (xy 130.257804 -435.237128) (xy 129.318004 -435.237128)
			(xy 129.305932 -435.236633) (xy 129.282968 -435.229174) (xy 129.263433 -435.214984) (xy 129.249237 -435.195454)
			(xy 129.241771 -435.172492) (xy 129.241296 -435.16042) (xy 128.334516 -435.16042) (xy 128.334516 -436.160418)
			(xy 128.334107 -436.172513) (xy 128.32664 -436.195522) (xy 128.31244 -436.215105) (xy 128.292892 -436.229353)
			(xy 128.269902 -436.236877) (xy 128.257808 -436.23738) (xy 127.318008 -436.23738) (xy 127.305898 -436.236977)
			(xy 127.282867 -436.229477) (xy 127.263292 -436.215213) (xy 127.249098 -436.195587) (xy 127.24168 -436.17253)
			(xy 127.2413 -436.160418) (xy 126.306752 -436.160418) (xy 126.312389 -436.164514) (xy 126.326583 -436.184051)
			(xy 126.334047 -436.207018) (xy 126.33452 -436.219092) (xy 126.33452 -438.760616) (xy 126.334049 -438.77269)
			(xy 126.326584 -438.795656) (xy 126.312389 -438.815191) (xy 126.292852 -438.829386) (xy 126.269886 -438.83685)
			(xy 126.257812 -438.837324) (xy 125.318012 -438.837324) (xy 125.30594 -438.836826) (xy 125.282976 -438.829369)
			(xy 125.26344 -438.81518) (xy 125.249244 -438.79565) (xy 125.241779 -438.772688) (xy 125.241304 -438.760616)
			(xy 90.234516 -438.760616) (xy 90.234516 -439.760614) (xy 127.2413 -439.760614) (xy 127.2413 -437.21909)
			(xy 127.241798 -437.207004) (xy 127.249253 -437.18401) (xy 127.263433 -437.164434) (xy 127.282957 -437.150182)
			(xy 127.305924 -437.142643) (xy 127.318008 -437.142128) (xy 128.257808 -437.142128) (xy 128.26992 -437.14251)
			(xy 128.292952 -437.150015) (xy 128.312528 -437.164284) (xy 128.326721 -437.183915) (xy 128.334137 -437.206976)
			(xy 128.334516 -437.21909) (xy 128.334516 -438.760616) (xy 129.241296 -438.760616) (xy 129.241296 -436.219092)
			(xy 129.241758 -436.207017) (xy 129.249223 -436.184049) (xy 129.26342 -436.164511) (xy 129.282959 -436.150317)
			(xy 129.305929 -436.142856) (xy 129.318004 -436.142384) (xy 130.257804 -436.142384) (xy 130.269878 -436.142861)
			(xy 130.292844 -436.150323) (xy 130.306738 -436.160418) (xy 131.241292 -436.160418) (xy 131.241292 -433.618894)
			(xy 131.241802 -433.606809) (xy 131.249254 -433.583816) (xy 131.263431 -433.564241) (xy 131.282953 -433.549989)
			(xy 131.305917 -433.542448) (xy 131.318 -433.541932) (xy 132.2578 -433.541932) (xy 132.269912 -433.542317)
			(xy 132.292945 -433.54982) (xy 132.312521 -433.564088) (xy 132.326714 -433.583719) (xy 132.334129 -433.60678)
			(xy 132.334508 -433.618894) (xy 132.334508 -435.16042) (xy 133.241288 -435.16042) (xy 133.241288 -432.618896)
			(xy 133.241761 -432.606822) (xy 133.249224 -432.583855) (xy 133.263418 -432.564318) (xy 133.282955 -432.550124)
			(xy 133.305922 -432.542661) (xy 133.317996 -432.542188) (xy 134.257796 -432.542188) (xy 134.26987 -432.542668)
			(xy 134.292836 -432.550129) (xy 134.30708 -432.560476) (xy 135.241284 -432.560476) (xy 135.241284 -430.018952)
			(xy 135.241723 -430.006876) (xy 135.249198 -429.983908) (xy 135.263401 -429.964373) (xy 135.282944 -429.95018)
			(xy 135.305915 -429.942717) (xy 135.317992 -429.942244) (xy 136.257792 -429.942244) (xy 136.269861 -429.94277)
			(xy 136.29282 -429.950225) (xy 136.312353 -429.964407) (xy 136.32655 -429.98393) (xy 136.334021 -430.006883)
			(xy 136.3345 -430.018952) (xy 136.3345 -431.560478) (xy 137.24128 -431.560478) (xy 137.24128 -429.018954)
			(xy 137.241669 -429.006858) (xy 137.249143 -428.983849) (xy 137.263348 -428.964267) (xy 137.2829 -428.950019)
			(xy 137.305893 -428.942495) (xy 137.317988 -428.941992) (xy 138.257788 -428.941992) (xy 138.269895 -428.942427)
			(xy 138.292921 -428.949922) (xy 138.307489 -428.960534) (xy 139.241276 -428.960534) (xy 139.241276 -426.41901)
			(xy 139.241717 -426.406917) (xy 139.249175 -426.383911) (xy 139.263367 -426.364328) (xy 139.282909 -426.350078)
			(xy 139.305893 -426.342553) (xy 139.317984 -426.342048) (xy 140.257784 -426.342048) (xy 140.269887 -426.342529)
			(xy 140.292905 -426.350018) (xy 140.312473 -426.364265) (xy 140.32667 -426.383869) (xy 140.334101 -426.406906)
			(xy 140.334492 -426.41901) (xy 140.334492 -427.960536) (xy 142.241016 -427.960536) (xy 142.241016 -425.419012)
			(xy 142.24147 -425.406961) (xy 142.248902 -425.384033) (xy 142.263043 -425.364516) (xy 142.282516 -425.350313)
			(xy 142.30542 -425.342809) (xy 142.31747 -425.342304) (xy 143.257778 -425.342304) (xy 143.269863 -425.342825)
			(xy 143.292857 -425.350272) (xy 143.312434 -425.364446) (xy 143.326686 -425.383966) (xy 143.334225 -425.406929)
			(xy 143.33474 -425.419012) (xy 143.33474 -427.960536) (xy 143.334272 -427.972584) (xy 143.326834 -427.995504)
			(xy 143.312694 -428.015016) (xy 143.293228 -428.029219) (xy 143.270333 -428.036732) (xy 143.258286 -428.037244)
			(xy 142.317978 -428.037244) (xy 142.305886 -428.036811) (xy 142.282882 -428.029347) (xy 142.263301 -428.015152)
			(xy 142.249051 -427.99561) (xy 142.241523 -427.972627) (xy 142.241016 -427.960536) (xy 140.334492 -427.960536)
			(xy 140.334492 -428.960534) (xy 140.334022 -428.972622) (xy 140.32656 -428.995619) (xy 140.312373 -429.015195)
			(xy 140.292843 -429.029446) (xy 140.269871 -429.036983) (xy 140.257784 -429.037496) (xy 139.317984 -429.037496)
			(xy 139.305874 -429.037097) (xy 139.282845 -429.029593) (xy 139.263272 -429.015327) (xy 139.249078 -428.995702)
			(xy 139.241659 -428.972646) (xy 139.241276 -428.960534) (xy 138.307489 -428.960534) (xy 138.312493 -428.964179)
			(xy 138.326689 -428.983796) (xy 138.334111 -429.006845) (xy 138.334496 -429.018954) (xy 138.334496 -431.560478)
			(xy 138.333975 -431.572563) (xy 138.326528 -431.595557) (xy 138.312354 -431.615134) (xy 138.292834 -431.629386)
			(xy 138.269871 -431.636925) (xy 138.257788 -431.63744) (xy 137.317988 -431.63744) (xy 137.305882 -431.636995)
			(xy 137.282862 -431.629497) (xy 137.263292 -431.615241) (xy 137.249096 -431.595628) (xy 137.241669 -431.572585)
			(xy 137.24128 -431.560478) (xy 136.3345 -431.560478) (xy 136.3345 -432.560476) (xy 136.334067 -432.572558)
			(xy 136.326605 -432.595542) (xy 136.312404 -432.615093) (xy 136.292856 -432.629297) (xy 136.269874 -432.636764)
			(xy 136.257792 -432.637184) (xy 135.317992 -432.637184) (xy 135.305906 -432.636794) (xy 135.282919 -432.629321)
			(xy 135.263367 -432.61511) (xy 135.249164 -432.595552) (xy 135.241701 -432.572562) (xy 135.241284 -432.560476)
			(xy 134.30708 -432.560476) (xy 134.312373 -432.564321) (xy 134.326568 -432.583857) (xy 134.334031 -432.606822)
			(xy 134.334504 -432.618896) (xy 134.334504 -435.16042) (xy 134.334053 -435.172496) (xy 134.326584 -435.195464)
			(xy 134.312384 -435.215001) (xy 134.292843 -435.229195) (xy 134.269872 -435.236656) (xy 134.257796 -435.237128)
			(xy 133.317996 -435.237128) (xy 133.305923 -435.236639) (xy 133.282959 -435.229178) (xy 133.263424 -435.214987)
			(xy 133.249229 -435.195455) (xy 133.241763 -435.172493) (xy 133.241288 -435.16042) (xy 132.334508 -435.16042)
			(xy 132.334508 -436.160418) (xy 132.334009 -436.172504) (xy 132.326553 -436.195497) (xy 132.312373 -436.215072)
			(xy 132.29285 -436.229324) (xy 132.269884 -436.236864) (xy 132.2578 -436.23738) (xy 131.318 -436.23738)
			(xy 131.305889 -436.236984) (xy 131.282858 -436.229482) (xy 131.263283 -436.215216) (xy 131.24909 -436.195589)
			(xy 131.241672 -436.17253) (xy 131.241292 -436.160418) (xy 130.306738 -436.160418) (xy 130.31238 -436.164517)
			(xy 130.326575 -436.184053) (xy 130.334039 -436.207018) (xy 130.334512 -436.219092) (xy 130.334512 -438.760616)
			(xy 130.334049 -438.772691) (xy 130.326583 -438.795658) (xy 130.312386 -438.815194) (xy 130.292847 -438.829388)
			(xy 130.269879 -438.836851) (xy 130.257804 -438.837324) (xy 129.318004 -438.837324) (xy 129.305931 -438.836833)
			(xy 129.282967 -438.829373) (xy 129.263431 -438.815183) (xy 129.249236 -438.795651) (xy 129.241771 -438.772689)
			(xy 129.241296 -438.760616) (xy 128.334516 -438.760616) (xy 128.334516 -439.760614) (xy 131.241292 -439.760614)
			(xy 131.241292 -437.21909) (xy 131.241798 -437.207005) (xy 131.249252 -437.184012) (xy 131.26343 -437.164436)
			(xy 131.282952 -437.150184) (xy 131.305917 -437.142644) (xy 131.318 -437.142128) (xy 132.2578 -437.142128)
			(xy 132.269912 -437.142516) (xy 132.292944 -437.150019) (xy 132.312519 -437.164287) (xy 132.326713 -437.183916)
			(xy 132.334129 -437.206977) (xy 132.334508 -437.21909) (xy 132.334508 -438.760616) (xy 133.241288 -438.760616)
			(xy 133.241288 -436.219092) (xy 133.241757 -436.207017) (xy 133.249222 -436.184051) (xy 133.263417 -436.164514)
			(xy 133.282954 -436.15032) (xy 133.305921 -436.142857) (xy 133.317996 -436.142384) (xy 134.257796 -436.142384)
			(xy 134.26987 -436.142868) (xy 134.292835 -436.150328) (xy 134.306725 -436.160418) (xy 135.241284 -436.160418)
			(xy 135.241284 -433.618894) (xy 135.241703 -433.6068) (xy 135.249167 -433.583792) (xy 135.263364 -433.564208)
			(xy 135.282911 -433.549959) (xy 135.305899 -433.542435) (xy 135.317992 -433.541932) (xy 136.257792 -433.541932)
			(xy 136.269904 -433.542323) (xy 136.292936 -433.549824) (xy 136.312512 -433.564091) (xy 136.326706 -433.58372)
			(xy 136.334121 -433.606781) (xy 136.3345 -433.618894) (xy 136.3345 -435.16042) (xy 137.24128 -435.16042)
			(xy 137.24128 -432.618896) (xy 137.241761 -432.606822) (xy 137.249223 -432.583857) (xy 137.263416 -432.564321)
			(xy 137.28295 -432.550126) (xy 137.305914 -432.542662) (xy 137.317988 -432.542188) (xy 138.257788 -432.542188)
			(xy 138.26987 -432.542623) (xy 138.292851 -432.550087) (xy 138.307154 -432.560476) (xy 139.241276 -432.560476)
			(xy 139.241276 -430.018952) (xy 139.241723 -430.006877) (xy 139.249197 -429.98391) (xy 139.263398 -429.964376)
			(xy 139.282939 -429.950182) (xy 139.305908 -429.942718) (xy 139.317984 -429.942244) (xy 140.257784 -429.942244)
			(xy 140.269853 -429.942777) (xy 140.292812 -429.950229) (xy 140.312345 -429.96441) (xy 140.326541 -429.983931)
			(xy 140.334013 -430.006883) (xy 140.334492 -430.018952) (xy 140.334492 -431.560478) (xy 142.241016 -431.560478)
			(xy 142.241016 -429.018954) (xy 142.241472 -429.006839) (xy 142.248969 -428.983798) (xy 142.263216 -428.964199)
			(xy 142.28282 -428.949958) (xy 142.305863 -428.942468) (xy 142.317978 -428.941992) (xy 143.257778 -428.941992)
			(xy 143.269887 -428.94253) (xy 143.292922 -428.950005) (xy 143.307426 -428.960534) (xy 144.241012 -428.960534)
			(xy 144.241012 -426.41901) (xy 144.24152 -426.406899) (xy 144.249001 -426.38386) (xy 144.263235 -426.36426)
			(xy 144.282828 -426.350018) (xy 144.305863 -426.342526) (xy 144.317974 -426.342048) (xy 145.257774 -426.342048)
			(xy 145.269896 -426.342482) (xy 145.292956 -426.349969) (xy 145.312572 -426.364216) (xy 145.326824 -426.38383)
			(xy 145.334315 -426.406888) (xy 145.334736 -426.41901) (xy 145.334736 -427.960536) (xy 146.241008 -427.960536)
			(xy 146.241008 -425.419012) (xy 146.24147 -425.406962) (xy 146.248901 -425.384035) (xy 146.263041 -425.364518)
			(xy 146.282511 -425.350315) (xy 146.305413 -425.34281) (xy 146.317462 -425.342304) (xy 147.25777 -425.342304)
			(xy 147.269854 -425.342832) (xy 147.292848 -425.350276) (xy 147.312425 -425.364448) (xy 147.326678 -425.383967)
			(xy 147.334217 -425.40693) (xy 147.334732 -425.419012) (xy 147.334732 -427.960536) (xy 147.334272 -427.972585)
			(xy 147.326833 -427.995506) (xy 147.312691 -428.015019) (xy 147.293223 -428.029222) (xy 147.270325 -428.036733)
			(xy 147.258278 -428.037244) (xy 146.31797 -428.037244) (xy 146.305877 -428.036818) (xy 146.282873 -428.029351)
			(xy 146.263292 -428.015154) (xy 146.249043 -427.995612) (xy 146.241515 -427.972627) (xy 146.241008 -427.960536)
			(xy 145.334736 -427.960536) (xy 145.334736 -428.960534) (xy 145.334317 -428.972653) (xy 145.326817 -428.995702)
			(xy 145.312562 -429.015305) (xy 145.292948 -429.029545) (xy 145.269893 -429.037026) (xy 145.257774 -429.037496)
			(xy 144.317974 -429.037496) (xy 144.305861 -429.037011) (xy 144.282823 -429.029521) (xy 144.263225 -429.015281)
			(xy 144.248983 -428.995684) (xy 144.24149 -428.972646) (xy 144.241012 -428.960534) (xy 143.307426 -428.960534)
			(xy 143.31252 -428.964232) (xy 143.326764 -428.983817) (xy 143.334259 -429.006846) (xy 143.33474 -429.018954)
			(xy 143.33474 -431.560478) (xy 143.334321 -431.572602) (xy 143.326832 -431.595664) (xy 143.312581 -431.615281)
			(xy 143.292964 -431.629532) (xy 143.269902 -431.637021) (xy 143.257778 -431.63744) (xy 142.317978 -431.63744)
			(xy 142.30586 -431.637007) (xy 142.282812 -431.629511) (xy 142.263209 -431.61526) (xy 142.248969 -431.595648)
			(xy 142.241486 -431.572596) (xy 142.241016 -431.560478) (xy 140.334492 -431.560478) (xy 140.334492 -432.560476)
			(xy 140.334067 -432.572559) (xy 140.326604 -432.595544) (xy 140.312401 -432.615096) (xy 140.292851 -432.6293)
			(xy 140.269867 -432.636765) (xy 140.257784 -432.637184) (xy 139.317984 -432.637184) (xy 139.305898 -432.636801)
			(xy 139.282911 -432.629326) (xy 139.263359 -432.615113) (xy 139.249156 -432.595553) (xy 139.241693 -432.572562)
			(xy 139.241276 -432.560476) (xy 138.307154 -432.560476) (xy 138.312401 -432.564287) (xy 138.326606 -432.583834)
			(xy 138.334074 -432.606814) (xy 138.334496 -432.618896) (xy 138.334496 -435.16042) (xy 138.334052 -435.172497)
			(xy 138.326583 -435.195467) (xy 138.312381 -435.215004) (xy 138.292838 -435.229198) (xy 138.269865 -435.236657)
			(xy 138.257788 -435.237128) (xy 137.317988 -435.237128) (xy 137.305915 -435.236646) (xy 137.282951 -435.229183)
			(xy 137.263416 -435.21499) (xy 137.249221 -435.195456) (xy 137.241755 -435.172493) (xy 137.24128 -435.16042)
			(xy 136.3345 -435.16042) (xy 136.3345 -436.160418) (xy 136.334009 -436.172505) (xy 136.326552 -436.195499)
			(xy 136.31237 -436.215075) (xy 136.292845 -436.229327) (xy 136.269877 -436.236865) (xy 136.257792 -436.23738)
			(xy 135.317992 -436.23738) (xy 135.305881 -436.23699) (xy 135.28285 -436.229486) (xy 135.263275 -436.215219)
			(xy 135.249081 -436.19559) (xy 135.241664 -436.172531) (xy 135.241284 -436.160418) (xy 134.306725 -436.160418)
			(xy 134.312372 -436.16452) (xy 134.326567 -436.184054) (xy 134.334031 -436.207019) (xy 134.334504 -436.219092)
			(xy 134.334504 -438.760616) (xy 134.334049 -438.772692) (xy 134.326582 -438.79566) (xy 134.312383 -438.815197)
			(xy 134.292842 -438.829391) (xy 134.269872 -438.836852) (xy 134.257796 -438.837324) (xy 133.317996 -438.837324)
			(xy 133.305923 -438.836839) (xy 133.282958 -438.829378) (xy 133.263423 -438.815186) (xy 133.249228 -438.795652)
			(xy 133.241763 -438.772689) (xy 133.241288 -438.760616) (xy 132.334508 -438.760616) (xy 132.334508 -439.760614)
			(xy 135.241284 -439.760614) (xy 135.241284 -437.21909) (xy 135.2417 -437.206996) (xy 135.249165 -437.183987)
			(xy 135.263363 -437.164404) (xy 135.28291 -437.150155) (xy 135.305899 -437.142631) (xy 135.317992 -437.142128)
			(xy 136.257792 -437.142128) (xy 136.269903 -437.142523) (xy 136.292935 -437.150024) (xy 136.312511 -437.16429)
			(xy 136.326705 -437.183918) (xy 136.334121 -437.206977) (xy 136.3345 -437.21909) (xy 136.3345 -438.760616)
			(xy 137.24128 -438.760616) (xy 137.24128 -436.219092) (xy 137.241757 -436.207018) (xy 137.249221 -436.184053)
			(xy 137.263414 -436.164517) (xy 137.282949 -436.150322) (xy 137.305914 -436.142858) (xy 137.317988 -436.142384)
			(xy 138.257788 -436.142384) (xy 138.269869 -436.142823) (xy 138.29285 -436.150286) (xy 138.306799 -436.160418)
			(xy 139.241276 -436.160418) (xy 139.241276 -433.618894) (xy 139.241703 -433.606801) (xy 139.249166 -433.583794)
			(xy 139.263361 -433.564211) (xy 139.282906 -433.549962) (xy 139.305892 -433.542436) (xy 139.317984 -433.541932)
			(xy 140.257784 -433.541932) (xy 140.269895 -433.542331) (xy 140.292927 -433.549829) (xy 140.312503 -433.564094)
			(xy 140.326697 -433.583722) (xy 140.334113 -433.606781) (xy 140.334492 -433.618894) (xy 140.334492 -435.16042)
			(xy 142.241016 -435.16042) (xy 142.241016 -432.618896) (xy 142.241457 -432.606844) (xy 142.248893 -432.583916)
			(xy 142.263038 -432.564399) (xy 142.282513 -432.550196) (xy 142.305419 -432.542693) (xy 142.31747 -432.542188)
			(xy 143.257778 -432.542188) (xy 143.269871 -432.542627) (xy 143.292879 -432.550084) (xy 143.30722 -432.560476)
			(xy 144.241012 -432.560476) (xy 144.241012 -430.018952) (xy 144.241419 -430.006898) (xy 144.248867 -429.983969)
			(xy 144.263021 -429.964453) (xy 144.282502 -429.950252) (xy 144.305413 -429.942749) (xy 144.317466 -429.942244)
			(xy 145.257774 -429.942244) (xy 145.269863 -429.94273) (xy 145.292863 -429.95018) (xy 145.312444 -429.964361)
			(xy 145.326695 -429.983891) (xy 145.334227 -430.006865) (xy 145.334736 -430.018952) (xy 145.334736 -431.560478)
			(xy 146.241008 -431.560478) (xy 146.241008 -429.018954) (xy 146.241472 -429.00684) (xy 146.248968 -428.9838)
			(xy 146.263213 -428.964202) (xy 146.282815 -428.949961) (xy 146.305856 -428.94247) (xy 146.31797 -428.941992)
			(xy 147.25777 -428.941992) (xy 147.269878 -428.942537) (xy 147.292913 -428.95001) (xy 147.307412 -428.960534)
			(xy 148.241004 -428.960534) (xy 148.241004 -426.41901) (xy 148.24152 -426.406899) (xy 148.249 -426.383862)
			(xy 148.263232 -426.364263) (xy 148.282823 -426.35002) (xy 148.305856 -426.342527) (xy 148.317966 -426.342048)
			(xy 149.257766 -426.342048) (xy 149.269888 -426.342489) (xy 149.292947 -426.349973) (xy 149.312564 -426.364219)
			(xy 149.326816 -426.383831) (xy 149.334307 -426.406888) (xy 149.334728 -426.41901) (xy 149.334728 -427.960536)
			(xy 150.241 -427.960536) (xy 150.241 -425.419012) (xy 150.24147 -425.406962) (xy 150.2489 -425.384037)
			(xy 150.263038 -425.364521) (xy 150.282506 -425.350318) (xy 150.305406 -425.342811) (xy 150.317454 -425.342304)
			(xy 151.257762 -425.342304) (xy 151.269846 -425.342839) (xy 151.292839 -425.350281) (xy 151.312417 -425.364451)
			(xy 151.32667 -425.383968) (xy 151.334209 -425.40693) (xy 151.334724 -425.419012) (xy 151.334724 -427.960536)
			(xy 151.334271 -427.972586) (xy 151.326832 -427.995508) (xy 151.312688 -428.015022) (xy 151.293218 -428.029225)
			(xy 151.270318 -428.036734) (xy 151.25827 -428.037244) (xy 150.317962 -428.037244) (xy 150.305869 -428.036825)
			(xy 150.282864 -428.029356) (xy 150.263284 -428.015157) (xy 150.249035 -427.995613) (xy 150.241507 -427.972628)
			(xy 150.241 -427.960536) (xy 149.334728 -427.960536) (xy 149.334728 -428.960534) (xy 149.334317 -428.972654)
			(xy 149.326816 -428.995704) (xy 149.31256 -429.015308) (xy 149.292943 -429.029547) (xy 149.269886 -429.037027)
			(xy 149.257766 -429.037496) (xy 148.317966 -429.037496) (xy 148.305853 -429.037018) (xy 148.282814 -429.029525)
			(xy 148.263216 -429.015284) (xy 148.248975 -428.995686) (xy 148.241482 -428.972647) (xy 148.241004 -428.960534)
			(xy 147.307412 -428.960534) (xy 147.312511 -428.964235) (xy 147.326755 -428.983819) (xy 147.334251 -429.006846)
			(xy 147.334732 -429.018954) (xy 147.334732 -431.560478) (xy 147.334321 -431.572603) (xy 147.326831 -431.595666)
			(xy 147.312578 -431.615284) (xy 147.292959 -431.629535) (xy 147.269895 -431.637022) (xy 147.25777 -431.63744)
			(xy 146.31797 -431.63744) (xy 146.305852 -431.637014) (xy 146.282804 -431.629515) (xy 146.263201 -431.615262)
			(xy 146.248961 -431.59565) (xy 146.241478 -431.572597) (xy 146.241008 -431.560478) (xy 145.334736 -431.560478)
			(xy 145.334736 -432.560476) (xy 145.33422 -432.572521) (xy 145.326799 -432.59544) (xy 145.312671 -432.614953)
			(xy 145.293214 -432.629159) (xy 145.270325 -432.636672) (xy 145.258282 -432.637184) (xy 144.317974 -432.637184)
			(xy 144.305885 -432.636715) (xy 144.282888 -432.629254) (xy 144.263311 -432.615067) (xy 144.24906 -432.595536)
			(xy 144.241524 -432.572563) (xy 144.241012 -432.560476) (xy 143.30722 -432.560476) (xy 143.312464 -432.564276)
			(xy 143.326713 -432.583818) (xy 143.334237 -432.606804) (xy 143.33474 -432.618896) (xy 143.33474 -435.16042)
			(xy 143.334258 -435.172467) (xy 143.326824 -435.195387) (xy 143.312688 -435.214899) (xy 143.293225 -435.229103)
			(xy 143.270332 -435.236615) (xy 143.258286 -435.237128) (xy 142.317978 -435.237128) (xy 142.305884 -435.236711)
			(xy 142.282877 -435.229244) (xy 142.263295 -435.215046) (xy 142.249046 -435.1955) (xy 142.24152 -435.172513)
			(xy 142.241016 -435.16042) (xy 140.334492 -435.16042) (xy 140.334492 -436.160418) (xy 140.334009 -436.172505)
			(xy 140.326551 -436.195501) (xy 140.312367 -436.215078) (xy 140.29284 -436.229329) (xy 140.26987 -436.236866)
			(xy 140.257784 -436.23738) (xy 139.317984 -436.23738) (xy 139.305872 -436.236997) (xy 139.282841 -436.229491)
			(xy 139.263266 -436.215221) (xy 139.249073 -436.195592) (xy 139.241656 -436.172531) (xy 139.241276 -436.160418)
			(xy 138.306799 -436.160418) (xy 138.3124 -436.164486) (xy 138.326605 -436.184032) (xy 138.334074 -436.207011)
			(xy 138.334496 -436.219092) (xy 138.334496 -438.760616) (xy 138.334049 -438.772693) (xy 138.326581 -438.795662)
			(xy 138.31238 -438.8152) (xy 138.292837 -438.829394) (xy 138.269865 -438.836853) (xy 138.257788 -438.837324)
			(xy 137.317988 -438.837324) (xy 137.305914 -438.836846) (xy 137.28295 -438.829382) (xy 137.263414 -438.815189)
			(xy 137.24922 -438.795654) (xy 137.241755 -438.77269) (xy 137.24128 -438.760616) (xy 136.3345 -438.760616)
			(xy 136.3345 -439.760614) (xy 139.241276 -439.760614) (xy 139.241276 -437.21909) (xy 139.2417 -437.206996)
			(xy 139.249164 -437.183989) (xy 139.26336 -437.164407) (xy 139.282905 -437.150158) (xy 139.305892 -437.142632)
			(xy 139.317984 -437.142128) (xy 140.257784 -437.142128) (xy 140.269895 -437.14253) (xy 140.292926 -437.150029)
			(xy 140.312502 -437.164293) (xy 140.326696 -437.18392) (xy 140.334112 -437.206978) (xy 140.334492 -437.21909)
			(xy 140.334492 -438.760616) (xy 142.241016 -438.760616) (xy 142.241016 -436.219092) (xy 142.241454 -436.20704)
			(xy 142.24889 -436.184111) (xy 142.263036 -436.164594) (xy 142.282512 -436.150392) (xy 142.305419 -436.142889)
			(xy 142.31747 -436.142384) (xy 143.257778 -436.142384) (xy 143.269871 -436.142827) (xy 143.292878 -436.150283)
			(xy 143.306865 -436.160418) (xy 144.241012 -436.160418) (xy 144.241012 -433.618894) (xy 144.241506 -433.606782)
			(xy 144.248992 -433.583743) (xy 144.263229 -433.564143) (xy 144.282825 -433.549901) (xy 144.305862 -433.54241)
			(xy 144.317974 -433.541932) (xy 145.257774 -433.541932) (xy 145.269895 -433.542382) (xy 145.292952 -433.549866)
			(xy 145.312567 -433.56411) (xy 145.326819 -433.58372) (xy 145.334313 -433.606773) (xy 145.334736 -433.618894)
			(xy 145.334736 -435.16042) (xy 146.241008 -435.16042) (xy 146.241008 -432.618896) (xy 146.241457 -432.606845)
			(xy 146.248892 -432.583918) (xy 146.263035 -432.564401) (xy 146.282508 -432.550199) (xy 146.305412 -432.542694)
			(xy 146.317462 -432.542188) (xy 147.25777 -432.542188) (xy 147.269863 -432.542634) (xy 147.29287 -432.550088)
			(xy 147.307207 -432.560476) (xy 148.241004 -432.560476) (xy 148.241004 -430.018952) (xy 148.241419 -430.006899)
			(xy 148.248865 -429.983971) (xy 148.263018 -429.964456) (xy 148.282497 -429.950254) (xy 148.305406 -429.94275)
			(xy 148.317458 -429.942244) (xy 149.257766 -429.942244) (xy 149.269854 -429.942736) (xy 149.292854 -429.950184)
			(xy 149.312435 -429.964364) (xy 149.326687 -429.983893) (xy 149.334219 -430.006866) (xy 149.334728 -430.018952)
			(xy 149.334728 -431.560478) (xy 150.241 -431.560478) (xy 150.241 -429.018954) (xy 150.241472 -429.006841)
			(xy 150.248967 -428.983803) (xy 150.263211 -428.964205) (xy 150.28281 -428.949964) (xy 150.305849 -428.942471)
			(xy 150.317962 -428.941992) (xy 151.257762 -428.941992) (xy 151.26987 -428.942543) (xy 151.292904 -428.950015)
			(xy 151.307399 -428.960534) (xy 152.240996 -428.960534) (xy 152.240996 -426.41901) (xy 152.24152 -426.4069)
			(xy 152.248999 -426.383864) (xy 152.263229 -426.364266) (xy 152.282818 -426.350023) (xy 152.305848 -426.342528)
			(xy 152.317958 -426.342048) (xy 153.257758 -426.342048) (xy 153.26988 -426.342496) (xy 153.292939 -426.349978)
			(xy 153.312555 -426.364222) (xy 153.326808 -426.383833) (xy 153.334299 -426.406889) (xy 153.33472 -426.41901)
			(xy 153.33472 -427.960536) (xy 154.240992 -427.960536) (xy 154.240992 -425.419012) (xy 154.24147 -425.406963)
			(xy 154.248898 -425.384039) (xy 154.263035 -425.364524) (xy 154.282501 -425.35032) (xy 154.305399 -425.342812)
			(xy 154.317446 -425.342304) (xy 155.257754 -425.342304) (xy 155.269838 -425.342846) (xy 155.292831 -425.350286)
			(xy 155.312408 -425.364454) (xy 155.326662 -425.38397) (xy 155.334201 -425.40693) (xy 155.334716 -425.419012)
			(xy 155.334716 -427.960536) (xy 155.334271 -427.972587) (xy 155.326831 -427.995511) (xy 155.312685 -428.015024)
			(xy 155.293213 -428.029227) (xy 155.270311 -428.036735) (xy 155.258262 -428.037244) (xy 154.317954 -428.037244)
			(xy 154.30586 -428.036832) (xy 154.282856 -428.02936) (xy 154.263275 -428.01516) (xy 154.249027 -427.995615)
			(xy 154.241499 -427.972628) (xy 154.240992 -427.960536) (xy 153.33472 -427.960536) (xy 153.33472 -428.960534)
			(xy 153.334369 -428.972663) (xy 153.326862 -428.99573) (xy 153.312594 -429.015348) (xy 153.292962 -429.029597)
			(xy 153.269887 -429.03708) (xy 153.257758 -429.037496) (xy 152.317958 -429.037496) (xy 152.305845 -429.037025)
			(xy 152.282806 -429.02953) (xy 152.263208 -429.015287) (xy 152.248966 -428.995687) (xy 152.241474 -428.972647)
			(xy 152.240996 -428.960534) (xy 151.307399 -428.960534) (xy 151.312503 -428.964238) (xy 151.326747 -428.98382)
			(xy 151.334243 -429.006847) (xy 151.334724 -429.018954) (xy 151.334724 -431.560478) (xy 151.334321 -431.572603)
			(xy 151.32683 -431.595668) (xy 151.312575 -431.615287) (xy 151.292954 -431.629537) (xy 151.269887 -431.637023)
			(xy 151.257762 -431.63744) (xy 150.317962 -431.63744) (xy 150.305843 -431.63702) (xy 150.282795 -431.62952)
			(xy 150.263192 -431.615265) (xy 150.248953 -431.595651) (xy 150.24147 -431.572597) (xy 150.241 -431.560478)
			(xy 149.334728 -431.560478) (xy 149.334728 -432.560476) (xy 149.33422 -432.572522) (xy 149.326797 -432.595442)
			(xy 149.312668 -432.614956) (xy 149.293209 -432.629161) (xy 149.270318 -432.636673) (xy 149.258274 -432.637184)
			(xy 148.317966 -432.637184) (xy 148.305877 -432.636722) (xy 148.282879 -432.629259) (xy 148.263302 -432.61507)
			(xy 148.249052 -432.595538) (xy 148.241516 -432.572563) (xy 148.241004 -432.560476) (xy 147.307207 -432.560476)
			(xy 147.312455 -432.564278) (xy 147.326705 -432.58382) (xy 147.334229 -432.606805) (xy 147.334732 -432.618896)
			(xy 147.334732 -435.16042) (xy 147.334258 -435.172468) (xy 147.326823 -435.195389) (xy 147.312685 -435.214901)
			(xy 147.29322 -435.229105) (xy 147.270324 -435.236616) (xy 147.258278 -435.237128) (xy 146.31797 -435.237128)
			(xy 146.305876 -435.236718) (xy 146.282869 -435.229249) (xy 146.263286 -435.215049) (xy 146.249038 -435.195502)
			(xy 146.241512 -435.172513) (xy 146.241008 -435.16042) (xy 145.334736 -435.16042) (xy 145.334736 -436.160418)
			(xy 145.334355 -436.172544) (xy 145.326854 -436.195608) (xy 145.312594 -436.215225) (xy 145.292969 -436.229474)
			(xy 145.2699 -436.236962) (xy 145.257774 -436.23738) (xy 144.317974 -436.23738) (xy 144.30586 -436.236911)
			(xy 144.282819 -436.229419) (xy 144.263219 -436.215175) (xy 144.248978 -436.195574) (xy 144.241488 -436.172532)
			(xy 144.241012 -436.160418) (xy 143.306865 -436.160418) (xy 143.312462 -436.164474) (xy 143.326712 -436.184016)
			(xy 143.334237 -436.207001) (xy 143.33474 -436.219092) (xy 143.33474 -438.760616) (xy 143.334254 -438.772663)
			(xy 143.326822 -438.795582) (xy 143.312686 -438.815094) (xy 143.293224 -438.829298) (xy 143.270331 -438.836811)
			(xy 143.258286 -438.837324) (xy 142.317978 -438.837324) (xy 142.305884 -438.836911) (xy 142.282876 -438.829444)
			(xy 142.263294 -438.815245) (xy 142.249045 -438.795698) (xy 142.24152 -438.772709) (xy 142.241016 -438.760616)
			(xy 140.334492 -438.760616) (xy 140.334492 -439.760614) (xy 144.241012 -439.760614) (xy 144.241012 -437.21909)
			(xy 144.241503 -437.206978) (xy 144.24899 -437.183938) (xy 144.263228 -437.164339) (xy 144.282824 -437.150097)
			(xy 144.305862 -437.142606) (xy 144.317974 -437.142128) (xy 145.257774 -437.142128) (xy 145.269894 -437.142582)
			(xy 145.292951 -437.150066) (xy 145.312565 -437.164309) (xy 145.326818 -437.183917) (xy 145.334312 -437.20697)
			(xy 145.334736 -437.21909) (xy 145.334736 -438.760616) (xy 146.241008 -438.760616) (xy 146.241008 -436.219092)
			(xy 146.241453 -436.207041) (xy 146.248889 -436.184113) (xy 146.263034 -436.164597) (xy 146.282507 -436.150394)
			(xy 146.305412 -436.14289) (xy 146.317462 -436.142384) (xy 147.25777 -436.142384) (xy 147.269862 -436.142834)
			(xy 147.292869 -436.150288) (xy 147.306851 -436.160418) (xy 148.241004 -436.160418) (xy 148.241004 -433.618894)
			(xy 148.241506 -433.606783) (xy 148.248991 -433.583745) (xy 148.263226 -433.564146) (xy 148.28282 -433.549904)
			(xy 148.305855 -433.542411) (xy 148.317966 -433.541932) (xy 149.257766 -433.541932) (xy 149.269886 -433.542389)
			(xy 149.292943 -433.549871) (xy 149.312558 -433.564113) (xy 149.326811 -433.583721) (xy 149.334305 -433.606774)
			(xy 149.334728 -433.618894) (xy 149.334728 -435.16042) (xy 150.241 -435.16042) (xy 150.241 -432.618896)
			(xy 150.241457 -432.606846) (xy 150.24889 -432.58392) (xy 150.263032 -432.564404) (xy 150.282503 -432.550201)
			(xy 150.305405 -432.542695) (xy 150.317454 -432.542188) (xy 151.257762 -432.542188) (xy 151.269854 -432.542641)
			(xy 151.292862 -432.550093) (xy 151.307195 -432.560476) (xy 152.240996 -432.560476) (xy 152.240996 -430.018952)
			(xy 152.241419 -430.0069) (xy 152.248864 -429.983973) (xy 152.263015 -429.964459) (xy 152.282492 -429.950257)
			(xy 152.305399 -429.942751) (xy 152.31745 -429.942244) (xy 153.257758 -429.942244) (xy 153.269846 -429.942743)
			(xy 153.292846 -429.950189) (xy 153.312427 -429.964367) (xy 153.326679 -429.983894) (xy 153.334211 -430.006866)
			(xy 153.33472 -430.018952) (xy 153.33472 -431.560478) (xy 154.240992 -431.560478) (xy 154.240992 -429.018954)
			(xy 154.241472 -429.006842) (xy 154.248966 -428.983805) (xy 154.263208 -428.964208) (xy 154.282805 -428.949966)
			(xy 154.305842 -428.942472) (xy 154.317954 -428.941992) (xy 155.257754 -428.941992) (xy 155.269862 -428.94255)
			(xy 155.292896 -428.950019) (xy 155.307387 -428.960534) (xy 156.240988 -428.960534) (xy 156.240988 -426.41901)
			(xy 156.24152 -426.406901) (xy 156.248998 -426.383867) (xy 156.263226 -426.364269) (xy 156.282813 -426.350025)
			(xy 156.305841 -426.342529) (xy 156.31795 -426.342048) (xy 157.25775 -426.342048) (xy 157.269868 -426.342469)
			(xy 157.292915 -426.349972) (xy 157.312516 -426.364226) (xy 157.326756 -426.383839) (xy 157.33424 -426.406891)
			(xy 157.334712 -426.41901) (xy 157.334712 -428.960534) (xy 157.334218 -428.972645) (xy 157.326728 -428.995681)
			(xy 157.31249 -429.015278) (xy 157.292896 -429.02952) (xy 157.269861 -429.037016) (xy 157.25775 -429.037496)
			(xy 156.31795 -429.037496) (xy 156.305836 -429.037031) (xy 156.282797 -429.029535) (xy 156.263199 -429.015289)
			(xy 156.248958 -428.995689) (xy 156.241466 -428.972648) (xy 156.240988 -428.960534) (xy 155.307387 -428.960534)
			(xy 155.312494 -428.96424) (xy 155.326739 -428.983822) (xy 155.334235 -429.006847) (xy 155.334716 -429.018954)
			(xy 155.334716 -431.560478) (xy 155.334321 -431.572604) (xy 155.326829 -431.59567) (xy 155.312572 -431.61529)
			(xy 155.292949 -431.62954) (xy 155.26988 -431.637024) (xy 155.257754 -431.63744) (xy 154.317954 -431.63744)
			(xy 154.305835 -431.637027) (xy 154.282786 -431.629525) (xy 154.263184 -431.615268) (xy 154.248944 -431.595653)
			(xy 154.241462 -431.572598) (xy 154.240992 -431.560478) (xy 153.33472 -431.560478) (xy 153.33472 -432.560476)
			(xy 153.33422 -432.572523) (xy 153.326796 -432.595444) (xy 153.312665 -432.614959) (xy 153.293204 -432.629164)
			(xy 153.270311 -432.636674) (xy 153.258266 -432.637184) (xy 152.317958 -432.637184) (xy 152.305869 -432.636729)
			(xy 152.282871 -432.629264) (xy 152.263293 -432.615073) (xy 152.249043 -432.595539) (xy 152.241508 -432.572564)
			(xy 152.240996 -432.560476) (xy 151.307195 -432.560476) (xy 151.312447 -432.564281) (xy 151.326697 -432.583821)
			(xy 151.334221 -432.606805) (xy 151.334724 -432.618896) (xy 151.334724 -435.16042) (xy 151.334257 -435.172469)
			(xy 151.326822 -435.195391) (xy 151.312682 -435.214904) (xy 151.293215 -435.229108) (xy 151.270317 -435.236618)
			(xy 151.25827 -435.237128) (xy 150.317962 -435.237128) (xy 150.305867 -435.236724) (xy 150.28286 -435.229253)
			(xy 150.263278 -435.215052) (xy 150.24903 -435.195503) (xy 150.241504 -435.172514) (xy 150.241 -435.16042)
			(xy 149.334728 -435.16042) (xy 149.334728 -436.160418) (xy 149.334355 -436.172545) (xy 149.326853 -436.19561)
			(xy 149.312591 -436.215228) (xy 149.292964 -436.229477) (xy 149.269893 -436.236963) (xy 149.257766 -436.23738)
			(xy 148.317966 -436.23738) (xy 148.305851 -436.236918) (xy 148.28281 -436.229423) (xy 148.26321 -436.215178)
			(xy 148.248969 -436.195576) (xy 148.24148 -436.172533) (xy 148.241004 -436.160418) (xy 147.306851 -436.160418)
			(xy 147.312454 -436.164477) (xy 147.326704 -436.184017) (xy 147.334229 -436.207001) (xy 147.334732 -436.219092)
			(xy 147.334732 -438.760616) (xy 147.334254 -438.772664) (xy 147.326821 -438.795584) (xy 147.312684 -438.815097)
			(xy 147.293219 -438.829301) (xy 147.270324 -438.836812) (xy 147.258278 -438.837324) (xy 146.31797 -438.837324)
			(xy 146.305875 -438.836918) (xy 146.282868 -438.829448) (xy 146.263285 -438.815247) (xy 146.249037 -438.795699)
			(xy 146.241512 -438.77271) (xy 146.241008 -438.760616) (xy 145.334736 -438.760616) (xy 145.334736 -439.760614)
			(xy 148.241004 -439.760614) (xy 148.241004 -437.21909) (xy 148.241503 -437.206978) (xy 148.248989 -437.183941)
			(xy 148.263225 -437.164342) (xy 148.282819 -437.1501) (xy 148.305854 -437.142607) (xy 148.317966 -437.142128)
			(xy 149.257766 -437.142128) (xy 149.269886 -437.142589) (xy 149.292942 -437.15007) (xy 149.312557 -437.164312)
			(xy 149.32681 -437.183918) (xy 149.334304 -437.20697) (xy 149.334728 -437.21909) (xy 149.334728 -438.760616)
			(xy 150.241 -438.760616) (xy 150.241 -436.219092) (xy 150.241453 -436.207041) (xy 150.248888 -436.184116)
			(xy 150.263031 -436.1646) (xy 150.282502 -436.150397) (xy 150.305405 -436.142891) (xy 150.317454 -436.142384)
			(xy 151.257762 -436.142384) (xy 151.269854 -436.142841) (xy 151.292861 -436.150292) (xy 151.306838 -436.160418)
			(xy 152.240996 -436.160418) (xy 152.240996 -433.618894) (xy 152.241506 -433.606783) (xy 152.24899 -433.583747)
			(xy 152.263224 -433.564149) (xy 152.282815 -433.549906) (xy 152.305848 -433.542412) (xy 152.317958 -433.541932)
			(xy 153.257758 -433.541932) (xy 153.269878 -433.542396) (xy 153.292934 -433.549876) (xy 153.31255 -433.564116)
			(xy 153.326803 -433.583722) (xy 153.334297 -433.606774) (xy 153.33472 -433.618894) (xy 153.33472 -435.16042)
			(xy 154.240992 -435.16042) (xy 154.240992 -432.618896) (xy 154.241456 -432.606846) (xy 154.248889 -432.583922)
			(xy 154.263029 -432.564407) (xy 154.282498 -432.550204) (xy 154.305398 -432.542696) (xy 154.317446 -432.542188)
			(xy 155.257754 -432.542188) (xy 155.269846 -432.542647) (xy 155.292853 -432.550097) (xy 155.307181 -432.560476)
			(xy 156.240988 -432.560476) (xy 156.240988 -430.018952) (xy 156.241419 -430.0069) (xy 156.248863 -429.983975)
			(xy 156.263012 -429.964461) (xy 156.282487 -429.950259) (xy 156.305392 -429.942752) (xy 156.317442 -429.942244)
			(xy 157.25775 -429.942244) (xy 157.269837 -429.94275) (xy 157.292837 -429.950193) (xy 157.312418 -429.96437)
			(xy 157.32667 -429.983896) (xy 157.334203 -430.006866) (xy 157.334712 -430.018952) (xy 157.334712 -432.560476)
			(xy 157.33422 -432.572524) (xy 157.326795 -432.595447) (xy 157.312662 -432.614962) (xy 157.293199 -432.629166)
			(xy 157.270304 -432.636675) (xy 157.258258 -432.637184) (xy 156.31795 -432.637184) (xy 156.305865 -432.636651)
			(xy 156.28287 -432.62921) (xy 156.263292 -432.61504) (xy 156.249039 -432.595522) (xy 156.241501 -432.572559)
			(xy 156.240988 -432.560476) (xy 155.307181 -432.560476) (xy 155.312438 -432.564284) (xy 155.326688 -432.583823)
			(xy 155.334213 -432.606806) (xy 155.334716 -432.618896) (xy 155.334716 -433.130695) (xy 197.035917 -433.130695)
			(xy 197.035917 -432.953425) (xy 197.04387 -432.776334) (xy 197.059761 -432.599778) (xy 197.083556 -432.424113)
			(xy 197.115209 -432.249692) (xy 197.154655 -432.076867) (xy 197.201815 -431.905986) (xy 197.256594 -431.737392)
			(xy 197.318882 -431.571427) (xy 197.388554 -431.408422) (xy 197.465468 -431.248708) (xy 197.549471 -431.092605)
			(xy 197.640392 -430.940428) (xy 197.738049 -430.792484) (xy 197.842246 -430.64907) (xy 197.952772 -430.510475)
			(xy 198.069404 -430.376978) (xy 198.191909 -430.248849) (xy 198.320038 -430.126344) (xy 198.453535 -430.009712)
			(xy 198.59213 -429.899186) (xy 198.735544 -429.794989) (xy 198.883488 -429.697332) (xy 199.035665 -429.606411)
			(xy 199.191768 -429.522408) (xy 199.351482 -429.445494) (xy 199.514487 -429.375822) (xy 199.680452 -429.313534)
			(xy 199.849046 -429.258755) (xy 200.019927 -429.211595) (xy 200.192752 -429.172149) (xy 200.367173 -429.140496)
			(xy 200.542838 -429.116701) (xy 200.719394 -429.10081) (xy 200.896485 -429.092857) (xy 201.073755 -429.092857)
			(xy 201.250846 -429.10081) (xy 201.427402 -429.116701) (xy 201.603067 -429.140496) (xy 201.777488 -429.172149)
			(xy 201.950313 -429.211595) (xy 202.121194 -429.258755) (xy 202.289788 -429.313534) (xy 202.455753 -429.375822)
			(xy 202.618758 -429.445494) (xy 202.778472 -429.522408) (xy 202.934575 -429.606411) (xy 203.086752 -429.697332)
			(xy 203.234696 -429.794989) (xy 203.37811 -429.899186) (xy 203.516705 -430.009712) (xy 203.650202 -430.126344)
			(xy 203.778331 -430.248849) (xy 203.900836 -430.376978) (xy 204.017468 -430.510475) (xy 204.127994 -430.64907)
			(xy 204.232191 -430.792484) (xy 204.329848 -430.940428) (xy 204.420769 -431.092605) (xy 204.504772 -431.248708)
			(xy 204.581686 -431.408422) (xy 204.651358 -431.571427) (xy 204.713646 -431.737392) (xy 204.768425 -431.905986)
			(xy 204.815585 -432.076867) (xy 204.855031 -432.249692) (xy 204.886684 -432.424113) (xy 204.910479 -432.599778)
			(xy 204.92637 -432.776334) (xy 204.934323 -432.953425) (xy 204.93482 -433.04206) (xy 204.934323 -433.130695)
			(xy 204.92637 -433.307786) (xy 204.910479 -433.484342) (xy 204.886684 -433.660007) (xy 204.855031 -433.834428)
			(xy 204.815585 -434.007253) (xy 204.768425 -434.178134) (xy 204.713646 -434.346728) (xy 204.651358 -434.512693)
			(xy 204.581686 -434.675698) (xy 204.504772 -434.835412) (xy 204.420769 -434.991515) (xy 204.329848 -435.143692)
			(xy 204.232191 -435.291636) (xy 204.127994 -435.43505) (xy 204.017468 -435.573645) (xy 203.900836 -435.707142)
			(xy 203.778331 -435.835271) (xy 203.650202 -435.957776) (xy 203.516705 -436.074408) (xy 203.37811 -436.184934)
			(xy 203.234696 -436.289131) (xy 203.086752 -436.386788) (xy 202.934575 -436.477709) (xy 202.778472 -436.561712)
			(xy 202.618758 -436.638626) (xy 202.455753 -436.708298) (xy 202.289788 -436.770586) (xy 202.121194 -436.825365)
			(xy 201.950313 -436.872525) (xy 201.777488 -436.911971) (xy 201.603067 -436.943624) (xy 201.427402 -436.967419)
			(xy 201.250846 -436.98331) (xy 201.073755 -436.991263) (xy 200.896485 -436.991263) (xy 200.719394 -436.98331)
			(xy 200.542838 -436.967419) (xy 200.367173 -436.943624) (xy 200.192752 -436.911971) (xy 200.019927 -436.872525)
			(xy 199.849046 -436.825365) (xy 199.680452 -436.770586) (xy 199.514487 -436.708298) (xy 199.351482 -436.638626)
			(xy 199.191768 -436.561712) (xy 199.035665 -436.477709) (xy 198.883488 -436.386788) (xy 198.735544 -436.289131)
			(xy 198.59213 -436.184934) (xy 198.453535 -436.074408) (xy 198.320038 -435.957776) (xy 198.191909 -435.835271)
			(xy 198.069404 -435.707142) (xy 197.952772 -435.573645) (xy 197.842246 -435.43505) (xy 197.738049 -435.291636)
			(xy 197.640392 -435.143692) (xy 197.549471 -434.991515) (xy 197.465468 -434.835412) (xy 197.388554 -434.675698)
			(xy 197.318882 -434.512693) (xy 197.256594 -434.346728) (xy 197.201815 -434.178134) (xy 197.154655 -434.007253)
			(xy 197.115209 -433.834428) (xy 197.083556 -433.660007) (xy 197.059761 -433.484342) (xy 197.04387 -433.307786)
			(xy 197.035917 -433.130695) (xy 155.334716 -433.130695) (xy 155.334716 -435.16042) (xy 155.334257 -435.17247)
			(xy 155.326821 -435.195393) (xy 155.312679 -435.214907) (xy 155.29321 -435.22911) (xy 155.27031 -435.236619)
			(xy 155.258262 -435.237128) (xy 154.317954 -435.237128) (xy 154.305859 -435.236731) (xy 154.282851 -435.229258)
			(xy 154.263269 -435.215054) (xy 154.249022 -435.195505) (xy 154.241496 -435.172514) (xy 154.240992 -435.16042)
			(xy 153.33472 -435.16042) (xy 153.33472 -436.160418) (xy 153.334354 -436.172546) (xy 153.326852 -436.195612)
			(xy 153.312588 -436.215231) (xy 153.292958 -436.22948) (xy 153.269886 -436.236964) (xy 153.257758 -436.23738)
			(xy 152.317958 -436.23738) (xy 152.305843 -436.236924) (xy 152.282801 -436.229428) (xy 152.263202 -436.215181)
			(xy 152.248961 -436.195577) (xy 152.241472 -436.172533) (xy 152.240996 -436.160418) (xy 151.306838 -436.160418)
			(xy 151.312445 -436.16448) (xy 151.326695 -436.184019) (xy 151.334221 -436.207002) (xy 151.334724 -436.219092)
			(xy 151.334724 -438.760616) (xy 151.334254 -438.772665) (xy 151.32682 -438.795587) (xy 151.312681 -438.8151)
			(xy 151.293214 -438.829304) (xy 151.270317 -438.836814) (xy 151.25827 -438.837324) (xy 150.317962 -438.837324)
			(xy 150.305867 -438.836924) (xy 150.282859 -438.829453) (xy 150.263277 -438.81525) (xy 150.249029 -438.795701)
			(xy 150.241504 -438.77271) (xy 150.241 -438.760616) (xy 149.334728 -438.760616) (xy 149.334728 -439.760614)
			(xy 152.240996 -439.760614) (xy 152.240996 -437.21909) (xy 152.241503 -437.206979) (xy 152.248988 -437.183943)
			(xy 152.263222 -437.164345) (xy 152.282814 -437.150102) (xy 152.305847 -437.142608) (xy 152.317958 -437.142128)
			(xy 153.257758 -437.142128) (xy 153.269878 -437.142595) (xy 153.292933 -437.150075) (xy 153.312548 -437.164315)
			(xy 153.326801 -437.18392) (xy 153.334296 -437.206971) (xy 153.33472 -437.21909) (xy 153.33472 -438.760616)
			(xy 154.240992 -438.760616) (xy 154.240992 -436.219092) (xy 154.241453 -436.207042) (xy 154.248887 -436.184118)
			(xy 154.263028 -436.164603) (xy 154.282497 -436.1504) (xy 154.305398 -436.142892) (xy 154.317446 -436.142384)
			(xy 155.257754 -436.142384) (xy 155.269846 -436.142847) (xy 155.292852 -436.150297) (xy 155.306825 -436.160418)
			(xy 156.240988 -436.160418) (xy 156.240988 -433.618894) (xy 156.241506 -433.606784) (xy 156.248989 -433.583749)
			(xy 156.263221 -433.564152) (xy 156.28281 -433.549909) (xy 156.30584 -433.542413) (xy 156.31795 -433.541932)
			(xy 157.25775 -433.541932) (xy 157.269867 -433.542369) (xy 157.29291 -433.549869) (xy 157.312511 -433.564121)
			(xy 157.326751 -433.583729) (xy 157.334238 -433.606777) (xy 157.334712 -433.618894) (xy 157.334712 -436.160418)
			(xy 157.334205 -436.172529) (xy 157.326718 -436.195564) (xy 157.312484 -436.215161) (xy 157.292893 -436.229404)
			(xy 157.26986 -436.2369) (xy 157.25775 -436.23738) (xy 156.31795 -436.23738) (xy 156.305835 -436.236931)
			(xy 156.282793 -436.229432) (xy 156.263193 -436.215184) (xy 156.248953 -436.195578) (xy 156.241464 -436.172534)
			(xy 156.240988 -436.160418) (xy 155.306825 -436.160418) (xy 155.312437 -436.164483) (xy 155.326687 -436.18402)
			(xy 155.334212 -436.207002) (xy 155.334716 -436.219092) (xy 155.334716 -438.760616) (xy 155.334254 -438.772665)
			(xy 155.326819 -438.795589) (xy 155.312678 -438.815103) (xy 155.293209 -438.829306) (xy 155.27031 -438.836815)
			(xy 155.258262 -438.837324) (xy 154.317954 -438.837324) (xy 154.305858 -438.836931) (xy 154.28285 -438.829457)
			(xy 154.263268 -438.815253) (xy 154.24902 -438.795702) (xy 154.241496 -438.77271) (xy 154.240992 -438.760616)
			(xy 153.33472 -438.760616) (xy 153.33472 -439.760614) (xy 156.240988 -439.760614) (xy 156.240988 -437.21909)
			(xy 156.241503 -437.20698) (xy 156.248987 -437.183945) (xy 156.263219 -437.164348) (xy 156.282809 -437.150105)
			(xy 156.30584 -437.142609) (xy 156.31795 -437.142128) (xy 157.25775 -437.142128) (xy 157.269866 -437.142569)
			(xy 157.292909 -437.150069) (xy 157.312509 -437.164319) (xy 157.32675 -437.183927) (xy 157.334237 -437.206974)
			(xy 157.334712 -437.21909) (xy 157.334712 -438.760616) (xy 314.141104 -438.760616) (xy 314.141104 -436.219092)
			(xy 314.141553 -436.207041) (xy 314.148989 -436.184115) (xy 314.163132 -436.164599) (xy 314.182605 -436.150396)
			(xy 314.205509 -436.14289) (xy 314.217558 -436.142384) (xy 315.157866 -436.142384) (xy 315.169958 -436.142837)
			(xy 315.192965 -436.15029) (xy 315.206945 -436.160418) (xy 316.1411 -436.160418) (xy 316.1411 -433.618894)
			(xy 316.141606 -433.606783) (xy 316.14909 -433.583746) (xy 316.163325 -433.564148) (xy 316.182917 -433.549905)
			(xy 316.205951 -433.542411) (xy 316.218062 -433.541932) (xy 317.157862 -433.541932) (xy 317.169982 -433.542392)
			(xy 317.193039 -433.549873) (xy 317.212654 -433.564115) (xy 317.226907 -433.583722) (xy 317.234401 -433.606774)
			(xy 317.234824 -433.618894) (xy 317.234824 -435.16042) (xy 318.141096 -435.16042) (xy 318.141096 -432.618896)
			(xy 318.141557 -432.606846) (xy 318.14899 -432.583921) (xy 318.163131 -432.564406) (xy 318.182601 -432.550202)
			(xy 318.205502 -432.542696) (xy 318.21755 -432.542188) (xy 319.157858 -432.542188) (xy 319.16995 -432.542644)
			(xy 319.192958 -432.550095) (xy 319.207287 -432.560476) (xy 320.141092 -432.560476) (xy 320.141092 -430.018952)
			(xy 320.141519 -430.0069) (xy 320.148964 -429.983974) (xy 320.163113 -429.96446) (xy 320.18259 -429.950258)
			(xy 320.205495 -429.942752) (xy 320.217546 -429.942244) (xy 321.157854 -429.942244) (xy 321.169942 -429.942747)
			(xy 321.192941 -429.950191) (xy 321.212522 -429.964368) (xy 321.226774 -429.983895) (xy 321.234307 -430.006866)
			(xy 321.234816 -430.018952) (xy 321.234816 -431.560478) (xy 322.141088 -431.560478) (xy 322.141088 -429.018954)
			(xy 322.141572 -429.006842) (xy 322.149066 -428.983806) (xy 322.163306 -428.964209) (xy 322.182902 -428.949967)
			(xy 322.205938 -428.942472) (xy 322.21805 -428.941992) (xy 323.15785 -428.941992) (xy 323.169963 -428.942468)
			(xy 323.193 -428.949964) (xy 323.207544 -428.960534) (xy 324.141084 -428.960534) (xy 324.141084 -426.41901)
			(xy 324.141469 -426.406883) (xy 324.148964 -426.383817) (xy 324.163223 -426.364198) (xy 324.182849 -426.349948)
			(xy 324.205919 -426.342464) (xy 324.218046 -426.342048) (xy 325.157846 -426.342048) (xy 325.169964 -426.342473)
			(xy 325.19301 -426.349974) (xy 325.212612 -426.364228) (xy 325.226852 -426.38384) (xy 325.234336 -426.406892)
			(xy 325.234808 -426.41901) (xy 325.234808 -427.960536) (xy 326.14108 -427.960536) (xy 326.14108 -425.419012)
			(xy 326.14157 -425.406964) (xy 326.148997 -425.384043) (xy 326.163131 -425.364528) (xy 326.182593 -425.350324)
			(xy 326.205488 -425.342814) (xy 326.217534 -425.342304) (xy 327.157842 -425.342304) (xy 327.16993 -425.342771)
			(xy 327.192926 -425.350235) (xy 327.212502 -425.364423) (xy 327.226753 -425.383953) (xy 327.23429 -425.406925)
			(xy 327.234804 -425.419012) (xy 327.234804 -427.960536) (xy 327.234371 -427.972588) (xy 327.226929 -427.995514)
			(xy 327.212781 -428.015029) (xy 327.193306 -428.029231) (xy 327.1704 -428.036737) (xy 327.15835 -428.037244)
			(xy 326.218042 -428.037244) (xy 326.205953 -428.036757) (xy 326.182951 -428.029309) (xy 326.163369 -428.015129)
			(xy 326.149118 -427.995598) (xy 326.141587 -427.972623) (xy 326.14108 -427.960536) (xy 325.234808 -427.960536)
			(xy 325.234808 -428.960534) (xy 325.234318 -428.972646) (xy 325.226827 -428.995682) (xy 325.212588 -429.01528)
			(xy 325.192993 -429.029522) (xy 325.169958 -429.037016) (xy 325.157846 -429.037496) (xy 324.218046 -429.037496)
			(xy 324.205929 -429.037002) (xy 324.182877 -429.029526) (xy 324.163264 -429.015292) (xy 324.149011 -428.995694)
			(xy 324.141511 -428.972651) (xy 324.141084 -428.960534) (xy 323.207544 -428.960534) (xy 323.212597 -428.964206)
			(xy 323.226838 -428.983804) (xy 323.234332 -429.006841) (xy 323.234812 -429.018954) (xy 323.234812 -431.560478)
			(xy 323.23427 -431.572586) (xy 323.226795 -431.59562) (xy 323.212569 -431.615218) (xy 323.192985 -431.629462)
			(xy 323.169958 -431.636959) (xy 323.15785 -431.63744) (xy 322.21805 -431.63744) (xy 322.205931 -431.63703)
			(xy 322.182882 -431.629527) (xy 322.163279 -431.615269) (xy 322.14904 -431.595653) (xy 322.141558 -431.572598)
			(xy 322.141088 -431.560478) (xy 321.234816 -431.560478) (xy 321.234816 -432.560476) (xy 321.23432 -432.572523)
			(xy 321.226896 -432.595445) (xy 321.212764 -432.61496) (xy 321.193302 -432.629165) (xy 321.170408 -432.636675)
			(xy 321.158362 -432.637184) (xy 320.218054 -432.637184) (xy 320.205964 -432.636732) (xy 320.182966 -432.629266)
			(xy 320.163389 -432.615074) (xy 320.149139 -432.59554) (xy 320.141604 -432.572564) (xy 320.141092 -432.560476)
			(xy 319.207287 -432.560476) (xy 319.212542 -432.564283) (xy 319.226793 -432.583822) (xy 319.234317 -432.606805)
			(xy 319.23482 -432.618896) (xy 319.23482 -435.16042) (xy 319.234357 -435.172469) (xy 319.226921 -435.195392)
			(xy 319.212781 -435.214906) (xy 319.193312 -435.229109) (xy 319.170414 -435.236618) (xy 319.158366 -435.237128)
			(xy 318.218058 -435.237128) (xy 318.205963 -435.236728) (xy 318.182956 -435.229256) (xy 318.163374 -435.215053)
			(xy 318.149126 -435.195504) (xy 318.1416 -435.172514) (xy 318.141096 -435.16042) (xy 317.234824 -435.16042)
			(xy 317.234824 -436.160418) (xy 317.234455 -436.172545) (xy 317.226953 -436.195611) (xy 317.212689 -436.215229)
			(xy 317.193061 -436.229478) (xy 317.16999 -436.236963) (xy 317.157862 -436.23738) (xy 316.218062 -436.23738)
			(xy 316.205947 -436.236921) (xy 316.182906 -436.229425) (xy 316.163306 -436.21518) (xy 316.149065 -436.195576)
			(xy 316.141576 -436.172533) (xy 316.1411 -436.160418) (xy 315.206945 -436.160418) (xy 315.212549 -436.164478)
			(xy 315.2268 -436.184018) (xy 315.234325 -436.207001) (xy 315.234828 -436.219092) (xy 315.234828 -438.760616)
			(xy 315.234354 -438.772664) (xy 315.22692 -438.795586) (xy 315.212782 -438.815099) (xy 315.193317 -438.829302)
			(xy 315.170421 -438.836813) (xy 315.158374 -438.837324) (xy 314.218066 -438.837324) (xy 314.205971 -438.836921)
			(xy 314.182963 -438.829451) (xy 314.163381 -438.815249) (xy 314.149133 -438.7957) (xy 314.141608 -438.77271)
			(xy 314.141104 -438.760616) (xy 157.334712 -438.760616) (xy 157.334712 -439.760614) (xy 316.1411 -439.760614)
			(xy 316.1411 -437.21909) (xy 316.141603 -437.206979) (xy 316.149088 -437.183942) (xy 316.163324 -437.164343)
			(xy 316.182917 -437.150101) (xy 316.205951 -437.142607) (xy 316.218062 -437.142128) (xy 317.157862 -437.142128)
			(xy 317.169982 -437.142592) (xy 317.193038 -437.150073) (xy 317.212653 -437.164313) (xy 317.226905 -437.183919)
			(xy 317.2344 -437.20697) (xy 317.234824 -437.21909) (xy 317.234824 -438.760616) (xy 318.141096 -438.760616)
			(xy 318.141096 -436.219092) (xy 318.141553 -436.207042) (xy 318.148988 -436.184117) (xy 318.163129 -436.164601)
			(xy 318.1826 -436.150398) (xy 318.205501 -436.142892) (xy 318.21755 -436.142384) (xy 319.157858 -436.142384)
			(xy 319.16995 -436.142844) (xy 319.192956 -436.150294) (xy 319.206932 -436.160418) (xy 320.141092 -436.160418)
			(xy 320.141092 -433.618894) (xy 320.141606 -433.606784) (xy 320.149089 -433.583748) (xy 320.163322 -433.564151)
			(xy 320.182912 -433.549908) (xy 320.205944 -433.542412) (xy 320.218054 -433.541932) (xy 321.157854 -433.541932)
			(xy 321.169974 -433.542399) (xy 321.19303 -433.549878) (xy 321.212646 -433.564117) (xy 321.226898 -433.583723)
			(xy 321.234393 -433.606775) (xy 321.234816 -433.618894) (xy 321.234816 -435.16042) (xy 322.141088 -435.16042)
			(xy 322.141088 -432.618896) (xy 322.141556 -432.606847) (xy 322.148989 -432.583923) (xy 322.163128 -432.564409)
			(xy 322.182596 -432.550205) (xy 322.205494 -432.542697) (xy 322.217542 -432.542188) (xy 323.15785 -432.542188)
			(xy 323.169942 -432.542651) (xy 323.192949 -432.5501) (xy 323.207275 -432.560476) (xy 324.141084 -432.560476)
			(xy 324.141084 -430.018952) (xy 324.141519 -430.006901) (xy 324.148963 -429.983976) (xy 324.163111 -429.964463)
			(xy 324.182585 -429.950261) (xy 324.205488 -429.942753) (xy 324.217538 -429.942244) (xy 325.157846 -429.942244)
			(xy 325.169938 -429.942668) (xy 325.192941 -429.950138) (xy 325.212521 -429.964336) (xy 325.22677 -429.983878)
			(xy 325.2343 -430.006861) (xy 325.234808 -430.018952) (xy 325.234808 -431.560478) (xy 326.14108 -431.560478)
			(xy 326.14108 -429.018954) (xy 326.141473 -429.006833) (xy 326.148978 -428.983781) (xy 326.163239 -428.964176)
			(xy 326.18286 -428.949938) (xy 326.20592 -428.942459) (xy 326.218042 -428.941992) (xy 327.157842 -428.941992)
			(xy 327.169954 -428.942475) (xy 327.192991 -428.949968) (xy 327.207531 -428.960534) (xy 328.141076 -428.960534)
			(xy 328.141076 -426.41901) (xy 328.141469 -426.406884) (xy 328.148963 -426.383819) (xy 328.16322 -426.364201)
			(xy 328.182844 -426.34995) (xy 328.205912 -426.342465) (xy 328.218038 -426.342048) (xy 329.157838 -426.342048)
			(xy 329.169956 -426.342479) (xy 329.193002 -426.349978) (xy 329.212604 -426.36423) (xy 329.226844 -426.383841)
			(xy 329.234328 -426.406892) (xy 329.2348 -426.41901) (xy 329.2348 -427.960536) (xy 331.141324 -427.960536)
			(xy 331.141324 -425.419012) (xy 331.141724 -425.406927) (xy 331.149192 -425.383939) (xy 331.1634 -425.364386)
			(xy 331.182957 -425.350183) (xy 331.205947 -425.34272) (xy 331.218032 -425.342304) (xy 332.157832 -425.342304)
			(xy 332.169909 -425.342737) (xy 332.19288 -425.35021) (xy 332.212417 -425.364414) (xy 332.22661 -425.38396)
			(xy 332.23407 -425.406934) (xy 332.23454 -425.419012) (xy 332.23454 -427.960536) (xy 332.234067 -427.972609)
			(xy 332.226599 -427.995572) (xy 332.212403 -428.015106) (xy 332.192869 -428.0293) (xy 332.169905 -428.036768)
			(xy 332.157832 -428.037244) (xy 331.218032 -428.037244) (xy 331.205963 -428.036709) (xy 331.183003 -428.02926)
			(xy 331.163468 -428.01508) (xy 331.149271 -427.995558) (xy 331.141801 -427.972605) (xy 331.141324 -427.960536)
			(xy 329.2348 -427.960536) (xy 329.2348 -428.960534) (xy 329.234318 -428.972647) (xy 329.226826 -428.995684)
			(xy 329.212585 -429.015282) (xy 329.192988 -429.029524) (xy 329.169951 -429.037017) (xy 329.157838 -429.037496)
			(xy 328.218038 -429.037496) (xy 328.205921 -429.037008) (xy 328.182869 -429.029531) (xy 328.163256 -429.015295)
			(xy 328.149002 -428.995696) (xy 328.141503 -428.972651) (xy 328.141076 -428.960534) (xy 327.207531 -428.960534)
			(xy 327.212588 -428.964209) (xy 327.22683 -428.983805) (xy 327.234324 -429.006842) (xy 327.234804 -429.018954)
			(xy 327.234804 -431.560478) (xy 327.23427 -431.572587) (xy 327.226794 -431.595623) (xy 327.212567 -431.615221)
			(xy 327.19298 -431.629465) (xy 327.169951 -431.63696) (xy 327.157842 -431.63744) (xy 326.218042 -431.63744)
			(xy 326.205919 -431.637004) (xy 326.182858 -431.629521) (xy 326.16324 -431.615274) (xy 326.148988 -431.59566)
			(xy 326.141499 -431.572601) (xy 326.14108 -431.560478) (xy 325.234808 -431.560478) (xy 325.234808 -432.560476)
			(xy 325.23432 -432.572524) (xy 325.226895 -432.595448) (xy 325.212761 -432.614963) (xy 325.193297 -432.629168)
			(xy 325.1704 -432.636676) (xy 325.158354 -432.637184) (xy 324.218046 -432.637184) (xy 324.205961 -432.636654)
			(xy 324.182966 -432.629213) (xy 324.163387 -432.615042) (xy 324.149134 -432.595522) (xy 324.141597 -432.572559)
			(xy 324.141084 -432.560476) (xy 323.207275 -432.560476) (xy 323.212534 -432.564285) (xy 323.226784 -432.583823)
			(xy 323.234309 -432.606806) (xy 323.234812 -432.618896) (xy 323.234812 -435.16042) (xy 323.234357 -435.17247)
			(xy 323.22692 -435.195394) (xy 323.212778 -435.214908) (xy 323.193307 -435.229111) (xy 323.170406 -435.236619)
			(xy 323.158358 -435.237128) (xy 322.21805 -435.237128) (xy 322.20596 -435.23665) (xy 322.182955 -435.229203)
			(xy 322.163372 -435.21502) (xy 322.149121 -435.195487) (xy 322.141593 -435.172508) (xy 322.141088 -435.16042)
			(xy 321.234816 -435.16042) (xy 321.234816 -436.160418) (xy 321.234454 -436.172546) (xy 321.226952 -436.195613)
			(xy 321.212686 -436.215232) (xy 321.193056 -436.229481) (xy 321.169983 -436.236965) (xy 321.157854 -436.23738)
			(xy 320.218054 -436.23738) (xy 320.205939 -436.236928) (xy 320.182897 -436.22943) (xy 320.163298 -436.215182)
			(xy 320.149057 -436.195578) (xy 320.141568 -436.172533) (xy 320.141092 -436.160418) (xy 319.206932 -436.160418)
			(xy 319.212541 -436.164481) (xy 319.226791 -436.184019) (xy 319.234316 -436.207002) (xy 319.23482 -436.219092)
			(xy 319.23482 -438.760616) (xy 319.234354 -438.772665) (xy 319.226919 -438.795588) (xy 319.212779 -438.815101)
			(xy 319.193312 -438.829305) (xy 319.170413 -438.836814) (xy 319.158366 -438.837324) (xy 318.218058 -438.837324)
			(xy 318.205963 -438.836928) (xy 318.182955 -438.829455) (xy 318.163372 -438.815252) (xy 318.149124 -438.795701)
			(xy 318.1416 -438.77271) (xy 318.141096 -438.760616) (xy 317.234824 -438.760616) (xy 317.234824 -439.760614)
			(xy 320.141092 -439.760614) (xy 320.141092 -437.21909) (xy 320.141603 -437.20698) (xy 320.149087 -437.183944)
			(xy 320.163321 -437.164346) (xy 320.182912 -437.150104) (xy 320.205944 -437.142608) (xy 320.218054 -437.142128)
			(xy 321.157854 -437.142128) (xy 321.169973 -437.142599) (xy 321.193029 -437.150077) (xy 321.212644 -437.164316)
			(xy 321.226897 -437.183921) (xy 321.234392 -437.206971) (xy 321.234816 -437.21909) (xy 321.234816 -438.760616)
			(xy 322.141088 -438.760616) (xy 322.141088 -436.219092) (xy 322.141553 -436.207043) (xy 322.148986 -436.184119)
			(xy 322.163126 -436.164604) (xy 322.182595 -436.150401) (xy 322.205494 -436.142893) (xy 322.217542 -436.142384)
			(xy 323.15785 -436.142384) (xy 323.169941 -436.142851) (xy 323.192948 -436.150299) (xy 323.206918 -436.160418)
			(xy 324.141084 -436.160418) (xy 324.141084 -433.618894) (xy 324.141456 -433.606766) (xy 324.148955 -433.5837)
			(xy 324.163218 -433.564081) (xy 324.182846 -433.549831) (xy 324.205918 -433.542348) (xy 324.218046 -433.541932)
			(xy 325.157846 -433.541932) (xy 325.169962 -433.542372) (xy 325.193006 -433.549872) (xy 325.212607 -433.564122)
			(xy 325.226847 -433.58373) (xy 325.234334 -433.606777) (xy 325.234808 -433.618894) (xy 325.234808 -435.16042)
			(xy 326.14108 -435.16042) (xy 326.14108 -432.618896) (xy 326.141556 -432.606848) (xy 326.148988 -432.583925)
			(xy 326.163125 -432.564411) (xy 326.182591 -432.550208) (xy 326.205487 -432.542698) (xy 326.217534 -432.542188)
			(xy 327.157842 -432.542188) (xy 327.169939 -432.542572) (xy 327.192949 -432.550047) (xy 327.207325 -432.560476)
			(xy 328.141076 -432.560476) (xy 328.141076 -430.018952) (xy 328.141518 -430.006902) (xy 328.148961 -429.983979)
			(xy 328.163108 -429.964466) (xy 328.18258 -429.950263) (xy 328.205481 -429.942754) (xy 328.21753 -429.942244)
			(xy 329.157838 -429.942244) (xy 329.16993 -429.942675) (xy 329.192933 -429.950143) (xy 329.212512 -429.964338)
			(xy 329.226761 -429.983879) (xy 329.234292 -430.006861) (xy 329.2348 -430.018952) (xy 329.2348 -431.560478)
			(xy 331.141324 -431.560478) (xy 331.141324 -429.018954) (xy 331.141768 -429.006864) (xy 331.149235 -428.983864)
			(xy 331.163428 -428.964286) (xy 331.182965 -428.950037) (xy 331.205943 -428.942503) (xy 331.218032 -428.941992)
			(xy 332.157832 -428.941992) (xy 332.169942 -428.942389) (xy 332.192969 -428.949896) (xy 332.207563 -428.960534)
			(xy 333.14132 -428.960534) (xy 333.14132 -426.41901) (xy 333.141816 -426.406923) (xy 333.149267 -426.383926)
			(xy 333.163447 -426.364348) (xy 333.182973 -426.350096) (xy 333.205943 -426.34256) (xy 333.218028 -426.342048)
			(xy 334.157828 -426.342048) (xy 334.169933 -426.342492) (xy 334.192952 -426.349993) (xy 334.212521 -426.364249)
			(xy 334.226716 -426.383861) (xy 334.234145 -426.406904) (xy 334.234536 -426.41901) (xy 334.234536 -427.960536)
			(xy 335.141316 -427.960536) (xy 335.141316 -425.419012) (xy 335.141723 -425.406928) (xy 335.149191 -425.383941)
			(xy 335.163397 -425.364389) (xy 335.182952 -425.350185) (xy 335.205939 -425.342722) (xy 335.218024 -425.342304)
			(xy 336.157824 -425.342304) (xy 336.169901 -425.342744) (xy 336.192871 -425.350215) (xy 336.212409 -425.364417)
			(xy 336.226602 -425.383961) (xy 336.234061 -425.406935) (xy 336.234532 -425.419012) (xy 336.234532 -427.960536)
			(xy 336.234067 -427.97261) (xy 336.226598 -427.995574) (xy 336.2124 -428.015109) (xy 336.192864 -428.029303)
			(xy 336.169898 -428.036769) (xy 336.157824 -428.037244) (xy 335.218024 -428.037244) (xy 335.205954 -428.036716)
			(xy 335.182994 -428.029264) (xy 335.16346 -428.015083) (xy 335.149263 -427.99556) (xy 335.141793 -427.972605)
			(xy 335.141316 -427.960536) (xy 334.234536 -427.960536) (xy 334.234536 -428.960534) (xy 334.234121 -428.972628)
			(xy 334.226652 -428.995634) (xy 334.212453 -429.015215) (xy 334.192907 -429.029464) (xy 334.16992 -429.03699)
			(xy 334.157828 -429.037496) (xy 333.218028 -429.037496) (xy 333.20592 -429.03706) (xy 333.182893 -429.029567)
			(xy 333.163319 -429.015311) (xy 333.149124 -428.995693) (xy 333.141703 -428.972643) (xy 333.14132 -428.960534)
			(xy 332.207563 -428.960534) (xy 332.212541 -428.964163) (xy 332.226734 -428.983788) (xy 332.234156 -429.006843)
			(xy 332.23454 -429.018954) (xy 332.23454 -431.560478) (xy 332.234073 -431.572568) (xy 332.22662 -431.595572)
			(xy 332.212434 -431.615154) (xy 332.192899 -431.629404) (xy 332.169921 -431.636933) (xy 332.157832 -431.63744)
			(xy 331.218032 -431.63744) (xy 331.205929 -431.636957) (xy 331.182909 -431.629471) (xy 331.163339 -431.615225)
			(xy 331.149142 -431.59562) (xy 331.141713 -431.572582) (xy 331.141324 -431.560478) (xy 329.2348 -431.560478)
			(xy 329.2348 -432.560476) (xy 329.23432 -432.572525) (xy 329.226894 -432.59545) (xy 329.212758 -432.614966)
			(xy 329.193292 -432.62917) (xy 329.170393 -432.636677) (xy 329.158346 -432.637184) (xy 328.218038 -432.637184)
			(xy 328.205953 -432.636661) (xy 328.182957 -432.629217) (xy 328.163379 -432.615044) (xy 328.149126 -432.595524)
			(xy 328.141589 -432.572559) (xy 328.141076 -432.560476) (xy 327.207325 -432.560476) (xy 327.212532 -432.564253)
			(xy 327.226779 -432.583806) (xy 327.234302 -432.606801) (xy 327.234804 -432.618896) (xy 327.234804 -435.16042)
			(xy 327.234357 -435.172471) (xy 327.226919 -435.195396) (xy 327.212775 -435.214911) (xy 327.193302 -435.229114)
			(xy 327.170399 -435.23662) (xy 327.15835 -435.237128) (xy 326.218042 -435.237128) (xy 326.205951 -435.236656)
			(xy 326.182947 -435.229207) (xy 326.163363 -435.215023) (xy 326.149113 -435.195488) (xy 326.141585 -435.172509)
			(xy 326.14108 -435.16042) (xy 325.234808 -435.16042) (xy 325.234808 -436.160418) (xy 325.234305 -436.172529)
			(xy 325.226818 -436.195565) (xy 325.212582 -436.215163) (xy 325.19299 -436.229405) (xy 325.169957 -436.2369)
			(xy 325.157846 -436.23738) (xy 324.218046 -436.23738) (xy 324.205927 -436.236901) (xy 324.182873 -436.229424)
			(xy 324.163259 -436.215187) (xy 324.149005 -436.195584) (xy 324.141509 -436.172536) (xy 324.141084 -436.160418)
			(xy 323.206918 -436.160418) (xy 323.212532 -436.164484) (xy 323.226783 -436.184021) (xy 323.234308 -436.207002)
			(xy 323.234812 -436.219092) (xy 323.234812 -438.760616) (xy 323.234354 -438.772666) (xy 323.226918 -438.79559)
			(xy 323.212776 -438.815104) (xy 323.193307 -438.829307) (xy 323.170406 -438.836815) (xy 323.158358 -438.837324)
			(xy 322.21805 -438.837324) (xy 322.205959 -438.836849) (xy 322.182954 -438.829402) (xy 322.16337 -438.815219)
			(xy 322.149119 -438.795684) (xy 322.141593 -438.772705) (xy 322.141088 -438.760616) (xy 321.234816 -438.760616)
			(xy 321.234816 -439.760614) (xy 324.141084 -439.760614) (xy 324.141084 -437.21909) (xy 324.141452 -437.206962)
			(xy 324.148953 -437.183895) (xy 324.163216 -437.164276) (xy 324.182845 -437.150027) (xy 324.205918 -437.142544)
			(xy 324.218046 -437.142128) (xy 325.157846 -437.142128) (xy 325.169962 -437.142572) (xy 325.193005 -437.150071)
			(xy 325.212605 -437.164321) (xy 325.226845 -437.183927) (xy 325.234333 -437.206974) (xy 325.234808 -437.21909)
			(xy 325.234808 -438.760616) (xy 326.14108 -438.760616) (xy 326.14108 -436.219092) (xy 326.141553 -436.207043)
			(xy 326.148985 -436.184121) (xy 326.163124 -436.164607) (xy 326.18259 -436.150403) (xy 326.205487 -436.142894)
			(xy 326.217534 -436.142384) (xy 327.157842 -436.142384) (xy 327.169938 -436.142772) (xy 327.192948 -436.150246)
			(xy 327.206971 -436.160418) (xy 328.141076 -436.160418) (xy 328.141076 -433.618894) (xy 328.141456 -433.606767)
			(xy 328.148954 -433.583702) (xy 328.163215 -433.564084) (xy 328.182841 -433.549834) (xy 328.205911 -433.542349)
			(xy 328.218038 -433.541932) (xy 329.157838 -433.541932) (xy 329.169954 -433.542379) (xy 329.192997 -433.549876)
			(xy 329.212598 -433.564125) (xy 329.226838 -433.583731) (xy 329.234326 -433.606778) (xy 329.2348 -433.618894)
			(xy 329.2348 -435.16042) (xy 331.141324 -435.16042) (xy 331.141324 -432.618896) (xy 331.14171 -432.60681)
			(xy 331.149182 -432.583822) (xy 331.163394 -432.564268) (xy 331.182954 -432.550066) (xy 331.205946 -432.542604)
			(xy 331.218032 -432.542188) (xy 332.157832 -432.542188) (xy 332.169908 -432.542637) (xy 332.192875 -432.550108)
			(xy 332.20714 -432.560476) (xy 333.14132 -432.560476) (xy 333.14132 -430.018952) (xy 333.141724 -430.006872)
			(xy 333.149203 -429.983899) (xy 333.163414 -429.96436) (xy 333.182967 -429.950168) (xy 333.205948 -429.942712)
			(xy 333.218028 -429.942244) (xy 334.157828 -429.942244) (xy 334.169899 -429.942739) (xy 334.192859 -429.950204)
			(xy 334.212392 -429.964394) (xy 334.226587 -429.983923) (xy 334.234058 -430.006881) (xy 334.234536 -430.018952)
			(xy 334.234536 -431.560478) (xy 335.141316 -431.560478) (xy 335.141316 -429.018954) (xy 335.141768 -429.006864)
			(xy 335.149234 -428.983866) (xy 335.163426 -428.964289) (xy 335.18296 -428.950039) (xy 335.205936 -428.942504)
			(xy 335.218024 -428.941992) (xy 336.157824 -428.941992) (xy 336.169933 -428.942396) (xy 336.19296 -428.949901)
			(xy 336.207549 -428.960534) (xy 337.141312 -428.960534) (xy 337.141312 -426.41901) (xy 337.141815 -426.406924)
			(xy 337.149266 -426.383928) (xy 337.163444 -426.364351) (xy 337.182968 -426.350099) (xy 337.205936 -426.342562)
			(xy 337.21802 -426.342048) (xy 338.15782 -426.342048) (xy 338.169925 -426.342499) (xy 338.192944 -426.349997)
			(xy 338.212512 -426.364252) (xy 338.226708 -426.383863) (xy 338.234137 -426.406904) (xy 338.234528 -426.41901)
			(xy 338.234528 -427.960536) (xy 339.141308 -427.960536) (xy 339.141308 -425.419012) (xy 339.141723 -425.406928)
			(xy 339.149189 -425.383943) (xy 339.163394 -425.364392) (xy 339.182947 -425.350188) (xy 339.205932 -425.342723)
			(xy 339.218016 -425.342304) (xy 340.157816 -425.342304) (xy 340.169893 -425.342751) (xy 340.192862 -425.350219)
			(xy 340.2124 -425.36442) (xy 340.226594 -425.383963) (xy 340.234053 -425.406935) (xy 340.234524 -425.419012)
			(xy 340.234524 -427.960536) (xy 340.234067 -427.972611) (xy 340.226596 -427.995577) (xy 340.212397 -428.015112)
			(xy 340.192859 -428.029306) (xy 340.169891 -428.03677) (xy 340.157816 -428.037244) (xy 339.218016 -428.037244)
			(xy 339.205946 -428.036723) (xy 339.182985 -428.029269) (xy 339.163451 -428.015086) (xy 339.149255 -427.995561)
			(xy 339.141785 -427.972606) (xy 339.141308 -427.960536) (xy 338.234528 -427.960536) (xy 338.234528 -428.960534)
			(xy 338.234121 -428.972629) (xy 338.226651 -428.995636) (xy 338.21245 -429.015218) (xy 338.192902 -429.029466)
			(xy 338.169913 -429.036992) (xy 338.15782 -429.037496) (xy 337.21802 -429.037496) (xy 337.205912 -429.037066)
			(xy 337.182885 -429.029572) (xy 337.163311 -429.015314) (xy 337.149116 -428.995695) (xy 337.141695 -428.972643)
			(xy 337.141312 -428.960534) (xy 336.207549 -428.960534) (xy 336.212532 -428.964166) (xy 336.226726 -428.983789)
			(xy 336.234148 -429.006843) (xy 336.234532 -429.018954) (xy 336.234532 -431.560478) (xy 336.234073 -431.572569)
			(xy 336.226619 -431.595574) (xy 336.212432 -431.615156) (xy 336.192894 -431.629407) (xy 336.169914 -431.636934)
			(xy 336.157824 -431.63744) (xy 335.218024 -431.63744) (xy 335.20592 -431.636964) (xy 335.182901 -431.629476)
			(xy 335.163331 -431.615228) (xy 335.149134 -431.595622) (xy 335.141705 -431.572583) (xy 335.141316 -431.560478)
			(xy 334.234536 -431.560478) (xy 334.234536 -432.560476) (xy 334.234016 -432.572547) (xy 334.226563 -432.595508)
			(xy 334.21238 -432.615043) (xy 334.192855 -432.62924) (xy 334.169898 -432.636708) (xy 334.157828 -432.637184)
			(xy 333.218028 -432.637184) (xy 333.205944 -432.636763) (xy 333.182959 -432.6293) (xy 333.163406 -432.615097)
			(xy 333.149202 -432.595545) (xy 333.141738 -432.57256) (xy 333.14132 -432.560476) (xy 332.20714 -432.560476)
			(xy 332.212412 -432.564308) (xy 332.226605 -432.58385) (xy 332.234068 -432.60682) (xy 332.23454 -432.618896)
			(xy 332.23454 -435.16042) (xy 332.234053 -435.172492) (xy 332.226589 -435.195455) (xy 332.212397 -435.214989)
			(xy 332.192865 -435.229184) (xy 332.169904 -435.236651) (xy 332.157832 -435.237128) (xy 331.218032 -435.237128)
			(xy 331.205953 -435.23666) (xy 331.182975 -435.229204) (xy 331.163426 -435.215011) (xy 331.14922 -435.195472)
			(xy 331.141748 -435.172499) (xy 331.141324 -435.16042) (xy 329.2348 -435.16042) (xy 329.2348 -436.160418)
			(xy 329.234304 -436.17253) (xy 329.226817 -436.195567) (xy 329.21258 -436.215165) (xy 329.192985 -436.229408)
			(xy 329.16995 -436.236901) (xy 329.157838 -436.23738) (xy 328.218038 -436.23738) (xy 328.205919 -436.236908)
			(xy 328.182864 -436.229428) (xy 328.16325 -436.21519) (xy 328.148997 -436.195586) (xy 328.141501 -436.172537)
			(xy 328.141076 -436.160418) (xy 327.206971 -436.160418) (xy 327.212531 -436.164451) (xy 327.226778 -436.184004)
			(xy 327.234301 -436.206997) (xy 327.234804 -436.219092) (xy 327.234804 -438.760616) (xy 327.234354 -438.772667)
			(xy 327.226917 -438.795592) (xy 327.212774 -438.815107) (xy 327.193302 -438.82931) (xy 327.170399 -438.836816)
			(xy 327.15835 -438.837324) (xy 326.218042 -438.837324) (xy 326.205951 -438.836856) (xy 326.182946 -438.829407)
			(xy 326.163362 -438.815222) (xy 326.149111 -438.795686) (xy 326.141585 -438.772705) (xy 326.14108 -438.760616)
			(xy 325.234808 -438.760616) (xy 325.234808 -439.760614) (xy 328.141076 -439.760614) (xy 328.141076 -437.21909)
			(xy 328.141452 -437.206963) (xy 328.148952 -437.183897) (xy 328.163213 -437.164279) (xy 328.18284 -437.15003)
			(xy 328.205911 -437.142545) (xy 328.218038 -437.142128) (xy 329.157838 -437.142128) (xy 329.169954 -437.142579)
			(xy 329.192996 -437.150076) (xy 329.212597 -437.164323) (xy 329.226837 -437.183929) (xy 329.234325 -437.206974)
			(xy 329.2348 -437.21909) (xy 329.2348 -438.760616) (xy 331.141324 -438.760616) (xy 331.141324 -436.219092)
			(xy 331.141706 -436.207006) (xy 331.14918 -436.184017) (xy 331.163393 -436.164464) (xy 331.182953 -436.150262)
			(xy 331.205945 -436.1428) (xy 331.218032 -436.142384) (xy 332.157832 -436.142384) (xy 332.169907 -436.142837)
			(xy 332.192874 -436.150307) (xy 332.206784 -436.160418) (xy 333.14132 -436.160418) (xy 333.14132 -433.618894)
			(xy 333.141802 -433.606806) (xy 333.149258 -433.583809) (xy 333.163441 -433.564231) (xy 333.18297 -433.54998)
			(xy 333.205942 -433.542444) (xy 333.218028 -433.541932) (xy 334.157828 -433.541932) (xy 334.169942 -433.542293)
			(xy 334.192975 -433.549804) (xy 334.212551 -433.564079) (xy 334.226743 -433.583714) (xy 334.234157 -433.606779)
			(xy 334.234536 -433.618894) (xy 334.234536 -435.16042) (xy 335.141316 -435.16042) (xy 335.141316 -432.618896)
			(xy 335.141709 -432.606811) (xy 335.149181 -432.583824) (xy 335.163391 -432.564271) (xy 335.182949 -432.550068)
			(xy 335.205938 -432.542605) (xy 335.218024 -432.542188) (xy 336.157824 -432.542188) (xy 336.169899 -432.542644)
			(xy 336.192867 -432.550113) (xy 336.207126 -432.560476) (xy 337.141312 -432.560476) (xy 337.141312 -430.018952)
			(xy 337.141724 -430.006873) (xy 337.149202 -429.983901) (xy 337.163411 -429.964363) (xy 337.182962 -429.950171)
			(xy 337.205941 -429.942713) (xy 337.21802 -429.942244) (xy 338.15782 -429.942244) (xy 338.169891 -429.942747)
			(xy 338.19285 -429.950209) (xy 338.212383 -429.964397) (xy 338.226578 -429.983924) (xy 338.234049 -430.006881)
			(xy 338.234528 -430.018952) (xy 338.234528 -431.560478) (xy 339.141308 -431.560478) (xy 339.141308 -429.018954)
			(xy 339.141768 -429.006865) (xy 339.149233 -428.983868) (xy 339.163423 -428.964292) (xy 339.182955 -428.950042)
			(xy 339.205929 -428.942505) (xy 339.218016 -428.941992) (xy 340.157816 -428.941992) (xy 340.169925 -428.942402)
			(xy 340.192951 -428.949905) (xy 340.207536 -428.960534) (xy 341.141304 -428.960534) (xy 341.141304 -426.41901)
			(xy 341.141815 -426.406925) (xy 341.149265 -426.38393) (xy 341.163441 -426.364353) (xy 341.182963 -426.350101)
			(xy 341.205928 -426.342563) (xy 341.218012 -426.342048) (xy 342.157812 -426.342048) (xy 342.169916 -426.342505)
			(xy 342.192935 -426.350002) (xy 342.212504 -426.364255) (xy 342.2267 -426.383864) (xy 342.234129 -426.406905)
			(xy 342.23452 -426.41901) (xy 342.23452 -427.960536) (xy 343.1413 -427.960536) (xy 343.1413 -425.419012)
			(xy 343.141723 -425.406929) (xy 343.149188 -425.383946) (xy 343.163392 -425.364394) (xy 343.182942 -425.35019)
			(xy 343.205925 -425.342724) (xy 343.218008 -425.342304) (xy 344.157808 -425.342304) (xy 344.169892 -425.342706)
			(xy 344.192877 -425.350177) (xy 344.212429 -425.364386) (xy 344.226632 -425.383941) (xy 344.234097 -425.406928)
			(xy 344.234516 -425.419012) (xy 344.234516 -427.960536) (xy 344.234067 -427.972612) (xy 344.226595 -427.995579)
			(xy 344.212395 -428.015115) (xy 344.192854 -428.029308) (xy 344.169884 -428.036771) (xy 344.157808 -428.037244)
			(xy 343.218008 -428.037244) (xy 343.205937 -428.03673) (xy 343.182977 -428.029274) (xy 343.163443 -428.015089)
			(xy 343.149247 -427.995563) (xy 343.141777 -427.972606) (xy 343.1413 -427.960536) (xy 342.23452 -427.960536)
			(xy 342.23452 -428.960534) (xy 342.234121 -428.972629) (xy 342.22665 -428.995638) (xy 342.212447 -429.015221)
			(xy 342.192897 -429.029469) (xy 342.169906 -429.036993) (xy 342.157812 -429.037496) (xy 341.218012 -429.037496)
			(xy 341.205903 -429.037073) (xy 341.182876 -429.029577) (xy 341.163302 -429.015317) (xy 341.149107 -428.995696)
			(xy 341.141687 -428.972644) (xy 341.141304 -428.960534) (xy 340.207536 -428.960534) (xy 340.212524 -428.964169)
			(xy 340.226718 -428.983791) (xy 340.23414 -429.006844) (xy 340.234524 -429.018954) (xy 340.234524 -431.560478)
			(xy 340.234073 -431.57257) (xy 340.226618 -431.595576) (xy 340.212429 -431.615159) (xy 340.192889 -431.629409)
			(xy 340.169906 -431.636935) (xy 340.157816 -431.63744) (xy 339.218016 -431.63744) (xy 339.205912 -431.63697)
			(xy 339.182892 -431.62948) (xy 339.163322 -431.615231) (xy 339.149126 -431.595623) (xy 339.141697 -431.572583)
			(xy 339.141308 -431.560478) (xy 338.234528 -431.560478) (xy 338.234528 -432.560476) (xy 338.234067 -432.572555)
			(xy 338.226609 -432.595534) (xy 338.212414 -432.615083) (xy 338.192873 -432.629288) (xy 338.169899 -432.63676)
			(xy 338.15782 -432.637184) (xy 337.21802 -432.637184) (xy 337.205936 -432.63677) (xy 337.18295 -432.629305)
			(xy 337.163397 -432.6151) (xy 337.149193 -432.595547) (xy 337.14173 -432.57256) (xy 337.141312 -432.560476)
			(xy 336.207126 -432.560476) (xy 336.212403 -432.564311) (xy 336.226597 -432.583851) (xy 336.234059 -432.606821)
			(xy 336.234532 -432.618896) (xy 336.234532 -435.16042) (xy 336.234053 -435.172493) (xy 336.226588 -435.195457)
			(xy 336.212394 -435.214991) (xy 336.19286 -435.229186) (xy 336.169897 -435.236652) (xy 336.157824 -435.237128)
			(xy 335.218024 -435.237128) (xy 335.205945 -435.236667) (xy 335.182966 -435.229209) (xy 335.163417 -435.215014)
			(xy 335.149212 -435.195473) (xy 335.14174 -435.172499) (xy 335.141316 -435.16042) (xy 334.234536 -435.16042)
			(xy 334.234536 -436.160418) (xy 334.234108 -436.172511) (xy 334.226643 -436.195516) (xy 334.212447 -436.215098)
			(xy 334.192904 -436.229347) (xy 334.16992 -436.236874) (xy 334.157828 -436.23738) (xy 333.218028 -436.23738)
			(xy 333.205919 -436.236959) (xy 333.182889 -436.229465) (xy 333.163314 -436.215206) (xy 333.149119 -436.195583)
			(xy 333.141701 -436.172529) (xy 333.14132 -436.160418) (xy 332.206784 -436.160418) (xy 332.21241 -436.164507)
			(xy 332.226604 -436.184047) (xy 332.234067 -436.207016) (xy 332.23454 -436.219092) (xy 332.23454 -438.760616)
			(xy 332.23405 -438.772688) (xy 332.226587 -438.79565) (xy 332.212396 -438.815184) (xy 332.192865 -438.829379)
			(xy 332.169904 -438.836847) (xy 332.157832 -438.837324) (xy 331.218032 -438.837324) (xy 331.205953 -438.83686)
			(xy 331.182974 -438.829403) (xy 331.163424 -438.81521) (xy 331.149218 -438.795669) (xy 331.141747 -438.772695)
			(xy 331.141324 -438.760616) (xy 329.2348 -438.760616) (xy 329.2348 -439.760614) (xy 333.14132 -439.760614)
			(xy 333.14132 -437.21909) (xy 333.141799 -437.207002) (xy 333.149256 -437.184004) (xy 333.16344 -437.164426)
			(xy 333.18297 -437.150176) (xy 333.205942 -437.14264) (xy 333.218028 -437.142128) (xy 334.157828 -437.142128)
			(xy 334.169941 -437.142493) (xy 334.192974 -437.150003) (xy 334.212549 -437.164277) (xy 334.226742 -437.183911)
			(xy 334.234157 -437.206975) (xy 334.234536 -437.21909) (xy 334.234536 -438.760616) (xy 335.141316 -438.760616)
			(xy 335.141316 -436.219092) (xy 335.141706 -436.207006) (xy 335.149179 -436.184019) (xy 335.16339 -436.164467)
			(xy 335.182948 -436.150264) (xy 335.205938 -436.142801) (xy 335.218024 -436.142384) (xy 336.157824 -436.142384)
			(xy 336.169899 -436.142844) (xy 336.192866 -436.150312) (xy 336.206771 -436.160418) (xy 337.141312 -436.160418)
			(xy 337.141312 -433.618894) (xy 337.141802 -433.606807) (xy 337.149257 -433.583811) (xy 337.163439 -433.564234)
			(xy 337.182965 -433.549982) (xy 337.205935 -433.542445) (xy 337.21802 -433.541932) (xy 338.15782 -433.541932)
			(xy 338.169933 -433.5423) (xy 338.192967 -433.549808) (xy 338.212542 -433.564081) (xy 338.226735 -433.583715)
			(xy 338.234149 -433.606779) (xy 338.234528 -433.618894) (xy 338.234528 -435.16042) (xy 339.141308 -435.16042)
			(xy 339.141308 -432.618896) (xy 339.141709 -432.606811) (xy 339.14918 -432.583826) (xy 339.163388 -432.564274)
			(xy 339.182944 -432.550071) (xy 339.205931 -432.542606) (xy 339.218016 -432.542188) (xy 340.157816 -432.542188)
			(xy 340.169891 -432.542651) (xy 340.192858 -432.550117) (xy 340.207113 -432.560476) (xy 341.141304 -432.560476)
			(xy 341.141304 -430.018952) (xy 341.141723 -430.006874) (xy 341.149201 -429.983903) (xy 341.163408 -429.964366)
			(xy 341.182957 -429.950173) (xy 341.205933 -429.942714) (xy 341.218012 -429.942244) (xy 342.157812 -429.942244)
			(xy 342.169882 -429.942753) (xy 342.192842 -429.950213) (xy 342.212374 -429.9644) (xy 342.22657 -429.983926)
			(xy 342.234041 -430.006882) (xy 342.23452 -430.018952) (xy 342.23452 -431.560478) (xy 343.1413 -431.560478)
			(xy 343.1413 -429.018954) (xy 343.141767 -429.006866) (xy 343.149232 -428.983871) (xy 343.16342 -428.964295)
			(xy 343.18295 -428.950044) (xy 343.205922 -428.942507) (xy 343.218008 -428.941992) (xy 344.157808 -428.941992)
			(xy 344.169917 -428.942409) (xy 344.192943 -428.94991) (xy 344.207523 -428.960534) (xy 345.141296 -428.960534)
			(xy 345.141296 -426.41901) (xy 345.141815 -426.406925) (xy 345.149264 -426.383932) (xy 345.163439 -426.364356)
			(xy 345.182958 -426.350104) (xy 345.205921 -426.342564) (xy 345.218004 -426.342048) (xy 346.157804 -426.342048)
			(xy 346.169908 -426.342512) (xy 346.192927 -426.350006) (xy 346.212495 -426.364257) (xy 346.226691 -426.383866)
			(xy 346.234121 -426.406905) (xy 346.234512 -426.41901) (xy 346.234512 -428.960534) (xy 346.234121 -428.97263)
			(xy 346.226649 -428.99564) (xy 346.212444 -429.015223) (xy 346.192892 -429.029471) (xy 346.169899 -429.036994)
			(xy 346.157804 -429.037496) (xy 345.218004 -429.037496) (xy 345.205895 -429.03708) (xy 345.182867 -429.029582)
			(xy 345.163293 -429.01532) (xy 345.149099 -428.995698) (xy 345.141679 -428.972644) (xy 345.141296 -428.960534)
			(xy 344.207523 -428.960534) (xy 344.212515 -428.964172) (xy 344.22671 -428.983792) (xy 344.234132 -429.006844)
			(xy 344.234516 -429.018954) (xy 344.234516 -431.560478) (xy 344.234073 -431.572571) (xy 344.226617 -431.595578)
			(xy 344.212426 -431.615162) (xy 344.192884 -431.629412) (xy 344.169899 -431.636937) (xy 344.157808 -431.63744)
			(xy 343.218008 -431.63744) (xy 343.205904 -431.636978) (xy 343.182883 -431.629485) (xy 343.163313 -431.615234)
			(xy 343.149117 -431.595625) (xy 343.141689 -431.572584) (xy 343.1413 -431.560478) (xy 342.23452 -431.560478)
			(xy 342.23452 -432.560476) (xy 342.234067 -432.572556) (xy 342.226607 -432.595536) (xy 342.212411 -432.615086)
			(xy 342.192868 -432.629291) (xy 342.169892 -432.636761) (xy 342.157812 -432.637184) (xy 341.218012 -432.637184)
			(xy 341.205928 -432.636777) (xy 341.182941 -432.629309) (xy 341.163389 -432.615103) (xy 341.149185 -432.595548)
			(xy 341.141722 -432.572561) (xy 341.141304 -432.560476) (xy 340.207113 -432.560476) (xy 340.212394 -432.564314)
			(xy 340.226588 -432.583853) (xy 340.234051 -432.606821) (xy 340.234524 -432.618896) (xy 340.234524 -435.16042)
			(xy 340.234053 -435.172494) (xy 340.226587 -435.195459) (xy 340.212391 -435.214994) (xy 340.192855 -435.229189)
			(xy 340.16989 -435.236654) (xy 340.157816 -435.237128) (xy 339.218016 -435.237128) (xy 339.205944 -435.236622)
			(xy 339.182981 -435.229167) (xy 339.163445 -435.21498) (xy 339.14925 -435.195451) (xy 339.141783 -435.172492)
			(xy 339.141308 -435.16042) (xy 338.234528 -435.16042) (xy 338.234528 -436.160418) (xy 338.234108 -436.172512)
			(xy 338.226642 -436.195518) (xy 338.212445 -436.215101) (xy 338.192899 -436.22935) (xy 338.169912 -436.236876)
			(xy 338.15782 -436.23738) (xy 337.21802 -436.23738) (xy 337.20591 -436.236966) (xy 337.18288 -436.22947)
			(xy 337.163305 -436.215208) (xy 337.149111 -436.195585) (xy 337.141693 -436.172529) (xy 337.141312 -436.160418)
			(xy 336.206771 -436.160418) (xy 336.212401 -436.16451) (xy 336.226595 -436.184049) (xy 336.234059 -436.207017)
			(xy 336.234532 -436.219092) (xy 336.234532 -438.760616) (xy 336.23405 -438.772689) (xy 336.226586 -438.795653)
			(xy 336.212393 -438.815187) (xy 336.19286 -438.829382) (xy 336.169897 -438.836848) (xy 336.157824 -438.837324)
			(xy 335.218024 -438.837324) (xy 335.205944 -438.836867) (xy 335.182965 -438.829408) (xy 335.163416 -438.815213)
			(xy 335.14921 -438.795671) (xy 335.141739 -438.772696) (xy 335.141316 -438.760616) (xy 334.234536 -438.760616)
			(xy 334.234536 -439.760614) (xy 337.141312 -439.760614) (xy 337.141312 -437.21909) (xy 337.141799 -437.207003)
			(xy 337.149255 -437.184007) (xy 337.163437 -437.164429) (xy 337.182965 -437.150178) (xy 337.205934 -437.142641)
			(xy 337.21802 -437.142128) (xy 338.15782 -437.142128) (xy 338.169933 -437.1425) (xy 338.192965 -437.150008)
			(xy 338.212541 -437.16428) (xy 338.226734 -437.183913) (xy 338.234149 -437.206976) (xy 338.234528 -437.21909)
			(xy 338.234528 -438.760616) (xy 339.141308 -438.760616) (xy 339.141308 -436.219092) (xy 339.141706 -436.207007)
			(xy 339.149178 -436.184021) (xy 339.163387 -436.16447) (xy 339.182943 -436.150267) (xy 339.205931 -436.142802)
			(xy 339.218016 -436.142384) (xy 340.157816 -436.142384) (xy 340.169891 -436.142851) (xy 340.192857 -436.150317)
			(xy 340.206758 -436.160418) (xy 341.141304 -436.160418) (xy 341.141304 -433.618894) (xy 341.141802 -433.606808)
			(xy 341.149256 -433.583813) (xy 341.163436 -433.564236) (xy 341.18296 -433.549985) (xy 341.205928 -433.542447)
			(xy 341.218012 -433.541932) (xy 342.157812 -433.541932) (xy 342.169925 -433.542306) (xy 342.192958 -433.549813)
			(xy 342.212534 -433.564084) (xy 342.226727 -433.583717) (xy 342.234141 -433.60678) (xy 342.23452 -433.618894)
			(xy 342.23452 -435.16042) (xy 343.1413 -435.16042) (xy 343.1413 -432.618896) (xy 343.141709 -432.606812)
			(xy 343.149179 -432.583828) (xy 343.163386 -432.564277) (xy 343.182939 -432.550073) (xy 343.205924 -432.542607)
			(xy 343.218008 -432.542188) (xy 344.157808 -432.542188) (xy 344.169883 -432.542657) (xy 344.192849 -432.550122)
			(xy 344.2071 -432.560476) (xy 345.141296 -432.560476) (xy 345.141296 -430.018952) (xy 345.141723 -430.006875)
			(xy 345.149199 -429.983905) (xy 345.163405 -429.964368) (xy 345.182952 -429.950176) (xy 345.205926 -429.942715)
			(xy 345.218004 -429.942244) (xy 346.157804 -429.942244) (xy 346.169874 -429.94276) (xy 346.192833 -429.950218)
			(xy 346.212366 -429.964403) (xy 346.226562 -429.983927) (xy 346.234033 -430.006882) (xy 346.234512 -430.018952)
			(xy 346.234512 -431.360072) (xy 356.154736 -431.360072) (xy 356.155234 -431.275192) (xy 356.163191 -431.105619)
			(xy 356.179087 -430.936605) (xy 356.202888 -430.768522) (xy 356.234542 -430.601739) (xy 356.273978 -430.436623)
			(xy 356.32111 -430.273538) (xy 356.375834 -430.11284) (xy 356.438031 -429.954885) (xy 356.507563 -429.800018)
			(xy 356.584278 -429.648581) (xy 356.668006 -429.500905) (xy 356.758564 -429.357317) (xy 356.855753 -429.218131)
			(xy 356.95936 -429.083654) (xy 357.069155 -428.954181) (xy 357.184899 -428.829996) (xy 357.306336 -428.711373)
			(xy 357.4332 -428.598572) (xy 357.565211 -428.491842) (xy 357.702081 -428.391417) (xy 357.843506 -428.297518)
			(xy 357.989178 -428.21035) (xy 358.138776 -428.130107) (xy 358.29197 -428.056963) (xy 358.448424 -427.991081)
			(xy 358.607794 -427.932604) (xy 358.76973 -427.881662) (xy 358.933876 -427.838366) (xy 359.099871 -427.802811)
			(xy 359.26735 -427.775076) (xy 359.435945 -427.755222) (xy 359.605285 -427.743292) (xy 359.774998 -427.739313)
			(xy 359.944711 -427.743292) (xy 360.114051 -427.755222) (xy 360.282646 -427.775076) (xy 360.450125 -427.802811)
			(xy 360.61612 -427.838366) (xy 360.780266 -427.881662) (xy 360.942202 -427.932604) (xy 361.018326 -427.960536)
			(xy 381.2413 -427.960536) (xy 381.2413 -425.419012) (xy 381.241723 -425.406929) (xy 381.249188 -425.383946)
			(xy 381.263392 -425.364394) (xy 381.282942 -425.35019) (xy 381.305925 -425.342724) (xy 381.318008 -425.342304)
			(xy 382.257808 -425.342304) (xy 382.269892 -425.342706) (xy 382.292877 -425.350177) (xy 382.312429 -425.364386)
			(xy 382.326632 -425.383941) (xy 382.334097 -425.406928) (xy 382.334516 -425.419012) (xy 382.334516 -427.960536)
			(xy 382.334067 -427.972612) (xy 382.326595 -427.995579) (xy 382.312395 -428.015115) (xy 382.292854 -428.029308)
			(xy 382.269884 -428.036771) (xy 382.257808 -428.037244) (xy 381.318008 -428.037244) (xy 381.305937 -428.03673)
			(xy 381.282977 -428.029274) (xy 381.263443 -428.015089) (xy 381.249247 -427.995563) (xy 381.241777 -427.972606)
			(xy 381.2413 -427.960536) (xy 361.018326 -427.960536) (xy 361.101572 -427.991081) (xy 361.258026 -428.056963)
			(xy 361.41122 -428.130107) (xy 361.560818 -428.21035) (xy 361.70649 -428.297518) (xy 361.847915 -428.391417)
			(xy 361.984785 -428.491842) (xy 362.116796 -428.598572) (xy 362.24366 -428.711373) (xy 362.365097 -428.829996)
			(xy 362.480841 -428.954181) (xy 362.590636 -429.083654) (xy 362.694243 -429.218131) (xy 362.791432 -429.357317)
			(xy 362.88199 -429.500905) (xy 362.965718 -429.648581) (xy 363.042433 -429.800018) (xy 363.111965 -429.954885)
			(xy 363.174162 -430.11284) (xy 363.228886 -430.273538) (xy 363.276018 -430.436623) (xy 363.315454 -430.601739)
			(xy 363.347108 -430.768522) (xy 363.370909 -430.936605) (xy 363.386805 -431.105619) (xy 363.394762 -431.275192)
			(xy 363.39526 -431.360072) (xy 363.394788 -431.445675) (xy 363.389359 -431.560478) (xy 381.2413 -431.560478)
			(xy 381.2413 -429.018954) (xy 381.241767 -429.006866) (xy 381.249232 -428.983871) (xy 381.26342 -428.964295)
			(xy 381.28295 -428.950044) (xy 381.305922 -428.942507) (xy 381.318008 -428.941992) (xy 382.257808 -428.941992)
			(xy 382.269917 -428.942409) (xy 382.292943 -428.94991) (xy 382.307523 -428.960534) (xy 383.241296 -428.960534)
			(xy 383.241296 -426.41901) (xy 383.241815 -426.406925) (xy 383.249264 -426.383932) (xy 383.263439 -426.364356)
			(xy 383.282958 -426.350104) (xy 383.305921 -426.342564) (xy 383.318004 -426.342048) (xy 384.257804 -426.342048)
			(xy 384.269908 -426.342512) (xy 384.292927 -426.350006) (xy 384.312495 -426.364257) (xy 384.326691 -426.383866)
			(xy 384.334121 -426.406905) (xy 384.334512 -426.41901) (xy 384.334512 -427.960536) (xy 385.241292 -427.960536)
			(xy 385.241292 -425.419012) (xy 385.241723 -425.40693) (xy 385.249187 -425.383948) (xy 385.263389 -425.364397)
			(xy 385.282937 -425.350193) (xy 385.305918 -425.342725) (xy 385.318 -425.342304) (xy 386.2578 -425.342304)
			(xy 386.269884 -425.342713) (xy 386.292869 -425.350182) (xy 386.31242 -425.364388) (xy 386.326624 -425.383942)
			(xy 386.334089 -425.406928) (xy 386.334508 -425.419012) (xy 386.334508 -427.960536) (xy 386.334067 -427.972612)
			(xy 386.326594 -427.995581) (xy 386.312392 -428.015117) (xy 386.292849 -428.029311) (xy 386.269877 -428.036772)
			(xy 386.2578 -428.037244) (xy 385.318 -428.037244) (xy 385.305929 -428.036736) (xy 385.282968 -428.029278)
			(xy 385.263434 -428.015092) (xy 385.249238 -427.995564) (xy 385.241769 -427.972607) (xy 385.241292 -427.960536)
			(xy 384.334512 -427.960536) (xy 384.334512 -428.960534) (xy 384.334121 -428.97263) (xy 384.326649 -428.99564)
			(xy 384.312444 -429.015223) (xy 384.292892 -429.029471) (xy 384.269899 -429.036994) (xy 384.257804 -429.037496)
			(xy 383.318004 -429.037496) (xy 383.305895 -429.03708) (xy 383.282867 -429.029582) (xy 383.263293 -429.01532)
			(xy 383.249099 -428.995698) (xy 383.241679 -428.972644) (xy 383.241296 -428.960534) (xy 382.307523 -428.960534)
			(xy 382.312515 -428.964172) (xy 382.32671 -428.983792) (xy 382.334132 -429.006844) (xy 382.334516 -429.018954)
			(xy 382.334516 -431.560478) (xy 382.334073 -431.572571) (xy 382.326617 -431.595578) (xy 382.312426 -431.615162)
			(xy 382.292884 -431.629412) (xy 382.269899 -431.636937) (xy 382.257808 -431.63744) (xy 381.318008 -431.63744)
			(xy 381.305904 -431.636978) (xy 381.282883 -431.629485) (xy 381.263313 -431.615234) (xy 381.249117 -431.595625)
			(xy 381.241689 -431.572584) (xy 381.2413 -431.560478) (xy 363.389359 -431.560478) (xy 363.386701 -431.616689)
			(xy 363.370537 -431.787129) (xy 363.346334 -431.956615) (xy 363.314145 -432.124767) (xy 363.274043 -432.291209)
			(xy 363.226117 -432.455569) (xy 363.170474 -432.61748) (xy 363.107239 -432.776579) (xy 363.036553 -432.932511)
			(xy 362.958574 -433.084927) (xy 362.873477 -433.233486) (xy 362.781452 -433.377855) (xy 362.682704 -433.517713)
			(xy 362.577455 -433.652746) (xy 362.46594 -433.782652) (xy 362.348408 -433.907141) (xy 362.225123 -434.025934)
			(xy 362.096359 -434.138766) (xy 361.962404 -434.245385) (xy 361.82356 -434.345551) (xy 361.680135 -434.439042)
			(xy 361.53245 -434.525647) (xy 361.380836 -434.605174) (xy 361.225632 -434.677444) (xy 361.146598 -434.710332)
			(xy 361.138713 -434.713995) (xy 361.125816 -434.725637) (xy 361.117551 -434.740919) (xy 361.115864 -434.749448)
			(xy 361.100116 -434.849016) (xy 361.109514 -434.873654) (xy 361.119928 -434.88229) (xy 361.169374 -434.924299)
			(xy 361.263563 -435.013553) (xy 361.352051 -435.108462) (xy 361.394803 -435.16042) (xy 381.2413 -435.16042)
			(xy 381.2413 -432.618896) (xy 381.241709 -432.606812) (xy 381.249179 -432.583828) (xy 381.263386 -432.564277)
			(xy 381.282939 -432.550073) (xy 381.305924 -432.542607) (xy 381.318008 -432.542188) (xy 382.257808 -432.542188)
			(xy 382.269883 -432.542657) (xy 382.292849 -432.550122) (xy 382.3071 -432.560476) (xy 383.241296 -432.560476)
			(xy 383.241296 -430.018952) (xy 383.241723 -430.006875) (xy 383.249199 -429.983905) (xy 383.263405 -429.964368)
			(xy 383.282952 -429.950176) (xy 383.305926 -429.942715) (xy 383.318004 -429.942244) (xy 384.257804 -429.942244)
			(xy 384.269874 -429.94276) (xy 384.292833 -429.950218) (xy 384.312366 -429.964403) (xy 384.326562 -429.983927)
			(xy 384.334033 -430.006882) (xy 384.334512 -430.018952) (xy 384.334512 -431.560478) (xy 385.241292 -431.560478)
			(xy 385.241292 -429.018954) (xy 385.241767 -429.006867) (xy 385.249231 -428.983873) (xy 385.263417 -428.964298)
			(xy 385.282945 -428.950047) (xy 385.305914 -428.942508) (xy 385.318 -428.941992) (xy 386.2578 -428.941992)
			(xy 386.269908 -428.942416) (xy 386.292934 -428.949914) (xy 386.307511 -428.960534) (xy 387.241288 -428.960534)
			(xy 387.241288 -426.41901) (xy 387.241717 -426.406916) (xy 387.249177 -426.383908) (xy 387.263371 -426.364324)
			(xy 387.282916 -426.350075) (xy 387.305904 -426.342551) (xy 387.317996 -426.342048) (xy 388.257796 -426.342048)
			(xy 388.269899 -426.342519) (xy 388.292918 -426.350011) (xy 388.312487 -426.36426) (xy 388.326683 -426.383867)
			(xy 388.334113 -426.406905) (xy 388.334504 -426.41901) (xy 388.334504 -427.960536) (xy 389.241284 -427.960536)
			(xy 389.241284 -425.419012) (xy 389.241723 -425.406931) (xy 389.249186 -425.38395) (xy 389.263386 -425.3644)
			(xy 389.282932 -425.350195) (xy 389.305911 -425.342726) (xy 389.317992 -425.342304) (xy 390.257792 -425.342304)
			(xy 390.269876 -425.342719) (xy 390.29286 -425.350186) (xy 390.312412 -425.364391) (xy 390.326616 -425.383943)
			(xy 390.334081 -425.406928) (xy 390.3345 -425.419012) (xy 390.3345 -427.960536) (xy 390.334067 -427.972613)
			(xy 390.326593 -427.995583) (xy 390.312389 -428.01512) (xy 390.292844 -428.029313) (xy 390.26987 -428.036773)
			(xy 390.257792 -428.037244) (xy 389.317992 -428.037244) (xy 389.305921 -428.036743) (xy 389.282959 -428.029283)
			(xy 389.263426 -428.015094) (xy 389.24923 -427.995566) (xy 389.241761 -427.972607) (xy 389.241284 -427.960536)
			(xy 388.334504 -427.960536) (xy 388.334504 -428.960534) (xy 388.334023 -428.972621) (xy 388.326562 -428.995615)
			(xy 388.312377 -429.015191) (xy 388.29285 -429.029442) (xy 388.269881 -429.036981) (xy 388.257796 -429.037496)
			(xy 387.317996 -429.037496) (xy 387.305887 -429.037087) (xy 387.282858 -429.029586) (xy 387.263285 -429.015323)
			(xy 387.249091 -428.995699) (xy 387.241671 -428.972645) (xy 387.241288 -428.960534) (xy 386.307511 -428.960534)
			(xy 386.312507 -428.964174) (xy 386.326701 -428.983794) (xy 386.334124 -429.006845) (xy 386.334508 -429.018954)
			(xy 386.334508 -431.560478) (xy 386.333975 -431.572562) (xy 386.32653 -431.595553) (xy 386.312359 -431.61513)
			(xy 386.292842 -431.629383) (xy 386.269882 -431.636924) (xy 386.2578 -431.63744) (xy 385.318 -431.63744)
			(xy 385.305895 -431.636984) (xy 385.282875 -431.62949) (xy 385.263305 -431.615237) (xy 385.249109 -431.595626)
			(xy 385.241681 -431.572584) (xy 385.241292 -431.560478) (xy 384.334512 -431.560478) (xy 384.334512 -432.560476)
			(xy 384.334067 -432.572557) (xy 384.326606 -432.595538) (xy 384.312409 -432.615089) (xy 384.292863 -432.629294)
			(xy 384.269885 -432.636762) (xy 384.257804 -432.637184) (xy 383.318004 -432.637184) (xy 383.305919 -432.636784)
			(xy 383.282932 -432.629314) (xy 383.26338 -432.615106) (xy 383.249176 -432.59555) (xy 383.241713 -432.572561)
			(xy 383.241296 -432.560476) (xy 382.3071 -432.560476) (xy 382.312386 -432.564317) (xy 382.32658 -432.583854)
			(xy 382.334043 -432.606821) (xy 382.334516 -432.618896) (xy 382.334516 -435.16042) (xy 382.334053 -435.172495)
			(xy 382.326586 -435.195461) (xy 382.312389 -435.214997) (xy 382.29285 -435.229191) (xy 382.269883 -435.236655)
			(xy 382.257808 -435.237128) (xy 381.318008 -435.237128) (xy 381.305936 -435.236629) (xy 381.282972 -435.229171)
			(xy 381.263437 -435.214983) (xy 381.249241 -435.195453) (xy 381.241775 -435.172492) (xy 381.2413 -435.16042)
			(xy 361.394803 -435.16042) (xy 361.434498 -435.208663) (xy 361.510589 -435.313772) (xy 361.580032 -435.423387)
			(xy 361.642562 -435.537087) (xy 361.697938 -435.654438) (xy 361.74595 -435.77499) (xy 361.786412 -435.89828)
			(xy 361.81917 -436.023838) (xy 361.844098 -436.151181) (xy 361.861101 -436.279823) (xy 361.870114 -436.40927)
			(xy 361.871103 -436.539027) (xy 361.864062 -436.668596) (xy 361.849021 -436.797482) (xy 361.826035 -436.92519)
			(xy 361.795194 -437.051232) (xy 361.756614 -437.175125) (xy 361.710445 -437.296394) (xy 361.656862 -437.414574)
			(xy 361.596072 -437.529214) (xy 361.528306 -437.639874) (xy 361.453825 -437.74613) (xy 361.372914 -437.847575)
			(xy 361.285882 -437.943821) (xy 361.193064 -438.034499) (xy 361.094814 -438.119261) (xy 360.991508 -438.197784)
			(xy 360.883543 -438.269766) (xy 360.771333 -438.334931) (xy 360.655306 -438.39303) (xy 360.535907 -438.443841)
			(xy 360.413594 -438.487169) (xy 360.288835 -438.522847) (xy 360.162108 -438.550739) (xy 360.033898 -438.570739)
			(xy 359.904696 -438.58277) (xy 359.774998 -438.586785) (xy 359.6453 -438.58277) (xy 359.516098 -438.570739)
			(xy 359.387888 -438.550739) (xy 359.261161 -438.522847) (xy 359.136402 -438.487169) (xy 359.014089 -438.443841)
			(xy 358.89469 -438.39303) (xy 358.778663 -438.334931) (xy 358.666453 -438.269766) (xy 358.558488 -438.197784)
			(xy 358.455182 -438.119261) (xy 358.356932 -438.034499) (xy 358.264114 -437.943821) (xy 358.177082 -437.847575)
			(xy 358.096171 -437.74613) (xy 358.02169 -437.639874) (xy 357.953924 -437.529214) (xy 357.893134 -437.414574)
			(xy 357.839551 -437.296394) (xy 357.793382 -437.175125) (xy 357.754802 -437.051232) (xy 357.723961 -436.92519)
			(xy 357.700975 -436.797482) (xy 357.685934 -436.668596) (xy 357.678893 -436.539027) (xy 357.679882 -436.40927)
			(xy 357.688895 -436.279823) (xy 357.705898 -436.151181) (xy 357.730826 -436.023838) (xy 357.763584 -435.89828)
			(xy 357.804046 -435.77499) (xy 357.852058 -435.654438) (xy 357.907434 -435.537087) (xy 357.969964 -435.423387)
			(xy 358.039407 -435.313772) (xy 358.115498 -435.208663) (xy 358.197945 -435.108462) (xy 358.286433 -435.013553)
			(xy 358.380622 -434.924299) (xy 358.430068 -434.88229) (xy 358.440228 -434.873908) (xy 358.449626 -434.849016)
			(xy 358.4321 -434.73624) (xy 358.415844 -434.715412) (xy 358.403398 -434.710332) (xy 358.325295 -434.677853)
			(xy 358.1719 -434.606515) (xy 358.022004 -434.52809) (xy 357.875935 -434.44275) (xy 357.734012 -434.350681)
			(xy 357.596544 -434.252083) (xy 357.463831 -434.147172) (xy 357.336162 -434.036176) (xy 357.213818 -433.919339)
			(xy 357.097064 -433.796915) (xy 356.986156 -433.669172) (xy 356.881335 -433.536387) (xy 356.782831 -433.398852)
			(xy 356.690858 -433.256866) (xy 356.605617 -433.110739) (xy 356.527295 -432.96079) (xy 356.456061 -432.807346)
			(xy 356.392073 -432.650743) (xy 356.335468 -432.491322) (xy 356.286372 -432.329431) (xy 356.244891 -432.165424)
			(xy 356.211115 -431.999658) (xy 356.185119 -431.832496) (xy 356.166958 -431.664301) (xy 356.156674 -431.495443)
			(xy 356.15499 -431.410872) (xy 356.155244 -431.410872) (xy 356.154736 -431.360072) (xy 346.234512 -431.360072)
			(xy 346.234512 -432.560476) (xy 346.234067 -432.572557) (xy 346.226606 -432.595538) (xy 346.212409 -432.615089)
			(xy 346.192863 -432.629294) (xy 346.169885 -432.636762) (xy 346.157804 -432.637184) (xy 345.218004 -432.637184)
			(xy 345.205919 -432.636784) (xy 345.182932 -432.629314) (xy 345.16338 -432.615106) (xy 345.149176 -432.59555)
			(xy 345.141713 -432.572561) (xy 345.141296 -432.560476) (xy 344.2071 -432.560476) (xy 344.212386 -432.564317)
			(xy 344.22658 -432.583854) (xy 344.234043 -432.606821) (xy 344.234516 -432.618896) (xy 344.234516 -435.16042)
			(xy 344.234053 -435.172495) (xy 344.226586 -435.195461) (xy 344.212389 -435.214997) (xy 344.19285 -435.229191)
			(xy 344.169883 -435.236655) (xy 344.157808 -435.237128) (xy 343.218008 -435.237128) (xy 343.205936 -435.236629)
			(xy 343.182972 -435.229171) (xy 343.163437 -435.214983) (xy 343.149241 -435.195453) (xy 343.141775 -435.172492)
			(xy 343.1413 -435.16042) (xy 342.23452 -435.16042) (xy 342.23452 -436.160418) (xy 342.234107 -436.172513)
			(xy 342.226641 -436.195521) (xy 342.212442 -436.215104) (xy 342.192894 -436.229352) (xy 342.169905 -436.236877)
			(xy 342.157812 -436.23738) (xy 341.218012 -436.23738) (xy 341.205902 -436.236973) (xy 341.182872 -436.229474)
			(xy 341.163297 -436.215211) (xy 341.149102 -436.195586) (xy 341.141685 -436.17253) (xy 341.141304 -436.160418)
			(xy 340.206758 -436.160418) (xy 340.212393 -436.164513) (xy 340.226587 -436.18405) (xy 340.234051 -436.207017)
			(xy 340.234524 -436.219092) (xy 340.234524 -438.760616) (xy 340.23405 -438.77269) (xy 340.226585 -438.795655)
			(xy 340.21239 -438.81519) (xy 340.192855 -438.829385) (xy 340.16989 -438.83685) (xy 340.157816 -438.837324)
			(xy 339.218016 -438.837324) (xy 339.205944 -438.836822) (xy 339.18298 -438.829366) (xy 339.163444 -438.815179)
			(xy 339.149248 -438.795649) (xy 339.141783 -438.772688) (xy 339.141308 -438.760616) (xy 338.234528 -438.760616)
			(xy 338.234528 -439.760614) (xy 341.141304 -439.760614) (xy 341.141304 -437.21909) (xy 341.141798 -437.207004)
			(xy 341.149253 -437.184009) (xy 341.163434 -437.164432) (xy 341.18296 -437.150181) (xy 341.205927 -437.142643)
			(xy 341.218012 -437.142128) (xy 342.157812 -437.142128) (xy 342.169924 -437.142506) (xy 342.192957 -437.150012)
			(xy 342.212532 -437.164283) (xy 342.226725 -437.183914) (xy 342.234141 -437.206976) (xy 342.23452 -437.21909)
			(xy 342.23452 -438.760616) (xy 343.1413 -438.760616) (xy 343.1413 -436.219092) (xy 343.141758 -436.207016)
			(xy 343.149223 -436.184047) (xy 343.163421 -436.16451) (xy 343.182962 -436.150316) (xy 343.205932 -436.142855)
			(xy 343.218008 -436.142384) (xy 344.157808 -436.142384) (xy 344.169882 -436.142857) (xy 344.192848 -436.150321)
			(xy 344.206744 -436.160418) (xy 345.141296 -436.160418) (xy 345.141296 -433.618894) (xy 345.141802 -433.606809)
			(xy 345.149255 -433.583815) (xy 345.163433 -433.564239) (xy 345.182955 -433.549987) (xy 345.20592 -433.542448)
			(xy 345.218004 -433.541932) (xy 346.157804 -433.541932) (xy 346.169916 -433.542313) (xy 346.192949 -433.549818)
			(xy 346.212525 -433.564087) (xy 346.226718 -433.583718) (xy 346.234133 -433.60678) (xy 346.234512 -433.618894)
			(xy 346.234512 -436.160418) (xy 346.234107 -436.172513) (xy 346.22664 -436.195523) (xy 346.212439 -436.215106)
			(xy 346.192889 -436.229355) (xy 346.169898 -436.236878) (xy 346.157804 -436.23738) (xy 345.218004 -436.23738)
			(xy 345.205893 -436.23698) (xy 345.182863 -436.229479) (xy 345.163288 -436.215214) (xy 345.149094 -436.195588)
			(xy 345.141676 -436.17253) (xy 345.141296 -436.160418) (xy 344.206744 -436.160418) (xy 344.212384 -436.164516)
			(xy 344.226579 -436.184052) (xy 344.234043 -436.207018) (xy 344.234516 -436.219092) (xy 344.234516 -438.760616)
			(xy 344.234049 -438.772691) (xy 344.226583 -438.795657) (xy 344.212387 -438.815193) (xy 344.19285 -438.829387)
			(xy 344.169883 -438.836851) (xy 344.157808 -438.837324) (xy 343.218008 -438.837324) (xy 343.205935 -438.836829)
			(xy 343.182971 -438.829371) (xy 343.163435 -438.815182) (xy 343.14924 -438.79565) (xy 343.141775 -438.772688)
			(xy 343.1413 -438.760616) (xy 342.23452 -438.760616) (xy 342.23452 -439.760614) (xy 345.141296 -439.760614)
			(xy 345.141296 -437.21909) (xy 345.141798 -437.207004) (xy 345.149252 -437.184011) (xy 345.163431 -437.164435)
			(xy 345.182955 -437.150183) (xy 345.20592 -437.142644) (xy 345.218004 -437.142128) (xy 346.157804 -437.142128)
			(xy 346.169916 -437.142513) (xy 346.192948 -437.150017) (xy 346.212524 -437.164286) (xy 346.226717 -437.183916)
			(xy 346.234133 -437.206977) (xy 346.234512 -437.21909) (xy 346.234512 -438.760616) (xy 381.2413 -438.760616)
			(xy 381.2413 -436.219092) (xy 381.241758 -436.207016) (xy 381.249223 -436.184047) (xy 381.263421 -436.16451)
			(xy 381.282962 -436.150316) (xy 381.305932 -436.142855) (xy 381.318008 -436.142384) (xy 382.257808 -436.142384)
			(xy 382.269882 -436.142857) (xy 382.292848 -436.150321) (xy 382.306744 -436.160418) (xy 383.241296 -436.160418)
			(xy 383.241296 -433.618894) (xy 383.241802 -433.606809) (xy 383.249255 -433.583815) (xy 383.263433 -433.564239)
			(xy 383.282955 -433.549987) (xy 383.30592 -433.542448) (xy 383.318004 -433.541932) (xy 384.257804 -433.541932)
			(xy 384.269916 -433.542313) (xy 384.292949 -433.549818) (xy 384.312525 -433.564087) (xy 384.326718 -433.583718)
			(xy 384.334133 -433.60678) (xy 384.334512 -433.618894) (xy 384.334512 -435.16042) (xy 385.241292 -435.16042)
			(xy 385.241292 -432.618896) (xy 385.241761 -432.606821) (xy 385.249224 -432.583854) (xy 385.26342 -432.564317)
			(xy 385.282958 -432.550123) (xy 385.305925 -432.54266) (xy 385.318 -432.542188) (xy 386.2578 -432.542188)
			(xy 386.269874 -432.542664) (xy 386.292841 -432.550126) (xy 386.307086 -432.560476) (xy 387.241288 -432.560476)
			(xy 387.241288 -430.018952) (xy 387.241723 -430.006875) (xy 387.249198 -429.983907) (xy 387.263403 -429.964371)
			(xy 387.282947 -429.950178) (xy 387.305919 -429.942716) (xy 387.317996 -429.942244) (xy 388.257796 -429.942244)
			(xy 388.269866 -429.942767) (xy 388.292824 -429.950222) (xy 388.312357 -429.964406) (xy 388.326554 -429.983929)
			(xy 388.334025 -430.006883) (xy 388.334504 -430.018952) (xy 388.334504 -431.560478) (xy 389.241284 -431.560478)
			(xy 389.241284 -429.018954) (xy 389.241669 -429.006858) (xy 389.249144 -428.983848) (xy 389.26335 -428.964265)
			(xy 389.282903 -428.950018) (xy 389.305897 -428.942495) (xy 389.317992 -428.941992) (xy 390.257792 -428.941992)
			(xy 390.2699 -428.942423) (xy 390.292925 -428.949919) (xy 390.307497 -428.960534) (xy 391.24128 -428.960534)
			(xy 391.24128 -426.41901) (xy 391.241717 -426.406917) (xy 391.249176 -426.38391) (xy 391.263369 -426.364326)
			(xy 391.282911 -426.350077) (xy 391.305896 -426.342552) (xy 391.317988 -426.342048) (xy 392.257788 -426.342048)
			(xy 392.269891 -426.342526) (xy 392.292909 -426.350016) (xy 392.312478 -426.364263) (xy 392.326675 -426.383869)
			(xy 392.334105 -426.406906) (xy 392.334496 -426.41901) (xy 392.334496 -427.960536) (xy 393.241276 -427.960536)
			(xy 393.241276 -425.419012) (xy 393.241774 -425.40694) (xy 393.249231 -425.383976) (xy 393.26342 -425.36444)
			(xy 393.28295 -425.350244) (xy 393.305912 -425.342779) (xy 393.317984 -425.342304) (xy 394.257784 -425.342304)
			(xy 394.269867 -425.342727) (xy 394.292851 -425.350191) (xy 394.312403 -425.364394) (xy 394.326607 -425.383945)
			(xy 394.334073 -425.406929) (xy 394.334492 -425.419012) (xy 394.334492 -427.960536) (xy 394.334066 -427.972614)
			(xy 394.326592 -427.995585) (xy 394.312386 -428.015123) (xy 394.292839 -428.029316) (xy 394.269862 -428.036775)
			(xy 394.257784 -428.037244) (xy 393.317984 -428.037244) (xy 393.305912 -428.03675) (xy 393.282951 -428.029287)
			(xy 393.263417 -428.015097) (xy 393.249222 -427.995567) (xy 393.241753 -427.972608) (xy 393.241276 -427.960536)
			(xy 392.334496 -427.960536) (xy 392.334496 -428.960534) (xy 392.334022 -428.972622) (xy 392.326561 -428.995617)
			(xy 392.312374 -429.015194) (xy 392.292845 -429.029444) (xy 392.269874 -429.036982) (xy 392.257788 -429.037496)
			(xy 391.317988 -429.037496) (xy 391.305878 -429.037094) (xy 391.28285 -429.029591) (xy 391.263276 -429.015326)
			(xy 391.249082 -428.995701) (xy 391.241663 -428.972645) (xy 391.24128 -428.960534) (xy 390.307497 -428.960534)
			(xy 390.312498 -428.964177) (xy 390.326693 -428.983795) (xy 390.334116 -429.006845) (xy 390.3345 -429.018954)
			(xy 390.3345 -431.560478) (xy 390.333975 -431.572562) (xy 390.326529 -431.595556) (xy 390.312356 -431.615132)
			(xy 390.292837 -431.629385) (xy 390.269874 -431.636925) (xy 390.257792 -431.63744) (xy 389.317992 -431.63744)
			(xy 389.305887 -431.636991) (xy 389.282866 -431.629494) (xy 389.263296 -431.61524) (xy 389.249101 -431.595628)
			(xy 389.241673 -431.572585) (xy 389.241284 -431.560478) (xy 388.334504 -431.560478) (xy 388.334504 -432.560476)
			(xy 388.334067 -432.572558) (xy 388.326605 -432.59554) (xy 388.312406 -432.615091) (xy 388.292858 -432.629296)
			(xy 388.269878 -432.636764) (xy 388.257796 -432.637184) (xy 387.317996 -432.637184) (xy 387.305911 -432.636791)
			(xy 387.282924 -432.629319) (xy 387.263371 -432.615109) (xy 387.249168 -432.595551) (xy 387.241705 -432.572562)
			(xy 387.241288 -432.560476) (xy 386.307086 -432.560476) (xy 386.312377 -432.56432) (xy 386.326572 -432.583856)
			(xy 386.334035 -432.606822) (xy 386.334508 -432.618896) (xy 386.334508 -435.16042) (xy 386.334053 -435.172496)
			(xy 386.326585 -435.195463) (xy 386.312386 -435.215) (xy 386.292845 -435.229194) (xy 386.269876 -435.236656)
			(xy 386.2578 -435.237128) (xy 385.318 -435.237128) (xy 385.305927 -435.236636) (xy 385.282964 -435.229176)
			(xy 385.263428 -435.214986) (xy 385.249233 -435.195454) (xy 385.241767 -435.172492) (xy 385.241292 -435.16042)
			(xy 384.334512 -435.16042) (xy 384.334512 -436.160418) (xy 384.334107 -436.172513) (xy 384.32664 -436.195523)
			(xy 384.312439 -436.215106) (xy 384.292889 -436.229355) (xy 384.269898 -436.236878) (xy 384.257804 -436.23738)
			(xy 383.318004 -436.23738) (xy 383.305893 -436.23698) (xy 383.282863 -436.229479) (xy 383.263288 -436.215214)
			(xy 383.249094 -436.195588) (xy 383.241676 -436.17253) (xy 383.241296 -436.160418) (xy 382.306744 -436.160418)
			(xy 382.312384 -436.164516) (xy 382.326579 -436.184052) (xy 382.334043 -436.207018) (xy 382.334516 -436.219092)
			(xy 382.334516 -438.760616) (xy 382.334049 -438.772691) (xy 382.326583 -438.795657) (xy 382.312387 -438.815193)
			(xy 382.29285 -438.829387) (xy 382.269883 -438.836851) (xy 382.257808 -438.837324) (xy 381.318008 -438.837324)
			(xy 381.305935 -438.836829) (xy 381.282971 -438.829371) (xy 381.263435 -438.815182) (xy 381.24924 -438.79565)
			(xy 381.241775 -438.772688) (xy 381.2413 -438.760616) (xy 346.234512 -438.760616) (xy 346.234512 -439.760614)
			(xy 383.241296 -439.760614) (xy 383.241296 -437.21909) (xy 383.241798 -437.207004) (xy 383.249252 -437.184011)
			(xy 383.263431 -437.164435) (xy 383.282955 -437.150183) (xy 383.30592 -437.142644) (xy 383.318004 -437.142128)
			(xy 384.257804 -437.142128) (xy 384.269916 -437.142513) (xy 384.292948 -437.150017) (xy 384.312524 -437.164286)
			(xy 384.326717 -437.183916) (xy 384.334133 -437.206977) (xy 384.334512 -437.21909) (xy 384.334512 -438.760616)
			(xy 385.241292 -438.760616) (xy 385.241292 -436.219092) (xy 385.241758 -436.207017) (xy 385.249222 -436.18405)
			(xy 385.263418 -436.164513) (xy 385.282957 -436.150319) (xy 385.305925 -436.142856) (xy 385.318 -436.142384)
			(xy 386.2578 -436.142384) (xy 386.269874 -436.142864) (xy 386.29284 -436.150326) (xy 386.306732 -436.160418)
			(xy 387.241288 -436.160418) (xy 387.241288 -433.618894) (xy 387.241703 -433.606799) (xy 387.249168 -433.583791)
			(xy 387.263366 -433.564207) (xy 387.282913 -433.549958) (xy 387.305903 -433.542435) (xy 387.317996 -433.541932)
			(xy 388.257796 -433.541932) (xy 388.269908 -433.54232) (xy 388.292941 -433.549822) (xy 388.312517 -433.56409)
			(xy 388.32671 -433.58372) (xy 388.334125 -433.606781) (xy 388.334504 -433.618894) (xy 388.334504 -435.16042)
			(xy 389.241284 -435.16042) (xy 389.241284 -432.618896) (xy 389.241761 -432.606822) (xy 389.249223 -432.583856)
			(xy 389.263417 -432.56432) (xy 389.282953 -432.550125) (xy 389.305918 -432.542661) (xy 389.317992 -432.542188)
			(xy 390.257792 -432.542188) (xy 390.269874 -432.542619) (xy 390.292856 -432.550084) (xy 390.307161 -432.560476)
			(xy 391.24128 -432.560476) (xy 391.24128 -430.018952) (xy 391.241723 -430.006876) (xy 391.249197 -429.983909)
			(xy 391.2634 -429.964374) (xy 391.282942 -429.950181) (xy 391.305912 -429.942717) (xy 391.317988 -429.942244)
			(xy 392.257788 -429.942244) (xy 392.269857 -429.942774) (xy 392.292816 -429.950227) (xy 392.312349 -429.964408)
			(xy 392.326546 -429.98393) (xy 392.334017 -430.006883) (xy 392.334496 -430.018952) (xy 392.334496 -431.560478)
			(xy 393.241276 -431.560478) (xy 393.241276 -429.018954) (xy 393.241669 -429.006858) (xy 393.249143 -428.98385)
			(xy 393.263347 -428.964268) (xy 393.282898 -428.95002) (xy 393.30589 -428.942496) (xy 393.317984 -428.941992)
			(xy 394.257784 -428.941992) (xy 394.269891 -428.94243) (xy 394.292917 -428.949924) (xy 394.307483 -428.960534)
			(xy 395.241272 -428.960534) (xy 395.241272 -426.41901) (xy 395.241717 -426.406918) (xy 395.249174 -426.383912)
			(xy 395.263366 -426.364329) (xy 395.282906 -426.35008) (xy 395.305889 -426.342553) (xy 395.31798 -426.342048)
			(xy 396.25778 -426.342048) (xy 396.269883 -426.342533) (xy 396.2929 -426.35002) (xy 396.312469 -426.364266)
			(xy 396.326666 -426.38387) (xy 396.334097 -426.406906) (xy 396.334488 -426.41901) (xy 396.334488 -427.960536)
			(xy 398.241012 -427.960536) (xy 398.241012 -425.419012) (xy 398.24147 -425.406961) (xy 398.248901 -425.384034)
			(xy 398.263042 -425.364517) (xy 398.282514 -425.350314) (xy 398.305417 -425.342809) (xy 398.317466 -425.342304)
			(xy 399.257774 -425.342304) (xy 399.269859 -425.342829) (xy 399.292852 -425.350274) (xy 399.31243 -425.364447)
			(xy 399.326682 -425.383966) (xy 399.334221 -425.406929) (xy 399.334736 -425.419012) (xy 399.334736 -427.960536)
			(xy 399.334272 -427.972585) (xy 399.326833 -427.995505) (xy 399.312692 -428.015017) (xy 399.293226 -428.029221)
			(xy 399.270329 -428.036732) (xy 399.258282 -428.037244) (xy 398.317974 -428.037244) (xy 398.305881 -428.036815)
			(xy 398.282877 -428.029349) (xy 398.263296 -428.015153) (xy 398.249047 -427.995611) (xy 398.241519 -427.972627)
			(xy 398.241012 -427.960536) (xy 396.334488 -427.960536) (xy 396.334488 -428.960534) (xy 396.334022 -428.972623)
			(xy 396.32656 -428.99562) (xy 396.312372 -429.015197) (xy 396.29284 -429.029447) (xy 396.269867 -429.036983)
			(xy 396.25778 -429.037496) (xy 395.31798 -429.037496) (xy 395.30587 -429.037101) (xy 395.282841 -429.029595)
			(xy 395.263268 -429.015328) (xy 395.249074 -428.995702) (xy 395.241655 -428.972646) (xy 395.241272 -428.960534)
			(xy 394.307483 -428.960534) (xy 394.312489 -428.96418) (xy 394.326685 -428.983797) (xy 394.334107 -429.006846)
			(xy 394.334492 -429.018954) (xy 394.334492 -431.560478) (xy 394.333974 -431.572563) (xy 394.326528 -431.595558)
			(xy 394.312353 -431.615135) (xy 394.292832 -431.629388) (xy 394.269867 -431.636926) (xy 394.257784 -431.63744)
			(xy 393.317984 -431.63744) (xy 393.305878 -431.636998) (xy 393.282857 -431.629499) (xy 393.263288 -431.615243)
			(xy 393.249092 -431.595629) (xy 393.241665 -431.572585) (xy 393.241276 -431.560478) (xy 392.334496 -431.560478)
			(xy 392.334496 -432.560476) (xy 392.334067 -432.572559) (xy 392.326604 -432.595543) (xy 392.312403 -432.615094)
			(xy 392.292853 -432.629299) (xy 392.269871 -432.636765) (xy 392.257788 -432.637184) (xy 391.317988 -432.637184)
			(xy 391.305902 -432.636797) (xy 391.282915 -432.629324) (xy 391.263363 -432.615112) (xy 391.24916 -432.595553)
			(xy 391.241697 -432.572562) (xy 391.24128 -432.560476) (xy 390.307161 -432.560476) (xy 390.312406 -432.564286)
			(xy 390.326611 -432.583833) (xy 390.334079 -432.606814) (xy 390.3345 -432.618896) (xy 390.3345 -435.16042)
			(xy 390.334053 -435.172496) (xy 390.326584 -435.195465) (xy 390.312383 -435.215003) (xy 390.29284 -435.229196)
			(xy 390.269869 -435.236657) (xy 390.257792 -435.237128) (xy 389.317992 -435.237128) (xy 389.305919 -435.236643)
			(xy 389.282955 -435.229181) (xy 389.26342 -435.214989) (xy 389.249225 -435.195456) (xy 389.241759 -435.172493)
			(xy 389.241284 -435.16042) (xy 388.334504 -435.16042) (xy 388.334504 -436.160418) (xy 388.334009 -436.172504)
			(xy 388.326553 -436.195498) (xy 388.312372 -436.215074) (xy 388.292847 -436.229325) (xy 388.26988 -436.236865)
			(xy 388.257796 -436.23738) (xy 387.317996 -436.23738) (xy 387.305885 -436.236987) (xy 387.282854 -436.229484)
			(xy 387.263279 -436.215217) (xy 387.249085 -436.195589) (xy 387.241668 -436.172531) (xy 387.241288 -436.160418)
			(xy 386.306732 -436.160418) (xy 386.312376 -436.164518) (xy 386.326571 -436.184053) (xy 386.334035 -436.207018)
			(xy 386.334508 -436.219092) (xy 386.334508 -438.760616) (xy 386.334049 -438.772691) (xy 386.326582 -438.795659)
			(xy 386.312384 -438.815196) (xy 386.292845 -438.82939) (xy 386.269875 -438.836852) (xy 386.2578 -438.837324)
			(xy 385.318 -438.837324) (xy 385.305927 -438.836836) (xy 385.282963 -438.829375) (xy 385.263427 -438.815184)
			(xy 385.249232 -438.795652) (xy 385.241767 -438.772689) (xy 385.241292 -438.760616) (xy 384.334512 -438.760616)
			(xy 384.334512 -439.760614) (xy 387.241288 -439.760614) (xy 387.241288 -437.21909) (xy 387.2417 -437.206995)
			(xy 387.249165 -437.183986) (xy 387.263364 -437.164402) (xy 387.282912 -437.150154) (xy 387.305902 -437.142631)
			(xy 387.317996 -437.142128) (xy 388.257796 -437.142128) (xy 388.269907 -437.14252) (xy 388.292939 -437.150022)
			(xy 388.312515 -437.164288) (xy 388.326709 -437.183917) (xy 388.334125 -437.206977) (xy 388.334504 -437.21909)
			(xy 388.334504 -438.760616) (xy 389.241284 -438.760616) (xy 389.241284 -436.219092) (xy 389.241757 -436.207018)
			(xy 389.249221 -436.184052) (xy 389.263416 -436.164516) (xy 389.282952 -436.150321) (xy 389.305918 -436.142857)
			(xy 389.317992 -436.142384) (xy 390.257792 -436.142384) (xy 390.269865 -436.142871) (xy 390.292831 -436.15033)
			(xy 390.306719 -436.160418) (xy 391.24128 -436.160418) (xy 391.24128 -433.618894) (xy 391.241703 -433.6068)
			(xy 391.249166 -433.583793) (xy 391.263363 -433.564209) (xy 391.282908 -433.549961) (xy 391.305896 -433.542436)
			(xy 391.317988 -433.541932) (xy 392.257788 -433.541932) (xy 392.269899 -433.542327) (xy 392.292932 -433.549827)
			(xy 392.312508 -433.564093) (xy 392.326702 -433.583721) (xy 392.334117 -433.606781) (xy 392.334496 -433.618894)
			(xy 392.334496 -435.16042) (xy 393.241276 -435.16042) (xy 393.241276 -432.618896) (xy 393.241761 -432.606823)
			(xy 393.249222 -432.583858) (xy 393.263414 -432.564323) (xy 393.282948 -432.550128) (xy 393.305911 -432.542663)
			(xy 393.317984 -432.542188) (xy 394.257784 -432.542188) (xy 394.269865 -432.542626) (xy 394.292847 -432.550089)
			(xy 394.307147 -432.560476) (xy 395.241272 -432.560476) (xy 395.241272 -430.018952) (xy 395.241723 -430.006877)
			(xy 395.249196 -429.983912) (xy 395.263397 -429.964377) (xy 395.282937 -429.950183) (xy 395.305905 -429.942718)
			(xy 395.31798 -429.942244) (xy 396.25778 -429.942244) (xy 396.269849 -429.94278) (xy 396.292807 -429.950232)
			(xy 396.31234 -429.964411) (xy 396.326537 -429.983932) (xy 396.334009 -430.006884) (xy 396.334488 -430.018952)
			(xy 396.334488 -431.560478) (xy 398.241012 -431.560478) (xy 398.241012 -429.018954) (xy 398.241472 -429.00684)
			(xy 398.248969 -428.983799) (xy 398.263215 -428.964201) (xy 398.282817 -428.94996) (xy 398.30586 -428.942469)
			(xy 398.317974 -428.941992) (xy 399.257774 -428.941992) (xy 399.269883 -428.942533) (xy 399.292917 -428.950008)
			(xy 399.307419 -428.960534) (xy 400.241008 -428.960534) (xy 400.241008 -426.41901) (xy 400.24152 -426.406899)
			(xy 400.249001 -426.383861) (xy 400.263233 -426.364262) (xy 400.282825 -426.350019) (xy 400.305859 -426.342526)
			(xy 400.31797 -426.342048) (xy 401.25777 -426.342048) (xy 401.269892 -426.342486) (xy 401.292952 -426.349971)
			(xy 401.312568 -426.364218) (xy 401.32682 -426.38383) (xy 401.334311 -426.406888) (xy 401.334732 -426.41901)
			(xy 401.334732 -427.960536) (xy 402.241004 -427.960536) (xy 402.241004 -425.419012) (xy 402.24147 -425.406962)
			(xy 402.2489 -425.384036) (xy 402.263039 -425.36452) (xy 402.282509 -425.350316) (xy 402.30541 -425.342811)
			(xy 402.317458 -425.342304) (xy 403.257766 -425.342304) (xy 403.26985 -425.342836) (xy 403.292844 -425.350279)
			(xy 403.312421 -425.36445) (xy 403.326674 -425.383968) (xy 403.334213 -425.40693) (xy 403.334728 -425.419012)
			(xy 403.334728 -427.960536) (xy 403.334271 -427.972585) (xy 403.326832 -427.995507) (xy 403.31269 -428.01502)
			(xy 403.293221 -428.029223) (xy 403.270322 -428.036734) (xy 403.258274 -428.037244) (xy 402.317966 -428.037244)
			(xy 402.305873 -428.036821) (xy 402.282869 -428.029353) (xy 402.263288 -428.015156) (xy 402.249039 -427.995612)
			(xy 402.241511 -427.972628) (xy 402.241004 -427.960536) (xy 401.334732 -427.960536) (xy 401.334732 -428.960534)
			(xy 401.334317 -428.972653) (xy 401.326817 -428.995703) (xy 401.312561 -429.015307) (xy 401.292945 -429.029546)
			(xy 401.26989 -429.037027) (xy 401.25777 -429.037496) (xy 400.31797 -429.037496) (xy 400.305857 -429.037014)
			(xy 400.282819 -429.029523) (xy 400.26322 -429.015282) (xy 400.248979 -428.995685) (xy 400.241486 -428.972647)
			(xy 400.241008 -428.960534) (xy 399.307419 -428.960534) (xy 399.312515 -428.964233) (xy 399.326759 -428.983818)
			(xy 399.334255 -429.006846) (xy 399.334736 -429.018954) (xy 399.334736 -431.560478) (xy 399.334321 -431.572602)
			(xy 399.326832 -431.595665) (xy 399.31258 -431.615282) (xy 399.292961 -431.629533) (xy 399.269898 -431.637022)
			(xy 399.257774 -431.63744) (xy 398.317974 -431.63744) (xy 398.305856 -431.63701) (xy 398.282808 -431.629513)
			(xy 398.263205 -431.615261) (xy 398.248965 -431.595649) (xy 398.241482 -431.572596) (xy 398.241012 -431.560478)
			(xy 396.334488 -431.560478) (xy 396.334488 -432.560476) (xy 396.334066 -432.572559) (xy 396.326603 -432.595545)
			(xy 396.3124 -432.615097) (xy 396.292848 -432.629301) (xy 396.269863 -432.636766) (xy 396.25778 -432.637184)
			(xy 395.31798 -432.637184) (xy 395.305894 -432.636804) (xy 395.282906 -432.629328) (xy 395.263354 -432.615114)
			(xy 395.249152 -432.595554) (xy 395.241689 -432.572562) (xy 395.241272 -432.560476) (xy 394.307147 -432.560476)
			(xy 394.312397 -432.564289) (xy 394.326602 -432.583835) (xy 394.33407 -432.606815) (xy 394.334492 -432.618896)
			(xy 394.334492 -435.16042) (xy 394.334052 -435.172497) (xy 394.326582 -435.195468) (xy 394.31238 -435.215006)
			(xy 394.292835 -435.229199) (xy 394.269861 -435.236658) (xy 394.257784 -435.237128) (xy 393.317984 -435.237128)
			(xy 393.305911 -435.23665) (xy 393.282946 -435.229185) (xy 393.263411 -435.214991) (xy 393.249217 -435.195457)
			(xy 393.241751 -435.172493) (xy 393.241276 -435.16042) (xy 392.334496 -435.16042) (xy 392.334496 -436.160418)
			(xy 392.334009 -436.172505) (xy 392.326552 -436.1955) (xy 392.312369 -436.215077) (xy 392.292842 -436.229328)
			(xy 392.269873 -436.236866) (xy 392.257788 -436.23738) (xy 391.317988 -436.23738) (xy 391.305876 -436.236994)
			(xy 391.282845 -436.229489) (xy 391.263271 -436.21522) (xy 391.249077 -436.195591) (xy 391.24166 -436.172531)
			(xy 391.24128 -436.160418) (xy 390.306719 -436.160418) (xy 390.312367 -436.164521) (xy 390.326562 -436.184055)
			(xy 390.334027 -436.207019) (xy 390.3345 -436.219092) (xy 390.3345 -438.760616) (xy 390.334049 -438.772692)
			(xy 390.326581 -438.795661) (xy 390.312382 -438.815199) (xy 390.29284 -438.829392) (xy 390.269868 -438.836853)
			(xy 390.257792 -438.837324) (xy 389.317992 -438.837324) (xy 389.305919 -438.836843) (xy 389.282954 -438.82938)
			(xy 389.263418 -438.815187) (xy 389.249224 -438.795653) (xy 389.241759 -438.772689) (xy 389.241284 -438.760616)
			(xy 388.334504 -438.760616) (xy 388.334504 -439.760614) (xy 391.24128 -439.760614) (xy 391.24128 -437.21909)
			(xy 391.2417 -437.206996) (xy 391.249164 -437.183988) (xy 391.263361 -437.164405) (xy 391.282907 -437.150156)
			(xy 391.305895 -437.142632) (xy 391.317988 -437.142128) (xy 392.257788 -437.142128) (xy 392.269899 -437.142527)
			(xy 392.292931 -437.150027) (xy 392.312506 -437.164292) (xy 392.3267 -437.183919) (xy 392.334116 -437.206978)
			(xy 392.334496 -437.21909) (xy 392.334496 -438.760616) (xy 393.241276 -438.760616) (xy 393.241276 -436.219092)
			(xy 393.241757 -436.207019) (xy 393.24922 -436.184054) (xy 393.263413 -436.164518) (xy 393.282947 -436.150324)
			(xy 393.305911 -436.142859) (xy 393.317984 -436.142384) (xy 394.257784 -436.142384) (xy 394.269865 -436.142826)
			(xy 394.292846 -436.150288) (xy 394.306794 -436.160418) (xy 395.241272 -436.160418) (xy 395.241272 -433.618894)
			(xy 395.241703 -433.606801) (xy 395.249165 -433.583795) (xy 395.26336 -433.564212) (xy 395.282903 -433.549963)
			(xy 395.305888 -433.542437) (xy 395.31798 -433.541932) (xy 396.25778 -433.541932) (xy 396.269891 -433.542334)
			(xy 396.292923 -433.549832) (xy 396.312499 -433.564096) (xy 396.326693 -433.583723) (xy 396.334109 -433.606782)
			(xy 396.334488 -433.618894) (xy 396.334488 -435.16042) (xy 398.241012 -435.16042) (xy 398.241012 -432.618896)
			(xy 398.241457 -432.606844) (xy 398.248892 -432.583917) (xy 398.263036 -432.5644) (xy 398.282511 -432.550197)
			(xy 398.305416 -432.542693) (xy 398.317466 -432.542188) (xy 399.257774 -432.542188) (xy 399.269867 -432.54263)
			(xy 399.292875 -432.550086) (xy 399.307214 -432.560476) (xy 400.241008 -432.560476) (xy 400.241008 -430.018952)
			(xy 400.241419 -430.006898) (xy 400.248866 -429.98397) (xy 400.263019 -429.964454) (xy 400.2825 -429.950253)
			(xy 400.30541 -429.942749) (xy 400.317462 -429.942244) (xy 401.25777 -429.942244) (xy 401.269858 -429.942733)
			(xy 401.292859 -429.950182) (xy 401.312439 -429.964363) (xy 401.326691 -429.983892) (xy 401.334223 -430.006865)
			(xy 401.334732 -430.018952) (xy 401.334732 -431.560478) (xy 402.241004 -431.560478) (xy 402.241004 -429.018954)
			(xy 402.241472 -429.00684) (xy 402.248968 -428.983801) (xy 402.263212 -428.964203) (xy 402.282812 -428.949962)
			(xy 402.305852 -428.94247) (xy 402.317966 -428.941992) (xy 403.257766 -428.941992) (xy 403.269874 -428.94254)
			(xy 403.292909 -428.950012) (xy 403.307406 -428.960534) (xy 404.241 -428.960534) (xy 404.241 -426.41901)
			(xy 404.24152 -426.4069) (xy 404.249 -426.383863) (xy 404.263231 -426.364265) (xy 404.28282 -426.350022)
			(xy 404.305852 -426.342527) (xy 404.317962 -426.342048) (xy 405.257762 -426.342048) (xy 405.269884 -426.342492)
			(xy 405.292943 -426.349975) (xy 405.31256 -426.36422) (xy 405.326812 -426.383832) (xy 405.334303 -426.406888)
			(xy 405.334724 -426.41901) (xy 405.334724 -427.960536) (xy 406.240996 -427.960536) (xy 406.240996 -425.419012)
			(xy 406.24147 -425.406963) (xy 406.248899 -425.384038) (xy 406.263036 -425.364523) (xy 406.282504 -425.350319)
			(xy 406.305403 -425.342812) (xy 406.31745 -425.342304) (xy 407.257758 -425.342304) (xy 407.269842 -425.342842)
			(xy 407.292835 -425.350283) (xy 407.312413 -425.364453) (xy 407.326666 -425.383969) (xy 407.334205 -425.40693)
			(xy 407.33472 -425.419012) (xy 407.33472 -427.960536) (xy 407.334271 -427.972586) (xy 407.326831 -427.99551)
			(xy 407.312687 -428.015023) (xy 407.293216 -428.029226) (xy 407.270315 -428.036735) (xy 407.258266 -428.037244)
			(xy 406.317958 -428.037244) (xy 406.305865 -428.036828) (xy 406.28286 -428.029358) (xy 406.263279 -428.015159)
			(xy 406.249031 -427.995614) (xy 406.241503 -427.972628) (xy 406.240996 -427.960536) (xy 405.334724 -427.960536)
			(xy 405.334724 -428.960534) (xy 405.334369 -428.972662) (xy 405.326862 -428.995729) (xy 405.312595 -429.015347)
			(xy 405.292964 -429.029595) (xy 405.269891 -429.03708) (xy 405.257762 -429.037496) (xy 404.317962 -429.037496)
			(xy 404.305849 -429.037021) (xy 404.28281 -429.029528) (xy 404.263212 -429.015285) (xy 404.24897 -428.995686)
			(xy 404.241478 -428.972647) (xy 404.241 -428.960534) (xy 403.307406 -428.960534) (xy 403.312507 -428.964236)
			(xy 403.326751 -428.98382) (xy 403.334247 -429.006846) (xy 403.334728 -429.018954) (xy 403.334728 -431.560478)
			(xy 403.334321 -431.572603) (xy 403.32683 -431.595667) (xy 403.312577 -431.615285) (xy 403.292956 -431.629536)
			(xy 403.269891 -431.637023) (xy 403.257766 -431.63744) (xy 402.317966 -431.63744) (xy 402.305847 -431.637017)
			(xy 402.282799 -431.629518) (xy 402.263196 -431.615264) (xy 402.248957 -431.59565) (xy 402.241474 -431.572597)
			(xy 402.241004 -431.560478) (xy 401.334732 -431.560478) (xy 401.334732 -432.560476) (xy 401.33422 -432.572522)
			(xy 401.326798 -432.595441) (xy 401.312669 -432.614955) (xy 401.293212 -432.62916) (xy 401.270322 -432.636672)
			(xy 401.258278 -432.637184) (xy 400.31797 -432.637184) (xy 400.305881 -432.636719) (xy 400.282884 -432.629257)
			(xy 400.263306 -432.615069) (xy 400.249056 -432.595537) (xy 400.24152 -432.572563) (xy 400.241008 -432.560476)
			(xy 399.307214 -432.560476) (xy 399.312459 -432.564277) (xy 399.326709 -432.583819) (xy 399.334233 -432.606804)
			(xy 399.334736 -432.618896) (xy 399.334736 -435.16042) (xy 399.334258 -435.172468) (xy 399.326824 -435.195388)
			(xy 399.312686 -435.2149) (xy 399.293223 -435.229104) (xy 399.270328 -435.236616) (xy 399.258282 -435.237128)
			(xy 398.317974 -435.237128) (xy 398.30588 -435.236714) (xy 398.282873 -435.229247) (xy 398.263291 -435.215047)
			(xy 398.249042 -435.195501) (xy 398.241516 -435.172513) (xy 398.241012 -435.16042) (xy 396.334488 -435.16042)
			(xy 396.334488 -436.160418) (xy 396.334009 -436.172506) (xy 396.32655 -436.195502) (xy 396.312366 -436.21508)
			(xy 396.292837 -436.229331) (xy 396.269866 -436.236867) (xy 396.25778 -436.23738) (xy 395.31798 -436.23738)
			(xy 395.305868 -436.237001) (xy 395.282837 -436.229493) (xy 395.263262 -436.215223) (xy 395.249069 -436.195592)
			(xy 395.241652 -436.172532) (xy 395.241272 -436.160418) (xy 394.306794 -436.160418) (xy 394.312396 -436.164487)
			(xy 394.326601 -436.184033) (xy 394.33407 -436.207011) (xy 394.334492 -436.219092) (xy 394.334492 -438.760616)
			(xy 394.334049 -438.772693) (xy 394.32658 -438.795663) (xy 394.312379 -438.815201) (xy 394.292835 -438.829395)
			(xy 394.269861 -438.836854) (xy 394.257784 -438.837324) (xy 393.317984 -438.837324) (xy 393.30591 -438.83685)
			(xy 393.282945 -438.829385) (xy 393.26341 -438.81519) (xy 393.249215 -438.795655) (xy 393.24175 -438.77269)
			(xy 393.241276 -438.760616) (xy 392.334496 -438.760616) (xy 392.334496 -439.760614) (xy 395.241272 -439.760614)
			(xy 395.241272 -437.21909) (xy 395.2417 -437.206997) (xy 395.249163 -437.183991) (xy 395.263359 -437.164408)
			(xy 395.282902 -437.150159) (xy 395.305888 -437.142633) (xy 395.31798 -437.142128) (xy 396.25778 -437.142128)
			(xy 396.269891 -437.142534) (xy 396.292922 -437.150031) (xy 396.312498 -437.164294) (xy 396.326692 -437.18392)
			(xy 396.334108 -437.206978) (xy 396.334488 -437.21909) (xy 396.334488 -438.760616) (xy 398.241012 -438.760616)
			(xy 398.241012 -436.219092) (xy 398.241453 -436.20704) (xy 398.24889 -436.184112) (xy 398.263035 -436.164596)
			(xy 398.28251 -436.150393) (xy 398.305416 -436.142889) (xy 398.317466 -436.142384) (xy 399.257774 -436.142384)
			(xy 399.269867 -436.14283) (xy 399.292874 -436.150285) (xy 399.306858 -436.160418) (xy 400.241008 -436.160418)
			(xy 400.241008 -433.618894) (xy 400.241506 -433.606782) (xy 400.248992 -433.583744) (xy 400.263228 -433.564145)
			(xy 400.282822 -433.549903) (xy 400.305858 -433.54241) (xy 400.31797 -433.541932) (xy 401.25777 -433.541932)
			(xy 401.269891 -433.542385) (xy 401.292947 -433.549869) (xy 401.312563 -433.564112) (xy 401.326815 -433.58372)
			(xy 401.334309 -433.606774) (xy 401.334732 -433.618894) (xy 401.334732 -435.16042) (xy 402.241004 -435.16042)
			(xy 402.241004 -432.618896) (xy 402.241457 -432.606845) (xy 402.248891 -432.583919) (xy 402.263034 -432.564403)
			(xy 402.282506 -432.5502) (xy 402.305409 -432.542694) (xy 402.317458 -432.542188) (xy 403.257766 -432.542188)
			(xy 403.269859 -432.542637) (xy 403.292866 -432.55009) (xy 403.307201 -432.560476) (xy 404.241 -432.560476)
			(xy 404.241 -430.018952) (xy 404.241419 -430.006899) (xy 404.248865 -429.983972) (xy 404.263016 -429.964457)
			(xy 404.282495 -429.950255) (xy 404.305403 -429.94275) (xy 404.317454 -429.942244) (xy 405.257762 -429.942244)
			(xy 405.26985 -429.94274) (xy 405.29285 -429.950187) (xy 405.312431 -429.964366) (xy 405.326683 -429.983894)
			(xy 405.334215 -430.006866) (xy 405.334724 -430.018952) (xy 405.334724 -431.560478) (xy 406.240996 -431.560478)
			(xy 406.240996 -429.018954) (xy 406.241472 -429.006841) (xy 406.248967 -428.983804) (xy 406.263209 -428.964206)
			(xy 406.282807 -428.949965) (xy 406.305845 -428.942471) (xy 406.317958 -428.941992) (xy 407.257758 -428.941992)
			(xy 407.269866 -428.942547) (xy 407.2929 -428.950017) (xy 407.307392 -428.960534) (xy 408.240992 -428.960534)
			(xy 408.240992 -426.41901) (xy 408.24152 -426.406901) (xy 408.248999 -426.383865) (xy 408.263228 -426.364268)
			(xy 408.282815 -426.350024) (xy 408.305845 -426.342528) (xy 408.317954 -426.342048) (xy 409.257754 -426.342048)
			(xy 409.269875 -426.342499) (xy 409.292934 -426.34998) (xy 409.312551 -426.364223) (xy 409.326804 -426.383833)
			(xy 409.334295 -426.406889) (xy 409.334716 -426.41901) (xy 409.334716 -427.960536) (xy 410.240988 -427.960536)
			(xy 410.240988 -425.419012) (xy 410.24147 -425.406964) (xy 410.248898 -425.38404) (xy 410.263033 -425.364526)
			(xy 410.282498 -425.350321) (xy 410.305395 -425.342813) (xy 410.317442 -425.342304) (xy 411.25775 -425.342304)
			(xy 411.269833 -425.342849) (xy 411.292826 -425.350288) (xy 411.312404 -425.364455) (xy 411.326658 -425.383971)
			(xy 411.334197 -425.406931) (xy 411.334712 -425.419012) (xy 411.334712 -427.960536) (xy 411.334271 -427.972587)
			(xy 411.32683 -427.995512) (xy 411.312684 -428.015026) (xy 411.293211 -428.029228) (xy 411.270307 -428.036736)
			(xy 411.258258 -428.037244) (xy 410.31795 -428.037244) (xy 410.305861 -428.03675) (xy 410.28286 -428.029305)
			(xy 410.263278 -428.015126) (xy 410.249026 -427.995597) (xy 410.241495 -427.972623) (xy 410.240988 -427.960536)
			(xy 409.334716 -427.960536) (xy 409.334716 -428.960534) (xy 409.334368 -428.972663) (xy 409.326861 -428.995731)
			(xy 409.312592 -429.015349) (xy 409.292959 -429.029598) (xy 409.269884 -429.037081) (xy 409.257754 -429.037496)
			(xy 408.317954 -429.037496) (xy 408.30584 -429.037028) (xy 408.282801 -429.029532) (xy 408.263203 -429.015288)
			(xy 408.248962 -428.995688) (xy 408.24147 -428.972648) (xy 408.240992 -428.960534) (xy 407.307392 -428.960534)
			(xy 407.312498 -428.964239) (xy 407.326743 -428.983821) (xy 407.334239 -429.006847) (xy 407.33472 -429.018954)
			(xy 407.33472 -431.560478) (xy 407.334321 -431.572604) (xy 407.326829 -431.595669) (xy 407.312574 -431.615288)
			(xy 407.292951 -431.629538) (xy 407.269884 -431.637024) (xy 407.257758 -431.63744) (xy 406.317958 -431.63744)
			(xy 406.305839 -431.637024) (xy 406.282791 -431.629522) (xy 406.263188 -431.615267) (xy 406.248948 -431.595652)
			(xy 406.241466 -431.572597) (xy 406.240996 -431.560478) (xy 405.334724 -431.560478) (xy 405.334724 -432.560476)
			(xy 405.33422 -432.572523) (xy 405.326797 -432.595443) (xy 405.312667 -432.614957) (xy 405.293207 -432.629162)
			(xy 405.270315 -432.636673) (xy 405.25827 -432.637184) (xy 404.317962 -432.637184) (xy 404.305873 -432.636726)
			(xy 404.282875 -432.629261) (xy 404.263298 -432.615072) (xy 404.249048 -432.595538) (xy 404.241512 -432.572564)
			(xy 404.241 -432.560476) (xy 403.307201 -432.560476) (xy 403.312451 -432.56428) (xy 403.326701 -432.583821)
			(xy 403.334225 -432.606805) (xy 403.334728 -432.618896) (xy 403.334728 -435.16042) (xy 403.334257 -435.172468)
			(xy 403.326823 -435.19539) (xy 403.312684 -435.214903) (xy 403.293217 -435.229106) (xy 403.270321 -435.236617)
			(xy 403.258274 -435.237128) (xy 402.317966 -435.237128) (xy 402.305871 -435.236721) (xy 402.282864 -435.229251)
			(xy 402.263282 -435.21505) (xy 402.249034 -435.195502) (xy 402.241508 -435.172513) (xy 402.241004 -435.16042)
			(xy 401.334732 -435.16042) (xy 401.334732 -436.160418) (xy 401.334355 -436.172545) (xy 401.326854 -436.195609)
			(xy 401.312592 -436.215226) (xy 401.292966 -436.229476) (xy 401.269897 -436.236962) (xy 401.25777 -436.23738)
			(xy 400.31797 -436.23738) (xy 400.305856 -436.236914) (xy 400.282814 -436.229421) (xy 400.263215 -436.215177)
			(xy 400.248974 -436.195575) (xy 400.241484 -436.172532) (xy 400.241008 -436.160418) (xy 399.306858 -436.160418)
			(xy 399.312458 -436.164476) (xy 399.326708 -436.184017) (xy 399.334233 -436.207001) (xy 399.334736 -436.219092)
			(xy 399.334736 -438.760616) (xy 399.334254 -438.772663) (xy 399.326821 -438.795583) (xy 399.312685 -438.815096)
			(xy 399.293222 -438.8293) (xy 399.270328 -438.836812) (xy 399.258282 -438.837324) (xy 398.317974 -438.837324)
			(xy 398.305879 -438.836914) (xy 398.282872 -438.829446) (xy 398.263289 -438.815246) (xy 398.249041 -438.795698)
			(xy 398.241516 -438.772709) (xy 398.241012 -438.760616) (xy 396.334488 -438.760616) (xy 396.334488 -439.760614)
			(xy 400.241008 -439.760614) (xy 400.241008 -437.21909) (xy 400.241503 -437.206978) (xy 400.248989 -437.18394)
			(xy 400.263226 -437.164341) (xy 400.282822 -437.150098) (xy 400.305858 -437.142606) (xy 400.31797 -437.142128)
			(xy 401.25777 -437.142128) (xy 401.26989 -437.142585) (xy 401.292946 -437.150068) (xy 401.312561 -437.16431)
			(xy 401.326814 -437.183918) (xy 401.334308 -437.20697) (xy 401.334732 -437.21909) (xy 401.334732 -438.760616)
			(xy 402.241004 -438.760616) (xy 402.241004 -436.219092) (xy 402.241453 -436.207041) (xy 402.248889 -436.184115)
			(xy 402.263032 -436.164599) (xy 402.282505 -436.150396) (xy 402.305409 -436.14289) (xy 402.317458 -436.142384)
			(xy 403.257766 -436.142384) (xy 403.269858 -436.142837) (xy 403.292865 -436.15029) (xy 403.306845 -436.160418)
			(xy 404.241 -436.160418) (xy 404.241 -433.618894) (xy 404.241506 -433.606783) (xy 404.24899 -433.583746)
			(xy 404.263225 -433.564148) (xy 404.282817 -433.549905) (xy 404.305851 -433.542411) (xy 404.317962 -433.541932)
			(xy 405.257762 -433.541932) (xy 405.269882 -433.542392) (xy 405.292939 -433.549873) (xy 405.312554 -433.564115)
			(xy 405.326807 -433.583722) (xy 405.334301 -433.606774) (xy 405.334724 -433.618894) (xy 405.334724 -435.16042)
			(xy 406.240996 -435.16042) (xy 406.240996 -432.618896) (xy 406.241457 -432.606846) (xy 406.24889 -432.583921)
			(xy 406.263031 -432.564406) (xy 406.282501 -432.550202) (xy 406.305402 -432.542696) (xy 406.31745 -432.542188)
			(xy 407.257758 -432.542188) (xy 407.26985 -432.542644) (xy 407.292858 -432.550095) (xy 407.307187 -432.560476)
			(xy 408.240992 -432.560476) (xy 408.240992 -430.018952) (xy 408.241419 -430.0069) (xy 408.248864 -429.983974)
			(xy 408.263013 -429.96446) (xy 408.28249 -429.950258) (xy 408.305395 -429.942752) (xy 408.317446 -429.942244)
			(xy 409.257754 -429.942244) (xy 409.269842 -429.942747) (xy 409.292841 -429.950191) (xy 409.312422 -429.964368)
			(xy 409.326674 -429.983895) (xy 409.334207 -430.006866) (xy 409.334716 -430.018952) (xy 409.334716 -431.560478)
			(xy 410.240988 -431.560478) (xy 410.240988 -429.018954) (xy 410.241472 -429.006842) (xy 410.248966 -428.983806)
			(xy 410.263206 -428.964209) (xy 410.282802 -428.949967) (xy 410.305838 -428.942472) (xy 410.31795 -428.941992)
			(xy 411.25775 -428.941992) (xy 411.269863 -428.942468) (xy 411.2929 -428.949964) (xy 411.307444 -428.960534)
			(xy 412.240984 -428.960534) (xy 412.240984 -426.41901) (xy 412.241369 -426.406883) (xy 412.248864 -426.383817)
			(xy 412.263123 -426.364198) (xy 412.282749 -426.349948) (xy 412.305819 -426.342464) (xy 412.317946 -426.342048)
			(xy 413.257746 -426.342048) (xy 413.269864 -426.342473) (xy 413.29291 -426.349974) (xy 413.312512 -426.364228)
			(xy 413.326752 -426.38384) (xy 413.334236 -426.406892) (xy 413.334708 -426.41901) (xy 413.334708 -428.960534)
			(xy 413.334218 -428.972646) (xy 413.326727 -428.995682) (xy 413.312488 -429.01528) (xy 413.292893 -429.029522)
			(xy 413.269858 -429.037016) (xy 413.257746 -429.037496) (xy 412.317946 -429.037496) (xy 412.305829 -429.037002)
			(xy 412.282777 -429.029526) (xy 412.263164 -429.015292) (xy 412.248911 -428.995694) (xy 412.241411 -428.972651)
			(xy 412.240984 -428.960534) (xy 411.307444 -428.960534) (xy 411.312497 -428.964206) (xy 411.326738 -428.983804)
			(xy 411.334232 -429.006841) (xy 411.334712 -429.018954) (xy 411.334712 -431.560478) (xy 411.33417 -431.572586)
			(xy 411.326695 -431.59562) (xy 411.312469 -431.615218) (xy 411.292885 -431.629462) (xy 411.269858 -431.636959)
			(xy 411.25775 -431.63744) (xy 410.31795 -431.63744) (xy 410.305831 -431.63703) (xy 410.282782 -431.629527)
			(xy 410.263179 -431.615269) (xy 410.24894 -431.595653) (xy 410.241458 -431.572598) (xy 410.240988 -431.560478)
			(xy 409.334716 -431.560478) (xy 409.334716 -432.560476) (xy 409.33422 -432.572523) (xy 409.326796 -432.595445)
			(xy 409.312664 -432.61496) (xy 409.293202 -432.629165) (xy 409.270308 -432.636675) (xy 409.258262 -432.637184)
			(xy 408.317954 -432.637184) (xy 408.305864 -432.636732) (xy 408.282866 -432.629266) (xy 408.263289 -432.615074)
			(xy 408.249039 -432.59554) (xy 408.241504 -432.572564) (xy 408.240992 -432.560476) (xy 407.307187 -432.560476)
			(xy 407.312442 -432.564283) (xy 407.326693 -432.583822) (xy 407.334217 -432.606805) (xy 407.33472 -432.618896)
			(xy 407.33472 -435.16042) (xy 407.334257 -435.172469) (xy 407.326821 -435.195392) (xy 407.312681 -435.214906)
			(xy 407.293212 -435.229109) (xy 407.270314 -435.236618) (xy 407.258266 -435.237128) (xy 406.317958 -435.237128)
			(xy 406.305863 -435.236728) (xy 406.282856 -435.229256) (xy 406.263274 -435.215053) (xy 406.249026 -435.195504)
			(xy 406.2415 -435.172514) (xy 406.240996 -435.16042) (xy 405.334724 -435.16042) (xy 405.334724 -436.160418)
			(xy 405.334355 -436.172545) (xy 405.326853 -436.195611) (xy 405.312589 -436.215229) (xy 405.292961 -436.229478)
			(xy 405.26989 -436.236963) (xy 405.257762 -436.23738) (xy 404.317962 -436.23738) (xy 404.305847 -436.236921)
			(xy 404.282806 -436.229425) (xy 404.263206 -436.21518) (xy 404.248965 -436.195576) (xy 404.241476 -436.172533)
			(xy 404.241 -436.160418) (xy 403.306845 -436.160418) (xy 403.312449 -436.164478) (xy 403.3267 -436.184018)
			(xy 403.334225 -436.207001) (xy 403.334728 -436.219092) (xy 403.334728 -438.760616) (xy 403.334254 -438.772664)
			(xy 403.32682 -438.795586) (xy 403.312682 -438.815099) (xy 403.293217 -438.829302) (xy 403.270321 -438.836813)
			(xy 403.258274 -438.837324) (xy 402.317966 -438.837324) (xy 402.305871 -438.836921) (xy 402.282863 -438.829451)
			(xy 402.263281 -438.815249) (xy 402.249033 -438.7957) (xy 402.241508 -438.77271) (xy 402.241004 -438.760616)
			(xy 401.334732 -438.760616) (xy 401.334732 -439.760614) (xy 404.241 -439.760614) (xy 404.241 -437.21909)
			(xy 404.241503 -437.206979) (xy 404.248988 -437.183942) (xy 404.263224 -437.164343) (xy 404.282817 -437.150101)
			(xy 404.305851 -437.142607) (xy 404.317962 -437.142128) (xy 405.257762 -437.142128) (xy 405.269882 -437.142592)
			(xy 405.292938 -437.150073) (xy 405.312553 -437.164313) (xy 405.326805 -437.183919) (xy 405.3343 -437.20697)
			(xy 405.334724 -437.21909) (xy 405.334724 -438.760616) (xy 406.240996 -438.760616) (xy 406.240996 -436.219092)
			(xy 406.241453 -436.207042) (xy 406.248888 -436.184117) (xy 406.263029 -436.164601) (xy 406.2825 -436.150398)
			(xy 406.305401 -436.142892) (xy 406.31745 -436.142384) (xy 407.257758 -436.142384) (xy 407.26985 -436.142844)
			(xy 407.292856 -436.150294) (xy 407.306832 -436.160418) (xy 408.240992 -436.160418) (xy 408.240992 -433.618894)
			(xy 408.241506 -433.606784) (xy 408.248989 -433.583748) (xy 408.263222 -433.564151) (xy 408.282812 -433.549908)
			(xy 408.305844 -433.542412) (xy 408.317954 -433.541932) (xy 409.257754 -433.541932) (xy 409.269874 -433.542399)
			(xy 409.29293 -433.549878) (xy 409.312546 -433.564117) (xy 409.326798 -433.583723) (xy 409.334293 -433.606775)
			(xy 409.334716 -433.618894) (xy 409.334716 -435.16042) (xy 410.240988 -435.16042) (xy 410.240988 -432.618896)
			(xy 410.241456 -432.606847) (xy 410.248889 -432.583923) (xy 410.263028 -432.564409) (xy 410.282496 -432.550205)
			(xy 410.305394 -432.542697) (xy 410.317442 -432.542188) (xy 411.25775 -432.542188) (xy 411.269842 -432.542651)
			(xy 411.292849 -432.5501) (xy 411.307175 -432.560476) (xy 412.240984 -432.560476) (xy 412.240984 -430.018952)
			(xy 412.241419 -430.006901) (xy 412.248863 -429.983976) (xy 412.263011 -429.964463) (xy 412.282485 -429.950261)
			(xy 412.305388 -429.942753) (xy 412.317438 -429.942244) (xy 413.257746 -429.942244) (xy 413.269838 -429.942668)
			(xy 413.292841 -429.950138) (xy 413.312421 -429.964336) (xy 413.32667 -429.983878) (xy 413.3342 -430.006861)
			(xy 413.334708 -430.018952) (xy 413.334708 -432.560476) (xy 413.33422 -432.572524) (xy 413.326795 -432.595448)
			(xy 413.312661 -432.614963) (xy 413.293197 -432.629168) (xy 413.2703 -432.636676) (xy 413.258254 -432.637184)
			(xy 412.317946 -432.637184) (xy 412.305861 -432.636654) (xy 412.282866 -432.629213) (xy 412.263287 -432.615042)
			(xy 412.249034 -432.595522) (xy 412.241497 -432.572559) (xy 412.240984 -432.560476) (xy 411.307175 -432.560476)
			(xy 411.312434 -432.564285) (xy 411.326684 -432.583823) (xy 411.334209 -432.606806) (xy 411.334712 -432.618896)
			(xy 411.334712 -435.16042) (xy 411.334257 -435.17247) (xy 411.32682 -435.195394) (xy 411.312678 -435.214908)
			(xy 411.293207 -435.229111) (xy 411.270306 -435.236619) (xy 411.258258 -435.237128) (xy 410.31795 -435.237128)
			(xy 410.30586 -435.23665) (xy 410.282855 -435.229203) (xy 410.263272 -435.21502) (xy 410.249021 -435.195487)
			(xy 410.241493 -435.172508) (xy 410.240988 -435.16042) (xy 409.334716 -435.16042) (xy 409.334716 -436.160418)
			(xy 409.334354 -436.172546) (xy 409.326852 -436.195613) (xy 409.312586 -436.215232) (xy 409.292956 -436.229481)
			(xy 409.269883 -436.236965) (xy 409.257754 -436.23738) (xy 408.317954 -436.23738) (xy 408.305839 -436.236928)
			(xy 408.282797 -436.22943) (xy 408.263198 -436.215182) (xy 408.248957 -436.195578) (xy 408.241468 -436.172533)
			(xy 408.240992 -436.160418) (xy 407.306832 -436.160418) (xy 407.312441 -436.164481) (xy 407.326691 -436.184019)
			(xy 407.334216 -436.207002) (xy 407.33472 -436.219092) (xy 407.33472 -438.760616) (xy 407.334254 -438.772665)
			(xy 407.326819 -438.795588) (xy 407.312679 -438.815101) (xy 407.293212 -438.829305) (xy 407.270313 -438.836814)
			(xy 407.258266 -438.837324) (xy 406.317958 -438.837324) (xy 406.305863 -438.836928) (xy 406.282855 -438.829455)
			(xy 406.263272 -438.815252) (xy 406.249024 -438.795701) (xy 406.2415 -438.77271) (xy 406.240996 -438.760616)
			(xy 405.334724 -438.760616) (xy 405.334724 -439.760614) (xy 408.240992 -439.760614) (xy 408.240992 -437.21909)
			(xy 408.241503 -437.20698) (xy 408.248987 -437.183944) (xy 408.263221 -437.164346) (xy 408.282812 -437.150104)
			(xy 408.305844 -437.142608) (xy 408.317954 -437.142128) (xy 409.257754 -437.142128) (xy 409.269873 -437.142599)
			(xy 409.292929 -437.150077) (xy 409.312544 -437.164316) (xy 409.326797 -437.183921) (xy 409.334292 -437.206971)
			(xy 409.334716 -437.21909) (xy 409.334716 -438.760616) (xy 410.240988 -438.760616) (xy 410.240988 -436.219092)
			(xy 410.241453 -436.207043) (xy 410.248886 -436.184119) (xy 410.263026 -436.164604) (xy 410.282495 -436.150401)
			(xy 410.305394 -436.142893) (xy 410.317442 -436.142384) (xy 411.25775 -436.142384) (xy 411.269841 -436.142851)
			(xy 411.292848 -436.150299) (xy 411.306818 -436.160418) (xy 412.240984 -436.160418) (xy 412.240984 -433.618894)
			(xy 412.241356 -433.606766) (xy 412.248855 -433.5837) (xy 412.263118 -433.564081) (xy 412.282746 -433.549831)
			(xy 412.305818 -433.542348) (xy 412.317946 -433.541932) (xy 413.257746 -433.541932) (xy 413.269862 -433.542372)
			(xy 413.292906 -433.549872) (xy 413.312507 -433.564122) (xy 413.326747 -433.58373) (xy 413.334234 -433.606777)
			(xy 413.334708 -433.618894) (xy 413.334708 -435.59984) (xy 446.741306 -435.59984) (xy 446.745288 -435.471854)
			(xy 446.75722 -435.344363) (xy 446.777054 -435.21786) (xy 446.804715 -435.092835) (xy 446.840095 -434.969772)
			(xy 446.883057 -434.849146) (xy 446.933435 -434.731425) (xy 446.991035 -434.617063) (xy 447.055633 -434.506504)
			(xy 447.12698 -434.400174) (xy 447.204799 -434.298486) (xy 447.288789 -434.201832) (xy 447.378626 -434.110587)
			(xy 447.473962 -434.025104) (xy 447.574427 -433.945713) (xy 447.679635 -433.872721) (xy 447.789176 -433.806412)
			(xy 447.902628 -433.747041) (xy 448.019552 -433.694837) (xy 448.139495 -433.650004) (xy 448.261993 -433.612715)
			(xy 448.386573 -433.583113) (xy 448.512751 -433.561314) (xy 448.640041 -433.547401) (xy 448.76795 -433.541429)
			(xy 448.895983 -433.54342) (xy 449.023644 -433.553368) (xy 449.15044 -433.571232) (xy 449.275879 -433.596945)
			(xy 449.399478 -433.630407) (xy 449.520757 -433.671488) (xy 449.639248 -433.72003) (xy 449.754492 -433.775844)
			(xy 449.866042 -433.838715) (xy 449.973469 -433.908399) (xy 450.076355 -433.984627) (xy 450.174303 -434.067104)
			(xy 450.266934 -434.155511) (xy 450.35389 -434.249506) (xy 450.434834 -434.348725) (xy 450.509453 -434.452784)
			(xy 450.577458 -434.561281) (xy 450.638586 -434.673796) (xy 450.692601 -434.789894) (xy 450.739294 -434.909125)
			(xy 450.778484 -435.031029) (xy 450.81002 -435.155133) (xy 450.833779 -435.280957) (xy 450.849669 -435.408016)
			(xy 450.85763 -435.535816) (xy 450.858128 -435.59984) (xy 450.85763 -435.663864) (xy 450.849669 -435.791664)
			(xy 450.833779 -435.918723) (xy 450.81002 -436.044547) (xy 450.778484 -436.168651) (xy 450.739294 -436.290555)
			(xy 450.692601 -436.409786) (xy 450.638586 -436.525884) (xy 450.577458 -436.638399) (xy 450.509453 -436.746896)
			(xy 450.434834 -436.850955) (xy 450.35389 -436.950174) (xy 450.266934 -437.044169) (xy 450.174303 -437.132576)
			(xy 450.076355 -437.215053) (xy 449.973469 -437.291281) (xy 449.866042 -437.360965) (xy 449.754492 -437.423836)
			(xy 449.639248 -437.47965) (xy 449.520757 -437.528192) (xy 449.399478 -437.569273) (xy 449.275879 -437.602735)
			(xy 449.15044 -437.628448) (xy 449.023644 -437.646312) (xy 448.895983 -437.65626) (xy 448.76795 -437.658251)
			(xy 448.640041 -437.652279) (xy 448.512751 -437.638366) (xy 448.386573 -437.616567) (xy 448.261993 -437.586965)
			(xy 448.139495 -437.549676) (xy 448.019552 -437.504843) (xy 447.902628 -437.452639) (xy 447.789176 -437.393268)
			(xy 447.679635 -437.326959) (xy 447.574427 -437.253967) (xy 447.473962 -437.174576) (xy 447.378626 -437.089093)
			(xy 447.288789 -436.997848) (xy 447.204799 -436.901194) (xy 447.12698 -436.799506) (xy 447.055633 -436.693176)
			(xy 446.991035 -436.582617) (xy 446.933435 -436.468255) (xy 446.883057 -436.350534) (xy 446.840095 -436.229908)
			(xy 446.804715 -436.106845) (xy 446.777054 -435.98182) (xy 446.75722 -435.855317) (xy 446.745288 -435.727826)
			(xy 446.741306 -435.59984) (xy 413.334708 -435.59984) (xy 413.334708 -436.160418) (xy 413.334205 -436.172529)
			(xy 413.326718 -436.195565) (xy 413.312482 -436.215163) (xy 413.29289 -436.229405) (xy 413.269857 -436.2369)
			(xy 413.257746 -436.23738) (xy 412.317946 -436.23738) (xy 412.305827 -436.236901) (xy 412.282773 -436.229424)
			(xy 412.263159 -436.215187) (xy 412.248905 -436.195584) (xy 412.241409 -436.172536) (xy 412.240984 -436.160418)
			(xy 411.306818 -436.160418) (xy 411.312432 -436.164484) (xy 411.326683 -436.184021) (xy 411.334208 -436.207002)
			(xy 411.334712 -436.219092) (xy 411.334712 -438.760616) (xy 411.334254 -438.772666) (xy 411.326818 -438.79559)
			(xy 411.312676 -438.815104) (xy 411.293207 -438.829307) (xy 411.270306 -438.836815) (xy 411.258258 -438.837324)
			(xy 410.31795 -438.837324) (xy 410.305859 -438.836849) (xy 410.282854 -438.829402) (xy 410.26327 -438.815219)
			(xy 410.249019 -438.795684) (xy 410.241493 -438.772705) (xy 410.240988 -438.760616) (xy 409.334716 -438.760616)
			(xy 409.334716 -439.760614) (xy 412.240984 -439.760614) (xy 412.240984 -437.21909) (xy 412.241352 -437.206962)
			(xy 412.248853 -437.183895) (xy 412.263116 -437.164276) (xy 412.282745 -437.150027) (xy 412.305818 -437.142544)
			(xy 412.317946 -437.142128) (xy 413.257746 -437.142128) (xy 413.269862 -437.142572) (xy 413.292905 -437.150071)
			(xy 413.312505 -437.164321) (xy 413.326745 -437.183927) (xy 413.334233 -437.206974) (xy 413.334708 -437.21909)
			(xy 413.334708 -439.760614) (xy 413.334201 -439.772725) (xy 413.326716 -439.795761) (xy 413.312481 -439.815358)
			(xy 413.292889 -439.829601) (xy 413.269857 -439.837096) (xy 413.257746 -439.837576) (xy 412.317946 -439.837576)
			(xy 412.305827 -439.837101) (xy 412.282772 -439.829623) (xy 412.263157 -439.815385) (xy 412.248904 -439.795782)
			(xy 412.241408 -439.772733) (xy 412.240984 -439.760614) (xy 409.334716 -439.760614) (xy 409.334351 -439.772742)
			(xy 409.326849 -439.795809) (xy 409.312585 -439.815428) (xy 409.292955 -439.829677) (xy 409.269882 -439.83716)
			(xy 409.257754 -439.837576) (xy 408.317954 -439.837576) (xy 408.305838 -439.837128) (xy 408.282796 -439.82963)
			(xy 408.263196 -439.815381) (xy 408.248956 -439.795775) (xy 408.241467 -439.77273) (xy 408.240992 -439.760614)
			(xy 405.334724 -439.760614) (xy 405.334351 -439.772741) (xy 405.32685 -439.795807) (xy 405.312588 -439.815425)
			(xy 405.29296 -439.829674) (xy 405.26989 -439.837159) (xy 405.257762 -439.837576) (xy 404.317962 -439.837576)
			(xy 404.305847 -439.837121) (xy 404.282805 -439.829625) (xy 404.263205 -439.815378) (xy 404.248964 -439.795774)
			(xy 404.241475 -439.772729) (xy 404.241 -439.760614) (xy 401.334732 -439.760614) (xy 401.334351 -439.77274)
			(xy 401.326852 -439.795805) (xy 401.312591 -439.815422) (xy 401.292965 -439.829672) (xy 401.269897 -439.837158)
			(xy 401.25777 -439.837576) (xy 400.31797 -439.837576) (xy 400.305855 -439.837114) (xy 400.282813 -439.82962)
			(xy 400.263213 -439.815375) (xy 400.248972 -439.795772) (xy 400.241483 -439.772729) (xy 400.241008 -439.760614)
			(xy 396.334488 -439.760614) (xy 396.334005 -439.772702) (xy 396.326548 -439.795698) (xy 396.312365 -439.815275)
			(xy 396.292836 -439.829526) (xy 396.269866 -439.837063) (xy 396.25778 -439.837576) (xy 395.31798 -439.837576)
			(xy 395.305868 -439.8372) (xy 395.282836 -439.829693) (xy 395.263261 -439.815421) (xy 395.249068 -439.79579)
			(xy 395.241652 -439.772728) (xy 395.241272 -439.760614) (xy 392.334496 -439.760614) (xy 392.334005 -439.772701)
			(xy 392.326549 -439.795696) (xy 392.312367 -439.815272) (xy 392.292841 -439.829524) (xy 392.269873 -439.837062)
			(xy 392.257788 -439.837576) (xy 391.317988 -439.837576) (xy 391.305876 -439.837194) (xy 391.282844 -439.829688)
			(xy 391.263269 -439.815419) (xy 391.249076 -439.795788) (xy 391.24166 -439.772727) (xy 391.24128 -439.760614)
			(xy 388.334504 -439.760614) (xy 388.334006 -439.7727) (xy 388.32655 -439.795694) (xy 388.31237 -439.81527)
			(xy 388.292846 -439.829521) (xy 388.26988 -439.837061) (xy 388.257796 -439.837576) (xy 387.317996 -439.837576)
			(xy 387.305885 -439.837187) (xy 387.282853 -439.829683) (xy 387.263278 -439.815416) (xy 387.249084 -439.795787)
			(xy 387.241668 -439.772727) (xy 387.241288 -439.760614) (xy 384.334512 -439.760614) (xy 384.334104 -439.772709)
			(xy 384.326638 -439.795718) (xy 384.312437 -439.815302) (xy 384.292889 -439.829551) (xy 384.269898 -439.837074)
			(xy 384.257804 -439.837576) (xy 383.318004 -439.837576) (xy 383.305893 -439.83718) (xy 383.282862 -439.829679)
			(xy 383.263286 -439.815413) (xy 383.249092 -439.795785) (xy 383.241676 -439.772727) (xy 383.241296 -439.760614)
			(xy 346.234512 -439.760614) (xy 346.234104 -439.772709) (xy 346.226638 -439.795718) (xy 346.212437 -439.815302)
			(xy 346.192889 -439.829551) (xy 346.169898 -439.837074) (xy 346.157804 -439.837576) (xy 345.218004 -439.837576)
			(xy 345.205893 -439.83718) (xy 345.182862 -439.829679) (xy 345.163286 -439.815413) (xy 345.149092 -439.795785)
			(xy 345.141676 -439.772727) (xy 345.141296 -439.760614) (xy 342.23452 -439.760614) (xy 342.234104 -439.772708)
			(xy 342.226639 -439.795716) (xy 342.21244 -439.815299) (xy 342.192894 -439.829548) (xy 342.169905 -439.837073)
			(xy 342.157812 -439.837576) (xy 341.218012 -439.837576) (xy 341.205901 -439.837173) (xy 341.18287 -439.829674)
			(xy 341.163295 -439.81541) (xy 341.149101 -439.795784) (xy 341.141684 -439.772726) (xy 341.141304 -439.760614)
			(xy 338.234528 -439.760614) (xy 338.234104 -439.772708) (xy 338.22664 -439.795714) (xy 338.212443 -439.815297)
			(xy 338.192899 -439.829546) (xy 338.169912 -439.837072) (xy 338.15782 -439.837576) (xy 337.21802 -439.837576)
			(xy 337.20591 -439.837166) (xy 337.182879 -439.829669) (xy 337.163304 -439.815407) (xy 337.149109 -439.795782)
			(xy 337.141692 -439.772726) (xy 337.141312 -439.760614) (xy 334.234536 -439.760614) (xy 334.234104 -439.772707)
			(xy 334.226641 -439.795712) (xy 334.212446 -439.815294) (xy 334.192904 -439.829543) (xy 334.169919 -439.83707)
			(xy 334.157828 -439.837576) (xy 333.218028 -439.837576) (xy 333.205918 -439.837159) (xy 333.182888 -439.829665)
			(xy 333.163312 -439.815404) (xy 333.149117 -439.795781) (xy 333.1417 -439.772725) (xy 333.14132 -439.760614)
			(xy 329.2348 -439.760614) (xy 329.234301 -439.772726) (xy 329.226815 -439.795763) (xy 329.212578 -439.815361)
			(xy 329.192984 -439.829604) (xy 329.169949 -439.837097) (xy 329.157838 -439.837576) (xy 328.218038 -439.837576)
			(xy 328.205919 -439.837108) (xy 328.182863 -439.829628) (xy 328.163249 -439.815388) (xy 328.148996 -439.795783)
			(xy 328.1415 -439.772733) (xy 328.141076 -439.760614) (xy 325.234808 -439.760614) (xy 325.234301 -439.772725)
			(xy 325.226816 -439.795761) (xy 325.212581 -439.815358) (xy 325.192989 -439.829601) (xy 325.169957 -439.837096)
			(xy 325.157846 -439.837576) (xy 324.218046 -439.837576) (xy 324.205927 -439.837101) (xy 324.182872 -439.829623)
			(xy 324.163257 -439.815385) (xy 324.149004 -439.795782) (xy 324.141508 -439.772733) (xy 324.141084 -439.760614)
			(xy 321.234816 -439.760614) (xy 321.234451 -439.772742) (xy 321.226949 -439.795809) (xy 321.212685 -439.815428)
			(xy 321.193055 -439.829677) (xy 321.169982 -439.83716) (xy 321.157854 -439.837576) (xy 320.218054 -439.837576)
			(xy 320.205938 -439.837128) (xy 320.182896 -439.82963) (xy 320.163296 -439.815381) (xy 320.149056 -439.795775)
			(xy 320.141567 -439.77273) (xy 320.141092 -439.760614) (xy 317.234824 -439.760614) (xy 317.234451 -439.772741)
			(xy 317.22695 -439.795807) (xy 317.212688 -439.815425) (xy 317.19306 -439.829674) (xy 317.16999 -439.837159)
			(xy 317.157862 -439.837576) (xy 316.218062 -439.837576) (xy 316.205947 -439.837121) (xy 316.182905 -439.829625)
			(xy 316.163305 -439.815378) (xy 316.149064 -439.795774) (xy 316.141575 -439.772729) (xy 316.1411 -439.760614)
			(xy 157.334712 -439.760614) (xy 157.334201 -439.772724) (xy 157.326716 -439.79576) (xy 157.312482 -439.815357)
			(xy 157.292892 -439.8296) (xy 157.26986 -439.837096) (xy 157.25775 -439.837576) (xy 156.31795 -439.837576)
			(xy 156.305834 -439.837131) (xy 156.282792 -439.829632) (xy 156.263192 -439.815382) (xy 156.248952 -439.795776)
			(xy 156.241463 -439.77273) (xy 156.240988 -439.760614) (xy 153.33472 -439.760614) (xy 153.334351 -439.772742)
			(xy 153.32685 -439.795808) (xy 153.312586 -439.815426) (xy 153.292958 -439.829675) (xy 153.269886 -439.83716)
			(xy 153.257758 -439.837576) (xy 152.317958 -439.837576) (xy 152.305843 -439.837124) (xy 152.2828 -439.829627)
			(xy 152.263201 -439.815379) (xy 152.24896 -439.795774) (xy 152.241471 -439.77273) (xy 152.240996 -439.760614)
			(xy 149.334728 -439.760614) (xy 149.334351 -439.772741) (xy 149.326851 -439.795806) (xy 149.312589 -439.815424)
			(xy 149.292963 -439.829673) (xy 149.269893 -439.837159) (xy 149.257766 -439.837576) (xy 148.317966 -439.837576)
			(xy 148.305851 -439.837118) (xy 148.282809 -439.829623) (xy 148.263209 -439.815377) (xy 148.248968 -439.795773)
			(xy 148.241479 -439.772729) (xy 148.241004 -439.760614) (xy 145.334736 -439.760614) (xy 145.334351 -439.77274)
			(xy 145.326852 -439.795804) (xy 145.312592 -439.815421) (xy 145.292968 -439.82967) (xy 145.2699 -439.837158)
			(xy 145.257774 -439.837576) (xy 144.317974 -439.837576) (xy 144.305859 -439.837111) (xy 144.282818 -439.829618)
			(xy 144.263218 -439.815374) (xy 144.248976 -439.795772) (xy 144.241487 -439.772729) (xy 144.241012 -439.760614)
			(xy 140.334492 -439.760614) (xy 140.334005 -439.772701) (xy 140.326549 -439.795697) (xy 140.312366 -439.815274)
			(xy 140.292839 -439.829525) (xy 140.269869 -439.837062) (xy 140.257784 -439.837576) (xy 139.317984 -439.837576)
			(xy 139.305872 -439.837197) (xy 139.28284 -439.82969) (xy 139.263265 -439.81542) (xy 139.249072 -439.795789)
			(xy 139.241656 -439.772728) (xy 139.241276 -439.760614) (xy 136.3345 -439.760614) (xy 136.334006 -439.7727)
			(xy 136.32655 -439.795695) (xy 136.312369 -439.815271) (xy 136.292844 -439.829523) (xy 136.269877 -439.837061)
			(xy 136.257792 -439.837576) (xy 135.317992 -439.837576) (xy 135.30588 -439.83719) (xy 135.282849 -439.829686)
			(xy 135.263274 -439.815417) (xy 135.24908 -439.795788) (xy 135.241664 -439.772727) (xy 135.241284 -439.760614)
			(xy 132.334508 -439.760614) (xy 132.334006 -439.7727) (xy 132.326551 -439.795693) (xy 132.312372 -439.815268)
			(xy 132.292849 -439.82952) (xy 132.269884 -439.83706) (xy 132.2578 -439.837576) (xy 131.318 -439.837576)
			(xy 131.305889 -439.837184) (xy 131.282857 -439.829681) (xy 131.263282 -439.815414) (xy 131.249088 -439.795786)
			(xy 131.241672 -439.772727) (xy 131.241292 -439.760614) (xy 128.334516 -439.760614) (xy 128.334104 -439.772709)
			(xy 128.326638 -439.795717) (xy 128.312439 -439.815301) (xy 128.292891 -439.829549) (xy 128.269901 -439.837073)
			(xy 128.257808 -439.837576) (xy 127.318008 -439.837576) (xy 127.305897 -439.837177) (xy 127.282866 -439.829677)
			(xy 127.263291 -439.815412) (xy 127.249096 -439.795785) (xy 127.24168 -439.772726) (xy 127.2413 -439.760614)
			(xy 90.234516 -439.760614) (xy 90.234104 -439.772709) (xy 90.226638 -439.795717) (xy 90.212439 -439.815301)
			(xy 90.192891 -439.829549) (xy 90.169901 -439.837073) (xy 90.157808 -439.837576) (xy 89.218008 -439.837576)
			(xy 89.205897 -439.837177) (xy 89.182866 -439.829677) (xy 89.163291 -439.815412) (xy 89.149096 -439.795785)
			(xy 89.14168 -439.772726) (xy 89.1413 -439.760614) (xy 86.234524 -439.760614) (xy 86.234104 -439.772708)
			(xy 86.226639 -439.795715) (xy 86.212442 -439.815298) (xy 86.192896 -439.829547) (xy 86.169909 -439.837072)
			(xy 86.157816 -439.837576) (xy 85.218016 -439.837576) (xy 85.205906 -439.83717) (xy 85.182875 -439.829672)
			(xy 85.163299 -439.815408) (xy 85.149105 -439.795783) (xy 85.141688 -439.772726) (xy 85.141308 -439.760614)
			(xy 82.234532 -439.760614) (xy 82.234104 -439.772707) (xy 82.22664 -439.795713) (xy 82.212445 -439.815295)
			(xy 82.192901 -439.829544) (xy 82.169916 -439.837071) (xy 82.157824 -439.837576) (xy 81.218024 -439.837576)
			(xy 81.205914 -439.837163) (xy 81.182883 -439.829667) (xy 81.163308 -439.815406) (xy 81.149113 -439.795781)
			(xy 81.141696 -439.772725) (xy 81.141316 -439.760614) (xy 78.23454 -439.760614) (xy 78.234104 -439.772706)
			(xy 78.226641 -439.795711) (xy 78.212447 -439.815292) (xy 78.192906 -439.829542) (xy 78.169923 -439.83707)
			(xy 78.157832 -439.837576) (xy 77.218032 -439.837576) (xy 77.205922 -439.837156) (xy 77.182892 -439.829663)
			(xy 77.163316 -439.815403) (xy 77.149122 -439.79578) (xy 77.141704 -439.772725) (xy 77.141324 -439.760614)
			(xy 73.234804 -439.760614) (xy 73.234301 -439.772725) (xy 73.226815 -439.795762) (xy 73.21258 -439.81536)
			(xy 73.192987 -439.829602) (xy 73.169953 -439.837097) (xy 73.157842 -439.837576) (xy 72.218042 -439.837576)
			(xy 72.205923 -439.837105) (xy 72.182868 -439.829626) (xy 72.163253 -439.815387) (xy 72.149 -439.795783)
			(xy 72.141504 -439.772733) (xy 72.14108 -439.760614) (xy 69.234812 -439.760614) (xy 69.234301 -439.772724)
			(xy 69.226816 -439.79576) (xy 69.212582 -439.815357) (xy 69.192992 -439.8296) (xy 69.16996 -439.837096)
			(xy 69.15785 -439.837576) (xy 68.21805 -439.837576) (xy 68.205934 -439.837131) (xy 68.182892 -439.829632)
			(xy 68.163292 -439.815382) (xy 68.149052 -439.795776) (xy 68.141563 -439.77273) (xy 68.141088 -439.760614)
			(xy 65.23482 -439.760614) (xy 65.234451 -439.772742) (xy 65.22695 -439.795808) (xy 65.212686 -439.815426)
			(xy 65.193058 -439.829675) (xy 65.169986 -439.83716) (xy 65.157858 -439.837576) (xy 64.218058 -439.837576)
			(xy 64.205943 -439.837124) (xy 64.1829 -439.829627) (xy 64.163301 -439.815379) (xy 64.14906 -439.795774)
			(xy 64.141571 -439.77273) (xy 64.141096 -439.760614) (xy 61.234828 -439.760614) (xy 61.234451 -439.772741)
			(xy 61.226951 -439.795806) (xy 61.212689 -439.815424) (xy 61.193063 -439.829673) (xy 61.169993 -439.837159)
			(xy 61.157866 -439.837576) (xy 60.218066 -439.837576) (xy 60.205951 -439.837118) (xy 60.182909 -439.829623)
			(xy 60.163309 -439.815377) (xy 60.149068 -439.795773) (xy 60.141579 -439.772729) (xy 60.141104 -439.760614)
			(xy 7.00913 -439.760614) (xy 7.00913 -439.989976) (xy 7.009638 -440.045746) (xy 7.017973 -440.156973)
			(xy 7.034597 -440.267266) (xy 7.059417 -440.376009) (xy 7.092293 -440.482593) (xy 7.133043 -440.586422)
			(xy 7.181438 -440.686915) (xy 7.237207 -440.783511) (xy 7.300039 -440.87567) (xy 7.369583 -440.962874)
			(xy 7.445449 -441.044639) (xy 7.527212 -441.120505) (xy 7.614417 -441.190048) (xy 7.706575 -441.252881)
			(xy 7.803171 -441.30865) (xy 7.903664 -441.357045) (xy 8.007493 -441.397795) (xy 8.114077 -441.430672)
			(xy 8.22282 -441.455492) (xy 8.333113 -441.472116) (xy 8.44434 -441.480451) (xy 8.50011 -441.480956)
		)
		(stroke
			(width 0)
			(type solid)
		)
		(fill yes)
		(layer "In1.Cu")
		(net "GND")
	)
	(gr_line
		(start 1.414272 -79.914242)
		(end 0.585724 -79.085694)
		(stroke
			(width 1.016)
			(type default)
		)
		(layer "In1.Cu")
	)
	(gr_line
		(start 1.999996 -403.371558)
		(end 1.999996 -81.328514)
		(stroke
			(width 1.016)
			(type default)
		)
		(layer "In1.Cu")
	)
	(gr_arc
		(start 1.999996 -403.371558)
		(mid 2.152159 -404.136965)
		(end 2.58572 -404.78583)
		(stroke
			(width 1.016)
			(type default)
		)
		(layer "In1.Cu")
	)
	(gr_arc
		(start 1.999996 -81.328514)
		(mid 1.847755 -80.563149)
		(end 1.414272 -79.914242)
		(stroke
			(width 1.016)
			(type default)
		)
		(layer "In1.Cu")
	)
	(gr_arc
		(start 1.999996 -11.780012)
		(mid 0.585785 -12.365797)
		(end 0 -13.780008)
		(stroke
			(width 1.016)
			(type default)
		)
		(layer "In1.Cu")
	)
	(gr_line
		(start 1.999996 -11.780012)
		(end 11.102086 -11.780012)
		(stroke
			(width 1.016)
			(type default)
		)
		(layer "In1.Cu")
	)
	(gr_line
		(start 5.914136 -408.114246)
		(end 2.58572 -404.78583)
		(stroke
			(width 1.016)
			(type default)
		)
		(layer "In1.Cu")
	)
	(gr_line
		(start 6.500114 -439.989976)
		(end 6.500114 -409.528518)
		(stroke
			(width 1.016)
			(type default)
		)
		(layer "In1.Cu")
	)
	(gr_arc
		(start 6.500114 -439.989976)
		(mid 7.085891 -441.404199)
		(end 8.50011 -441.989972)
		(stroke
			(width 1.016)
			(type default)
		)
		(layer "In1.Cu")
	)
	(gr_arc
		(start 6.500114 -409.528518)
		(mid 6.347771 -408.763109)
		(end 5.914136 -408.114246)
		(stroke
			(width 1.016)
			(type default)
		)
		(layer "In1.Cu")
	)
	(gr_arc
		(start 11.102086 -11.780012)
		(mid 12.516297 -11.194227)
		(end 13.102082 -9.780016)
		(stroke
			(width 1.016)
			(type default)
		)
		(layer "In1.Cu")
	)
	(gr_line
		(start 13.102082 -9.780016)
		(end 13.102082 -0.500126)
		(stroke
			(width 1.016)
			(type default)
		)
		(layer "In1.Cu")
	)
	(gr_arc
		(start 13.601954 0)
		(mid 13.24848 -0.146572)
		(end 13.102082 -0.500126)
		(stroke
			(width 1.016)
			(type default)
		)
		(layer "In1.Cu")
	)
	(gr_line
		(start 13.601954 0)
		(end 81.202022 0)
		(stroke
			(width 1.016)
			(type default)
		)
		(layer "In1.Cu")
	)
	(gr_circle
		(center 25.82545 -40.816276)
		(end 26.71445 -40.816276)
		(stroke
			(width 0.2)
			(type default)
		)
		(fill no)
		(layer "In1.Cu")
	)
	(gr_circle
		(center 29.291534 -348.709488)
		(end 30.171644 -348.709488)
		(stroke
			(width 0.2)
			(type default)
		)
		(fill no)
		(layer "In1.Cu")
	)
	(gr_circle
		(center 29.908754 -348.709488)
		(end 30.788864 -348.709488)
		(stroke
			(width 0.2)
			(type default)
		)
		(fill no)
		(layer "In1.Cu")
	)
	(gr_circle
		(center 30.525974 -348.709488)
		(end 31.406084 -348.709488)
		(stroke
			(width 0.2)
			(type default)
		)
		(fill no)
		(layer "In1.Cu")
	)
	(gr_circle
		(center 30.795214 -347.966538)
		(end 31.684214 -347.966538)
		(stroke
			(width 0.2)
			(type default)
		)
		(fill no)
		(layer "In1.Cu")
	)
	(gr_circle
		(center 30.795214 -347.229938)
		(end 31.684214 -347.229938)
		(stroke
			(width 0.2)
			(type default)
		)
		(fill no)
		(layer "In1.Cu")
	)
	(gr_circle
		(center 31.22803 -350.318578)
		(end 32.11703 -350.318578)
		(stroke
			(width 0.2)
			(type default)
		)
		(fill no)
		(layer "In1.Cu")
	)
	(gr_circle
		(center 31.22803 -349.581978)
		(end 32.11703 -349.581978)
		(stroke
			(width 0.2)
			(type default)
		)
		(fill no)
		(layer "In1.Cu")
	)
	(gr_circle
		(center 31.752794 -349.142558)
		(end 32.641794 -349.142558)
		(stroke
			(width 0.2)
			(type default)
		)
		(fill no)
		(layer "In1.Cu")
	)
	(gr_circle
		(center 31.778194 -349.904558)
		(end 32.667194 -349.904558)
		(stroke
			(width 0.2)
			(type default)
		)
		(fill no)
		(layer "In1.Cu")
	)
	(gr_circle
		(center 32.311594 -350.260158)
		(end 33.200594 -350.260158)
		(stroke
			(width 0.2)
			(type default)
		)
		(fill no)
		(layer "In1.Cu")
	)
	(gr_circle
		(center 32.311594 -349.523558)
		(end 33.200594 -349.523558)
		(stroke
			(width 0.2)
			(type default)
		)
		(fill no)
		(layer "In1.Cu")
	)
	(gr_circle
		(center 32.311594 -348.786958)
		(end 33.200594 -348.786958)
		(stroke
			(width 0.2)
			(type default)
		)
		(fill no)
		(layer "In1.Cu")
	)
	(gr_circle
		(center 37.571934 -348.709488)
		(end 38.452044 -348.709488)
		(stroke
			(width 0.2)
			(type default)
		)
		(fill no)
		(layer "In1.Cu")
	)
	(gr_circle
		(center 38.189154 -348.709488)
		(end 39.069264 -348.709488)
		(stroke
			(width 0.2)
			(type default)
		)
		(fill no)
		(layer "In1.Cu")
	)
	(gr_circle
		(center 38.806374 -348.709488)
		(end 39.686484 -348.709488)
		(stroke
			(width 0.2)
			(type default)
		)
		(fill no)
		(layer "In1.Cu")
	)
	(gr_circle
		(center 39.050214 -347.974158)
		(end 39.939214 -347.974158)
		(stroke
			(width 0.2)
			(type default)
		)
		(fill no)
		(layer "In1.Cu")
	)
	(gr_circle
		(center 39.050214 -347.237558)
		(end 39.939214 -347.237558)
		(stroke
			(width 0.2)
			(type default)
		)
		(fill no)
		(layer "In1.Cu")
	)
	(gr_circle
		(center 39.50843 -350.318578)
		(end 40.39743 -350.318578)
		(stroke
			(width 0.2)
			(type default)
		)
		(fill no)
		(layer "In1.Cu")
	)
	(gr_circle
		(center 39.50843 -349.581978)
		(end 40.39743 -349.581978)
		(stroke
			(width 0.2)
			(type default)
		)
		(fill no)
		(layer "In1.Cu")
	)
	(gr_circle
		(center 40.033194 -349.142558)
		(end 40.922194 -349.142558)
		(stroke
			(width 0.2)
			(type default)
		)
		(fill no)
		(layer "In1.Cu")
	)
	(gr_circle
		(center 40.058594 -349.904558)
		(end 40.947594 -349.904558)
		(stroke
			(width 0.2)
			(type default)
		)
		(fill no)
		(layer "In1.Cu")
	)
	(gr_circle
		(center 40.591994 -350.260158)
		(end 41.480994 -350.260158)
		(stroke
			(width 0.2)
			(type default)
		)
		(fill no)
		(layer "In1.Cu")
	)
	(gr_circle
		(center 40.591994 -349.523558)
		(end 41.480994 -349.523558)
		(stroke
			(width 0.2)
			(type default)
		)
		(fill no)
		(layer "In1.Cu")
	)
	(gr_circle
		(center 40.591994 -348.786958)
		(end 41.480994 -348.786958)
		(stroke
			(width 0.2)
			(type default)
		)
		(fill no)
		(layer "In1.Cu")
	)
	(gr_circle
		(center 41.369742 -358.549194)
		(end 42.258742 -358.549194)
		(stroke
			(width 0.2)
			(type default)
		)
		(fill no)
		(layer "In1.Cu")
	)
	(gr_circle
		(center 41.417494 -357.898192)
		(end 42.306494 -357.898192)
		(stroke
			(width 0.2)
			(type default)
		)
		(fill no)
		(layer "In1.Cu")
	)
	(gr_circle
		(center 41.417494 -357.263192)
		(end 42.306494 -357.263192)
		(stroke
			(width 0.2)
			(type default)
		)
		(fill no)
		(layer "In1.Cu")
	)
	(gr_circle
		(center 41.427146 -359.2576)
		(end 42.316146 -359.2576)
		(stroke
			(width 0.2)
			(type default)
		)
		(fill no)
		(layer "In1.Cu")
	)
	(gr_circle
		(center 43.935904 -358.51084)
		(end 44.824904 -358.51084)
		(stroke
			(width 0.2)
			(type default)
		)
		(fill no)
		(layer "In1.Cu")
	)
	(gr_circle
		(center 43.983656 -357.859838)
		(end 44.872656 -357.859838)
		(stroke
			(width 0.2)
			(type default)
		)
		(fill no)
		(layer "In1.Cu")
	)
	(gr_circle
		(center 43.983656 -357.224838)
		(end 44.872656 -357.224838)
		(stroke
			(width 0.2)
			(type default)
		)
		(fill no)
		(layer "In1.Cu")
	)
	(gr_circle
		(center 43.993308 -359.219246)
		(end 44.882308 -359.219246)
		(stroke
			(width 0.2)
			(type default)
		)
		(fill no)
		(layer "In1.Cu")
	)
	(gr_circle
		(center 45.877734 -348.709488)
		(end 46.757844 -348.709488)
		(stroke
			(width 0.2)
			(type default)
		)
		(fill no)
		(layer "In1.Cu")
	)
	(gr_circle
		(center 46.494954 -348.709488)
		(end 47.375064 -348.709488)
		(stroke
			(width 0.2)
			(type default)
		)
		(fill no)
		(layer "In1.Cu")
	)
	(gr_circle
		(center 47.112174 -348.709488)
		(end 47.992284 -348.709488)
		(stroke
			(width 0.2)
			(type default)
		)
		(fill no)
		(layer "In1.Cu")
	)
	(gr_circle
		(center 47.366174 -348.017338)
		(end 48.255174 -348.017338)
		(stroke
			(width 0.2)
			(type default)
		)
		(fill no)
		(layer "In1.Cu")
	)
	(gr_circle
		(center 47.366174 -347.280738)
		(end 48.255174 -347.280738)
		(stroke
			(width 0.2)
			(type default)
		)
		(fill no)
		(layer "In1.Cu")
	)
	(gr_circle
		(center 47.81423 -350.318578)
		(end 48.70323 -350.318578)
		(stroke
			(width 0.2)
			(type default)
		)
		(fill no)
		(layer "In1.Cu")
	)
	(gr_circle
		(center 47.81423 -349.581978)
		(end 48.70323 -349.581978)
		(stroke
			(width 0.2)
			(type default)
		)
		(fill no)
		(layer "In1.Cu")
	)
	(gr_circle
		(center 47.880778 -358.108504)
		(end 48.769778 -358.108504)
		(stroke
			(width 0.2)
			(type default)
		)
		(fill no)
		(layer "In1.Cu")
	)
	(gr_circle
		(center 47.92853 -357.457502)
		(end 48.81753 -357.457502)
		(stroke
			(width 0.2)
			(type default)
		)
		(fill no)
		(layer "In1.Cu")
	)
	(gr_circle
		(center 47.92853 -356.822502)
		(end 48.81753 -356.822502)
		(stroke
			(width 0.2)
			(type default)
		)
		(fill no)
		(layer "In1.Cu")
	)
	(gr_circle
		(center 48.338994 -349.142558)
		(end 49.227994 -349.142558)
		(stroke
			(width 0.2)
			(type default)
		)
		(fill no)
		(layer "In1.Cu")
	)
	(gr_circle
		(center 48.364394 -349.904558)
		(end 49.253394 -349.904558)
		(stroke
			(width 0.2)
			(type default)
		)
		(fill no)
		(layer "In1.Cu")
	)
	(gr_circle
		(center 48.718978 -358.108504)
		(end 49.607978 -358.108504)
		(stroke
			(width 0.2)
			(type default)
		)
		(fill no)
		(layer "In1.Cu")
	)
	(gr_circle
		(center 48.76673 -357.457502)
		(end 49.65573 -357.457502)
		(stroke
			(width 0.2)
			(type default)
		)
		(fill no)
		(layer "In1.Cu")
	)
	(gr_circle
		(center 48.76673 -356.822502)
		(end 49.65573 -356.822502)
		(stroke
			(width 0.2)
			(type default)
		)
		(fill no)
		(layer "In1.Cu")
	)
	(gr_circle
		(center 48.897794 -350.260158)
		(end 49.786794 -350.260158)
		(stroke
			(width 0.2)
			(type default)
		)
		(fill no)
		(layer "In1.Cu")
	)
	(gr_circle
		(center 48.897794 -349.523558)
		(end 49.786794 -349.523558)
		(stroke
			(width 0.2)
			(type default)
		)
		(fill no)
		(layer "In1.Cu")
	)
	(gr_circle
		(center 48.897794 -348.786958)
		(end 49.786794 -348.786958)
		(stroke
			(width 0.2)
			(type default)
		)
		(fill no)
		(layer "In1.Cu")
	)
	(gr_circle
		(center 49.353978 -358.108504)
		(end 50.242978 -358.108504)
		(stroke
			(width 0.2)
			(type default)
		)
		(fill no)
		(layer "In1.Cu")
	)
	(gr_circle
		(center 49.40173 -357.457502)
		(end 50.29073 -357.457502)
		(stroke
			(width 0.2)
			(type default)
		)
		(fill no)
		(layer "In1.Cu")
	)
	(gr_circle
		(center 49.40173 -356.822502)
		(end 50.29073 -356.822502)
		(stroke
			(width 0.2)
			(type default)
		)
		(fill no)
		(layer "In1.Cu")
	)
	(gr_circle
		(center 49.988978 -358.108504)
		(end 50.877978 -358.108504)
		(stroke
			(width 0.2)
			(type default)
		)
		(fill no)
		(layer "In1.Cu")
	)
	(gr_circle
		(center 50.03673 -357.457502)
		(end 50.92573 -357.457502)
		(stroke
			(width 0.2)
			(type default)
		)
		(fill no)
		(layer "In1.Cu")
	)
	(gr_circle
		(center 50.03673 -356.822502)
		(end 50.92573 -356.822502)
		(stroke
			(width 0.2)
			(type default)
		)
		(fill no)
		(layer "In1.Cu")
	)
	(gr_circle
		(center 50.623978 -358.108504)
		(end 51.512978 -358.108504)
		(stroke
			(width 0.2)
			(type default)
		)
		(fill no)
		(layer "In1.Cu")
	)
	(gr_circle
		(center 50.67173 -357.457502)
		(end 51.56073 -357.457502)
		(stroke
			(width 0.2)
			(type default)
		)
		(fill no)
		(layer "In1.Cu")
	)
	(gr_circle
		(center 50.67173 -356.822502)
		(end 51.56073 -356.822502)
		(stroke
			(width 0.2)
			(type default)
		)
		(fill no)
		(layer "In1.Cu")
	)
	(gr_circle
		(center 54.234334 -348.709488)
		(end 55.114444 -348.709488)
		(stroke
			(width 0.2)
			(type default)
		)
		(fill no)
		(layer "In1.Cu")
	)
	(gr_circle
		(center 54.851554 -348.709488)
		(end 55.731664 -348.709488)
		(stroke
			(width 0.2)
			(type default)
		)
		(fill no)
		(layer "In1.Cu")
	)
	(gr_circle
		(center 55.468774 -348.709488)
		(end 56.348884 -348.709488)
		(stroke
			(width 0.2)
			(type default)
		)
		(fill no)
		(layer "In1.Cu")
	)
	(gr_circle
		(center 55.727854 -347.997018)
		(end 56.616854 -347.997018)
		(stroke
			(width 0.2)
			(type default)
		)
		(fill no)
		(layer "In1.Cu")
	)
	(gr_circle
		(center 55.727854 -347.260418)
		(end 56.616854 -347.260418)
		(stroke
			(width 0.2)
			(type default)
		)
		(fill no)
		(layer "In1.Cu")
	)
	(gr_circle
		(center 56.17083 -350.318578)
		(end 57.05983 -350.318578)
		(stroke
			(width 0.2)
			(type default)
		)
		(fill no)
		(layer "In1.Cu")
	)
	(gr_circle
		(center 56.17083 -349.581978)
		(end 57.05983 -349.581978)
		(stroke
			(width 0.2)
			(type default)
		)
		(fill no)
		(layer "In1.Cu")
	)
	(gr_circle
		(center 56.695594 -349.142558)
		(end 57.584594 -349.142558)
		(stroke
			(width 0.2)
			(type default)
		)
		(fill no)
		(layer "In1.Cu")
	)
	(gr_circle
		(center 56.720994 -349.904558)
		(end 57.609994 -349.904558)
		(stroke
			(width 0.2)
			(type default)
		)
		(fill no)
		(layer "In1.Cu")
	)
	(gr_circle
		(center 57.254394 -350.260158)
		(end 58.143394 -350.260158)
		(stroke
			(width 0.2)
			(type default)
		)
		(fill no)
		(layer "In1.Cu")
	)
	(gr_circle
		(center 57.254394 -349.523558)
		(end 58.143394 -349.523558)
		(stroke
			(width 0.2)
			(type default)
		)
		(fill no)
		(layer "In1.Cu")
	)
	(gr_circle
		(center 57.254394 -348.786958)
		(end 58.143394 -348.786958)
		(stroke
			(width 0.2)
			(type default)
		)
		(fill no)
		(layer "In1.Cu")
	)
	(gr_circle
		(center 61.93663 -166.86276)
		(end 62.82563 -166.86276)
		(stroke
			(width 0.2)
			(type default)
		)
		(fill no)
		(layer "In1.Cu")
	)
	(gr_circle
		(center 61.93663 -166.12616)
		(end 62.82563 -166.12616)
		(stroke
			(width 0.2)
			(type default)
		)
		(fill no)
		(layer "In1.Cu")
	)
	(gr_circle
		(center 61.93663 -165.38956)
		(end 62.82563 -165.38956)
		(stroke
			(width 0.2)
			(type default)
		)
		(fill no)
		(layer "In1.Cu")
	)
	(gr_circle
		(center 62.47003 -165.74516)
		(end 63.35903 -165.74516)
		(stroke
			(width 0.2)
			(type default)
		)
		(fill no)
		(layer "In1.Cu")
	)
	(gr_circle
		(center 62.49543 -166.50716)
		(end 63.38443 -166.50716)
		(stroke
			(width 0.2)
			(type default)
		)
		(fill no)
		(layer "In1.Cu")
	)
	(gr_circle
		(center 62.565534 -348.709488)
		(end 63.445644 -348.709488)
		(stroke
			(width 0.2)
			(type default)
		)
		(fill no)
		(layer "In1.Cu")
	)
	(gr_circle
		(center 63.020194 -166.06774)
		(end 63.909194 -166.06774)
		(stroke
			(width 0.2)
			(type default)
		)
		(fill no)
		(layer "In1.Cu")
	)
	(gr_circle
		(center 63.020194 -165.33114)
		(end 63.909194 -165.33114)
		(stroke
			(width 0.2)
			(type default)
		)
		(fill no)
		(layer "In1.Cu")
	)
	(gr_circle
		(center 63.182754 -348.709488)
		(end 64.062864 -348.709488)
		(stroke
			(width 0.2)
			(type default)
		)
		(fill no)
		(layer "In1.Cu")
	)
	(gr_circle
		(center 63.199264 -12.43711)
		(end 64.088264 -12.43711)
		(stroke
			(width 0.2)
			(type default)
		)
		(fill no)
		(layer "In1.Cu")
	)
	(gr_circle
		(center 63.579248 -168.42232)
		(end 64.468248 -168.42232)
		(stroke
			(width 0.2)
			(type default)
		)
		(fill no)
		(layer "In1.Cu")
	)
	(gr_circle
		(center 63.579248 -167.68572)
		(end 64.468248 -167.68572)
		(stroke
			(width 0.2)
			(type default)
		)
		(fill no)
		(layer "In1.Cu")
	)
	(gr_circle
		(center 63.631064 -13.09751)
		(end 64.520064 -13.09751)
		(stroke
			(width 0.2)
			(type default)
		)
		(fill no)
		(layer "In1.Cu")
	)
	(gr_circle
		(center 63.72225 -166.94023)
		(end 64.60236 -166.94023)
		(stroke
			(width 0.2)
			(type default)
		)
		(fill no)
		(layer "In1.Cu")
	)
	(gr_circle
		(center 63.799974 -348.709488)
		(end 64.680084 -348.709488)
		(stroke
			(width 0.2)
			(type default)
		)
		(fill no)
		(layer "In1.Cu")
	)
	(gr_circle
		(center 64.061594 -348.038928)
		(end 64.941704 -348.038928)
		(stroke
			(width 0.2)
			(type default)
		)
		(fill no)
		(layer "In1.Cu")
	)
	(gr_circle
		(center 64.061594 -347.302328)
		(end 64.941704 -347.302328)
		(stroke
			(width 0.2)
			(type default)
		)
		(fill no)
		(layer "In1.Cu")
	)
	(gr_circle
		(center 64.088264 -12.43711)
		(end 64.977264 -12.43711)
		(stroke
			(width 0.2)
			(type default)
		)
		(fill no)
		(layer "In1.Cu")
	)
	(gr_circle
		(center 64.33947 -166.94023)
		(end 65.21958 -166.94023)
		(stroke
			(width 0.2)
			(type default)
		)
		(fill no)
		(layer "In1.Cu")
	)
	(gr_circle
		(center 64.50203 -350.318578)
		(end 65.39103 -350.318578)
		(stroke
			(width 0.2)
			(type default)
		)
		(fill no)
		(layer "In1.Cu")
	)
	(gr_circle
		(center 64.50203 -349.581978)
		(end 65.39103 -349.581978)
		(stroke
			(width 0.2)
			(type default)
		)
		(fill no)
		(layer "In1.Cu")
	)
	(gr_circle
		(center 64.520064 -13.09751)
		(end 65.409064 -13.09751)
		(stroke
			(width 0.2)
			(type default)
		)
		(fill no)
		(layer "In1.Cu")
	)
	(gr_circle
		(center 64.95669 -166.94023)
		(end 65.8368 -166.94023)
		(stroke
			(width 0.2)
			(type default)
		)
		(fill no)
		(layer "In1.Cu")
	)
	(gr_circle
		(center 64.977264 -12.43711)
		(end 65.866264 -12.43711)
		(stroke
			(width 0.2)
			(type default)
		)
		(fill no)
		(layer "In1.Cu")
	)
	(gr_circle
		(center 65.026794 -349.142558)
		(end 65.915794 -349.142558)
		(stroke
			(width 0.2)
			(type default)
		)
		(fill no)
		(layer "In1.Cu")
	)
	(gr_circle
		(center 65.052194 -349.904558)
		(end 65.941194 -349.904558)
		(stroke
			(width 0.2)
			(type default)
		)
		(fill no)
		(layer "In1.Cu")
	)
	(gr_circle
		(center 65.409064 -13.09751)
		(end 66.298064 -13.09751)
		(stroke
			(width 0.2)
			(type default)
		)
		(fill no)
		(layer "In1.Cu")
	)
	(gr_circle
		(center 65.585594 -350.260158)
		(end 66.474594 -350.260158)
		(stroke
			(width 0.2)
			(type default)
		)
		(fill no)
		(layer "In1.Cu")
	)
	(gr_circle
		(center 65.585594 -349.523558)
		(end 66.474594 -349.523558)
		(stroke
			(width 0.2)
			(type default)
		)
		(fill no)
		(layer "In1.Cu")
	)
	(gr_circle
		(center 65.585594 -348.786958)
		(end 66.474594 -348.786958)
		(stroke
			(width 0.2)
			(type default)
		)
		(fill no)
		(layer "In1.Cu")
	)
	(gr_circle
		(center 65.866264 -12.43711)
		(end 66.755264 -12.43711)
		(stroke
			(width 0.2)
			(type default)
		)
		(fill no)
		(layer "In1.Cu")
	)
	(gr_circle
		(center 66.298064 -13.09751)
		(end 67.187064 -13.09751)
		(stroke
			(width 0.2)
			(type default)
		)
		(fill no)
		(layer "In1.Cu")
	)
	(gr_circle
		(center 66.399664 -25.56891)
		(end 67.288664 -25.56891)
		(stroke
			(width 0.2)
			(type default)
		)
		(fill no)
		(layer "In1.Cu")
	)
	(gr_circle
		(center 66.501264 -12.43711)
		(end 67.390264 -12.43711)
		(stroke
			(width 0.2)
			(type default)
		)
		(fill no)
		(layer "In1.Cu")
	)
	(gr_circle
		(center 66.774822 -20.327366)
		(end 67.663822 -20.327366)
		(stroke
			(width 0.2)
			(type default)
		)
		(fill no)
		(layer "In1.Cu")
	)
	(gr_circle
		(center 66.774822 -19.692366)
		(end 67.663822 -19.692366)
		(stroke
			(width 0.2)
			(type default)
		)
		(fill no)
		(layer "In1.Cu")
	)
	(gr_circle
		(center 66.780664 -24.88311)
		(end 67.669664 -24.88311)
		(stroke
			(width 0.2)
			(type default)
		)
		(fill no)
		(layer "In1.Cu")
	)
	(gr_circle
		(center 66.848228 -18.642584)
		(end 67.737228 -18.642584)
		(stroke
			(width 0.2)
			(type default)
		)
		(fill no)
		(layer "In1.Cu")
	)
	(gr_circle
		(center 66.882264 -22.26691)
		(end 67.771264 -22.26691)
		(stroke
			(width 0.2)
			(type default)
		)
		(fill no)
		(layer "In1.Cu")
	)
	(gr_circle
		(center 66.933064 -13.09751)
		(end 67.822064 -13.09751)
		(stroke
			(width 0.2)
			(type default)
		)
		(fill no)
		(layer "In1.Cu")
	)
	(gr_circle
		(center 67.288664 -25.56891)
		(end 68.177664 -25.56891)
		(stroke
			(width 0.2)
			(type default)
		)
		(fill no)
		(layer "In1.Cu")
	)
	(gr_circle
		(center 67.40271 -12.489434)
		(end 68.29171 -12.489434)
		(stroke
			(width 0.2)
			(type default)
		)
		(fill no)
		(layer "In1.Cu")
	)
	(gr_circle
		(center 67.669664 -24.88311)
		(end 68.558664 -24.88311)
		(stroke
			(width 0.2)
			(type default)
		)
		(fill no)
		(layer "In1.Cu")
	)
	(gr_circle
		(center 68.177664 -25.56891)
		(end 69.066664 -25.56891)
		(stroke
			(width 0.2)
			(type default)
		)
		(fill no)
		(layer "In1.Cu")
	)
	(gr_circle
		(center 68.54444 -18.476214)
		(end 69.43344 -18.476214)
		(stroke
			(width 0.2)
			(type default)
		)
		(fill no)
		(layer "In1.Cu")
	)
	(gr_circle
		(center 68.558664 -24.88311)
		(end 69.447664 -24.88311)
		(stroke
			(width 0.2)
			(type default)
		)
		(fill no)
		(layer "In1.Cu")
	)
	(gr_circle
		(center 69.498464 -24.55291)
		(end 70.387464 -24.55291)
		(stroke
			(width 0.2)
			(type default)
		)
		(fill no)
		(layer "In1.Cu")
	)
	(gr_circle
		(center 70.25005 -175.559974)
		(end 71.13905 -175.559974)
		(stroke
			(width 0.2)
			(type default)
		)
		(fill no)
		(layer "In1.Cu")
	)
	(gr_circle
		(center 70.25005 -174.823374)
		(end 71.13905 -174.823374)
		(stroke
			(width 0.2)
			(type default)
		)
		(fill no)
		(layer "In1.Cu")
	)
	(gr_circle
		(center 70.25005 -174.086774)
		(end 71.13905 -174.086774)
		(stroke
			(width 0.2)
			(type default)
		)
		(fill no)
		(layer "In1.Cu")
	)
	(gr_circle
		(center 70.78345 -174.442374)
		(end 71.67245 -174.442374)
		(stroke
			(width 0.2)
			(type default)
		)
		(fill no)
		(layer "In1.Cu")
	)
	(gr_circle
		(center 70.80885 -175.204374)
		(end 71.69785 -175.204374)
		(stroke
			(width 0.2)
			(type default)
		)
		(fill no)
		(layer "In1.Cu")
	)
	(gr_circle
		(center 71.099934 -336.988404)
		(end 71.980044 -336.988404)
		(stroke
			(width 0.2)
			(type default)
		)
		(fill no)
		(layer "In1.Cu")
	)
	(gr_circle
		(center 71.333614 -174.764954)
		(end 72.222614 -174.764954)
		(stroke
			(width 0.2)
			(type default)
		)
		(fill no)
		(layer "In1.Cu")
	)
	(gr_circle
		(center 71.333614 -174.028354)
		(end 72.222614 -174.028354)
		(stroke
			(width 0.2)
			(type default)
		)
		(fill no)
		(layer "In1.Cu")
	)
	(gr_circle
		(center 71.717154 -336.988404)
		(end 72.597264 -336.988404)
		(stroke
			(width 0.2)
			(type default)
		)
		(fill no)
		(layer "In1.Cu")
	)
	(gr_circle
		(center 71.892668 -177.10912)
		(end 72.781668 -177.10912)
		(stroke
			(width 0.2)
			(type default)
		)
		(fill no)
		(layer "In1.Cu")
	)
	(gr_circle
		(center 71.892668 -176.37252)
		(end 72.781668 -176.37252)
		(stroke
			(width 0.2)
			(type default)
		)
		(fill no)
		(layer "In1.Cu")
	)
	(gr_circle
		(center 72.03567 -175.639222)
		(end 72.91578 -175.639222)
		(stroke
			(width 0.2)
			(type default)
		)
		(fill no)
		(layer "In1.Cu")
	)
	(gr_circle
		(center 72.334374 -336.988404)
		(end 73.214484 -336.988404)
		(stroke
			(width 0.2)
			(type default)
		)
		(fill no)
		(layer "In1.Cu")
	)
	(gr_circle
		(center 72.616314 -336.255868)
		(end 73.496424 -336.255868)
		(stroke
			(width 0.2)
			(type default)
		)
		(fill no)
		(layer "In1.Cu")
	)
	(gr_circle
		(center 72.616314 -335.519268)
		(end 73.496424 -335.519268)
		(stroke
			(width 0.2)
			(type default)
		)
		(fill no)
		(layer "In1.Cu")
	)
	(gr_circle
		(center 72.65289 -175.639222)
		(end 73.533 -175.639222)
		(stroke
			(width 0.2)
			(type default)
		)
		(fill no)
		(layer "In1.Cu")
	)
	(gr_circle
		(center 73.03643 -338.597494)
		(end 73.92543 -338.597494)
		(stroke
			(width 0.2)
			(type default)
		)
		(fill no)
		(layer "In1.Cu")
	)
	(gr_circle
		(center 73.03643 -337.860894)
		(end 73.92543 -337.860894)
		(stroke
			(width 0.2)
			(type default)
		)
		(fill no)
		(layer "In1.Cu")
	)
	(gr_circle
		(center 73.27011 -175.639222)
		(end 74.15022 -175.639222)
		(stroke
			(width 0.2)
			(type default)
		)
		(fill no)
		(layer "In1.Cu")
	)
	(gr_circle
		(center 73.561194 -337.421474)
		(end 74.450194 -337.421474)
		(stroke
			(width 0.2)
			(type default)
		)
		(fill no)
		(layer "In1.Cu")
	)
	(gr_circle
		(center 73.586594 -338.183474)
		(end 74.475594 -338.183474)
		(stroke
			(width 0.2)
			(type default)
		)
		(fill no)
		(layer "In1.Cu")
	)
	(gr_circle
		(center 74.119994 -338.539074)
		(end 75.008994 -338.539074)
		(stroke
			(width 0.2)
			(type default)
		)
		(fill no)
		(layer "In1.Cu")
	)
	(gr_circle
		(center 74.119994 -337.802474)
		(end 75.008994 -337.802474)
		(stroke
			(width 0.2)
			(type default)
		)
		(fill no)
		(layer "In1.Cu")
	)
	(gr_circle
		(center 74.119994 -337.065874)
		(end 75.008994 -337.065874)
		(stroke
			(width 0.2)
			(type default)
		)
		(fill no)
		(layer "In1.Cu")
	)
	(gr_circle
		(center 74.811382 -351.637854)
		(end 75.700382 -351.637854)
		(stroke
			(width 0.2)
			(type default)
		)
		(fill no)
		(layer "In1.Cu")
	)
	(gr_circle
		(center 74.849482 -353.131374)
		(end 75.738482 -353.131374)
		(stroke
			(width 0.2)
			(type default)
		)
		(fill no)
		(layer "In1.Cu")
	)
	(gr_circle
		(center 74.849736 -352.30816)
		(end 75.738736 -352.30816)
		(stroke
			(width 0.2)
			(type default)
		)
		(fill no)
		(layer "In1.Cu")
	)
	(gr_circle
		(center 74.86015 -350.929448)
		(end 75.74915 -350.929448)
		(stroke
			(width 0.2)
			(type default)
		)
		(fill no)
		(layer "In1.Cu")
	)
	(gr_circle
		(center 77.178408 -16.520668)
		(end 78.067408 -16.520668)
		(stroke
			(width 0.2)
			(type default)
		)
		(fill no)
		(layer "In1.Cu")
	)
	(gr_circle
		(center 77.473048 -351.5995)
		(end 78.362048 -351.5995)
		(stroke
			(width 0.2)
			(type default)
		)
		(fill no)
		(layer "In1.Cu")
	)
	(gr_circle
		(center 77.511402 -352.978212)
		(end 78.400402 -352.978212)
		(stroke
			(width 0.2)
			(type default)
		)
		(fill no)
		(layer "In1.Cu")
	)
	(gr_circle
		(center 77.511402 -352.269806)
		(end 78.400402 -352.269806)
		(stroke
			(width 0.2)
			(type default)
		)
		(fill no)
		(layer "In1.Cu")
	)
	(gr_circle
		(center 77.521816 -350.891094)
		(end 78.410816 -350.891094)
		(stroke
			(width 0.2)
			(type default)
		)
		(fill no)
		(layer "In1.Cu")
	)
	(gr_circle
		(center 77.84338 -16.55064)
		(end 78.73238 -16.55064)
		(stroke
			(width 0.2)
			(type default)
		)
		(fill no)
		(layer "In1.Cu")
	)
	(gr_circle
		(center 78.85303 -178.798474)
		(end 79.74203 -178.798474)
		(stroke
			(width 0.2)
			(type default)
		)
		(fill no)
		(layer "In1.Cu")
	)
	(gr_circle
		(center 78.85303 -178.036474)
		(end 79.74203 -178.036474)
		(stroke
			(width 0.2)
			(type default)
		)
		(fill no)
		(layer "In1.Cu")
	)
	(gr_circle
		(center 79.10703 -179.560474)
		(end 79.99603 -179.560474)
		(stroke
			(width 0.2)
			(type default)
		)
		(fill no)
		(layer "In1.Cu")
	)
	(gr_circle
		(center 79.13243 -180.322474)
		(end 80.02143 -180.322474)
		(stroke
			(width 0.2)
			(type default)
		)
		(fill no)
		(layer "In1.Cu")
	)
	(gr_circle
		(center 79.403194 -178.384454)
		(end 80.292194 -178.384454)
		(stroke
			(width 0.2)
			(type default)
		)
		(fill no)
		(layer "In1.Cu")
	)
	(gr_circle
		(center 79.455518 -336.981292)
		(end 80.335628 -336.981292)
		(stroke
			(width 0.2)
			(type default)
		)
		(fill no)
		(layer "In1.Cu")
	)
	(gr_circle
		(center 79.657194 -179.883054)
		(end 80.546194 -179.883054)
		(stroke
			(width 0.2)
			(type default)
		)
		(fill no)
		(layer "In1.Cu")
	)
	(gr_circle
		(center 79.657194 -179.146454)
		(end 80.546194 -179.146454)
		(stroke
			(width 0.2)
			(type default)
		)
		(fill no)
		(layer "In1.Cu")
	)
	(gr_circle
		(center 79.921862 -18.238724)
		(end 80.810862 -18.238724)
		(stroke
			(width 0.2)
			(type default)
		)
		(fill no)
		(layer "In1.Cu")
	)
	(gr_circle
		(center 79.921862 -17.502124)
		(end 80.810862 -17.502124)
		(stroke
			(width 0.2)
			(type default)
		)
		(fill no)
		(layer "In1.Cu")
	)
	(gr_circle
		(center 80.072738 -336.981292)
		(end 80.952848 -336.981292)
		(stroke
			(width 0.2)
			(type default)
		)
		(fill no)
		(layer "In1.Cu")
	)
	(gr_circle
		(center 80.241648 -182.2196)
		(end 81.130648 -182.2196)
		(stroke
			(width 0.2)
			(type default)
		)
		(fill no)
		(layer "In1.Cu")
	)
	(gr_circle
		(center 80.241648 -181.483)
		(end 81.130648 -181.483)
		(stroke
			(width 0.2)
			(type default)
		)
		(fill no)
		(layer "In1.Cu")
	)
	(gr_circle
		(center 80.35925 -180.755544)
		(end 81.23936 -180.755544)
		(stroke
			(width 0.2)
			(type default)
		)
		(fill no)
		(layer "In1.Cu")
	)
	(gr_circle
		(center 80.689958 -336.981292)
		(end 81.570068 -336.981292)
		(stroke
			(width 0.2)
			(type default)
		)
		(fill no)
		(layer "In1.Cu")
	)
	(gr_circle
		(center 80.97647 -180.755544)
		(end 81.85658 -180.755544)
		(stroke
			(width 0.2)
			(type default)
		)
		(fill no)
		(layer "In1.Cu")
	)
	(gr_circle
		(center 80.977994 -336.245708)
		(end 81.858104 -336.245708)
		(stroke
			(width 0.2)
			(type default)
		)
		(fill no)
		(layer "In1.Cu")
	)
	(gr_circle
		(center 80.977994 -335.509108)
		(end 81.858104 -335.509108)
		(stroke
			(width 0.2)
			(type default)
		)
		(fill no)
		(layer "In1.Cu")
	)
	(gr_circle
		(center 81.392014 -338.590382)
		(end 82.281014 -338.590382)
		(stroke
			(width 0.2)
			(type default)
		)
		(fill no)
		(layer "In1.Cu")
	)
	(gr_circle
		(center 81.392014 -337.853782)
		(end 82.281014 -337.853782)
		(stroke
			(width 0.2)
			(type default)
		)
		(fill no)
		(layer "In1.Cu")
	)
	(gr_circle
		(center 81.59369 -180.755544)
		(end 82.4738 -180.755544)
		(stroke
			(width 0.2)
			(type default)
		)
		(fill no)
		(layer "In1.Cu")
	)
	(gr_arc
		(start 81.701894 -9.780016)
		(mid 82.287679 -11.194227)
		(end 83.70189 -11.780012)
		(stroke
			(width 1.016)
			(type default)
		)
		(layer "In1.Cu")
	)
	(gr_arc
		(start 81.701894 -0.500126)
		(mid 81.555625 -0.146451)
		(end 81.202022 0)
		(stroke
			(width 1.016)
			(type default)
		)
		(layer "In1.Cu")
	)
	(gr_line
		(start 81.701894 -0.500126)
		(end 81.701894 -9.780016)
		(stroke
			(width 1.016)
			(type default)
		)
		(layer "In1.Cu")
	)
	(gr_circle
		(center 81.916778 -337.414362)
		(end 82.805778 -337.414362)
		(stroke
			(width 0.2)
			(type default)
		)
		(fill no)
		(layer "In1.Cu")
	)
	(gr_circle
		(center 81.942178 -338.176362)
		(end 82.831178 -338.176362)
		(stroke
			(width 0.2)
			(type default)
		)
		(fill no)
		(layer "In1.Cu")
	)
	(gr_circle
		(center 82.183986 -348.89948)
		(end 83.072986 -348.89948)
		(stroke
			(width 0.2)
			(type default)
		)
		(fill no)
		(layer "In1.Cu")
	)
	(gr_circle
		(center 82.222086 -350.393)
		(end 83.111086 -350.393)
		(stroke
			(width 0.2)
			(type default)
		)
		(fill no)
		(layer "In1.Cu")
	)
	(gr_circle
		(center 82.22234 -349.569786)
		(end 83.11134 -349.569786)
		(stroke
			(width 0.2)
			(type default)
		)
		(fill no)
		(layer "In1.Cu")
	)
	(gr_circle
		(center 82.232754 -348.191074)
		(end 83.121754 -348.191074)
		(stroke
			(width 0.2)
			(type default)
		)
		(fill no)
		(layer "In1.Cu")
	)
	(gr_circle
		(center 82.475578 -338.531962)
		(end 83.364578 -338.531962)
		(stroke
			(width 0.2)
			(type default)
		)
		(fill no)
		(layer "In1.Cu")
	)
	(gr_circle
		(center 82.475578 -337.795362)
		(end 83.364578 -337.795362)
		(stroke
			(width 0.2)
			(type default)
		)
		(fill no)
		(layer "In1.Cu")
	)
	(gr_circle
		(center 82.475578 -337.058762)
		(end 83.364578 -337.058762)
		(stroke
			(width 0.2)
			(type default)
		)
		(fill no)
		(layer "In1.Cu")
	)
	(gr_circle
		(center 82.989674 -165.962076)
		(end 84.386674 -165.962076)
		(stroke
			(width 0.2)
			(type default)
		)
		(fill no)
		(layer "In1.Cu")
	)
	(gr_line
		(start 83.70189 -11.780012)
		(end 124.102114 -11.780012)
		(stroke
			(width 1.016)
			(type default)
		)
		(layer "In1.Cu")
	)
	(gr_circle
		(center 84.845652 -348.861126)
		(end 85.734652 -348.861126)
		(stroke
			(width 0.2)
			(type default)
		)
		(fill no)
		(layer "In1.Cu")
	)
	(gr_circle
		(center 84.884006 -350.239838)
		(end 85.773006 -350.239838)
		(stroke
			(width 0.2)
			(type default)
		)
		(fill no)
		(layer "In1.Cu")
	)
	(gr_circle
		(center 84.884006 -349.531432)
		(end 85.773006 -349.531432)
		(stroke
			(width 0.2)
			(type default)
		)
		(fill no)
		(layer "In1.Cu")
	)
	(gr_circle
		(center 84.89442 -348.15272)
		(end 85.78342 -348.15272)
		(stroke
			(width 0.2)
			(type default)
		)
		(fill no)
		(layer "In1.Cu")
	)
	(gr_circle
		(center 86.97087 -180.610002)
		(end 87.85987 -180.610002)
		(stroke
			(width 0.2)
			(type default)
		)
		(fill no)
		(layer "In1.Cu")
	)
	(gr_circle
		(center 86.97087 -179.873402)
		(end 87.85987 -179.873402)
		(stroke
			(width 0.2)
			(type default)
		)
		(fill no)
		(layer "In1.Cu")
	)
	(gr_circle
		(center 86.97087 -179.136802)
		(end 87.85987 -179.136802)
		(stroke
			(width 0.2)
			(type default)
		)
		(fill no)
		(layer "In1.Cu")
	)
	(gr_circle
		(center 87.01913 -164.097716)
		(end 87.90813 -164.097716)
		(stroke
			(width 0.2)
			(type default)
		)
		(fill no)
		(layer "In1.Cu")
	)
	(gr_circle
		(center 87.03945 -163.447476)
		(end 87.92845 -163.447476)
		(stroke
			(width 0.2)
			(type default)
		)
		(fill no)
		(layer "In1.Cu")
	)
	(gr_circle
		(center 87.03945 -162.812476)
		(end 87.92845 -162.812476)
		(stroke
			(width 0.2)
			(type default)
		)
		(fill no)
		(layer "In1.Cu")
	)
	(gr_circle
		(center 87.50427 -179.492402)
		(end 88.39327 -179.492402)
		(stroke
			(width 0.2)
			(type default)
		)
		(fill no)
		(layer "In1.Cu")
	)
	(gr_circle
		(center 87.52967 -180.254402)
		(end 88.41867 -180.254402)
		(stroke
			(width 0.2)
			(type default)
		)
		(fill no)
		(layer "In1.Cu")
	)
	(gr_circle
		(center 87.65413 -164.097716)
		(end 88.54313 -164.097716)
		(stroke
			(width 0.2)
			(type default)
		)
		(fill no)
		(layer "In1.Cu")
	)
	(gr_circle
		(center 87.67445 -163.447476)
		(end 88.56345 -163.447476)
		(stroke
			(width 0.2)
			(type default)
		)
		(fill no)
		(layer "In1.Cu")
	)
	(gr_circle
		(center 87.67445 -162.812476)
		(end 88.56345 -162.812476)
		(stroke
			(width 0.2)
			(type default)
		)
		(fill no)
		(layer "In1.Cu")
	)
	(gr_circle
		(center 87.813134 -336.966814)
		(end 88.693244 -336.966814)
		(stroke
			(width 0.2)
			(type default)
		)
		(fill no)
		(layer "In1.Cu")
	)
	(gr_circle
		(center 88.054434 -179.814982)
		(end 88.943434 -179.814982)
		(stroke
			(width 0.2)
			(type default)
		)
		(fill no)
		(layer "In1.Cu")
	)
	(gr_circle
		(center 88.054434 -179.078382)
		(end 88.943434 -179.078382)
		(stroke
			(width 0.2)
			(type default)
		)
		(fill no)
		(layer "In1.Cu")
	)
	(gr_circle
		(center 88.28913 -164.097716)
		(end 89.17813 -164.097716)
		(stroke
			(width 0.2)
			(type default)
		)
		(fill no)
		(layer "In1.Cu")
	)
	(gr_circle
		(center 88.30945 -163.447476)
		(end 89.19845 -163.447476)
		(stroke
			(width 0.2)
			(type default)
		)
		(fill no)
		(layer "In1.Cu")
	)
	(gr_circle
		(center 88.30945 -162.812476)
		(end 89.19845 -162.812476)
		(stroke
			(width 0.2)
			(type default)
		)
		(fill no)
		(layer "In1.Cu")
	)
	(gr_circle
		(center 88.430354 -336.966814)
		(end 89.310464 -336.966814)
		(stroke
			(width 0.2)
			(type default)
		)
		(fill no)
		(layer "In1.Cu")
	)
	(gr_circle
		(center 88.49233 -182.13324)
		(end 89.38133 -182.13324)
		(stroke
			(width 0.2)
			(type default)
		)
		(fill no)
		(layer "In1.Cu")
	)
	(gr_circle
		(center 88.49233 -181.39664)
		(end 89.38133 -181.39664)
		(stroke
			(width 0.2)
			(type default)
		)
		(fill no)
		(layer "In1.Cu")
	)
	(gr_circle
		(center 88.75649 -180.687472)
		(end 89.6366 -180.687472)
		(stroke
			(width 0.2)
			(type default)
		)
		(fill no)
		(layer "In1.Cu")
	)
	(gr_circle
		(center 88.92413 -164.097716)
		(end 89.81313 -164.097716)
		(stroke
			(width 0.2)
			(type default)
		)
		(fill no)
		(layer "In1.Cu")
	)
	(gr_circle
		(center 88.94445 -163.447476)
		(end 89.83345 -163.447476)
		(stroke
			(width 0.2)
			(type default)
		)
		(fill no)
		(layer "In1.Cu")
	)
	(gr_circle
		(center 88.94445 -162.812476)
		(end 89.83345 -162.812476)
		(stroke
			(width 0.2)
			(type default)
		)
		(fill no)
		(layer "In1.Cu")
	)
	(gr_circle
		(center 89.047574 -336.966814)
		(end 89.927684 -336.966814)
		(stroke
			(width 0.2)
			(type default)
		)
		(fill no)
		(layer "In1.Cu")
	)
	(gr_circle
		(center 89.314528 -345.237562)
		(end 90.203528 -345.237562)
		(stroke
			(width 0.2)
			(type default)
		)
		(fill no)
		(layer "In1.Cu")
	)
	(gr_circle
		(center 89.319354 -336.255868)
		(end 90.199464 -336.255868)
		(stroke
			(width 0.2)
			(type default)
		)
		(fill no)
		(layer "In1.Cu")
	)
	(gr_circle
		(center 89.319354 -335.519268)
		(end 90.199464 -335.519268)
		(stroke
			(width 0.2)
			(type default)
		)
		(fill no)
		(layer "In1.Cu")
	)
	(gr_circle
		(center 89.350088 -345.96959)
		(end 90.239088 -345.96959)
		(stroke
			(width 0.2)
			(type default)
		)
		(fill no)
		(layer "In1.Cu")
	)
	(gr_circle
		(center 89.37371 -180.687472)
		(end 90.25382 -180.687472)
		(stroke
			(width 0.2)
			(type default)
		)
		(fill no)
		(layer "In1.Cu")
	)
	(gr_circle
		(center 89.388442 -346.639896)
		(end 90.277442 -346.639896)
		(stroke
			(width 0.2)
			(type default)
		)
		(fill no)
		(layer "In1.Cu")
	)
	(gr_circle
		(center 89.55913 -164.097716)
		(end 90.44813 -164.097716)
		(stroke
			(width 0.2)
			(type default)
		)
		(fill no)
		(layer "In1.Cu")
	)
	(gr_circle
		(center 89.57945 -163.447476)
		(end 90.46845 -163.447476)
		(stroke
			(width 0.2)
			(type default)
		)
		(fill no)
		(layer "In1.Cu")
	)
	(gr_circle
		(center 89.57945 -162.812476)
		(end 90.46845 -162.812476)
		(stroke
			(width 0.2)
			(type default)
		)
		(fill no)
		(layer "In1.Cu")
	)
	(gr_circle
		(center 89.74963 -338.575904)
		(end 90.63863 -338.575904)
		(stroke
			(width 0.2)
			(type default)
		)
		(fill no)
		(layer "In1.Cu")
	)
	(gr_circle
		(center 89.74963 -337.839304)
		(end 90.63863 -337.839304)
		(stroke
			(width 0.2)
			(type default)
		)
		(fill no)
		(layer "In1.Cu")
	)
	(gr_circle
		(center 89.983056 -345.261184)
		(end 90.872056 -345.261184)
		(stroke
			(width 0.2)
			(type default)
		)
		(fill no)
		(layer "In1.Cu")
	)
	(gr_circle
		(center 89.985088 -345.96959)
		(end 90.874088 -345.96959)
		(stroke
			(width 0.2)
			(type default)
		)
		(fill no)
		(layer "In1.Cu")
	)
	(gr_circle
		(center 89.99093 -180.687472)
		(end 90.87104 -180.687472)
		(stroke
			(width 0.2)
			(type default)
		)
		(fill no)
		(layer "In1.Cu")
	)
	(gr_circle
		(center 90.023442 -346.639896)
		(end 90.912442 -346.639896)
		(stroke
			(width 0.2)
			(type default)
		)
		(fill no)
		(layer "In1.Cu")
	)
	(gr_circle
		(center 90.21953 -164.107876)
		(end 91.10853 -164.107876)
		(stroke
			(width 0.2)
			(type default)
		)
		(fill no)
		(layer "In1.Cu")
	)
	(gr_circle
		(center 90.23985 -163.457636)
		(end 91.12885 -163.457636)
		(stroke
			(width 0.2)
			(type default)
		)
		(fill no)
		(layer "In1.Cu")
	)
	(gr_circle
		(center 90.23985 -162.822636)
		(end 91.12885 -162.822636)
		(stroke
			(width 0.2)
			(type default)
		)
		(fill no)
		(layer "In1.Cu")
	)
	(gr_circle
		(center 90.274394 -337.399884)
		(end 91.163394 -337.399884)
		(stroke
			(width 0.2)
			(type default)
		)
		(fill no)
		(layer "In1.Cu")
	)
	(gr_circle
		(center 90.299794 -338.161884)
		(end 91.188794 -338.161884)
		(stroke
			(width 0.2)
			(type default)
		)
		(fill no)
		(layer "In1.Cu")
	)
	(gr_circle
		(center 90.618056 -345.261184)
		(end 91.507056 -345.261184)
		(stroke
			(width 0.2)
			(type default)
		)
		(fill no)
		(layer "In1.Cu")
	)
	(gr_circle
		(center 90.620088 -345.96959)
		(end 91.509088 -345.96959)
		(stroke
			(width 0.2)
			(type default)
		)
		(fill no)
		(layer "In1.Cu")
	)
	(gr_circle
		(center 90.658442 -346.639896)
		(end 91.547442 -346.639896)
		(stroke
			(width 0.2)
			(type default)
		)
		(fill no)
		(layer "In1.Cu")
	)
	(gr_circle
		(center 90.833194 -338.517484)
		(end 91.722194 -338.517484)
		(stroke
			(width 0.2)
			(type default)
		)
		(fill no)
		(layer "In1.Cu")
	)
	(gr_circle
		(center 90.833194 -337.780884)
		(end 91.722194 -337.780884)
		(stroke
			(width 0.2)
			(type default)
		)
		(fill no)
		(layer "In1.Cu")
	)
	(gr_circle
		(center 90.833194 -337.044284)
		(end 91.722194 -337.044284)
		(stroke
			(width 0.2)
			(type default)
		)
		(fill no)
		(layer "In1.Cu")
	)
	(gr_circle
		(center 91.255088 -345.96959)
		(end 92.144088 -345.96959)
		(stroke
			(width 0.2)
			(type default)
		)
		(fill no)
		(layer "In1.Cu")
	)
	(gr_circle
		(center 91.293442 -346.639896)
		(end 92.182442 -346.639896)
		(stroke
			(width 0.2)
			(type default)
		)
		(fill no)
		(layer "In1.Cu")
	)
	(gr_circle
		(center 91.380056 -345.261184)
		(end 92.269056 -345.261184)
		(stroke
			(width 0.2)
			(type default)
		)
		(fill no)
		(layer "In1.Cu")
	)
	(gr_circle
		(center 91.966288 -345.96959)
		(end 92.855288 -345.96959)
		(stroke
			(width 0.2)
			(type default)
		)
		(fill no)
		(layer "In1.Cu")
	)
	(gr_circle
		(center 92.004642 -346.639896)
		(end 92.893642 -346.639896)
		(stroke
			(width 0.2)
			(type default)
		)
		(fill no)
		(layer "In1.Cu")
	)
	(gr_circle
		(center 92.015056 -345.261184)
		(end 92.904056 -345.261184)
		(stroke
			(width 0.2)
			(type default)
		)
		(fill no)
		(layer "In1.Cu")
	)
	(gr_circle
		(center 92.387674 -165.962076)
		(end 93.784674 -165.962076)
		(stroke
			(width 0.2)
			(type default)
		)
		(fill no)
		(layer "In1.Cu")
	)
	(gr_circle
		(center 92.601288 -345.96959)
		(end 93.490288 -345.96959)
		(stroke
			(width 0.2)
			(type default)
		)
		(fill no)
		(layer "In1.Cu")
	)
	(gr_circle
		(center 92.639642 -346.639896)
		(end 93.528642 -346.639896)
		(stroke
			(width 0.2)
			(type default)
		)
		(fill no)
		(layer "In1.Cu")
	)
	(gr_circle
		(center 92.650056 -345.261184)
		(end 93.539056 -345.261184)
		(stroke
			(width 0.2)
			(type default)
		)
		(fill no)
		(layer "In1.Cu")
	)
	(gr_circle
		(center 95.36303 -180.627274)
		(end 96.25203 -180.627274)
		(stroke
			(width 0.2)
			(type default)
		)
		(fill no)
		(layer "In1.Cu")
	)
	(gr_circle
		(center 95.36303 -179.890674)
		(end 96.25203 -179.890674)
		(stroke
			(width 0.2)
			(type default)
		)
		(fill no)
		(layer "In1.Cu")
	)
	(gr_circle
		(center 95.36303 -179.154074)
		(end 96.25203 -179.154074)
		(stroke
			(width 0.2)
			(type default)
		)
		(fill no)
		(layer "In1.Cu")
	)
	(gr_circle
		(center 95.89643 -179.509674)
		(end 96.78543 -179.509674)
		(stroke
			(width 0.2)
			(type default)
		)
		(fill no)
		(layer "In1.Cu")
	)
	(gr_circle
		(center 95.92183 -180.271674)
		(end 96.81083 -180.271674)
		(stroke
			(width 0.2)
			(type default)
		)
		(fill no)
		(layer "In1.Cu")
	)
	(gr_circle
		(center 96.144334 -337.017614)
		(end 97.024444 -337.017614)
		(stroke
			(width 0.2)
			(type default)
		)
		(fill no)
		(layer "In1.Cu")
	)
	(gr_circle
		(center 96.446594 -179.832254)
		(end 97.335594 -179.832254)
		(stroke
			(width 0.2)
			(type default)
		)
		(fill no)
		(layer "In1.Cu")
	)
	(gr_circle
		(center 96.446594 -179.095654)
		(end 97.335594 -179.095654)
		(stroke
			(width 0.2)
			(type default)
		)
		(fill no)
		(layer "In1.Cu")
	)
	(gr_circle
		(center 96.761554 -337.017614)
		(end 97.641664 -337.017614)
		(stroke
			(width 0.2)
			(type default)
		)
		(fill no)
		(layer "In1.Cu")
	)
	(gr_circle
		(center 96.980248 -182.13324)
		(end 97.869248 -182.13324)
		(stroke
			(width 0.2)
			(type default)
		)
		(fill no)
		(layer "In1.Cu")
	)
	(gr_circle
		(center 96.980248 -181.39664)
		(end 97.869248 -181.39664)
		(stroke
			(width 0.2)
			(type default)
		)
		(fill no)
		(layer "In1.Cu")
	)
	(gr_circle
		(center 97.14865 -180.704744)
		(end 98.02876 -180.704744)
		(stroke
			(width 0.2)
			(type default)
		)
		(fill no)
		(layer "In1.Cu")
	)
	(gr_circle
		(center 97.378774 -337.017614)
		(end 98.258884 -337.017614)
		(stroke
			(width 0.2)
			(type default)
		)
		(fill no)
		(layer "In1.Cu")
	)
	(gr_circle
		(center 97.658174 -336.319368)
		(end 98.538284 -336.319368)
		(stroke
			(width 0.2)
			(type default)
		)
		(fill no)
		(layer "In1.Cu")
	)
	(gr_circle
		(center 97.658174 -335.582768)
		(end 98.538284 -335.582768)
		(stroke
			(width 0.2)
			(type default)
		)
		(fill no)
		(layer "In1.Cu")
	)
	(gr_circle
		(center 97.76587 -180.704744)
		(end 98.64598 -180.704744)
		(stroke
			(width 0.2)
			(type default)
		)
		(fill no)
		(layer "In1.Cu")
	)
	(gr_circle
		(center 98.08083 -338.626704)
		(end 98.96983 -338.626704)
		(stroke
			(width 0.2)
			(type default)
		)
		(fill no)
		(layer "In1.Cu")
	)
	(gr_circle
		(center 98.08083 -337.890104)
		(end 98.96983 -337.890104)
		(stroke
			(width 0.2)
			(type default)
		)
		(fill no)
		(layer "In1.Cu")
	)
	(gr_circle
		(center 98.199194 -339.358224)
		(end 99.088194 -339.358224)
		(stroke
			(width 0.2)
			(type default)
		)
		(fill no)
		(layer "In1.Cu")
	)
	(gr_circle
		(center 98.38309 -180.704744)
		(end 99.2632 -180.704744)
		(stroke
			(width 0.2)
			(type default)
		)
		(fill no)
		(layer "In1.Cu")
	)
	(gr_circle
		(center 98.605594 -337.450684)
		(end 99.494594 -337.450684)
		(stroke
			(width 0.2)
			(type default)
		)
		(fill no)
		(layer "In1.Cu")
	)
	(gr_circle
		(center 98.630994 -338.212684)
		(end 99.519994 -338.212684)
		(stroke
			(width 0.2)
			(type default)
		)
		(fill no)
		(layer "In1.Cu")
	)
	(gr_circle
		(center 98.747834 -339.736684)
		(end 99.636834 -339.736684)
		(stroke
			(width 0.2)
			(type default)
		)
		(fill no)
		(layer "In1.Cu")
	)
	(gr_circle
		(center 98.747834 -338.974684)
		(end 99.636834 -338.974684)
		(stroke
			(width 0.2)
			(type default)
		)
		(fill no)
		(layer "In1.Cu")
	)
	(gr_circle
		(center 103.74503 -176.106074)
		(end 104.63403 -176.106074)
		(stroke
			(width 0.2)
			(type default)
		)
		(fill no)
		(layer "In1.Cu")
	)
	(gr_circle
		(center 103.74503 -175.369474)
		(end 104.63403 -175.369474)
		(stroke
			(width 0.2)
			(type default)
		)
		(fill no)
		(layer "In1.Cu")
	)
	(gr_circle
		(center 103.74503 -174.632874)
		(end 104.63403 -174.632874)
		(stroke
			(width 0.2)
			(type default)
		)
		(fill no)
		(layer "In1.Cu")
	)
	(gr_circle
		(center 104.27843 -174.988474)
		(end 105.16743 -174.988474)
		(stroke
			(width 0.2)
			(type default)
		)
		(fill no)
		(layer "In1.Cu")
	)
	(gr_circle
		(center 104.30383 -175.750474)
		(end 105.19283 -175.750474)
		(stroke
			(width 0.2)
			(type default)
		)
		(fill no)
		(layer "In1.Cu")
	)
	(gr_circle
		(center 104.420162 -341.927688)
		(end 105.300272 -341.927688)
		(stroke
			(width 0.2)
			(type default)
		)
		(fill no)
		(layer "In1.Cu")
	)
	(gr_circle
		(center 104.828594 -175.311054)
		(end 105.717594 -175.311054)
		(stroke
			(width 0.2)
			(type default)
		)
		(fill no)
		(layer "In1.Cu")
	)
	(gr_circle
		(center 104.828594 -174.574454)
		(end 105.717594 -174.574454)
		(stroke
			(width 0.2)
			(type default)
		)
		(fill no)
		(layer "In1.Cu")
	)
	(gr_circle
		(center 105.037382 -341.927688)
		(end 105.917492 -341.927688)
		(stroke
			(width 0.2)
			(type default)
		)
		(fill no)
		(layer "In1.Cu")
	)
	(gr_circle
		(center 105.336848 -177.65776)
		(end 106.225848 -177.65776)
		(stroke
			(width 0.2)
			(type default)
		)
		(fill no)
		(layer "In1.Cu")
	)
	(gr_circle
		(center 105.336848 -176.92116)
		(end 106.225848 -176.92116)
		(stroke
			(width 0.2)
			(type default)
		)
		(fill no)
		(layer "In1.Cu")
	)
	(gr_circle
		(center 105.53065 -176.183544)
		(end 106.41076 -176.183544)
		(stroke
			(width 0.2)
			(type default)
		)
		(fill no)
		(layer "In1.Cu")
	)
	(gr_circle
		(center 105.654602 -341.927688)
		(end 106.534712 -341.927688)
		(stroke
			(width 0.2)
			(type default)
		)
		(fill no)
		(layer "In1.Cu")
	)
	(gr_circle
		(center 105.934002 -341.229442)
		(end 106.814112 -341.229442)
		(stroke
			(width 0.2)
			(type default)
		)
		(fill no)
		(layer "In1.Cu")
	)
	(gr_circle
		(center 105.934002 -340.492842)
		(end 106.814112 -340.492842)
		(stroke
			(width 0.2)
			(type default)
		)
		(fill no)
		(layer "In1.Cu")
	)
	(gr_circle
		(center 106.14787 -176.183544)
		(end 107.02798 -176.183544)
		(stroke
			(width 0.2)
			(type default)
		)
		(fill no)
		(layer "In1.Cu")
	)
	(gr_circle
		(center 106.34345 -343.450164)
		(end 107.23245 -343.450164)
		(stroke
			(width 0.2)
			(type default)
		)
		(fill no)
		(layer "In1.Cu")
	)
	(gr_circle
		(center 106.34345 -342.713564)
		(end 107.23245 -342.713564)
		(stroke
			(width 0.2)
			(type default)
		)
		(fill no)
		(layer "In1.Cu")
	)
	(gr_circle
		(center 106.76509 -176.183544)
		(end 107.6452 -176.183544)
		(stroke
			(width 0.2)
			(type default)
		)
		(fill no)
		(layer "In1.Cu")
	)
	(gr_circle
		(center 106.98607 -342.540844)
		(end 107.87507 -342.540844)
		(stroke
			(width 0.2)
			(type default)
		)
		(fill no)
		(layer "In1.Cu")
	)
	(gr_circle
		(center 106.98607 -341.804244)
		(end 107.87507 -341.804244)
		(stroke
			(width 0.2)
			(type default)
		)
		(fill no)
		(layer "In1.Cu")
	)
	(gr_circle
		(center 107.01401 -343.986104)
		(end 107.90301 -343.986104)
		(stroke
			(width 0.2)
			(type default)
		)
		(fill no)
		(layer "In1.Cu")
	)
	(gr_circle
		(center 107.01401 -343.249504)
		(end 107.90301 -343.249504)
		(stroke
			(width 0.2)
			(type default)
		)
		(fill no)
		(layer "In1.Cu")
	)
	(gr_circle
		(center 110.140496 -150.941786)
		(end 111.537496 -150.941786)
		(stroke
			(width 0.2)
			(type default)
		)
		(fill no)
		(layer "In1.Cu")
	)
	(gr_circle
		(center 111.97463 -169.857674)
		(end 112.86363 -169.857674)
		(stroke
			(width 0.2)
			(type default)
		)
		(fill no)
		(layer "In1.Cu")
	)
	(gr_circle
		(center 111.97463 -169.121074)
		(end 112.86363 -169.121074)
		(stroke
			(width 0.2)
			(type default)
		)
		(fill no)
		(layer "In1.Cu")
	)
	(gr_circle
		(center 111.97463 -168.384474)
		(end 112.86363 -168.384474)
		(stroke
			(width 0.2)
			(type default)
		)
		(fill no)
		(layer "In1.Cu")
	)
	(gr_circle
		(center 112.50803 -168.740074)
		(end 113.39703 -168.740074)
		(stroke
			(width 0.2)
			(type default)
		)
		(fill no)
		(layer "In1.Cu")
	)
	(gr_circle
		(center 112.53343 -169.502074)
		(end 113.42243 -169.502074)
		(stroke
			(width 0.2)
			(type default)
		)
		(fill no)
		(layer "In1.Cu")
	)
	(gr_circle
		(center 113.058194 -169.062654)
		(end 113.947194 -169.062654)
		(stroke
			(width 0.2)
			(type default)
		)
		(fill no)
		(layer "In1.Cu")
	)
	(gr_circle
		(center 113.058194 -168.326054)
		(end 113.947194 -168.326054)
		(stroke
			(width 0.2)
			(type default)
		)
		(fill no)
		(layer "In1.Cu")
	)
	(gr_circle
		(center 113.591848 -171.33316)
		(end 114.480848 -171.33316)
		(stroke
			(width 0.2)
			(type default)
		)
		(fill no)
		(layer "In1.Cu")
	)
	(gr_circle
		(center 113.591848 -170.59656)
		(end 114.480848 -170.59656)
		(stroke
			(width 0.2)
			(type default)
		)
		(fill no)
		(layer "In1.Cu")
	)
	(gr_circle
		(center 113.76025 -169.935144)
		(end 114.64036 -169.935144)
		(stroke
			(width 0.2)
			(type default)
		)
		(fill no)
		(layer "In1.Cu")
	)
	(gr_circle
		(center 114.37747 -169.935144)
		(end 115.25758 -169.935144)
		(stroke
			(width 0.2)
			(type default)
		)
		(fill no)
		(layer "In1.Cu")
	)
	(gr_circle
		(center 114.99469 -169.935144)
		(end 115.8748 -169.935144)
		(stroke
			(width 0.2)
			(type default)
		)
		(fill no)
		(layer "In1.Cu")
	)
	(gr_circle
		(center 116.258594 -152.657556)
		(end 117.147594 -152.657556)
		(stroke
			(width 0.2)
			(type default)
		)
		(fill no)
		(layer "In1.Cu")
	)
	(gr_circle
		(center 116.258594 -152.022556)
		(end 117.147594 -152.022556)
		(stroke
			(width 0.2)
			(type default)
		)
		(fill no)
		(layer "In1.Cu")
	)
	(gr_circle
		(center 116.893594 -152.657556)
		(end 117.782594 -152.657556)
		(stroke
			(width 0.2)
			(type default)
		)
		(fill no)
		(layer "In1.Cu")
	)
	(gr_circle
		(center 116.893594 -152.022556)
		(end 117.782594 -152.022556)
		(stroke
			(width 0.2)
			(type default)
		)
		(fill no)
		(layer "In1.Cu")
	)
	(gr_circle
		(center 117.559074 -152.657556)
		(end 118.448074 -152.657556)
		(stroke
			(width 0.2)
			(type default)
		)
		(fill no)
		(layer "In1.Cu")
	)
	(gr_circle
		(center 117.559074 -152.022556)
		(end 118.448074 -152.022556)
		(stroke
			(width 0.2)
			(type default)
		)
		(fill no)
		(layer "In1.Cu")
	)
	(gr_circle
		(center 118.194074 -152.657556)
		(end 119.083074 -152.657556)
		(stroke
			(width 0.2)
			(type default)
		)
		(fill no)
		(layer "In1.Cu")
	)
	(gr_circle
		(center 118.194074 -152.022556)
		(end 119.083074 -152.022556)
		(stroke
			(width 0.2)
			(type default)
		)
		(fill no)
		(layer "In1.Cu")
	)
	(gr_circle
		(center 118.829074 -152.657556)
		(end 119.718074 -152.657556)
		(stroke
			(width 0.2)
			(type default)
		)
		(fill no)
		(layer "In1.Cu")
	)
	(gr_circle
		(center 118.829074 -152.022556)
		(end 119.718074 -152.022556)
		(stroke
			(width 0.2)
			(type default)
		)
		(fill no)
		(layer "In1.Cu")
	)
	(gr_circle
		(center 119.464074 -152.657556)
		(end 120.353074 -152.657556)
		(stroke
			(width 0.2)
			(type default)
		)
		(fill no)
		(layer "In1.Cu")
	)
	(gr_circle
		(center 119.464074 -152.022556)
		(end 120.353074 -152.022556)
		(stroke
			(width 0.2)
			(type default)
		)
		(fill no)
		(layer "In1.Cu")
	)
	(gr_circle
		(center 120.25503 -163.126674)
		(end 121.14403 -163.126674)
		(stroke
			(width 0.2)
			(type default)
		)
		(fill no)
		(layer "In1.Cu")
	)
	(gr_circle
		(center 120.25503 -162.390074)
		(end 121.14403 -162.390074)
		(stroke
			(width 0.2)
			(type default)
		)
		(fill no)
		(layer "In1.Cu")
	)
	(gr_circle
		(center 120.25503 -161.653474)
		(end 121.14403 -161.653474)
		(stroke
			(width 0.2)
			(type default)
		)
		(fill no)
		(layer "In1.Cu")
	)
	(gr_circle
		(center 120.78843 -162.009074)
		(end 121.67743 -162.009074)
		(stroke
			(width 0.2)
			(type default)
		)
		(fill no)
		(layer "In1.Cu")
	)
	(gr_circle
		(center 120.81383 -162.771074)
		(end 121.70283 -162.771074)
		(stroke
			(width 0.2)
			(type default)
		)
		(fill no)
		(layer "In1.Cu")
	)
	(gr_circle
		(center 121.338594 -162.331654)
		(end 122.227594 -162.331654)
		(stroke
			(width 0.2)
			(type default)
		)
		(fill no)
		(layer "In1.Cu")
	)
	(gr_circle
		(center 121.338594 -161.595054)
		(end 122.227594 -161.595054)
		(stroke
			(width 0.2)
			(type default)
		)
		(fill no)
		(layer "In1.Cu")
	)
	(gr_circle
		(center 121.872248 -164.62756)
		(end 122.761248 -164.62756)
		(stroke
			(width 0.2)
			(type default)
		)
		(fill no)
		(layer "In1.Cu")
	)
	(gr_circle
		(center 121.872248 -163.89096)
		(end 122.761248 -163.89096)
		(stroke
			(width 0.2)
			(type default)
		)
		(fill no)
		(layer "In1.Cu")
	)
	(gr_circle
		(center 122.04065 -163.204144)
		(end 122.92076 -163.204144)
		(stroke
			(width 0.2)
			(type default)
		)
		(fill no)
		(layer "In1.Cu")
	)
	(gr_circle
		(center 122.65787 -163.204144)
		(end 123.53798 -163.204144)
		(stroke
			(width 0.2)
			(type default)
		)
		(fill no)
		(layer "In1.Cu")
	)
	(gr_circle
		(center 123.27509 -163.204144)
		(end 124.1552 -163.204144)
		(stroke
			(width 0.2)
			(type default)
		)
		(fill no)
		(layer "In1.Cu")
	)
	(gr_arc
		(start 124.102114 -11.780012)
		(mid 125.516325 -11.194227)
		(end 126.10211 -9.780016)
		(stroke
			(width 1.016)
			(type default)
		)
		(layer "In1.Cu")
	)
	(gr_line
		(start 126.10211 -9.780016)
		(end 126.10211 -5.780024)
		(stroke
			(width 1.016)
			(type default)
		)
		(layer "In1.Cu")
	)
	(gr_arc
		(start 126.601982 -5.279898)
		(mid 126.248489 -5.42646)
		(end 126.10211 -5.780024)
		(stroke
			(width 1.016)
			(type default)
		)
		(layer "In1.Cu")
	)
	(gr_line
		(start 126.601982 -5.279898)
		(end 194.20205 -5.279898)
		(stroke
			(width 1.016)
			(type default)
		)
		(layer "In1.Cu")
	)
	(gr_circle
		(center 128.71323 -154.465274)
		(end 129.60223 -154.465274)
		(stroke
			(width 0.2)
			(type default)
		)
		(fill no)
		(layer "In1.Cu")
	)
	(gr_circle
		(center 128.71323 -153.728674)
		(end 129.60223 -153.728674)
		(stroke
			(width 0.2)
			(type default)
		)
		(fill no)
		(layer "In1.Cu")
	)
	(gr_circle
		(center 128.71323 -152.992074)
		(end 129.60223 -152.992074)
		(stroke
			(width 0.2)
			(type default)
		)
		(fill no)
		(layer "In1.Cu")
	)
	(gr_circle
		(center 129.24663 -153.347674)
		(end 130.13563 -153.347674)
		(stroke
			(width 0.2)
			(type default)
		)
		(fill no)
		(layer "In1.Cu")
	)
	(gr_circle
		(center 129.27203 -154.109674)
		(end 130.16103 -154.109674)
		(stroke
			(width 0.2)
			(type default)
		)
		(fill no)
		(layer "In1.Cu")
	)
	(gr_circle
		(center 129.796794 -153.670254)
		(end 130.685794 -153.670254)
		(stroke
			(width 0.2)
			(type default)
		)
		(fill no)
		(layer "In1.Cu")
	)
	(gr_circle
		(center 129.796794 -152.933654)
		(end 130.685794 -152.933654)
		(stroke
			(width 0.2)
			(type default)
		)
		(fill no)
		(layer "In1.Cu")
	)
	(gr_circle
		(center 130.305048 -155.94076)
		(end 131.194048 -155.94076)
		(stroke
			(width 0.2)
			(type default)
		)
		(fill no)
		(layer "In1.Cu")
	)
	(gr_circle
		(center 130.305048 -155.20416)
		(end 131.194048 -155.20416)
		(stroke
			(width 0.2)
			(type default)
		)
		(fill no)
		(layer "In1.Cu")
	)
	(gr_circle
		(center 130.49885 -154.542744)
		(end 131.37896 -154.542744)
		(stroke
			(width 0.2)
			(type default)
		)
		(fill no)
		(layer "In1.Cu")
	)
	(gr_circle
		(center 131.11607 -154.542744)
		(end 131.99618 -154.542744)
		(stroke
			(width 0.2)
			(type default)
		)
		(fill no)
		(layer "In1.Cu")
	)
	(gr_circle
		(center 131.73329 -154.542744)
		(end 132.6134 -154.542744)
		(stroke
			(width 0.2)
			(type default)
		)
		(fill no)
		(layer "In1.Cu")
	)
	(gr_circle
		(center 176.332134 -26.634948)
		(end 177.221134 -26.634948)
		(stroke
			(width 0.2)
			(type default)
		)
		(fill no)
		(layer "In1.Cu")
	)
	(gr_circle
		(center 176.713134 -25.949148)
		(end 177.602134 -25.949148)
		(stroke
			(width 0.2)
			(type default)
		)
		(fill no)
		(layer "In1.Cu")
	)
	(gr_circle
		(center 176.878234 -19.942048)
		(end 177.767234 -19.942048)
		(stroke
			(width 0.2)
			(type default)
		)
		(fill no)
		(layer "In1.Cu")
	)
	(gr_circle
		(center 176.968912 -21.349208)
		(end 177.857912 -21.349208)
		(stroke
			(width 0.2)
			(type default)
		)
		(fill no)
		(layer "In1.Cu")
	)
	(gr_circle
		(center 176.968912 -20.714208)
		(end 177.857912 -20.714208)
		(stroke
			(width 0.2)
			(type default)
		)
		(fill no)
		(layer "In1.Cu")
	)
	(gr_circle
		(center 177.221134 -26.634948)
		(end 178.110134 -26.634948)
		(stroke
			(width 0.2)
			(type default)
		)
		(fill no)
		(layer "In1.Cu")
	)
	(gr_circle
		(center 177.472594 -21.85289)
		(end 178.361594 -21.85289)
		(stroke
			(width 0.2)
			(type default)
		)
		(fill no)
		(layer "In1.Cu")
	)
	(gr_circle
		(center 177.602134 -25.949148)
		(end 178.491134 -25.949148)
		(stroke
			(width 0.2)
			(type default)
		)
		(fill no)
		(layer "In1.Cu")
	)
	(gr_circle
		(center 178.110134 -26.634948)
		(end 178.999134 -26.634948)
		(stroke
			(width 0.2)
			(type default)
		)
		(fill no)
		(layer "In1.Cu")
	)
	(gr_circle
		(center 178.491134 -25.949148)
		(end 179.380134 -25.949148)
		(stroke
			(width 0.2)
			(type default)
		)
		(fill no)
		(layer "In1.Cu")
	)
	(gr_circle
		(center 179.507134 -25.517348)
		(end 180.396134 -25.517348)
		(stroke
			(width 0.2)
			(type default)
		)
		(fill no)
		(layer "In1.Cu")
	)
	(gr_circle
		(center 180.921914 -27.107388)
		(end 181.810914 -27.107388)
		(stroke
			(width 0.2)
			(type default)
		)
		(fill no)
		(layer "In1.Cu")
	)
	(gr_circle
		(center 183.610758 -353.283774)
		(end 184.490868 -353.283774)
		(stroke
			(width 0.2)
			(type default)
		)
		(fill no)
		(layer "In1.Cu")
	)
	(gr_circle
		(center 184.227978 -353.283774)
		(end 185.108088 -353.283774)
		(stroke
			(width 0.2)
			(type default)
		)
		(fill no)
		(layer "In1.Cu")
	)
	(gr_line
		(start 184.258458 -410.708348)
		(end 184.258458 -400.09572)
		(stroke
			(width 0.635)
			(type default)
		)
		(layer "In1.Cu")
	)
	(gr_line
		(start 184.258458 -400.09572)
		(end 184.463944 -399.890234)
		(stroke
			(width 0.635)
			(type default)
		)
		(layer "In1.Cu")
	)
	(gr_line
		(start 184.463944 -399.890234)
		(end 188.119004 -399.890234)
		(stroke
			(width 0.635)
			(type default)
		)
		(layer "In1.Cu")
	)
	(gr_line
		(start 184.8104 -411.26029)
		(end 184.258458 -410.708348)
		(stroke
			(width 0.635)
			(type default)
		)
		(layer "In1.Cu")
	)
	(gr_circle
		(center 184.845198 -353.283774)
		(end 185.725308 -353.283774)
		(stroke
			(width 0.2)
			(type default)
		)
		(fill no)
		(layer "In1.Cu")
	)
	(gr_circle
		(center 184.962292 -352.558604)
		(end 185.851292 -352.558604)
		(stroke
			(width 0.2)
			(type default)
		)
		(fill no)
		(layer "In1.Cu")
	)
	(gr_circle
		(center 184.962292 -351.822004)
		(end 185.851292 -351.822004)
		(stroke
			(width 0.2)
			(type default)
		)
		(fill no)
		(layer "In1.Cu")
	)
	(gr_circle
		(center 185.547254 -354.892864)
		(end 186.436254 -354.892864)
		(stroke
			(width 0.2)
			(type default)
		)
		(fill no)
		(layer "In1.Cu")
	)
	(gr_circle
		(center 185.547254 -354.156264)
		(end 186.436254 -354.156264)
		(stroke
			(width 0.2)
			(type default)
		)
		(fill no)
		(layer "In1.Cu")
	)
	(gr_circle
		(center 186.034172 -362.234988)
		(end 186.923172 -362.234988)
		(stroke
			(width 0.2)
			(type default)
		)
		(fill no)
		(layer "In1.Cu")
	)
	(gr_circle
		(center 186.034172 -361.472988)
		(end 186.923172 -361.472988)
		(stroke
			(width 0.2)
			(type default)
		)
		(fill no)
		(layer "In1.Cu")
	)
	(gr_circle
		(center 186.034172 -360.710988)
		(end 186.923172 -360.710988)
		(stroke
			(width 0.2)
			(type default)
		)
		(fill no)
		(layer "In1.Cu")
	)
	(gr_circle
		(center 186.072018 -353.716844)
		(end 186.961018 -353.716844)
		(stroke
			(width 0.2)
			(type default)
		)
		(fill no)
		(layer "In1.Cu")
	)
	(gr_circle
		(center 186.097418 -354.478844)
		(end 186.986418 -354.478844)
		(stroke
			(width 0.2)
			(type default)
		)
		(fill no)
		(layer "In1.Cu")
	)
	(gr_circle
		(center 186.630818 -354.834444)
		(end 187.519818 -354.834444)
		(stroke
			(width 0.2)
			(type default)
		)
		(fill no)
		(layer "In1.Cu")
	)
	(gr_circle
		(center 186.630818 -354.097844)
		(end 187.519818 -354.097844)
		(stroke
			(width 0.2)
			(type default)
		)
		(fill no)
		(layer "In1.Cu")
	)
	(gr_circle
		(center 186.630818 -353.361244)
		(end 187.519818 -353.361244)
		(stroke
			(width 0.2)
			(type default)
		)
		(fill no)
		(layer "In1.Cu")
	)
	(gr_circle
		(center 186.796172 -362.234988)
		(end 187.685172 -362.234988)
		(stroke
			(width 0.2)
			(type default)
		)
		(fill no)
		(layer "In1.Cu")
	)
	(gr_circle
		(center 186.796172 -361.472988)
		(end 187.685172 -361.472988)
		(stroke
			(width 0.2)
			(type default)
		)
		(fill no)
		(layer "In1.Cu")
	)
	(gr_circle
		(center 186.796172 -360.710988)
		(end 187.685172 -360.710988)
		(stroke
			(width 0.2)
			(type default)
		)
		(fill no)
		(layer "In1.Cu")
	)
	(gr_line
		(start 187.965334 -411.26029)
		(end 184.8104 -411.26029)
		(stroke
			(width 0.635)
			(type default)
		)
		(layer "In1.Cu")
	)
	(gr_line
		(start 188.119004 -399.890234)
		(end 188.303916 -400.075146)
		(stroke
			(width 0.635)
			(type default)
		)
		(layer "In1.Cu")
	)
	(gr_line
		(start 188.303916 -402.905976)
		(end 191.073786 -405.675846)
		(stroke
			(width 0.635)
			(type default)
		)
		(layer "In1.Cu")
	)
	(gr_line
		(start 188.303916 -400.075146)
		(end 188.303916 -402.905976)
		(stroke
			(width 0.635)
			(type default)
		)
		(layer "In1.Cu")
	)
	(gr_line
		(start 188.720222 -412.015178)
		(end 187.965334 -411.26029)
		(stroke
			(width 0.635)
			(type default)
		)
		(layer "In1.Cu")
	)
	(gr_circle
		(center 190.508636 -23.593552)
		(end 191.397636 -23.593552)
		(stroke
			(width 0.2)
			(type default)
		)
		(fill no)
		(layer "In1.Cu")
	)
	(gr_circle
		(center 190.508636 -22.856952)
		(end 191.397636 -22.856952)
		(stroke
			(width 0.2)
			(type default)
		)
		(fill no)
		(layer "In1.Cu")
	)
	(gr_line
		(start 191.073786 -405.675846)
		(end 195.418964 -405.675846)
		(stroke
			(width 0.635)
			(type default)
		)
		(layer "In1.Cu")
	)
	(gr_circle
		(center 191.67983 -362.430568)
		(end 193.07683 -362.430568)
		(stroke
			(width 0.2)
			(type default)
		)
		(fill no)
		(layer "In1.Cu")
	)
	(gr_circle
		(center 191.927734 -13.106908)
		(end 192.816734 -13.106908)
		(stroke
			(width 0.2)
			(type default)
		)
		(fill no)
		(layer "In1.Cu")
	)
	(gr_circle
		(center 191.937386 -353.309174)
		(end 192.817496 -353.309174)
		(stroke
			(width 0.2)
			(type default)
		)
		(fill no)
		(layer "In1.Cu")
	)
	(gr_circle
		(center 192.461134 -16.416528)
		(end 193.350134 -16.416528)
		(stroke
			(width 0.2)
			(type default)
		)
		(fill no)
		(layer "In1.Cu")
	)
	(gr_circle
		(center 192.461134 -15.781528)
		(end 193.350134 -15.781528)
		(stroke
			(width 0.2)
			(type default)
		)
		(fill no)
		(layer "In1.Cu")
	)
	(gr_circle
		(center 192.554606 -353.309174)
		(end 193.434716 -353.309174)
		(stroke
			(width 0.2)
			(type default)
		)
		(fill no)
		(layer "In1.Cu")
	)
	(gr_circle
		(center 192.689734 -13.106908)
		(end 193.578734 -13.106908)
		(stroke
			(width 0.2)
			(type default)
		)
		(fill no)
		(layer "In1.Cu")
	)
	(gr_circle
		(center 193.096134 -16.416528)
		(end 193.985134 -16.416528)
		(stroke
			(width 0.2)
			(type default)
		)
		(fill no)
		(layer "In1.Cu")
	)
	(gr_circle
		(center 193.096134 -15.781528)
		(end 193.985134 -15.781528)
		(stroke
			(width 0.2)
			(type default)
		)
		(fill no)
		(layer "In1.Cu")
	)
	(gr_circle
		(center 193.171826 -353.309174)
		(end 194.051936 -353.309174)
		(stroke
			(width 0.2)
			(type default)
		)
		(fill no)
		(layer "In1.Cu")
	)
	(gr_circle
		(center 193.28892 -352.563684)
		(end 194.17792 -352.563684)
		(stroke
			(width 0.2)
			(type default)
		)
		(fill no)
		(layer "In1.Cu")
	)
	(gr_circle
		(center 193.28892 -351.827084)
		(end 194.17792 -351.827084)
		(stroke
			(width 0.2)
			(type default)
		)
		(fill no)
		(layer "In1.Cu")
	)
	(gr_circle
		(center 193.731134 -15.781528)
		(end 194.620134 -15.781528)
		(stroke
			(width 0.2)
			(type default)
		)
		(fill no)
		(layer "In1.Cu")
	)
	(gr_circle
		(center 193.858134 -16.543528)
		(end 194.747134 -16.543528)
		(stroke
			(width 0.2)
			(type default)
		)
		(fill no)
		(layer "In1.Cu")
	)
	(gr_circle
		(center 193.873882 -354.918264)
		(end 194.762882 -354.918264)
		(stroke
			(width 0.2)
			(type default)
		)
		(fill no)
		(layer "In1.Cu")
	)
	(gr_circle
		(center 193.873882 -354.181664)
		(end 194.762882 -354.181664)
		(stroke
			(width 0.2)
			(type default)
		)
		(fill no)
		(layer "In1.Cu")
	)
	(gr_circle
		(center 194.398646 -353.742244)
		(end 195.287646 -353.742244)
		(stroke
			(width 0.2)
			(type default)
		)
		(fill no)
		(layer "In1.Cu")
	)
	(gr_circle
		(center 194.424046 -354.504244)
		(end 195.313046 -354.504244)
		(stroke
			(width 0.2)
			(type default)
		)
		(fill no)
		(layer "In1.Cu")
	)
	(gr_line
		(start 194.505072 -441.989972)
		(end 8.50011 -441.989972)
		(stroke
			(width 1.016)
			(type default)
		)
		(layer "In1.Cu")
	)
	(gr_arc
		(start 194.505072 -441.989972)
		(mid 194.858553 -441.843573)
		(end 195.004944 -441.4901)
		(stroke
			(width 1.016)
			(type default)
		)
		(layer "In1.Cu")
	)
	(gr_arc
		(start 194.701922 -9.780016)
		(mid 195.287707 -11.194227)
		(end 196.701918 -11.780012)
		(stroke
			(width 1.016)
			(type default)
		)
		(layer "In1.Cu")
	)
	(gr_arc
		(start 194.701922 -5.780024)
		(mid 194.555654 -5.42634)
		(end 194.20205 -5.279898)
		(stroke
			(width 1.016)
			(type default)
		)
		(layer "In1.Cu")
	)
	(gr_line
		(start 194.701922 -5.780024)
		(end 194.701922 -9.780016)
		(stroke
			(width 1.016)
			(type default)
		)
		(layer "In1.Cu")
	)
	(gr_circle
		(center 194.957446 -354.859844)
		(end 195.846446 -354.859844)
		(stroke
			(width 0.2)
			(type default)
		)
		(fill no)
		(layer "In1.Cu")
	)
	(gr_circle
		(center 194.957446 -354.123244)
		(end 195.846446 -354.123244)
		(stroke
			(width 0.2)
			(type default)
		)
		(fill no)
		(layer "In1.Cu")
	)
	(gr_circle
		(center 194.957446 -353.386644)
		(end 195.846446 -353.386644)
		(stroke
			(width 0.2)
			(type default)
		)
		(fill no)
		(layer "In1.Cu")
	)
	(gr_line
		(start 195.004944 -441.17006)
		(end 195.004944 -441.4901)
		(stroke
			(width 1.016)
			(type default)
		)
		(layer "In1.Cu")
	)
	(gr_line
		(start 195.270882 -412.015178)
		(end 188.720222 -412.015178)
		(stroke
			(width 0.635)
			(type default)
		)
		(layer "In1.Cu")
	)
	(gr_line
		(start 195.418964 -405.675846)
		(end 197.51167 -403.58314)
		(stroke
			(width 0.635)
			(type default)
		)
		(layer "In1.Cu")
	)
	(gr_arc
		(start 195.50507 -440.669934)
		(mid 195.151428 -440.816418)
		(end 195.004944 -441.17006)
		(stroke
			(width 1.016)
			(type default)
		)
		(layer "In1.Cu")
	)
	(gr_line
		(start 196.432424 -421.71112)
		(end 196.432424 -413.17672)
		(stroke
			(width 0.635)
			(type default)
		)
		(layer "In1.Cu")
	)
	(gr_line
		(start 196.432424 -413.17672)
		(end 195.270882 -412.015178)
		(stroke
			(width 0.635)
			(type default)
		)
		(layer "In1.Cu")
	)
	(gr_line
		(start 196.701918 -11.780012)
		(end 221.30004 -11.780012)
		(stroke
			(width 1.016)
			(type default)
		)
		(layer "In1.Cu")
	)
	(gr_line
		(start 197.51167 -403.58314)
		(end 197.51167 -400.104356)
		(stroke
			(width 0.635)
			(type default)
		)
		(layer "In1.Cu")
	)
	(gr_line
		(start 197.51167 -400.104356)
		(end 197.764146 -399.85188)
		(stroke
			(width 0.635)
			(type default)
		)
		(layer "In1.Cu")
	)
	(gr_line
		(start 197.764146 -399.85188)
		(end 201.33818 -399.85188)
		(stroke
			(width 0.635)
			(type default)
		)
		(layer "In1.Cu")
	)
	(gr_circle
		(center 198.160386 -37.328094)
		(end 199.049386 -37.328094)
		(stroke
			(width 0.2)
			(type default)
		)
		(fill no)
		(layer "In1.Cu")
	)
	(gr_circle
		(center 198.486014 -30.133798)
		(end 199.375014 -30.133798)
		(stroke
			(width 0.2)
			(type default)
		)
		(fill no)
		(layer "In1.Cu")
	)
	(gr_circle
		(center 198.836026 -37.965634)
		(end 199.725026 -37.965634)
		(stroke
			(width 0.2)
			(type default)
		)
		(fill no)
		(layer "In1.Cu")
	)
	(gr_circle
		(center 199.121014 -30.133798)
		(end 200.010014 -30.133798)
		(stroke
			(width 0.2)
			(type default)
		)
		(fill no)
		(layer "In1.Cu")
	)
	(gr_circle
		(center 199.435974 -30.720538)
		(end 200.324974 -30.720538)
		(stroke
			(width 0.2)
			(type default)
		)
		(fill no)
		(layer "In1.Cu")
	)
	(gr_circle
		(center 199.756014 -30.133798)
		(end 200.645014 -30.133798)
		(stroke
			(width 0.2)
			(type default)
		)
		(fill no)
		(layer "In1.Cu")
	)
	(gr_circle
		(center 200.070974 -30.720538)
		(end 200.959974 -30.720538)
		(stroke
			(width 0.2)
			(type default)
		)
		(fill no)
		(layer "In1.Cu")
	)
	(gr_circle
		(center 200.33234 -378.160534)
		(end 201.22134 -378.160534)
		(stroke
			(width 0.2)
			(type default)
		)
		(fill no)
		(layer "In1.Cu")
	)
	(gr_circle
		(center 200.391014 -30.133798)
		(end 201.280014 -30.133798)
		(stroke
			(width 0.2)
			(type default)
		)
		(fill no)
		(layer "In1.Cu")
	)
	(gr_circle
		(center 200.705974 -30.720538)
		(end 201.594974 -30.720538)
		(stroke
			(width 0.2)
			(type default)
		)
		(fill no)
		(layer "In1.Cu")
	)
	(gr_line
		(start 201.33818 -399.85188)
		(end 201.59853 -400.11223)
		(stroke
			(width 0.635)
			(type default)
		)
		(layer "In1.Cu")
	)
	(gr_circle
		(center 201.340974 -30.720538)
		(end 202.229974 -30.720538)
		(stroke
			(width 0.2)
			(type default)
		)
		(fill no)
		(layer "In1.Cu")
	)
	(gr_line
		(start 201.59853 -403.575266)
		(end 201.811636 -403.788372)
		(stroke
			(width 0.635)
			(type default)
		)
		(layer "In1.Cu")
	)
	(gr_line
		(start 201.59853 -400.11223)
		(end 201.59853 -403.575266)
		(stroke
			(width 0.635)
			(type default)
		)
		(layer "In1.Cu")
	)
	(gr_circle
		(center 201.745342 -346.583)
		(end 202.634342 -346.583)
		(stroke
			(width 0.2)
			(type default)
		)
		(fill no)
		(layer "In1.Cu")
	)
	(gr_circle
		(center 201.745342 -345.821)
		(end 202.634342 -345.821)
		(stroke
			(width 0.2)
			(type default)
		)
		(fill no)
		(layer "In1.Cu")
	)
	(gr_circle
		(center 201.745342 -344.8304)
		(end 202.634342 -344.8304)
		(stroke
			(width 0.2)
			(type default)
		)
		(fill no)
		(layer "In1.Cu")
	)
	(gr_circle
		(center 201.745342 -344.0684)
		(end 202.634342 -344.0684)
		(stroke
			(width 0.2)
			(type default)
		)
		(fill no)
		(layer "In1.Cu")
	)
	(gr_line
		(start 201.811636 -406.668732)
		(end 203.461112 -408.318208)
		(stroke
			(width 0.635)
			(type default)
		)
		(layer "In1.Cu")
	)
	(gr_line
		(start 201.811636 -403.788372)
		(end 201.811636 -406.668732)
		(stroke
			(width 0.635)
			(type default)
		)
		(layer "In1.Cu")
	)
	(gr_line
		(start 203.461112 -408.318208)
		(end 205.948026 -408.318208)
		(stroke
			(width 0.635)
			(type default)
		)
		(layer "In1.Cu")
	)
	(gr_line
		(start 205.73746 -435.231032)
		(end 205.73746 -431.016156)
		(stroke
			(width 0.635)
			(type default)
		)
		(layer "In1.Cu")
	)
	(gr_line
		(start 205.73746 -435.231032)
		(end 207.302608 -436.79618)
		(stroke
			(width 0.635)
			(type default)
		)
		(layer "In1.Cu")
	)
	(gr_line
		(start 205.73746 -431.016156)
		(end 196.432424 -421.71112)
		(stroke
			(width 0.635)
			(type default)
		)
		(layer "In1.Cu")
	)
	(gr_line
		(start 205.948026 -408.318208)
		(end 207.991202 -406.275032)
		(stroke
			(width 0.635)
			(type default)
		)
		(layer "In1.Cu")
	)
	(gr_line
		(start 207.302608 -436.79618)
		(end 229.074472 -436.79618)
		(stroke
			(width 0.635)
			(type default)
		)
		(layer "In1.Cu")
	)
	(gr_line
		(start 207.991202 -406.275032)
		(end 207.991202 -403.722586)
		(stroke
			(width 0.635)
			(type default)
		)
		(layer "In1.Cu")
	)
	(gr_line
		(start 207.991202 -403.722586)
		(end 208.17967 -403.534118)
		(stroke
			(width 0.635)
			(type default)
		)
		(layer "In1.Cu")
	)
	(gr_line
		(start 208.17967 -403.534118)
		(end 208.17967 -400.079464)
		(stroke
			(width 0.635)
			(type default)
		)
		(layer "In1.Cu")
	)
	(gr_line
		(start 208.17967 -400.079464)
		(end 208.42605 -399.833084)
		(stroke
			(width 0.635)
			(type default)
		)
		(layer "In1.Cu")
	)
	(gr_line
		(start 208.42605 -399.833084)
		(end 211.971128 -399.833084)
		(stroke
			(width 0.635)
			(type default)
		)
		(layer "In1.Cu")
	)
	(gr_circle
		(center 208.508854 -37.366448)
		(end 209.397854 -37.366448)
		(stroke
			(width 0.2)
			(type default)
		)
		(fill no)
		(layer "In1.Cu")
	)
	(gr_line
		(start 211.971128 -399.833084)
		(end 212.28304 -400.144996)
		(stroke
			(width 0.635)
			(type default)
		)
		(layer "In1.Cu")
	)
	(gr_line
		(start 212.28304 -403.63267)
		(end 212.414358 -403.763988)
		(stroke
			(width 0.635)
			(type default)
		)
		(layer "In1.Cu")
	)
	(gr_line
		(start 212.28304 -400.144996)
		(end 212.28304 -403.63267)
		(stroke
			(width 0.635)
			(type default)
		)
		(layer "In1.Cu")
	)
	(gr_line
		(start 212.414358 -406.410668)
		(end 214.347044 -408.343354)
		(stroke
			(width 0.635)
			(type default)
		)
		(layer "In1.Cu")
	)
	(gr_line
		(start 212.414358 -403.763988)
		(end 212.414358 -406.410668)
		(stroke
			(width 0.635)
			(type default)
		)
		(layer "In1.Cu")
	)
	(gr_line
		(start 214.347044 -408.343354)
		(end 216.541604 -408.343354)
		(stroke
			(width 0.635)
			(type default)
		)
		(layer "In1.Cu")
	)
	(gr_line
		(start 216.541604 -408.343354)
		(end 218.667584 -406.217374)
		(stroke
			(width 0.635)
			(type default)
		)
		(layer "In1.Cu")
	)
	(gr_line
		(start 218.667584 -406.217374)
		(end 218.667584 -403.755606)
		(stroke
			(width 0.635)
			(type default)
		)
		(layer "In1.Cu")
	)
	(gr_line
		(start 218.667584 -403.755606)
		(end 218.839796 -403.583394)
		(stroke
			(width 0.635)
			(type default)
		)
		(layer "In1.Cu")
	)
	(gr_line
		(start 218.839796 -403.583394)
		(end 218.839796 -400.095974)
		(stroke
			(width 0.635)
			(type default)
		)
		(layer "In1.Cu")
	)
	(gr_line
		(start 218.839796 -400.095974)
		(end 219.045282 -399.890488)
		(stroke
			(width 0.635)
			(type default)
		)
		(layer "In1.Cu")
	)
	(gr_line
		(start 219.045282 -399.890488)
		(end 222.709232 -399.890488)
		(stroke
			(width 0.635)
			(type default)
		)
		(layer "In1.Cu")
	)
	(gr_line
		(start 222.709232 -399.890488)
		(end 222.906082 -400.087338)
		(stroke
			(width 0.635)
			(type default)
		)
		(layer "In1.Cu")
	)
	(gr_line
		(start 222.906082 -403.607778)
		(end 223.099122 -403.800818)
		(stroke
			(width 0.635)
			(type default)
		)
		(layer "In1.Cu")
	)
	(gr_line
		(start 222.906082 -400.087338)
		(end 222.906082 -403.607778)
		(stroke
			(width 0.635)
			(type default)
		)
		(layer "In1.Cu")
	)
	(gr_line
		(start 223.099122 -406.414732)
		(end 224.990406 -408.306016)
		(stroke
			(width 0.635)
			(type default)
		)
		(layer "In1.Cu")
	)
	(gr_line
		(start 223.099122 -403.800818)
		(end 223.099122 -406.414732)
		(stroke
			(width 0.635)
			(type default)
		)
		(layer "In1.Cu")
	)
	(gr_arc
		(start 223.300036 -34.120074)
		(mid 223.885821 -35.534285)
		(end 225.300032 -36.12007)
		(stroke
			(width 1.016)
			(type default)
		)
		(layer "In1.Cu")
	)
	(gr_arc
		(start 223.300036 -13.780008)
		(mid 222.714256 -12.365778)
		(end 221.30004 -11.780012)
		(stroke
			(width 1.016)
			(type default)
		)
		(layer "In1.Cu")
	)
	(gr_line
		(start 223.300036 -13.780008)
		(end 223.300036 -34.120074)
		(stroke
			(width 1.016)
			(type default)
		)
		(layer "In1.Cu")
	)
	(gr_line
		(start 224.990406 -408.306016)
		(end 227.218748 -408.306016)
		(stroke
			(width 0.635)
			(type default)
		)
		(layer "In1.Cu")
	)
	(gr_line
		(start 225.300032 -36.12007)
		(end 256.800096 -36.12007)
		(stroke
			(width 1.016)
			(type default)
		)
		(layer "In1.Cu")
	)
	(gr_line
		(start 227.218748 -408.306016)
		(end 229.331774 -406.19299)
		(stroke
			(width 0.635)
			(type default)
		)
		(layer "In1.Cu")
	)
	(gr_line
		(start 229.074472 -436.79618)
		(end 229.997 -435.873652)
		(stroke
			(width 0.635)
			(type default)
		)
		(layer "In1.Cu")
	)
	(gr_line
		(start 229.331774 -406.19299)
		(end 229.331774 -403.768052)
		(stroke
			(width 0.635)
			(type default)
		)
		(layer "In1.Cu")
	)
	(gr_line
		(start 229.331774 -403.768052)
		(end 229.516178 -403.583648)
		(stroke
			(width 0.635)
			(type default)
		)
		(layer "In1.Cu")
	)
	(gr_line
		(start 229.516178 -403.583648)
		(end 229.516178 -400.11223)
		(stroke
			(width 0.635)
			(type default)
		)
		(layer "In1.Cu")
	)
	(gr_line
		(start 229.516178 -400.11223)
		(end 229.746302 -399.882106)
		(stroke
			(width 0.635)
			(type default)
		)
		(layer "In1.Cu")
	)
	(gr_line
		(start 229.746302 -399.882106)
		(end 233.352594 -399.882106)
		(stroke
			(width 0.635)
			(type default)
		)
		(layer "In1.Cu")
	)
	(gr_line
		(start 229.997 -435.873652)
		(end 229.997 -422.180766)
		(stroke
			(width 0.635)
			(type default)
		)
		(layer "In1.Cu")
	)
	(gr_line
		(start 233.352594 -399.882106)
		(end 233.574336 -400.103848)
		(stroke
			(width 0.635)
			(type default)
		)
		(layer "In1.Cu")
	)
	(gr_line
		(start 233.574336 -403.673564)
		(end 233.820462 -403.91969)
		(stroke
			(width 0.635)
			(type default)
		)
		(layer "In1.Cu")
	)
	(gr_line
		(start 233.574336 -400.103848)
		(end 233.574336 -403.673564)
		(stroke
			(width 0.635)
			(type default)
		)
		(layer "In1.Cu")
	)
	(gr_line
		(start 233.820462 -404.855172)
		(end 234.522264 -405.556974)
		(stroke
			(width 0.635)
			(type default)
		)
		(layer "In1.Cu")
	)
	(gr_line
		(start 233.820462 -403.91969)
		(end 233.820462 -404.855172)
		(stroke
			(width 0.635)
			(type default)
		)
		(layer "In1.Cu")
	)
	(gr_line
		(start 234.522264 -405.556974)
		(end 238.715804 -405.556974)
		(stroke
			(width 0.635)
			(type default)
		)
		(layer "In1.Cu")
	)
	(gr_line
		(start 234.897676 -417.28009)
		(end 229.997 -422.180766)
		(stroke
			(width 0.635)
			(type default)
		)
		(layer "In1.Cu")
	)
	(gr_circle
		(center 237.629954 -44.025566)
		(end 238.518954 -44.025566)
		(stroke
			(width 0.2)
			(type default)
		)
		(fill no)
		(layer "In1.Cu")
	)
	(gr_circle
		(center 237.640114 -44.716446)
		(end 238.529114 -44.716446)
		(stroke
			(width 0.2)
			(type default)
		)
		(fill no)
		(layer "In1.Cu")
	)
	(gr_circle
		(center 238.292894 -44.802806)
		(end 239.181894 -44.802806)
		(stroke
			(width 0.2)
			(type default)
		)
		(fill no)
		(layer "In1.Cu")
	)
	(gr_circle
		(center 238.292894 -44.040806)
		(end 239.181894 -44.040806)
		(stroke
			(width 0.2)
			(type default)
		)
		(fill no)
		(layer "In1.Cu")
	)
	(gr_arc
		(start 238.695992 -393.003532)
		(mid 238.724179 -393.144586)
		(end 238.804196 -393.264136)
		(stroke
			(width 0.635)
			(type default)
		)
		(layer "In1.Cu")
	)
	(gr_line
		(start 238.695992 -384.337306)
		(end 238.695992 -393.003532)
		(stroke
			(width 0.635)
			(type default)
		)
		(layer "In1.Cu")
	)
	(gr_line
		(start 238.715804 -405.556974)
		(end 238.882682 -405.390096)
		(stroke
			(width 0.635)
			(type default)
		)
		(layer "In1.Cu")
	)
	(gr_line
		(start 238.752126 -384.198876)
		(end 238.695992 -384.337306)
		(stroke
			(width 0.635)
			(type default)
		)
		(layer "In1.Cu")
	)
	(gr_line
		(start 238.804196 -393.264136)
		(end 239.027716 -393.487656)
		(stroke
			(width 0.635)
			(type default)
		)
		(layer "In1.Cu")
	)
	(gr_line
		(start 238.805974 -384.146806)
		(end 238.752126 -384.198876)
		(stroke
			(width 0.635)
			(type default)
		)
		(layer "In1.Cu")
	)
	(gr_line
		(start 238.882682 -405.390096)
		(end 238.882682 -394.210794)
		(stroke
			(width 0.635)
			(type default)
		)
		(layer "In1.Cu")
	)
	(gr_line
		(start 238.882682 -394.210794)
		(end 238.882682 -394.001498)
		(stroke
			(width 0.635)
			(type default)
		)
		(layer "In1.Cu")
	)
	(gr_line
		(start 238.882682 -394.210794)
		(end 279.615392 -394.210794)
		(stroke
			(width 0.635)
			(type default)
		)
		(layer "In1.Cu")
	)
	(gr_line
		(start 238.882682 -394.001498)
		(end 239.28832 -393.59586)
		(stroke
			(width 0.635)
			(type default)
		)
		(layer "In1.Cu")
	)
	(gr_circle
		(center 238.943134 -44.802806)
		(end 239.832134 -44.802806)
		(stroke
			(width 0.2)
			(type default)
		)
		(fill no)
		(layer "In1.Cu")
	)
	(gr_circle
		(center 238.943134 -44.040806)
		(end 239.832134 -44.040806)
		(stroke
			(width 0.2)
			(type default)
		)
		(fill no)
		(layer "In1.Cu")
	)
	(gr_arc
		(start 239.027716 -393.487656)
		(mid 239.147257 -393.567682)
		(end 239.28832 -393.59586)
		(stroke
			(width 0.635)
			(type default)
		)
		(layer "In1.Cu")
	)
	(gr_line
		(start 239.281716 -383.671064)
		(end 238.805974 -384.146806)
		(stroke
			(width 0.635)
			(type default)
		)
		(layer "In1.Cu")
	)
	(gr_line
		(start 239.28832 -393.59586)
		(end 273.155664 -393.59586)
		(stroke
			(width 0.635)
			(type default)
		)
		(layer "In1.Cu")
	)
	(gr_arc
		(start 239.54232 -383.56286)
		(mid 239.401266 -383.591047)
		(end 239.281716 -383.671064)
		(stroke
			(width 0.635)
			(type default)
		)
		(layer "In1.Cu")
	)
	(gr_circle
		(center 239.578134 -44.802806)
		(end 240.467134 -44.802806)
		(stroke
			(width 0.2)
			(type default)
		)
		(fill no)
		(layer "In1.Cu")
	)
	(gr_circle
		(center 239.578134 -44.040806)
		(end 240.467134 -44.040806)
		(stroke
			(width 0.2)
			(type default)
		)
		(fill no)
		(layer "In1.Cu")
	)
	(gr_circle
		(center 240.213134 -44.802806)
		(end 241.102134 -44.802806)
		(stroke
			(width 0.2)
			(type default)
		)
		(fill no)
		(layer "In1.Cu")
	)
	(gr_circle
		(center 240.213134 -44.040806)
		(end 241.102134 -44.040806)
		(stroke
			(width 0.2)
			(type default)
		)
		(fill no)
		(layer "In1.Cu")
	)
	(gr_circle
		(center 240.893854 -44.830746)
		(end 241.782854 -44.830746)
		(stroke
			(width 0.2)
			(type default)
		)
		(fill no)
		(layer "In1.Cu")
	)
	(gr_circle
		(center 244.518942 -43.246802)
		(end 245.407942 -43.246802)
		(stroke
			(width 0.2)
			(type default)
		)
		(fill no)
		(layer "In1.Cu")
	)
	(gr_circle
		(center 244.518942 -42.611802)
		(end 245.407942 -42.611802)
		(stroke
			(width 0.2)
			(type default)
		)
		(fill no)
		(layer "In1.Cu")
	)
	(gr_circle
		(center 245.857522 -52.022502)
		(end 246.746522 -52.022502)
		(stroke
			(width 0.2)
			(type default)
		)
		(fill no)
		(layer "In1.Cu")
	)
	(gr_circle
		(center 246.873522 -52.022502)
		(end 247.762522 -52.022502)
		(stroke
			(width 0.2)
			(type default)
		)
		(fill no)
		(layer "In1.Cu")
	)
	(gr_circle
		(center 247.825514 -40.94988)
		(end 248.714514 -40.94988)
		(stroke
			(width 0.2)
			(type default)
		)
		(fill no)
		(layer "In1.Cu")
	)
	(gr_circle
		(center 247.840246 -51.320446)
		(end 248.729246 -51.320446)
		(stroke
			(width 0.2)
			(type default)
		)
		(fill no)
		(layer "In1.Cu")
	)
	(gr_circle
		(center 248.214134 -52.171346)
		(end 249.103134 -52.171346)
		(stroke
			(width 0.2)
			(type default)
		)
		(fill no)
		(layer "In1.Cu")
	)
	(gr_circle
		(center 248.881646 -51.320446)
		(end 249.770646 -51.320446)
		(stroke
			(width 0.2)
			(type default)
		)
		(fill no)
		(layer "In1.Cu")
	)
	(gr_circle
		(center 249.202448 -40.945816)
		(end 250.091448 -40.945816)
		(stroke
			(width 0.2)
			(type default)
		)
		(fill no)
		(layer "In1.Cu")
	)
	(gr_circle
		(center 249.905266 -51.349148)
		(end 250.794266 -51.349148)
		(stroke
			(width 0.2)
			(type default)
		)
		(fill no)
		(layer "In1.Cu")
	)
	(gr_circle
		(center 250.449334 -49.555146)
		(end 251.338334 -49.555146)
		(stroke
			(width 0.2)
			(type default)
		)
		(fill no)
		(layer "In1.Cu")
	)
	(gr_circle
		(center 250.779534 -52.222146)
		(end 251.668534 -52.222146)
		(stroke
			(width 0.2)
			(type default)
		)
		(fill no)
		(layer "In1.Cu")
	)
	(gr_circle
		(center 250.779534 -51.333146)
		(end 251.668534 -51.333146)
		(stroke
			(width 0.2)
			(type default)
		)
		(fill no)
		(layer "In1.Cu")
	)
	(gr_circle
		(center 250.779534 -50.444146)
		(end 251.668534 -50.444146)
		(stroke
			(width 0.2)
			(type default)
		)
		(fill no)
		(layer "In1.Cu")
	)
	(gr_circle
		(center 251.516134 -52.501546)
		(end 252.405134 -52.501546)
		(stroke
			(width 0.2)
			(type default)
		)
		(fill no)
		(layer "In1.Cu")
	)
	(gr_circle
		(center 251.516134 -51.612546)
		(end 252.405134 -51.612546)
		(stroke
			(width 0.2)
			(type default)
		)
		(fill no)
		(layer "In1.Cu")
	)
	(gr_circle
		(center 251.516134 -50.723546)
		(end 252.405134 -50.723546)
		(stroke
			(width 0.2)
			(type default)
		)
		(fill no)
		(layer "In1.Cu")
	)
	(gr_circle
		(center 255.347978 -39.380922)
		(end 256.236978 -39.380922)
		(stroke
			(width 0.2)
			(type default)
		)
		(fill no)
		(layer "In1.Cu")
	)
	(gr_arc
		(start 256.800096 -36.12007)
		(mid 258.214307 -35.534285)
		(end 258.800092 -34.120074)
		(stroke
			(width 1.016)
			(type default)
		)
		(layer "In1.Cu")
	)
	(gr_line
		(start 258.800092 -34.120074)
		(end 258.800092 -13.780008)
		(stroke
			(width 1.016)
			(type default)
		)
		(layer "In1.Cu")
	)
	(gr_arc
		(start 260.800088 -11.780012)
		(mid 259.385888 -12.365802)
		(end 258.800092 -13.780008)
		(stroke
			(width 1.016)
			(type default)
		)
		(layer "In1.Cu")
	)
	(gr_line
		(start 260.800088 -11.780012)
		(end 385.601972 -11.780012)
		(stroke
			(width 1.016)
			(type default)
		)
		(layer "In1.Cu")
	)
	(gr_line
		(start 272.19021 -417.28009)
		(end 234.897676 -417.28009)
		(stroke
			(width 0.635)
			(type default)
		)
		(layer "In1.Cu")
	)
	(gr_arc
		(start 273.155664 -393.59586)
		(mid 273.296718 -393.567673)
		(end 273.416268 -393.487656)
		(stroke
			(width 0.635)
			(type default)
		)
		(layer "In1.Cu")
	)
	(gr_line
		(start 273.33067 -394.041884)
		(end 279.547066 -394.041884)
		(stroke
			(width 0.635)
			(type default)
		)
		(layer "In1.Cu")
	)
	(gr_line
		(start 273.416268 -393.487656)
		(end 273.893788 -393.010136)
		(stroke
			(width 0.635)
			(type default)
		)
		(layer "In1.Cu")
	)
	(gr_line
		(start 273.481546 -383.56286)
		(end 239.54232 -383.56286)
		(stroke
			(width 0.635)
			(type default)
		)
		(layer "In1.Cu")
	)
	(gr_line
		(start 273.619976 -383.618994)
		(end 273.481546 -383.56286)
		(stroke
			(width 0.635)
			(type default)
		)
		(layer "In1.Cu")
	)
	(gr_line
		(start 273.672046 -383.672842)
		(end 273.619976 -383.618994)
		(stroke
			(width 0.635)
			(type default)
		)
		(layer "In1.Cu")
	)
	(gr_arc
		(start 273.893788 -393.010136)
		(mid 273.97387 -392.890613)
		(end 274.001992 -392.749532)
		(stroke
			(width 0.635)
			(type default)
		)
		(layer "In1.Cu")
	)
	(gr_line
		(start 273.893788 -383.894584)
		(end 273.672046 -383.672842)
		(stroke
			(width 0.635)
			(type default)
		)
		(layer "In1.Cu")
	)
	(gr_line
		(start 274.001992 -392.749532)
		(end 274.001992 -384.155188)
		(stroke
			(width 0.635)
			(type default)
		)
		(layer "In1.Cu")
	)
	(gr_arc
		(start 274.001992 -384.155188)
		(mid 273.973805 -384.014134)
		(end 273.893788 -383.894584)
		(stroke
			(width 0.635)
			(type default)
		)
		(layer "In1.Cu")
	)
	(gr_line
		(start 274.123404 -393.697206)
		(end 279.133554 -393.697206)
		(stroke
			(width 0.635)
			(type default)
		)
		(layer "In1.Cu")
	)
	(gr_line
		(start 274.433792 -392.938762)
		(end 273.33067 -394.041884)
		(stroke
			(width 0.635)
			(type default)
		)
		(layer "In1.Cu")
	)
	(gr_line
		(start 274.433792 -392.938762)
		(end 274.50288 -392.869674)
		(stroke
			(width 0.635)
			(type default)
		)
		(layer "In1.Cu")
	)
	(gr_line
		(start 274.433792 -392.317732)
		(end 274.67052 -392.55446)
		(stroke
			(width 0.635)
			(type default)
		)
		(layer "In1.Cu")
	)
	(gr_line
		(start 274.433792 -384.002788)
		(end 274.433792 -392.938762)
		(stroke
			(width 0.635)
			(type default)
		)
		(layer "In1.Cu")
	)
	(gr_line
		(start 274.433792 -384.002788)
		(end 274.433792 -392.317732)
		(stroke
			(width 0.635)
			(type default)
		)
		(layer "In1.Cu")
	)
	(gr_line
		(start 274.50288 -392.869674)
		(end 279.110694 -392.869674)
		(stroke
			(width 0.635)
			(type default)
		)
		(layer "In1.Cu")
	)
	(gr_line
		(start 274.732496 -393.237466)
		(end 274.433792 -392.938762)
		(stroke
			(width 0.635)
			(type default)
		)
		(layer "In1.Cu")
	)
	(gr_line
		(start 274.778724 -392.605514)
		(end 274.192746 -392.019536)
		(stroke
			(width 0.635)
			(type default)
		)
		(layer "In1.Cu")
	)
	(gr_line
		(start 274.87372 -383.56286)
		(end 274.433792 -384.002788)
		(stroke
			(width 0.635)
			(type default)
		)
		(layer "In1.Cu")
	)
	(gr_circle
		(center 276.112986 -348.704662)
		(end 276.993096 -348.704662)
		(stroke
			(width 0.2)
			(type default)
		)
		(fill no)
		(layer "In1.Cu")
	)
	(gr_line
		(start 276.314916 -440.669934)
		(end 195.50507 -440.669934)
		(stroke
			(width 1.016)
			(type default)
		)
		(layer "In1.Cu")
	)
	(gr_circle
		(center 276.730206 -348.704662)
		(end 277.610316 -348.704662)
		(stroke
			(width 0.2)
			(type default)
		)
		(fill no)
		(layer "In1.Cu")
	)
	(gr_line
		(start 276.815042 -441.4901)
		(end 276.815042 -441.17006)
		(stroke
			(width 1.016)
			(type default)
		)
		(layer "In1.Cu")
	)
	(gr_arc
		(start 276.815042 -441.4901)
		(mid 276.961452 -441.843558)
		(end 277.314914 -441.989972)
		(stroke
			(width 1.016)
			(type default)
		)
		(layer "In1.Cu")
	)
	(gr_arc
		(start 276.815042 -441.17006)
		(mid 276.668558 -440.816418)
		(end 276.314916 -440.669934)
		(stroke
			(width 1.016)
			(type default)
		)
		(layer "In1.Cu")
	)
	(gr_circle
		(center 277.347426 -348.704662)
		(end 278.227536 -348.704662)
		(stroke
			(width 0.2)
			(type default)
		)
		(fill no)
		(layer "In1.Cu")
	)
	(gr_circle
		(center 277.593806 -348.025212)
		(end 278.482806 -348.025212)
		(stroke
			(width 0.2)
			(type default)
		)
		(fill no)
		(layer "In1.Cu")
	)
	(gr_circle
		(center 277.593806 -347.288612)
		(end 278.482806 -347.288612)
		(stroke
			(width 0.2)
			(type default)
		)
		(fill no)
		(layer "In1.Cu")
	)
	(gr_circle
		(center 278.049482 -350.313752)
		(end 278.938482 -350.313752)
		(stroke
			(width 0.2)
			(type default)
		)
		(fill no)
		(layer "In1.Cu")
	)
	(gr_circle
		(center 278.049482 -349.577152)
		(end 278.938482 -349.577152)
		(stroke
			(width 0.2)
			(type default)
		)
		(fill no)
		(layer "In1.Cu")
	)
	(gr_circle
		(center 278.574246 -349.137732)
		(end 279.463246 -349.137732)
		(stroke
			(width 0.2)
			(type default)
		)
		(fill no)
		(layer "In1.Cu")
	)
	(gr_circle
		(center 278.599646 -349.899732)
		(end 279.488646 -349.899732)
		(stroke
			(width 0.2)
			(type default)
		)
		(fill no)
		(layer "In1.Cu")
	)
	(gr_line
		(start 278.892508 -393.237466)
		(end 274.732496 -393.237466)
		(stroke
			(width 0.635)
			(type default)
		)
		(layer "In1.Cu")
	)
	(gr_line
		(start 279.110694 -392.869674)
		(end 279.351994 -392.628374)
		(stroke
			(width 0.635)
			(type default)
		)
		(layer "In1.Cu")
	)
	(gr_circle
		(center 279.133046 -350.255332)
		(end 280.022046 -350.255332)
		(stroke
			(width 0.2)
			(type default)
		)
		(fill no)
		(layer "In1.Cu")
	)
	(gr_circle
		(center 279.133046 -349.518732)
		(end 280.022046 -349.518732)
		(stroke
			(width 0.2)
			(type default)
		)
		(fill no)
		(layer "In1.Cu")
	)
	(gr_circle
		(center 279.133046 -348.782132)
		(end 280.022046 -348.782132)
		(stroke
			(width 0.2)
			(type default)
		)
		(fill no)
		(layer "In1.Cu")
	)
	(gr_line
		(start 279.133554 -393.697206)
		(end 279.983946 -392.846814)
		(stroke
			(width 0.635)
			(type default)
		)
		(layer "In1.Cu")
	)
	(gr_line
		(start 279.329134 -392.605514)
		(end 274.778724 -392.605514)
		(stroke
			(width 0.635)
			(type default)
		)
		(layer "In1.Cu")
	)
	(gr_line
		(start 279.351994 -392.628374)
		(end 279.329134 -392.605514)
		(stroke
			(width 0.635)
			(type default)
		)
		(layer "In1.Cu")
	)
	(gr_line
		(start 279.547066 -394.041884)
		(end 280.477976 -393.110974)
		(stroke
			(width 0.635)
			(type default)
		)
		(layer "In1.Cu")
	)
	(gr_line
		(start 279.616408 -392.513566)
		(end 278.892508 -393.237466)
		(stroke
			(width 0.635)
			(type default)
		)
		(layer "In1.Cu")
	)
	(gr_line
		(start 279.616408 -383.780538)
		(end 279.616408 -392.513566)
		(stroke
			(width 0.635)
			(type default)
		)
		(layer "In1.Cu")
	)
	(gr_line
		(start 279.834086 -383.56286)
		(end 279.616408 -383.780538)
		(stroke
			(width 0.635)
			(type default)
		)
		(layer "In1.Cu")
	)
	(gr_arc
		(start 279.875996 -394.318998)
		(mid 279.756473 -394.238916)
		(end 279.615392 -394.210794)
		(stroke
			(width 0.635)
			(type default)
		)
		(layer "In1.Cu")
	)
	(gr_line
		(start 279.983946 -392.846814)
		(end 279.983946 -383.781046)
		(stroke
			(width 0.635)
			(type default)
		)
		(layer "In1.Cu")
	)
	(gr_line
		(start 279.983946 -383.781046)
		(end 280.202132 -383.56286)
		(stroke
			(width 0.635)
			(type default)
		)
		(layer "In1.Cu")
	)
	(gr_line
		(start 280.202132 -383.56286)
		(end 274.87372 -383.56286)
		(stroke
			(width 0.635)
			(type default)
		)
		(layer "In1.Cu")
	)
	(gr_line
		(start 280.202132 -383.56286)
		(end 279.834086 -383.56286)
		(stroke
			(width 0.635)
			(type default)
		)
		(layer "In1.Cu")
	)
	(gr_line
		(start 280.259536 -394.702538)
		(end 279.875996 -394.318998)
		(stroke
			(width 0.635)
			(type default)
		)
		(layer "In1.Cu")
	)
	(gr_line
		(start 280.36774 -409.10256)
		(end 272.19021 -417.28009)
		(stroke
			(width 0.635)
			(type default)
		)
		(layer "In1.Cu")
	)
	(gr_line
		(start 280.36774 -407.8097)
		(end 280.36774 -394.963142)
		(stroke
			(width 0.635)
			(type default)
		)
		(layer "In1.Cu")
	)
	(gr_arc
		(start 280.36774 -394.963142)
		(mid 280.339553 -394.822088)
		(end 280.259536 -394.702538)
		(stroke
			(width 0.635)
			(type default)
		)
		(layer "In1.Cu")
	)
	(gr_line
		(start 280.36774 -394.963142)
		(end 280.36774 -409.10256)
		(stroke
			(width 0.635)
			(type default)
		)
		(layer "In1.Cu")
	)
	(gr_line
		(start 280.477976 -393.110974)
		(end 280.477976 -383.838704)
		(stroke
			(width 0.635)
			(type default)
		)
		(layer "In1.Cu")
	)
	(gr_line
		(start 280.477976 -383.838704)
		(end 280.202132 -383.56286)
		(stroke
			(width 0.635)
			(type default)
		)
		(layer "In1.Cu")
	)
	(gr_line
		(start 280.537412 -392.55446)
		(end 274.67052 -392.55446)
		(stroke
			(width 0.635)
			(type default)
		)
		(layer "In1.Cu")
	)
	(gr_line
		(start 280.537412 -392.55446)
		(end 280.9113 -392.180572)
		(stroke
			(width 0.635)
			(type default)
		)
		(layer "In1.Cu")
	)
	(gr_line
		(start 280.9113 -392.180572)
		(end 280.9113 -384.272028)
		(stroke
			(width 0.635)
			(type default)
		)
		(layer "In1.Cu")
	)
	(gr_line
		(start 280.9113 -384.272028)
		(end 280.202132 -383.56286)
		(stroke
			(width 0.635)
			(type default)
		)
		(layer "In1.Cu")
	)
	(gr_circle
		(center 284.393386 -348.704662)
		(end 285.273496 -348.704662)
		(stroke
			(width 0.2)
			(type default)
		)
		(fill no)
		(layer "In1.Cu")
	)
	(gr_circle
		(center 285.010606 -348.704662)
		(end 285.890716 -348.704662)
		(stroke
			(width 0.2)
			(type default)
		)
		(fill no)
		(layer "In1.Cu")
	)
	(gr_circle
		(center 285.627826 -348.704662)
		(end 286.507936 -348.704662)
		(stroke
			(width 0.2)
			(type default)
		)
		(fill no)
		(layer "In1.Cu")
	)
	(gr_circle
		(center 285.869126 -347.982032)
		(end 286.758126 -347.982032)
		(stroke
			(width 0.2)
			(type default)
		)
		(fill no)
		(layer "In1.Cu")
	)
	(gr_circle
		(center 285.869126 -347.245432)
		(end 286.758126 -347.245432)
		(stroke
			(width 0.2)
			(type default)
		)
		(fill no)
		(layer "In1.Cu")
	)
	(gr_circle
		(center 286.329882 -350.313752)
		(end 287.218882 -350.313752)
		(stroke
			(width 0.2)
			(type default)
		)
		(fill no)
		(layer "In1.Cu")
	)
	(gr_circle
		(center 286.329882 -349.577152)
		(end 287.218882 -349.577152)
		(stroke
			(width 0.2)
			(type default)
		)
		(fill no)
		(layer "In1.Cu")
	)
	(gr_circle
		(center 286.36595 -355.279198)
		(end 287.25495 -355.279198)
		(stroke
			(width 0.2)
			(type default)
		)
		(fill no)
		(layer "In1.Cu")
	)
	(gr_circle
		(center 286.37611 -356.584758)
		(end 287.26511 -356.584758)
		(stroke
			(width 0.2)
			(type default)
		)
		(fill no)
		(layer "In1.Cu")
	)
	(gr_circle
		(center 286.37611 -355.949758)
		(end 287.26511 -355.949758)
		(stroke
			(width 0.2)
			(type default)
		)
		(fill no)
		(layer "In1.Cu")
	)
	(gr_circle
		(center 286.854646 -349.137732)
		(end 287.743646 -349.137732)
		(stroke
			(width 0.2)
			(type default)
		)
		(fill no)
		(layer "In1.Cu")
	)
	(gr_circle
		(center 286.880046 -349.899732)
		(end 287.769046 -349.899732)
		(stroke
			(width 0.2)
			(type default)
		)
		(fill no)
		(layer "In1.Cu")
	)
	(gr_circle
		(center 287.00095 -355.279198)
		(end 287.88995 -355.279198)
		(stroke
			(width 0.2)
			(type default)
		)
		(fill no)
		(layer "In1.Cu")
	)
	(gr_circle
		(center 287.01111 -356.584758)
		(end 287.90011 -356.584758)
		(stroke
			(width 0.2)
			(type default)
		)
		(fill no)
		(layer "In1.Cu")
	)
	(gr_circle
		(center 287.01111 -355.949758)
		(end 287.90011 -355.949758)
		(stroke
			(width 0.2)
			(type default)
		)
		(fill no)
		(layer "In1.Cu")
	)
	(gr_circle
		(center 287.413446 -350.255332)
		(end 288.302446 -350.255332)
		(stroke
			(width 0.2)
			(type default)
		)
		(fill no)
		(layer "In1.Cu")
	)
	(gr_circle
		(center 287.413446 -349.518732)
		(end 288.302446 -349.518732)
		(stroke
			(width 0.2)
			(type default)
		)
		(fill no)
		(layer "In1.Cu")
	)
	(gr_circle
		(center 287.413446 -348.782132)
		(end 288.302446 -348.782132)
		(stroke
			(width 0.2)
			(type default)
		)
		(fill no)
		(layer "In1.Cu")
	)
	(gr_circle
		(center 287.63595 -355.279198)
		(end 288.52495 -355.279198)
		(stroke
			(width 0.2)
			(type default)
		)
		(fill no)
		(layer "In1.Cu")
	)
	(gr_circle
		(center 287.64611 -356.584758)
		(end 288.53511 -356.584758)
		(stroke
			(width 0.2)
			(type default)
		)
		(fill no)
		(layer "In1.Cu")
	)
	(gr_circle
		(center 287.64611 -355.949758)
		(end 288.53511 -355.949758)
		(stroke
			(width 0.2)
			(type default)
		)
		(fill no)
		(layer "In1.Cu")
	)
	(gr_circle
		(center 288.27095 -355.279198)
		(end 289.15995 -355.279198)
		(stroke
			(width 0.2)
			(type default)
		)
		(fill no)
		(layer "In1.Cu")
	)
	(gr_circle
		(center 288.28111 -356.584758)
		(end 289.17011 -356.584758)
		(stroke
			(width 0.2)
			(type default)
		)
		(fill no)
		(layer "In1.Cu")
	)
	(gr_circle
		(center 288.28111 -355.949758)
		(end 289.17011 -355.949758)
		(stroke
			(width 0.2)
			(type default)
		)
		(fill no)
		(layer "In1.Cu")
	)
	(gr_circle
		(center 288.90595 -355.279198)
		(end 289.79495 -355.279198)
		(stroke
			(width 0.2)
			(type default)
		)
		(fill no)
		(layer "In1.Cu")
	)
	(gr_circle
		(center 288.91611 -356.584758)
		(end 289.80511 -356.584758)
		(stroke
			(width 0.2)
			(type default)
		)
		(fill no)
		(layer "In1.Cu")
	)
	(gr_circle
		(center 288.91611 -355.949758)
		(end 289.80511 -355.949758)
		(stroke
			(width 0.2)
			(type default)
		)
		(fill no)
		(layer "In1.Cu")
	)
	(gr_circle
		(center 292.699186 -348.704662)
		(end 293.579296 -348.704662)
		(stroke
			(width 0.2)
			(type default)
		)
		(fill no)
		(layer "In1.Cu")
	)
	(gr_circle
		(center 293.316406 -348.704662)
		(end 294.196516 -348.704662)
		(stroke
			(width 0.2)
			(type default)
		)
		(fill no)
		(layer "In1.Cu")
	)
	(gr_circle
		(center 293.933626 -348.704662)
		(end 294.813736 -348.704662)
		(stroke
			(width 0.2)
			(type default)
		)
		(fill no)
		(layer "In1.Cu")
	)
	(gr_circle
		(center 294.146986 -347.959172)
		(end 295.035986 -347.959172)
		(stroke
			(width 0.2)
			(type default)
		)
		(fill no)
		(layer "In1.Cu")
	)
	(gr_circle
		(center 294.146986 -347.222572)
		(end 295.035986 -347.222572)
		(stroke
			(width 0.2)
			(type default)
		)
		(fill no)
		(layer "In1.Cu")
	)
	(gr_circle
		(center 294.635682 -350.313752)
		(end 295.524682 -350.313752)
		(stroke
			(width 0.2)
			(type default)
		)
		(fill no)
		(layer "In1.Cu")
	)
	(gr_circle
		(center 294.635682 -349.577152)
		(end 295.524682 -349.577152)
		(stroke
			(width 0.2)
			(type default)
		)
		(fill no)
		(layer "In1.Cu")
	)
	(gr_circle
		(center 295.160446 -349.137732)
		(end 296.049446 -349.137732)
		(stroke
			(width 0.2)
			(type default)
		)
		(fill no)
		(layer "In1.Cu")
	)
	(gr_circle
		(center 295.185846 -349.899732)
		(end 296.074846 -349.899732)
		(stroke
			(width 0.2)
			(type default)
		)
		(fill no)
		(layer "In1.Cu")
	)
	(gr_circle
		(center 295.719246 -350.255332)
		(end 296.608246 -350.255332)
		(stroke
			(width 0.2)
			(type default)
		)
		(fill no)
		(layer "In1.Cu")
	)
	(gr_circle
		(center 295.719246 -349.518732)
		(end 296.608246 -349.518732)
		(stroke
			(width 0.2)
			(type default)
		)
		(fill no)
		(layer "In1.Cu")
	)
	(gr_circle
		(center 295.719246 -348.782132)
		(end 296.608246 -348.782132)
		(stroke
			(width 0.2)
			(type default)
		)
		(fill no)
		(layer "In1.Cu")
	)
	(gr_circle
		(center 296.29989 -358.769666)
		(end 297.69689 -358.769666)
		(stroke
			(width 0.2)
			(type default)
		)
		(fill no)
		(layer "In1.Cu")
	)
	(gr_circle
		(center 301.055786 -348.704662)
		(end 301.935896 -348.704662)
		(stroke
			(width 0.2)
			(type default)
		)
		(fill no)
		(layer "In1.Cu")
	)
	(gr_circle
		(center 301.673006 -348.704662)
		(end 302.553116 -348.704662)
		(stroke
			(width 0.2)
			(type default)
		)
		(fill no)
		(layer "In1.Cu")
	)
	(gr_circle
		(center 302.290226 -348.704662)
		(end 303.170336 -348.704662)
		(stroke
			(width 0.2)
			(type default)
		)
		(fill no)
		(layer "In1.Cu")
	)
	(gr_circle
		(center 302.526446 -348.002352)
		(end 303.415446 -348.002352)
		(stroke
			(width 0.2)
			(type default)
		)
		(fill no)
		(layer "In1.Cu")
	)
	(gr_circle
		(center 302.526446 -347.265752)
		(end 303.415446 -347.265752)
		(stroke
			(width 0.2)
			(type default)
		)
		(fill no)
		(layer "In1.Cu")
	)
	(gr_circle
		(center 302.992282 -350.313752)
		(end 303.881282 -350.313752)
		(stroke
			(width 0.2)
			(type default)
		)
		(fill no)
		(layer "In1.Cu")
	)
	(gr_circle
		(center 302.992282 -349.577152)
		(end 303.881282 -349.577152)
		(stroke
			(width 0.2)
			(type default)
		)
		(fill no)
		(layer "In1.Cu")
	)
	(gr_circle
		(center 303.517046 -349.137732)
		(end 304.406046 -349.137732)
		(stroke
			(width 0.2)
			(type default)
		)
		(fill no)
		(layer "In1.Cu")
	)
	(gr_circle
		(center 303.542446 -349.899732)
		(end 304.431446 -349.899732)
		(stroke
			(width 0.2)
			(type default)
		)
		(fill no)
		(layer "In1.Cu")
	)
	(gr_circle
		(center 304.075846 -350.255332)
		(end 304.964846 -350.255332)
		(stroke
			(width 0.2)
			(type default)
		)
		(fill no)
		(layer "In1.Cu")
	)
	(gr_circle
		(center 304.075846 -349.518732)
		(end 304.964846 -349.518732)
		(stroke
			(width 0.2)
			(type default)
		)
		(fill no)
		(layer "In1.Cu")
	)
	(gr_circle
		(center 304.075846 -348.782132)
		(end 304.964846 -348.782132)
		(stroke
			(width 0.2)
			(type default)
		)
		(fill no)
		(layer "In1.Cu")
	)
	(gr_circle
		(center 309.386986 -348.704662)
		(end 310.267096 -348.704662)
		(stroke
			(width 0.2)
			(type default)
		)
		(fill no)
		(layer "In1.Cu")
	)
	(gr_circle
		(center 310.004206 -348.704662)
		(end 310.884316 -348.704662)
		(stroke
			(width 0.2)
			(type default)
		)
		(fill no)
		(layer "In1.Cu")
	)
	(gr_circle
		(center 310.621426 -348.704662)
		(end 311.501536 -348.704662)
		(stroke
			(width 0.2)
			(type default)
		)
		(fill no)
		(layer "In1.Cu")
	)
	(gr_circle
		(center 310.867806 -348.002352)
		(end 311.756806 -348.002352)
		(stroke
			(width 0.2)
			(type default)
		)
		(fill no)
		(layer "In1.Cu")
	)
	(gr_circle
		(center 310.867806 -347.265752)
		(end 311.756806 -347.265752)
		(stroke
			(width 0.2)
			(type default)
		)
		(fill no)
		(layer "In1.Cu")
	)
	(gr_circle
		(center 311.323482 -350.313752)
		(end 312.212482 -350.313752)
		(stroke
			(width 0.2)
			(type default)
		)
		(fill no)
		(layer "In1.Cu")
	)
	(gr_circle
		(center 311.323482 -349.577152)
		(end 312.212482 -349.577152)
		(stroke
			(width 0.2)
			(type default)
		)
		(fill no)
		(layer "In1.Cu")
	)
	(gr_circle
		(center 311.848246 -349.137732)
		(end 312.737246 -349.137732)
		(stroke
			(width 0.2)
			(type default)
		)
		(fill no)
		(layer "In1.Cu")
	)
	(gr_circle
		(center 311.873646 -349.899732)
		(end 312.762646 -349.899732)
		(stroke
			(width 0.2)
			(type default)
		)
		(fill no)
		(layer "In1.Cu")
	)
	(gr_circle
		(center 312.407046 -350.255332)
		(end 313.296046 -350.255332)
		(stroke
			(width 0.2)
			(type default)
		)
		(fill no)
		(layer "In1.Cu")
	)
	(gr_circle
		(center 312.407046 -349.518732)
		(end 313.296046 -349.518732)
		(stroke
			(width 0.2)
			(type default)
		)
		(fill no)
		(layer "In1.Cu")
	)
	(gr_circle
		(center 312.407046 -348.782132)
		(end 313.296046 -348.782132)
		(stroke
			(width 0.2)
			(type default)
		)
		(fill no)
		(layer "In1.Cu")
	)
	(gr_circle
		(center 319.0367 -336.983578)
		(end 319.91681 -336.983578)
		(stroke
			(width 0.2)
			(type default)
		)
		(fill no)
		(layer "In1.Cu")
	)
	(gr_circle
		(center 319.65392 -336.983578)
		(end 320.53403 -336.983578)
		(stroke
			(width 0.2)
			(type default)
		)
		(fill no)
		(layer "In1.Cu")
	)
	(gr_circle
		(center 320.27114 -336.983578)
		(end 321.15125 -336.983578)
		(stroke
			(width 0.2)
			(type default)
		)
		(fill no)
		(layer "In1.Cu")
	)
	(gr_circle
		(center 320.5607 -336.239612)
		(end 321.4497 -336.239612)
		(stroke
			(width 0.2)
			(type default)
		)
		(fill no)
		(layer "In1.Cu")
	)
	(gr_circle
		(center 320.5607 -335.503012)
		(end 321.4497 -335.503012)
		(stroke
			(width 0.2)
			(type default)
		)
		(fill no)
		(layer "In1.Cu")
	)
	(gr_circle
		(center 320.973196 -338.592668)
		(end 321.862196 -338.592668)
		(stroke
			(width 0.2)
			(type default)
		)
		(fill no)
		(layer "In1.Cu")
	)
	(gr_circle
		(center 320.973196 -337.856068)
		(end 321.862196 -337.856068)
		(stroke
			(width 0.2)
			(type default)
		)
		(fill no)
		(layer "In1.Cu")
	)
	(gr_circle
		(center 321.49796 -337.416648)
		(end 322.38696 -337.416648)
		(stroke
			(width 0.2)
			(type default)
		)
		(fill no)
		(layer "In1.Cu")
	)
	(gr_circle
		(center 321.52336 -338.178648)
		(end 322.41236 -338.178648)
		(stroke
			(width 0.2)
			(type default)
		)
		(fill no)
		(layer "In1.Cu")
	)
	(gr_circle
		(center 322.05676 -338.534248)
		(end 322.94576 -338.534248)
		(stroke
			(width 0.2)
			(type default)
		)
		(fill no)
		(layer "In1.Cu")
	)
	(gr_circle
		(center 322.05676 -337.797648)
		(end 322.94576 -337.797648)
		(stroke
			(width 0.2)
			(type default)
		)
		(fill no)
		(layer "In1.Cu")
	)
	(gr_circle
		(center 322.05676 -337.061048)
		(end 322.94576 -337.061048)
		(stroke
			(width 0.2)
			(type default)
		)
		(fill no)
		(layer "In1.Cu")
	)
	(gr_circle
		(center 327.392284 -336.976466)
		(end 328.272394 -336.976466)
		(stroke
			(width 0.2)
			(type default)
		)
		(fill no)
		(layer "In1.Cu")
	)
	(gr_circle
		(center 327.692258 -104.30129)
		(end 328.581258 -104.30129)
		(stroke
			(width 0.2)
			(type default)
		)
		(fill no)
		(layer "In1.Cu")
	)
	(gr_circle
		(center 327.951084 -349.43161)
		(end 329.348084 -349.43161)
		(stroke
			(width 0.2)
			(type default)
		)
		(fill no)
		(layer "In1.Cu")
	)
	(gr_circle
		(center 328.009504 -336.976466)
		(end 328.889614 -336.976466)
		(stroke
			(width 0.2)
			(type default)
		)
		(fill no)
		(layer "In1.Cu")
	)
	(gr_circle
		(center 328.626724 -336.976466)
		(end 329.506834 -336.976466)
		(stroke
			(width 0.2)
			(type default)
		)
		(fill no)
		(layer "In1.Cu")
	)
	(gr_circle
		(center 328.918824 -336.253836)
		(end 329.807824 -336.253836)
		(stroke
			(width 0.2)
			(type default)
		)
		(fill no)
		(layer "In1.Cu")
	)
	(gr_circle
		(center 328.918824 -335.517236)
		(end 329.807824 -335.517236)
		(stroke
			(width 0.2)
			(type default)
		)
		(fill no)
		(layer "In1.Cu")
	)
	(gr_circle
		(center 329.32878 -338.585556)
		(end 330.21778 -338.585556)
		(stroke
			(width 0.2)
			(type default)
		)
		(fill no)
		(layer "In1.Cu")
	)
	(gr_circle
		(center 329.32878 -337.848956)
		(end 330.21778 -337.848956)
		(stroke
			(width 0.2)
			(type default)
		)
		(fill no)
		(layer "In1.Cu")
	)
	(gr_circle
		(center 329.853544 -337.409536)
		(end 330.742544 -337.409536)
		(stroke
			(width 0.2)
			(type default)
		)
		(fill no)
		(layer "In1.Cu")
	)
	(gr_circle
		(center 329.878944 -338.171536)
		(end 330.767944 -338.171536)
		(stroke
			(width 0.2)
			(type default)
		)
		(fill no)
		(layer "In1.Cu")
	)
	(gr_circle
		(center 330.412344 -338.527136)
		(end 331.301344 -338.527136)
		(stroke
			(width 0.2)
			(type default)
		)
		(fill no)
		(layer "In1.Cu")
	)
	(gr_circle
		(center 330.412344 -337.790536)
		(end 331.301344 -337.790536)
		(stroke
			(width 0.2)
			(type default)
		)
		(fill no)
		(layer "In1.Cu")
	)
	(gr_circle
		(center 330.412344 -337.053936)
		(end 331.301344 -337.053936)
		(stroke
			(width 0.2)
			(type default)
		)
		(fill no)
		(layer "In1.Cu")
	)
	(gr_circle
		(center 335.411064 -349.43161)
		(end 336.808064 -349.43161)
		(stroke
			(width 0.2)
			(type default)
		)
		(fill no)
		(layer "In1.Cu")
	)
	(gr_circle
		(center 335.7499 -336.961988)
		(end 336.63001 -336.961988)
		(stroke
			(width 0.2)
			(type default)
		)
		(fill no)
		(layer "In1.Cu")
	)
	(gr_circle
		(center 336.36712 -336.961988)
		(end 337.24723 -336.961988)
		(stroke
			(width 0.2)
			(type default)
		)
		(fill no)
		(layer "In1.Cu")
	)
	(gr_circle
		(center 336.98434 -336.961988)
		(end 337.86445 -336.961988)
		(stroke
			(width 0.2)
			(type default)
		)
		(fill no)
		(layer "In1.Cu")
	)
	(gr_circle
		(center 337.280504 -336.253836)
		(end 338.169504 -336.253836)
		(stroke
			(width 0.2)
			(type default)
		)
		(fill no)
		(layer "In1.Cu")
	)
	(gr_circle
		(center 337.280504 -335.517236)
		(end 338.169504 -335.517236)
		(stroke
			(width 0.2)
			(type default)
		)
		(fill no)
		(layer "In1.Cu")
	)
	(gr_circle
		(center 337.686396 -338.571078)
		(end 338.575396 -338.571078)
		(stroke
			(width 0.2)
			(type default)
		)
		(fill no)
		(layer "In1.Cu")
	)
	(gr_circle
		(center 337.686396 -337.834478)
		(end 338.575396 -337.834478)
		(stroke
			(width 0.2)
			(type default)
		)
		(fill no)
		(layer "In1.Cu")
	)
	(gr_circle
		(center 338.21116 -337.395058)
		(end 339.10016 -337.395058)
		(stroke
			(width 0.2)
			(type default)
		)
		(fill no)
		(layer "In1.Cu")
	)
	(gr_circle
		(center 338.23656 -338.157058)
		(end 339.12556 -338.157058)
		(stroke
			(width 0.2)
			(type default)
		)
		(fill no)
		(layer "In1.Cu")
	)
	(gr_circle
		(center 338.76996 -338.512658)
		(end 339.65896 -338.512658)
		(stroke
			(width 0.2)
			(type default)
		)
		(fill no)
		(layer "In1.Cu")
	)
	(gr_circle
		(center 338.76996 -337.776058)
		(end 339.65896 -337.776058)
		(stroke
			(width 0.2)
			(type default)
		)
		(fill no)
		(layer "In1.Cu")
	)
	(gr_circle
		(center 338.76996 -337.039458)
		(end 339.65896 -337.039458)
		(stroke
			(width 0.2)
			(type default)
		)
		(fill no)
		(layer "In1.Cu")
	)
	(gr_circle
		(center 339.73897 -352.973132)
		(end 340.62797 -352.973132)
		(stroke
			(width 0.2)
			(type default)
		)
		(fill no)
		(layer "In1.Cu")
	)
	(gr_circle
		(center 339.739224 -352.215196)
		(end 340.628224 -352.215196)
		(stroke
			(width 0.2)
			(type default)
		)
		(fill no)
		(layer "In1.Cu")
	)
	(gr_circle
		(center 339.739224 -351.453196)
		(end 340.628224 -351.453196)
		(stroke
			(width 0.2)
			(type default)
		)
		(fill no)
		(layer "In1.Cu")
	)
	(gr_circle
		(center 340.501224 -352.215196)
		(end 341.390224 -352.215196)
		(stroke
			(width 0.2)
			(type default)
		)
		(fill no)
		(layer "In1.Cu")
	)
	(gr_circle
		(center 340.501224 -351.453196)
		(end 341.390224 -351.453196)
		(stroke
			(width 0.2)
			(type default)
		)
		(fill no)
		(layer "In1.Cu")
	)
	(gr_circle
		(center 340.667848 -353.010216)
		(end 341.556848 -353.010216)
		(stroke
			(width 0.2)
			(type default)
		)
		(fill no)
		(layer "In1.Cu")
	)
	(gr_circle
		(center 341.263224 -352.215196)
		(end 342.152224 -352.215196)
		(stroke
			(width 0.2)
			(type default)
		)
		(fill no)
		(layer "In1.Cu")
	)
	(gr_circle
		(center 341.263224 -351.453196)
		(end 342.152224 -351.453196)
		(stroke
			(width 0.2)
			(type default)
		)
		(fill no)
		(layer "In1.Cu")
	)
	(gr_circle
		(center 341.302848 -353.010216)
		(end 342.191848 -353.010216)
		(stroke
			(width 0.2)
			(type default)
		)
		(fill no)
		(layer "In1.Cu")
	)
	(gr_circle
		(center 341.937848 -353.010216)
		(end 342.826848 -353.010216)
		(stroke
			(width 0.2)
			(type default)
		)
		(fill no)
		(layer "In1.Cu")
	)
	(gr_circle
		(center 342.025224 -352.215196)
		(end 342.914224 -352.215196)
		(stroke
			(width 0.2)
			(type default)
		)
		(fill no)
		(layer "In1.Cu")
	)
	(gr_circle
		(center 342.025224 -351.453196)
		(end 342.914224 -351.453196)
		(stroke
			(width 0.2)
			(type default)
		)
		(fill no)
		(layer "In1.Cu")
	)
	(gr_circle
		(center 342.572848 -353.010216)
		(end 343.461848 -353.010216)
		(stroke
			(width 0.2)
			(type default)
		)
		(fill no)
		(layer "In1.Cu")
	)
	(gr_circle
		(center 342.787224 -352.215196)
		(end 343.676224 -352.215196)
		(stroke
			(width 0.2)
			(type default)
		)
		(fill no)
		(layer "In1.Cu")
	)
	(gr_circle
		(center 342.787224 -351.453196)
		(end 343.676224 -351.453196)
		(stroke
			(width 0.2)
			(type default)
		)
		(fill no)
		(layer "In1.Cu")
	)
	(gr_circle
		(center 343.46515 -353.006152)
		(end 344.35415 -353.006152)
		(stroke
			(width 0.2)
			(type default)
		)
		(fill no)
		(layer "In1.Cu")
	)
	(gr_circle
		(center 343.465404 -352.248216)
		(end 344.354404 -352.248216)
		(stroke
			(width 0.2)
			(type default)
		)
		(fill no)
		(layer "In1.Cu")
	)
	(gr_circle
		(center 343.465404 -351.486216)
		(end 344.354404 -351.486216)
		(stroke
			(width 0.2)
			(type default)
		)
		(fill no)
		(layer "In1.Cu")
	)
	(gr_circle
		(center 344.016838 -159.073596)
		(end 344.905838 -159.073596)
		(stroke
			(width 0.2)
			(type default)
		)
		(fill no)
		(layer "In1.Cu")
	)
	(gr_circle
		(center 344.016838 -158.336996)
		(end 344.905838 -158.336996)
		(stroke
			(width 0.2)
			(type default)
		)
		(fill no)
		(layer "In1.Cu")
	)
	(gr_circle
		(center 344.016838 -157.600396)
		(end 344.905838 -157.600396)
		(stroke
			(width 0.2)
			(type default)
		)
		(fill no)
		(layer "In1.Cu")
	)
	(gr_circle
		(center 344.0811 -337.012788)
		(end 344.96121 -337.012788)
		(stroke
			(width 0.2)
			(type default)
		)
		(fill no)
		(layer "In1.Cu")
	)
	(gr_circle
		(center 344.550238 -157.955996)
		(end 345.439238 -157.955996)
		(stroke
			(width 0.2)
			(type default)
		)
		(fill no)
		(layer "In1.Cu")
	)
	(gr_circle
		(center 344.575638 -158.717996)
		(end 345.464638 -158.717996)
		(stroke
			(width 0.2)
			(type default)
		)
		(fill no)
		(layer "In1.Cu")
	)
	(gr_circle
		(center 344.69832 -337.012788)
		(end 345.57843 -337.012788)
		(stroke
			(width 0.2)
			(type default)
		)
		(fill no)
		(layer "In1.Cu")
	)
	(gr_circle
		(center 345.100402 -158.278576)
		(end 345.989402 -158.278576)
		(stroke
			(width 0.2)
			(type default)
		)
		(fill no)
		(layer "In1.Cu")
	)
	(gr_circle
		(center 345.100402 -157.541976)
		(end 345.989402 -157.541976)
		(stroke
			(width 0.2)
			(type default)
		)
		(fill no)
		(layer "In1.Cu")
	)
	(gr_circle
		(center 345.31554 -337.012788)
		(end 346.19565 -337.012788)
		(stroke
			(width 0.2)
			(type default)
		)
		(fill no)
		(layer "In1.Cu")
	)
	(gr_circle
		(center 345.623896 -336.317336)
		(end 346.512896 -336.317336)
		(stroke
			(width 0.2)
			(type default)
		)
		(fill no)
		(layer "In1.Cu")
	)
	(gr_circle
		(center 345.623896 -335.580736)
		(end 346.512896 -335.580736)
		(stroke
			(width 0.2)
			(type default)
		)
		(fill no)
		(layer "In1.Cu")
	)
	(gr_circle
		(center 345.684856 -160.633156)
		(end 346.573856 -160.633156)
		(stroke
			(width 0.2)
			(type default)
		)
		(fill no)
		(layer "In1.Cu")
	)
	(gr_circle
		(center 345.684856 -159.896556)
		(end 346.573856 -159.896556)
		(stroke
			(width 0.2)
			(type default)
		)
		(fill no)
		(layer "In1.Cu")
	)
	(gr_circle
		(center 345.802458 -159.151066)
		(end 346.682568 -159.151066)
		(stroke
			(width 0.2)
			(type default)
		)
		(fill no)
		(layer "In1.Cu")
	)
	(gr_circle
		(center 346.017596 -339.358478)
		(end 346.906596 -339.358478)
		(stroke
			(width 0.2)
			(type default)
		)
		(fill no)
		(layer "In1.Cu")
	)
	(gr_circle
		(center 346.017596 -338.621878)
		(end 346.906596 -338.621878)
		(stroke
			(width 0.2)
			(type default)
		)
		(fill no)
		(layer "In1.Cu")
	)
	(gr_circle
		(center 346.017596 -337.885278)
		(end 346.906596 -337.885278)
		(stroke
			(width 0.2)
			(type default)
		)
		(fill no)
		(layer "In1.Cu")
	)
	(gr_circle
		(center 346.419678 -159.151066)
		(end 347.299788 -159.151066)
		(stroke
			(width 0.2)
			(type default)
		)
		(fill no)
		(layer "In1.Cu")
	)
	(gr_circle
		(center 346.54236 -337.445858)
		(end 347.43136 -337.445858)
		(stroke
			(width 0.2)
			(type default)
		)
		(fill no)
		(layer "In1.Cu")
	)
	(gr_circle
		(center 346.56776 -339.731858)
		(end 347.45676 -339.731858)
		(stroke
			(width 0.2)
			(type default)
		)
		(fill no)
		(layer "In1.Cu")
	)
	(gr_circle
		(center 346.56776 -338.969858)
		(end 347.45676 -338.969858)
		(stroke
			(width 0.2)
			(type default)
		)
		(fill no)
		(layer "In1.Cu")
	)
	(gr_circle
		(center 346.56776 -338.207858)
		(end 347.45676 -338.207858)
		(stroke
			(width 0.2)
			(type default)
		)
		(fill no)
		(layer "In1.Cu")
	)
	(gr_circle
		(center 347.036898 -159.151066)
		(end 347.917008 -159.151066)
		(stroke
			(width 0.2)
			(type default)
		)
		(fill no)
		(layer "In1.Cu")
	)
	(gr_circle
		(center 352.322638 -167.430196)
		(end 353.211638 -167.430196)
		(stroke
			(width 0.2)
			(type default)
		)
		(fill no)
		(layer "In1.Cu")
	)
	(gr_circle
		(center 352.322638 -166.693596)
		(end 353.211638 -166.693596)
		(stroke
			(width 0.2)
			(type default)
		)
		(fill no)
		(layer "In1.Cu")
	)
	(gr_circle
		(center 352.322638 -165.956996)
		(end 353.211638 -165.956996)
		(stroke
			(width 0.2)
			(type default)
		)
		(fill no)
		(layer "In1.Cu")
	)
	(gr_circle
		(center 352.356928 -341.922862)
		(end 353.237038 -341.922862)
		(stroke
			(width 0.2)
			(type default)
		)
		(fill no)
		(layer "In1.Cu")
	)
	(gr_circle
		(center 352.856038 -166.312596)
		(end 353.745038 -166.312596)
		(stroke
			(width 0.2)
			(type default)
		)
		(fill no)
		(layer "In1.Cu")
	)
	(gr_circle
		(center 352.881438 -167.074596)
		(end 353.770438 -167.074596)
		(stroke
			(width 0.2)
			(type default)
		)
		(fill no)
		(layer "In1.Cu")
	)
	(gr_circle
		(center 352.974148 -341.922862)
		(end 353.854258 -341.922862)
		(stroke
			(width 0.2)
			(type default)
		)
		(fill no)
		(layer "In1.Cu")
	)
	(gr_circle
		(center 353.406202 -166.635176)
		(end 354.295202 -166.635176)
		(stroke
			(width 0.2)
			(type default)
		)
		(fill no)
		(layer "In1.Cu")
	)
	(gr_circle
		(center 353.406202 -165.898576)
		(end 354.295202 -165.898576)
		(stroke
			(width 0.2)
			(type default)
		)
		(fill no)
		(layer "In1.Cu")
	)
	(gr_circle
		(center 353.591368 -341.922862)
		(end 354.471478 -341.922862)
		(stroke
			(width 0.2)
			(type default)
		)
		(fill no)
		(layer "In1.Cu")
	)
	(gr_circle
		(center 353.899724 -341.22741)
		(end 354.788724 -341.22741)
		(stroke
			(width 0.2)
			(type default)
		)
		(fill no)
		(layer "In1.Cu")
	)
	(gr_circle
		(center 353.899724 -340.49081)
		(end 354.788724 -340.49081)
		(stroke
			(width 0.2)
			(type default)
		)
		(fill no)
		(layer "In1.Cu")
	)
	(gr_circle
		(center 353.990656 -168.982136)
		(end 354.879656 -168.982136)
		(stroke
			(width 0.2)
			(type default)
		)
		(fill no)
		(layer "In1.Cu")
	)
	(gr_circle
		(center 353.990656 -168.245536)
		(end 354.879656 -168.245536)
		(stroke
			(width 0.2)
			(type default)
		)
		(fill no)
		(layer "In1.Cu")
	)
	(gr_circle
		(center 354.108258 -167.507666)
		(end 354.988368 -167.507666)
		(stroke
			(width 0.2)
			(type default)
		)
		(fill no)
		(layer "In1.Cu")
	)
	(gr_circle
		(center 354.293424 -343.531952)
		(end 355.182424 -343.531952)
		(stroke
			(width 0.2)
			(type default)
		)
		(fill no)
		(layer "In1.Cu")
	)
	(gr_circle
		(center 354.293424 -342.795352)
		(end 355.182424 -342.795352)
		(stroke
			(width 0.2)
			(type default)
		)
		(fill no)
		(layer "In1.Cu")
	)
	(gr_circle
		(center 354.725478 -167.507666)
		(end 355.605588 -167.507666)
		(stroke
			(width 0.2)
			(type default)
		)
		(fill no)
		(layer "In1.Cu")
	)
	(gr_circle
		(center 354.818188 -342.355932)
		(end 355.707188 -342.355932)
		(stroke
			(width 0.2)
			(type default)
		)
		(fill no)
		(layer "In1.Cu")
	)
	(gr_circle
		(center 354.843588 -343.117932)
		(end 355.732588 -343.117932)
		(stroke
			(width 0.2)
			(type default)
		)
		(fill no)
		(layer "In1.Cu")
	)
	(gr_circle
		(center 355.342698 -167.507666)
		(end 356.222808 -167.507666)
		(stroke
			(width 0.2)
			(type default)
		)
		(fill no)
		(layer "In1.Cu")
	)
	(gr_circle
		(center 355.376988 -343.473532)
		(end 356.265988 -343.473532)
		(stroke
			(width 0.2)
			(type default)
		)
		(fill no)
		(layer "In1.Cu")
	)
	(gr_circle
		(center 355.376988 -342.736932)
		(end 356.265988 -342.736932)
		(stroke
			(width 0.2)
			(type default)
		)
		(fill no)
		(layer "In1.Cu")
	)
	(gr_circle
		(center 355.376988 -342.000332)
		(end 356.265988 -342.000332)
		(stroke
			(width 0.2)
			(type default)
		)
		(fill no)
		(layer "In1.Cu")
	)
	(gr_circle
		(center 359.58526 -152.71242)
		(end 360.98226 -152.71242)
		(stroke
			(width 0.2)
			(type default)
		)
		(fill no)
		(layer "In1.Cu")
	)
	(gr_circle
		(center 360.603038 -175.705516)
		(end 361.492038 -175.705516)
		(stroke
			(width 0.2)
			(type default)
		)
		(fill no)
		(layer "In1.Cu")
	)
	(gr_circle
		(center 360.603038 -174.968916)
		(end 361.492038 -174.968916)
		(stroke
			(width 0.2)
			(type default)
		)
		(fill no)
		(layer "In1.Cu")
	)
	(gr_circle
		(center 360.603038 -174.232316)
		(end 361.492038 -174.232316)
		(stroke
			(width 0.2)
			(type default)
		)
		(fill no)
		(layer "In1.Cu")
	)
	(gr_circle
		(center 361.136438 -174.587916)
		(end 362.025438 -174.587916)
		(stroke
			(width 0.2)
			(type default)
		)
		(fill no)
		(layer "In1.Cu")
	)
	(gr_circle
		(center 361.161838 -175.349916)
		(end 362.050838 -175.349916)
		(stroke
			(width 0.2)
			(type default)
		)
		(fill no)
		(layer "In1.Cu")
	)
	(gr_circle
		(center 361.686602 -174.910496)
		(end 362.575602 -174.910496)
		(stroke
			(width 0.2)
			(type default)
		)
		(fill no)
		(layer "In1.Cu")
	)
	(gr_circle
		(center 361.686602 -174.173896)
		(end 362.575602 -174.173896)
		(stroke
			(width 0.2)
			(type default)
		)
		(fill no)
		(layer "In1.Cu")
	)
	(gr_circle
		(center 362.271056 -177.254916)
		(end 363.160056 -177.254916)
		(stroke
			(width 0.2)
			(type default)
		)
		(fill no)
		(layer "In1.Cu")
	)
	(gr_circle
		(center 362.271056 -176.518316)
		(end 363.160056 -176.518316)
		(stroke
			(width 0.2)
			(type default)
		)
		(fill no)
		(layer "In1.Cu")
	)
	(gr_circle
		(center 362.396278 -175.859186)
		(end 363.276388 -175.859186)
		(stroke
			(width 0.2)
			(type default)
		)
		(fill no)
		(layer "In1.Cu")
	)
	(gr_circle
		(center 363.013498 -175.859186)
		(end 363.893608 -175.859186)
		(stroke
			(width 0.2)
			(type default)
		)
		(fill no)
		(layer "In1.Cu")
	)
	(gr_circle
		(center 363.630718 -175.859186)
		(end 364.510828 -175.859186)
		(stroke
			(width 0.2)
			(type default)
		)
		(fill no)
		(layer "In1.Cu")
	)
	(gr_circle
		(center 366.744504 -164.53358)
		(end 367.633504 -164.53358)
		(stroke
			(width 0.2)
			(type default)
		)
		(fill no)
		(layer "In1.Cu")
	)
	(gr_circle
		(center 366.744504 -163.89858)
		(end 367.633504 -163.89858)
		(stroke
			(width 0.2)
			(type default)
		)
		(fill no)
		(layer "In1.Cu")
	)
	(gr_circle
		(center 366.757204 -165.19398)
		(end 367.646204 -165.19398)
		(stroke
			(width 0.2)
			(type default)
		)
		(fill no)
		(layer "In1.Cu")
	)
	(gr_circle
		(center 367.379504 -164.53358)
		(end 368.268504 -164.53358)
		(stroke
			(width 0.2)
			(type default)
		)
		(fill no)
		(layer "In1.Cu")
	)
	(gr_circle
		(center 367.379504 -163.89858)
		(end 368.268504 -163.89858)
		(stroke
			(width 0.2)
			(type default)
		)
		(fill no)
		(layer "In1.Cu")
	)
	(gr_circle
		(center 367.392204 -165.19398)
		(end 368.281204 -165.19398)
		(stroke
			(width 0.2)
			(type default)
		)
		(fill no)
		(layer "In1.Cu")
	)
	(gr_circle
		(center 368.044984 -164.53358)
		(end 368.933984 -164.53358)
		(stroke
			(width 0.2)
			(type default)
		)
		(fill no)
		(layer "In1.Cu")
	)
	(gr_circle
		(center 368.044984 -163.89858)
		(end 368.933984 -163.89858)
		(stroke
			(width 0.2)
			(type default)
		)
		(fill no)
		(layer "In1.Cu")
	)
	(gr_circle
		(center 368.057684 -165.19398)
		(end 368.946684 -165.19398)
		(stroke
			(width 0.2)
			(type default)
		)
		(fill no)
		(layer "In1.Cu")
	)
	(gr_circle
		(center 368.679984 -164.53358)
		(end 369.568984 -164.53358)
		(stroke
			(width 0.2)
			(type default)
		)
		(fill no)
		(layer "In1.Cu")
	)
	(gr_circle
		(center 368.679984 -163.89858)
		(end 369.568984 -163.89858)
		(stroke
			(width 0.2)
			(type default)
		)
		(fill no)
		(layer "In1.Cu")
	)
	(gr_circle
		(center 368.692684 -165.19398)
		(end 369.581684 -165.19398)
		(stroke
			(width 0.2)
			(type default)
		)
		(fill no)
		(layer "In1.Cu")
	)
	(gr_circle
		(center 368.96421 -179.204874)
		(end 369.85321 -179.204874)
		(stroke
			(width 0.2)
			(type default)
		)
		(fill no)
		(layer "In1.Cu")
	)
	(gr_circle
		(center 369.314984 -164.53358)
		(end 370.203984 -164.53358)
		(stroke
			(width 0.2)
			(type default)
		)
		(fill no)
		(layer "In1.Cu")
	)
	(gr_circle
		(center 369.314984 -163.89858)
		(end 370.203984 -163.89858)
		(stroke
			(width 0.2)
			(type default)
		)
		(fill no)
		(layer "In1.Cu")
	)
	(gr_circle
		(center 369.327684 -165.19398)
		(end 370.216684 -165.19398)
		(stroke
			(width 0.2)
			(type default)
		)
		(fill no)
		(layer "In1.Cu")
	)
	(gr_circle
		(center 369.49761 -179.560474)
		(end 370.38661 -179.560474)
		(stroke
			(width 0.2)
			(type default)
		)
		(fill no)
		(layer "In1.Cu")
	)
	(gr_circle
		(center 369.49761 -178.798474)
		(end 370.38661 -178.798474)
		(stroke
			(width 0.2)
			(type default)
		)
		(fill no)
		(layer "In1.Cu")
	)
	(gr_circle
		(center 369.49761 -178.036474)
		(end 370.38661 -178.036474)
		(stroke
			(width 0.2)
			(type default)
		)
		(fill no)
		(layer "In1.Cu")
	)
	(gr_circle
		(center 369.52301 -180.322474)
		(end 370.41201 -180.322474)
		(stroke
			(width 0.2)
			(type default)
		)
		(fill no)
		(layer "In1.Cu")
	)
	(gr_circle
		(center 369.949984 -164.53358)
		(end 370.838984 -164.53358)
		(stroke
			(width 0.2)
			(type default)
		)
		(fill no)
		(layer "In1.Cu")
	)
	(gr_circle
		(center 369.949984 -163.89858)
		(end 370.838984 -163.89858)
		(stroke
			(width 0.2)
			(type default)
		)
		(fill no)
		(layer "In1.Cu")
	)
	(gr_circle
		(center 369.962684 -165.19398)
		(end 370.851684 -165.19398)
		(stroke
			(width 0.2)
			(type default)
		)
		(fill no)
		(layer "In1.Cu")
	)
	(gr_circle
		(center 370.047774 -179.883054)
		(end 370.936774 -179.883054)
		(stroke
			(width 0.2)
			(type default)
		)
		(fill no)
		(layer "In1.Cu")
	)
	(gr_circle
		(center 370.047774 -179.146454)
		(end 370.936774 -179.146454)
		(stroke
			(width 0.2)
			(type default)
		)
		(fill no)
		(layer "In1.Cu")
	)
	(gr_circle
		(center 370.529358 -182.141876)
		(end 371.418358 -182.141876)
		(stroke
			(width 0.2)
			(type default)
		)
		(fill no)
		(layer "In1.Cu")
	)
	(gr_circle
		(center 370.529358 -181.405276)
		(end 371.418358 -181.405276)
		(stroke
			(width 0.2)
			(type default)
		)
		(fill no)
		(layer "In1.Cu")
	)
	(gr_circle
		(center 370.686584 -164.53358)
		(end 371.575584 -164.53358)
		(stroke
			(width 0.2)
			(type default)
		)
		(fill no)
		(layer "In1.Cu")
	)
	(gr_circle
		(center 370.686584 -163.89858)
		(end 371.575584 -163.89858)
		(stroke
			(width 0.2)
			(type default)
		)
		(fill no)
		(layer "In1.Cu")
	)
	(gr_circle
		(center 370.699284 -165.19398)
		(end 371.588284 -165.19398)
		(stroke
			(width 0.2)
			(type default)
		)
		(fill no)
		(layer "In1.Cu")
	)
	(gr_circle
		(center 370.74221 -180.803804)
		(end 371.62232 -180.803804)
		(stroke
			(width 0.2)
			(type default)
		)
		(fill no)
		(layer "In1.Cu")
	)
	(gr_circle
		(center 371.35943 -180.803804)
		(end 372.23954 -180.803804)
		(stroke
			(width 0.2)
			(type default)
		)
		(fill no)
		(layer "In1.Cu")
	)
	(gr_circle
		(center 371.97665 -180.803804)
		(end 372.85676 -180.803804)
		(stroke
			(width 0.2)
			(type default)
		)
		(fill no)
		(layer "In1.Cu")
	)
	(gr_circle
		(center 377.367038 -180.678074)
		(end 378.256038 -180.678074)
		(stroke
			(width 0.2)
			(type default)
		)
		(fill no)
		(layer "In1.Cu")
	)
	(gr_circle
		(center 377.367038 -179.941474)
		(end 378.256038 -179.941474)
		(stroke
			(width 0.2)
			(type default)
		)
		(fill no)
		(layer "In1.Cu")
	)
	(gr_circle
		(center 377.367038 -179.204874)
		(end 378.256038 -179.204874)
		(stroke
			(width 0.2)
			(type default)
		)
		(fill no)
		(layer "In1.Cu")
	)
	(gr_circle
		(center 377.869958 -162.59683)
		(end 379.266958 -162.59683)
		(stroke
			(width 0.2)
			(type default)
		)
		(fill no)
		(layer "In1.Cu")
	)
	(gr_circle
		(center 377.900438 -179.560474)
		(end 378.789438 -179.560474)
		(stroke
			(width 0.2)
			(type default)
		)
		(fill no)
		(layer "In1.Cu")
	)
	(gr_circle
		(center 377.925838 -180.322474)
		(end 378.814838 -180.322474)
		(stroke
			(width 0.2)
			(type default)
		)
		(fill no)
		(layer "In1.Cu")
	)
	(gr_circle
		(center 378.450602 -179.883054)
		(end 379.339602 -179.883054)
		(stroke
			(width 0.2)
			(type default)
		)
		(fill no)
		(layer "In1.Cu")
	)
	(gr_circle
		(center 378.450602 -179.146454)
		(end 379.339602 -179.146454)
		(stroke
			(width 0.2)
			(type default)
		)
		(fill no)
		(layer "In1.Cu")
	)
	(gr_circle
		(center 379.035056 -182.230776)
		(end 379.924056 -182.230776)
		(stroke
			(width 0.2)
			(type default)
		)
		(fill no)
		(layer "In1.Cu")
	)
	(gr_circle
		(center 379.035056 -181.494176)
		(end 379.924056 -181.494176)
		(stroke
			(width 0.2)
			(type default)
		)
		(fill no)
		(layer "In1.Cu")
	)
	(gr_circle
		(center 379.152658 -180.755544)
		(end 380.032768 -180.755544)
		(stroke
			(width 0.2)
			(type default)
		)
		(fill no)
		(layer "In1.Cu")
	)
	(gr_circle
		(center 379.769878 -180.755544)
		(end 380.649988 -180.755544)
		(stroke
			(width 0.2)
			(type default)
		)
		(fill no)
		(layer "In1.Cu")
	)
	(gr_circle
		(center 380.387098 -180.755544)
		(end 381.267208 -180.755544)
		(stroke
			(width 0.2)
			(type default)
		)
		(fill no)
		(layer "In1.Cu")
	)
	(gr_arc
		(start 385.601972 -11.780012)
		(mid 387.016183 -11.194227)
		(end 387.601968 -9.780016)
		(stroke
			(width 1.016)
			(type default)
		)
		(layer "In1.Cu")
	)
	(gr_circle
		(center 385.698238 -180.678074)
		(end 386.587238 -180.678074)
		(stroke
			(width 0.2)
			(type default)
		)
		(fill no)
		(layer "In1.Cu")
	)
	(gr_circle
		(center 385.698238 -179.941474)
		(end 386.587238 -179.941474)
		(stroke
			(width 0.2)
			(type default)
		)
		(fill no)
		(layer "In1.Cu")
	)
	(gr_circle
		(center 385.698238 -179.204874)
		(end 386.587238 -179.204874)
		(stroke
			(width 0.2)
			(type default)
		)
		(fill no)
		(layer "In1.Cu")
	)
	(gr_circle
		(center 386.231638 -179.560474)
		(end 387.120638 -179.560474)
		(stroke
			(width 0.2)
			(type default)
		)
		(fill no)
		(layer "In1.Cu")
	)
	(gr_circle
		(center 386.257038 -180.322474)
		(end 387.146038 -180.322474)
		(stroke
			(width 0.2)
			(type default)
		)
		(fill no)
		(layer "In1.Cu")
	)
	(gr_circle
		(center 386.781802 -179.883054)
		(end 387.670802 -179.883054)
		(stroke
			(width 0.2)
			(type default)
		)
		(fill no)
		(layer "In1.Cu")
	)
	(gr_circle
		(center 386.781802 -179.146454)
		(end 387.670802 -179.146454)
		(stroke
			(width 0.2)
			(type default)
		)
		(fill no)
		(layer "In1.Cu")
	)
	(gr_circle
		(center 387.206998 -162.65271)
		(end 388.603998 -162.65271)
		(stroke
			(width 0.2)
			(type default)
		)
		(fill no)
		(layer "In1.Cu")
	)
	(gr_circle
		(center 387.293358 -157.001972)
		(end 388.182358 -157.001972)
		(stroke
			(width 0.2)
			(type default)
		)
		(fill no)
		(layer "In1.Cu")
	)
	(gr_circle
		(center 387.293358 -156.366972)
		(end 388.182358 -156.366972)
		(stroke
			(width 0.2)
			(type default)
		)
		(fill no)
		(layer "In1.Cu")
	)
	(gr_circle
		(center 387.293358 -155.724352)
		(end 388.182358 -155.724352)
		(stroke
			(width 0.2)
			(type default)
		)
		(fill no)
		(layer "In1.Cu")
	)
	(gr_circle
		(center 387.293358 -155.089352)
		(end 388.182358 -155.089352)
		(stroke
			(width 0.2)
			(type default)
		)
		(fill no)
		(layer "In1.Cu")
	)
	(gr_circle
		(center 387.293358 -154.428952)
		(end 388.182358 -154.428952)
		(stroke
			(width 0.2)
			(type default)
		)
		(fill no)
		(layer "In1.Cu")
	)
	(gr_circle
		(center 387.293358 -153.793952)
		(end 388.182358 -153.793952)
		(stroke
			(width 0.2)
			(type default)
		)
		(fill no)
		(layer "In1.Cu")
	)
	(gr_circle
		(center 387.366256 -182.230776)
		(end 388.255256 -182.230776)
		(stroke
			(width 0.2)
			(type default)
		)
		(fill no)
		(layer "In1.Cu")
	)
	(gr_circle
		(center 387.366256 -181.494176)
		(end 388.255256 -181.494176)
		(stroke
			(width 0.2)
			(type default)
		)
		(fill no)
		(layer "In1.Cu")
	)
	(gr_circle
		(center 387.483858 -180.755544)
		(end 388.363968 -180.755544)
		(stroke
			(width 0.2)
			(type default)
		)
		(fill no)
		(layer "In1.Cu")
	)
	(gr_line
		(start 387.601968 -9.780016)
		(end 387.601968 -0.500126)
		(stroke
			(width 1.016)
			(type default)
		)
		(layer "In1.Cu")
	)
	(gr_circle
		(center 387.928358 -157.001972)
		(end 388.817358 -157.001972)
		(stroke
			(width 0.2)
			(type default)
		)
		(fill no)
		(layer "In1.Cu")
	)
	(gr_circle
		(center 387.928358 -156.366972)
		(end 388.817358 -156.366972)
		(stroke
			(width 0.2)
			(type default)
		)
		(fill no)
		(layer "In1.Cu")
	)
	(gr_circle
		(center 387.928358 -155.724352)
		(end 388.817358 -155.724352)
		(stroke
			(width 0.2)
			(type default)
		)
		(fill no)
		(layer "In1.Cu")
	)
	(gr_circle
		(center 387.928358 -155.089352)
		(end 388.817358 -155.089352)
		(stroke
			(width 0.2)
			(type default)
		)
		(fill no)
		(layer "In1.Cu")
	)
	(gr_circle
		(center 387.928358 -154.428952)
		(end 388.817358 -154.428952)
		(stroke
			(width 0.2)
			(type default)
		)
		(fill no)
		(layer "In1.Cu")
	)
	(gr_circle
		(center 387.928358 -153.793952)
		(end 388.817358 -153.793952)
		(stroke
			(width 0.2)
			(type default)
		)
		(fill no)
		(layer "In1.Cu")
	)
	(gr_circle
		(center 388.101078 -180.755544)
		(end 388.981188 -180.755544)
		(stroke
			(width 0.2)
			(type default)
		)
		(fill no)
		(layer "In1.Cu")
	)
	(gr_arc
		(start 388.102094 0)
		(mid 387.748465 -0.146487)
		(end 387.601968 -0.500126)
		(stroke
			(width 1.016)
			(type default)
		)
		(layer "In1.Cu")
	)
	(gr_line
		(start 388.102094 0)
		(end 455.701908 0)
		(stroke
			(width 1.016)
			(type default)
		)
		(layer "In1.Cu")
	)
	(gr_circle
		(center 388.718298 -180.755544)
		(end 389.598408 -180.755544)
		(stroke
			(width 0.2)
			(type default)
		)
		(fill no)
		(layer "In1.Cu")
	)
	(gr_circle
		(center 394.628878 -173.21911)
		(end 395.517878 -173.21911)
		(stroke
			(width 0.2)
			(type default)
		)
		(fill no)
		(layer "In1.Cu")
	)
	(gr_circle
		(center 394.628878 -172.45711)
		(end 395.517878 -172.45711)
		(stroke
			(width 0.2)
			(type default)
		)
		(fill no)
		(layer "In1.Cu")
	)
	(gr_circle
		(center 394.646658 -173.987714)
		(end 395.535658 -173.987714)
		(stroke
			(width 0.2)
			(type default)
		)
		(fill no)
		(layer "In1.Cu")
	)
	(gr_circle
		(center 394.672058 -174.749714)
		(end 395.561058 -174.749714)
		(stroke
			(width 0.2)
			(type default)
		)
		(fill no)
		(layer "In1.Cu")
	)
	(gr_circle
		(center 395.196822 -174.310294)
		(end 396.085822 -174.310294)
		(stroke
			(width 0.2)
			(type default)
		)
		(fill no)
		(layer "In1.Cu")
	)
	(gr_circle
		(center 395.196822 -173.573694)
		(end 396.085822 -173.573694)
		(stroke
			(width 0.2)
			(type default)
		)
		(fill no)
		(layer "In1.Cu")
	)
	(gr_circle
		(center 395.230858 -172.819314)
		(end 396.119858 -172.819314)
		(stroke
			(width 0.2)
			(type default)
		)
		(fill no)
		(layer "In1.Cu")
	)
	(gr_circle
		(center 395.781276 -176.657254)
		(end 396.670276 -176.657254)
		(stroke
			(width 0.2)
			(type default)
		)
		(fill no)
		(layer "In1.Cu")
	)
	(gr_circle
		(center 395.781276 -175.895254)
		(end 396.670276 -175.895254)
		(stroke
			(width 0.2)
			(type default)
		)
		(fill no)
		(layer "In1.Cu")
	)
	(gr_circle
		(center 395.898878 -175.182784)
		(end 396.778988 -175.182784)
		(stroke
			(width 0.2)
			(type default)
		)
		(fill no)
		(layer "In1.Cu")
	)
	(gr_circle
		(center 396.516098 -175.182784)
		(end 397.396208 -175.182784)
		(stroke
			(width 0.2)
			(type default)
		)
		(fill no)
		(layer "In1.Cu")
	)
	(gr_circle
		(center 397.133318 -175.182784)
		(end 398.013428 -175.182784)
		(stroke
			(width 0.2)
			(type default)
		)
		(fill no)
		(layer "In1.Cu")
	)
	(gr_circle
		(center 399.165064 -81.051146)
		(end 400.054064 -81.051146)
		(stroke
			(width 0.2)
			(type default)
		)
		(fill no)
		(layer "In1.Cu")
	)
	(gr_circle
		(center 402.436838 -166.527988)
		(end 403.325838 -166.527988)
		(stroke
			(width 0.2)
			(type default)
		)
		(fill no)
		(layer "In1.Cu")
	)
	(gr_circle
		(center 402.436838 -165.791388)
		(end 403.325838 -165.791388)
		(stroke
			(width 0.2)
			(type default)
		)
		(fill no)
		(layer "In1.Cu")
	)
	(gr_circle
		(center 402.436838 -165.054788)
		(end 403.325838 -165.054788)
		(stroke
			(width 0.2)
			(type default)
		)
		(fill no)
		(layer "In1.Cu")
	)
	(gr_circle
		(center 402.970238 -165.410388)
		(end 403.859238 -165.410388)
		(stroke
			(width 0.2)
			(type default)
		)
		(fill no)
		(layer "In1.Cu")
	)
	(gr_circle
		(center 402.995638 -166.172388)
		(end 403.884638 -166.172388)
		(stroke
			(width 0.2)
			(type default)
		)
		(fill no)
		(layer "In1.Cu")
	)
	(gr_circle
		(center 403.520402 -165.732968)
		(end 404.409402 -165.732968)
		(stroke
			(width 0.2)
			(type default)
		)
		(fill no)
		(layer "In1.Cu")
	)
	(gr_circle
		(center 403.520402 -164.996368)
		(end 404.409402 -164.996368)
		(stroke
			(width 0.2)
			(type default)
		)
		(fill no)
		(layer "In1.Cu")
	)
	(gr_circle
		(center 404.104856 -168.082214)
		(end 404.993856 -168.082214)
		(stroke
			(width 0.2)
			(type default)
		)
		(fill no)
		(layer "In1.Cu")
	)
	(gr_circle
		(center 404.104856 -167.320214)
		(end 404.993856 -167.320214)
		(stroke
			(width 0.2)
			(type default)
		)
		(fill no)
		(layer "In1.Cu")
	)
	(gr_circle
		(center 404.222458 -166.605458)
		(end 405.102568 -166.605458)
		(stroke
			(width 0.2)
			(type default)
		)
		(fill no)
		(layer "In1.Cu")
	)
	(gr_circle
		(center 404.839678 -166.605458)
		(end 405.719788 -166.605458)
		(stroke
			(width 0.2)
			(type default)
		)
		(fill no)
		(layer "In1.Cu")
	)
	(gr_circle
		(center 405.456898 -166.605458)
		(end 406.337008 -166.605458)
		(stroke
			(width 0.2)
			(type default)
		)
		(fill no)
		(layer "In1.Cu")
	)
	(gr_circle
		(center 410.818838 -161.701988)
		(end 411.707838 -161.701988)
		(stroke
			(width 0.2)
			(type default)
		)
		(fill no)
		(layer "In1.Cu")
	)
	(gr_circle
		(center 410.818838 -160.965388)
		(end 411.707838 -160.965388)
		(stroke
			(width 0.2)
			(type default)
		)
		(fill no)
		(layer "In1.Cu")
	)
	(gr_circle
		(center 410.818838 -160.228788)
		(end 411.707838 -160.228788)
		(stroke
			(width 0.2)
			(type default)
		)
		(fill no)
		(layer "In1.Cu")
	)
	(gr_circle
		(center 411.352238 -160.584388)
		(end 412.241238 -160.584388)
		(stroke
			(width 0.2)
			(type default)
		)
		(fill no)
		(layer "In1.Cu")
	)
	(gr_circle
		(center 411.377638 -161.346388)
		(end 412.266638 -161.346388)
		(stroke
			(width 0.2)
			(type default)
		)
		(fill no)
		(layer "In1.Cu")
	)
	(gr_circle
		(center 411.902402 -160.906968)
		(end 412.791402 -160.906968)
		(stroke
			(width 0.2)
			(type default)
		)
		(fill no)
		(layer "In1.Cu")
	)
	(gr_circle
		(center 411.902402 -160.170368)
		(end 412.791402 -160.170368)
		(stroke
			(width 0.2)
			(type default)
		)
		(fill no)
		(layer "In1.Cu")
	)
	(gr_circle
		(center 412.486856 -163.256214)
		(end 413.375856 -163.256214)
		(stroke
			(width 0.2)
			(type default)
		)
		(fill no)
		(layer "In1.Cu")
	)
	(gr_circle
		(center 412.486856 -162.494214)
		(end 413.375856 -162.494214)
		(stroke
			(width 0.2)
			(type default)
		)
		(fill no)
		(layer "In1.Cu")
	)
	(gr_circle
		(center 412.604458 -161.779458)
		(end 413.484568 -161.779458)
		(stroke
			(width 0.2)
			(type default)
		)
		(fill no)
		(layer "In1.Cu")
	)
	(gr_circle
		(center 413.221678 -161.779458)
		(end 414.101788 -161.779458)
		(stroke
			(width 0.2)
			(type default)
		)
		(fill no)
		(layer "In1.Cu")
	)
	(gr_circle
		(center 413.838898 -161.779458)
		(end 414.719008 -161.779458)
		(stroke
			(width 0.2)
			(type default)
		)
		(fill no)
		(layer "In1.Cu")
	)
	(gr_circle
		(center 424.33494 -353.10318)
		(end 425.21505 -353.10318)
		(stroke
			(width 0.2)
			(type default)
		)
		(fill no)
		(layer "In1.Cu")
	)
	(gr_circle
		(center 424.95216 -353.10318)
		(end 425.83227 -353.10318)
		(stroke
			(width 0.2)
			(type default)
		)
		(fill no)
		(layer "In1.Cu")
	)
	(gr_circle
		(center 425.56938 -353.10318)
		(end 426.44949 -353.10318)
		(stroke
			(width 0.2)
			(type default)
		)
		(fill no)
		(layer "In1.Cu")
	)
	(gr_circle
		(center 425.686474 -352.35769)
		(end 426.575474 -352.35769)
		(stroke
			(width 0.2)
			(type default)
		)
		(fill no)
		(layer "In1.Cu")
	)
	(gr_circle
		(center 425.686474 -351.62109)
		(end 426.575474 -351.62109)
		(stroke
			(width 0.2)
			(type default)
		)
		(fill no)
		(layer "In1.Cu")
	)
	(gr_circle
		(center 426.271436 -354.71227)
		(end 427.160436 -354.71227)
		(stroke
			(width 0.2)
			(type default)
		)
		(fill no)
		(layer "In1.Cu")
	)
	(gr_circle
		(center 426.271436 -353.97567)
		(end 427.160436 -353.97567)
		(stroke
			(width 0.2)
			(type default)
		)
		(fill no)
		(layer "In1.Cu")
	)
	(gr_circle
		(center 426.7962 -353.53625)
		(end 427.6852 -353.53625)
		(stroke
			(width 0.2)
			(type default)
		)
		(fill no)
		(layer "In1.Cu")
	)
	(gr_circle
		(center 426.8216 -354.29825)
		(end 427.7106 -354.29825)
		(stroke
			(width 0.2)
			(type default)
		)
		(fill no)
		(layer "In1.Cu")
	)
	(gr_circle
		(center 427.355 -354.65385)
		(end 428.244 -354.65385)
		(stroke
			(width 0.2)
			(type default)
		)
		(fill no)
		(layer "In1.Cu")
	)
	(gr_circle
		(center 427.355 -353.91725)
		(end 428.244 -353.91725)
		(stroke
			(width 0.2)
			(type default)
		)
		(fill no)
		(layer "In1.Cu")
	)
	(gr_circle
		(center 427.355 -353.18065)
		(end 428.244 -353.18065)
		(stroke
			(width 0.2)
			(type default)
		)
		(fill no)
		(layer "In1.Cu")
	)
	(gr_circle
		(center 432.01336 -361.827826)
		(end 433.41036 -361.827826)
		(stroke
			(width 0.2)
			(type default)
		)
		(fill no)
		(layer "In1.Cu")
	)
	(gr_circle
		(center 432.661568 -353.12858)
		(end 433.541678 -353.12858)
		(stroke
			(width 0.2)
			(type default)
		)
		(fill no)
		(layer "In1.Cu")
	)
	(gr_circle
		(center 433.278788 -353.12858)
		(end 434.158898 -353.12858)
		(stroke
			(width 0.2)
			(type default)
		)
		(fill no)
		(layer "In1.Cu")
	)
	(gr_circle
		(center 433.896008 -353.12858)
		(end 434.776118 -353.12858)
		(stroke
			(width 0.2)
			(type default)
		)
		(fill no)
		(layer "In1.Cu")
	)
	(gr_circle
		(center 434.013102 -352.38309)
		(end 434.902102 -352.38309)
		(stroke
			(width 0.2)
			(type default)
		)
		(fill no)
		(layer "In1.Cu")
	)
	(gr_circle
		(center 434.013102 -351.64649)
		(end 434.902102 -351.64649)
		(stroke
			(width 0.2)
			(type default)
		)
		(fill no)
		(layer "In1.Cu")
	)
	(gr_circle
		(center 434.598064 -354.73767)
		(end 435.487064 -354.73767)
		(stroke
			(width 0.2)
			(type default)
		)
		(fill no)
		(layer "In1.Cu")
	)
	(gr_circle
		(center 434.598064 -354.00107)
		(end 435.487064 -354.00107)
		(stroke
			(width 0.2)
			(type default)
		)
		(fill no)
		(layer "In1.Cu")
	)
	(gr_circle
		(center 435.122828 -353.56165)
		(end 436.011828 -353.56165)
		(stroke
			(width 0.2)
			(type default)
		)
		(fill no)
		(layer "In1.Cu")
	)
	(gr_circle
		(center 435.148228 -354.32365)
		(end 436.037228 -354.32365)
		(stroke
			(width 0.2)
			(type default)
		)
		(fill no)
		(layer "In1.Cu")
	)
	(gr_circle
		(center 435.469538 -361.496102)
		(end 436.358538 -361.496102)
		(stroke
			(width 0.2)
			(type default)
		)
		(fill no)
		(layer "In1.Cu")
	)
	(gr_circle
		(center 435.469538 -360.734102)
		(end 436.358538 -360.734102)
		(stroke
			(width 0.2)
			(type default)
		)
		(fill no)
		(layer "In1.Cu")
	)
	(gr_circle
		(center 435.469538 -359.972102)
		(end 436.358538 -359.972102)
		(stroke
			(width 0.2)
			(type default)
		)
		(fill no)
		(layer "In1.Cu")
	)
	(gr_circle
		(center 435.681628 -354.67925)
		(end 436.570628 -354.67925)
		(stroke
			(width 0.2)
			(type default)
		)
		(fill no)
		(layer "In1.Cu")
	)
	(gr_circle
		(center 435.681628 -353.94265)
		(end 436.570628 -353.94265)
		(stroke
			(width 0.2)
			(type default)
		)
		(fill no)
		(layer "In1.Cu")
	)
	(gr_circle
		(center 435.681628 -353.20605)
		(end 436.570628 -353.20605)
		(stroke
			(width 0.2)
			(type default)
		)
		(fill no)
		(layer "In1.Cu")
	)
	(gr_circle
		(center 436.231538 -361.496102)
		(end 437.120538 -361.496102)
		(stroke
			(width 0.2)
			(type default)
		)
		(fill no)
		(layer "In1.Cu")
	)
	(gr_circle
		(center 436.231538 -360.734102)
		(end 437.120538 -360.734102)
		(stroke
			(width 0.2)
			(type default)
		)
		(fill no)
		(layer "In1.Cu")
	)
	(gr_circle
		(center 436.231538 -359.972102)
		(end 437.120538 -359.972102)
		(stroke
			(width 0.2)
			(type default)
		)
		(fill no)
		(layer "In1.Cu")
	)
	(gr_circle
		(center 437.703214 -12.400788)
		(end 438.592214 -12.400788)
		(stroke
			(width 0.2)
			(type default)
		)
		(fill no)
		(layer "In1.Cu")
	)
	(gr_circle
		(center 438.06999 -13.069316)
		(end 438.95899 -13.069316)
		(stroke
			(width 0.2)
			(type default)
		)
		(fill no)
		(layer "In1.Cu")
	)
	(gr_circle
		(center 438.592214 -12.400788)
		(end 439.481214 -12.400788)
		(stroke
			(width 0.2)
			(type default)
		)
		(fill no)
		(layer "In1.Cu")
	)
	(gr_circle
		(center 438.71515 -13.061696)
		(end 439.60415 -13.061696)
		(stroke
			(width 0.2)
			(type default)
		)
		(fill no)
		(layer "In1.Cu")
	)
	(gr_circle
		(center 439.39333 -13.043916)
		(end 440.28233 -13.043916)
		(stroke
			(width 0.2)
			(type default)
		)
		(fill no)
		(layer "In1.Cu")
	)
	(gr_circle
		(center 439.481214 -12.400788)
		(end 440.370214 -12.400788)
		(stroke
			(width 0.2)
			(type default)
		)
		(fill no)
		(layer "In1.Cu")
	)
	(gr_circle
		(center 440.945524 -11.261852)
		(end 441.834524 -11.261852)
		(stroke
			(width 0.2)
			(type default)
		)
		(fill no)
		(layer "In1.Cu")
	)
	(gr_circle
		(center 440.945524 -10.626852)
		(end 441.834524 -10.626852)
		(stroke
			(width 0.2)
			(type default)
		)
		(fill no)
		(layer "In1.Cu")
	)
	(gr_circle
		(center 441.129674 -25.982422)
		(end 442.018674 -25.982422)
		(stroke
			(width 0.2)
			(type default)
		)
		(fill no)
		(layer "In1.Cu")
	)
	(gr_circle
		(center 441.354718 -20.73656)
		(end 442.243718 -20.73656)
		(stroke
			(width 0.2)
			(type default)
		)
		(fill no)
		(layer "In1.Cu")
	)
	(gr_circle
		(center 441.354718 -20.10156)
		(end 442.243718 -20.10156)
		(stroke
			(width 0.2)
			(type default)
		)
		(fill no)
		(layer "In1.Cu")
	)
	(gr_circle
		(center 441.354718 -19.21256)
		(end 442.243718 -19.21256)
		(stroke
			(width 0.2)
			(type default)
		)
		(fill no)
		(layer "In1.Cu")
	)
	(gr_circle
		(center 441.354718 -18.57756)
		(end 442.243718 -18.57756)
		(stroke
			(width 0.2)
			(type default)
		)
		(fill no)
		(layer "In1.Cu")
	)
	(gr_circle
		(center 441.475622 -14.123162)
		(end 442.364622 -14.123162)
		(stroke
			(width 0.2)
			(type default)
		)
		(fill no)
		(layer "In1.Cu")
	)
	(gr_circle
		(center 441.475622 -13.488162)
		(end 442.364622 -13.488162)
		(stroke
			(width 0.2)
			(type default)
		)
		(fill no)
		(layer "In1.Cu")
	)
	(gr_circle
		(center 441.56249 -25.461976)
		(end 442.45149 -25.461976)
		(stroke
			(width 0.2)
			(type default)
		)
		(fill no)
		(layer "In1.Cu")
	)
	(gr_circle
		(center 442.018674 -25.982422)
		(end 442.907674 -25.982422)
		(stroke
			(width 0.2)
			(type default)
		)
		(fill no)
		(layer "In1.Cu")
	)
	(gr_circle
		(center 442.371734 -20.983702)
		(end 443.260734 -20.983702)
		(stroke
			(width 0.2)
			(type default)
		)
		(fill no)
		(layer "In1.Cu")
	)
	(gr_circle
		(center 442.371734 -20.348702)
		(end 443.260734 -20.348702)
		(stroke
			(width 0.2)
			(type default)
		)
		(fill no)
		(layer "In1.Cu")
	)
	(gr_circle
		(center 442.371734 -19.459702)
		(end 443.260734 -19.459702)
		(stroke
			(width 0.2)
			(type default)
		)
		(fill no)
		(layer "In1.Cu")
	)
	(gr_circle
		(center 442.371734 -18.824702)
		(end 443.260734 -18.824702)
		(stroke
			(width 0.2)
			(type default)
		)
		(fill no)
		(layer "In1.Cu")
	)
	(gr_circle
		(center 442.45149 -25.461976)
		(end 443.34049 -25.461976)
		(stroke
			(width 0.2)
			(type default)
		)
		(fill no)
		(layer "In1.Cu")
	)
	(gr_circle
		(center 442.907674 -25.982422)
		(end 443.796674 -25.982422)
		(stroke
			(width 0.2)
			(type default)
		)
		(fill no)
		(layer "In1.Cu")
	)
	(gr_circle
		(center 443.34049 -25.461976)
		(end 444.22949 -25.461976)
		(stroke
			(width 0.2)
			(type default)
		)
		(fill no)
		(layer "In1.Cu")
	)
	(gr_circle
		(center 444.166244 -24.741632)
		(end 445.055244 -24.741632)
		(stroke
			(width 0.2)
			(type default)
		)
		(fill no)
		(layer "In1.Cu")
	)
	(gr_circle
		(center 450.669914 -14.526514)
		(end 451.558914 -14.526514)
		(stroke
			(width 0.2)
			(type default)
		)
		(fill no)
		(layer "In1.Cu")
	)
	(gr_circle
		(center 450.670676 -16.010382)
		(end 451.559676 -16.010382)
		(stroke
			(width 0.2)
			(type default)
		)
		(fill no)
		(layer "In1.Cu")
	)
	(gr_circle
		(center 450.670676 -15.273782)
		(end 451.559676 -15.273782)
		(stroke
			(width 0.2)
			(type default)
		)
		(fill no)
		(layer "In1.Cu")
	)
	(gr_circle
		(center 452.054976 -18.535142)
		(end 452.943976 -18.535142)
		(stroke
			(width 0.2)
			(type default)
		)
		(fill no)
		(layer "In1.Cu")
	)
	(gr_circle
		(center 452.054976 -17.798542)
		(end 452.943976 -17.798542)
		(stroke
			(width 0.2)
			(type default)
		)
		(fill no)
		(layer "In1.Cu")
	)
	(gr_arc
		(start 456.202034 -9.780016)
		(mid 456.787819 -11.194227)
		(end 458.20203 -11.780012)
		(stroke
			(width 1.016)
			(type default)
		)
		(layer "In1.Cu")
	)
	(gr_arc
		(start 456.202034 -0.500126)
		(mid 456.05556 -0.146464)
		(end 455.701908 0)
		(stroke
			(width 1.016)
			(type default)
		)
		(layer "In1.Cu")
	)
	(gr_line
		(start 456.202034 -0.500126)
		(end 456.202034 -9.780016)
		(stroke
			(width 1.016)
			(type default)
		)
		(layer "In1.Cu")
	)
	(gr_line
		(start 458.20203 -11.780012)
		(end 469.799924 -11.780012)
		(stroke
			(width 1.016)
			(type default)
		)
		(layer "In1.Cu")
	)
	(gr_line
		(start 463.300064 -441.989972)
		(end 277.314914 -441.989972)
		(stroke
			(width 1.016)
			(type default)
		)
		(layer "In1.Cu")
	)
	(gr_arc
		(start 463.300064 -441.989972)
		(mid 464.71429 -441.404198)
		(end 465.30006 -439.989976)
		(stroke
			(width 1.016)
			(type default)
		)
		(layer "In1.Cu")
	)
	(gr_line
		(start 465.30006 -409.528518)
		(end 465.30006 -439.989976)
		(stroke
			(width 1.016)
			(type default)
		)
		(layer "In1.Cu")
	)
	(gr_arc
		(start 465.885784 -408.114246)
		(mid 465.452221 -408.76312)
		(end 465.30006 -409.528518)
		(stroke
			(width 1.016)
			(type default)
		)
		(layer "In1.Cu")
	)
	(gr_line
		(start 467.71433 -406.2857)
		(end 465.885784 -408.114246)
		(stroke
			(width 1.016)
			(type default)
		)
		(layer "In1.Cu")
	)
	(gr_arc
		(start 467.71433 -406.2857)
		(mid 468.147828 -405.636947)
		(end 468.300054 -404.871682)
		(stroke
			(width 1.016)
			(type default)
		)
		(layer "In1.Cu")
	)
	(gr_line
		(start 468.300054 -82.828384)
		(end 468.300054 -404.871682)
		(stroke
			(width 1.016)
			(type default)
		)
		(layer "In1.Cu")
	)
	(gr_arc
		(start 468.885778 -81.414112)
		(mid 468.452215 -82.062986)
		(end 468.300054 -82.828384)
		(stroke
			(width 1.016)
			(type default)
		)
		(layer "In1.Cu")
	)
	(gr_line
		(start 471.214196 -79.085694)
		(end 468.885778 -81.414112)
		(stroke
			(width 1.016)
			(type default)
		)
		(layer "In1.Cu")
	)
	(gr_arc
		(start 471.214196 -79.085694)
		(mid 471.6477 -78.436942)
		(end 471.79992 -77.671676)
		(stroke
			(width 1.016)
			(type default)
		)
		(layer "In1.Cu")
	)
	(gr_arc
		(start 471.79992 -13.780008)
		(mid 471.214139 -12.365784)
		(end 469.799924 -11.780012)
		(stroke
			(width 1.016)
			(type default)
		)
		(layer "In1.Cu")
	)
	(gr_line
		(start 471.79992 -13.780008)
		(end 471.79992 -77.671676)
		(stroke
			(width 1.016)
			(type default)
		)
		(layer "In1.Cu")
	)
	(gr_poly
		(pts
			(xy 77.493114 -227.0125) (xy 77.393292 -226.839272) (xy 77.35189 -226.863148) (xy 77.315314 -226.999546)
			(xy 77.451966 -227.036376)
		)
		(stroke
			(width 0)
			(type solid)
		)
		(fill yes)
		(layer "In2.Cu")
		(net "M_C_CPU1_SA_DQS_DN<1>")
	)
	(gr_poly
		(pts
			(xy 77.52207 -228.640386) (xy 77.421994 -228.467158) (xy 77.380846 -228.49078) (xy 77.34427 -228.627432)
			(xy 77.480922 -228.664008)
		)
		(stroke
			(width 0)
			(type solid)
		)
		(fill yes)
		(layer "In2.Cu")
		(net "M_C_CPU1_SA_DQS_DP<6>")
	)
	(gr_poly
		(pts
			(xy 77.579982 -224.828862) (xy 77.616558 -224.69221) (xy 77.479906 -224.655634) (xy 77.441552 -224.677986)
			(xy 77.541374 -224.851214)
		)
		(stroke
			(width 0)
			(type solid)
		)
		(fill yes)
		(layer "In2.Cu")
		(net "M_C_CPU1_SA_DQ<9>")
	)
	(gr_poly
		(pts
			(xy 77.950314 -224.583498) (xy 77.865732 -224.402142) (xy 77.8256 -224.420938) (xy 77.777086 -224.55378)
			(xy 77.910182 -224.602294)
		)
		(stroke
			(width 0)
			(type solid)
		)
		(fill yes)
		(layer "In2.Cu")
		(net "M_C_CPU1_SA_DQ<10>")
	)
	(gr_poly
		(pts
			(xy 77.963014 -227.822506) (xy 77.863192 -227.649278) (xy 77.82179 -227.673154) (xy 77.785214 -227.809552)
			(xy 77.921866 -227.846128)
		)
		(stroke
			(width 0)
			(type solid)
		)
		(fill yes)
		(layer "In2.Cu")
		(net "M_C_CPU1_SA_DQS_DN<1>")
	)
	(gr_poly
		(pts
			(xy 77.963776 -229.443026) (xy 77.8637 -229.269798) (xy 77.822552 -229.293674) (xy 77.785976 -229.430326)
			(xy 77.922628 -229.466902)
		)
		(stroke
			(width 0)
			(type solid)
		)
		(fill yes)
		(layer "In2.Cu")
		(net "M_C_CPU1_SA_DQS_DP<6>")
	)
	(gr_poly
		(pts
			(xy 78.0288 -253.596648) (xy 77.928724 -253.496572) (xy 77.828648 -253.596648) (xy 77.828648 -253.641098)
			(xy 78.0288 -253.641098)
		)
		(stroke
			(width 0)
			(type solid)
		)
		(fill yes)
		(layer "In2.Cu")
		(net "M_C_CPU1_SA_CA<2>")
	)
	(gr_poly
		(pts
			(xy 78.060042 -228.895148) (xy 78.096618 -228.758496) (xy 77.959966 -228.72192) (xy 77.918818 -228.745542)
			(xy 78.018894 -228.91877)
		)
		(stroke
			(width 0)
			(type solid)
		)
		(fill yes)
		(layer "In2.Cu")
		(net "M_C_CPU1_SA_DQS_DN<6>")
	)
	(gr_poly
		(pts
			(xy 78.060296 -227.275898) (xy 78.096872 -227.1395) (xy 77.96022 -227.10267) (xy 77.919072 -227.126546)
			(xy 78.018894 -227.299774)
		)
		(stroke
			(width 0)
			(type solid)
		)
		(fill yes)
		(layer "In2.Cu")
		(net "M_C_CPU1_SA_DQS_DP<1>")
	)
	(gr_poly
		(pts
			(xy 78.06055 -224.023428) (xy 78.097126 -223.88703) (xy 77.960474 -223.8502) (xy 77.92212 -223.872552)
			(xy 78.022196 -224.04578)
		)
		(stroke
			(width 0)
			(type solid)
		)
		(fill yes)
		(layer "In2.Cu")
		(net "M_C_CPU1_SA_DQ<8>")
	)
	(gr_poly
		(pts
			(xy 78.431898 -225.395536) (xy 78.331822 -225.222308) (xy 78.293214 -225.24466) (xy 78.256638 -225.381312)
			(xy 78.39329 -225.417888)
		)
		(stroke
			(width 0)
			(type solid)
		)
		(fill yes)
		(layer "In2.Cu")
		(net "M_C_CPU1_SA_DQ<10>")
	)
	(gr_poly
		(pts
			(xy 78.432406 -223.776794) (xy 78.33233 -223.603566) (xy 78.293976 -223.625664) (xy 78.2574 -223.762316)
			(xy 78.393798 -223.798892)
		)
		(stroke
			(width 0)
			(type solid)
		)
		(fill yes)
		(layer "In2.Cu")
		(net "M_C_CPU1_SA_DQ<7>")
	)
	(gr_poly
		(pts
			(xy 78.43393 -230.252778) (xy 78.333854 -230.07955) (xy 78.292706 -230.103426) (xy 78.25613 -230.240078)
			(xy 78.392528 -230.276654)
		)
		(stroke
			(width 0)
			(type solid)
		)
		(fill yes)
		(layer "In2.Cu")
		(net "M_C_CPU1_SA_DQS_DP<6>")
	)
	(gr_poly
		(pts
			(xy 78.434946 -228.63429) (xy 78.33487 -228.461062) (xy 78.293722 -228.484938) (xy 78.257146 -228.621336)
			(xy 78.393798 -228.658166)
		)
		(stroke
			(width 0)
			(type solid)
		)
		(fill yes)
		(layer "In2.Cu")
		(net "M_C_CPU1_SA_DQS_DN<1>")
	)
	(gr_poly
		(pts
			(xy 78.498446 -256.026158) (xy 78.398624 -255.926082) (xy 78.298548 -256.026158) (xy 78.298548 -256.073656)
			(xy 78.498446 -256.073656)
		)
		(stroke
			(width 0)
			(type solid)
		)
		(fill yes)
		(layer "In2.Cu")
		(net "M_C_CPU1_CLK_DP<0>")
	)
	(gr_poly
		(pts
			(xy 78.4987 -246.305832) (xy 78.398624 -246.20601) (xy 78.298548 -246.305832) (xy 78.298548 -246.353584)
			(xy 78.4987 -246.353584)
		)
		(stroke
			(width 0)
			(type solid)
		)
		(fill yes)
		(layer "In2.Cu")
		(net "M_C_CPU1_SA_DQS_DP<4>")
	)
	(gr_poly
		(pts
			(xy 78.501494 -254.406146) (xy 78.401418 -254.306324) (xy 78.301342 -254.406146) (xy 78.301342 -254.450596)
			(xy 78.501494 -254.450596)
		)
		(stroke
			(width 0)
			(type solid)
		)
		(fill yes)
		(layer "In2.Cu")
		(net "M_C_CPU1_SA_CA<4>")
	)
	(gr_poly
		(pts
			(xy 78.501494 -252.786134) (xy 78.401418 -252.686312) (xy 78.301342 -252.786134) (xy 78.301342 -252.830584)
			(xy 78.501494 -252.830584)
		)
		(stroke
			(width 0)
			(type solid)
		)
		(fill yes)
		(layer "In2.Cu")
		(net "M_C_CPU1_SA_CA<0>")
	)
	(gr_poly
		(pts
			(xy 78.501494 -247.926098) (xy 78.401418 -247.826276) (xy 78.301342 -247.926098) (xy 78.301342 -247.970548)
			(xy 78.501494 -247.970548)
		)
		(stroke
			(width 0)
			(type solid)
		)
		(fill yes)
		(layer "In2.Cu")
		(net "M_C_CPU1_SA_CB<4>")
	)
	(gr_poly
		(pts
			(xy 78.501494 -244.686074) (xy 78.401418 -244.586252) (xy 78.301342 -244.686074) (xy 78.301342 -244.730524)
			(xy 78.501494 -244.730524)
		)
		(stroke
			(width 0)
			(type solid)
		)
		(fill yes)
		(layer "In2.Cu")
		(net "M_C_CPU1_SA_CB<0>")
	)
	(gr_poly
		(pts
			(xy 78.525878 -224.85477) (xy 78.574138 -224.721674) (xy 78.441296 -224.673414) (xy 78.40091 -224.69221)
			(xy 78.485492 -224.873312)
		)
		(stroke
			(width 0)
			(type solid)
		)
		(fill yes)
		(layer "In2.Cu")
		(net "M_C_CPU1_SA_DQ<8>")
	)
	(gr_poly
		(pts
			(xy 78.528418 -226.463606) (xy 78.564994 -226.326954) (xy 78.428596 -226.290378) (xy 78.389988 -226.312476)
			(xy 78.490064 -226.485704)
		)
		(stroke
			(width 0)
			(type solid)
		)
		(fill yes)
		(layer "In2.Cu")
		(net "M_C_CPU1_SA_DQ<9>")
	)
	(gr_poly
		(pts
			(xy 78.528926 -223.225106) (xy 78.565502 -223.088454) (xy 78.429104 -223.051878) (xy 78.390496 -223.073976)
			(xy 78.490572 -223.247204)
		)
		(stroke
			(width 0)
			(type solid)
		)
		(fill yes)
		(layer "In2.Cu")
		(net "M_C_CPU1_SA_DQ<5>")
	)
	(gr_poly
		(pts
			(xy 78.530196 -228.085142) (xy 78.566772 -227.94849) (xy 78.43012 -227.911914) (xy 78.388972 -227.935536)
			(xy 78.489048 -228.108764)
		)
		(stroke
			(width 0)
			(type solid)
		)
		(fill yes)
		(layer "In2.Cu")
		(net "M_C_CPU1_SA_DQS_DP<1>")
	)
	(gr_poly
		(pts
			(xy 78.530958 -229.706424) (xy 78.567534 -229.569772) (xy 78.430882 -229.533196) (xy 78.389734 -229.557072)
			(xy 78.48981 -229.7303)
		)
		(stroke
			(width 0)
			(type solid)
		)
		(fill yes)
		(layer "In2.Cu")
		(net "M_C_CPU1_SA_DQS_DN<6>")
	)
	(gr_poly
		(pts
			(xy 78.53426 -247.523) (xy 78.53426 -247.475502) (xy 78.334362 -247.475502) (xy 78.334362 -247.523)
			(xy 78.434184 -247.623076)
		)
		(stroke
			(width 0)
			(type solid)
		)
		(fill yes)
		(layer "In2.Cu")
		(net "M_C_CPU1_SA_DQS_DP<9>")
	)
	(gr_poly
		(pts
			(xy 78.53426 -242.662964) (xy 78.53426 -242.615466) (xy 78.334362 -242.615466) (xy 78.334362 -242.662964)
			(xy 78.434184 -242.76304)
		)
		(stroke
			(width 0)
			(type solid)
		)
		(fill yes)
		(layer "In2.Cu")
		(net "M_C_CPU1_SA_DQS_DP<8>")
	)
	(gr_poly
		(pts
			(xy 78.539086 -253.994158) (xy 78.535276 -253.949962) (xy 78.33614 -253.967234) (xy 78.33995 -254.011684)
			(xy 78.448154 -254.102616)
		)
		(stroke
			(width 0)
			(type solid)
		)
		(fill yes)
		(layer "In2.Cu")
		(net "M_C_CPU1_SA_CA<3>")
	)
	(gr_poly
		(pts
			(xy 78.539086 -252.374146) (xy 78.535276 -252.32995) (xy 78.33614 -252.347476) (xy 78.33995 -252.391672)
			(xy 78.448154 -252.482604)
		)
		(stroke
			(width 0)
			(type solid)
		)
		(fill yes)
		(layer "In2.Cu")
		(net "M_C_CPU1_SA_CS_N<1>")
	)
	(gr_poly
		(pts
			(xy 78.539086 -245.894098) (xy 78.535276 -245.849902) (xy 78.33614 -245.867428) (xy 78.33995 -245.911624)
			(xy 78.448154 -246.002556)
		)
		(stroke
			(width 0)
			(type solid)
		)
		(fill yes)
		(layer "In2.Cu")
		(net "M_C_CPU1_SA_CB<3>")
	)
	(gr_poly
		(pts
			(xy 78.539086 -244.274086) (xy 78.535276 -244.22989) (xy 78.33614 -244.247416) (xy 78.33995 -244.291612)
			(xy 78.448154 -244.382544)
		)
		(stroke
			(width 0)
			(type solid)
		)
		(fill yes)
		(layer "In2.Cu")
		(net "M_C_CPU1_SA_DQ<31>")
	)
	(gr_poly
		(pts
			(xy 78.539086 -241.034062) (xy 78.535276 -240.989866) (xy 78.33614 -241.007138) (xy 78.33995 -241.051588)
			(xy 78.448154 -241.14252)
		)
		(stroke
			(width 0)
			(type solid)
		)
		(fill yes)
		(layer "In2.Cu")
		(net "M_C_CPU1_SA_DQ<27>")
	)
	(gr_poly
		(pts
			(xy 78.554834 -284.180026) (xy 78.536038 -284.13964) (xy 78.403196 -284.09138) (xy 78.354682 -284.224222)
			(xy 78.373478 -284.264608)
		)
		(stroke
			(width 0)
			(type solid)
		)
		(fill yes)
		(layer "In2.Cu")
		(net "M_C_CPU1_SB_DQ<16>")
	)
	(gr_poly
		(pts
			(xy 78.71079 -283.227272) (xy 78.70698 -283.183076) (xy 78.598776 -283.092144) (xy 78.507844 -283.200348)
			(xy 78.511654 -283.244544)
		)
		(stroke
			(width 0)
			(type solid)
		)
		(fill yes)
		(layer "In2.Cu")
		(net "M_C_CPU1_SB_DQ<13>")
	)
	(gr_poly
		(pts
			(xy 78.721966 -278.280876) (xy 78.651354 -278.158448) (xy 78.528926 -278.22906) (xy 78.517242 -278.27224)
			(xy 78.710536 -278.323802)
		)
		(stroke
			(width 0)
			(type solid)
		)
		(fill yes)
		(layer "In2.Cu")
		(net "M_C_CPU1_SB_DQ<5>")
	)
	(gr_poly
		(pts
			(xy 78.730348 -293.986712) (xy 78.691994 -293.96436) (xy 78.555342 -294.000936) (xy 78.591918 -294.137588)
			(xy 78.630526 -294.15994)
		)
		(stroke
			(width 0)
			(type solid)
		)
		(fill yes)
		(layer "In2.Cu")
		(net "M_C_CPU1_SB_DQ<28>")
	)
	(gr_poly
		(pts
			(xy 78.77683 -273.083528) (xy 78.78064 -273.039078) (xy 78.58125 -273.021806) (xy 78.57744 -273.066002)
			(xy 78.668372 -273.17446)
		)
		(stroke
			(width 0)
			(type solid)
		)
		(fill yes)
		(layer "In2.Cu")
		(net "M_C_CPU1_SB_CB<2>")
	)
	(gr_poly
		(pts
			(xy 78.801468 -286.437832) (xy 78.701392 -286.33801) (xy 78.60157 -286.437832) (xy 78.60157 -286.485584)
			(xy 78.801468 -286.485584)
		)
		(stroke
			(width 0)
			(type solid)
		)
		(fill yes)
		(layer "In2.Cu")
		(net "M_C_CPU1_SB_DQS_DN<7>")
	)
	(gr_poly
		(pts
			(xy 78.80223 -288.057844) (xy 78.702408 -287.957768) (xy 78.602332 -288.057844) (xy 78.602332 -288.102294)
			(xy 78.80223 -288.102294)
		)
		(stroke
			(width 0)
			(type solid)
		)
		(fill yes)
		(layer "In2.Cu")
		(net "M_C_CPU1_SB_DQ<21>")
	)
	(gr_poly
		(pts
			(xy 78.83271 -263.35482) (xy 78.83271 -263.310116) (xy 78.632812 -263.310116) (xy 78.632812 -263.35482)
			(xy 78.732888 -263.454642)
		)
		(stroke
			(width 0)
			(type solid)
		)
		(fill yes)
		(layer "In2.Cu")
		(net "M_C_CPU1_SB_CA<3>")
	)
	(gr_poly
		(pts
			(xy 78.834742 -269.834868) (xy 78.834742 -269.790418) (xy 78.63459 -269.790418) (xy 78.63459 -269.834868)
			(xy 78.734666 -269.93469)
		)
		(stroke
			(width 0)
			(type solid)
		)
		(fill yes)
		(layer "In2.Cu")
		(net "M_C_CPU1_SB_CB<6>")
	)
	(gr_poly
		(pts
			(xy 78.834742 -266.594844) (xy 78.834742 -266.550394) (xy 78.63459 -266.550394) (xy 78.63459 -266.594844)
			(xy 78.734666 -266.694666)
		)
		(stroke
			(width 0)
			(type solid)
		)
		(fill yes)
		(layer "In2.Cu")
		(net "M_C_CPU1_SB_CS_N<1>")
	)
	(gr_poly
		(pts
			(xy 78.834742 -264.974832) (xy 78.834742 -264.930382) (xy 78.63459 -264.930382) (xy 78.63459 -264.974832)
			(xy 78.734666 -265.074654)
		)
		(stroke
			(width 0)
			(type solid)
		)
		(fill yes)
		(layer "In2.Cu")
		(net "M_C_CPU1_SB_PAR")
	)
	(gr_poly
		(pts
			(xy 78.890622 -224.584768) (xy 78.80604 -224.403666) (xy 78.765654 -224.422208) (xy 78.717394 -224.555304)
			(xy 78.850236 -224.603564)
		)
		(stroke
			(width 0)
			(type solid)
		)
		(fill yes)
		(layer "In2.Cu")
		(net "M_C_CPU1_SA_DQ<7>")
	)
	(gr_poly
		(pts
			(xy 78.900274 -227.82403) (xy 78.800452 -227.650802) (xy 78.761844 -227.6729) (xy 78.725268 -227.809552)
			(xy 78.86192 -227.846128)
		)
		(stroke
			(width 0)
			(type solid)
		)
		(fill yes)
		(layer "In2.Cu")
		(net "M_C_CPU1_SA_DQ<11>")
	)
	(gr_poly
		(pts
			(xy 78.900528 -226.20224) (xy 78.800706 -226.029012) (xy 78.762098 -226.051364) (xy 78.725522 -226.188016)
			(xy 78.862174 -226.224592)
		)
		(stroke
			(width 0)
			(type solid)
		)
		(fill yes)
		(layer "In2.Cu")
		(net "M_C_CPU1_SA_DQ<10>")
	)
	(gr_poly
		(pts
			(xy 78.901798 -222.965264) (xy 78.801722 -222.792036) (xy 78.763368 -222.814388) (xy 78.726792 -222.95104)
			(xy 78.86319 -222.987616)
		)
		(stroke
			(width 0)
			(type solid)
		)
		(fill yes)
		(layer "In2.Cu")
		(net "M_C_CPU1_SA_DQ<6>")
	)
	(gr_poly
		(pts
			(xy 78.903576 -231.062276) (xy 78.8035 -230.889048) (xy 78.762098 -230.912924) (xy 78.725522 -231.049576)
			(xy 78.862174 -231.086152)
		)
		(stroke
			(width 0)
			(type solid)
		)
		(fill yes)
		(layer "In2.Cu")
		(net "M_C_CPU1_SA_DQS_DP<6>")
	)
	(gr_poly
		(pts
			(xy 78.903576 -229.442264) (xy 78.8035 -229.269036) (xy 78.762098 -229.292912) (xy 78.725522 -229.429564)
			(xy 78.862174 -229.46614)
		)
		(stroke
			(width 0)
			(type solid)
		)
		(fill yes)
		(layer "In2.Cu")
		(net "M_C_CPU1_SA_DQS_DN<1>")
	)
	(gr_poly
		(pts
			(xy 78.961234 -242.255802) (xy 78.861412 -242.155726) (xy 78.761336 -242.255802) (xy 78.761336 -242.3033)
			(xy 78.961234 -242.3033)
		)
		(stroke
			(width 0)
			(type solid)
		)
		(fill yes)
		(layer "In2.Cu")
		(net "M_C_CPU1_SA_DQS_DN<8>")
	)
	(gr_poly
		(pts
			(xy 78.966568 -255.215644) (xy 78.866492 -255.115568) (xy 78.76667 -255.215644) (xy 78.76667 -255.260094)
			(xy 78.966568 -255.260094)
		)
		(stroke
			(width 0)
			(type solid)
		)
		(fill yes)
		(layer "In2.Cu")
		(net "M_C_CPU1_SA_CA<6>")
	)
	(gr_poly
		(pts
			(xy 78.966568 -253.595632) (xy 78.866492 -253.495556) (xy 78.76667 -253.595632) (xy 78.76667 -253.640082)
			(xy 78.966568 -253.640082)
		)
		(stroke
			(width 0)
			(type solid)
		)
		(fill yes)
		(layer "In2.Cu")
		(net "M_C_CPU1_SA_CA<2>")
	)
	(gr_poly
		(pts
			(xy 78.966568 -248.735596) (xy 78.866492 -248.63552) (xy 78.76667 -248.735596) (xy 78.76667 -248.780046)
			(xy 78.966568 -248.780046)
		)
		(stroke
			(width 0)
			(type solid)
		)
		(fill yes)
		(layer "In2.Cu")
		(net "M_C_CPU1_SA_CB<5>")
	)
	(gr_poly
		(pts
			(xy 78.966568 -245.495572) (xy 78.866492 -245.395496) (xy 78.76667 -245.495572) (xy 78.76667 -245.540022)
			(xy 78.966568 -245.540022)
		)
		(stroke
			(width 0)
			(type solid)
		)
		(fill yes)
		(layer "In2.Cu")
		(net "M_C_CPU1_SA_CB<1>")
	)
	(gr_poly
		(pts
			(xy 78.966568 -243.87556) (xy 78.866492 -243.775484) (xy 78.76667 -243.87556) (xy 78.76667 -243.92001)
			(xy 78.966568 -243.92001)
		)
		(stroke
			(width 0)
			(type solid)
		)
		(fill yes)
		(layer "In2.Cu")
		(net "M_C_CPU1_SA_DQ<29>")
	)
	(gr_poly
		(pts
			(xy 78.966568 -240.635536) (xy 78.866492 -240.53546) (xy 78.76667 -240.635536) (xy 78.76667 -240.679986)
			(xy 78.966568 -240.679986)
		)
		(stroke
			(width 0)
			(type solid)
		)
		(fill yes)
		(layer "In2.Cu")
		(net "M_C_CPU1_SA_DQ<25>")
	)
	(gr_poly
		(pts
			(xy 78.968346 -247.115584) (xy 78.868524 -247.015508) (xy 78.768448 -247.115584) (xy 78.768448 -247.163082)
			(xy 78.968346 -247.163082)
		)
		(stroke
			(width 0)
			(type solid)
		)
		(fill yes)
		(layer "In2.Cu")
		(net "M_C_CPU1_SA_DQS_DN<9>")
	)
	(gr_poly
		(pts
			(xy 78.97749 -251.572522) (xy 78.97749 -251.528072) (xy 78.777338 -251.528072) (xy 78.777338 -251.572522)
			(xy 78.877414 -251.672598)
		)
		(stroke
			(width 0)
			(type solid)
		)
		(fill yes)
		(layer "In2.Cu")
		(net "M_C_CPU1_SA_CS_N<0>")
	)
	(gr_poly
		(pts
			(xy 78.981046 -250.35637) (xy 78.88097 -250.256294) (xy 78.780894 -250.35637) (xy 78.780894 -250.40082)
			(xy 78.981046 -250.40082)
		)
		(stroke
			(width 0)
			(type solid)
		)
		(fill yes)
		(layer "In2.Cu")
		(net "M_C_CPU1_ALERT_R_N")
	)
	(gr_poly
		(pts
			(xy 78.981046 -241.852704) (xy 78.981046 -241.804952) (xy 78.780894 -241.804952) (xy 78.780894 -241.852704)
			(xy 78.88097 -241.952526)
		)
		(stroke
			(width 0)
			(type solid)
		)
		(fill yes)
		(layer "In2.Cu")
		(net "M_C_CPU1_SA_DQS_DN<3>")
	)
	(gr_poly
		(pts
			(xy 78.98384 -254.812546) (xy 78.98384 -254.768096) (xy 78.783688 -254.768096) (xy 78.783688 -254.812546)
			(xy 78.883764 -254.912622)
		)
		(stroke
			(width 0)
			(type solid)
		)
		(fill yes)
		(layer "In2.Cu")
		(net "M_C_CPU1_SA_CA<5>")
	)
	(gr_poly
		(pts
			(xy 78.98384 -253.192534) (xy 78.98384 -253.148084) (xy 78.783688 -253.148084) (xy 78.783688 -253.192534)
			(xy 78.883764 -253.29261)
		)
		(stroke
			(width 0)
			(type solid)
		)
		(fill yes)
		(layer "In2.Cu")
		(net "M_C_CPU1_SA_CA<1>")
	)
	(gr_poly
		(pts
			(xy 78.98384 -248.332498) (xy 78.98384 -248.288048) (xy 78.783688 -248.288048) (xy 78.783688 -248.332498)
			(xy 78.883764 -248.432574)
		)
		(stroke
			(width 0)
			(type solid)
		)
		(fill yes)
		(layer "In2.Cu")
		(net "M_C_CPU1_SA_CB<6>")
	)
	(gr_poly
		(pts
			(xy 78.98384 -245.092474) (xy 78.98384 -245.048024) (xy 78.783688 -245.048024) (xy 78.783688 -245.092474)
			(xy 78.883764 -245.19255)
		)
		(stroke
			(width 0)
			(type solid)
		)
		(fill yes)
		(layer "In2.Cu")
		(net "M_C_CPU1_SA_CB<2>")
	)
	(gr_poly
		(pts
			(xy 78.98384 -243.472462) (xy 78.98384 -243.428012) (xy 78.783688 -243.428012) (xy 78.783688 -243.472462)
			(xy 78.883764 -243.572538)
		)
		(stroke
			(width 0)
			(type solid)
		)
		(fill yes)
		(layer "In2.Cu")
		(net "M_C_CPU1_SA_DQ<30>")
	)
	(gr_poly
		(pts
			(xy 78.988666 -246.712486) (xy 78.988666 -246.664988) (xy 78.788768 -246.664988) (xy 78.788768 -246.712486)
			(xy 78.88859 -246.812562)
		)
		(stroke
			(width 0)
			(type solid)
		)
		(fill yes)
		(layer "In2.Cu")
		(net "M_C_CPU1_SA_DQS_DN<4>")
	)
	(gr_poly
		(pts
			(xy 78.99273 -256.432812) (xy 78.99273 -256.385314) (xy 78.792578 -256.385314) (xy 78.792578 -256.432812)
			(xy 78.892654 -256.532888)
		)
		(stroke
			(width 0)
			(type solid)
		)
		(fill yes)
		(layer "In2.Cu")
		(net "M_C_CPU1_CLK_DN<0>")
	)
	(gr_poly
		(pts
			(xy 78.995778 -227.286312) (xy 79.044038 -227.15347) (xy 78.911196 -227.104956) (xy 78.87081 -227.123752)
			(xy 78.955392 -227.305108)
		)
		(stroke
			(width 0)
			(type solid)
		)
		(fill yes)
		(layer "In2.Cu")
		(net "M_C_CPU1_SA_DQ<9>")
	)
	(gr_poly
		(pts
			(xy 78.995778 -224.04578) (xy 79.044038 -223.912938) (xy 78.911196 -223.864678) (xy 78.87081 -223.883474)
			(xy 78.955392 -224.064576)
		)
		(stroke
			(width 0)
			(type solid)
		)
		(fill yes)
		(layer "In2.Cu")
		(net "M_C_CPU1_SA_DQ<5>")
	)
	(gr_poly
		(pts
			(xy 78.99654 -240.232184) (xy 78.99654 -240.187734) (xy 78.796388 -240.187734) (xy 78.796388 -240.232184)
			(xy 78.896464 -240.33226)
		)
		(stroke
			(width 0)
			(type solid)
		)
		(fill yes)
		(layer "In2.Cu")
		(net "M_C_CPU1_SA_DQ<26>")
	)
	(gr_poly
		(pts
			(xy 78.999842 -230.51516) (xy 79.036418 -230.378762) (xy 78.899766 -230.342186) (xy 78.858618 -230.365808)
			(xy 78.958694 -230.539036)
		)
		(stroke
			(width 0)
			(type solid)
		)
		(fill yes)
		(layer "In2.Cu")
		(net "M_C_CPU1_SA_DQS_DN<6>")
	)
	(gr_poly
		(pts
			(xy 78.999842 -228.895402) (xy 79.036418 -228.75875) (xy 78.899766 -228.722174) (xy 78.858618 -228.745796)
			(xy 78.958694 -228.919024)
		)
		(stroke
			(width 0)
			(type solid)
		)
		(fill yes)
		(layer "In2.Cu")
		(net "M_C_CPU1_SA_DQS_DP<1>")
	)
	(gr_poly
		(pts
			(xy 79.001112 -225.65741) (xy 79.037688 -225.521012) (xy 78.90129 -225.484182) (xy 78.862682 -225.506534)
			(xy 78.962758 -225.679762)
		)
		(stroke
			(width 0)
			(type solid)
		)
		(fill yes)
		(layer "In2.Cu")
		(net "M_C_CPU1_SA_DQ<8>")
	)
	(gr_poly
		(pts
			(xy 79.200248 -293.177468) (xy 79.16164 -293.155116) (xy 79.025242 -293.191692) (xy 79.061818 -293.328344)
			(xy 79.100172 -293.350696)
		)
		(stroke
			(width 0)
			(type solid)
		)
		(fill yes)
		(layer "In2.Cu")
		(net "M_C_CPU1_SB_DQ<28>")
	)
	(gr_poly
		(pts
			(xy 79.266796 -280.3652) (xy 79.266796 -280.32075) (xy 79.066898 -280.32075) (xy 79.066898 -280.3652)
			(xy 79.16672 -280.465276)
		)
		(stroke
			(width 0)
			(type solid)
		)
		(fill yes)
		(layer "In2.Cu")
		(net "M_C_CPU1_SB_DQ<11>")
	)
	(gr_poly
		(pts
			(xy 79.266796 -273.885152) (xy 79.266796 -273.840702) (xy 79.066898 -273.840702) (xy 79.066898 -273.885152)
			(xy 79.16672 -273.985228)
		)
		(stroke
			(width 0)
			(type solid)
		)
		(fill yes)
		(layer "In2.Cu")
		(net "M_C_CPU1_SB_CB<3>")
	)
	(gr_poly
		(pts
			(xy 79.266796 -264.16508) (xy 79.266796 -264.12063) (xy 79.066898 -264.12063) (xy 79.066898 -264.16508)
			(xy 79.16672 -264.265156)
		)
		(stroke
			(width 0)
			(type solid)
		)
		(fill yes)
		(layer "In2.Cu")
		(net "M_C_CPU1_SB_CA<5>")
	)
	(gr_poly
		(pts
			(xy 79.267558 -284.007814) (xy 79.167482 -283.907738) (xy 79.067406 -284.007814) (xy 79.067406 -284.052264)
			(xy 79.267558 -284.052264)
		)
		(stroke
			(width 0)
			(type solid)
		)
		(fill yes)
		(layer "In2.Cu")
		(net "M_C_CPU1_SB_DQ<16>")
	)
	(gr_poly
		(pts
			(xy 79.267558 -282.387802) (xy 79.167482 -282.287726) (xy 79.067406 -282.387802) (xy 79.067406 -282.432252)
			(xy 79.267558 -282.432252)
		)
		(stroke
			(width 0)
			(type solid)
		)
		(fill yes)
		(layer "In2.Cu")
		(net "M_C_CPU1_SB_DQ<12>")
	)
	(gr_poly
		(pts
			(xy 79.267558 -279.147778) (xy 79.167482 -279.047702) (xy 79.067406 -279.147778) (xy 79.067406 -279.192228)
			(xy 79.267558 -279.192228)
		)
		(stroke
			(width 0)
			(type solid)
		)
		(fill yes)
		(layer "In2.Cu")
		(net "M_C_CPU1_SB_DQ<8>")
	)
	(gr_poly
		(pts
			(xy 79.267558 -274.287742) (xy 79.167482 -274.187666) (xy 79.067406 -274.287742) (xy 79.067406 -274.332192)
			(xy 79.267558 -274.332192)
		)
		(stroke
			(width 0)
			(type solid)
		)
		(fill yes)
		(layer "In2.Cu")
		(net "M_C_CPU1_SB_DQ<0>")
	)
	(gr_poly
		(pts
			(xy 79.267558 -264.56767) (xy 79.167482 -264.467594) (xy 79.067406 -264.56767) (xy 79.067406 -264.61212)
			(xy 79.267558 -264.61212)
		)
		(stroke
			(width 0)
			(type solid)
		)
		(fill yes)
		(layer "In2.Cu")
		(net "M_C_CPU1_SB_CA<6>")
	)
	(gr_poly
		(pts
			(xy 79.26832 -262.947658) (xy 79.168244 -262.847582) (xy 79.068168 -262.947658) (xy 79.068168 -262.992108)
			(xy 79.26832 -262.992108)
		)
		(stroke
			(width 0)
			(type solid)
		)
		(fill yes)
		(layer "In2.Cu")
		(net "M_C_CPU1_SB_CA<2>")
	)
	(gr_poly
		(pts
			(xy 79.26959 -287.247584) (xy 79.169514 -287.147508) (xy 79.069692 -287.247584) (xy 79.069692 -287.292034)
			(xy 79.26959 -287.292034)
		)
		(stroke
			(width 0)
			(type solid)
		)
		(fill yes)
		(layer "In2.Cu")
		(net "M_C_CPU1_SB_DQ<20>")
	)
	(gr_poly
		(pts
			(xy 79.26959 -285.627572) (xy 79.169514 -285.527496) (xy 79.069692 -285.627572) (xy 79.069692 -285.675324)
			(xy 79.26959 -285.675324)
		)
		(stroke
			(width 0)
			(type solid)
		)
		(fill yes)
		(layer "In2.Cu")
		(net "M_C_CPU1_SB_DQS_DP<2>")
	)
	(gr_poly
		(pts
			(xy 79.26959 -271.047464) (xy 79.169514 -270.947388) (xy 79.069692 -271.047464) (xy 79.069692 -271.095216)
			(xy 79.26959 -271.095216)
		)
		(stroke
			(width 0)
			(type solid)
		)
		(fill yes)
		(layer "In2.Cu")
		(net "M_C_CPU1_SB_DQS_DP<9>")
	)
	(gr_poly
		(pts
			(xy 79.28102 -288.464498) (xy 79.28102 -288.420048) (xy 79.080868 -288.420048) (xy 79.080868 -288.464498)
			(xy 79.180944 -288.564574)
		)
		(stroke
			(width 0)
			(type solid)
		)
		(fill yes)
		(layer "In2.Cu")
		(net "M_C_CPU1_SB_DQ<23>")
	)
	(gr_poly
		(pts
			(xy 79.283814 -286.844486) (xy 79.283814 -286.796988) (xy 79.083662 -286.796988) (xy 79.083662 -286.844486)
			(xy 79.183738 -286.944562)
		)
		(stroke
			(width 0)
			(type solid)
		)
		(fill yes)
		(layer "In2.Cu")
		(net "M_C_CPU1_SB_DQS_DP<7>")
	)
	(gr_poly
		(pts
			(xy 79.283814 -285.224474) (xy 79.283814 -285.180024) (xy 79.083662 -285.180024) (xy 79.083662 -285.224474)
			(xy 79.183738 -285.32455)
		)
		(stroke
			(width 0)
			(type solid)
		)
		(fill yes)
		(layer "In2.Cu")
		(net "M_C_CPU1_SB_DQ<19>")
	)
	(gr_poly
		(pts
			(xy 79.283814 -283.604462) (xy 79.283814 -283.560012) (xy 79.083662 -283.560012) (xy 79.083662 -283.604462)
			(xy 79.183738 -283.704538)
		)
		(stroke
			(width 0)
			(type solid)
		)
		(fill yes)
		(layer "In2.Cu")
		(net "M_C_CPU1_SB_DQ<15>")
	)
	(gr_poly
		(pts
			(xy 79.283814 -278.744426) (xy 79.283814 -278.699976) (xy 79.083662 -278.699976) (xy 79.083662 -278.744426)
			(xy 79.183738 -278.844502)
		)
		(stroke
			(width 0)
			(type solid)
		)
		(fill yes)
		(layer "In2.Cu")
		(net "M_C_CPU1_SB_DQ<7>")
	)
	(gr_poly
		(pts
			(xy 79.283814 -275.504402) (xy 79.283814 -275.459952) (xy 79.083662 -275.459952) (xy 79.083662 -275.504402)
			(xy 79.183738 -275.604478)
		)
		(stroke
			(width 0)
			(type solid)
		)
		(fill yes)
		(layer "In2.Cu")
		(net "M_C_CPU1_SB_DQ<3>")
	)
	(gr_poly
		(pts
			(xy 79.283814 -265.78433) (xy 79.283814 -265.73988) (xy 79.083662 -265.73988) (xy 79.083662 -265.78433)
			(xy 79.183738 -265.884406)
		)
		(stroke
			(width 0)
			(type solid)
		)
		(fill yes)
		(layer "In2.Cu")
		(net "M_C_CPU1_SB_CS_N<0>")
	)
	(gr_poly
		(pts
			(xy 79.288894 -277.124668) (xy 79.288894 -277.076916) (xy 79.088996 -277.076916) (xy 79.088996 -277.124668)
			(xy 79.188818 -277.22449)
		)
		(stroke
			(width 0)
			(type solid)
		)
		(fill yes)
		(layer "In2.Cu")
		(net "M_C_CPU1_SB_DQS_DP<5>")
	)
	(gr_poly
		(pts
			(xy 79.288894 -272.264632) (xy 79.288894 -272.21688) (xy 79.088996 -272.21688) (xy 79.088996 -272.264632)
			(xy 79.188818 -272.364454)
		)
		(stroke
			(width 0)
			(type solid)
		)
		(fill yes)
		(layer "In2.Cu")
		(net "M_C_CPU1_SB_DQS_DP<4>")
	)
	(gr_poly
		(pts
			(xy 79.296514 -277.528528) (xy 79.196438 -277.428452) (xy 79.096362 -277.528528) (xy 79.096362 -277.572978)
			(xy 79.296514 -277.572978)
		)
		(stroke
			(width 0)
			(type solid)
		)
		(fill yes)
		(layer "In2.Cu")
		(net "M_C_CPU1_SB_DQ<4>")
	)
	(gr_poly
		(pts
			(xy 79.296514 -275.908516) (xy 79.196438 -275.80844) (xy 79.096362 -275.908516) (xy 79.096362 -275.956014)
			(xy 79.296514 -275.956014)
		)
		(stroke
			(width 0)
			(type solid)
		)
		(fill yes)
		(layer "In2.Cu")
		(net "M_C_CPU1_SB_DQS_DP<0>")
	)
	(gr_poly
		(pts
			(xy 79.296514 -272.668492) (xy 79.196438 -272.568416) (xy 79.096362 -272.668492) (xy 79.096362 -272.712942)
			(xy 79.296514 -272.712942)
		)
		(stroke
			(width 0)
			(type solid)
		)
		(fill yes)
		(layer "In2.Cu")
		(net "M_C_CPU1_SB_CB<0>")
	)
	(gr_poly
		(pts
			(xy 79.361538 -227.01504) (xy 79.276956 -226.833938) (xy 79.23657 -226.852734) (xy 79.18831 -226.985576)
			(xy 79.321152 -227.033836)
		)
		(stroke
			(width 0)
			(type solid)
		)
		(fill yes)
		(layer "In2.Cu")
		(net "M_C_CPU1_SA_DQ<10>")
	)
	(gr_poly
		(pts
			(xy 79.370174 -223.77273) (xy 79.270098 -223.599502) (xy 79.231744 -223.6216) (xy 79.194914 -223.758252)
			(xy 79.331566 -223.794828)
		)
		(stroke
			(width 0)
			(type solid)
		)
		(fill yes)
		(layer "In2.Cu")
		(net "M_C_CPU1_SA_DQ<6>")
	)
	(gr_poly
		(pts
			(xy 79.371444 -225.396044) (xy 79.271622 -225.222816) (xy 79.233014 -225.245168) (xy 79.196438 -225.38182)
			(xy 79.33309 -225.418396)
		)
		(stroke
			(width 0)
			(type solid)
		)
		(fill yes)
		(layer "In2.Cu")
		(net "M_C_CPU1_SA_DQ<7>")
	)
	(gr_poly
		(pts
			(xy 79.37373 -230.253032) (xy 79.273654 -230.079804) (xy 79.232506 -230.103426) (xy 79.19593 -230.240078)
			(xy 79.332582 -230.276654)
		)
		(stroke
			(width 0)
			(type solid)
		)
		(fill yes)
		(layer "In2.Cu")
		(net "M_C_CPU1_SA_DQS_DN<1>")
	)
	(gr_poly
		(pts
			(xy 79.373984 -231.873552) (xy 79.274162 -231.700324) (xy 79.23276 -231.7242) (xy 79.196184 -231.860852)
			(xy 79.332836 -231.897428)
		)
		(stroke
			(width 0)
			(type solid)
		)
		(fill yes)
		(layer "In2.Cu")
		(net "M_C_CPU1_SA_DQS_DP<6>")
	)
	(gr_poly
		(pts
			(xy 79.4385 -255.622298) (xy 79.4385 -255.577848) (xy 79.238348 -255.577848) (xy 79.238348 -255.622298)
			(xy 79.338424 -255.722374)
		)
		(stroke
			(width 0)
			(type solid)
		)
		(fill yes)
		(layer "In2.Cu")
		(net "M_C_CPU1_SA_PAR")
	)
	(gr_poly
		(pts
			(xy 79.4385 -254.002286) (xy 79.4385 -253.957836) (xy 79.238348 -253.957836) (xy 79.238348 -254.002286)
			(xy 79.338424 -254.102362)
		)
		(stroke
			(width 0)
			(type solid)
		)
		(fill yes)
		(layer "In2.Cu")
		(net "M_C_CPU1_SA_CA<3>")
	)
	(gr_poly
		(pts
			(xy 79.4385 -252.382274) (xy 79.4385 -252.337824) (xy 79.238348 -252.337824) (xy 79.238348 -252.382274)
			(xy 79.338424 -252.48235)
		)
		(stroke
			(width 0)
			(type solid)
		)
		(fill yes)
		(layer "In2.Cu")
		(net "M_C_CPU1_SA_CS_N<1>")
	)
	(gr_poly
		(pts
			(xy 79.4385 -249.14225) (xy 79.4385 -249.0978) (xy 79.238348 -249.0978) (xy 79.238348 -249.14225)
			(xy 79.338424 -249.242326)
		)
		(stroke
			(width 0)
			(type solid)
		)
		(fill yes)
		(layer "In2.Cu")
		(net "M_C_CPU1_SA_CB<7>")
	)
	(gr_poly
		(pts
			(xy 79.4385 -247.522492) (xy 79.4385 -247.47474) (xy 79.238602 -247.47474) (xy 79.238602 -247.522492)
			(xy 79.338424 -247.622568)
		)
		(stroke
			(width 0)
			(type solid)
		)
		(fill yes)
		(layer "In2.Cu")
		(net "M_C_CPU1_SA_DQS_DP<9>")
	)
	(gr_poly
		(pts
			(xy 79.4385 -245.902226) (xy 79.4385 -245.857776) (xy 79.238348 -245.857776) (xy 79.238348 -245.902226)
			(xy 79.338424 -246.002302)
		)
		(stroke
			(width 0)
			(type solid)
		)
		(fill yes)
		(layer "In2.Cu")
		(net "M_C_CPU1_SA_CB<3>")
	)
	(gr_poly
		(pts
			(xy 79.4385 -244.282214) (xy 79.4385 -244.237764) (xy 79.238348 -244.237764) (xy 79.238348 -244.282214)
			(xy 79.338424 -244.38229)
		)
		(stroke
			(width 0)
			(type solid)
		)
		(fill yes)
		(layer "In2.Cu")
		(net "M_C_CPU1_SA_DQ<31>")
	)
	(gr_poly
		(pts
			(xy 79.4385 -241.04219) (xy 79.4385 -240.99774) (xy 79.238348 -240.99774) (xy 79.238348 -241.04219)
			(xy 79.338424 -241.142266)
		)
		(stroke
			(width 0)
			(type solid)
		)
		(fill yes)
		(layer "In2.Cu")
		(net "M_C_CPU1_SA_DQ<27>")
	)
	(gr_poly
		(pts
			(xy 79.44231 -256.025904) (xy 79.342488 -255.926082) (xy 79.242412 -256.025904) (xy 79.242412 -256.073656)
			(xy 79.44231 -256.073656)
		)
		(stroke
			(width 0)
			(type solid)
		)
		(fill yes)
		(layer "In2.Cu")
		(net "M_C_CPU1_CLK_DP<0>")
	)
	(gr_poly
		(pts
			(xy 79.4512 -250.762516) (xy 79.4512 -250.718066) (xy 79.251048 -250.718066) (xy 79.251048 -250.762516)
			(xy 79.351124 -250.862592)
		)
		(stroke
			(width 0)
			(type solid)
		)
		(fill yes)
		(layer "In2.Cu")
		(net "M_C_CPU1_RESET_N")
	)
	(gr_poly
		(pts
			(xy 79.4512 -241.44605) (xy 79.351124 -241.346228) (xy 79.251048 -241.44605) (xy 79.251048 -241.493802)
			(xy 79.4512 -241.493802)
		)
		(stroke
			(width 0)
			(type solid)
		)
		(fill yes)
		(layer "In2.Cu")
		(net "M_C_CPU1_SA_DQS_DP<3>")
	)
	(gr_poly
		(pts
			(xy 79.45882 -254.406146) (xy 79.358744 -254.30607) (xy 79.258922 -254.406146) (xy 79.258922 -254.450596)
			(xy 79.45882 -254.450596)
		)
		(stroke
			(width 0)
			(type solid)
		)
		(fill yes)
		(layer "In2.Cu")
		(net "M_C_CPU1_SA_CA<4>")
	)
	(gr_poly
		(pts
			(xy 79.45882 -252.786134) (xy 79.358744 -252.686312) (xy 79.258922 -252.786134) (xy 79.258922 -252.830584)
			(xy 79.45882 -252.830584)
		)
		(stroke
			(width 0)
			(type solid)
		)
		(fill yes)
		(layer "In2.Cu")
		(net "M_C_CPU1_SA_CA<0>")
	)
	(gr_poly
		(pts
			(xy 79.45882 -247.926098) (xy 79.358744 -247.826276) (xy 79.258922 -247.926098) (xy 79.258922 -247.970548)
			(xy 79.45882 -247.970548)
		)
		(stroke
			(width 0)
			(type solid)
		)
		(fill yes)
		(layer "In2.Cu")
		(net "M_C_CPU1_SA_CB<4>")
	)
	(gr_poly
		(pts
			(xy 79.45882 -246.305832) (xy 79.358744 -246.20601) (xy 79.258668 -246.305832) (xy 79.258668 -246.353584)
			(xy 79.45882 -246.353584)
		)
		(stroke
			(width 0)
			(type solid)
		)
		(fill yes)
		(layer "In2.Cu")
		(net "M_C_CPU1_SA_DQS_DP<4>")
	)
	(gr_poly
		(pts
			(xy 79.45882 -244.686074) (xy 79.358744 -244.586252) (xy 79.258922 -244.686074) (xy 79.258922 -244.730524)
			(xy 79.45882 -244.730524)
		)
		(stroke
			(width 0)
			(type solid)
		)
		(fill yes)
		(layer "In2.Cu")
		(net "M_C_CPU1_SA_CB<0>")
	)
	(gr_poly
		(pts
			(xy 79.45882 -243.066062) (xy 79.358744 -242.96624) (xy 79.258922 -243.066062) (xy 79.258922 -243.110512)
			(xy 79.45882 -243.110512)
		)
		(stroke
			(width 0)
			(type solid)
		)
		(fill yes)
		(layer "In2.Cu")
		(net "M_C_CPU1_SA_DQ<28>")
	)
	(gr_poly
		(pts
			(xy 79.465678 -239.825276) (xy 79.365602 -239.725454) (xy 79.26578 -239.825276) (xy 79.26578 -239.86998)
			(xy 79.465678 -239.86998)
		)
		(stroke
			(width 0)
			(type solid)
		)
		(fill yes)
		(layer "In2.Cu")
		(net "M_C_CPU1_SA_DQ<24>")
	)
	(gr_poly
		(pts
			(xy 79.465678 -224.856548) (xy 79.513938 -224.723706) (xy 79.381096 -224.675192) (xy 79.340964 -224.693988)
			(xy 79.425546 -224.875344)
		)
		(stroke
			(width 0)
			(type solid)
		)
		(fill yes)
		(layer "In2.Cu")
		(net "M_C_CPU1_SA_DQ<5>")
	)
	(gr_poly
		(pts
			(xy 79.466948 -242.662456) (xy 79.466948 -242.614704) (xy 79.26705 -242.614704) (xy 79.26705 -242.662456)
			(xy 79.367126 -242.762532)
		)
		(stroke
			(width 0)
			(type solid)
		)
		(fill yes)
		(layer "In2.Cu")
		(net "M_C_CPU1_SA_DQS_DP<8>")
	)
	(gr_poly
		(pts
			(xy 79.469234 -226.463098) (xy 79.50581 -226.326446) (xy 79.369412 -226.28987) (xy 79.330804 -226.311968)
			(xy 79.43088 -226.485196)
		)
		(stroke
			(width 0)
			(type solid)
		)
		(fill yes)
		(layer "In2.Cu")
		(net "M_C_CPU1_SA_DQ<8>")
	)
	(gr_poly
		(pts
			(xy 79.469488 -231.324404) (xy 79.506064 -231.187752) (xy 79.369412 -231.151176) (xy 79.328264 -231.175052)
			(xy 79.428086 -231.34828)
		)
		(stroke
			(width 0)
			(type solid)
		)
		(fill yes)
		(layer "In2.Cu")
		(net "M_C_CPU1_SA_DQS_DN<6>")
	)
	(gr_poly
		(pts
			(xy 79.469742 -229.704392) (xy 79.506318 -229.56774) (xy 79.369666 -229.531164) (xy 79.328518 -229.55504)
			(xy 79.42834 -229.728268)
		)
		(stroke
			(width 0)
			(type solid)
		)
		(fill yes)
		(layer "In2.Cu")
		(net "M_C_CPU1_SA_DQS_DP<1>")
	)
	(gr_poly
		(pts
			(xy 79.469742 -228.085904) (xy 79.506318 -227.949252) (xy 79.369666 -227.912676) (xy 79.331312 -227.934774)
			(xy 79.431388 -228.108002)
		)
		(stroke
			(width 0)
			(type solid)
		)
		(fill yes)
		(layer "In2.Cu")
		(net "M_C_CPU1_SA_DQ<9>")
	)
	(gr_poly
		(pts
			(xy 79.469996 -223.225868) (xy 79.506572 -223.089216) (xy 79.36992 -223.05264) (xy 79.331566 -223.074992)
			(xy 79.431642 -223.24822)
		)
		(stroke
			(width 0)
			(type solid)
		)
		(fill yes)
		(layer "In2.Cu")
		(net "M_C_CPU1_SA_DQ<4>")
	)
	(gr_poly
		(pts
			(xy 79.65567 -262.08101) (xy 79.585058 -261.958582) (xy 79.46263 -262.029194) (xy 79.450946 -262.07212)
			(xy 79.64424 -262.123936)
		)
		(stroke
			(width 0)
			(type solid)
		)
		(fill yes)
		(layer "In2.Cu")
		(net "M_C_CPU1_SB_CA<0>")
	)
	(gr_poly
		(pts
			(xy 79.680562 -292.349428) (xy 79.642208 -292.327076) (xy 79.505556 -292.363652) (xy 79.542132 -292.500304)
			(xy 79.580486 -292.522656)
		)
		(stroke
			(width 0)
			(type solid)
		)
		(fill yes)
		(layer "In2.Cu")
		(net "M_C_CPU1_SB_DQ<28>")
	)
	(gr_poly
		(pts
			(xy 79.737458 -287.654238) (xy 79.737458 -287.609788) (xy 79.537306 -287.609788) (xy 79.537306 -287.654238)
			(xy 79.637382 -287.754314)
		)
		(stroke
			(width 0)
			(type solid)
		)
		(fill yes)
		(layer "In2.Cu")
		(net "M_C_CPU1_SB_DQ<22>")
	)
	(gr_poly
		(pts
			(xy 79.738728 -279.958546) (xy 79.638652 -279.85847) (xy 79.538576 -279.958546) (xy 79.538576 -280.002996)
			(xy 79.738728 -280.002996)
		)
		(stroke
			(width 0)
			(type solid)
		)
		(fill yes)
		(layer "In2.Cu")
		(net "M_C_CPU1_SB_DQ<9>")
	)
	(gr_poly
		(pts
			(xy 79.738728 -273.478498) (xy 79.638652 -273.378422) (xy 79.538576 -273.478498) (xy 79.538576 -273.522948)
			(xy 79.738728 -273.522948)
		)
		(stroke
			(width 0)
			(type solid)
		)
		(fill yes)
		(layer "In2.Cu")
		(net "M_C_CPU1_SB_CB<1>")
	)
	(gr_poly
		(pts
			(xy 79.738728 -263.758426) (xy 79.638652 -263.65835) (xy 79.538576 -263.758426) (xy 79.538576 -263.802876)
			(xy 79.738728 -263.802876)
		)
		(stroke
			(width 0)
			(type solid)
		)
		(fill yes)
		(layer "In2.Cu")
		(net "M_C_CPU1_SB_CA<4>")
	)
	(gr_poly
		(pts
			(xy 79.73949 -284.414468) (xy 79.73949 -284.369764) (xy 79.539592 -284.369764) (xy 79.539592 -284.414468)
			(xy 79.639414 -284.51429)
		)
		(stroke
			(width 0)
			(type solid)
		)
		(fill yes)
		(layer "In2.Cu")
		(net "M_C_CPU1_SB_DQ<18>")
	)
	(gr_poly
		(pts
			(xy 79.73949 -282.794456) (xy 79.73949 -282.749752) (xy 79.539592 -282.749752) (xy 79.539592 -282.794456)
			(xy 79.639414 -282.894278)
		)
		(stroke
			(width 0)
			(type solid)
		)
		(fill yes)
		(layer "In2.Cu")
		(net "M_C_CPU1_SB_DQ<14>")
	)
	(gr_poly
		(pts
			(xy 79.73949 -279.554432) (xy 79.73949 -279.509728) (xy 79.539592 -279.509728) (xy 79.539592 -279.554432)
			(xy 79.639414 -279.654254)
		)
		(stroke
			(width 0)
			(type solid)
		)
		(fill yes)
		(layer "In2.Cu")
		(net "M_C_CPU1_SB_DQ<10>")
	)
	(gr_poly
		(pts
			(xy 79.73949 -274.694396) (xy 79.73949 -274.649692) (xy 79.539592 -274.649692) (xy 79.539592 -274.694396)
			(xy 79.639414 -274.794218)
		)
		(stroke
			(width 0)
			(type solid)
		)
		(fill yes)
		(layer "In2.Cu")
		(net "M_C_CPU1_SB_DQ<2>")
	)
	(gr_poly
		(pts
			(xy 79.73949 -266.594336) (xy 79.73949 -266.549632) (xy 79.539592 -266.549632) (xy 79.539592 -266.594336)
			(xy 79.639414 -266.694158)
		)
		(stroke
			(width 0)
			(type solid)
		)
		(fill yes)
		(layer "In2.Cu")
		(net "M_C_CPU1_SB_CS_N<1>")
	)
	(gr_poly
		(pts
			(xy 79.73949 -264.974324) (xy 79.73949 -264.92962) (xy 79.539592 -264.92962) (xy 79.539592 -264.974324)
			(xy 79.639414 -265.074146)
		)
		(stroke
			(width 0)
			(type solid)
		)
		(fill yes)
		(layer "In2.Cu")
		(net "M_C_CPU1_SB_PAR")
	)
	(gr_poly
		(pts
			(xy 79.740506 -263.354058) (xy 79.740506 -263.309608) (xy 79.540354 -263.309608) (xy 79.540354 -263.354058)
			(xy 79.64043 -263.454134)
		)
		(stroke
			(width 0)
			(type solid)
		)
		(fill yes)
		(layer "In2.Cu")
		(net "M_C_CPU1_SB_CA<3>")
	)
	(gr_poly
		(pts
			(xy 79.751174 -288.058098) (xy 79.651098 -287.958022) (xy 79.551022 -288.058098) (xy 79.551022 -288.102548)
			(xy 79.751174 -288.102548)
		)
		(stroke
			(width 0)
			(type solid)
		)
		(fill yes)
		(layer "In2.Cu")
		(net "M_C_CPU1_SB_DQ<21>")
	)
	(gr_poly
		(pts
			(xy 79.758794 -286.437832) (xy 79.658718 -286.337756) (xy 79.558896 -286.437832) (xy 79.558896 -286.485584)
			(xy 79.758794 -286.485584)
		)
		(stroke
			(width 0)
			(type solid)
		)
		(fill yes)
		(layer "In2.Cu")
		(net "M_C_CPU1_SB_DQS_DN<7>")
	)
	(gr_poly
		(pts
			(xy 79.758794 -284.818074) (xy 79.658718 -284.718252) (xy 79.558896 -284.818074) (xy 79.558896 -284.862524)
			(xy 79.758794 -284.862524)
		)
		(stroke
			(width 0)
			(type solid)
		)
		(fill yes)
		(layer "In2.Cu")
		(net "M_C_CPU1_SB_DQ<17>")
	)
	(gr_poly
		(pts
			(xy 79.758794 -283.198062) (xy 79.658718 -283.09824) (xy 79.558896 -283.198062) (xy 79.558896 -283.242512)
			(xy 79.758794 -283.242512)
		)
		(stroke
			(width 0)
			(type solid)
		)
		(fill yes)
		(layer "In2.Cu")
		(net "M_C_CPU1_SB_DQ<13>")
	)
	(gr_poly
		(pts
			(xy 79.758794 -278.338026) (xy 79.658718 -278.238204) (xy 79.558896 -278.338026) (xy 79.558896 -278.382476)
			(xy 79.758794 -278.382476)
		)
		(stroke
			(width 0)
			(type solid)
		)
		(fill yes)
		(layer "In2.Cu")
		(net "M_C_CPU1_SB_DQ<5>")
	)
	(gr_poly
		(pts
			(xy 79.758794 -276.71776) (xy 79.658718 -276.617938) (xy 79.558896 -276.71776) (xy 79.558896 -276.765512)
			(xy 79.758794 -276.765512)
		)
		(stroke
			(width 0)
			(type solid)
		)
		(fill yes)
		(layer "In2.Cu")
		(net "M_C_CPU1_SB_DQS_DN<5>")
	)
	(gr_poly
		(pts
			(xy 79.758794 -275.098002) (xy 79.658718 -274.99818) (xy 79.558896 -275.098002) (xy 79.558896 -275.142452)
			(xy 79.758794 -275.142452)
		)
		(stroke
			(width 0)
			(type solid)
		)
		(fill yes)
		(layer "In2.Cu")
		(net "M_C_CPU1_SB_DQ<1>")
	)
	(gr_poly
		(pts
			(xy 79.758794 -271.857724) (xy 79.658718 -271.757902) (xy 79.558896 -271.857724) (xy 79.558896 -271.905476)
			(xy 79.758794 -271.905476)
		)
		(stroke
			(width 0)
			(type solid)
		)
		(fill yes)
		(layer "In2.Cu")
		(net "M_C_CPU1_SB_DQS_DN<4>")
	)
	(gr_poly
		(pts
			(xy 79.765652 -277.935436) (xy 79.765652 -277.890732) (xy 79.565754 -277.890732) (xy 79.565754 -277.935436)
			(xy 79.665576 -278.035258)
		)
		(stroke
			(width 0)
			(type solid)
		)
		(fill yes)
		(layer "In2.Cu")
		(net "M_C_CPU1_SB_DQ<6>")
	)
	(gr_poly
		(pts
			(xy 79.765652 -276.315424) (xy 79.765652 -276.267926) (xy 79.565754 -276.267926) (xy 79.565754 -276.315424)
			(xy 79.665576 -276.4155)
		)
		(stroke
			(width 0)
			(type solid)
		)
		(fill yes)
		(layer "In2.Cu")
		(net "M_C_CPU1_SB_DQS_DN<0>")
	)
	(gr_poly
		(pts
			(xy 79.765652 -273.0754) (xy 79.765652 -273.030696) (xy 79.565754 -273.030696) (xy 79.565754 -273.0754)
			(xy 79.665576 -273.175222)
		)
		(stroke
			(width 0)
			(type solid)
		)
		(fill yes)
		(layer "In2.Cu")
		(net "M_C_CPU1_SB_CB<2>")
	)
	(gr_poly
		(pts
			(xy 79.765652 -269.83436) (xy 79.765652 -269.789656) (xy 79.565754 -269.789656) (xy 79.565754 -269.83436)
			(xy 79.66583 -269.934182)
		)
		(stroke
			(width 0)
			(type solid)
		)
		(fill yes)
		(layer "In2.Cu")
		(net "M_C_CPU1_SB_CB<6>")
	)
	(gr_poly
		(pts
			(xy 79.806546 -294.672004) (xy 79.76997 -294.535352) (xy 79.731362 -294.513254) (xy 79.631286 -294.686482)
			(xy 79.669894 -294.70858)
		)
		(stroke
			(width 0)
			(type solid)
		)
		(fill yes)
		(layer "In2.Cu")
		(net "M_C_CPU1_SB_DQ<30>")
	)
	(gr_poly
		(pts
			(xy 79.84109 -227.824284) (xy 79.741014 -227.651056) (xy 79.70266 -227.673408) (xy 79.666084 -227.81006)
			(xy 79.802482 -227.846636)
		)
		(stroke
			(width 0)
			(type solid)
		)
		(fill yes)
		(layer "In2.Cu")
		(net "M_C_CPU1_SA_DQ<10>")
	)
	(gr_poly
		(pts
			(xy 79.841344 -229.445058) (xy 79.741268 -229.27183) (xy 79.702914 -229.293928) (xy 79.666338 -229.43058)
			(xy 79.80299 -229.467156)
		)
		(stroke
			(width 0)
			(type solid)
		)
		(fill yes)
		(layer "In2.Cu")
		(net "M_C_CPU1_SA_DQ<11>")
	)
	(gr_poly
		(pts
			(xy 79.841344 -226.205034) (xy 79.741522 -226.031806) (xy 79.702914 -226.054158) (xy 79.666338 -226.190556)
			(xy 79.80299 -226.227386)
		)
		(stroke
			(width 0)
			(type solid)
		)
		(fill yes)
		(layer "In2.Cu")
		(net "M_C_CPU1_SA_DQ<7>")
	)
	(gr_poly
		(pts
			(xy 79.841344 -224.584768) (xy 79.741268 -224.41154) (xy 79.70266 -224.433638) (xy 79.666084 -224.57029)
			(xy 79.802736 -224.606866)
		)
		(stroke
			(width 0)
			(type solid)
		)
		(fill yes)
		(layer "In2.Cu")
		(net "M_C_CPU1_SA_DQ<6>")
	)
	(gr_poly
		(pts
			(xy 79.843122 -232.682288) (xy 79.7433 -232.50906) (xy 79.701898 -232.532936) (xy 79.665322 -232.669334)
			(xy 79.801974 -232.706164)
		)
		(stroke
			(width 0)
			(type solid)
		)
		(fill yes)
		(layer "In2.Cu")
		(net "M_C_CPU1_SA_DQS_DP<6>")
	)
	(gr_poly
		(pts
			(xy 79.843376 -231.06253) (xy 79.743554 -230.889302) (xy 79.702152 -230.912924) (xy 79.665576 -231.049576)
			(xy 79.802228 -231.086152)
		)
		(stroke
			(width 0)
			(type solid)
		)
		(fill yes)
		(layer "In2.Cu")
		(net "M_C_CPU1_SA_DQS_DN<1>")
	)
	(gr_poly
		(pts
			(xy 79.844138 -222.962978) (xy 79.744062 -222.78975) (xy 79.702914 -222.813626) (xy 79.666338 -222.950278)
			(xy 79.802736 -222.986854)
		)
		(stroke
			(width 0)
			(type solid)
		)
		(fill yes)
		(layer "In2.Cu")
		(net "M_C_CPU1_SA_DQS_DP<5>")
	)
	(gr_poly
		(pts
			(xy 79.901288 -240.2332) (xy 79.901288 -240.189004) (xy 79.70139 -240.189004) (xy 79.70139 -240.2332)
			(xy 79.801466 -240.333276)
		)
		(stroke
			(width 0)
			(type solid)
		)
		(fill yes)
		(layer "In2.Cu")
		(net "M_C_CPU1_SA_DQ<26>")
	)
	(gr_poly
		(pts
			(xy 79.91221 -254.8128) (xy 79.91221 -254.76835) (xy 79.712312 -254.76835) (xy 79.712312 -254.8128)
			(xy 79.812388 -254.912876)
		)
		(stroke
			(width 0)
			(type solid)
		)
		(fill yes)
		(layer "In2.Cu")
		(net "M_C_CPU1_SA_CA<5>")
	)
	(gr_poly
		(pts
			(xy 79.91221 -253.192788) (xy 79.91221 -253.148338) (xy 79.712312 -253.148338) (xy 79.712312 -253.192788)
			(xy 79.812388 -253.292864)
		)
		(stroke
			(width 0)
			(type solid)
		)
		(fill yes)
		(layer "In2.Cu")
		(net "M_C_CPU1_SA_CA<1>")
	)
	(gr_poly
		(pts
			(xy 79.91221 -251.572776) (xy 79.91221 -251.528326) (xy 79.712312 -251.528326) (xy 79.712312 -251.572776)
			(xy 79.812388 -251.672852)
		)
		(stroke
			(width 0)
			(type solid)
		)
		(fill yes)
		(layer "In2.Cu")
		(net "M_C_CPU1_SA_CS_N<0>")
	)
	(gr_poly
		(pts
			(xy 79.91221 -248.332752) (xy 79.91221 -248.288302) (xy 79.712312 -248.288302) (xy 79.712312 -248.332752)
			(xy 79.812388 -248.432828)
		)
		(stroke
			(width 0)
			(type solid)
		)
		(fill yes)
		(layer "In2.Cu")
		(net "M_C_CPU1_SA_CB<6>")
	)
	(gr_poly
		(pts
			(xy 79.91221 -246.71274) (xy 79.91221 -246.665242) (xy 79.712312 -246.665242) (xy 79.712312 -246.71274)
			(xy 79.812134 -246.812816)
		)
		(stroke
			(width 0)
			(type solid)
		)
		(fill yes)
		(layer "In2.Cu")
		(net "M_C_CPU1_SA_DQS_DN<4>")
	)
	(gr_poly
		(pts
			(xy 79.91221 -245.092728) (xy 79.91221 -245.048278) (xy 79.712312 -245.048278) (xy 79.712312 -245.092728)
			(xy 79.812388 -245.192804)
		)
		(stroke
			(width 0)
			(type solid)
		)
		(fill yes)
		(layer "In2.Cu")
		(net "M_C_CPU1_SA_CB<2>")
	)
	(gr_poly
		(pts
			(xy 79.91221 -243.472716) (xy 79.91221 -243.428266) (xy 79.712312 -243.428266) (xy 79.712312 -243.472716)
			(xy 79.812388 -243.572538)
		)
		(stroke
			(width 0)
			(type solid)
		)
		(fill yes)
		(layer "In2.Cu")
		(net "M_C_CPU1_SA_DQ<30>")
	)
	(gr_poly
		(pts
			(xy 79.91221 -236.992922) (xy 79.91221 -236.94517) (xy 79.712312 -236.94517) (xy 79.712312 -236.992922)
			(xy 79.812388 -237.092744)
		)
		(stroke
			(width 0)
			(type solid)
		)
		(fill yes)
		(layer "In2.Cu")
		(net "M_C_CPU1_SA_DQS_DN<2>")
	)
	(gr_poly
		(pts
			(xy 79.91475 -235.372402) (xy 79.91475 -235.327952) (xy 79.714852 -235.327952) (xy 79.714852 -235.372402)
			(xy 79.814928 -235.472478)
		)
		(stroke
			(width 0)
			(type solid)
		)
		(fill yes)
		(layer "In2.Cu")
		(net "M_C_CPU1_SA_DQ<18>")
	)
	(gr_poly
		(pts
			(xy 79.9211 -256.432812) (xy 79.9211 -256.38506) (xy 79.720948 -256.38506) (xy 79.720948 -256.432812)
			(xy 79.821024 -256.532634)
		)
		(stroke
			(width 0)
			(type solid)
		)
		(fill yes)
		(layer "In2.Cu")
		(net "M_C_CPU1_CLK_DN<0>")
	)
	(gr_poly
		(pts
			(xy 79.9211 -250.35637) (xy 79.821024 -250.256294) (xy 79.720948 -250.35637) (xy 79.720948 -250.40082)
			(xy 79.9211 -250.40082)
		)
		(stroke
			(width 0)
			(type solid)
		)
		(fill yes)
		(layer "In2.Cu")
		(net "M_C_CPU1_ALERT_R_N")
	)
	(gr_poly
		(pts
			(xy 79.9211 -242.256056) (xy 79.821024 -242.156234) (xy 79.720948 -242.256056) (xy 79.720948 -242.303808)
			(xy 79.9211 -242.303808)
		)
		(stroke
			(width 0)
			(type solid)
		)
		(fill yes)
		(layer "In2.Cu")
		(net "M_C_CPU1_SA_DQS_DN<8>")
	)
	(gr_poly
		(pts
			(xy 79.9211 -241.852704) (xy 79.9211 -241.804952) (xy 79.720948 -241.804952) (xy 79.720948 -241.852704)
			(xy 79.821024 -241.952526)
		)
		(stroke
			(width 0)
			(type solid)
		)
		(fill yes)
		(layer "In2.Cu")
		(net "M_C_CPU1_SA_DQS_DN<3>")
	)
	(gr_poly
		(pts
			(xy 79.935578 -227.285296) (xy 79.984092 -227.152454) (xy 79.85125 -227.10394) (xy 79.810864 -227.122736)
			(xy 79.895446 -227.304092)
		)
		(stroke
			(width 0)
			(type solid)
		)
		(fill yes)
		(layer "In2.Cu")
		(net "M_C_CPU1_SA_DQ<8>")
	)
	(gr_poly
		(pts
			(xy 79.936848 -247.116346) (xy 79.837026 -247.01627) (xy 79.73695 -247.116346) (xy 79.73695 -247.163844)
			(xy 79.936848 -247.163844)
		)
		(stroke
			(width 0)
			(type solid)
		)
		(fill yes)
		(layer "In2.Cu")
		(net "M_C_CPU1_SA_DQS_DN<9>")
	)
	(gr_poly
		(pts
			(xy 79.937102 -255.21666) (xy 79.837026 -255.116584) (xy 79.73695 -255.21666) (xy 79.73695 -255.26111)
			(xy 79.937102 -255.26111)
		)
		(stroke
			(width 0)
			(type solid)
		)
		(fill yes)
		(layer "In2.Cu")
		(net "M_C_CPU1_SA_CA<6>")
	)
	(gr_poly
		(pts
			(xy 79.937102 -253.596648) (xy 79.837026 -253.496572) (xy 79.73695 -253.596648) (xy 79.73695 -253.641098)
			(xy 79.937102 -253.641098)
		)
		(stroke
			(width 0)
			(type solid)
		)
		(fill yes)
		(layer "In2.Cu")
		(net "M_C_CPU1_SA_CA<2>")
	)
	(gr_poly
		(pts
			(xy 79.937102 -248.736612) (xy 79.837026 -248.636536) (xy 79.73695 -248.736612) (xy 79.73695 -248.781062)
			(xy 79.937102 -248.781062)
		)
		(stroke
			(width 0)
			(type solid)
		)
		(fill yes)
		(layer "In2.Cu")
		(net "M_C_CPU1_SA_CB<5>")
	)
	(gr_poly
		(pts
			(xy 79.937102 -245.496588) (xy 79.837026 -245.396512) (xy 79.73695 -245.496588) (xy 79.73695 -245.541038)
			(xy 79.937102 -245.541038)
		)
		(stroke
			(width 0)
			(type solid)
		)
		(fill yes)
		(layer "In2.Cu")
		(net "M_C_CPU1_SA_CB<1>")
	)
	(gr_poly
		(pts
			(xy 79.937102 -243.876576) (xy 79.837026 -243.7765) (xy 79.73695 -243.876576) (xy 79.73695 -243.921026)
			(xy 79.937102 -243.921026)
		)
		(stroke
			(width 0)
			(type solid)
		)
		(fill yes)
		(layer "In2.Cu")
		(net "M_C_CPU1_SA_DQ<29>")
	)
	(gr_poly
		(pts
			(xy 79.937102 -240.636552) (xy 79.837026 -240.536476) (xy 79.73695 -240.636552) (xy 79.73695 -240.681002)
			(xy 79.937102 -240.681002)
		)
		(stroke
			(width 0)
			(type solid)
		)
		(fill yes)
		(layer "In2.Cu")
		(net "M_C_CPU1_SA_DQ<25>")
	)
	(gr_poly
		(pts
			(xy 79.938372 -225.653092) (xy 79.974948 -225.51644) (xy 79.838296 -225.479864) (xy 79.799688 -225.501962)
			(xy 79.899764 -225.67519)
		)
		(stroke
			(width 0)
			(type solid)
		)
		(fill yes)
		(layer "In2.Cu")
		(net "M_C_CPU1_SA_DQ<5>")
	)
	(gr_poly
		(pts
			(xy 79.939388 -228.894894) (xy 79.975964 -228.758496) (xy 79.839312 -228.721666) (xy 79.800704 -228.744018)
			(xy 79.90078 -228.917246)
		)
		(stroke
			(width 0)
			(type solid)
		)
		(fill yes)
		(layer "In2.Cu")
		(net "M_C_CPU1_SA_DQ<9>")
	)
	(gr_poly
		(pts
			(xy 79.939896 -230.51516) (xy 79.976472 -230.378508) (xy 79.83982 -230.341932) (xy 79.798672 -230.365808)
			(xy 79.898748 -230.539036)
		)
		(stroke
			(width 0)
			(type solid)
		)
		(fill yes)
		(layer "In2.Cu")
		(net "M_C_CPU1_SA_DQS_DP<1>")
	)
	(gr_poly
		(pts
			(xy 79.940404 -232.13568) (xy 79.97698 -231.999282) (xy 79.840328 -231.962452) (xy 79.79918 -231.986328)
			(xy 79.899002 -232.159556)
		)
		(stroke
			(width 0)
			(type solid)
		)
		(fill yes)
		(layer "In2.Cu")
		(net "M_C_CPU1_SA_DQS_DN<6>")
	)
	(gr_poly
		(pts
			(xy 79.940404 -224.035874) (xy 79.97698 -223.899222) (xy 79.840328 -223.862646) (xy 79.801974 -223.884998)
			(xy 79.90205 -224.058226)
		)
		(stroke
			(width 0)
			(type solid)
		)
		(fill yes)
		(layer "In2.Cu")
		(net "M_C_CPU1_SA_DQ<4>")
	)
	(gr_poly
		(pts
			(xy 79.940912 -222.416624) (xy 79.977488 -222.279972) (xy 79.840836 -222.243396) (xy 79.799688 -222.267272)
			(xy 79.89951 -222.4405)
		)
		(stroke
			(width 0)
			(type solid)
		)
		(fill yes)
		(layer "In2.Cu")
		(net "M_C_CPU1_SA_DQS_DN<5>")
	)
	(gr_poly
		(pts
			(xy 79.974948 -233.741214) (xy 79.971138 -233.697018) (xy 79.771748 -233.71429) (xy 79.775812 -233.75874)
			(xy 79.884016 -233.849672)
		)
		(stroke
			(width 0)
			(type solid)
		)
		(fill yes)
		(layer "In2.Cu")
		(net "M_C_CPU1_SA_DQ<14>")
	)
	(gr_poly
		(pts
			(xy 80.141318 -294.795956) (xy 80.10271 -294.773858) (xy 79.966058 -294.810434) (xy 80.002634 -294.947086)
			(xy 80.041242 -294.969184)
		)
		(stroke
			(width 0)
			(type solid)
		)
		(fill yes)
		(layer "In2.Cu")
		(net "M_C_CPU1_SB_DQ<29>")
	)
	(gr_poly
		(pts
			(xy 80.201262 -277.527512) (xy 80.10144 -277.427436) (xy 80.001364 -277.527512) (xy 80.001364 -277.571708)
			(xy 80.201262 -277.571708)
		)
		(stroke
			(width 0)
			(type solid)
		)
		(fill yes)
		(layer "In2.Cu")
		(net "M_C_CPU1_SB_DQ<4>")
	)
	(gr_poly
		(pts
			(xy 80.201262 -275.907246) (xy 80.10144 -275.80717) (xy 80.001364 -275.907246) (xy 80.001364 -275.954744)
			(xy 80.201262 -275.954744)
		)
		(stroke
			(width 0)
			(type solid)
		)
		(fill yes)
		(layer "In2.Cu")
		(net "M_C_CPU1_SB_DQS_DP<0>")
	)
	(gr_poly
		(pts
			(xy 80.201262 -272.667476) (xy 80.10144 -272.5674) (xy 80.001364 -272.667476) (xy 80.001364 -272.711672)
			(xy 80.201262 -272.711672)
		)
		(stroke
			(width 0)
			(type solid)
		)
		(fill yes)
		(layer "In2.Cu")
		(net "M_C_CPU1_SB_CB<0>")
	)
	(gr_poly
		(pts
			(xy 80.212184 -286.84474) (xy 80.212184 -286.796988) (xy 80.012286 -286.796988) (xy 80.012286 -286.84474)
			(xy 80.112362 -286.944816)
		)
		(stroke
			(width 0)
			(type solid)
		)
		(fill yes)
		(layer "In2.Cu")
		(net "M_C_CPU1_SB_DQS_DP<7>")
	)
	(gr_poly
		(pts
			(xy 80.212184 -285.224728) (xy 80.212184 -285.180278) (xy 80.012286 -285.180278) (xy 80.012286 -285.224728)
			(xy 80.112362 -285.324804)
		)
		(stroke
			(width 0)
			(type solid)
		)
		(fill yes)
		(layer "In2.Cu")
		(net "M_C_CPU1_SB_DQ<19>")
	)
	(gr_poly
		(pts
			(xy 80.212184 -283.604716) (xy 80.212184 -283.560266) (xy 80.012286 -283.560266) (xy 80.012286 -283.604716)
			(xy 80.112362 -283.704792)
		)
		(stroke
			(width 0)
			(type solid)
		)
		(fill yes)
		(layer "In2.Cu")
		(net "M_C_CPU1_SB_DQ<15>")
	)
	(gr_poly
		(pts
			(xy 80.212184 -281.984958) (xy 80.212184 -281.937206) (xy 80.012286 -281.937206) (xy 80.012286 -281.984958)
			(xy 80.112362 -282.08478)
		)
		(stroke
			(width 0)
			(type solid)
		)
		(fill yes)
		(layer "In2.Cu")
		(net "M_C_CPU1_SB_DQS_DP<6>")
	)
	(gr_poly
		(pts
			(xy 80.212184 -278.74468) (xy 80.212184 -278.70023) (xy 80.012286 -278.70023) (xy 80.012286 -278.74468)
			(xy 80.112362 -278.844756)
		)
		(stroke
			(width 0)
			(type solid)
		)
		(fill yes)
		(layer "In2.Cu")
		(net "M_C_CPU1_SB_DQ<7>")
	)
	(gr_poly
		(pts
			(xy 80.212184 -277.124922) (xy 80.212184 -277.07717) (xy 80.012286 -277.07717) (xy 80.012286 -277.124922)
			(xy 80.112362 -277.224744)
		)
		(stroke
			(width 0)
			(type solid)
		)
		(fill yes)
		(layer "In2.Cu")
		(net "M_C_CPU1_SB_DQS_DP<5>")
	)
	(gr_poly
		(pts
			(xy 80.212184 -275.504656) (xy 80.212184 -275.460206) (xy 80.012286 -275.460206) (xy 80.012286 -275.504656)
			(xy 80.112362 -275.604732)
		)
		(stroke
			(width 0)
			(type solid)
		)
		(fill yes)
		(layer "In2.Cu")
		(net "M_C_CPU1_SB_DQ<3>")
	)
	(gr_poly
		(pts
			(xy 80.212184 -272.264886) (xy 80.212184 -272.217134) (xy 80.012286 -272.217134) (xy 80.012286 -272.264886)
			(xy 80.112362 -272.364708)
		)
		(stroke
			(width 0)
			(type solid)
		)
		(fill yes)
		(layer "In2.Cu")
		(net "M_C_CPU1_SB_DQS_DP<4>")
	)
	(gr_poly
		(pts
			(xy 80.212184 -270.64462) (xy 80.212184 -270.60017) (xy 80.012286 -270.60017) (xy 80.012286 -270.64462)
			(xy 80.112362 -270.744696)
		)
		(stroke
			(width 0)
			(type solid)
		)
		(fill yes)
		(layer "In2.Cu")
		(net "M_C_CPU1_SB_CB<7>")
	)
	(gr_poly
		(pts
			(xy 80.212184 -265.784584) (xy 80.212184 -265.740134) (xy 80.012286 -265.740134) (xy 80.012286 -265.784584)
			(xy 80.112362 -265.88466)
		)
		(stroke
			(width 0)
			(type solid)
		)
		(fill yes)
		(layer "In2.Cu")
		(net "M_C_CPU1_SB_CS_N<0>")
	)
	(gr_poly
		(pts
			(xy 80.212184 -262.54456) (xy 80.212184 -262.50011) (xy 80.012286 -262.50011) (xy 80.012286 -262.54456)
			(xy 80.112362 -262.644636)
		)
		(stroke
			(width 0)
			(type solid)
		)
		(fill yes)
		(layer "In2.Cu")
		(net "M_C_CPU1_SB_CA<1>")
	)
	(gr_poly
		(pts
			(xy 80.221074 -288.464498) (xy 80.221074 -288.420048) (xy 80.020922 -288.420048) (xy 80.020922 -288.464498)
			(xy 80.120998 -288.564574)
		)
		(stroke
			(width 0)
			(type solid)
		)
		(fill yes)
		(layer "In2.Cu")
		(net "M_C_CPU1_SB_DQ<23>")
	)
	(gr_poly
		(pts
			(xy 80.221074 -269.428214) (xy 80.120998 -269.328138) (xy 80.020922 -269.428214) (xy 80.020922 -269.472664)
			(xy 80.221074 -269.472664)
		)
		(stroke
			(width 0)
			(type solid)
		)
		(fill yes)
		(layer "In2.Cu")
		(net "M_C_CPU1_SB_CB<4>")
	)
	(gr_poly
		(pts
			(xy 80.22717 -292.108128) (xy 80.127094 -292.008052) (xy 80.027018 -292.108128) (xy 80.027018 -292.152578)
			(xy 80.22717 -292.152578)
		)
		(stroke
			(width 0)
			(type solid)
		)
		(fill yes)
		(layer "In2.Cu")
		(net "M_C_CPU1_SB_DQ<28>")
	)
	(gr_poly
		(pts
			(xy 80.234282 -262.94842) (xy 80.134206 -262.848344) (xy 80.03413 -262.94842) (xy 80.03413 -262.99287)
			(xy 80.234282 -262.99287)
		)
		(stroke
			(width 0)
			(type solid)
		)
		(fill yes)
		(layer "In2.Cu")
		(net "M_C_CPU1_SB_CA<2>")
	)
	(gr_poly
		(pts
			(xy 80.235552 -284.008576) (xy 80.13573 -283.9085) (xy 80.035654 -284.008576) (xy 80.035654 -284.052772)
			(xy 80.235552 -284.052772)
		)
		(stroke
			(width 0)
			(type solid)
		)
		(fill yes)
		(layer "In2.Cu")
		(net "M_C_CPU1_SB_DQ<16>")
	)
	(gr_poly
		(pts
			(xy 80.235552 -282.388564) (xy 80.13573 -282.288488) (xy 80.035654 -282.388564) (xy 80.035654 -282.43276)
			(xy 80.235552 -282.43276)
		)
		(stroke
			(width 0)
			(type solid)
		)
		(fill yes)
		(layer "In2.Cu")
		(net "M_C_CPU1_SB_DQ<12>")
	)
	(gr_poly
		(pts
			(xy 80.235552 -279.14854) (xy 80.13573 -279.048464) (xy 80.035654 -279.14854) (xy 80.035654 -279.192736)
			(xy 80.235552 -279.192736)
		)
		(stroke
			(width 0)
			(type solid)
		)
		(fill yes)
		(layer "In2.Cu")
		(net "M_C_CPU1_SB_DQ<8>")
	)
	(gr_poly
		(pts
			(xy 80.235552 -274.288504) (xy 80.13573 -274.188428) (xy 80.035654 -274.288504) (xy 80.035654 -274.3327)
			(xy 80.235552 -274.3327)
		)
		(stroke
			(width 0)
			(type solid)
		)
		(fill yes)
		(layer "In2.Cu")
		(net "M_C_CPU1_SB_DQ<0>")
	)
	(gr_poly
		(pts
			(xy 80.235552 -264.568432) (xy 80.13573 -264.468356) (xy 80.035654 -264.568432) (xy 80.035654 -264.612628)
			(xy 80.235552 -264.612628)
		)
		(stroke
			(width 0)
			(type solid)
		)
		(fill yes)
		(layer "In2.Cu")
		(net "M_C_CPU1_SB_CA<6>")
	)
	(gr_poly
		(pts
			(xy 80.237076 -280.364184) (xy 80.237076 -280.319734) (xy 80.036924 -280.319734) (xy 80.036924 -280.364184)
			(xy 80.137 -280.46426)
		)
		(stroke
			(width 0)
			(type solid)
		)
		(fill yes)
		(layer "In2.Cu")
		(net "M_C_CPU1_SB_DQ<11>")
	)
	(gr_poly
		(pts
			(xy 80.237076 -273.884136) (xy 80.237076 -273.839686) (xy 80.036924 -273.839686) (xy 80.036924 -273.884136)
			(xy 80.137 -273.984212)
		)
		(stroke
			(width 0)
			(type solid)
		)
		(fill yes)
		(layer "In2.Cu")
		(net "M_C_CPU1_SB_CB<3>")
	)
	(gr_poly
		(pts
			(xy 80.237076 -264.164064) (xy 80.237076 -264.119614) (xy 80.036924 -264.119614) (xy 80.036924 -264.164064)
			(xy 80.137 -264.26414)
		)
		(stroke
			(width 0)
			(type solid)
		)
		(fill yes)
		(layer "In2.Cu")
		(net "M_C_CPU1_SB_CA<5>")
	)
	(gr_poly
		(pts
			(xy 80.237838 -287.248346) (xy 80.137762 -287.14827) (xy 80.037686 -287.248346) (xy 80.037686 -287.292796)
			(xy 80.237838 -287.292796)
		)
		(stroke
			(width 0)
			(type solid)
		)
		(fill yes)
		(layer "In2.Cu")
		(net "M_C_CPU1_SB_DQ<20>")
	)
	(gr_poly
		(pts
			(xy 80.241394 -288.868358) (xy 80.141318 -288.768282) (xy 80.041242 -288.868358) (xy 80.041242 -288.912808)
			(xy 80.241394 -288.912808)
		)
		(stroke
			(width 0)
			(type solid)
		)
		(fill yes)
		(layer "In2.Cu")
		(net "M_C_CPU1_SB_DQ<24>")
	)
	(gr_poly
		(pts
			(xy 80.264762 -267.802106) (xy 80.19415 -267.679424) (xy 80.071722 -267.75029) (xy 80.060292 -267.793216)
			(xy 80.253332 -267.845032)
		)
		(stroke
			(width 0)
			(type solid)
		)
		(fill yes)
		(layer "In2.Cu")
		(net "M_C_CPU1_SB_RSP<0>")
	)
	(gr_poly
		(pts
			(xy 80.276954 -293.860728) (xy 80.240378 -293.724076) (xy 80.202024 -293.701724) (xy 80.101948 -293.874952)
			(xy 80.140556 -293.897304)
		)
		(stroke
			(width 0)
			(type solid)
		)
		(fill yes)
		(layer "In2.Cu")
		(net "M_C_CPU1_SB_DQ<30>")
	)
	(gr_poly
		(pts
			(xy 80.310228 -228.633274) (xy 80.210152 -228.460046) (xy 80.171798 -228.482398) (xy 80.135222 -228.61905)
			(xy 80.27162 -228.655626)
		)
		(stroke
			(width 0)
			(type solid)
		)
		(fill yes)
		(layer "In2.Cu")
		(net "M_C_CPU1_SA_DQ<10>")
	)
	(gr_poly
		(pts
			(xy 80.310228 -227.013262) (xy 80.210152 -226.840034) (xy 80.171798 -226.862386) (xy 80.135222 -226.999038)
			(xy 80.27162 -227.035614)
		)
		(stroke
			(width 0)
			(type solid)
		)
		(fill yes)
		(layer "In2.Cu")
		(net "M_C_CPU1_SA_DQ<7>")
	)
	(gr_poly
		(pts
			(xy 80.310228 -225.39325) (xy 80.210152 -225.220022) (xy 80.171798 -225.242374) (xy 80.135222 -225.379026)
			(xy 80.27162 -225.415602)
		)
		(stroke
			(width 0)
			(type solid)
		)
		(fill yes)
		(layer "In2.Cu")
		(net "M_C_CPU1_SA_DQ<6>")
	)
	(gr_poly
		(pts
			(xy 80.31099 -230.254556) (xy 80.210914 -230.081328) (xy 80.172306 -230.103426) (xy 80.13573 -230.240078)
			(xy 80.272382 -230.276654)
		)
		(stroke
			(width 0)
			(type solid)
		)
		(fill yes)
		(layer "In2.Cu")
		(net "M_C_CPU1_SA_DQ<11>")
	)
	(gr_poly
		(pts
			(xy 80.313022 -231.872282) (xy 80.2132 -231.699054) (xy 80.171798 -231.72293) (xy 80.135222 -231.859328)
			(xy 80.271874 -231.895904)
		)
		(stroke
			(width 0)
			(type solid)
		)
		(fill yes)
		(layer "In2.Cu")
		(net "M_C_CPU1_SA_DQS_DN<1>")
	)
	(gr_poly
		(pts
			(xy 80.314038 -223.773746) (xy 80.214216 -223.600518) (xy 80.172814 -223.624394) (xy 80.136238 -223.761046)
			(xy 80.27289 -223.797622)
		)
		(stroke
			(width 0)
			(type solid)
		)
		(fill yes)
		(layer "In2.Cu")
		(net "M_C_CPU1_SA_DQS_DP<5>")
	)
	(gr_poly
		(pts
			(xy 80.391254 -256.026158) (xy 80.291178 -255.926336) (xy 80.191102 -256.026158) (xy 80.191102 -256.07391)
			(xy 80.391254 -256.07391)
		)
		(stroke
			(width 0)
			(type solid)
		)
		(fill yes)
		(layer "In2.Cu")
		(net "M_C_CPU1_CLK_DP<0>")
	)
	(gr_poly
		(pts
			(xy 80.391254 -255.622552) (xy 80.391254 -255.578102) (xy 80.191102 -255.578102) (xy 80.191102 -255.622552)
			(xy 80.291178 -255.722628)
		)
		(stroke
			(width 0)
			(type solid)
		)
		(fill yes)
		(layer "In2.Cu")
		(net "M_C_CPU1_SA_PAR")
	)
	(gr_poly
		(pts
			(xy 80.391254 -254.4064) (xy 80.291178 -254.306324) (xy 80.191102 -254.4064) (xy 80.191102 -254.45085)
			(xy 80.391254 -254.45085)
		)
		(stroke
			(width 0)
			(type solid)
		)
		(fill yes)
		(layer "In2.Cu")
		(net "M_C_CPU1_SA_CA<4>")
	)
	(gr_poly
		(pts
			(xy 80.391254 -254.00254) (xy 80.391254 -253.95809) (xy 80.191102 -253.95809) (xy 80.191102 -254.00254)
			(xy 80.291178 -254.102616)
		)
		(stroke
			(width 0)
			(type solid)
		)
		(fill yes)
		(layer "In2.Cu")
		(net "M_C_CPU1_SA_CA<3>")
	)
	(gr_poly
		(pts
			(xy 80.391254 -252.786388) (xy 80.291178 -252.686312) (xy 80.191102 -252.786388) (xy 80.191102 -252.830838)
			(xy 80.391254 -252.830838)
		)
		(stroke
			(width 0)
			(type solid)
		)
		(fill yes)
		(layer "In2.Cu")
		(net "M_C_CPU1_SA_CA<0>")
	)
	(gr_poly
		(pts
			(xy 80.391254 -252.382528) (xy 80.391254 -252.338078) (xy 80.191102 -252.338078) (xy 80.191102 -252.382528)
			(xy 80.291178 -252.482604)
		)
		(stroke
			(width 0)
			(type solid)
		)
		(fill yes)
		(layer "In2.Cu")
		(net "M_C_CPU1_SA_CS_N<1>")
	)
	(gr_poly
		(pts
			(xy 80.391254 -250.762516) (xy 80.391254 -250.718066) (xy 80.191102 -250.718066) (xy 80.191102 -250.762516)
			(xy 80.291178 -250.862592)
		)
		(stroke
			(width 0)
			(type solid)
		)
		(fill yes)
		(layer "In2.Cu")
		(net "M_C_CPU1_RESET_N")
	)
	(gr_poly
		(pts
			(xy 80.391254 -249.142504) (xy 80.391254 -249.098054) (xy 80.191102 -249.098054) (xy 80.191102 -249.142504)
			(xy 80.291178 -249.24258)
		)
		(stroke
			(width 0)
			(type solid)
		)
		(fill yes)
		(layer "In2.Cu")
		(net "M_C_CPU1_SA_CB<7>")
	)
	(gr_poly
		(pts
			(xy 80.391254 -247.926352) (xy 80.291178 -247.826276) (xy 80.191102 -247.926352) (xy 80.191102 -247.970802)
			(xy 80.391254 -247.970802)
		)
		(stroke
			(width 0)
			(type solid)
		)
		(fill yes)
		(layer "In2.Cu")
		(net "M_C_CPU1_SA_CB<4>")
	)
	(gr_poly
		(pts
			(xy 80.391254 -247.522746) (xy 80.391254 -247.474994) (xy 80.191102 -247.474994) (xy 80.191102 -247.522746)
			(xy 80.291178 -247.622568)
		)
		(stroke
			(width 0)
			(type solid)
		)
		(fill yes)
		(layer "In2.Cu")
		(net "M_C_CPU1_SA_DQS_DP<9>")
	)
	(gr_poly
		(pts
			(xy 80.391254 -245.90248) (xy 80.391254 -245.85803) (xy 80.191102 -245.85803) (xy 80.191102 -245.90248)
			(xy 80.291178 -246.002556)
		)
		(stroke
			(width 0)
			(type solid)
		)
		(fill yes)
		(layer "In2.Cu")
		(net "M_C_CPU1_SA_CB<3>")
	)
	(gr_poly
		(pts
			(xy 80.391254 -244.686328) (xy 80.291178 -244.586252) (xy 80.191102 -244.686328) (xy 80.191102 -244.730778)
			(xy 80.391254 -244.730778)
		)
		(stroke
			(width 0)
			(type solid)
		)
		(fill yes)
		(layer "In2.Cu")
		(net "M_C_CPU1_SA_CB<0>")
	)
	(gr_poly
		(pts
			(xy 80.391254 -244.282468) (xy 80.391254 -244.238018) (xy 80.191102 -244.238018) (xy 80.191102 -244.282468)
			(xy 80.291178 -244.382544)
		)
		(stroke
			(width 0)
			(type solid)
		)
		(fill yes)
		(layer "In2.Cu")
		(net "M_C_CPU1_SA_DQ<31>")
	)
	(gr_poly
		(pts
			(xy 80.391254 -243.066316) (xy 80.291178 -242.96624) (xy 80.191102 -243.066316) (xy 80.191102 -243.110766)
			(xy 80.391254 -243.110766)
		)
		(stroke
			(width 0)
			(type solid)
		)
		(fill yes)
		(layer "In2.Cu")
		(net "M_C_CPU1_SA_DQ<28>")
	)
	(gr_poly
		(pts
			(xy 80.391254 -242.66271) (xy 80.391254 -242.614958) (xy 80.191102 -242.614958) (xy 80.191102 -242.66271)
			(xy 80.291178 -242.762532)
		)
		(stroke
			(width 0)
			(type solid)
		)
		(fill yes)
		(layer "In2.Cu")
		(net "M_C_CPU1_SA_DQS_DP<8>")
	)
	(gr_poly
		(pts
			(xy 80.391254 -241.44605) (xy 80.291178 -241.346228) (xy 80.191102 -241.44605) (xy 80.191102 -241.493802)
			(xy 80.391254 -241.493802)
		)
		(stroke
			(width 0)
			(type solid)
		)
		(fill yes)
		(layer "In2.Cu")
		(net "M_C_CPU1_SA_DQS_DP<3>")
	)
	(gr_poly
		(pts
			(xy 80.391254 -241.042444) (xy 80.391254 -240.997994) (xy 80.191102 -240.997994) (xy 80.191102 -241.042444)
			(xy 80.291178 -241.14252)
		)
		(stroke
			(width 0)
			(type solid)
		)
		(fill yes)
		(layer "In2.Cu")
		(net "M_C_CPU1_SA_DQ<27>")
	)
	(gr_poly
		(pts
			(xy 80.391254 -239.826292) (xy 80.291178 -239.726216) (xy 80.191102 -239.826292) (xy 80.191102 -239.870742)
			(xy 80.391254 -239.870742)
		)
		(stroke
			(width 0)
			(type solid)
		)
		(fill yes)
		(layer "In2.Cu")
		(net "M_C_CPU1_SA_DQ<24>")
	)
	(gr_poly
		(pts
			(xy 80.391254 -239.422432) (xy 80.391254 -239.377982) (xy 80.191102 -239.377982) (xy 80.191102 -239.422432)
			(xy 80.291178 -239.522508)
		)
		(stroke
			(width 0)
			(type solid)
		)
		(fill yes)
		(layer "In2.Cu")
		(net "M_C_CPU1_SA_DQ<23>")
	)
	(gr_poly
		(pts
			(xy 80.391254 -238.20628) (xy 80.291178 -238.106204) (xy 80.191102 -238.20628) (xy 80.191102 -238.25073)
			(xy 80.391254 -238.25073)
		)
		(stroke
			(width 0)
			(type solid)
		)
		(fill yes)
		(layer "In2.Cu")
		(net "M_C_CPU1_SA_DQ<20>")
	)
	(gr_poly
		(pts
			(xy 80.391254 -237.802674) (xy 80.391254 -237.754922) (xy 80.191102 -237.754922) (xy 80.191102 -237.802674)
			(xy 80.291178 -237.902496)
		)
		(stroke
			(width 0)
			(type solid)
		)
		(fill yes)
		(layer "In2.Cu")
		(net "M_C_CPU1_SA_DQS_DP<7>")
	)
	(gr_poly
		(pts
			(xy 80.391254 -236.586014) (xy 80.291178 -236.486192) (xy 80.191102 -236.586014) (xy 80.191102 -236.633766)
			(xy 80.391254 -236.633766)
		)
		(stroke
			(width 0)
			(type solid)
		)
		(fill yes)
		(layer "In2.Cu")
		(net "M_C_CPU1_SA_DQS_DP<2>")
	)
	(gr_poly
		(pts
			(xy 80.391254 -236.182408) (xy 80.391254 -236.137958) (xy 80.191102 -236.137958) (xy 80.191102 -236.182408)
			(xy 80.291178 -236.282484)
		)
		(stroke
			(width 0)
			(type solid)
		)
		(fill yes)
		(layer "In2.Cu")
		(net "M_C_CPU1_SA_DQ<19>")
	)
	(gr_poly
		(pts
			(xy 80.391254 -234.966256) (xy 80.291178 -234.86618) (xy 80.191102 -234.966256) (xy 80.191102 -235.010706)
			(xy 80.391254 -235.010706)
		)
		(stroke
			(width 0)
			(type solid)
		)
		(fill yes)
		(layer "In2.Cu")
		(net "M_C_CPU1_SA_DQ<16>")
	)
	(gr_poly
		(pts
			(xy 80.391254 -234.562396) (xy 80.391254 -234.517946) (xy 80.191102 -234.517946) (xy 80.191102 -234.562396)
			(xy 80.291178 -234.662472)
		)
		(stroke
			(width 0)
			(type solid)
		)
		(fill yes)
		(layer "In2.Cu")
		(net "M_C_CPU1_SA_DQ<15>")
	)
	(gr_poly
		(pts
			(xy 80.391254 -233.346244) (xy 80.291178 -233.246168) (xy 80.191102 -233.346244) (xy 80.191102 -233.390694)
			(xy 80.391254 -233.390694)
		)
		(stroke
			(width 0)
			(type solid)
		)
		(fill yes)
		(layer "In2.Cu")
		(net "M_C_CPU1_SA_DQ<12>")
	)
	(gr_poly
		(pts
			(xy 80.391254 -232.942638) (xy 80.391254 -232.894886) (xy 80.191102 -232.894886) (xy 80.191102 -232.942638)
			(xy 80.291178 -233.04246)
		)
		(stroke
			(width 0)
			(type solid)
		)
		(fill yes)
		(layer "In2.Cu")
		(net "M_C_CPU1_SA_DQS_DP<6>")
	)
	(gr_poly
		(pts
			(xy 80.398874 -246.305832) (xy 80.298798 -246.20601) (xy 80.198722 -246.305832) (xy 80.198722 -246.353584)
			(xy 80.398874 -246.353584)
		)
		(stroke
			(width 0)
			(type solid)
		)
		(fill yes)
		(layer "In2.Cu")
		(net "M_C_CPU1_SA_DQS_DP<4>")
	)
	(gr_poly
		(pts
			(xy 80.409034 -223.223836) (xy 80.44561 -223.087184) (xy 80.308958 -223.050608) (xy 80.26781 -223.074484)
			(xy 80.367886 -223.247712)
		)
		(stroke
			(width 0)
			(type solid)
		)
		(fill yes)
		(layer "In2.Cu")
		(net "M_C_CPU1_SA_DQS_DN<5>")
	)
	(gr_poly
		(pts
			(xy 80.410304 -229.706424) (xy 80.447134 -229.569772) (xy 80.310482 -229.533196) (xy 80.271874 -229.555548)
			(xy 80.37195 -229.728776)
		)
		(stroke
			(width 0)
			(type solid)
		)
		(fill yes)
		(layer "In2.Cu")
		(net "M_C_CPU1_SA_DQ<9>")
	)
	(gr_poly
		(pts
			(xy 80.410304 -228.086666) (xy 80.447134 -227.950014) (xy 80.310482 -227.913438) (xy 80.271874 -227.93579)
			(xy 80.37195 -228.109018)
		)
		(stroke
			(width 0)
			(type solid)
		)
		(fill yes)
		(layer "In2.Cu")
		(net "M_C_CPU1_SA_DQ<8>")
	)
	(gr_poly
		(pts
			(xy 80.410304 -226.466654) (xy 80.447134 -226.330002) (xy 80.310482 -226.293426) (xy 80.271874 -226.315778)
			(xy 80.37195 -226.489006)
		)
		(stroke
			(width 0)
			(type solid)
		)
		(fill yes)
		(layer "In2.Cu")
		(net "M_C_CPU1_SA_DQ<5>")
	)
	(gr_poly
		(pts
			(xy 80.410304 -224.846642) (xy 80.447134 -224.70999) (xy 80.310482 -224.673414) (xy 80.271874 -224.695766)
			(xy 80.37195 -224.868994)
		)
		(stroke
			(width 0)
			(type solid)
		)
		(fill yes)
		(layer "In2.Cu")
		(net "M_C_CPU1_SA_DQ<4>")
	)
	(gr_poly
		(pts
			(xy 80.410812 -231.327198) (xy 80.447388 -231.190546) (xy 80.31099 -231.15397) (xy 80.269588 -231.177592)
			(xy 80.369664 -231.35082)
		)
		(stroke
			(width 0)
			(type solid)
		)
		(fill yes)
		(layer "In2.Cu")
		(net "M_C_CPU1_SA_DQS_DP<1>")
	)
	(gr_poly
		(pts
			(xy 80.610202 -293.987474) (xy 80.571594 -293.965122) (xy 80.434942 -294.001698) (xy 80.471772 -294.13835)
			(xy 80.510126 -294.160702)
		)
		(stroke
			(width 0)
			(type solid)
		)
		(fill yes)
		(layer "In2.Cu")
		(net "M_C_CPU1_SB_DQ<29>")
	)
	(gr_poly
		(pts
			(xy 80.660494 -289.714686) (xy 80.65643 -289.67049) (xy 80.548226 -289.579558) (xy 80.457294 -289.687762)
			(xy 80.461104 -289.732212)
		)
		(stroke
			(width 0)
			(type solid)
		)
		(fill yes)
		(layer "In2.Cu")
		(net "M_C_CPU1_SB_DQ<25>")
	)
	(gr_poly
		(pts
			(xy 80.683862 -291.298122) (xy 80.583786 -291.198046) (xy 80.48371 -291.298122) (xy 80.48371 -291.34562)
			(xy 80.683862 -291.34562)
		)
		(stroke
			(width 0)
			(type solid)
		)
		(fill yes)
		(layer "In2.Cu")
		(net "M_C_CPU1_SB_DQS_DN<8>")
	)
	(gr_poly
		(pts
			(xy 80.684878 -266.991846) (xy 80.584802 -266.89177) (xy 80.48498 -266.991846) (xy 80.48498 -267.036296)
			(xy 80.684878 -267.036296)
		)
		(stroke
			(width 0)
			(type solid)
		)
		(fill yes)
		(layer "In2.Cu")
		(net "M_C_CPU1_SA_RSP<0>")
	)
	(gr_poly
		(pts
			(xy 80.691228 -290.894516) (xy 80.691228 -290.846764) (xy 80.491076 -290.846764) (xy 80.491076 -290.894516)
			(xy 80.591152 -290.994338)
		)
		(stroke
			(width 0)
			(type solid)
		)
		(fill yes)
		(layer "In2.Cu")
		(net "M_C_CPU1_SB_DQS_DN<3>")
	)
	(gr_poly
		(pts
			(xy 80.691228 -289.27425) (xy 80.691228 -289.2298) (xy 80.491076 -289.2298) (xy 80.491076 -289.27425)
			(xy 80.591152 -289.374326)
		)
		(stroke
			(width 0)
			(type solid)
		)
		(fill yes)
		(layer "In2.Cu")
		(net "M_C_CPU1_SB_DQ<26>")
	)
	(gr_poly
		(pts
			(xy 80.691228 -288.058098) (xy 80.591152 -287.958022) (xy 80.491076 -288.058098) (xy 80.491076 -288.102548)
			(xy 80.691228 -288.102548)
		)
		(stroke
			(width 0)
			(type solid)
		)
		(fill yes)
		(layer "In2.Cu")
		(net "M_C_CPU1_SB_DQ<21>")
	)
	(gr_poly
		(pts
			(xy 80.691228 -287.654492) (xy 80.691228 -287.610042) (xy 80.491076 -287.610042) (xy 80.491076 -287.654492)
			(xy 80.591152 -287.754568)
		)
		(stroke
			(width 0)
			(type solid)
		)
		(fill yes)
		(layer "In2.Cu")
		(net "M_C_CPU1_SB_DQ<22>")
	)
	(gr_poly
		(pts
			(xy 80.691228 -286.438086) (xy 80.591152 -286.33801) (xy 80.491076 -286.438086) (xy 80.491076 -286.485838)
			(xy 80.691228 -286.485838)
		)
		(stroke
			(width 0)
			(type solid)
		)
		(fill yes)
		(layer "In2.Cu")
		(net "M_C_CPU1_SB_DQS_DN<7>")
	)
	(gr_poly
		(pts
			(xy 80.691228 -286.034734) (xy 80.691228 -285.986982) (xy 80.491076 -285.986982) (xy 80.491076 -286.034734)
			(xy 80.591152 -286.134556)
		)
		(stroke
			(width 0)
			(type solid)
		)
		(fill yes)
		(layer "In2.Cu")
		(net "M_C_CPU1_SB_DQS_DN<2>")
	)
	(gr_poly
		(pts
			(xy 80.691228 -284.818328) (xy 80.591152 -284.718252) (xy 80.491076 -284.818328) (xy 80.491076 -284.862778)
			(xy 80.691228 -284.862778)
		)
		(stroke
			(width 0)
			(type solid)
		)
		(fill yes)
		(layer "In2.Cu")
		(net "M_C_CPU1_SB_DQ<17>")
	)
	(gr_poly
		(pts
			(xy 80.691228 -284.414468) (xy 80.691228 -284.370018) (xy 80.491076 -284.370018) (xy 80.491076 -284.414468)
			(xy 80.591152 -284.514544)
		)
		(stroke
			(width 0)
			(type solid)
		)
		(fill yes)
		(layer "In2.Cu")
		(net "M_C_CPU1_SB_DQ<18>")
	)
	(gr_poly
		(pts
			(xy 80.691228 -283.198316) (xy 80.591152 -283.09824) (xy 80.491076 -283.198316) (xy 80.491076 -283.242766)
			(xy 80.691228 -283.242766)
		)
		(stroke
			(width 0)
			(type solid)
		)
		(fill yes)
		(layer "In2.Cu")
		(net "M_C_CPU1_SB_DQ<13>")
	)
	(gr_poly
		(pts
			(xy 80.691228 -282.794456) (xy 80.691228 -282.750006) (xy 80.491076 -282.750006) (xy 80.491076 -282.794456)
			(xy 80.591152 -282.894532)
		)
		(stroke
			(width 0)
			(type solid)
		)
		(fill yes)
		(layer "In2.Cu")
		(net "M_C_CPU1_SB_DQ<14>")
	)
	(gr_poly
		(pts
			(xy 80.691228 -281.57805) (xy 80.591152 -281.478228) (xy 80.491076 -281.57805) (xy 80.491076 -281.625802)
			(xy 80.691228 -281.625802)
		)
		(stroke
			(width 0)
			(type solid)
		)
		(fill yes)
		(layer "In2.Cu")
		(net "M_C_CPU1_SB_DQS_DN<6>")
	)
	(gr_poly
		(pts
			(xy 80.691228 -281.174698) (xy 80.691228 -281.126946) (xy 80.491076 -281.126946) (xy 80.491076 -281.174698)
			(xy 80.591152 -281.27452)
		)
		(stroke
			(width 0)
			(type solid)
		)
		(fill yes)
		(layer "In2.Cu")
		(net "M_C_CPU1_SB_DQS_DN<1>")
	)
	(gr_poly
		(pts
			(xy 80.691228 -279.958292) (xy 80.591152 -279.858216) (xy 80.491076 -279.958292) (xy 80.491076 -280.002742)
			(xy 80.691228 -280.002742)
		)
		(stroke
			(width 0)
			(type solid)
		)
		(fill yes)
		(layer "In2.Cu")
		(net "M_C_CPU1_SB_DQ<9>")
	)
	(gr_poly
		(pts
			(xy 80.691228 -279.554432) (xy 80.691228 -279.509982) (xy 80.491076 -279.509982) (xy 80.491076 -279.554432)
			(xy 80.591152 -279.654508)
		)
		(stroke
			(width 0)
			(type solid)
		)
		(fill yes)
		(layer "In2.Cu")
		(net "M_C_CPU1_SB_DQ<10>")
	)
	(gr_poly
		(pts
			(xy 80.691228 -278.33828) (xy 80.591152 -278.238204) (xy 80.491076 -278.33828) (xy 80.491076 -278.38273)
			(xy 80.691228 -278.38273)
		)
		(stroke
			(width 0)
			(type solid)
		)
		(fill yes)
		(layer "In2.Cu")
		(net "M_C_CPU1_SB_DQ<5>")
	)
	(gr_poly
		(pts
			(xy 80.691228 -277.93442) (xy 80.691228 -277.88997) (xy 80.491076 -277.88997) (xy 80.491076 -277.93442)
			(xy 80.591152 -278.034496)
		)
		(stroke
			(width 0)
			(type solid)
		)
		(fill yes)
		(layer "In2.Cu")
		(net "M_C_CPU1_SB_DQ<6>")
	)
	(gr_poly
		(pts
			(xy 80.691228 -276.718014) (xy 80.591152 -276.618192) (xy 80.491076 -276.718014) (xy 80.491076 -276.765766)
			(xy 80.691228 -276.765766)
		)
		(stroke
			(width 0)
			(type solid)
		)
		(fill yes)
		(layer "In2.Cu")
		(net "M_C_CPU1_SB_DQS_DN<5>")
	)
	(gr_poly
		(pts
			(xy 80.691228 -276.314662) (xy 80.691228 -276.26691) (xy 80.491076 -276.26691) (xy 80.491076 -276.314662)
			(xy 80.591152 -276.414484)
		)
		(stroke
			(width 0)
			(type solid)
		)
		(fill yes)
		(layer "In2.Cu")
		(net "M_C_CPU1_SB_DQS_DN<0>")
	)
	(gr_poly
		(pts
			(xy 80.691228 -275.098256) (xy 80.591152 -274.99818) (xy 80.491076 -275.098256) (xy 80.491076 -275.142706)
			(xy 80.691228 -275.142706)
		)
		(stroke
			(width 0)
			(type solid)
		)
		(fill yes)
		(layer "In2.Cu")
		(net "M_C_CPU1_SB_DQ<1>")
	)
	(gr_poly
		(pts
			(xy 80.691228 -274.694396) (xy 80.691228 -274.649946) (xy 80.491076 -274.649946) (xy 80.491076 -274.694396)
			(xy 80.591152 -274.794472)
		)
		(stroke
			(width 0)
			(type solid)
		)
		(fill yes)
		(layer "In2.Cu")
		(net "M_C_CPU1_SB_DQ<2>")
	)
	(gr_poly
		(pts
			(xy 80.691228 -273.478244) (xy 80.591152 -273.378168) (xy 80.491076 -273.478244) (xy 80.491076 -273.522694)
			(xy 80.691228 -273.522694)
		)
		(stroke
			(width 0)
			(type solid)
		)
		(fill yes)
		(layer "In2.Cu")
		(net "M_C_CPU1_SB_CB<1>")
	)
	(gr_poly
		(pts
			(xy 80.691228 -273.074384) (xy 80.691228 -273.029934) (xy 80.491076 -273.029934) (xy 80.491076 -273.074384)
			(xy 80.591152 -273.17446)
		)
		(stroke
			(width 0)
			(type solid)
		)
		(fill yes)
		(layer "In2.Cu")
		(net "M_C_CPU1_SB_CB<2>")
	)
	(gr_poly
		(pts
			(xy 80.691228 -271.857978) (xy 80.591152 -271.758156) (xy 80.491076 -271.857978) (xy 80.491076 -271.90573)
			(xy 80.691228 -271.90573)
		)
		(stroke
			(width 0)
			(type solid)
		)
		(fill yes)
		(layer "In2.Cu")
		(net "M_C_CPU1_SB_DQS_DN<4>")
	)
	(gr_poly
		(pts
			(xy 80.691228 -271.454626) (xy 80.691228 -271.406874) (xy 80.491076 -271.406874) (xy 80.491076 -271.454626)
			(xy 80.591152 -271.554448)
		)
		(stroke
			(width 0)
			(type solid)
		)
		(fill yes)
		(layer "In2.Cu")
		(net "M_C_CPU1_SB_DQS_DN<9>")
	)
	(gr_poly
		(pts
			(xy 80.691228 -270.23822) (xy 80.591152 -270.138144) (xy 80.491076 -270.23822) (xy 80.491076 -270.28267)
			(xy 80.691228 -270.28267)
		)
		(stroke
			(width 0)
			(type solid)
		)
		(fill yes)
		(layer "In2.Cu")
		(net "M_C_CPU1_SB_CB<5>")
	)
	(gr_poly
		(pts
			(xy 80.691228 -269.83436) (xy 80.691228 -269.78991) (xy 80.491076 -269.78991) (xy 80.491076 -269.83436)
			(xy 80.591152 -269.934436)
		)
		(stroke
			(width 0)
			(type solid)
		)
		(fill yes)
		(layer "In2.Cu")
		(net "M_C_CPU1_SB_CB<6>")
	)
	(gr_poly
		(pts
			(xy 80.691228 -266.594336) (xy 80.691228 -266.549886) (xy 80.491076 -266.549886) (xy 80.491076 -266.594336)
			(xy 80.591152 -266.694412)
		)
		(stroke
			(width 0)
			(type solid)
		)
		(fill yes)
		(layer "In2.Cu")
		(net "M_C_CPU1_SB_CS_N<1>")
	)
	(gr_poly
		(pts
			(xy 80.691228 -264.974324) (xy 80.691228 -264.929874) (xy 80.491076 -264.929874) (xy 80.491076 -264.974324)
			(xy 80.591152 -265.0744)
		)
		(stroke
			(width 0)
			(type solid)
		)
		(fill yes)
		(layer "In2.Cu")
		(net "M_C_CPU1_SB_PAR")
	)
	(gr_poly
		(pts
			(xy 80.691228 -263.758172) (xy 80.591152 -263.658096) (xy 80.491076 -263.758172) (xy 80.491076 -263.802622)
			(xy 80.691228 -263.802622)
		)
		(stroke
			(width 0)
			(type solid)
		)
		(fill yes)
		(layer "In2.Cu")
		(net "M_C_CPU1_SB_CA<4>")
	)
	(gr_poly
		(pts
			(xy 80.691228 -263.354312) (xy 80.691228 -263.309862) (xy 80.491076 -263.309862) (xy 80.491076 -263.354312)
			(xy 80.591152 -263.454388)
		)
		(stroke
			(width 0)
			(type solid)
		)
		(fill yes)
		(layer "In2.Cu")
		(net "M_C_CPU1_SB_CA<3>")
	)
	(gr_poly
		(pts
			(xy 80.691228 -262.13816) (xy 80.591152 -262.038084) (xy 80.491076 -262.13816) (xy 80.491076 -262.18261)
			(xy 80.691228 -262.18261)
		)
		(stroke
			(width 0)
			(type solid)
		)
		(fill yes)
		(layer "In2.Cu")
		(net "M_C_CPU1_SB_CA<0>")
	)
	(gr_poly
		(pts
			(xy 80.746854 -293.050722) (xy 80.710278 -292.91407) (xy 80.671924 -292.891718) (xy 80.571848 -293.064946)
			(xy 80.610456 -293.087298)
		)
		(stroke
			(width 0)
			(type solid)
		)
		(fill yes)
		(layer "In2.Cu")
		(net "M_C_CPU1_SB_DQ<30>")
	)
	(gr_poly
		(pts
			(xy 80.781144 -231.064816) (xy 80.681068 -230.891588) (xy 80.64246 -230.913686) (xy 80.605884 -231.050338)
			(xy 80.742536 -231.086914)
		)
		(stroke
			(width 0)
			(type solid)
		)
		(fill yes)
		(layer "In2.Cu")
		(net "M_C_CPU1_SA_DQ<11>")
	)
	(gr_poly
		(pts
			(xy 80.781144 -229.444804) (xy 80.681068 -229.271576) (xy 80.64246 -229.293674) (xy 80.605884 -229.430326)
			(xy 80.742536 -229.466902)
		)
		(stroke
			(width 0)
			(type solid)
		)
		(fill yes)
		(layer "In2.Cu")
		(net "M_C_CPU1_SA_DQ<10>")
	)
	(gr_poly
		(pts
			(xy 80.781144 -227.824792) (xy 80.681068 -227.651564) (xy 80.64246 -227.673662) (xy 80.605884 -227.810314)
			(xy 80.742536 -227.84689)
		)
		(stroke
			(width 0)
			(type solid)
		)
		(fill yes)
		(layer "In2.Cu")
		(net "M_C_CPU1_SA_DQ<7>")
	)
	(gr_poly
		(pts
			(xy 80.781144 -226.20478) (xy 80.681068 -226.031552) (xy 80.64246 -226.05365) (xy 80.605884 -226.190302)
			(xy 80.742536 -226.226878)
		)
		(stroke
			(width 0)
			(type solid)
		)
		(fill yes)
		(layer "In2.Cu")
		(net "M_C_CPU1_SA_DQ<6>")
	)
	(gr_poly
		(pts
			(xy 80.783938 -224.583752) (xy 80.684116 -224.410524) (xy 80.642714 -224.4344) (xy 80.606138 -224.571052)
			(xy 80.74279 -224.607628)
		)
		(stroke
			(width 0)
			(type solid)
		)
		(fill yes)
		(layer "In2.Cu")
		(net "M_C_CPU1_SA_DQS_DP<5>")
	)
	(gr_poly
		(pts
			(xy 80.785208 -222.965264) (xy 80.685132 -222.792036) (xy 80.64373 -222.815912) (xy 80.607154 -222.952564)
			(xy 80.743806 -222.98914)
		)
		(stroke
			(width 0)
			(type solid)
		)
		(fill yes)
		(layer "In2.Cu")
		(net "M_C_CPU1_SA_DQS_DN<0>")
	)
	(gr_poly
		(pts
			(xy 80.8609 -246.712486) (xy 80.8609 -246.664988) (xy 80.661002 -246.664988) (xy 80.661002 -246.712486)
			(xy 80.760824 -246.812562)
		)
		(stroke
			(width 0)
			(type solid)
		)
		(fill yes)
		(layer "In2.Cu")
		(net "M_C_CPU1_SA_DQS_DN<4>")
	)
	(gr_poly
		(pts
			(xy 80.861154 -256.432812) (xy 80.861154 -256.38506) (xy 80.661002 -256.38506) (xy 80.661002 -256.432812)
			(xy 80.761078 -256.532634)
		)
		(stroke
			(width 0)
			(type solid)
		)
		(fill yes)
		(layer "In2.Cu")
		(net "M_C_CPU1_CLK_DN<0>")
	)
	(gr_poly
		(pts
			(xy 80.861154 -255.216406) (xy 80.761078 -255.11633) (xy 80.661002 -255.216406) (xy 80.661002 -255.260856)
			(xy 80.861154 -255.260856)
		)
		(stroke
			(width 0)
			(type solid)
		)
		(fill yes)
		(layer "In2.Cu")
		(net "M_C_CPU1_SA_CA<6>")
	)
	(gr_poly
		(pts
			(xy 80.861154 -254.812546) (xy 80.861154 -254.768096) (xy 80.661002 -254.768096) (xy 80.661002 -254.812546)
			(xy 80.761078 -254.912622)
		)
		(stroke
			(width 0)
			(type solid)
		)
		(fill yes)
		(layer "In2.Cu")
		(net "M_C_CPU1_SA_CA<5>")
	)
	(gr_poly
		(pts
			(xy 80.861154 -253.596394) (xy 80.761078 -253.496318) (xy 80.661002 -253.596394) (xy 80.661002 -253.640844)
			(xy 80.861154 -253.640844)
		)
		(stroke
			(width 0)
			(type solid)
		)
		(fill yes)
		(layer "In2.Cu")
		(net "M_C_CPU1_SA_CA<2>")
	)
	(gr_poly
		(pts
			(xy 80.861154 -253.192534) (xy 80.861154 -253.148084) (xy 80.661002 -253.148084) (xy 80.661002 -253.192534)
			(xy 80.761078 -253.29261)
		)
		(stroke
			(width 0)
			(type solid)
		)
		(fill yes)
		(layer "In2.Cu")
		(net "M_C_CPU1_SA_CA<1>")
	)
	(gr_poly
		(pts
			(xy 80.861154 -251.572522) (xy 80.861154 -251.528072) (xy 80.661002 -251.528072) (xy 80.661002 -251.572522)
			(xy 80.761078 -251.672598)
		)
		(stroke
			(width 0)
			(type solid)
		)
		(fill yes)
		(layer "In2.Cu")
		(net "M_C_CPU1_SA_CS_N<0>")
	)
	(gr_poly
		(pts
			(xy 80.861154 -250.35637) (xy 80.761078 -250.256294) (xy 80.661002 -250.35637) (xy 80.661002 -250.40082)
			(xy 80.861154 -250.40082)
		)
		(stroke
			(width 0)
			(type solid)
		)
		(fill yes)
		(layer "In2.Cu")
		(net "M_C_CPU1_ALERT_R_N")
	)
	(gr_poly
		(pts
			(xy 80.861154 -248.736358) (xy 80.761078 -248.636282) (xy 80.661002 -248.736358) (xy 80.661002 -248.780808)
			(xy 80.861154 -248.780808)
		)
		(stroke
			(width 0)
			(type solid)
		)
		(fill yes)
		(layer "In2.Cu")
		(net "M_C_CPU1_SA_CB<5>")
	)
	(gr_poly
		(pts
			(xy 80.861154 -248.332498) (xy 80.861154 -248.288048) (xy 80.661002 -248.288048) (xy 80.661002 -248.332498)
			(xy 80.761078 -248.432574)
		)
		(stroke
			(width 0)
			(type solid)
		)
		(fill yes)
		(layer "In2.Cu")
		(net "M_C_CPU1_SA_CB<6>")
	)
	(gr_poly
		(pts
			(xy 80.861154 -247.116092) (xy 80.761078 -247.01627) (xy 80.661002 -247.116092) (xy 80.661002 -247.163844)
			(xy 80.861154 -247.163844)
		)
		(stroke
			(width 0)
			(type solid)
		)
		(fill yes)
		(layer "In2.Cu")
		(net "M_C_CPU1_SA_DQS_DN<9>")
	)
	(gr_poly
		(pts
			(xy 80.861154 -245.496334) (xy 80.761078 -245.396258) (xy 80.661002 -245.496334) (xy 80.661002 -245.540784)
			(xy 80.861154 -245.540784)
		)
		(stroke
			(width 0)
			(type solid)
		)
		(fill yes)
		(layer "In2.Cu")
		(net "M_C_CPU1_SA_CB<1>")
	)
	(gr_poly
		(pts
			(xy 80.861154 -245.092474) (xy 80.861154 -245.048024) (xy 80.661002 -245.048024) (xy 80.661002 -245.092474)
			(xy 80.761078 -245.19255)
		)
		(stroke
			(width 0)
			(type solid)
		)
		(fill yes)
		(layer "In2.Cu")
		(net "M_C_CPU1_SA_CB<2>")
	)
	(gr_poly
		(pts
			(xy 80.861154 -243.876322) (xy 80.761078 -243.776246) (xy 80.661002 -243.876322) (xy 80.661002 -243.920772)
			(xy 80.861154 -243.920772)
		)
		(stroke
			(width 0)
			(type solid)
		)
		(fill yes)
		(layer "In2.Cu")
		(net "M_C_CPU1_SA_DQ<29>")
	)
	(gr_poly
		(pts
			(xy 80.861154 -243.472462) (xy 80.861154 -243.428012) (xy 80.661002 -243.428012) (xy 80.661002 -243.472462)
			(xy 80.761078 -243.572538)
		)
		(stroke
			(width 0)
			(type solid)
		)
		(fill yes)
		(layer "In2.Cu")
		(net "M_C_CPU1_SA_DQ<30>")
	)
	(gr_poly
		(pts
			(xy 80.861154 -242.256056) (xy 80.761078 -242.156234) (xy 80.661002 -242.256056) (xy 80.661002 -242.303808)
			(xy 80.861154 -242.303808)
		)
		(stroke
			(width 0)
			(type solid)
		)
		(fill yes)
		(layer "In2.Cu")
		(net "M_C_CPU1_SA_DQS_DN<8>")
	)
	(gr_poly
		(pts
			(xy 80.861154 -241.852704) (xy 80.861154 -241.804952) (xy 80.661002 -241.804952) (xy 80.661002 -241.852704)
			(xy 80.761078 -241.952526)
		)
		(stroke
			(width 0)
			(type solid)
		)
		(fill yes)
		(layer "In2.Cu")
		(net "M_C_CPU1_SA_DQS_DN<3>")
	)
	(gr_poly
		(pts
			(xy 80.861154 -240.636298) (xy 80.761078 -240.536222) (xy 80.661002 -240.636298) (xy 80.661002 -240.680748)
			(xy 80.861154 -240.680748)
		)
		(stroke
			(width 0)
			(type solid)
		)
		(fill yes)
		(layer "In2.Cu")
		(net "M_C_CPU1_SA_DQ<25>")
	)
	(gr_poly
		(pts
			(xy 80.861154 -240.232438) (xy 80.861154 -240.187988) (xy 80.661002 -240.187988) (xy 80.661002 -240.232438)
			(xy 80.761078 -240.332514)
		)
		(stroke
			(width 0)
			(type solid)
		)
		(fill yes)
		(layer "In2.Cu")
		(net "M_C_CPU1_SA_DQ<26>")
	)
	(gr_poly
		(pts
			(xy 80.861154 -239.016286) (xy 80.761078 -238.91621) (xy 80.661002 -239.016286) (xy 80.661002 -239.060736)
			(xy 80.861154 -239.060736)
		)
		(stroke
			(width 0)
			(type solid)
		)
		(fill yes)
		(layer "In2.Cu")
		(net "M_C_CPU1_SA_DQ<21>")
	)
	(gr_poly
		(pts
			(xy 80.861154 -238.612426) (xy 80.861154 -238.567976) (xy 80.661002 -238.567976) (xy 80.661002 -238.612426)
			(xy 80.761078 -238.712502)
		)
		(stroke
			(width 0)
			(type solid)
		)
		(fill yes)
		(layer "In2.Cu")
		(net "M_C_CPU1_SA_DQ<22>")
	)
	(gr_poly
		(pts
			(xy 80.861154 -237.39602) (xy 80.761078 -237.296198) (xy 80.661002 -237.39602) (xy 80.661002 -237.443772)
			(xy 80.861154 -237.443772)
		)
		(stroke
			(width 0)
			(type solid)
		)
		(fill yes)
		(layer "In2.Cu")
		(net "M_C_CPU1_SA_DQS_DN<7>")
	)
	(gr_poly
		(pts
			(xy 80.861154 -236.992668) (xy 80.861154 -236.944916) (xy 80.661002 -236.944916) (xy 80.661002 -236.992668)
			(xy 80.761078 -237.09249)
		)
		(stroke
			(width 0)
			(type solid)
		)
		(fill yes)
		(layer "In2.Cu")
		(net "M_C_CPU1_SA_DQS_DN<2>")
	)
	(gr_poly
		(pts
			(xy 80.861154 -235.776262) (xy 80.761078 -235.676186) (xy 80.661002 -235.776262) (xy 80.661002 -235.820712)
			(xy 80.861154 -235.820712)
		)
		(stroke
			(width 0)
			(type solid)
		)
		(fill yes)
		(layer "In2.Cu")
		(net "M_C_CPU1_SA_DQ<17>")
	)
	(gr_poly
		(pts
			(xy 80.861154 -235.372402) (xy 80.861154 -235.327952) (xy 80.661002 -235.327952) (xy 80.661002 -235.372402)
			(xy 80.761078 -235.472478)
		)
		(stroke
			(width 0)
			(type solid)
		)
		(fill yes)
		(layer "In2.Cu")
		(net "M_C_CPU1_SA_DQ<18>")
	)
	(gr_poly
		(pts
			(xy 80.861154 -234.15625) (xy 80.761078 -234.056174) (xy 80.661002 -234.15625) (xy 80.661002 -234.2007)
			(xy 80.861154 -234.2007)
		)
		(stroke
			(width 0)
			(type solid)
		)
		(fill yes)
		(layer "In2.Cu")
		(net "M_C_CPU1_SA_DQ<13>")
	)
	(gr_poly
		(pts
			(xy 80.861154 -233.75239) (xy 80.861154 -233.70794) (xy 80.661002 -233.70794) (xy 80.661002 -233.75239)
			(xy 80.761078 -233.852466)
		)
		(stroke
			(width 0)
			(type solid)
		)
		(fill yes)
		(layer "In2.Cu")
		(net "M_C_CPU1_SA_DQ<14>")
	)
	(gr_poly
		(pts
			(xy 80.861154 -232.535984) (xy 80.761078 -232.436162) (xy 80.661002 -232.535984) (xy 80.661002 -232.583736)
			(xy 80.861154 -232.583736)
		)
		(stroke
			(width 0)
			(type solid)
		)
		(fill yes)
		(layer "In2.Cu")
		(net "M_C_CPU1_SA_DQS_DN<6>")
	)
	(gr_poly
		(pts
			(xy 80.861154 -232.132632) (xy 80.861154 -232.08488) (xy 80.661002 -232.08488) (xy 80.661002 -232.132632)
			(xy 80.761078 -232.232454)
		)
		(stroke
			(width 0)
			(type solid)
		)
		(fill yes)
		(layer "In2.Cu")
		(net "M_C_CPU1_SA_DQS_DN<1>")
	)
	(gr_poly
		(pts
			(xy 80.878934 -230.51389) (xy 80.91551 -230.377238) (xy 80.778858 -230.340662) (xy 80.74025 -230.363014)
			(xy 80.840326 -230.536242)
		)
		(stroke
			(width 0)
			(type solid)
		)
		(fill yes)
		(layer "In2.Cu")
		(net "M_C_CPU1_SA_DQ<9>")
	)
	(gr_poly
		(pts
			(xy 80.879442 -224.034604) (xy 80.916018 -223.897952) (xy 80.779366 -223.861376) (xy 80.738218 -223.885252)
			(xy 80.83804 -224.05848)
		)
		(stroke
			(width 0)
			(type solid)
		)
		(fill yes)
		(layer "In2.Cu")
		(net "M_C_CPU1_SA_DQS_DN<5>")
	)
	(gr_poly
		(pts
			(xy 80.879696 -228.895402) (xy 80.916272 -228.75875) (xy 80.77962 -228.722174) (xy 80.741012 -228.744272)
			(xy 80.841088 -228.9175)
		)
		(stroke
			(width 0)
			(type solid)
		)
		(fill yes)
		(layer "In2.Cu")
		(net "M_C_CPU1_SA_DQ<8>")
	)
	(gr_poly
		(pts
			(xy 80.879696 -227.27539) (xy 80.916272 -227.138738) (xy 80.77962 -227.102162) (xy 80.741012 -227.12426)
			(xy 80.841088 -227.297488)
		)
		(stroke
			(width 0)
			(type solid)
		)
		(fill yes)
		(layer "In2.Cu")
		(net "M_C_CPU1_SA_DQ<5>")
	)
	(gr_poly
		(pts
			(xy 80.879696 -225.655378) (xy 80.916272 -225.518726) (xy 80.77962 -225.48215) (xy 80.741012 -225.504248)
			(xy 80.841088 -225.677476)
		)
		(stroke
			(width 0)
			(type solid)
		)
		(fill yes)
		(layer "In2.Cu")
		(net "M_C_CPU1_SA_DQ<4>")
	)
	(gr_poly
		(pts
			(xy 81.09077 -293.15918) (xy 81.052416 -293.136828) (xy 80.915764 -293.173404) (xy 80.95234 -293.310056)
			(xy 80.990948 -293.332408)
		)
		(stroke
			(width 0)
			(type solid)
		)
		(fill yes)
		(layer "In2.Cu")
		(net "M_C_CPU1_SB_DQ<29>")
	)
	(gr_poly
		(pts
			(xy 81.161128 -292.108128) (xy 81.061052 -292.008052) (xy 80.960976 -292.108128) (xy 80.960976 -292.152578)
			(xy 81.161128 -292.152578)
		)
		(stroke
			(width 0)
			(type solid)
		)
		(fill yes)
		(layer "In2.Cu")
		(net "M_C_CPU1_SB_DQ<28>")
	)
	(gr_poly
		(pts
			(xy 81.161128 -291.704522) (xy 81.161128 -291.65677) (xy 80.960976 -291.65677) (xy 80.960976 -291.704522)
			(xy 81.061052 -291.804344)
		)
		(stroke
			(width 0)
			(type solid)
		)
		(fill yes)
		(layer "In2.Cu")
		(net "M_C_CPU1_SB_DQS_DP<8>")
	)
	(gr_poly
		(pts
			(xy 81.161128 -290.487862) (xy 81.061052 -290.38804) (xy 80.960976 -290.487862) (xy 80.960976 -290.535614)
			(xy 81.161128 -290.535614)
		)
		(stroke
			(width 0)
			(type solid)
		)
		(fill yes)
		(layer "In2.Cu")
		(net "M_C_CPU1_SB_DQS_DP<3>")
	)
	(gr_poly
		(pts
			(xy 81.161128 -290.084256) (xy 81.161128 -290.039806) (xy 80.960976 -290.039806) (xy 80.960976 -290.084256)
			(xy 81.061052 -290.184332)
		)
		(stroke
			(width 0)
			(type solid)
		)
		(fill yes)
		(layer "In2.Cu")
		(net "M_C_CPU1_SB_DQ<27>")
	)
	(gr_poly
		(pts
			(xy 81.161128 -288.868104) (xy 81.061052 -288.768028) (xy 80.960976 -288.868104) (xy 80.960976 -288.912554)
			(xy 81.161128 -288.912554)
		)
		(stroke
			(width 0)
			(type solid)
		)
		(fill yes)
		(layer "In2.Cu")
		(net "M_C_CPU1_SB_DQ<24>")
	)
	(gr_poly
		(pts
			(xy 81.161128 -288.464498) (xy 81.161128 -288.420048) (xy 80.960976 -288.420048) (xy 80.960976 -288.464498)
			(xy 81.061052 -288.564574)
		)
		(stroke
			(width 0)
			(type solid)
		)
		(fill yes)
		(layer "In2.Cu")
		(net "M_C_CPU1_SB_DQ<23>")
	)
	(gr_poly
		(pts
			(xy 81.161128 -287.248092) (xy 81.061052 -287.148016) (xy 80.960976 -287.248092) (xy 80.960976 -287.292542)
			(xy 81.161128 -287.292542)
		)
		(stroke
			(width 0)
			(type solid)
		)
		(fill yes)
		(layer "In2.Cu")
		(net "M_C_CPU1_SB_DQ<20>")
	)
	(gr_poly
		(pts
			(xy 81.161128 -286.844486) (xy 81.161128 -286.796734) (xy 80.960976 -286.796734) (xy 80.960976 -286.844486)
			(xy 81.061052 -286.944562)
		)
		(stroke
			(width 0)
			(type solid)
		)
		(fill yes)
		(layer "In2.Cu")
		(net "M_C_CPU1_SB_DQS_DP<7>")
	)
	(gr_poly
		(pts
			(xy 81.161128 -285.62808) (xy 81.061052 -285.528258) (xy 80.960976 -285.62808) (xy 80.960976 -285.675832)
			(xy 81.161128 -285.675832)
		)
		(stroke
			(width 0)
			(type solid)
		)
		(fill yes)
		(layer "In2.Cu")
		(net "M_C_CPU1_SB_DQS_DP<2>")
	)
	(gr_poly
		(pts
			(xy 81.161128 -285.224474) (xy 81.161128 -285.180024) (xy 80.960976 -285.180024) (xy 80.960976 -285.224474)
			(xy 81.061052 -285.32455)
		)
		(stroke
			(width 0)
			(type solid)
		)
		(fill yes)
		(layer "In2.Cu")
		(net "M_C_CPU1_SB_DQ<19>")
	)
	(gr_poly
		(pts
			(xy 81.161128 -284.008322) (xy 81.061052 -283.908246) (xy 80.960976 -284.008322) (xy 80.960976 -284.052772)
			(xy 81.161128 -284.052772)
		)
		(stroke
			(width 0)
			(type solid)
		)
		(fill yes)
		(layer "In2.Cu")
		(net "M_C_CPU1_SB_DQ<16>")
	)
	(gr_poly
		(pts
			(xy 81.161128 -283.604462) (xy 81.161128 -283.560012) (xy 80.960976 -283.560012) (xy 80.960976 -283.604462)
			(xy 81.061052 -283.704538)
		)
		(stroke
			(width 0)
			(type solid)
		)
		(fill yes)
		(layer "In2.Cu")
		(net "M_C_CPU1_SB_DQ<15>")
	)
	(gr_poly
		(pts
			(xy 81.161128 -282.38831) (xy 81.061052 -282.288234) (xy 80.960976 -282.38831) (xy 80.960976 -282.43276)
			(xy 81.161128 -282.43276)
		)
		(stroke
			(width 0)
			(type solid)
		)
		(fill yes)
		(layer "In2.Cu")
		(net "M_C_CPU1_SB_DQ<12>")
	)
	(gr_poly
		(pts
			(xy 81.161128 -281.984704) (xy 81.161128 -281.936952) (xy 80.960976 -281.936952) (xy 80.960976 -281.984704)
			(xy 81.061052 -282.084526)
		)
		(stroke
			(width 0)
			(type solid)
		)
		(fill yes)
		(layer "In2.Cu")
		(net "M_C_CPU1_SB_DQS_DP<6>")
	)
	(gr_poly
		(pts
			(xy 81.161128 -280.768044) (xy 81.061052 -280.668222) (xy 80.960976 -280.768044) (xy 80.960976 -280.815796)
			(xy 81.161128 -280.815796)
		)
		(stroke
			(width 0)
			(type solid)
		)
		(fill yes)
		(layer "In2.Cu")
		(net "M_C_CPU1_SB_DQS_DP<1>")
	)
	(gr_poly
		(pts
			(xy 81.161128 -280.364438) (xy 81.161128 -280.319988) (xy 80.960976 -280.319988) (xy 80.960976 -280.364438)
			(xy 81.061052 -280.464514)
		)
		(stroke
			(width 0)
			(type solid)
		)
		(fill yes)
		(layer "In2.Cu")
		(net "M_C_CPU1_SB_DQ<11>")
	)
	(gr_poly
		(pts
			(xy 81.161128 -279.148286) (xy 81.061052 -279.04821) (xy 80.960976 -279.148286) (xy 80.960976 -279.192736)
			(xy 81.161128 -279.192736)
		)
		(stroke
			(width 0)
			(type solid)
		)
		(fill yes)
		(layer "In2.Cu")
		(net "M_C_CPU1_SB_DQ<8>")
	)
	(gr_poly
		(pts
			(xy 81.161128 -278.744426) (xy 81.161128 -278.699976) (xy 80.960976 -278.699976) (xy 80.960976 -278.744426)
			(xy 81.061052 -278.844502)
		)
		(stroke
			(width 0)
			(type solid)
		)
		(fill yes)
		(layer "In2.Cu")
		(net "M_C_CPU1_SB_DQ<7>")
	)
	(gr_poly
		(pts
			(xy 81.161128 -277.528274) (xy 81.061052 -277.428198) (xy 80.960976 -277.528274) (xy 80.960976 -277.572724)
			(xy 81.161128 -277.572724)
		)
		(stroke
			(width 0)
			(type solid)
		)
		(fill yes)
		(layer "In2.Cu")
		(net "M_C_CPU1_SB_DQ<4>")
	)
	(gr_poly
		(pts
			(xy 81.161128 -277.124668) (xy 81.161128 -277.076916) (xy 80.960976 -277.076916) (xy 80.960976 -277.124668)
			(xy 81.061052 -277.22449)
		)
		(stroke
			(width 0)
			(type solid)
		)
		(fill yes)
		(layer "In2.Cu")
		(net "M_C_CPU1_SB_DQS_DP<5>")
	)
	(gr_poly
		(pts
			(xy 81.161128 -275.908008) (xy 81.061052 -275.808186) (xy 80.960976 -275.908008) (xy 80.960976 -275.95576)
			(xy 81.161128 -275.95576)
		)
		(stroke
			(width 0)
			(type solid)
		)
		(fill yes)
		(layer "In2.Cu")
		(net "M_C_CPU1_SB_DQS_DP<0>")
	)
	(gr_poly
		(pts
			(xy 81.161128 -275.504402) (xy 81.161128 -275.459952) (xy 80.960976 -275.459952) (xy 80.960976 -275.504402)
			(xy 81.061052 -275.604478)
		)
		(stroke
			(width 0)
			(type solid)
		)
		(fill yes)
		(layer "In2.Cu")
		(net "M_C_CPU1_SB_DQ<3>")
	)
	(gr_poly
		(pts
			(xy 81.161128 -274.28825) (xy 81.061052 -274.188174) (xy 80.960976 -274.28825) (xy 80.960976 -274.3327)
			(xy 81.161128 -274.3327)
		)
		(stroke
			(width 0)
			(type solid)
		)
		(fill yes)
		(layer "In2.Cu")
		(net "M_C_CPU1_SB_DQ<0>")
	)
	(gr_poly
		(pts
			(xy 81.161128 -273.88439) (xy 81.161128 -273.83994) (xy 80.960976 -273.83994) (xy 80.960976 -273.88439)
			(xy 81.061052 -273.984466)
		)
		(stroke
			(width 0)
			(type solid)
		)
		(fill yes)
		(layer "In2.Cu")
		(net "M_C_CPU1_SB_CB<3>")
	)
	(gr_poly
		(pts
			(xy 81.161128 -272.668238) (xy 81.061052 -272.568162) (xy 80.960976 -272.668238) (xy 80.960976 -272.712688)
			(xy 81.161128 -272.712688)
		)
		(stroke
			(width 0)
			(type solid)
		)
		(fill yes)
		(layer "In2.Cu")
		(net "M_C_CPU1_SB_CB<0>")
	)
	(gr_poly
		(pts
			(xy 81.161128 -272.264632) (xy 81.161128 -272.21688) (xy 80.960976 -272.21688) (xy 80.960976 -272.264632)
			(xy 81.061052 -272.364454)
		)
		(stroke
			(width 0)
			(type solid)
		)
		(fill yes)
		(layer "In2.Cu")
		(net "M_C_CPU1_SB_DQS_DP<4>")
	)
	(gr_poly
		(pts
			(xy 81.161128 -271.047972) (xy 81.061052 -270.94815) (xy 80.960976 -271.047972) (xy 80.960976 -271.095724)
			(xy 81.161128 -271.095724)
		)
		(stroke
			(width 0)
			(type solid)
		)
		(fill yes)
		(layer "In2.Cu")
		(net "M_C_CPU1_SB_DQS_DP<9>")
	)
	(gr_poly
		(pts
			(xy 81.161128 -270.644366) (xy 81.161128 -270.599916) (xy 80.960976 -270.599916) (xy 80.960976 -270.644366)
			(xy 81.061052 -270.744442)
		)
		(stroke
			(width 0)
			(type solid)
		)
		(fill yes)
		(layer "In2.Cu")
		(net "M_C_CPU1_SB_CB<7>")
	)
	(gr_poly
		(pts
			(xy 81.161128 -269.428214) (xy 81.061052 -269.328138) (xy 80.960976 -269.428214) (xy 80.960976 -269.472664)
			(xy 81.161128 -269.472664)
		)
		(stroke
			(width 0)
			(type solid)
		)
		(fill yes)
		(layer "In2.Cu")
		(net "M_C_CPU1_SB_CB<4>")
	)
	(gr_poly
		(pts
			(xy 81.161128 -267.801852) (xy 81.061052 -267.701776) (xy 80.960976 -267.801852) (xy 80.960976 -267.846302)
			(xy 81.161128 -267.846302)
		)
		(stroke
			(width 0)
			(type solid)
		)
		(fill yes)
		(layer "In2.Cu")
		(net "M_C_CPU1_SB_RSP<0>")
	)
	(gr_poly
		(pts
			(xy 81.161128 -265.78433) (xy 81.161128 -265.73988) (xy 80.960976 -265.73988) (xy 80.960976 -265.78433)
			(xy 81.061052 -265.884406)
		)
		(stroke
			(width 0)
			(type solid)
		)
		(fill yes)
		(layer "In2.Cu")
		(net "M_C_CPU1_SB_CS_N<0>")
	)
	(gr_poly
		(pts
			(xy 81.161128 -264.568178) (xy 81.061052 -264.468102) (xy 80.960976 -264.568178) (xy 80.960976 -264.612628)
			(xy 81.161128 -264.612628)
		)
		(stroke
			(width 0)
			(type solid)
		)
		(fill yes)
		(layer "In2.Cu")
		(net "M_C_CPU1_SB_CA<6>")
	)
	(gr_poly
		(pts
			(xy 81.161128 -264.164318) (xy 81.161128 -264.119868) (xy 80.960976 -264.119868) (xy 80.960976 -264.164318)
			(xy 81.061052 -264.264394)
		)
		(stroke
			(width 0)
			(type solid)
		)
		(fill yes)
		(layer "In2.Cu")
		(net "M_C_CPU1_SB_CA<5>")
	)
	(gr_poly
		(pts
			(xy 81.161128 -262.948166) (xy 81.061052 -262.84809) (xy 80.960976 -262.948166) (xy 80.960976 -262.992616)
			(xy 81.161128 -262.992616)
		)
		(stroke
			(width 0)
			(type solid)
		)
		(fill yes)
		(layer "In2.Cu")
		(net "M_C_CPU1_SB_CA<2>")
	)
	(gr_poly
		(pts
			(xy 81.161128 -262.544306) (xy 81.161128 -262.499856) (xy 80.960976 -262.499856) (xy 80.960976 -262.544306)
			(xy 81.061052 -262.644382)
		)
		(stroke
			(width 0)
			(type solid)
		)
		(fill yes)
		(layer "In2.Cu")
		(net "M_C_CPU1_SB_CA<1>")
	)
	(gr_poly
		(pts
			(xy 81.2165 -295.48201) (xy 81.179924 -295.345358) (xy 81.141316 -295.32326) (xy 81.04124 -295.496488)
			(xy 81.079848 -295.518586)
		)
		(stroke
			(width 0)
			(type solid)
		)
		(fill yes)
		(layer "In2.Cu")
		(net "M_C_CPU1_SB_DQ<31>")
	)
	(gr_poly
		(pts
			(xy 81.250282 -228.633274) (xy 81.150206 -228.460046) (xy 81.111852 -228.482398) (xy 81.075022 -228.61905)
			(xy 81.211674 -228.655626)
		)
		(stroke
			(width 0)
			(type solid)
		)
		(fill yes)
		(layer "In2.Cu")
		(net "M_C_CPU1_SA_DQ<7>")
	)
	(gr_poly
		(pts
			(xy 81.250282 -227.013262) (xy 81.150206 -226.840034) (xy 81.111852 -226.862386) (xy 81.075022 -226.999038)
			(xy 81.211674 -227.035614)
		)
		(stroke
			(width 0)
			(type solid)
		)
		(fill yes)
		(layer "In2.Cu")
		(net "M_C_CPU1_SA_DQ<6>")
	)
	(gr_poly
		(pts
			(xy 81.251044 -230.254556) (xy 81.150968 -230.081328) (xy 81.11236 -230.103426) (xy 81.075784 -230.240078)
			(xy 81.212436 -230.276654)
		)
		(stroke
			(width 0)
			(type solid)
		)
		(fill yes)
		(layer "In2.Cu")
		(net "M_C_CPU1_SA_DQ<10>")
	)
	(gr_poly
		(pts
			(xy 81.253076 -225.392488) (xy 81.153254 -225.21926) (xy 81.111852 -225.243136) (xy 81.075276 -225.379534)
			(xy 81.211928 -225.416364)
		)
		(stroke
			(width 0)
			(type solid)
		)
		(fill yes)
		(layer "In2.Cu")
		(net "M_C_CPU1_SA_DQS_DP<5>")
	)
	(gr_poly
		(pts
			(xy 81.253076 -223.772476) (xy 81.153254 -223.599248) (xy 81.111852 -223.623124) (xy 81.075276 -223.759522)
			(xy 81.211928 -223.796352)
		)
		(stroke
			(width 0)
			(type solid)
		)
		(fill yes)
		(layer "In2.Cu")
		(net "M_C_CPU1_SA_DQS_DN<0>")
	)
	(gr_poly
		(pts
			(xy 81.331054 -256.026158) (xy 81.230978 -255.926336) (xy 81.130902 -256.026158) (xy 81.130902 -256.07391)
			(xy 81.331054 -256.07391)
		)
		(stroke
			(width 0)
			(type solid)
		)
		(fill yes)
		(layer "In2.Cu")
		(net "M_C_CPU1_CLK_DP<0>")
	)
	(gr_poly
		(pts
			(xy 81.331054 -255.622552) (xy 81.331054 -255.578102) (xy 81.130902 -255.578102) (xy 81.130902 -255.622552)
			(xy 81.230978 -255.722628)
		)
		(stroke
			(width 0)
			(type solid)
		)
		(fill yes)
		(layer "In2.Cu")
		(net "M_C_CPU1_SA_PAR")
	)
	(gr_poly
		(pts
			(xy 81.331054 -254.4064) (xy 81.230978 -254.306324) (xy 81.130902 -254.4064) (xy 81.130902 -254.45085)
			(xy 81.331054 -254.45085)
		)
		(stroke
			(width 0)
			(type solid)
		)
		(fill yes)
		(layer "In2.Cu")
		(net "M_C_CPU1_SA_CA<4>")
	)
	(gr_poly
		(pts
			(xy 81.331054 -254.00254) (xy 81.331054 -253.95809) (xy 81.130902 -253.95809) (xy 81.130902 -254.00254)
			(xy 81.230978 -254.102616)
		)
		(stroke
			(width 0)
			(type solid)
		)
		(fill yes)
		(layer "In2.Cu")
		(net "M_C_CPU1_SA_CA<3>")
	)
	(gr_poly
		(pts
			(xy 81.331054 -252.786388) (xy 81.230978 -252.686312) (xy 81.130902 -252.786388) (xy 81.130902 -252.830838)
			(xy 81.331054 -252.830838)
		)
		(stroke
			(width 0)
			(type solid)
		)
		(fill yes)
		(layer "In2.Cu")
		(net "M_C_CPU1_SA_CA<0>")
	)
	(gr_poly
		(pts
			(xy 81.331054 -252.382528) (xy 81.331054 -252.338078) (xy 81.130902 -252.338078) (xy 81.130902 -252.382528)
			(xy 81.230978 -252.482604)
		)
		(stroke
			(width 0)
			(type solid)
		)
		(fill yes)
		(layer "In2.Cu")
		(net "M_C_CPU1_SA_CS_N<1>")
	)
	(gr_poly
		(pts
			(xy 81.331054 -250.762516) (xy 81.331054 -250.718066) (xy 81.130902 -250.718066) (xy 81.130902 -250.762516)
			(xy 81.230978 -250.862592)
		)
		(stroke
			(width 0)
			(type solid)
		)
		(fill yes)
		(layer "In2.Cu")
		(net "M_C_CPU1_RESET_N")
	)
	(gr_poly
		(pts
			(xy 81.331054 -249.142504) (xy 81.331054 -249.098054) (xy 81.130902 -249.098054) (xy 81.130902 -249.142504)
			(xy 81.230978 -249.24258)
		)
		(stroke
			(width 0)
			(type solid)
		)
		(fill yes)
		(layer "In2.Cu")
		(net "M_C_CPU1_SA_CB<7>")
	)
	(gr_poly
		(pts
			(xy 81.331054 -247.926352) (xy 81.230978 -247.826276) (xy 81.130902 -247.926352) (xy 81.130902 -247.970802)
			(xy 81.331054 -247.970802)
		)
		(stroke
			(width 0)
			(type solid)
		)
		(fill yes)
		(layer "In2.Cu")
		(net "M_C_CPU1_SA_CB<4>")
	)
	(gr_poly
		(pts
			(xy 81.331054 -247.522746) (xy 81.331054 -247.474994) (xy 81.130902 -247.474994) (xy 81.130902 -247.522746)
			(xy 81.230978 -247.622568)
		)
		(stroke
			(width 0)
			(type solid)
		)
		(fill yes)
		(layer "In2.Cu")
		(net "M_C_CPU1_SA_DQS_DP<9>")
	)
	(gr_poly
		(pts
			(xy 81.331054 -246.306086) (xy 81.230978 -246.206264) (xy 81.130902 -246.306086) (xy 81.130902 -246.353838)
			(xy 81.331054 -246.353838)
		)
		(stroke
			(width 0)
			(type solid)
		)
		(fill yes)
		(layer "In2.Cu")
		(net "M_C_CPU1_SA_DQS_DP<4>")
	)
	(gr_poly
		(pts
			(xy 81.331054 -245.90248) (xy 81.331054 -245.85803) (xy 81.130902 -245.85803) (xy 81.130902 -245.90248)
			(xy 81.230978 -246.002556)
		)
		(stroke
			(width 0)
			(type solid)
		)
		(fill yes)
		(layer "In2.Cu")
		(net "M_C_CPU1_SA_CB<3>")
	)
	(gr_poly
		(pts
			(xy 81.331054 -244.686328) (xy 81.230978 -244.586252) (xy 81.130902 -244.686328) (xy 81.130902 -244.730778)
			(xy 81.331054 -244.730778)
		)
		(stroke
			(width 0)
			(type solid)
		)
		(fill yes)
		(layer "In2.Cu")
		(net "M_C_CPU1_SA_CB<0>")
	)
	(gr_poly
		(pts
			(xy 81.331054 -244.282468) (xy 81.331054 -244.238018) (xy 81.130902 -244.238018) (xy 81.130902 -244.282468)
			(xy 81.230978 -244.382544)
		)
		(stroke
			(width 0)
			(type solid)
		)
		(fill yes)
		(layer "In2.Cu")
		(net "M_C_CPU1_SA_DQ<31>")
	)
	(gr_poly
		(pts
			(xy 81.331054 -243.066316) (xy 81.230978 -242.96624) (xy 81.130902 -243.066316) (xy 81.130902 -243.110766)
			(xy 81.331054 -243.110766)
		)
		(stroke
			(width 0)
			(type solid)
		)
		(fill yes)
		(layer "In2.Cu")
		(net "M_C_CPU1_SA_DQ<28>")
	)
	(gr_poly
		(pts
			(xy 81.331054 -242.66271) (xy 81.331054 -242.614958) (xy 81.130902 -242.614958) (xy 81.130902 -242.66271)
			(xy 81.230978 -242.762532)
		)
		(stroke
			(width 0)
			(type solid)
		)
		(fill yes)
		(layer "In2.Cu")
		(net "M_C_CPU1_SA_DQS_DP<8>")
	)
	(gr_poly
		(pts
			(xy 81.331054 -241.44605) (xy 81.230978 -241.346228) (xy 81.130902 -241.44605) (xy 81.130902 -241.493802)
			(xy 81.331054 -241.493802)
		)
		(stroke
			(width 0)
			(type solid)
		)
		(fill yes)
		(layer "In2.Cu")
		(net "M_C_CPU1_SA_DQS_DP<3>")
	)
	(gr_poly
		(pts
			(xy 81.331054 -241.042444) (xy 81.331054 -240.997994) (xy 81.130902 -240.997994) (xy 81.130902 -241.042444)
			(xy 81.230978 -241.14252)
		)
		(stroke
			(width 0)
			(type solid)
		)
		(fill yes)
		(layer "In2.Cu")
		(net "M_C_CPU1_SA_DQ<27>")
	)
	(gr_poly
		(pts
			(xy 81.331054 -239.826292) (xy 81.230978 -239.726216) (xy 81.130902 -239.826292) (xy 81.130902 -239.870742)
			(xy 81.331054 -239.870742)
		)
		(stroke
			(width 0)
			(type solid)
		)
		(fill yes)
		(layer "In2.Cu")
		(net "M_C_CPU1_SA_DQ<24>")
	)
	(gr_poly
		(pts
			(xy 81.331054 -239.422432) (xy 81.331054 -239.377982) (xy 81.130902 -239.377982) (xy 81.130902 -239.422432)
			(xy 81.230978 -239.522508)
		)
		(stroke
			(width 0)
			(type solid)
		)
		(fill yes)
		(layer "In2.Cu")
		(net "M_C_CPU1_SA_DQ<23>")
	)
	(gr_poly
		(pts
			(xy 81.331054 -238.20628) (xy 81.230978 -238.106204) (xy 81.130902 -238.20628) (xy 81.130902 -238.25073)
			(xy 81.331054 -238.25073)
		)
		(stroke
			(width 0)
			(type solid)
		)
		(fill yes)
		(layer "In2.Cu")
		(net "M_C_CPU1_SA_DQ<20>")
	)
	(gr_poly
		(pts
			(xy 81.331054 -237.802674) (xy 81.331054 -237.754922) (xy 81.130902 -237.754922) (xy 81.130902 -237.802674)
			(xy 81.230978 -237.902496)
		)
		(stroke
			(width 0)
			(type solid)
		)
		(fill yes)
		(layer "In2.Cu")
		(net "M_C_CPU1_SA_DQS_DP<7>")
	)
	(gr_poly
		(pts
			(xy 81.331054 -236.586014) (xy 81.230978 -236.486192) (xy 81.130902 -236.586014) (xy 81.130902 -236.633766)
			(xy 81.331054 -236.633766)
		)
		(stroke
			(width 0)
			(type solid)
		)
		(fill yes)
		(layer "In2.Cu")
		(net "M_C_CPU1_SA_DQS_DP<2>")
	)
	(gr_poly
		(pts
			(xy 81.331054 -236.182408) (xy 81.331054 -236.137958) (xy 81.130902 -236.137958) (xy 81.130902 -236.182408)
			(xy 81.230978 -236.282484)
		)
		(stroke
			(width 0)
			(type solid)
		)
		(fill yes)
		(layer "In2.Cu")
		(net "M_C_CPU1_SA_DQ<19>")
	)
	(gr_poly
		(pts
			(xy 81.331054 -234.966256) (xy 81.230978 -234.86618) (xy 81.130902 -234.966256) (xy 81.130902 -235.010706)
			(xy 81.331054 -235.010706)
		)
		(stroke
			(width 0)
			(type solid)
		)
		(fill yes)
		(layer "In2.Cu")
		(net "M_C_CPU1_SA_DQ<16>")
	)
	(gr_poly
		(pts
			(xy 81.331054 -234.562396) (xy 81.331054 -234.517946) (xy 81.130902 -234.517946) (xy 81.130902 -234.562396)
			(xy 81.230978 -234.662472)
		)
		(stroke
			(width 0)
			(type solid)
		)
		(fill yes)
		(layer "In2.Cu")
		(net "M_C_CPU1_SA_DQ<15>")
	)
	(gr_poly
		(pts
			(xy 81.331054 -233.346244) (xy 81.230978 -233.246168) (xy 81.130902 -233.346244) (xy 81.130902 -233.390694)
			(xy 81.331054 -233.390694)
		)
		(stroke
			(width 0)
			(type solid)
		)
		(fill yes)
		(layer "In2.Cu")
		(net "M_C_CPU1_SA_DQ<12>")
	)
	(gr_poly
		(pts
			(xy 81.331054 -232.942638) (xy 81.331054 -232.894886) (xy 81.130902 -232.894886) (xy 81.130902 -232.942638)
			(xy 81.230978 -233.04246)
		)
		(stroke
			(width 0)
			(type solid)
		)
		(fill yes)
		(layer "In2.Cu")
		(net "M_C_CPU1_SA_DQS_DP<6>")
	)
	(gr_poly
		(pts
			(xy 81.331054 -231.725978) (xy 81.230978 -231.626156) (xy 81.130902 -231.725978) (xy 81.130902 -231.77373)
			(xy 81.331054 -231.77373)
		)
		(stroke
			(width 0)
			(type solid)
		)
		(fill yes)
		(layer "In2.Cu")
		(net "M_C_CPU1_SA_DQS_DP<1>")
	)
	(gr_poly
		(pts
			(xy 81.331054 -231.322626) (xy 81.331054 -231.278176) (xy 81.130902 -231.278176) (xy 81.130902 -231.322626)
			(xy 81.230978 -231.422702)
		)
		(stroke
			(width 0)
			(type solid)
		)
		(fill yes)
		(layer "In2.Cu")
		(net "M_C_CPU1_SA_DQ<11>")
	)
	(gr_poly
		(pts
			(xy 81.350358 -229.706424) (xy 81.386934 -229.569772) (xy 81.250536 -229.533196) (xy 81.211928 -229.555548)
			(xy 81.312004 -229.728776)
		)
		(stroke
			(width 0)
			(type solid)
		)
		(fill yes)
		(layer "In2.Cu")
		(net "M_C_CPU1_SA_DQ<8>")
	)
	(gr_poly
		(pts
			(xy 81.350358 -228.086666) (xy 81.386934 -227.950014) (xy 81.250536 -227.913438) (xy 81.211928 -227.93579)
			(xy 81.312004 -228.109018)
		)
		(stroke
			(width 0)
			(type solid)
		)
		(fill yes)
		(layer "In2.Cu")
		(net "M_C_CPU1_SA_DQ<5>")
	)
	(gr_poly
		(pts
			(xy 81.350358 -226.466654) (xy 81.386934 -226.330002) (xy 81.250536 -226.293426) (xy 81.211928 -226.315778)
			(xy 81.312004 -226.489006)
		)
		(stroke
			(width 0)
			(type solid)
		)
		(fill yes)
		(layer "In2.Cu")
		(net "M_C_CPU1_SA_DQ<4>")
	)
	(gr_poly
		(pts
			(xy 81.350358 -224.84588) (xy 81.386934 -224.709482) (xy 81.250282 -224.672652) (xy 81.209134 -224.696528)
			(xy 81.308956 -224.869756)
		)
		(stroke
			(width 0)
			(type solid)
		)
		(fill yes)
		(layer "In2.Cu")
		(net "M_C_CPU1_SA_DQS_DN<5>")
	)
	(gr_poly
		(pts
			(xy 81.350358 -223.225868) (xy 81.386934 -223.08947) (xy 81.250282 -223.05264) (xy 81.209134 -223.076516)
			(xy 81.308956 -223.249744)
		)
		(stroke
			(width 0)
			(type solid)
		)
		(fill yes)
		(layer "In2.Cu")
		(net "M_C_CPU1_SA_DQS_DP<0>")
	)
	(gr_poly
		(pts
			(xy 81.631028 -292.918134) (xy 81.530952 -292.818058) (xy 81.430876 -292.918134) (xy 81.430876 -292.962584)
			(xy 81.631028 -292.962584)
		)
		(stroke
			(width 0)
			(type solid)
		)
		(fill yes)
		(layer "In2.Cu")
		(net "M_C_CPU1_SB_DQ<29>")
	)
	(gr_poly
		(pts
			(xy 81.631028 -292.514274) (xy 81.631028 -292.469824) (xy 81.430876 -292.469824) (xy 81.430876 -292.514274)
			(xy 81.530952 -292.61435)
		)
		(stroke
			(width 0)
			(type solid)
		)
		(fill yes)
		(layer "In2.Cu")
		(net "M_C_CPU1_SB_DQ<30>")
	)
	(gr_poly
		(pts
			(xy 81.631028 -290.894516) (xy 81.631028 -290.846764) (xy 81.430876 -290.846764) (xy 81.430876 -290.894516)
			(xy 81.530952 -290.994338)
		)
		(stroke
			(width 0)
			(type solid)
		)
		(fill yes)
		(layer "In2.Cu")
		(net "M_C_CPU1_SB_DQS_DN<3>")
	)
	(gr_poly
		(pts
			(xy 81.631028 -289.67811) (xy 81.530952 -289.578034) (xy 81.430876 -289.67811) (xy 81.430876 -289.72256)
			(xy 81.631028 -289.72256)
		)
		(stroke
			(width 0)
			(type solid)
		)
		(fill yes)
		(layer "In2.Cu")
		(net "M_C_CPU1_SB_DQ<25>")
	)
	(gr_poly
		(pts
			(xy 81.631028 -289.27425) (xy 81.631028 -289.2298) (xy 81.430876 -289.2298) (xy 81.430876 -289.27425)
			(xy 81.530952 -289.374326)
		)
		(stroke
			(width 0)
			(type solid)
		)
		(fill yes)
		(layer "In2.Cu")
		(net "M_C_CPU1_SB_DQ<26>")
	)
	(gr_poly
		(pts
			(xy 81.631028 -288.058098) (xy 81.530952 -287.958022) (xy 81.430876 -288.058098) (xy 81.430876 -288.102548)
			(xy 81.631028 -288.102548)
		)
		(stroke
			(width 0)
			(type solid)
		)
		(fill yes)
		(layer "In2.Cu")
		(net "M_C_CPU1_SB_DQ<21>")
	)
	(gr_poly
		(pts
			(xy 81.631028 -287.654492) (xy 81.631028 -287.610042) (xy 81.430876 -287.610042) (xy 81.430876 -287.654492)
			(xy 81.530952 -287.754568)
		)
		(stroke
			(width 0)
			(type solid)
		)
		(fill yes)
		(layer "In2.Cu")
		(net "M_C_CPU1_SB_DQ<22>")
	)
	(gr_poly
		(pts
			(xy 81.631028 -286.438086) (xy 81.530952 -286.33801) (xy 81.430876 -286.438086) (xy 81.430876 -286.485838)
			(xy 81.631028 -286.485838)
		)
		(stroke
			(width 0)
			(type solid)
		)
		(fill yes)
		(layer "In2.Cu")
		(net "M_C_CPU1_SB_DQS_DN<7>")
	)
	(gr_poly
		(pts
			(xy 81.631028 -286.034734) (xy 81.631028 -285.986982) (xy 81.430876 -285.986982) (xy 81.430876 -286.034734)
			(xy 81.530952 -286.134556)
		)
		(stroke
			(width 0)
			(type solid)
		)
		(fill yes)
		(layer "In2.Cu")
		(net "M_C_CPU1_SB_DQS_DN<2>")
	)
	(gr_poly
		(pts
			(xy 81.631028 -284.818328) (xy 81.530952 -284.718252) (xy 81.430876 -284.818328) (xy 81.430876 -284.862778)
			(xy 81.631028 -284.862778)
		)
		(stroke
			(width 0)
			(type solid)
		)
		(fill yes)
		(layer "In2.Cu")
		(net "M_C_CPU1_SB_DQ<17>")
	)
	(gr_poly
		(pts
			(xy 81.631028 -284.414468) (xy 81.631028 -284.370018) (xy 81.430876 -284.370018) (xy 81.430876 -284.414468)
			(xy 81.530952 -284.514544)
		)
		(stroke
			(width 0)
			(type solid)
		)
		(fill yes)
		(layer "In2.Cu")
		(net "M_C_CPU1_SB_DQ<18>")
	)
	(gr_poly
		(pts
			(xy 81.631028 -283.198316) (xy 81.530952 -283.09824) (xy 81.430876 -283.198316) (xy 81.430876 -283.242766)
			(xy 81.631028 -283.242766)
		)
		(stroke
			(width 0)
			(type solid)
		)
		(fill yes)
		(layer "In2.Cu")
		(net "M_C_CPU1_SB_DQ<13>")
	)
	(gr_poly
		(pts
			(xy 81.631028 -282.794456) (xy 81.631028 -282.750006) (xy 81.430876 -282.750006) (xy 81.430876 -282.794456)
			(xy 81.530952 -282.894532)
		)
		(stroke
			(width 0)
			(type solid)
		)
		(fill yes)
		(layer "In2.Cu")
		(net "M_C_CPU1_SB_DQ<14>")
	)
	(gr_poly
		(pts
			(xy 81.631028 -281.57805) (xy 81.530952 -281.478228) (xy 81.430876 -281.57805) (xy 81.430876 -281.625802)
			(xy 81.631028 -281.625802)
		)
		(stroke
			(width 0)
			(type solid)
		)
		(fill yes)
		(layer "In2.Cu")
		(net "M_C_CPU1_SB_DQS_DN<6>")
	)
	(gr_poly
		(pts
			(xy 81.631028 -281.174698) (xy 81.631028 -281.126946) (xy 81.430876 -281.126946) (xy 81.430876 -281.174698)
			(xy 81.530952 -281.27452)
		)
		(stroke
			(width 0)
			(type solid)
		)
		(fill yes)
		(layer "In2.Cu")
		(net "M_C_CPU1_SB_DQS_DN<1>")
	)
	(gr_poly
		(pts
			(xy 81.631028 -279.958292) (xy 81.530952 -279.858216) (xy 81.430876 -279.958292) (xy 81.430876 -280.002742)
			(xy 81.631028 -280.002742)
		)
		(stroke
			(width 0)
			(type solid)
		)
		(fill yes)
		(layer "In2.Cu")
		(net "M_C_CPU1_SB_DQ<9>")
	)
	(gr_poly
		(pts
			(xy 81.631028 -279.554432) (xy 81.631028 -279.509982) (xy 81.430876 -279.509982) (xy 81.430876 -279.554432)
			(xy 81.530952 -279.654508)
		)
		(stroke
			(width 0)
			(type solid)
		)
		(fill yes)
		(layer "In2.Cu")
		(net "M_C_CPU1_SB_DQ<10>")
	)
	(gr_poly
		(pts
			(xy 81.631028 -278.33828) (xy 81.530952 -278.238204) (xy 81.430876 -278.33828) (xy 81.430876 -278.38273)
			(xy 81.631028 -278.38273)
		)
		(stroke
			(width 0)
			(type solid)
		)
		(fill yes)
		(layer "In2.Cu")
		(net "M_C_CPU1_SB_DQ<5>")
	)
	(gr_poly
		(pts
			(xy 81.631028 -277.93442) (xy 81.631028 -277.88997) (xy 81.430876 -277.88997) (xy 81.430876 -277.93442)
			(xy 81.530952 -278.034496)
		)
		(stroke
			(width 0)
			(type solid)
		)
		(fill yes)
		(layer "In2.Cu")
		(net "M_C_CPU1_SB_DQ<6>")
	)
	(gr_poly
		(pts
			(xy 81.631028 -276.718014) (xy 81.530952 -276.618192) (xy 81.430876 -276.718014) (xy 81.430876 -276.765766)
			(xy 81.631028 -276.765766)
		)
		(stroke
			(width 0)
			(type solid)
		)
		(fill yes)
		(layer "In2.Cu")
		(net "M_C_CPU1_SB_DQS_DN<5>")
	)
	(gr_poly
		(pts
			(xy 81.631028 -276.314662) (xy 81.631028 -276.26691) (xy 81.430876 -276.26691) (xy 81.430876 -276.314662)
			(xy 81.530952 -276.414484)
		)
		(stroke
			(width 0)
			(type solid)
		)
		(fill yes)
		(layer "In2.Cu")
		(net "M_C_CPU1_SB_DQS_DN<0>")
	)
	(gr_poly
		(pts
			(xy 81.631028 -275.098256) (xy 81.530952 -274.99818) (xy 81.430876 -275.098256) (xy 81.430876 -275.142706)
			(xy 81.631028 -275.142706)
		)
		(stroke
			(width 0)
			(type solid)
		)
		(fill yes)
		(layer "In2.Cu")
		(net "M_C_CPU1_SB_DQ<1>")
	)
	(gr_poly
		(pts
			(xy 81.631028 -274.694396) (xy 81.631028 -274.649946) (xy 81.430876 -274.649946) (xy 81.430876 -274.694396)
			(xy 81.530952 -274.794472)
		)
		(stroke
			(width 0)
			(type solid)
		)
		(fill yes)
		(layer "In2.Cu")
		(net "M_C_CPU1_SB_DQ<2>")
	)
	(gr_poly
		(pts
			(xy 81.631028 -273.478244) (xy 81.530952 -273.378168) (xy 81.430876 -273.478244) (xy 81.430876 -273.522694)
			(xy 81.631028 -273.522694)
		)
		(stroke
			(width 0)
			(type solid)
		)
		(fill yes)
		(layer "In2.Cu")
		(net "M_C_CPU1_SB_CB<1>")
	)
	(gr_poly
		(pts
			(xy 81.631028 -273.074384) (xy 81.631028 -273.029934) (xy 81.430876 -273.029934) (xy 81.430876 -273.074384)
			(xy 81.530952 -273.17446)
		)
		(stroke
			(width 0)
			(type solid)
		)
		(fill yes)
		(layer "In2.Cu")
		(net "M_C_CPU1_SB_CB<2>")
	)
	(gr_poly
		(pts
			(xy 81.631028 -271.857978) (xy 81.530952 -271.758156) (xy 81.430876 -271.857978) (xy 81.430876 -271.90573)
			(xy 81.631028 -271.90573)
		)
		(stroke
			(width 0)
			(type solid)
		)
		(fill yes)
		(layer "In2.Cu")
		(net "M_C_CPU1_SB_DQS_DN<4>")
	)
	(gr_poly
		(pts
			(xy 81.631028 -271.454626) (xy 81.631028 -271.406874) (xy 81.430876 -271.406874) (xy 81.430876 -271.454626)
			(xy 81.530952 -271.554448)
		)
		(stroke
			(width 0)
			(type solid)
		)
		(fill yes)
		(layer "In2.Cu")
		(net "M_C_CPU1_SB_DQS_DN<9>")
	)
	(gr_poly
		(pts
			(xy 81.631028 -270.23822) (xy 81.530952 -270.138144) (xy 81.430876 -270.23822) (xy 81.430876 -270.28267)
			(xy 81.631028 -270.28267)
		)
		(stroke
			(width 0)
			(type solid)
		)
		(fill yes)
		(layer "In2.Cu")
		(net "M_C_CPU1_SB_CB<5>")
	)
	(gr_poly
		(pts
			(xy 81.631028 -269.83436) (xy 81.631028 -269.78991) (xy 81.430876 -269.78991) (xy 81.430876 -269.83436)
			(xy 81.530952 -269.934436)
		)
		(stroke
			(width 0)
			(type solid)
		)
		(fill yes)
		(layer "In2.Cu")
		(net "M_C_CPU1_SB_CB<6>")
	)
	(gr_poly
		(pts
			(xy 81.631028 -266.594336) (xy 81.631028 -266.549886) (xy 81.430876 -266.549886) (xy 81.430876 -266.594336)
			(xy 81.530952 -266.694412)
		)
		(stroke
			(width 0)
			(type solid)
		)
		(fill yes)
		(layer "In2.Cu")
		(net "M_C_CPU1_SB_CS_N<1>")
	)
	(gr_poly
		(pts
			(xy 81.631028 -264.974324) (xy 81.631028 -264.929874) (xy 81.430876 -264.929874) (xy 81.430876 -264.974324)
			(xy 81.530952 -265.0744)
		)
		(stroke
			(width 0)
			(type solid)
		)
		(fill yes)
		(layer "In2.Cu")
		(net "M_C_CPU1_SB_PAR")
	)
	(gr_poly
		(pts
			(xy 81.631028 -263.758172) (xy 81.530952 -263.658096) (xy 81.430876 -263.758172) (xy 81.430876 -263.802622)
			(xy 81.631028 -263.802622)
		)
		(stroke
			(width 0)
			(type solid)
		)
		(fill yes)
		(layer "In2.Cu")
		(net "M_C_CPU1_SB_CA<4>")
	)
	(gr_poly
		(pts
			(xy 81.631028 -263.354312) (xy 81.631028 -263.309862) (xy 81.430876 -263.309862) (xy 81.430876 -263.354312)
			(xy 81.530952 -263.454388)
		)
		(stroke
			(width 0)
			(type solid)
		)
		(fill yes)
		(layer "In2.Cu")
		(net "M_C_CPU1_SB_CA<3>")
	)
	(gr_poly
		(pts
			(xy 81.631028 -262.13816) (xy 81.530952 -262.038084) (xy 81.430876 -262.13816) (xy 81.430876 -262.18261)
			(xy 81.631028 -262.18261)
		)
		(stroke
			(width 0)
			(type solid)
		)
		(fill yes)
		(layer "In2.Cu")
		(net "M_C_CPU1_SB_CA<0>")
	)
	(gr_poly
		(pts
			(xy 81.637124 -266.991846) (xy 81.537302 -266.89177) (xy 81.437226 -266.991846) (xy 81.437226 -267.036296)
			(xy 81.637124 -267.036296)
		)
		(stroke
			(width 0)
			(type solid)
		)
		(fill yes)
		(layer "In2.Cu")
		(net "M_C_CPU1_SA_RSP<0>")
	)
	(gr_poly
		(pts
			(xy 81.638394 -291.298122) (xy 81.538318 -291.198046) (xy 81.438242 -291.298122) (xy 81.438242 -291.34562)
			(xy 81.638394 -291.34562)
		)
		(stroke
			(width 0)
			(type solid)
		)
		(fill yes)
		(layer "In2.Cu")
		(net "M_C_CPU1_SB_DQS_DN<8>")
	)
	(gr_poly
		(pts
			(xy 81.687162 -294.670734) (xy 81.650332 -294.534082) (xy 81.611978 -294.51173) (xy 81.511902 -294.684958)
			(xy 81.55051 -294.70731)
		)
		(stroke
			(width 0)
			(type solid)
		)
		(fill yes)
		(layer "In2.Cu")
		(net "M_C_CPU1_SB_DQ<31>")
	)
	(gr_poly
		(pts
			(xy 81.720182 -229.44328) (xy 81.620106 -229.270052) (xy 81.581752 -229.292404) (xy 81.544922 -229.429056)
			(xy 81.681574 -229.465632)
		)
		(stroke
			(width 0)
			(type solid)
		)
		(fill yes)
		(layer "In2.Cu")
		(net "M_C_CPU1_SA_DQ<7>")
	)
	(gr_poly
		(pts
			(xy 81.720182 -227.823268) (xy 81.620106 -227.65004) (xy 81.581752 -227.672392) (xy 81.544922 -227.809044)
			(xy 81.681574 -227.84562)
		)
		(stroke
			(width 0)
			(type solid)
		)
		(fill yes)
		(layer "In2.Cu")
		(net "M_C_CPU1_SA_DQ<6>")
	)
	(gr_poly
		(pts
			(xy 81.720182 -222.963232) (xy 81.620106 -222.790004) (xy 81.581752 -222.812356) (xy 81.544922 -222.949008)
			(xy 81.681574 -222.985584)
		)
		(stroke
			(width 0)
			(type solid)
		)
		(fill yes)
		(layer "In2.Cu")
		(net "M_C_CPU1_SA_DQ<3>")
	)
	(gr_poly
		(pts
			(xy 81.722976 -226.202494) (xy 81.623154 -226.029266) (xy 81.581752 -226.053142) (xy 81.545176 -226.18954)
			(xy 81.681828 -226.22637)
		)
		(stroke
			(width 0)
			(type solid)
		)
		(fill yes)
		(layer "In2.Cu")
		(net "M_C_CPU1_SA_DQS_DP<5>")
	)
	(gr_poly
		(pts
			(xy 81.722976 -224.582482) (xy 81.623154 -224.409254) (xy 81.581752 -224.43313) (xy 81.545176 -224.569528)
			(xy 81.681828 -224.606104)
		)
		(stroke
			(width 0)
			(type solid)
		)
		(fill yes)
		(layer "In2.Cu")
		(net "M_C_CPU1_SA_DQS_DN<0>")
	)
	(gr_poly
		(pts
			(xy 81.800954 -246.712486) (xy 81.800954 -246.664988) (xy 81.601056 -246.664988) (xy 81.601056 -246.712486)
			(xy 81.700878 -246.812562)
		)
		(stroke
			(width 0)
			(type solid)
		)
		(fill yes)
		(layer "In2.Cu")
		(net "M_C_CPU1_SA_DQS_DN<4>")
	)
	(gr_poly
		(pts
			(xy 81.801208 -256.432812) (xy 81.801208 -256.38506) (xy 81.601056 -256.38506) (xy 81.601056 -256.432812)
			(xy 81.701132 -256.532634)
		)
		(stroke
			(width 0)
			(type solid)
		)
		(fill yes)
		(layer "In2.Cu")
		(net "M_C_CPU1_CLK_DN<0>")
	)
	(gr_poly
		(pts
			(xy 81.801208 -255.216406) (xy 81.701132 -255.11633) (xy 81.601056 -255.216406) (xy 81.601056 -255.260856)
			(xy 81.801208 -255.260856)
		)
		(stroke
			(width 0)
			(type solid)
		)
		(fill yes)
		(layer "In2.Cu")
		(net "M_C_CPU1_SA_CA<6>")
	)
	(gr_poly
		(pts
			(xy 81.801208 -254.812546) (xy 81.801208 -254.768096) (xy 81.601056 -254.768096) (xy 81.601056 -254.812546)
			(xy 81.701132 -254.912622)
		)
		(stroke
			(width 0)
			(type solid)
		)
		(fill yes)
		(layer "In2.Cu")
		(net "M_C_CPU1_SA_CA<5>")
	)
	(gr_poly
		(pts
			(xy 81.801208 -253.596394) (xy 81.701132 -253.496318) (xy 81.601056 -253.596394) (xy 81.601056 -253.640844)
			(xy 81.801208 -253.640844)
		)
		(stroke
			(width 0)
			(type solid)
		)
		(fill yes)
		(layer "In2.Cu")
		(net "M_C_CPU1_SA_CA<2>")
	)
	(gr_poly
		(pts
			(xy 81.801208 -253.192534) (xy 81.801208 -253.148084) (xy 81.601056 -253.148084) (xy 81.601056 -253.192534)
			(xy 81.701132 -253.29261)
		)
		(stroke
			(width 0)
			(type solid)
		)
		(fill yes)
		(layer "In2.Cu")
		(net "M_C_CPU1_SA_CA<1>")
	)
	(gr_poly
		(pts
			(xy 81.801208 -251.572522) (xy 81.801208 -251.528072) (xy 81.601056 -251.528072) (xy 81.601056 -251.572522)
			(xy 81.701132 -251.672598)
		)
		(stroke
			(width 0)
			(type solid)
		)
		(fill yes)
		(layer "In2.Cu")
		(net "M_C_CPU1_SA_CS_N<0>")
	)
	(gr_poly
		(pts
			(xy 81.801208 -250.35637) (xy 81.701132 -250.256294) (xy 81.601056 -250.35637) (xy 81.601056 -250.40082)
			(xy 81.801208 -250.40082)
		)
		(stroke
			(width 0)
			(type solid)
		)
		(fill yes)
		(layer "In2.Cu")
		(net "M_C_CPU1_ALERT_R_N")
	)
	(gr_poly
		(pts
			(xy 81.801208 -248.736358) (xy 81.701132 -248.636282) (xy 81.601056 -248.736358) (xy 81.601056 -248.780808)
			(xy 81.801208 -248.780808)
		)
		(stroke
			(width 0)
			(type solid)
		)
		(fill yes)
		(layer "In2.Cu")
		(net "M_C_CPU1_SA_CB<5>")
	)
	(gr_poly
		(pts
			(xy 81.801208 -248.332498) (xy 81.801208 -248.288048) (xy 81.601056 -248.288048) (xy 81.601056 -248.332498)
			(xy 81.701132 -248.432574)
		)
		(stroke
			(width 0)
			(type solid)
		)
		(fill yes)
		(layer "In2.Cu")
		(net "M_C_CPU1_SA_CB<6>")
	)
	(gr_poly
		(pts
			(xy 81.801208 -247.116092) (xy 81.701132 -247.01627) (xy 81.601056 -247.116092) (xy 81.601056 -247.163844)
			(xy 81.801208 -247.163844)
		)
		(stroke
			(width 0)
			(type solid)
		)
		(fill yes)
		(layer "In2.Cu")
		(net "M_C_CPU1_SA_DQS_DN<9>")
	)
	(gr_poly
		(pts
			(xy 81.801208 -245.496334) (xy 81.701132 -245.396258) (xy 81.601056 -245.496334) (xy 81.601056 -245.540784)
			(xy 81.801208 -245.540784)
		)
		(stroke
			(width 0)
			(type solid)
		)
		(fill yes)
		(layer "In2.Cu")
		(net "M_C_CPU1_SA_CB<1>")
	)
	(gr_poly
		(pts
			(xy 81.801208 -245.092474) (xy 81.801208 -245.048024) (xy 81.601056 -245.048024) (xy 81.601056 -245.092474)
			(xy 81.701132 -245.19255)
		)
		(stroke
			(width 0)
			(type solid)
		)
		(fill yes)
		(layer "In2.Cu")
		(net "M_C_CPU1_SA_CB<2>")
	)
	(gr_poly
		(pts
			(xy 81.801208 -243.876322) (xy 81.701132 -243.776246) (xy 81.601056 -243.876322) (xy 81.601056 -243.920772)
			(xy 81.801208 -243.920772)
		)
		(stroke
			(width 0)
			(type solid)
		)
		(fill yes)
		(layer "In2.Cu")
		(net "M_C_CPU1_SA_DQ<29>")
	)
	(gr_poly
		(pts
			(xy 81.801208 -243.472462) (xy 81.801208 -243.428012) (xy 81.601056 -243.428012) (xy 81.601056 -243.472462)
			(xy 81.701132 -243.572538)
		)
		(stroke
			(width 0)
			(type solid)
		)
		(fill yes)
		(layer "In2.Cu")
		(net "M_C_CPU1_SA_DQ<30>")
	)
	(gr_poly
		(pts
			(xy 81.801208 -242.256056) (xy 81.701132 -242.156234) (xy 81.601056 -242.256056) (xy 81.601056 -242.303808)
			(xy 81.801208 -242.303808)
		)
		(stroke
			(width 0)
			(type solid)
		)
		(fill yes)
		(layer "In2.Cu")
		(net "M_C_CPU1_SA_DQS_DN<8>")
	)
	(gr_poly
		(pts
			(xy 81.801208 -241.852704) (xy 81.801208 -241.804952) (xy 81.601056 -241.804952) (xy 81.601056 -241.852704)
			(xy 81.701132 -241.952526)
		)
		(stroke
			(width 0)
			(type solid)
		)
		(fill yes)
		(layer "In2.Cu")
		(net "M_C_CPU1_SA_DQS_DN<3>")
	)
	(gr_poly
		(pts
			(xy 81.801208 -240.636298) (xy 81.701132 -240.536222) (xy 81.601056 -240.636298) (xy 81.601056 -240.680748)
			(xy 81.801208 -240.680748)
		)
		(stroke
			(width 0)
			(type solid)
		)
		(fill yes)
		(layer "In2.Cu")
		(net "M_C_CPU1_SA_DQ<25>")
	)
	(gr_poly
		(pts
			(xy 81.801208 -240.232438) (xy 81.801208 -240.187988) (xy 81.601056 -240.187988) (xy 81.601056 -240.232438)
			(xy 81.701132 -240.332514)
		)
		(stroke
			(width 0)
			(type solid)
		)
		(fill yes)
		(layer "In2.Cu")
		(net "M_C_CPU1_SA_DQ<26>")
	)
	(gr_poly
		(pts
			(xy 81.801208 -239.016286) (xy 81.701132 -238.91621) (xy 81.601056 -239.016286) (xy 81.601056 -239.060736)
			(xy 81.801208 -239.060736)
		)
		(stroke
			(width 0)
			(type solid)
		)
		(fill yes)
		(layer "In2.Cu")
		(net "M_C_CPU1_SA_DQ<21>")
	)
	(gr_poly
		(pts
			(xy 81.801208 -238.612426) (xy 81.801208 -238.567976) (xy 81.601056 -238.567976) (xy 81.601056 -238.612426)
			(xy 81.701132 -238.712502)
		)
		(stroke
			(width 0)
			(type solid)
		)
		(fill yes)
		(layer "In2.Cu")
		(net "M_C_CPU1_SA_DQ<22>")
	)
	(gr_poly
		(pts
			(xy 81.801208 -237.39602) (xy 81.701132 -237.296198) (xy 81.601056 -237.39602) (xy 81.601056 -237.443772)
			(xy 81.801208 -237.443772)
		)
		(stroke
			(width 0)
			(type solid)
		)
		(fill yes)
		(layer "In2.Cu")
		(net "M_C_CPU1_SA_DQS_DN<7>")
	)
	(gr_poly
		(pts
			(xy 81.801208 -236.992668) (xy 81.801208 -236.944916) (xy 81.601056 -236.944916) (xy 81.601056 -236.992668)
			(xy 81.701132 -237.09249)
		)
		(stroke
			(width 0)
			(type solid)
		)
		(fill yes)
		(layer "In2.Cu")
		(net "M_C_CPU1_SA_DQS_DN<2>")
	)
	(gr_poly
		(pts
			(xy 81.801208 -235.776262) (xy 81.701132 -235.676186) (xy 81.601056 -235.776262) (xy 81.601056 -235.820712)
			(xy 81.801208 -235.820712)
		)
		(stroke
			(width 0)
			(type solid)
		)
		(fill yes)
		(layer "In2.Cu")
		(net "M_C_CPU1_SA_DQ<17>")
	)
	(gr_poly
		(pts
			(xy 81.801208 -235.372402) (xy 81.801208 -235.327952) (xy 81.601056 -235.327952) (xy 81.601056 -235.372402)
			(xy 81.701132 -235.472478)
		)
		(stroke
			(width 0)
			(type solid)
		)
		(fill yes)
		(layer "In2.Cu")
		(net "M_C_CPU1_SA_DQ<18>")
	)
	(gr_poly
		(pts
			(xy 81.801208 -234.15625) (xy 81.701132 -234.056174) (xy 81.601056 -234.15625) (xy 81.601056 -234.2007)
			(xy 81.801208 -234.2007)
		)
		(stroke
			(width 0)
			(type solid)
		)
		(fill yes)
		(layer "In2.Cu")
		(net "M_C_CPU1_SA_DQ<13>")
	)
	(gr_poly
		(pts
			(xy 81.801208 -233.75239) (xy 81.801208 -233.70794) (xy 81.601056 -233.70794) (xy 81.601056 -233.75239)
			(xy 81.701132 -233.852466)
		)
		(stroke
			(width 0)
			(type solid)
		)
		(fill yes)
		(layer "In2.Cu")
		(net "M_C_CPU1_SA_DQ<14>")
	)
	(gr_poly
		(pts
			(xy 81.801208 -232.535984) (xy 81.701132 -232.436162) (xy 81.601056 -232.535984) (xy 81.601056 -232.583736)
			(xy 81.801208 -232.583736)
		)
		(stroke
			(width 0)
			(type solid)
		)
		(fill yes)
		(layer "In2.Cu")
		(net "M_C_CPU1_SA_DQS_DN<6>")
	)
	(gr_poly
		(pts
			(xy 81.801208 -232.132632) (xy 81.801208 -232.08488) (xy 81.601056 -232.08488) (xy 81.601056 -232.132632)
			(xy 81.701132 -232.232454)
		)
		(stroke
			(width 0)
			(type solid)
		)
		(fill yes)
		(layer "In2.Cu")
		(net "M_C_CPU1_SA_DQS_DN<1>")
	)
	(gr_poly
		(pts
			(xy 81.801208 -230.916226) (xy 81.701132 -230.81615) (xy 81.601056 -230.916226) (xy 81.601056 -230.960676)
			(xy 81.801208 -230.960676)
		)
		(stroke
			(width 0)
			(type solid)
		)
		(fill yes)
		(layer "In2.Cu")
		(net "M_C_CPU1_SA_DQ<9>")
	)
	(gr_poly
		(pts
			(xy 81.801208 -230.51262) (xy 81.801208 -230.46817) (xy 81.601056 -230.46817) (xy 81.601056 -230.51262)
			(xy 81.701132 -230.612696)
		)
		(stroke
			(width 0)
			(type solid)
		)
		(fill yes)
		(layer "In2.Cu")
		(net "M_C_CPU1_SA_DQ<10>")
	)
	(gr_poly
		(pts
			(xy 81.820258 -228.896672) (xy 81.856834 -228.76002) (xy 81.720436 -228.723444) (xy 81.681828 -228.745796)
			(xy 81.781904 -228.919024)
		)
		(stroke
			(width 0)
			(type solid)
		)
		(fill yes)
		(layer "In2.Cu")
		(net "M_C_CPU1_SA_DQ<5>")
	)
	(gr_poly
		(pts
			(xy 81.820258 -227.27666) (xy 81.856834 -227.140008) (xy 81.720436 -227.103432) (xy 81.681828 -227.125784)
			(xy 81.781904 -227.299012)
		)
		(stroke
			(width 0)
			(type solid)
		)
		(fill yes)
		(layer "In2.Cu")
		(net "M_C_CPU1_SA_DQ<4>")
	)
	(gr_poly
		(pts
			(xy 81.820258 -225.655886) (xy 81.856834 -225.519488) (xy 81.720182 -225.482912) (xy 81.679034 -225.506534)
			(xy 81.778856 -225.679762)
		)
		(stroke
			(width 0)
			(type solid)
		)
		(fill yes)
		(layer "In2.Cu")
		(net "M_C_CPU1_SA_DQS_DN<5>")
	)
	(gr_poly
		(pts
			(xy 81.820258 -224.035874) (xy 81.856834 -223.899476) (xy 81.720182 -223.8629) (xy 81.679034 -223.886522)
			(xy 81.778856 -224.05975)
		)
		(stroke
			(width 0)
			(type solid)
		)
		(fill yes)
		(layer "In2.Cu")
		(net "M_C_CPU1_SA_DQS_DP<0>")
	)
	(gr_poly
		(pts
			(xy 82.093816 -291.704268) (xy 82.093816 -291.65677) (xy 81.893918 -291.65677) (xy 81.893918 -291.704268)
			(xy 81.99374 -291.804344)
		)
		(stroke
			(width 0)
			(type solid)
		)
		(fill yes)
		(layer "In2.Cu")
		(net "M_C_CPU1_SB_DQS_DP<8>")
	)
	(gr_poly
		(pts
			(xy 82.094832 -267.801852) (xy 81.994756 -267.701776) (xy 81.894934 -267.801852) (xy 81.894934 -267.846302)
			(xy 82.094832 -267.846302)
		)
		(stroke
			(width 0)
			(type solid)
		)
		(fill yes)
		(layer "In2.Cu")
		(net "M_C_CPU1_SB_RSP<0>")
	)
	(gr_poly
		(pts
			(xy 82.101182 -292.108128) (xy 82.001106 -292.008052) (xy 81.90103 -292.108128) (xy 81.90103 -292.152578)
			(xy 82.101182 -292.152578)
		)
		(stroke
			(width 0)
			(type solid)
		)
		(fill yes)
		(layer "In2.Cu")
		(net "M_C_CPU1_SB_DQ<28>")
	)
	(gr_poly
		(pts
			(xy 82.101182 -290.487862) (xy 82.001106 -290.38804) (xy 81.90103 -290.487862) (xy 81.90103 -290.535614)
			(xy 82.101182 -290.535614)
		)
		(stroke
			(width 0)
			(type solid)
		)
		(fill yes)
		(layer "In2.Cu")
		(net "M_C_CPU1_SB_DQS_DP<3>")
	)
	(gr_poly
		(pts
			(xy 82.101182 -290.084256) (xy 82.101182 -290.039806) (xy 81.90103 -290.039806) (xy 81.90103 -290.084256)
			(xy 82.001106 -290.184332)
		)
		(stroke
			(width 0)
			(type solid)
		)
		(fill yes)
		(layer "In2.Cu")
		(net "M_C_CPU1_SB_DQ<27>")
	)
	(gr_poly
		(pts
			(xy 82.101182 -288.868104) (xy 82.001106 -288.768028) (xy 81.90103 -288.868104) (xy 81.90103 -288.912554)
			(xy 82.101182 -288.912554)
		)
		(stroke
			(width 0)
			(type solid)
		)
		(fill yes)
		(layer "In2.Cu")
		(net "M_C_CPU1_SB_DQ<24>")
	)
	(gr_poly
		(pts
			(xy 82.101182 -288.464498) (xy 82.101182 -288.420048) (xy 81.90103 -288.420048) (xy 81.90103 -288.464498)
			(xy 82.001106 -288.564574)
		)
		(stroke
			(width 0)
			(type solid)
		)
		(fill yes)
		(layer "In2.Cu")
		(net "M_C_CPU1_SB_DQ<23>")
	)
	(gr_poly
		(pts
			(xy 82.101182 -287.248092) (xy 82.001106 -287.148016) (xy 81.90103 -287.248092) (xy 81.90103 -287.292542)
			(xy 82.101182 -287.292542)
		)
		(stroke
			(width 0)
			(type solid)
		)
		(fill yes)
		(layer "In2.Cu")
		(net "M_C_CPU1_SB_DQ<20>")
	)
	(gr_poly
		(pts
			(xy 82.101182 -286.844486) (xy 82.101182 -286.796734) (xy 81.90103 -286.796734) (xy 81.90103 -286.844486)
			(xy 82.001106 -286.944562)
		)
		(stroke
			(width 0)
			(type solid)
		)
		(fill yes)
		(layer "In2.Cu")
		(net "M_C_CPU1_SB_DQS_DP<7>")
	)
	(gr_poly
		(pts
			(xy 82.101182 -285.62808) (xy 82.001106 -285.528258) (xy 81.90103 -285.62808) (xy 81.90103 -285.675832)
			(xy 82.101182 -285.675832)
		)
		(stroke
			(width 0)
			(type solid)
		)
		(fill yes)
		(layer "In2.Cu")
		(net "M_C_CPU1_SB_DQS_DP<2>")
	)
	(gr_poly
		(pts
			(xy 82.101182 -285.224474) (xy 82.101182 -285.180024) (xy 81.90103 -285.180024) (xy 81.90103 -285.224474)
			(xy 82.001106 -285.32455)
		)
		(stroke
			(width 0)
			(type solid)
		)
		(fill yes)
		(layer "In2.Cu")
		(net "M_C_CPU1_SB_DQ<19>")
	)
	(gr_poly
		(pts
			(xy 82.101182 -284.008322) (xy 82.001106 -283.908246) (xy 81.90103 -284.008322) (xy 81.90103 -284.052772)
			(xy 82.101182 -284.052772)
		)
		(stroke
			(width 0)
			(type solid)
		)
		(fill yes)
		(layer "In2.Cu")
		(net "M_C_CPU1_SB_DQ<16>")
	)
	(gr_poly
		(pts
			(xy 82.101182 -283.604462) (xy 82.101182 -283.560012) (xy 81.90103 -283.560012) (xy 81.90103 -283.604462)
			(xy 82.001106 -283.704538)
		)
		(stroke
			(width 0)
			(type solid)
		)
		(fill yes)
		(layer "In2.Cu")
		(net "M_C_CPU1_SB_DQ<15>")
	)
	(gr_poly
		(pts
			(xy 82.101182 -282.38831) (xy 82.001106 -282.288234) (xy 81.90103 -282.38831) (xy 81.90103 -282.43276)
			(xy 82.101182 -282.43276)
		)
		(stroke
			(width 0)
			(type solid)
		)
		(fill yes)
		(layer "In2.Cu")
		(net "M_C_CPU1_SB_DQ<12>")
	)
	(gr_poly
		(pts
			(xy 82.101182 -281.984704) (xy 82.101182 -281.936952) (xy 81.90103 -281.936952) (xy 81.90103 -281.984704)
			(xy 82.001106 -282.084526)
		)
		(stroke
			(width 0)
			(type solid)
		)
		(fill yes)
		(layer "In2.Cu")
		(net "M_C_CPU1_SB_DQS_DP<6>")
	)
	(gr_poly
		(pts
			(xy 82.101182 -280.768044) (xy 82.001106 -280.668222) (xy 81.90103 -280.768044) (xy 81.90103 -280.815796)
			(xy 82.101182 -280.815796)
		)
		(stroke
			(width 0)
			(type solid)
		)
		(fill yes)
		(layer "In2.Cu")
		(net "M_C_CPU1_SB_DQS_DP<1>")
	)
	(gr_poly
		(pts
			(xy 82.101182 -280.364438) (xy 82.101182 -280.319988) (xy 81.90103 -280.319988) (xy 81.90103 -280.364438)
			(xy 82.001106 -280.464514)
		)
		(stroke
			(width 0)
			(type solid)
		)
		(fill yes)
		(layer "In2.Cu")
		(net "M_C_CPU1_SB_DQ<11>")
	)
	(gr_poly
		(pts
			(xy 82.101182 -279.148286) (xy 82.001106 -279.04821) (xy 81.90103 -279.148286) (xy 81.90103 -279.192736)
			(xy 82.101182 -279.192736)
		)
		(stroke
			(width 0)
			(type solid)
		)
		(fill yes)
		(layer "In2.Cu")
		(net "M_C_CPU1_SB_DQ<8>")
	)
	(gr_poly
		(pts
			(xy 82.101182 -278.744426) (xy 82.101182 -278.699976) (xy 81.90103 -278.699976) (xy 81.90103 -278.744426)
			(xy 82.001106 -278.844502)
		)
		(stroke
			(width 0)
			(type solid)
		)
		(fill yes)
		(layer "In2.Cu")
		(net "M_C_CPU1_SB_DQ<7>")
	)
	(gr_poly
		(pts
			(xy 82.101182 -277.528274) (xy 82.001106 -277.428198) (xy 81.90103 -277.528274) (xy 81.90103 -277.572724)
			(xy 82.101182 -277.572724)
		)
		(stroke
			(width 0)
			(type solid)
		)
		(fill yes)
		(layer "In2.Cu")
		(net "M_C_CPU1_SB_DQ<4>")
	)
	(gr_poly
		(pts
			(xy 82.101182 -277.124668) (xy 82.101182 -277.076916) (xy 81.90103 -277.076916) (xy 81.90103 -277.124668)
			(xy 82.001106 -277.22449)
		)
		(stroke
			(width 0)
			(type solid)
		)
		(fill yes)
		(layer "In2.Cu")
		(net "M_C_CPU1_SB_DQS_DP<5>")
	)
	(gr_poly
		(pts
			(xy 82.101182 -275.908008) (xy 82.001106 -275.808186) (xy 81.90103 -275.908008) (xy 81.90103 -275.95576)
			(xy 82.101182 -275.95576)
		)
		(stroke
			(width 0)
			(type solid)
		)
		(fill yes)
		(layer "In2.Cu")
		(net "M_C_CPU1_SB_DQS_DP<0>")
	)
	(gr_poly
		(pts
			(xy 82.101182 -275.504402) (xy 82.101182 -275.459952) (xy 81.90103 -275.459952) (xy 81.90103 -275.504402)
			(xy 82.001106 -275.604478)
		)
		(stroke
			(width 0)
			(type solid)
		)
		(fill yes)
		(layer "In2.Cu")
		(net "M_C_CPU1_SB_DQ<3>")
	)
	(gr_poly
		(pts
			(xy 82.101182 -274.28825) (xy 82.001106 -274.188174) (xy 81.90103 -274.28825) (xy 81.90103 -274.3327)
			(xy 82.101182 -274.3327)
		)
		(stroke
			(width 0)
			(type solid)
		)
		(fill yes)
		(layer "In2.Cu")
		(net "M_C_CPU1_SB_DQ<0>")
	)
	(gr_poly
		(pts
			(xy 82.101182 -273.88439) (xy 82.101182 -273.83994) (xy 81.90103 -273.83994) (xy 81.90103 -273.88439)
			(xy 82.001106 -273.984466)
		)
		(stroke
			(width 0)
			(type solid)
		)
		(fill yes)
		(layer "In2.Cu")
		(net "M_C_CPU1_SB_CB<3>")
	)
	(gr_poly
		(pts
			(xy 82.101182 -272.668238) (xy 82.001106 -272.568162) (xy 81.90103 -272.668238) (xy 81.90103 -272.712688)
			(xy 82.101182 -272.712688)
		)
		(stroke
			(width 0)
			(type solid)
		)
		(fill yes)
		(layer "In2.Cu")
		(net "M_C_CPU1_SB_CB<0>")
	)
	(gr_poly
		(pts
			(xy 82.101182 -272.264632) (xy 82.101182 -272.21688) (xy 81.90103 -272.21688) (xy 81.90103 -272.264632)
			(xy 82.001106 -272.364454)
		)
		(stroke
			(width 0)
			(type solid)
		)
		(fill yes)
		(layer "In2.Cu")
		(net "M_C_CPU1_SB_DQS_DP<4>")
	)
	(gr_poly
		(pts
			(xy 82.101182 -271.047972) (xy 82.001106 -270.94815) (xy 81.90103 -271.047972) (xy 81.90103 -271.095724)
			(xy 82.101182 -271.095724)
		)
		(stroke
			(width 0)
			(type solid)
		)
		(fill yes)
		(layer "In2.Cu")
		(net "M_C_CPU1_SB_DQS_DP<9>")
	)
	(gr_poly
		(pts
			(xy 82.101182 -270.644366) (xy 82.101182 -270.599916) (xy 81.90103 -270.599916) (xy 81.90103 -270.644366)
			(xy 82.001106 -270.744442)
		)
		(stroke
			(width 0)
			(type solid)
		)
		(fill yes)
		(layer "In2.Cu")
		(net "M_C_CPU1_SB_CB<7>")
	)
	(gr_poly
		(pts
			(xy 82.101182 -269.428214) (xy 82.001106 -269.328138) (xy 81.90103 -269.428214) (xy 81.90103 -269.472664)
			(xy 82.101182 -269.472664)
		)
		(stroke
			(width 0)
			(type solid)
		)
		(fill yes)
		(layer "In2.Cu")
		(net "M_C_CPU1_SB_CB<4>")
	)
	(gr_poly
		(pts
			(xy 82.101182 -265.78433) (xy 82.101182 -265.73988) (xy 81.90103 -265.73988) (xy 81.90103 -265.78433)
			(xy 82.001106 -265.884406)
		)
		(stroke
			(width 0)
			(type solid)
		)
		(fill yes)
		(layer "In2.Cu")
		(net "M_C_CPU1_SB_CS_N<0>")
	)
	(gr_poly
		(pts
			(xy 82.101182 -264.568178) (xy 82.001106 -264.468102) (xy 81.90103 -264.568178) (xy 81.90103 -264.612628)
			(xy 82.101182 -264.612628)
		)
		(stroke
			(width 0)
			(type solid)
		)
		(fill yes)
		(layer "In2.Cu")
		(net "M_C_CPU1_SB_CA<6>")
	)
	(gr_poly
		(pts
			(xy 82.101182 -264.164318) (xy 82.101182 -264.119868) (xy 81.90103 -264.119868) (xy 81.90103 -264.164318)
			(xy 82.001106 -264.264394)
		)
		(stroke
			(width 0)
			(type solid)
		)
		(fill yes)
		(layer "In2.Cu")
		(net "M_C_CPU1_SB_CA<5>")
	)
	(gr_poly
		(pts
			(xy 82.101182 -262.948166) (xy 82.001106 -262.84809) (xy 81.90103 -262.948166) (xy 81.90103 -262.992616)
			(xy 82.101182 -262.992616)
		)
		(stroke
			(width 0)
			(type solid)
		)
		(fill yes)
		(layer "In2.Cu")
		(net "M_C_CPU1_SB_CA<2>")
	)
	(gr_poly
		(pts
			(xy 82.101182 -262.544306) (xy 82.101182 -262.499856) (xy 81.90103 -262.499856) (xy 81.90103 -262.544306)
			(xy 82.001106 -262.644382)
		)
		(stroke
			(width 0)
			(type solid)
		)
		(fill yes)
		(layer "In2.Cu")
		(net "M_C_CPU1_SB_CA<1>")
	)
	(gr_poly
		(pts
			(xy 82.157062 -293.860728) (xy 82.120232 -293.724076) (xy 82.081878 -293.701724) (xy 81.981802 -293.874952)
			(xy 82.02041 -293.897304)
		)
		(stroke
			(width 0)
			(type solid)
		)
		(fill yes)
		(layer "In2.Cu")
		(net "M_C_CPU1_SB_DQ<31>")
	)
	(gr_poly
		(pts
			(xy 82.191098 -228.634798) (xy 82.091022 -228.46157) (xy 82.052414 -228.483668) (xy 82.015838 -228.62032)
			(xy 82.15249 -228.656896)
		)
		(stroke
			(width 0)
			(type solid)
		)
		(fill yes)
		(layer "In2.Cu")
		(net "M_C_CPU1_SA_DQ<6>")
	)
	(gr_poly
		(pts
			(xy 82.191098 -223.774762) (xy 82.091022 -223.601534) (xy 82.052414 -223.623632) (xy 82.015838 -223.760284)
			(xy 82.15249 -223.79686)
		)
		(stroke
			(width 0)
			(type solid)
		)
		(fill yes)
		(layer "In2.Cu")
		(net "M_C_CPU1_SA_DQ<3>")
	)
	(gr_poly
		(pts
			(xy 82.194146 -227.01377) (xy 82.09407 -226.840542) (xy 82.052668 -226.864418) (xy 82.016092 -227.00107)
			(xy 82.152744 -227.037646)
		)
		(stroke
			(width 0)
			(type solid)
		)
		(fill yes)
		(layer "In2.Cu")
		(net "M_C_CPU1_SA_DQS_DP<5>")
	)
	(gr_poly
		(pts
			(xy 82.194146 -225.393758) (xy 82.09407 -225.22053) (xy 82.052668 -225.244406) (xy 82.016092 -225.381058)
			(xy 82.152744 -225.417634)
		)
		(stroke
			(width 0)
			(type solid)
		)
		(fill yes)
		(layer "In2.Cu")
		(net "M_C_CPU1_SA_DQS_DN<0>")
	)
	(gr_poly
		(pts
			(xy 82.271108 -256.026158) (xy 82.171032 -255.926336) (xy 82.070956 -256.026158) (xy 82.070956 -256.07391)
			(xy 82.271108 -256.07391)
		)
		(stroke
			(width 0)
			(type solid)
		)
		(fill yes)
		(layer "In2.Cu")
		(net "M_C_CPU1_CLK_DP<0>")
	)
	(gr_poly
		(pts
			(xy 82.271108 -255.622552) (xy 82.271108 -255.578102) (xy 82.070956 -255.578102) (xy 82.070956 -255.622552)
			(xy 82.171032 -255.722628)
		)
		(stroke
			(width 0)
			(type solid)
		)
		(fill yes)
		(layer "In2.Cu")
		(net "M_C_CPU1_SA_PAR")
	)
	(gr_poly
		(pts
			(xy 82.271108 -254.4064) (xy 82.171032 -254.306324) (xy 82.070956 -254.4064) (xy 82.070956 -254.45085)
			(xy 82.271108 -254.45085)
		)
		(stroke
			(width 0)
			(type solid)
		)
		(fill yes)
		(layer "In2.Cu")
		(net "M_C_CPU1_SA_CA<4>")
	)
	(gr_poly
		(pts
			(xy 82.271108 -254.00254) (xy 82.271108 -253.95809) (xy 82.070956 -253.95809) (xy 82.070956 -254.00254)
			(xy 82.171032 -254.102616)
		)
		(stroke
			(width 0)
			(type solid)
		)
		(fill yes)
		(layer "In2.Cu")
		(net "M_C_CPU1_SA_CA<3>")
	)
	(gr_poly
		(pts
			(xy 82.271108 -252.786388) (xy 82.171032 -252.686312) (xy 82.070956 -252.786388) (xy 82.070956 -252.830838)
			(xy 82.271108 -252.830838)
		)
		(stroke
			(width 0)
			(type solid)
		)
		(fill yes)
		(layer "In2.Cu")
		(net "M_C_CPU1_SA_CA<0>")
	)
	(gr_poly
		(pts
			(xy 82.271108 -252.382528) (xy 82.271108 -252.338078) (xy 82.070956 -252.338078) (xy 82.070956 -252.382528)
			(xy 82.171032 -252.482604)
		)
		(stroke
			(width 0)
			(type solid)
		)
		(fill yes)
		(layer "In2.Cu")
		(net "M_C_CPU1_SA_CS_N<1>")
	)
	(gr_poly
		(pts
			(xy 82.271108 -250.762516) (xy 82.271108 -250.718066) (xy 82.070956 -250.718066) (xy 82.070956 -250.762516)
			(xy 82.171032 -250.862592)
		)
		(stroke
			(width 0)
			(type solid)
		)
		(fill yes)
		(layer "In2.Cu")
		(net "M_C_CPU1_RESET_N")
	)
	(gr_poly
		(pts
			(xy 82.271108 -249.142504) (xy 82.271108 -249.098054) (xy 82.070956 -249.098054) (xy 82.070956 -249.142504)
			(xy 82.171032 -249.24258)
		)
		(stroke
			(width 0)
			(type solid)
		)
		(fill yes)
		(layer "In2.Cu")
		(net "M_C_CPU1_SA_CB<7>")
	)
	(gr_poly
		(pts
			(xy 82.271108 -247.926352) (xy 82.171032 -247.826276) (xy 82.070956 -247.926352) (xy 82.070956 -247.970802)
			(xy 82.271108 -247.970802)
		)
		(stroke
			(width 0)
			(type solid)
		)
		(fill yes)
		(layer "In2.Cu")
		(net "M_C_CPU1_SA_CB<4>")
	)
	(gr_poly
		(pts
			(xy 82.271108 -247.522746) (xy 82.271108 -247.474994) (xy 82.070956 -247.474994) (xy 82.070956 -247.522746)
			(xy 82.171032 -247.622568)
		)
		(stroke
			(width 0)
			(type solid)
		)
		(fill yes)
		(layer "In2.Cu")
		(net "M_C_CPU1_SA_DQS_DP<9>")
	)
	(gr_poly
		(pts
			(xy 82.271108 -246.306086) (xy 82.171032 -246.206264) (xy 82.070956 -246.306086) (xy 82.070956 -246.353838)
			(xy 82.271108 -246.353838)
		)
		(stroke
			(width 0)
			(type solid)
		)
		(fill yes)
		(layer "In2.Cu")
		(net "M_C_CPU1_SA_DQS_DP<4>")
	)
	(gr_poly
		(pts
			(xy 82.271108 -245.90248) (xy 82.271108 -245.85803) (xy 82.070956 -245.85803) (xy 82.070956 -245.90248)
			(xy 82.171032 -246.002556)
		)
		(stroke
			(width 0)
			(type solid)
		)
		(fill yes)
		(layer "In2.Cu")
		(net "M_C_CPU1_SA_CB<3>")
	)
	(gr_poly
		(pts
			(xy 82.271108 -244.686328) (xy 82.171032 -244.586252) (xy 82.070956 -244.686328) (xy 82.070956 -244.730778)
			(xy 82.271108 -244.730778)
		)
		(stroke
			(width 0)
			(type solid)
		)
		(fill yes)
		(layer "In2.Cu")
		(net "M_C_CPU1_SA_CB<0>")
	)
	(gr_poly
		(pts
			(xy 82.271108 -244.282468) (xy 82.271108 -244.238018) (xy 82.070956 -244.238018) (xy 82.070956 -244.282468)
			(xy 82.171032 -244.382544)
		)
		(stroke
			(width 0)
			(type solid)
		)
		(fill yes)
		(layer "In2.Cu")
		(net "M_C_CPU1_SA_DQ<31>")
	)
	(gr_poly
		(pts
			(xy 82.271108 -243.066316) (xy 82.171032 -242.96624) (xy 82.070956 -243.066316) (xy 82.070956 -243.110766)
			(xy 82.271108 -243.110766)
		)
		(stroke
			(width 0)
			(type solid)
		)
		(fill yes)
		(layer "In2.Cu")
		(net "M_C_CPU1_SA_DQ<28>")
	)
	(gr_poly
		(pts
			(xy 82.271108 -242.66271) (xy 82.271108 -242.614958) (xy 82.070956 -242.614958) (xy 82.070956 -242.66271)
			(xy 82.171032 -242.762532)
		)
		(stroke
			(width 0)
			(type solid)
		)
		(fill yes)
		(layer "In2.Cu")
		(net "M_C_CPU1_SA_DQS_DP<8>")
	)
	(gr_poly
		(pts
			(xy 82.271108 -241.44605) (xy 82.171032 -241.346228) (xy 82.070956 -241.44605) (xy 82.070956 -241.493802)
			(xy 82.271108 -241.493802)
		)
		(stroke
			(width 0)
			(type solid)
		)
		(fill yes)
		(layer "In2.Cu")
		(net "M_C_CPU1_SA_DQS_DP<3>")
	)
	(gr_poly
		(pts
			(xy 82.271108 -241.042444) (xy 82.271108 -240.997994) (xy 82.070956 -240.997994) (xy 82.070956 -241.042444)
			(xy 82.171032 -241.14252)
		)
		(stroke
			(width 0)
			(type solid)
		)
		(fill yes)
		(layer "In2.Cu")
		(net "M_C_CPU1_SA_DQ<27>")
	)
	(gr_poly
		(pts
			(xy 82.271108 -239.826292) (xy 82.171032 -239.726216) (xy 82.070956 -239.826292) (xy 82.070956 -239.870742)
			(xy 82.271108 -239.870742)
		)
		(stroke
			(width 0)
			(type solid)
		)
		(fill yes)
		(layer "In2.Cu")
		(net "M_C_CPU1_SA_DQ<24>")
	)
	(gr_poly
		(pts
			(xy 82.271108 -239.422432) (xy 82.271108 -239.377982) (xy 82.070956 -239.377982) (xy 82.070956 -239.422432)
			(xy 82.171032 -239.522508)
		)
		(stroke
			(width 0)
			(type solid)
		)
		(fill yes)
		(layer "In2.Cu")
		(net "M_C_CPU1_SA_DQ<23>")
	)
	(gr_poly
		(pts
			(xy 82.271108 -238.20628) (xy 82.171032 -238.106204) (xy 82.070956 -238.20628) (xy 82.070956 -238.25073)
			(xy 82.271108 -238.25073)
		)
		(stroke
			(width 0)
			(type solid)
		)
		(fill yes)
		(layer "In2.Cu")
		(net "M_C_CPU1_SA_DQ<20>")
	)
	(gr_poly
		(pts
			(xy 82.271108 -237.802674) (xy 82.271108 -237.754922) (xy 82.070956 -237.754922) (xy 82.070956 -237.802674)
			(xy 82.171032 -237.902496)
		)
		(stroke
			(width 0)
			(type solid)
		)
		(fill yes)
		(layer "In2.Cu")
		(net "M_C_CPU1_SA_DQS_DP<7>")
	)
	(gr_poly
		(pts
			(xy 82.271108 -236.586014) (xy 82.171032 -236.486192) (xy 82.070956 -236.586014) (xy 82.070956 -236.633766)
			(xy 82.271108 -236.633766)
		)
		(stroke
			(width 0)
			(type solid)
		)
		(fill yes)
		(layer "In2.Cu")
		(net "M_C_CPU1_SA_DQS_DP<2>")
	)
	(gr_poly
		(pts
			(xy 82.271108 -236.182408) (xy 82.271108 -236.137958) (xy 82.070956 -236.137958) (xy 82.070956 -236.182408)
			(xy 82.171032 -236.282484)
		)
		(stroke
			(width 0)
			(type solid)
		)
		(fill yes)
		(layer "In2.Cu")
		(net "M_C_CPU1_SA_DQ<19>")
	)
	(gr_poly
		(pts
			(xy 82.271108 -234.966256) (xy 82.171032 -234.86618) (xy 82.070956 -234.966256) (xy 82.070956 -235.010706)
			(xy 82.271108 -235.010706)
		)
		(stroke
			(width 0)
			(type solid)
		)
		(fill yes)
		(layer "In2.Cu")
		(net "M_C_CPU1_SA_DQ<16>")
	)
	(gr_poly
		(pts
			(xy 82.271108 -234.562396) (xy 82.271108 -234.517946) (xy 82.070956 -234.517946) (xy 82.070956 -234.562396)
			(xy 82.171032 -234.662472)
		)
		(stroke
			(width 0)
			(type solid)
		)
		(fill yes)
		(layer "In2.Cu")
		(net "M_C_CPU1_SA_DQ<15>")
	)
	(gr_poly
		(pts
			(xy 82.271108 -233.346244) (xy 82.171032 -233.246168) (xy 82.070956 -233.346244) (xy 82.070956 -233.390694)
			(xy 82.271108 -233.390694)
		)
		(stroke
			(width 0)
			(type solid)
		)
		(fill yes)
		(layer "In2.Cu")
		(net "M_C_CPU1_SA_DQ<12>")
	)
	(gr_poly
		(pts
			(xy 82.271108 -232.942638) (xy 82.271108 -232.894886) (xy 82.070956 -232.894886) (xy 82.070956 -232.942638)
			(xy 82.171032 -233.04246)
		)
		(stroke
			(width 0)
			(type solid)
		)
		(fill yes)
		(layer "In2.Cu")
		(net "M_C_CPU1_SA_DQS_DP<6>")
	)
	(gr_poly
		(pts
			(xy 82.271108 -231.725978) (xy 82.171032 -231.626156) (xy 82.070956 -231.725978) (xy 82.070956 -231.77373)
			(xy 82.271108 -231.77373)
		)
		(stroke
			(width 0)
			(type solid)
		)
		(fill yes)
		(layer "In2.Cu")
		(net "M_C_CPU1_SA_DQS_DP<1>")
	)
	(gr_poly
		(pts
			(xy 82.271108 -231.322626) (xy 82.271108 -231.278176) (xy 82.070956 -231.278176) (xy 82.070956 -231.322626)
			(xy 82.171032 -231.422702)
		)
		(stroke
			(width 0)
			(type solid)
		)
		(fill yes)
		(layer "In2.Cu")
		(net "M_C_CPU1_SA_DQ<11>")
	)
	(gr_poly
		(pts
			(xy 82.271108 -230.10622) (xy 82.171032 -230.006144) (xy 82.070956 -230.10622) (xy 82.070956 -230.15067)
			(xy 82.271108 -230.15067)
		)
		(stroke
			(width 0)
			(type solid)
		)
		(fill yes)
		(layer "In2.Cu")
		(net "M_C_CPU1_SA_DQ<8>")
	)
	(gr_poly
		(pts
			(xy 82.271108 -229.702614) (xy 82.271108 -229.658164) (xy 82.070956 -229.658164) (xy 82.070956 -229.702614)
			(xy 82.171032 -229.80269)
		)
		(stroke
			(width 0)
			(type solid)
		)
		(fill yes)
		(layer "In2.Cu")
		(net "M_C_CPU1_SA_DQ<7>")
	)
	(gr_poly
		(pts
			(xy 82.289396 -226.464622) (xy 82.325972 -226.32797) (xy 82.18932 -226.291394) (xy 82.147918 -226.31527)
			(xy 82.247994 -226.488498)
		)
		(stroke
			(width 0)
			(type solid)
		)
		(fill yes)
		(layer "In2.Cu")
		(net "M_C_CPU1_SA_DQS_DN<5>")
	)
	(gr_poly
		(pts
			(xy 82.289396 -224.84461) (xy 82.325972 -224.707958) (xy 82.18932 -224.671382) (xy 82.147918 -224.695258)
			(xy 82.247994 -224.868486)
		)
		(stroke
			(width 0)
			(type solid)
		)
		(fill yes)
		(layer "In2.Cu")
		(net "M_C_CPU1_SA_DQS_DP<0>")
	)
	(gr_poly
		(pts
			(xy 82.28965 -228.085396) (xy 82.326226 -227.948744) (xy 82.189574 -227.912168) (xy 82.150966 -227.934266)
			(xy 82.251042 -228.107494)
		)
		(stroke
			(width 0)
			(type solid)
		)
		(fill yes)
		(layer "In2.Cu")
		(net "M_C_CPU1_SA_DQ<4>")
	)
	(gr_poly
		(pts
			(xy 82.28965 -223.22536) (xy 82.326226 -223.088708) (xy 82.189574 -223.052132) (xy 82.150966 -223.07423)
			(xy 82.251042 -223.247458)
		)
		(stroke
			(width 0)
			(type solid)
		)
		(fill yes)
		(layer "In2.Cu")
		(net "M_C_CPU1_SA_DQ<1>")
	)
	(gr_poly
		(pts
			(xy 82.571082 -292.918134) (xy 82.471006 -292.818058) (xy 82.37093 -292.918134) (xy 82.37093 -292.962584)
			(xy 82.571082 -292.962584)
		)
		(stroke
			(width 0)
			(type solid)
		)
		(fill yes)
		(layer "In2.Cu")
		(net "M_C_CPU1_SB_DQ<29>")
	)
	(gr_poly
		(pts
			(xy 82.571082 -292.514274) (xy 82.571082 -292.469824) (xy 82.37093 -292.469824) (xy 82.37093 -292.514274)
			(xy 82.471006 -292.61435)
		)
		(stroke
			(width 0)
			(type solid)
		)
		(fill yes)
		(layer "In2.Cu")
		(net "M_C_CPU1_SB_DQ<30>")
	)
	(gr_poly
		(pts
			(xy 82.571082 -291.297868) (xy 82.471006 -291.198046) (xy 82.37093 -291.297868) (xy 82.37093 -291.34562)
			(xy 82.571082 -291.34562)
		)
		(stroke
			(width 0)
			(type solid)
		)
		(fill yes)
		(layer "In2.Cu")
		(net "M_C_CPU1_SB_DQS_DN<8>")
	)
	(gr_poly
		(pts
			(xy 82.571082 -290.894516) (xy 82.571082 -290.846764) (xy 82.37093 -290.846764) (xy 82.37093 -290.894516)
			(xy 82.471006 -290.994338)
		)
		(stroke
			(width 0)
			(type solid)
		)
		(fill yes)
		(layer "In2.Cu")
		(net "M_C_CPU1_SB_DQS_DN<3>")
	)
	(gr_poly
		(pts
			(xy 82.571082 -289.67811) (xy 82.471006 -289.578034) (xy 82.37093 -289.67811) (xy 82.37093 -289.72256)
			(xy 82.571082 -289.72256)
		)
		(stroke
			(width 0)
			(type solid)
		)
		(fill yes)
		(layer "In2.Cu")
		(net "M_C_CPU1_SB_DQ<25>")
	)
	(gr_poly
		(pts
			(xy 82.571082 -289.27425) (xy 82.571082 -289.2298) (xy 82.37093 -289.2298) (xy 82.37093 -289.27425)
			(xy 82.471006 -289.374326)
		)
		(stroke
			(width 0)
			(type solid)
		)
		(fill yes)
		(layer "In2.Cu")
		(net "M_C_CPU1_SB_DQ<26>")
	)
	(gr_poly
		(pts
			(xy 82.571082 -288.058098) (xy 82.471006 -287.958022) (xy 82.37093 -288.058098) (xy 82.37093 -288.102548)
			(xy 82.571082 -288.102548)
		)
		(stroke
			(width 0)
			(type solid)
		)
		(fill yes)
		(layer "In2.Cu")
		(net "M_C_CPU1_SB_DQ<21>")
	)
	(gr_poly
		(pts
			(xy 82.571082 -287.654492) (xy 82.571082 -287.610042) (xy 82.37093 -287.610042) (xy 82.37093 -287.654492)
			(xy 82.471006 -287.754568)
		)
		(stroke
			(width 0)
			(type solid)
		)
		(fill yes)
		(layer "In2.Cu")
		(net "M_C_CPU1_SB_DQ<22>")
	)
	(gr_poly
		(pts
			(xy 82.571082 -286.438086) (xy 82.471006 -286.33801) (xy 82.37093 -286.438086) (xy 82.37093 -286.485838)
			(xy 82.571082 -286.485838)
		)
		(stroke
			(width 0)
			(type solid)
		)
		(fill yes)
		(layer "In2.Cu")
		(net "M_C_CPU1_SB_DQS_DN<7>")
	)
	(gr_poly
		(pts
			(xy 82.571082 -286.034734) (xy 82.571082 -285.986982) (xy 82.37093 -285.986982) (xy 82.37093 -286.034734)
			(xy 82.471006 -286.134556)
		)
		(stroke
			(width 0)
			(type solid)
		)
		(fill yes)
		(layer "In2.Cu")
		(net "M_C_CPU1_SB_DQS_DN<2>")
	)
	(gr_poly
		(pts
			(xy 82.571082 -284.818328) (xy 82.471006 -284.718252) (xy 82.37093 -284.818328) (xy 82.37093 -284.862778)
			(xy 82.571082 -284.862778)
		)
		(stroke
			(width 0)
			(type solid)
		)
		(fill yes)
		(layer "In2.Cu")
		(net "M_C_CPU1_SB_DQ<17>")
	)
	(gr_poly
		(pts
			(xy 82.571082 -284.414468) (xy 82.571082 -284.370018) (xy 82.37093 -284.370018) (xy 82.37093 -284.414468)
			(xy 82.471006 -284.514544)
		)
		(stroke
			(width 0)
			(type solid)
		)
		(fill yes)
		(layer "In2.Cu")
		(net "M_C_CPU1_SB_DQ<18>")
	)
	(gr_poly
		(pts
			(xy 82.571082 -283.198316) (xy 82.471006 -283.09824) (xy 82.37093 -283.198316) (xy 82.37093 -283.242766)
			(xy 82.571082 -283.242766)
		)
		(stroke
			(width 0)
			(type solid)
		)
		(fill yes)
		(layer "In2.Cu")
		(net "M_C_CPU1_SB_DQ<13>")
	)
	(gr_poly
		(pts
			(xy 82.571082 -282.794456) (xy 82.571082 -282.750006) (xy 82.37093 -282.750006) (xy 82.37093 -282.794456)
			(xy 82.471006 -282.894532)
		)
		(stroke
			(width 0)
			(type solid)
		)
		(fill yes)
		(layer "In2.Cu")
		(net "M_C_CPU1_SB_DQ<14>")
	)
	(gr_poly
		(pts
			(xy 82.571082 -281.57805) (xy 82.471006 -281.478228) (xy 82.37093 -281.57805) (xy 82.37093 -281.625802)
			(xy 82.571082 -281.625802)
		)
		(stroke
			(width 0)
			(type solid)
		)
		(fill yes)
		(layer "In2.Cu")
		(net "M_C_CPU1_SB_DQS_DN<6>")
	)
	(gr_poly
		(pts
			(xy 82.571082 -281.174698) (xy 82.571082 -281.126946) (xy 82.37093 -281.126946) (xy 82.37093 -281.174698)
			(xy 82.471006 -281.27452)
		)
		(stroke
			(width 0)
			(type solid)
		)
		(fill yes)
		(layer "In2.Cu")
		(net "M_C_CPU1_SB_DQS_DN<1>")
	)
	(gr_poly
		(pts
			(xy 82.571082 -279.958292) (xy 82.471006 -279.858216) (xy 82.37093 -279.958292) (xy 82.37093 -280.002742)
			(xy 82.571082 -280.002742)
		)
		(stroke
			(width 0)
			(type solid)
		)
		(fill yes)
		(layer "In2.Cu")
		(net "M_C_CPU1_SB_DQ<9>")
	)
	(gr_poly
		(pts
			(xy 82.571082 -279.554432) (xy 82.571082 -279.509982) (xy 82.37093 -279.509982) (xy 82.37093 -279.554432)
			(xy 82.471006 -279.654508)
		)
		(stroke
			(width 0)
			(type solid)
		)
		(fill yes)
		(layer "In2.Cu")
		(net "M_C_CPU1_SB_DQ<10>")
	)
	(gr_poly
		(pts
			(xy 82.571082 -278.33828) (xy 82.471006 -278.238204) (xy 82.37093 -278.33828) (xy 82.37093 -278.38273)
			(xy 82.571082 -278.38273)
		)
		(stroke
			(width 0)
			(type solid)
		)
		(fill yes)
		(layer "In2.Cu")
		(net "M_C_CPU1_SB_DQ<5>")
	)
	(gr_poly
		(pts
			(xy 82.571082 -277.93442) (xy 82.571082 -277.88997) (xy 82.37093 -277.88997) (xy 82.37093 -277.93442)
			(xy 82.471006 -278.034496)
		)
		(stroke
			(width 0)
			(type solid)
		)
		(fill yes)
		(layer "In2.Cu")
		(net "M_C_CPU1_SB_DQ<6>")
	)
	(gr_poly
		(pts
			(xy 82.571082 -276.718014) (xy 82.471006 -276.618192) (xy 82.37093 -276.718014) (xy 82.37093 -276.765766)
			(xy 82.571082 -276.765766)
		)
		(stroke
			(width 0)
			(type solid)
		)
		(fill yes)
		(layer "In2.Cu")
		(net "M_C_CPU1_SB_DQS_DN<5>")
	)
	(gr_poly
		(pts
			(xy 82.571082 -276.314662) (xy 82.571082 -276.26691) (xy 82.37093 -276.26691) (xy 82.37093 -276.314662)
			(xy 82.471006 -276.414484)
		)
		(stroke
			(width 0)
			(type solid)
		)
		(fill yes)
		(layer "In2.Cu")
		(net "M_C_CPU1_SB_DQS_DN<0>")
	)
	(gr_poly
		(pts
			(xy 82.571082 -275.098256) (xy 82.471006 -274.99818) (xy 82.37093 -275.098256) (xy 82.37093 -275.142706)
			(xy 82.571082 -275.142706)
		)
		(stroke
			(width 0)
			(type solid)
		)
		(fill yes)
		(layer "In2.Cu")
		(net "M_C_CPU1_SB_DQ<1>")
	)
	(gr_poly
		(pts
			(xy 82.571082 -274.694396) (xy 82.571082 -274.649946) (xy 82.37093 -274.649946) (xy 82.37093 -274.694396)
			(xy 82.471006 -274.794472)
		)
		(stroke
			(width 0)
			(type solid)
		)
		(fill yes)
		(layer "In2.Cu")
		(net "M_C_CPU1_SB_DQ<2>")
	)
	(gr_poly
		(pts
			(xy 82.571082 -273.478244) (xy 82.471006 -273.378168) (xy 82.37093 -273.478244) (xy 82.37093 -273.522694)
			(xy 82.571082 -273.522694)
		)
		(stroke
			(width 0)
			(type solid)
		)
		(fill yes)
		(layer "In2.Cu")
		(net "M_C_CPU1_SB_CB<1>")
	)
	(gr_poly
		(pts
			(xy 82.571082 -273.074384) (xy 82.571082 -273.029934) (xy 82.37093 -273.029934) (xy 82.37093 -273.074384)
			(xy 82.471006 -273.17446)
		)
		(stroke
			(width 0)
			(type solid)
		)
		(fill yes)
		(layer "In2.Cu")
		(net "M_C_CPU1_SB_CB<2>")
	)
	(gr_poly
		(pts
			(xy 82.571082 -271.857978) (xy 82.471006 -271.758156) (xy 82.37093 -271.857978) (xy 82.37093 -271.90573)
			(xy 82.571082 -271.90573)
		)
		(stroke
			(width 0)
			(type solid)
		)
		(fill yes)
		(layer "In2.Cu")
		(net "M_C_CPU1_SB_DQS_DN<4>")
	)
	(gr_poly
		(pts
			(xy 82.571082 -271.454626) (xy 82.571082 -271.406874) (xy 82.37093 -271.406874) (xy 82.37093 -271.454626)
			(xy 82.471006 -271.554448)
		)
		(stroke
			(width 0)
			(type solid)
		)
		(fill yes)
		(layer "In2.Cu")
		(net "M_C_CPU1_SB_DQS_DN<9>")
	)
	(gr_poly
		(pts
			(xy 82.571082 -270.23822) (xy 82.471006 -270.138144) (xy 82.37093 -270.23822) (xy 82.37093 -270.28267)
			(xy 82.571082 -270.28267)
		)
		(stroke
			(width 0)
			(type solid)
		)
		(fill yes)
		(layer "In2.Cu")
		(net "M_C_CPU1_SB_CB<5>")
	)
	(gr_poly
		(pts
			(xy 82.571082 -269.83436) (xy 82.571082 -269.78991) (xy 82.37093 -269.78991) (xy 82.37093 -269.83436)
			(xy 82.471006 -269.934436)
		)
		(stroke
			(width 0)
			(type solid)
		)
		(fill yes)
		(layer "In2.Cu")
		(net "M_C_CPU1_SB_CB<6>")
	)
	(gr_poly
		(pts
			(xy 82.571082 -266.991846) (xy 82.471006 -266.89177) (xy 82.37093 -266.991846) (xy 82.37093 -267.036296)
			(xy 82.571082 -267.036296)
		)
		(stroke
			(width 0)
			(type solid)
		)
		(fill yes)
		(layer "In2.Cu")
		(net "M_C_CPU1_SA_RSP<0>")
	)
	(gr_poly
		(pts
			(xy 82.571082 -266.594336) (xy 82.571082 -266.549886) (xy 82.37093 -266.549886) (xy 82.37093 -266.594336)
			(xy 82.471006 -266.694412)
		)
		(stroke
			(width 0)
			(type solid)
		)
		(fill yes)
		(layer "In2.Cu")
		(net "M_C_CPU1_SB_CS_N<1>")
	)
	(gr_poly
		(pts
			(xy 82.571082 -264.974324) (xy 82.571082 -264.929874) (xy 82.37093 -264.929874) (xy 82.37093 -264.974324)
			(xy 82.471006 -265.0744)
		)
		(stroke
			(width 0)
			(type solid)
		)
		(fill yes)
		(layer "In2.Cu")
		(net "M_C_CPU1_SB_PAR")
	)
	(gr_poly
		(pts
			(xy 82.571082 -263.758172) (xy 82.471006 -263.658096) (xy 82.37093 -263.758172) (xy 82.37093 -263.802622)
			(xy 82.571082 -263.802622)
		)
		(stroke
			(width 0)
			(type solid)
		)
		(fill yes)
		(layer "In2.Cu")
		(net "M_C_CPU1_SB_CA<4>")
	)
	(gr_poly
		(pts
			(xy 82.571082 -263.354312) (xy 82.571082 -263.309862) (xy 82.37093 -263.309862) (xy 82.37093 -263.354312)
			(xy 82.471006 -263.454388)
		)
		(stroke
			(width 0)
			(type solid)
		)
		(fill yes)
		(layer "In2.Cu")
		(net "M_C_CPU1_SB_CA<3>")
	)
	(gr_poly
		(pts
			(xy 82.571082 -262.13816) (xy 82.471006 -262.038084) (xy 82.37093 -262.13816) (xy 82.37093 -262.18261)
			(xy 82.571082 -262.18261)
		)
		(stroke
			(width 0)
			(type solid)
		)
		(fill yes)
		(layer "In2.Cu")
		(net "M_C_CPU1_SB_CA<0>")
	)
	(gr_poly
		(pts
			(xy 82.660236 -224.583244) (xy 82.56016 -224.410016) (xy 82.521806 -224.432368) (xy 82.48523 -224.56902)
			(xy 82.621628 -224.605596)
		)
		(stroke
			(width 0)
			(type solid)
		)
		(fill yes)
		(layer "In2.Cu")
		(net "M_C_CPU1_SA_DQ<3>")
	)
	(gr_poly
		(pts
			(xy 82.660236 -222.963232) (xy 82.56016 -222.790004) (xy 82.521806 -222.812356) (xy 82.48523 -222.949008)
			(xy 82.621628 -222.985584)
		)
		(stroke
			(width 0)
			(type solid)
		)
		(fill yes)
		(layer "In2.Cu")
		(net "M_C_CPU1_SA_DQ<2>")
	)
	(gr_poly
		(pts
			(xy 82.66303 -227.822506) (xy 82.563208 -227.649278) (xy 82.521806 -227.673154) (xy 82.48523 -227.809552)
			(xy 82.621882 -227.846128)
		)
		(stroke
			(width 0)
			(type solid)
		)
		(fill yes)
		(layer "In2.Cu")
		(net "M_C_CPU1_SA_DQS_DP<5>")
	)
	(gr_poly
		(pts
			(xy 82.66303 -226.202494) (xy 82.563208 -226.029266) (xy 82.521806 -226.053142) (xy 82.48523 -226.18954)
			(xy 82.621882 -226.22637)
		)
		(stroke
			(width 0)
			(type solid)
		)
		(fill yes)
		(layer "In2.Cu")
		(net "M_C_CPU1_SA_DQS_DN<0>")
	)
	(gr_poly
		(pts
			(xy 82.740754 -246.712486) (xy 82.740754 -246.664988) (xy 82.540856 -246.664988) (xy 82.540856 -246.712486)
			(xy 82.640678 -246.812562)
		)
		(stroke
			(width 0)
			(type solid)
		)
		(fill yes)
		(layer "In2.Cu")
		(net "M_C_CPU1_SA_DQS_DN<4>")
	)
	(gr_poly
		(pts
			(xy 82.741008 -256.432812) (xy 82.741008 -256.38506) (xy 82.540856 -256.38506) (xy 82.540856 -256.432812)
			(xy 82.640932 -256.532634)
		)
		(stroke
			(width 0)
			(type solid)
		)
		(fill yes)
		(layer "In2.Cu")
		(net "M_C_CPU1_CLK_DN<0>")
	)
	(gr_poly
		(pts
			(xy 82.741008 -255.216406) (xy 82.640932 -255.11633) (xy 82.540856 -255.216406) (xy 82.540856 -255.260856)
			(xy 82.741008 -255.260856)
		)
		(stroke
			(width 0)
			(type solid)
		)
		(fill yes)
		(layer "In2.Cu")
		(net "M_C_CPU1_SA_CA<6>")
	)
	(gr_poly
		(pts
			(xy 82.741008 -254.812546) (xy 82.741008 -254.768096) (xy 82.540856 -254.768096) (xy 82.540856 -254.812546)
			(xy 82.640932 -254.912622)
		)
		(stroke
			(width 0)
			(type solid)
		)
		(fill yes)
		(layer "In2.Cu")
		(net "M_C_CPU1_SA_CA<5>")
	)
	(gr_poly
		(pts
			(xy 82.741008 -253.596394) (xy 82.640932 -253.496318) (xy 82.540856 -253.596394) (xy 82.540856 -253.640844)
			(xy 82.741008 -253.640844)
		)
		(stroke
			(width 0)
			(type solid)
		)
		(fill yes)
		(layer "In2.Cu")
		(net "M_C_CPU1_SA_CA<2>")
	)
	(gr_poly
		(pts
			(xy 82.741008 -253.192534) (xy 82.741008 -253.148084) (xy 82.540856 -253.148084) (xy 82.540856 -253.192534)
			(xy 82.640932 -253.29261)
		)
		(stroke
			(width 0)
			(type solid)
		)
		(fill yes)
		(layer "In2.Cu")
		(net "M_C_CPU1_SA_CA<1>")
	)
	(gr_poly
		(pts
			(xy 82.741008 -251.572522) (xy 82.741008 -251.528072) (xy 82.540856 -251.528072) (xy 82.540856 -251.572522)
			(xy 82.640932 -251.672598)
		)
		(stroke
			(width 0)
			(type solid)
		)
		(fill yes)
		(layer "In2.Cu")
		(net "M_C_CPU1_SA_CS_N<0>")
	)
	(gr_poly
		(pts
			(xy 82.741008 -250.35637) (xy 82.640932 -250.256294) (xy 82.540856 -250.35637) (xy 82.540856 -250.40082)
			(xy 82.741008 -250.40082)
		)
		(stroke
			(width 0)
			(type solid)
		)
		(fill yes)
		(layer "In2.Cu")
		(net "M_C_CPU1_ALERT_R_N")
	)
	(gr_poly
		(pts
			(xy 82.741008 -248.736358) (xy 82.640932 -248.636282) (xy 82.540856 -248.736358) (xy 82.540856 -248.780808)
			(xy 82.741008 -248.780808)
		)
		(stroke
			(width 0)
			(type solid)
		)
		(fill yes)
		(layer "In2.Cu")
		(net "M_C_CPU1_SA_CB<5>")
	)
	(gr_poly
		(pts
			(xy 82.741008 -248.332498) (xy 82.741008 -248.288048) (xy 82.540856 -248.288048) (xy 82.540856 -248.332498)
			(xy 82.640932 -248.432574)
		)
		(stroke
			(width 0)
			(type solid)
		)
		(fill yes)
		(layer "In2.Cu")
		(net "M_C_CPU1_SA_CB<6>")
	)
	(gr_poly
		(pts
			(xy 82.741008 -247.116092) (xy 82.640932 -247.01627) (xy 82.540856 -247.116092) (xy 82.540856 -247.163844)
			(xy 82.741008 -247.163844)
		)
		(stroke
			(width 0)
			(type solid)
		)
		(fill yes)
		(layer "In2.Cu")
		(net "M_C_CPU1_SA_DQS_DN<9>")
	)
	(gr_poly
		(pts
			(xy 82.741008 -245.496334) (xy 82.640932 -245.396258) (xy 82.540856 -245.496334) (xy 82.540856 -245.540784)
			(xy 82.741008 -245.540784)
		)
		(stroke
			(width 0)
			(type solid)
		)
		(fill yes)
		(layer "In2.Cu")
		(net "M_C_CPU1_SA_CB<1>")
	)
	(gr_poly
		(pts
			(xy 82.741008 -245.092474) (xy 82.741008 -245.048024) (xy 82.540856 -245.048024) (xy 82.540856 -245.092474)
			(xy 82.640932 -245.19255)
		)
		(stroke
			(width 0)
			(type solid)
		)
		(fill yes)
		(layer "In2.Cu")
		(net "M_C_CPU1_SA_CB<2>")
	)
	(gr_poly
		(pts
			(xy 82.741008 -243.876322) (xy 82.640932 -243.776246) (xy 82.540856 -243.876322) (xy 82.540856 -243.920772)
			(xy 82.741008 -243.920772)
		)
		(stroke
			(width 0)
			(type solid)
		)
		(fill yes)
		(layer "In2.Cu")
		(net "M_C_CPU1_SA_DQ<29>")
	)
	(gr_poly
		(pts
			(xy 82.741008 -243.472462) (xy 82.741008 -243.428012) (xy 82.540856 -243.428012) (xy 82.540856 -243.472462)
			(xy 82.640932 -243.572538)
		)
		(stroke
			(width 0)
			(type solid)
		)
		(fill yes)
		(layer "In2.Cu")
		(net "M_C_CPU1_SA_DQ<30>")
	)
	(gr_poly
		(pts
			(xy 82.741008 -242.256056) (xy 82.640932 -242.156234) (xy 82.540856 -242.256056) (xy 82.540856 -242.303808)
			(xy 82.741008 -242.303808)
		)
		(stroke
			(width 0)
			(type solid)
		)
		(fill yes)
		(layer "In2.Cu")
		(net "M_C_CPU1_SA_DQS_DN<8>")
	)
	(gr_poly
		(pts
			(xy 82.741008 -241.852704) (xy 82.741008 -241.804952) (xy 82.540856 -241.804952) (xy 82.540856 -241.852704)
			(xy 82.640932 -241.952526)
		)
		(stroke
			(width 0)
			(type solid)
		)
		(fill yes)
		(layer "In2.Cu")
		(net "M_C_CPU1_SA_DQS_DN<3>")
	)
	(gr_poly
		(pts
			(xy 82.741008 -240.636298) (xy 82.640932 -240.536222) (xy 82.540856 -240.636298) (xy 82.540856 -240.680748)
			(xy 82.741008 -240.680748)
		)
		(stroke
			(width 0)
			(type solid)
		)
		(fill yes)
		(layer "In2.Cu")
		(net "M_C_CPU1_SA_DQ<25>")
	)
	(gr_poly
		(pts
			(xy 82.741008 -240.232438) (xy 82.741008 -240.187988) (xy 82.540856 -240.187988) (xy 82.540856 -240.232438)
			(xy 82.640932 -240.332514)
		)
		(stroke
			(width 0)
			(type solid)
		)
		(fill yes)
		(layer "In2.Cu")
		(net "M_C_CPU1_SA_DQ<26>")
	)
	(gr_poly
		(pts
			(xy 82.741008 -239.016286) (xy 82.640932 -238.91621) (xy 82.540856 -239.016286) (xy 82.540856 -239.060736)
			(xy 82.741008 -239.060736)
		)
		(stroke
			(width 0)
			(type solid)
		)
		(fill yes)
		(layer "In2.Cu")
		(net "M_C_CPU1_SA_DQ<21>")
	)
	(gr_poly
		(pts
			(xy 82.741008 -238.612426) (xy 82.741008 -238.567976) (xy 82.540856 -238.567976) (xy 82.540856 -238.612426)
			(xy 82.640932 -238.712502)
		)
		(stroke
			(width 0)
			(type solid)
		)
		(fill yes)
		(layer "In2.Cu")
		(net "M_C_CPU1_SA_DQ<22>")
	)
	(gr_poly
		(pts
			(xy 82.741008 -237.39602) (xy 82.640932 -237.296198) (xy 82.540856 -237.39602) (xy 82.540856 -237.443772)
			(xy 82.741008 -237.443772)
		)
		(stroke
			(width 0)
			(type solid)
		)
		(fill yes)
		(layer "In2.Cu")
		(net "M_C_CPU1_SA_DQS_DN<7>")
	)
	(gr_poly
		(pts
			(xy 82.741008 -236.992668) (xy 82.741008 -236.944916) (xy 82.540856 -236.944916) (xy 82.540856 -236.992668)
			(xy 82.640932 -237.09249)
		)
		(stroke
			(width 0)
			(type solid)
		)
		(fill yes)
		(layer "In2.Cu")
		(net "M_C_CPU1_SA_DQS_DN<2>")
	)
	(gr_poly
		(pts
			(xy 82.741008 -235.776262) (xy 82.640932 -235.676186) (xy 82.540856 -235.776262) (xy 82.540856 -235.820712)
			(xy 82.741008 -235.820712)
		)
		(stroke
			(width 0)
			(type solid)
		)
		(fill yes)
		(layer "In2.Cu")
		(net "M_C_CPU1_SA_DQ<17>")
	)
	(gr_poly
		(pts
			(xy 82.741008 -235.372402) (xy 82.741008 -235.327952) (xy 82.540856 -235.327952) (xy 82.540856 -235.372402)
			(xy 82.640932 -235.472478)
		)
		(stroke
			(width 0)
			(type solid)
		)
		(fill yes)
		(layer "In2.Cu")
		(net "M_C_CPU1_SA_DQ<18>")
	)
	(gr_poly
		(pts
			(xy 82.741008 -234.15625) (xy 82.640932 -234.056174) (xy 82.540856 -234.15625) (xy 82.540856 -234.2007)
			(xy 82.741008 -234.2007)
		)
		(stroke
			(width 0)
			(type solid)
		)
		(fill yes)
		(layer "In2.Cu")
		(net "M_C_CPU1_SA_DQ<13>")
	)
	(gr_poly
		(pts
			(xy 82.741008 -233.75239) (xy 82.741008 -233.70794) (xy 82.540856 -233.70794) (xy 82.540856 -233.75239)
			(xy 82.640932 -233.852466)
		)
		(stroke
			(width 0)
			(type solid)
		)
		(fill yes)
		(layer "In2.Cu")
		(net "M_C_CPU1_SA_DQ<14>")
	)
	(gr_poly
		(pts
			(xy 82.741008 -232.535984) (xy 82.640932 -232.436162) (xy 82.540856 -232.535984) (xy 82.540856 -232.583736)
			(xy 82.741008 -232.583736)
		)
		(stroke
			(width 0)
			(type solid)
		)
		(fill yes)
		(layer "In2.Cu")
		(net "M_C_CPU1_SA_DQS_DN<6>")
	)
	(gr_poly
		(pts
			(xy 82.741008 -232.132632) (xy 82.741008 -232.08488) (xy 82.540856 -232.08488) (xy 82.540856 -232.132632)
			(xy 82.640932 -232.232454)
		)
		(stroke
			(width 0)
			(type solid)
		)
		(fill yes)
		(layer "In2.Cu")
		(net "M_C_CPU1_SA_DQS_DN<1>")
	)
	(gr_poly
		(pts
			(xy 82.741008 -230.916226) (xy 82.640932 -230.81615) (xy 82.540856 -230.916226) (xy 82.540856 -230.960676)
			(xy 82.741008 -230.960676)
		)
		(stroke
			(width 0)
			(type solid)
		)
		(fill yes)
		(layer "In2.Cu")
		(net "M_C_CPU1_SA_DQ<9>")
	)
	(gr_poly
		(pts
			(xy 82.741008 -230.51262) (xy 82.741008 -230.46817) (xy 82.540856 -230.46817) (xy 82.540856 -230.51262)
			(xy 82.640932 -230.612696)
		)
		(stroke
			(width 0)
			(type solid)
		)
		(fill yes)
		(layer "In2.Cu")
		(net "M_C_CPU1_SA_DQ<10>")
	)
	(gr_poly
		(pts
			(xy 82.741008 -229.296214) (xy 82.640932 -229.196138) (xy 82.540856 -229.296214) (xy 82.540856 -229.340664)
			(xy 82.741008 -229.340664)
		)
		(stroke
			(width 0)
			(type solid)
		)
		(fill yes)
		(layer "In2.Cu")
		(net "M_C_CPU1_SA_DQ<5>")
	)
	(gr_poly
		(pts
			(xy 82.741008 -228.892608) (xy 82.741008 -228.848158) (xy 82.540856 -228.848158) (xy 82.540856 -228.892608)
			(xy 82.640932 -228.992684)
		)
		(stroke
			(width 0)
			(type solid)
		)
		(fill yes)
		(layer "In2.Cu")
		(net "M_C_CPU1_SA_DQ<6>")
	)
	(gr_poly
		(pts
			(xy 82.760058 -222.415862) (xy 82.796634 -222.27921) (xy 82.659982 -222.242634) (xy 82.621628 -222.264986)
			(xy 82.72145 -222.438214)
		)
		(stroke
			(width 0)
			(type solid)
		)
		(fill yes)
		(layer "In2.Cu")
		(net "M_C_CPU1_SA_DQ<0>")
	)
	(gr_poly
		(pts
			(xy 82.760312 -227.275898) (xy 82.796888 -227.1395) (xy 82.660236 -227.10267) (xy 82.619088 -227.126546)
			(xy 82.71891 -227.299774)
		)
		(stroke
			(width 0)
			(type solid)
		)
		(fill yes)
		(layer "In2.Cu")
		(net "M_C_CPU1_SA_DQS_DN<5>")
	)
	(gr_poly
		(pts
			(xy 82.760312 -225.655886) (xy 82.796888 -225.519488) (xy 82.660236 -225.482912) (xy 82.619088 -225.506534)
			(xy 82.71891 -225.679762)
		)
		(stroke
			(width 0)
			(type solid)
		)
		(fill yes)
		(layer "In2.Cu")
		(net "M_C_CPU1_SA_DQS_DP<0>")
	)
	(gr_poly
		(pts
			(xy 82.760312 -224.036636) (xy 82.797142 -223.899984) (xy 82.66049 -223.863408) (xy 82.621882 -223.88576)
			(xy 82.721958 -224.058988)
		)
		(stroke
			(width 0)
			(type solid)
		)
		(fill yes)
		(layer "In2.Cu")
		(net "M_C_CPU1_SA_DQ<1>")
	)
	(gr_poly
		(pts
			(xy 83.040982 -293.32428) (xy 83.040982 -293.27983) (xy 82.84083 -293.27983) (xy 82.84083 -293.32428)
			(xy 82.940906 -293.424356)
		)
		(stroke
			(width 0)
			(type solid)
		)
		(fill yes)
		(layer "In2.Cu")
		(net "M_C_CPU1_SB_DQ<31>")
	)
	(gr_poly
		(pts
			(xy 83.040982 -292.108128) (xy 82.940906 -292.008052) (xy 82.84083 -292.108128) (xy 82.84083 -292.152578)
			(xy 83.040982 -292.152578)
		)
		(stroke
			(width 0)
			(type solid)
		)
		(fill yes)
		(layer "In2.Cu")
		(net "M_C_CPU1_SB_DQ<28>")
	)
	(gr_poly
		(pts
			(xy 83.040982 -291.704522) (xy 83.040982 -291.65677) (xy 82.84083 -291.65677) (xy 82.84083 -291.704522)
			(xy 82.940906 -291.804344)
		)
		(stroke
			(width 0)
			(type solid)
		)
		(fill yes)
		(layer "In2.Cu")
		(net "M_C_CPU1_SB_DQS_DP<8>")
	)
	(gr_poly
		(pts
			(xy 83.040982 -290.487862) (xy 82.940906 -290.38804) (xy 82.84083 -290.487862) (xy 82.84083 -290.535614)
			(xy 83.040982 -290.535614)
		)
		(stroke
			(width 0)
			(type solid)
		)
		(fill yes)
		(layer "In2.Cu")
		(net "M_C_CPU1_SB_DQS_DP<3>")
	)
	(gr_poly
		(pts
			(xy 83.040982 -290.084256) (xy 83.040982 -290.039806) (xy 82.84083 -290.039806) (xy 82.84083 -290.084256)
			(xy 82.940906 -290.184332)
		)
		(stroke
			(width 0)
			(type solid)
		)
		(fill yes)
		(layer "In2.Cu")
		(net "M_C_CPU1_SB_DQ<27>")
	)
	(gr_poly
		(pts
			(xy 83.040982 -288.868104) (xy 82.940906 -288.768028) (xy 82.84083 -288.868104) (xy 82.84083 -288.912554)
			(xy 83.040982 -288.912554)
		)
		(stroke
			(width 0)
			(type solid)
		)
		(fill yes)
		(layer "In2.Cu")
		(net "M_C_CPU1_SB_DQ<24>")
	)
	(gr_poly
		(pts
			(xy 83.040982 -288.464498) (xy 83.040982 -288.420048) (xy 82.84083 -288.420048) (xy 82.84083 -288.464498)
			(xy 82.940906 -288.564574)
		)
		(stroke
			(width 0)
			(type solid)
		)
		(fill yes)
		(layer "In2.Cu")
		(net "M_C_CPU1_SB_DQ<23>")
	)
	(gr_poly
		(pts
			(xy 83.040982 -287.248092) (xy 82.940906 -287.148016) (xy 82.84083 -287.248092) (xy 82.84083 -287.292542)
			(xy 83.040982 -287.292542)
		)
		(stroke
			(width 0)
			(type solid)
		)
		(fill yes)
		(layer "In2.Cu")
		(net "M_C_CPU1_SB_DQ<20>")
	)
	(gr_poly
		(pts
			(xy 83.040982 -286.844486) (xy 83.040982 -286.796734) (xy 82.84083 -286.796734) (xy 82.84083 -286.844486)
			(xy 82.940906 -286.944562)
		)
		(stroke
			(width 0)
			(type solid)
		)
		(fill yes)
		(layer "In2.Cu")
		(net "M_C_CPU1_SB_DQS_DP<7>")
	)
	(gr_poly
		(pts
			(xy 83.040982 -285.62808) (xy 82.940906 -285.528258) (xy 82.84083 -285.62808) (xy 82.84083 -285.675832)
			(xy 83.040982 -285.675832)
		)
		(stroke
			(width 0)
			(type solid)
		)
		(fill yes)
		(layer "In2.Cu")
		(net "M_C_CPU1_SB_DQS_DP<2>")
	)
	(gr_poly
		(pts
			(xy 83.040982 -285.224474) (xy 83.040982 -285.180024) (xy 82.84083 -285.180024) (xy 82.84083 -285.224474)
			(xy 82.940906 -285.32455)
		)
		(stroke
			(width 0)
			(type solid)
		)
		(fill yes)
		(layer "In2.Cu")
		(net "M_C_CPU1_SB_DQ<19>")
	)
	(gr_poly
		(pts
			(xy 83.040982 -284.008322) (xy 82.940906 -283.908246) (xy 82.84083 -284.008322) (xy 82.84083 -284.052772)
			(xy 83.040982 -284.052772)
		)
		(stroke
			(width 0)
			(type solid)
		)
		(fill yes)
		(layer "In2.Cu")
		(net "M_C_CPU1_SB_DQ<16>")
	)
	(gr_poly
		(pts
			(xy 83.040982 -283.604462) (xy 83.040982 -283.560012) (xy 82.84083 -283.560012) (xy 82.84083 -283.604462)
			(xy 82.940906 -283.704538)
		)
		(stroke
			(width 0)
			(type solid)
		)
		(fill yes)
		(layer "In2.Cu")
		(net "M_C_CPU1_SB_DQ<15>")
	)
	(gr_poly
		(pts
			(xy 83.040982 -282.38831) (xy 82.940906 -282.288234) (xy 82.84083 -282.38831) (xy 82.84083 -282.43276)
			(xy 83.040982 -282.43276)
		)
		(stroke
			(width 0)
			(type solid)
		)
		(fill yes)
		(layer "In2.Cu")
		(net "M_C_CPU1_SB_DQ<12>")
	)
	(gr_poly
		(pts
			(xy 83.040982 -281.984704) (xy 83.040982 -281.936952) (xy 82.84083 -281.936952) (xy 82.84083 -281.984704)
			(xy 82.940906 -282.084526)
		)
		(stroke
			(width 0)
			(type solid)
		)
		(fill yes)
		(layer "In2.Cu")
		(net "M_C_CPU1_SB_DQS_DP<6>")
	)
	(gr_poly
		(pts
			(xy 83.040982 -280.768044) (xy 82.940906 -280.668222) (xy 82.84083 -280.768044) (xy 82.84083 -280.815796)
			(xy 83.040982 -280.815796)
		)
		(stroke
			(width 0)
			(type solid)
		)
		(fill yes)
		(layer "In2.Cu")
		(net "M_C_CPU1_SB_DQS_DP<1>")
	)
	(gr_poly
		(pts
			(xy 83.040982 -280.364438) (xy 83.040982 -280.319988) (xy 82.84083 -280.319988) (xy 82.84083 -280.364438)
			(xy 82.940906 -280.464514)
		)
		(stroke
			(width 0)
			(type solid)
		)
		(fill yes)
		(layer "In2.Cu")
		(net "M_C_CPU1_SB_DQ<11>")
	)
	(gr_poly
		(pts
			(xy 83.040982 -279.148286) (xy 82.940906 -279.04821) (xy 82.84083 -279.148286) (xy 82.84083 -279.192736)
			(xy 83.040982 -279.192736)
		)
		(stroke
			(width 0)
			(type solid)
		)
		(fill yes)
		(layer "In2.Cu")
		(net "M_C_CPU1_SB_DQ<8>")
	)
	(gr_poly
		(pts
			(xy 83.040982 -278.744426) (xy 83.040982 -278.699976) (xy 82.84083 -278.699976) (xy 82.84083 -278.744426)
			(xy 82.940906 -278.844502)
		)
		(stroke
			(width 0)
			(type solid)
		)
		(fill yes)
		(layer "In2.Cu")
		(net "M_C_CPU1_SB_DQ<7>")
	)
	(gr_poly
		(pts
			(xy 83.040982 -277.528274) (xy 82.940906 -277.428198) (xy 82.84083 -277.528274) (xy 82.84083 -277.572724)
			(xy 83.040982 -277.572724)
		)
		(stroke
			(width 0)
			(type solid)
		)
		(fill yes)
		(layer "In2.Cu")
		(net "M_C_CPU1_SB_DQ<4>")
	)
	(gr_poly
		(pts
			(xy 83.040982 -277.124668) (xy 83.040982 -277.076916) (xy 82.84083 -277.076916) (xy 82.84083 -277.124668)
			(xy 82.940906 -277.22449)
		)
		(stroke
			(width 0)
			(type solid)
		)
		(fill yes)
		(layer "In2.Cu")
		(net "M_C_CPU1_SB_DQS_DP<5>")
	)
	(gr_poly
		(pts
			(xy 83.040982 -275.908008) (xy 82.940906 -275.808186) (xy 82.84083 -275.908008) (xy 82.84083 -275.95576)
			(xy 83.040982 -275.95576)
		)
		(stroke
			(width 0)
			(type solid)
		)
		(fill yes)
		(layer "In2.Cu")
		(net "M_C_CPU1_SB_DQS_DP<0>")
	)
	(gr_poly
		(pts
			(xy 83.040982 -275.504402) (xy 83.040982 -275.459952) (xy 82.84083 -275.459952) (xy 82.84083 -275.504402)
			(xy 82.940906 -275.604478)
		)
		(stroke
			(width 0)
			(type solid)
		)
		(fill yes)
		(layer "In2.Cu")
		(net "M_C_CPU1_SB_DQ<3>")
	)
	(gr_poly
		(pts
			(xy 83.040982 -274.28825) (xy 82.940906 -274.188174) (xy 82.84083 -274.28825) (xy 82.84083 -274.3327)
			(xy 83.040982 -274.3327)
		)
		(stroke
			(width 0)
			(type solid)
		)
		(fill yes)
		(layer "In2.Cu")
		(net "M_C_CPU1_SB_DQ<0>")
	)
	(gr_poly
		(pts
			(xy 83.040982 -273.88439) (xy 83.040982 -273.83994) (xy 82.84083 -273.83994) (xy 82.84083 -273.88439)
			(xy 82.940906 -273.984466)
		)
		(stroke
			(width 0)
			(type solid)
		)
		(fill yes)
		(layer "In2.Cu")
		(net "M_C_CPU1_SB_CB<3>")
	)
	(gr_poly
		(pts
			(xy 83.040982 -272.668238) (xy 82.940906 -272.568162) (xy 82.84083 -272.668238) (xy 82.84083 -272.712688)
			(xy 83.040982 -272.712688)
		)
		(stroke
			(width 0)
			(type solid)
		)
		(fill yes)
		(layer "In2.Cu")
		(net "M_C_CPU1_SB_CB<0>")
	)
	(gr_poly
		(pts
			(xy 83.040982 -272.264632) (xy 83.040982 -272.21688) (xy 82.84083 -272.21688) (xy 82.84083 -272.264632)
			(xy 82.940906 -272.364454)
		)
		(stroke
			(width 0)
			(type solid)
		)
		(fill yes)
		(layer "In2.Cu")
		(net "M_C_CPU1_SB_DQS_DP<4>")
	)
	(gr_poly
		(pts
			(xy 83.040982 -271.047972) (xy 82.940906 -270.94815) (xy 82.84083 -271.047972) (xy 82.84083 -271.095724)
			(xy 83.040982 -271.095724)
		)
		(stroke
			(width 0)
			(type solid)
		)
		(fill yes)
		(layer "In2.Cu")
		(net "M_C_CPU1_SB_DQS_DP<9>")
	)
	(gr_poly
		(pts
			(xy 83.040982 -270.644366) (xy 83.040982 -270.599916) (xy 82.84083 -270.599916) (xy 82.84083 -270.644366)
			(xy 82.940906 -270.744442)
		)
		(stroke
			(width 0)
			(type solid)
		)
		(fill yes)
		(layer "In2.Cu")
		(net "M_C_CPU1_SB_CB<7>")
	)
	(gr_poly
		(pts
			(xy 83.040982 -269.428214) (xy 82.940906 -269.328138) (xy 82.84083 -269.428214) (xy 82.84083 -269.472664)
			(xy 83.040982 -269.472664)
		)
		(stroke
			(width 0)
			(type solid)
		)
		(fill yes)
		(layer "In2.Cu")
		(net "M_C_CPU1_SB_CB<4>")
	)
	(gr_poly
		(pts
			(xy 83.040982 -264.164318) (xy 83.040982 -264.119868) (xy 82.84083 -264.119868) (xy 82.84083 -264.164318)
			(xy 82.940906 -264.264394)
		)
		(stroke
			(width 0)
			(type solid)
		)
		(fill yes)
		(layer "In2.Cu")
		(net "M_C_CPU1_SB_CA<5>")
	)
	(gr_poly
		(pts
			(xy 83.040982 -262.948166) (xy 82.940906 -262.84809) (xy 82.84083 -262.948166) (xy 82.84083 -262.992616)
			(xy 83.040982 -262.992616)
		)
		(stroke
			(width 0)
			(type solid)
		)
		(fill yes)
		(layer "In2.Cu")
		(net "M_C_CPU1_SB_CA<2>")
	)
	(gr_poly
		(pts
			(xy 83.040982 -262.544306) (xy 83.040982 -262.499856) (xy 82.84083 -262.499856) (xy 82.84083 -262.544306)
			(xy 82.940906 -262.644382)
		)
		(stroke
			(width 0)
			(type solid)
		)
		(fill yes)
		(layer "In2.Cu")
		(net "M_C_CPU1_SB_CA<1>")
	)
	(gr_poly
		(pts
			(xy 83.041236 -265.78433) (xy 83.041236 -265.73988) (xy 82.841084 -265.73988) (xy 82.841084 -265.78433)
			(xy 82.94116 -265.884406)
		)
		(stroke
			(width 0)
			(type solid)
		)
		(fill yes)
		(layer "In2.Cu")
		(net "M_C_CPU1_SB_CS_N<0>")
	)
	(gr_poly
		(pts
			(xy 83.041236 -264.568178) (xy 82.94116 -264.468102) (xy 82.841084 -264.568178) (xy 82.841084 -264.612628)
			(xy 83.041236 -264.612628)
		)
		(stroke
			(width 0)
			(type solid)
		)
		(fill yes)
		(layer "In2.Cu")
		(net "M_C_CPU1_SB_CA<6>")
	)
	(gr_poly
		(pts
			(xy 83.047078 -267.801852) (xy 82.947256 -267.701776) (xy 82.84718 -267.801852) (xy 82.84718 -267.846302)
			(xy 83.047078 -267.846302)
		)
		(stroke
			(width 0)
			(type solid)
		)
		(fill yes)
		(layer "In2.Cu")
		(net "M_C_CPU1_SB_RSP<0>")
	)
	(gr_poly
		(pts
			(xy 83.130136 -225.39325) (xy 83.03006 -225.220022) (xy 82.991706 -225.242374) (xy 82.95513 -225.379026)
			(xy 83.091528 -225.415602)
		)
		(stroke
			(width 0)
			(type solid)
		)
		(fill yes)
		(layer "In2.Cu")
		(net "M_C_CPU1_SA_DQ<3>")
	)
	(gr_poly
		(pts
			(xy 83.130136 -223.773238) (xy 83.03006 -223.60001) (xy 82.991706 -223.622362) (xy 82.95513 -223.759014)
			(xy 83.091528 -223.79559)
		)
		(stroke
			(width 0)
			(type solid)
		)
		(fill yes)
		(layer "In2.Cu")
		(net "M_C_CPU1_SA_DQ<2>")
	)
	(gr_poly
		(pts
			(xy 83.13293 -227.0125) (xy 83.033108 -226.839272) (xy 82.991706 -226.863148) (xy 82.95513 -226.999546)
			(xy 83.091782 -227.036376)
		)
		(stroke
			(width 0)
			(type solid)
		)
		(fill yes)
		(layer "In2.Cu")
		(net "M_C_CPU1_SA_DQS_DN<0>")
	)
	(gr_poly
		(pts
			(xy 83.211162 -256.026158) (xy 83.111086 -255.926336) (xy 83.01101 -256.026158) (xy 83.01101 -256.07391)
			(xy 83.211162 -256.07391)
		)
		(stroke
			(width 0)
			(type solid)
		)
		(fill yes)
		(layer "In2.Cu")
		(net "M_C_CPU1_CLK_DP<0>")
	)
	(gr_poly
		(pts
			(xy 83.211162 -255.622552) (xy 83.211162 -255.578102) (xy 83.01101 -255.578102) (xy 83.01101 -255.622552)
			(xy 83.111086 -255.722628)
		)
		(stroke
			(width 0)
			(type solid)
		)
		(fill yes)
		(layer "In2.Cu")
		(net "M_C_CPU1_SA_PAR")
	)
	(gr_poly
		(pts
			(xy 83.211162 -254.4064) (xy 83.111086 -254.306324) (xy 83.01101 -254.4064) (xy 83.01101 -254.45085)
			(xy 83.211162 -254.45085)
		)
		(stroke
			(width 0)
			(type solid)
		)
		(fill yes)
		(layer "In2.Cu")
		(net "M_C_CPU1_SA_CA<4>")
	)
	(gr_poly
		(pts
			(xy 83.211162 -254.00254) (xy 83.211162 -253.95809) (xy 83.01101 -253.95809) (xy 83.01101 -254.00254)
			(xy 83.111086 -254.102616)
		)
		(stroke
			(width 0)
			(type solid)
		)
		(fill yes)
		(layer "In2.Cu")
		(net "M_C_CPU1_SA_CA<3>")
	)
	(gr_poly
		(pts
			(xy 83.211162 -252.786388) (xy 83.111086 -252.686312) (xy 83.01101 -252.786388) (xy 83.01101 -252.830838)
			(xy 83.211162 -252.830838)
		)
		(stroke
			(width 0)
			(type solid)
		)
		(fill yes)
		(layer "In2.Cu")
		(net "M_C_CPU1_SA_CA<0>")
	)
	(gr_poly
		(pts
			(xy 83.211162 -252.382528) (xy 83.211162 -252.338078) (xy 83.01101 -252.338078) (xy 83.01101 -252.382528)
			(xy 83.111086 -252.482604)
		)
		(stroke
			(width 0)
			(type solid)
		)
		(fill yes)
		(layer "In2.Cu")
		(net "M_C_CPU1_SA_CS_N<1>")
	)
	(gr_poly
		(pts
			(xy 83.211162 -250.762516) (xy 83.211162 -250.718066) (xy 83.01101 -250.718066) (xy 83.01101 -250.762516)
			(xy 83.111086 -250.862592)
		)
		(stroke
			(width 0)
			(type solid)
		)
		(fill yes)
		(layer "In2.Cu")
		(net "M_C_CPU1_RESET_N")
	)
	(gr_poly
		(pts
			(xy 83.211162 -249.142504) (xy 83.211162 -249.098054) (xy 83.01101 -249.098054) (xy 83.01101 -249.142504)
			(xy 83.111086 -249.24258)
		)
		(stroke
			(width 0)
			(type solid)
		)
		(fill yes)
		(layer "In2.Cu")
		(net "M_C_CPU1_SA_CB<7>")
	)
	(gr_poly
		(pts
			(xy 83.211162 -247.926352) (xy 83.111086 -247.826276) (xy 83.01101 -247.926352) (xy 83.01101 -247.970802)
			(xy 83.211162 -247.970802)
		)
		(stroke
			(width 0)
			(type solid)
		)
		(fill yes)
		(layer "In2.Cu")
		(net "M_C_CPU1_SA_CB<4>")
	)
	(gr_poly
		(pts
			(xy 83.211162 -247.522746) (xy 83.211162 -247.474994) (xy 83.01101 -247.474994) (xy 83.01101 -247.522746)
			(xy 83.111086 -247.622568)
		)
		(stroke
			(width 0)
			(type solid)
		)
		(fill yes)
		(layer "In2.Cu")
		(net "M_C_CPU1_SA_DQS_DP<9>")
	)
	(gr_poly
		(pts
			(xy 83.211162 -246.306086) (xy 83.111086 -246.206264) (xy 83.01101 -246.306086) (xy 83.01101 -246.353838)
			(xy 83.211162 -246.353838)
		)
		(stroke
			(width 0)
			(type solid)
		)
		(fill yes)
		(layer "In2.Cu")
		(net "M_C_CPU1_SA_DQS_DP<4>")
	)
	(gr_poly
		(pts
			(xy 83.211162 -245.90248) (xy 83.211162 -245.85803) (xy 83.01101 -245.85803) (xy 83.01101 -245.90248)
			(xy 83.111086 -246.002556)
		)
		(stroke
			(width 0)
			(type solid)
		)
		(fill yes)
		(layer "In2.Cu")
		(net "M_C_CPU1_SA_CB<3>")
	)
	(gr_poly
		(pts
			(xy 83.211162 -244.686328) (xy 83.111086 -244.586252) (xy 83.01101 -244.686328) (xy 83.01101 -244.730778)
			(xy 83.211162 -244.730778)
		)
		(stroke
			(width 0)
			(type solid)
		)
		(fill yes)
		(layer "In2.Cu")
		(net "M_C_CPU1_SA_CB<0>")
	)
	(gr_poly
		(pts
			(xy 83.211162 -244.282468) (xy 83.211162 -244.238018) (xy 83.01101 -244.238018) (xy 83.01101 -244.282468)
			(xy 83.111086 -244.382544)
		)
		(stroke
			(width 0)
			(type solid)
		)
		(fill yes)
		(layer "In2.Cu")
		(net "M_C_CPU1_SA_DQ<31>")
	)
	(gr_poly
		(pts
			(xy 83.211162 -243.066316) (xy 83.111086 -242.96624) (xy 83.01101 -243.066316) (xy 83.01101 -243.110766)
			(xy 83.211162 -243.110766)
		)
		(stroke
			(width 0)
			(type solid)
		)
		(fill yes)
		(layer "In2.Cu")
		(net "M_C_CPU1_SA_DQ<28>")
	)
	(gr_poly
		(pts
			(xy 83.211162 -242.66271) (xy 83.211162 -242.614958) (xy 83.01101 -242.614958) (xy 83.01101 -242.66271)
			(xy 83.111086 -242.762532)
		)
		(stroke
			(width 0)
			(type solid)
		)
		(fill yes)
		(layer "In2.Cu")
		(net "M_C_CPU1_SA_DQS_DP<8>")
	)
	(gr_poly
		(pts
			(xy 83.211162 -241.44605) (xy 83.111086 -241.346228) (xy 83.01101 -241.44605) (xy 83.01101 -241.493802)
			(xy 83.211162 -241.493802)
		)
		(stroke
			(width 0)
			(type solid)
		)
		(fill yes)
		(layer "In2.Cu")
		(net "M_C_CPU1_SA_DQS_DP<3>")
	)
	(gr_poly
		(pts
			(xy 83.211162 -241.042444) (xy 83.211162 -240.997994) (xy 83.01101 -240.997994) (xy 83.01101 -241.042444)
			(xy 83.111086 -241.14252)
		)
		(stroke
			(width 0)
			(type solid)
		)
		(fill yes)
		(layer "In2.Cu")
		(net "M_C_CPU1_SA_DQ<27>")
	)
	(gr_poly
		(pts
			(xy 83.211162 -239.826292) (xy 83.111086 -239.726216) (xy 83.01101 -239.826292) (xy 83.01101 -239.870742)
			(xy 83.211162 -239.870742)
		)
		(stroke
			(width 0)
			(type solid)
		)
		(fill yes)
		(layer "In2.Cu")
		(net "M_C_CPU1_SA_DQ<24>")
	)
	(gr_poly
		(pts
			(xy 83.211162 -239.422432) (xy 83.211162 -239.377982) (xy 83.01101 -239.377982) (xy 83.01101 -239.422432)
			(xy 83.111086 -239.522508)
		)
		(stroke
			(width 0)
			(type solid)
		)
		(fill yes)
		(layer "In2.Cu")
		(net "M_C_CPU1_SA_DQ<23>")
	)
	(gr_poly
		(pts
			(xy 83.211162 -238.20628) (xy 83.111086 -238.106204) (xy 83.01101 -238.20628) (xy 83.01101 -238.25073)
			(xy 83.211162 -238.25073)
		)
		(stroke
			(width 0)
			(type solid)
		)
		(fill yes)
		(layer "In2.Cu")
		(net "M_C_CPU1_SA_DQ<20>")
	)
	(gr_poly
		(pts
			(xy 83.211162 -237.802674) (xy 83.211162 -237.754922) (xy 83.01101 -237.754922) (xy 83.01101 -237.802674)
			(xy 83.111086 -237.902496)
		)
		(stroke
			(width 0)
			(type solid)
		)
		(fill yes)
		(layer "In2.Cu")
		(net "M_C_CPU1_SA_DQS_DP<7>")
	)
	(gr_poly
		(pts
			(xy 83.211162 -236.586014) (xy 83.111086 -236.486192) (xy 83.01101 -236.586014) (xy 83.01101 -236.633766)
			(xy 83.211162 -236.633766)
		)
		(stroke
			(width 0)
			(type solid)
		)
		(fill yes)
		(layer "In2.Cu")
		(net "M_C_CPU1_SA_DQS_DP<2>")
	)
	(gr_poly
		(pts
			(xy 83.211162 -236.182408) (xy 83.211162 -236.137958) (xy 83.01101 -236.137958) (xy 83.01101 -236.182408)
			(xy 83.111086 -236.282484)
		)
		(stroke
			(width 0)
			(type solid)
		)
		(fill yes)
		(layer "In2.Cu")
		(net "M_C_CPU1_SA_DQ<19>")
	)
	(gr_poly
		(pts
			(xy 83.211162 -234.966256) (xy 83.111086 -234.86618) (xy 83.01101 -234.966256) (xy 83.01101 -235.010706)
			(xy 83.211162 -235.010706)
		)
		(stroke
			(width 0)
			(type solid)
		)
		(fill yes)
		(layer "In2.Cu")
		(net "M_C_CPU1_SA_DQ<16>")
	)
	(gr_poly
		(pts
			(xy 83.211162 -234.562396) (xy 83.211162 -234.517946) (xy 83.01101 -234.517946) (xy 83.01101 -234.562396)
			(xy 83.111086 -234.662472)
		)
		(stroke
			(width 0)
			(type solid)
		)
		(fill yes)
		(layer "In2.Cu")
		(net "M_C_CPU1_SA_DQ<15>")
	)
	(gr_poly
		(pts
			(xy 83.211162 -233.346244) (xy 83.111086 -233.246168) (xy 83.01101 -233.346244) (xy 83.01101 -233.390694)
			(xy 83.211162 -233.390694)
		)
		(stroke
			(width 0)
			(type solid)
		)
		(fill yes)
		(layer "In2.Cu")
		(net "M_C_CPU1_SA_DQ<12>")
	)
	(gr_poly
		(pts
			(xy 83.211162 -232.942638) (xy 83.211162 -232.894886) (xy 83.01101 -232.894886) (xy 83.01101 -232.942638)
			(xy 83.111086 -233.04246)
		)
		(stroke
			(width 0)
			(type solid)
		)
		(fill yes)
		(layer "In2.Cu")
		(net "M_C_CPU1_SA_DQS_DP<6>")
	)
	(gr_poly
		(pts
			(xy 83.211162 -231.725978) (xy 83.111086 -231.626156) (xy 83.01101 -231.725978) (xy 83.01101 -231.77373)
			(xy 83.211162 -231.77373)
		)
		(stroke
			(width 0)
			(type solid)
		)
		(fill yes)
		(layer "In2.Cu")
		(net "M_C_CPU1_SA_DQS_DP<1>")
	)
	(gr_poly
		(pts
			(xy 83.211162 -231.322626) (xy 83.211162 -231.278176) (xy 83.01101 -231.278176) (xy 83.01101 -231.322626)
			(xy 83.111086 -231.422702)
		)
		(stroke
			(width 0)
			(type solid)
		)
		(fill yes)
		(layer "In2.Cu")
		(net "M_C_CPU1_SA_DQ<11>")
	)
	(gr_poly
		(pts
			(xy 83.211162 -230.10622) (xy 83.111086 -230.006144) (xy 83.01101 -230.10622) (xy 83.01101 -230.15067)
			(xy 83.211162 -230.15067)
		)
		(stroke
			(width 0)
			(type solid)
		)
		(fill yes)
		(layer "In2.Cu")
		(net "M_C_CPU1_SA_DQ<8>")
	)
	(gr_poly
		(pts
			(xy 83.211162 -229.702614) (xy 83.211162 -229.658164) (xy 83.01101 -229.658164) (xy 83.01101 -229.702614)
			(xy 83.111086 -229.80269)
		)
		(stroke
			(width 0)
			(type solid)
		)
		(fill yes)
		(layer "In2.Cu")
		(net "M_C_CPU1_SA_DQ<7>")
	)
	(gr_poly
		(pts
			(xy 83.211162 -228.486462) (xy 83.111086 -228.386386) (xy 83.01101 -228.486462) (xy 83.01101 -228.530912)
			(xy 83.211162 -228.530912)
		)
		(stroke
			(width 0)
			(type solid)
		)
		(fill yes)
		(layer "In2.Cu")
		(net "M_C_CPU1_SA_DQ<4>")
	)
	(gr_poly
		(pts
			(xy 83.211162 -228.082856) (xy 83.211162 -228.035104) (xy 83.01101 -228.035104) (xy 83.01101 -228.082856)
			(xy 83.111086 -228.182678)
		)
		(stroke
			(width 0)
			(type solid)
		)
		(fill yes)
		(layer "In2.Cu")
		(net "M_C_CPU1_SA_DQS_DP<5>")
	)
	(gr_poly
		(pts
			(xy 83.230212 -226.465892) (xy 83.266788 -226.329494) (xy 83.130136 -226.292664) (xy 83.088988 -226.31654)
			(xy 83.18881 -226.489768)
		)
		(stroke
			(width 0)
			(type solid)
		)
		(fill yes)
		(layer "In2.Cu")
		(net "M_C_CPU1_SA_DQS_DP<0>")
	)
	(gr_poly
		(pts
			(xy 83.230212 -224.846642) (xy 83.267042 -224.70999) (xy 83.13039 -224.673414) (xy 83.091782 -224.695766)
			(xy 83.191858 -224.868994)
		)
		(stroke
			(width 0)
			(type solid)
		)
		(fill yes)
		(layer "In2.Cu")
		(net "M_C_CPU1_SA_DQ<1>")
	)
	(gr_poly
		(pts
			(xy 83.230212 -223.22663) (xy 83.267042 -223.089978) (xy 83.13039 -223.053402) (xy 83.091782 -223.075754)
			(xy 83.191858 -223.248982)
		)
		(stroke
			(width 0)
			(type solid)
		)
		(fill yes)
		(layer "In2.Cu")
		(net "M_C_CPU1_SA_DQ<0>")
	)
	(gr_poly
		(pts
			(xy 83.50377 -291.298122) (xy 83.403694 -291.198046) (xy 83.303618 -291.298122) (xy 83.303618 -291.34562)
			(xy 83.50377 -291.34562)
		)
		(stroke
			(width 0)
			(type solid)
		)
		(fill yes)
		(layer "In2.Cu")
		(net "M_C_CPU1_SB_DQS_DN<8>")
	)
	(gr_poly
		(pts
			(xy 83.504786 -266.991846) (xy 83.40471 -266.89177) (xy 83.304888 -266.991846) (xy 83.304888 -267.036296)
			(xy 83.504786 -267.036296)
		)
		(stroke
			(width 0)
			(type solid)
		)
		(fill yes)
		(layer "In2.Cu")
		(net "M_C_CPU1_SA_RSP<0>")
	)
	(gr_poly
		(pts
			(xy 83.511136 -292.918134) (xy 83.41106 -292.818058) (xy 83.310984 -292.918134) (xy 83.310984 -292.962584)
			(xy 83.511136 -292.962584)
		)
		(stroke
			(width 0)
			(type solid)
		)
		(fill yes)
		(layer "In2.Cu")
		(net "M_C_CPU1_SB_DQ<29>")
	)
	(gr_poly
		(pts
			(xy 83.511136 -292.514274) (xy 83.511136 -292.469824) (xy 83.310984 -292.469824) (xy 83.310984 -292.514274)
			(xy 83.41106 -292.61435)
		)
		(stroke
			(width 0)
			(type solid)
		)
		(fill yes)
		(layer "In2.Cu")
		(net "M_C_CPU1_SB_DQ<30>")
	)
	(gr_poly
		(pts
			(xy 83.511136 -290.894516) (xy 83.511136 -290.846764) (xy 83.310984 -290.846764) (xy 83.310984 -290.894516)
			(xy 83.41106 -290.994338)
		)
		(stroke
			(width 0)
			(type solid)
		)
		(fill yes)
		(layer "In2.Cu")
		(net "M_C_CPU1_SB_DQS_DN<3>")
	)
	(gr_poly
		(pts
			(xy 83.511136 -289.67811) (xy 83.41106 -289.578034) (xy 83.310984 -289.67811) (xy 83.310984 -289.72256)
			(xy 83.511136 -289.72256)
		)
		(stroke
			(width 0)
			(type solid)
		)
		(fill yes)
		(layer "In2.Cu")
		(net "M_C_CPU1_SB_DQ<25>")
	)
	(gr_poly
		(pts
			(xy 83.511136 -289.27425) (xy 83.511136 -289.2298) (xy 83.310984 -289.2298) (xy 83.310984 -289.27425)
			(xy 83.41106 -289.374326)
		)
		(stroke
			(width 0)
			(type solid)
		)
		(fill yes)
		(layer "In2.Cu")
		(net "M_C_CPU1_SB_DQ<26>")
	)
	(gr_poly
		(pts
			(xy 83.511136 -288.058098) (xy 83.41106 -287.958022) (xy 83.310984 -288.058098) (xy 83.310984 -288.102548)
			(xy 83.511136 -288.102548)
		)
		(stroke
			(width 0)
			(type solid)
		)
		(fill yes)
		(layer "In2.Cu")
		(net "M_C_CPU1_SB_DQ<21>")
	)
	(gr_poly
		(pts
			(xy 83.511136 -287.654492) (xy 83.511136 -287.610042) (xy 83.310984 -287.610042) (xy 83.310984 -287.654492)
			(xy 83.41106 -287.754568)
		)
		(stroke
			(width 0)
			(type solid)
		)
		(fill yes)
		(layer "In2.Cu")
		(net "M_C_CPU1_SB_DQ<22>")
	)
	(gr_poly
		(pts
			(xy 83.511136 -286.438086) (xy 83.41106 -286.33801) (xy 83.310984 -286.438086) (xy 83.310984 -286.485838)
			(xy 83.511136 -286.485838)
		)
		(stroke
			(width 0)
			(type solid)
		)
		(fill yes)
		(layer "In2.Cu")
		(net "M_C_CPU1_SB_DQS_DN<7>")
	)
	(gr_poly
		(pts
			(xy 83.511136 -286.034734) (xy 83.511136 -285.986982) (xy 83.310984 -285.986982) (xy 83.310984 -286.034734)
			(xy 83.41106 -286.134556)
		)
		(stroke
			(width 0)
			(type solid)
		)
		(fill yes)
		(layer "In2.Cu")
		(net "M_C_CPU1_SB_DQS_DN<2>")
	)
	(gr_poly
		(pts
			(xy 83.511136 -284.818328) (xy 83.41106 -284.718252) (xy 83.310984 -284.818328) (xy 83.310984 -284.862778)
			(xy 83.511136 -284.862778)
		)
		(stroke
			(width 0)
			(type solid)
		)
		(fill yes)
		(layer "In2.Cu")
		(net "M_C_CPU1_SB_DQ<17>")
	)
	(gr_poly
		(pts
			(xy 83.511136 -284.414468) (xy 83.511136 -284.370018) (xy 83.310984 -284.370018) (xy 83.310984 -284.414468)
			(xy 83.41106 -284.514544)
		)
		(stroke
			(width 0)
			(type solid)
		)
		(fill yes)
		(layer "In2.Cu")
		(net "M_C_CPU1_SB_DQ<18>")
	)
	(gr_poly
		(pts
			(xy 83.511136 -283.198316) (xy 83.41106 -283.09824) (xy 83.310984 -283.198316) (xy 83.310984 -283.242766)
			(xy 83.511136 -283.242766)
		)
		(stroke
			(width 0)
			(type solid)
		)
		(fill yes)
		(layer "In2.Cu")
		(net "M_C_CPU1_SB_DQ<13>")
	)
	(gr_poly
		(pts
			(xy 83.511136 -282.794456) (xy 83.511136 -282.750006) (xy 83.310984 -282.750006) (xy 83.310984 -282.794456)
			(xy 83.41106 -282.894532)
		)
		(stroke
			(width 0)
			(type solid)
		)
		(fill yes)
		(layer "In2.Cu")
		(net "M_C_CPU1_SB_DQ<14>")
	)
	(gr_poly
		(pts
			(xy 83.511136 -281.57805) (xy 83.41106 -281.478228) (xy 83.310984 -281.57805) (xy 83.310984 -281.625802)
			(xy 83.511136 -281.625802)
		)
		(stroke
			(width 0)
			(type solid)
		)
		(fill yes)
		(layer "In2.Cu")
		(net "M_C_CPU1_SB_DQS_DN<6>")
	)
	(gr_poly
		(pts
			(xy 83.511136 -281.174698) (xy 83.511136 -281.126946) (xy 83.310984 -281.126946) (xy 83.310984 -281.174698)
			(xy 83.41106 -281.27452)
		)
		(stroke
			(width 0)
			(type solid)
		)
		(fill yes)
		(layer "In2.Cu")
		(net "M_C_CPU1_SB_DQS_DN<1>")
	)
	(gr_poly
		(pts
			(xy 83.511136 -279.958292) (xy 83.41106 -279.858216) (xy 83.310984 -279.958292) (xy 83.310984 -280.002742)
			(xy 83.511136 -280.002742)
		)
		(stroke
			(width 0)
			(type solid)
		)
		(fill yes)
		(layer "In2.Cu")
		(net "M_C_CPU1_SB_DQ<9>")
	)
	(gr_poly
		(pts
			(xy 83.511136 -279.554432) (xy 83.511136 -279.509982) (xy 83.310984 -279.509982) (xy 83.310984 -279.554432)
			(xy 83.41106 -279.654508)
		)
		(stroke
			(width 0)
			(type solid)
		)
		(fill yes)
		(layer "In2.Cu")
		(net "M_C_CPU1_SB_DQ<10>")
	)
	(gr_poly
		(pts
			(xy 83.511136 -278.33828) (xy 83.41106 -278.238204) (xy 83.310984 -278.33828) (xy 83.310984 -278.38273)
			(xy 83.511136 -278.38273)
		)
		(stroke
			(width 0)
			(type solid)
		)
		(fill yes)
		(layer "In2.Cu")
		(net "M_C_CPU1_SB_DQ<5>")
	)
	(gr_poly
		(pts
			(xy 83.511136 -277.93442) (xy 83.511136 -277.88997) (xy 83.310984 -277.88997) (xy 83.310984 -277.93442)
			(xy 83.41106 -278.034496)
		)
		(stroke
			(width 0)
			(type solid)
		)
		(fill yes)
		(layer "In2.Cu")
		(net "M_C_CPU1_SB_DQ<6>")
	)
	(gr_poly
		(pts
			(xy 83.511136 -276.718014) (xy 83.41106 -276.618192) (xy 83.310984 -276.718014) (xy 83.310984 -276.765766)
			(xy 83.511136 -276.765766)
		)
		(stroke
			(width 0)
			(type solid)
		)
		(fill yes)
		(layer "In2.Cu")
		(net "M_C_CPU1_SB_DQS_DN<5>")
	)
	(gr_poly
		(pts
			(xy 83.511136 -276.314662) (xy 83.511136 -276.26691) (xy 83.310984 -276.26691) (xy 83.310984 -276.314662)
			(xy 83.41106 -276.414484)
		)
		(stroke
			(width 0)
			(type solid)
		)
		(fill yes)
		(layer "In2.Cu")
		(net "M_C_CPU1_SB_DQS_DN<0>")
	)
	(gr_poly
		(pts
			(xy 83.511136 -275.098256) (xy 83.41106 -274.99818) (xy 83.310984 -275.098256) (xy 83.310984 -275.142706)
			(xy 83.511136 -275.142706)
		)
		(stroke
			(width 0)
			(type solid)
		)
		(fill yes)
		(layer "In2.Cu")
		(net "M_C_CPU1_SB_DQ<1>")
	)
	(gr_poly
		(pts
			(xy 83.511136 -274.694396) (xy 83.511136 -274.649946) (xy 83.310984 -274.649946) (xy 83.310984 -274.694396)
			(xy 83.41106 -274.794472)
		)
		(stroke
			(width 0)
			(type solid)
		)
		(fill yes)
		(layer "In2.Cu")
		(net "M_C_CPU1_SB_DQ<2>")
	)
	(gr_poly
		(pts
			(xy 83.511136 -273.478244) (xy 83.41106 -273.378168) (xy 83.310984 -273.478244) (xy 83.310984 -273.522694)
			(xy 83.511136 -273.522694)
		)
		(stroke
			(width 0)
			(type solid)
		)
		(fill yes)
		(layer "In2.Cu")
		(net "M_C_CPU1_SB_CB<1>")
	)
	(gr_poly
		(pts
			(xy 83.511136 -273.074384) (xy 83.511136 -273.029934) (xy 83.310984 -273.029934) (xy 83.310984 -273.074384)
			(xy 83.41106 -273.17446)
		)
		(stroke
			(width 0)
			(type solid)
		)
		(fill yes)
		(layer "In2.Cu")
		(net "M_C_CPU1_SB_CB<2>")
	)
	(gr_poly
		(pts
			(xy 83.511136 -271.857978) (xy 83.41106 -271.758156) (xy 83.310984 -271.857978) (xy 83.310984 -271.90573)
			(xy 83.511136 -271.90573)
		)
		(stroke
			(width 0)
			(type solid)
		)
		(fill yes)
		(layer "In2.Cu")
		(net "M_C_CPU1_SB_DQS_DN<4>")
	)
	(gr_poly
		(pts
			(xy 83.511136 -271.454626) (xy 83.511136 -271.406874) (xy 83.310984 -271.406874) (xy 83.310984 -271.454626)
			(xy 83.41106 -271.554448)
		)
		(stroke
			(width 0)
			(type solid)
		)
		(fill yes)
		(layer "In2.Cu")
		(net "M_C_CPU1_SB_DQS_DN<9>")
	)
	(gr_poly
		(pts
			(xy 83.511136 -270.23822) (xy 83.41106 -270.138144) (xy 83.310984 -270.23822) (xy 83.310984 -270.28267)
			(xy 83.511136 -270.28267)
		)
		(stroke
			(width 0)
			(type solid)
		)
		(fill yes)
		(layer "In2.Cu")
		(net "M_C_CPU1_SB_CB<5>")
	)
	(gr_poly
		(pts
			(xy 83.511136 -269.83436) (xy 83.511136 -269.78991) (xy 83.310984 -269.78991) (xy 83.310984 -269.83436)
			(xy 83.41106 -269.934436)
		)
		(stroke
			(width 0)
			(type solid)
		)
		(fill yes)
		(layer "In2.Cu")
		(net "M_C_CPU1_SB_CB<6>")
	)
	(gr_poly
		(pts
			(xy 83.511136 -266.594336) (xy 83.511136 -266.549886) (xy 83.310984 -266.549886) (xy 83.310984 -266.594336)
			(xy 83.41106 -266.694412)
		)
		(stroke
			(width 0)
			(type solid)
		)
		(fill yes)
		(layer "In2.Cu")
		(net "M_C_CPU1_SB_CS_N<1>")
	)
	(gr_poly
		(pts
			(xy 83.511136 -264.974324) (xy 83.511136 -264.929874) (xy 83.310984 -264.929874) (xy 83.310984 -264.974324)
			(xy 83.41106 -265.0744)
		)
		(stroke
			(width 0)
			(type solid)
		)
		(fill yes)
		(layer "In2.Cu")
		(net "M_C_CPU1_SB_PAR")
	)
	(gr_poly
		(pts
			(xy 83.511136 -263.758172) (xy 83.41106 -263.658096) (xy 83.310984 -263.758172) (xy 83.310984 -263.802622)
			(xy 83.511136 -263.802622)
		)
		(stroke
			(width 0)
			(type solid)
		)
		(fill yes)
		(layer "In2.Cu")
		(net "M_C_CPU1_SB_CA<4>")
	)
	(gr_poly
		(pts
			(xy 83.511136 -263.354312) (xy 83.511136 -263.309862) (xy 83.310984 -263.309862) (xy 83.310984 -263.354312)
			(xy 83.41106 -263.454388)
		)
		(stroke
			(width 0)
			(type solid)
		)
		(fill yes)
		(layer "In2.Cu")
		(net "M_C_CPU1_SB_CA<3>")
	)
	(gr_poly
		(pts
			(xy 83.511136 -262.13816) (xy 83.41106 -262.038084) (xy 83.310984 -262.13816) (xy 83.310984 -262.18261)
			(xy 83.511136 -262.18261)
		)
		(stroke
			(width 0)
			(type solid)
		)
		(fill yes)
		(layer "In2.Cu")
		(net "M_C_CPU1_SB_CA<0>")
	)
	(gr_poly
		(pts
			(xy 83.60029 -226.203256) (xy 83.500214 -226.030028) (xy 83.46186 -226.05238) (xy 83.42503 -226.189032)
			(xy 83.561682 -226.225608)
		)
		(stroke
			(width 0)
			(type solid)
		)
		(fill yes)
		(layer "In2.Cu")
		(net "M_C_CPU1_SA_DQ<3>")
	)
	(gr_poly
		(pts
			(xy 83.60029 -224.583244) (xy 83.500214 -224.410016) (xy 83.46186 -224.432368) (xy 83.42503 -224.56902)
			(xy 83.561682 -224.605596)
		)
		(stroke
			(width 0)
			(type solid)
		)
		(fill yes)
		(layer "In2.Cu")
		(net "M_C_CPU1_SA_DQ<2>")
	)
	(gr_poly
		(pts
			(xy 83.680808 -246.712486) (xy 83.680808 -246.664988) (xy 83.48091 -246.664988) (xy 83.48091 -246.712486)
			(xy 83.580732 -246.812562)
		)
		(stroke
			(width 0)
			(type solid)
		)
		(fill yes)
		(layer "In2.Cu")
		(net "M_C_CPU1_SA_DQS_DN<4>")
	)
	(gr_poly
		(pts
			(xy 83.681062 -256.432812) (xy 83.681062 -256.38506) (xy 83.48091 -256.38506) (xy 83.48091 -256.432812)
			(xy 83.580986 -256.532634)
		)
		(stroke
			(width 0)
			(type solid)
		)
		(fill yes)
		(layer "In2.Cu")
		(net "M_C_CPU1_CLK_DN<0>")
	)
	(gr_poly
		(pts
			(xy 83.681062 -255.216406) (xy 83.580986 -255.11633) (xy 83.48091 -255.216406) (xy 83.48091 -255.260856)
			(xy 83.681062 -255.260856)
		)
		(stroke
			(width 0)
			(type solid)
		)
		(fill yes)
		(layer "In2.Cu")
		(net "M_C_CPU1_SA_CA<6>")
	)
	(gr_poly
		(pts
			(xy 83.681062 -254.812546) (xy 83.681062 -254.768096) (xy 83.48091 -254.768096) (xy 83.48091 -254.812546)
			(xy 83.580986 -254.912622)
		)
		(stroke
			(width 0)
			(type solid)
		)
		(fill yes)
		(layer "In2.Cu")
		(net "M_C_CPU1_SA_CA<5>")
	)
	(gr_poly
		(pts
			(xy 83.681062 -253.596394) (xy 83.580986 -253.496318) (xy 83.48091 -253.596394) (xy 83.48091 -253.640844)
			(xy 83.681062 -253.640844)
		)
		(stroke
			(width 0)
			(type solid)
		)
		(fill yes)
		(layer "In2.Cu")
		(net "M_C_CPU1_SA_CA<2>")
	)
	(gr_poly
		(pts
			(xy 83.681062 -253.192534) (xy 83.681062 -253.148084) (xy 83.48091 -253.148084) (xy 83.48091 -253.192534)
			(xy 83.580986 -253.29261)
		)
		(stroke
			(width 0)
			(type solid)
		)
		(fill yes)
		(layer "In2.Cu")
		(net "M_C_CPU1_SA_CA<1>")
	)
	(gr_poly
		(pts
			(xy 83.681062 -251.572522) (xy 83.681062 -251.528072) (xy 83.48091 -251.528072) (xy 83.48091 -251.572522)
			(xy 83.580986 -251.672598)
		)
		(stroke
			(width 0)
			(type solid)
		)
		(fill yes)
		(layer "In2.Cu")
		(net "M_C_CPU1_SA_CS_N<0>")
	)
	(gr_poly
		(pts
			(xy 83.681062 -250.35637) (xy 83.580986 -250.256294) (xy 83.48091 -250.35637) (xy 83.48091 -250.40082)
			(xy 83.681062 -250.40082)
		)
		(stroke
			(width 0)
			(type solid)
		)
		(fill yes)
		(layer "In2.Cu")
		(net "M_C_CPU1_ALERT_R_N")
	)
	(gr_poly
		(pts
			(xy 83.681062 -248.736358) (xy 83.580986 -248.636282) (xy 83.48091 -248.736358) (xy 83.48091 -248.780808)
			(xy 83.681062 -248.780808)
		)
		(stroke
			(width 0)
			(type solid)
		)
		(fill yes)
		(layer "In2.Cu")
		(net "M_C_CPU1_SA_CB<5>")
	)
	(gr_poly
		(pts
			(xy 83.681062 -248.332498) (xy 83.681062 -248.288048) (xy 83.48091 -248.288048) (xy 83.48091 -248.332498)
			(xy 83.580986 -248.432574)
		)
		(stroke
			(width 0)
			(type solid)
		)
		(fill yes)
		(layer "In2.Cu")
		(net "M_C_CPU1_SA_CB<6>")
	)
	(gr_poly
		(pts
			(xy 83.681062 -247.116092) (xy 83.580986 -247.01627) (xy 83.48091 -247.116092) (xy 83.48091 -247.163844)
			(xy 83.681062 -247.163844)
		)
		(stroke
			(width 0)
			(type solid)
		)
		(fill yes)
		(layer "In2.Cu")
		(net "M_C_CPU1_SA_DQS_DN<9>")
	)
	(gr_poly
		(pts
			(xy 83.681062 -245.496334) (xy 83.580986 -245.396258) (xy 83.48091 -245.496334) (xy 83.48091 -245.540784)
			(xy 83.681062 -245.540784)
		)
		(stroke
			(width 0)
			(type solid)
		)
		(fill yes)
		(layer "In2.Cu")
		(net "M_C_CPU1_SA_CB<1>")
	)
	(gr_poly
		(pts
			(xy 83.681062 -245.092474) (xy 83.681062 -245.048024) (xy 83.48091 -245.048024) (xy 83.48091 -245.092474)
			(xy 83.580986 -245.19255)
		)
		(stroke
			(width 0)
			(type solid)
		)
		(fill yes)
		(layer "In2.Cu")
		(net "M_C_CPU1_SA_CB<2>")
	)
	(gr_poly
		(pts
			(xy 83.681062 -243.876322) (xy 83.580986 -243.776246) (xy 83.48091 -243.876322) (xy 83.48091 -243.920772)
			(xy 83.681062 -243.920772)
		)
		(stroke
			(width 0)
			(type solid)
		)
		(fill yes)
		(layer "In2.Cu")
		(net "M_C_CPU1_SA_DQ<29>")
	)
	(gr_poly
		(pts
			(xy 83.681062 -243.472462) (xy 83.681062 -243.428012) (xy 83.48091 -243.428012) (xy 83.48091 -243.472462)
			(xy 83.580986 -243.572538)
		)
		(stroke
			(width 0)
			(type solid)
		)
		(fill yes)
		(layer "In2.Cu")
		(net "M_C_CPU1_SA_DQ<30>")
	)
	(gr_poly
		(pts
			(xy 83.681062 -242.256056) (xy 83.580986 -242.156234) (xy 83.48091 -242.256056) (xy 83.48091 -242.303808)
			(xy 83.681062 -242.303808)
		)
		(stroke
			(width 0)
			(type solid)
		)
		(fill yes)
		(layer "In2.Cu")
		(net "M_C_CPU1_SA_DQS_DN<8>")
	)
	(gr_poly
		(pts
			(xy 83.681062 -241.852704) (xy 83.681062 -241.804952) (xy 83.48091 -241.804952) (xy 83.48091 -241.852704)
			(xy 83.580986 -241.952526)
		)
		(stroke
			(width 0)
			(type solid)
		)
		(fill yes)
		(layer "In2.Cu")
		(net "M_C_CPU1_SA_DQS_DN<3>")
	)
	(gr_poly
		(pts
			(xy 83.681062 -240.636298) (xy 83.580986 -240.536222) (xy 83.48091 -240.636298) (xy 83.48091 -240.680748)
			(xy 83.681062 -240.680748)
		)
		(stroke
			(width 0)
			(type solid)
		)
		(fill yes)
		(layer "In2.Cu")
		(net "M_C_CPU1_SA_DQ<25>")
	)
	(gr_poly
		(pts
			(xy 83.681062 -240.232438) (xy 83.681062 -240.187988) (xy 83.48091 -240.187988) (xy 83.48091 -240.232438)
			(xy 83.580986 -240.332514)
		)
		(stroke
			(width 0)
			(type solid)
		)
		(fill yes)
		(layer "In2.Cu")
		(net "M_C_CPU1_SA_DQ<26>")
	)
	(gr_poly
		(pts
			(xy 83.681062 -239.016286) (xy 83.580986 -238.91621) (xy 83.48091 -239.016286) (xy 83.48091 -239.060736)
			(xy 83.681062 -239.060736)
		)
		(stroke
			(width 0)
			(type solid)
		)
		(fill yes)
		(layer "In2.Cu")
		(net "M_C_CPU1_SA_DQ<21>")
	)
	(gr_poly
		(pts
			(xy 83.681062 -238.612426) (xy 83.681062 -238.567976) (xy 83.48091 -238.567976) (xy 83.48091 -238.612426)
			(xy 83.580986 -238.712502)
		)
		(stroke
			(width 0)
			(type solid)
		)
		(fill yes)
		(layer "In2.Cu")
		(net "M_C_CPU1_SA_DQ<22>")
	)
	(gr_poly
		(pts
			(xy 83.681062 -237.39602) (xy 83.580986 -237.296198) (xy 83.48091 -237.39602) (xy 83.48091 -237.443772)
			(xy 83.681062 -237.443772)
		)
		(stroke
			(width 0)
			(type solid)
		)
		(fill yes)
		(layer "In2.Cu")
		(net "M_C_CPU1_SA_DQS_DN<7>")
	)
	(gr_poly
		(pts
			(xy 83.681062 -236.992668) (xy 83.681062 -236.944916) (xy 83.48091 -236.944916) (xy 83.48091 -236.992668)
			(xy 83.580986 -237.09249)
		)
		(stroke
			(width 0)
			(type solid)
		)
		(fill yes)
		(layer "In2.Cu")
		(net "M_C_CPU1_SA_DQS_DN<2>")
	)
	(gr_poly
		(pts
			(xy 83.681062 -235.776262) (xy 83.580986 -235.676186) (xy 83.48091 -235.776262) (xy 83.48091 -235.820712)
			(xy 83.681062 -235.820712)
		)
		(stroke
			(width 0)
			(type solid)
		)
		(fill yes)
		(layer "In2.Cu")
		(net "M_C_CPU1_SA_DQ<17>")
	)
	(gr_poly
		(pts
			(xy 83.681062 -235.372402) (xy 83.681062 -235.327952) (xy 83.48091 -235.327952) (xy 83.48091 -235.372402)
			(xy 83.580986 -235.472478)
		)
		(stroke
			(width 0)
			(type solid)
		)
		(fill yes)
		(layer "In2.Cu")
		(net "M_C_CPU1_SA_DQ<18>")
	)
	(gr_poly
		(pts
			(xy 83.681062 -234.15625) (xy 83.580986 -234.056174) (xy 83.48091 -234.15625) (xy 83.48091 -234.2007)
			(xy 83.681062 -234.2007)
		)
		(stroke
			(width 0)
			(type solid)
		)
		(fill yes)
		(layer "In2.Cu")
		(net "M_C_CPU1_SA_DQ<13>")
	)
	(gr_poly
		(pts
			(xy 83.681062 -233.75239) (xy 83.681062 -233.70794) (xy 83.48091 -233.70794) (xy 83.48091 -233.75239)
			(xy 83.580986 -233.852466)
		)
		(stroke
			(width 0)
			(type solid)
		)
		(fill yes)
		(layer "In2.Cu")
		(net "M_C_CPU1_SA_DQ<14>")
	)
	(gr_poly
		(pts
			(xy 83.681062 -232.535984) (xy 83.580986 -232.436162) (xy 83.48091 -232.535984) (xy 83.48091 -232.583736)
			(xy 83.681062 -232.583736)
		)
		(stroke
			(width 0)
			(type solid)
		)
		(fill yes)
		(layer "In2.Cu")
		(net "M_C_CPU1_SA_DQS_DN<6>")
	)
	(gr_poly
		(pts
			(xy 83.681062 -232.132632) (xy 83.681062 -232.08488) (xy 83.48091 -232.08488) (xy 83.48091 -232.132632)
			(xy 83.580986 -232.232454)
		)
		(stroke
			(width 0)
			(type solid)
		)
		(fill yes)
		(layer "In2.Cu")
		(net "M_C_CPU1_SA_DQS_DN<1>")
	)
	(gr_poly
		(pts
			(xy 83.681062 -230.916226) (xy 83.580986 -230.81615) (xy 83.48091 -230.916226) (xy 83.48091 -230.960676)
			(xy 83.681062 -230.960676)
		)
		(stroke
			(width 0)
			(type solid)
		)
		(fill yes)
		(layer "In2.Cu")
		(net "M_C_CPU1_SA_DQ<9>")
	)
	(gr_poly
		(pts
			(xy 83.681062 -230.51262) (xy 83.681062 -230.46817) (xy 83.48091 -230.46817) (xy 83.48091 -230.51262)
			(xy 83.580986 -230.612696)
		)
		(stroke
			(width 0)
			(type solid)
		)
		(fill yes)
		(layer "In2.Cu")
		(net "M_C_CPU1_SA_DQ<10>")
	)
	(gr_poly
		(pts
			(xy 83.681062 -229.296214) (xy 83.580986 -229.196138) (xy 83.48091 -229.296214) (xy 83.48091 -229.340664)
			(xy 83.681062 -229.340664)
		)
		(stroke
			(width 0)
			(type solid)
		)
		(fill yes)
		(layer "In2.Cu")
		(net "M_C_CPU1_SA_DQ<5>")
	)
	(gr_poly
		(pts
			(xy 83.681062 -228.892608) (xy 83.681062 -228.848158) (xy 83.48091 -228.848158) (xy 83.48091 -228.892608)
			(xy 83.580986 -228.992684)
		)
		(stroke
			(width 0)
			(type solid)
		)
		(fill yes)
		(layer "In2.Cu")
		(net "M_C_CPU1_SA_DQ<6>")
	)
	(gr_poly
		(pts
			(xy 83.681062 -227.676202) (xy 83.580986 -227.57638) (xy 83.48091 -227.676202) (xy 83.48091 -227.723954)
			(xy 83.681062 -227.723954)
		)
		(stroke
			(width 0)
			(type solid)
		)
		(fill yes)
		(layer "In2.Cu")
		(net "M_C_CPU1_SA_DQS_DN<5>")
	)
	(gr_poly
		(pts
			(xy 83.681062 -227.27285) (xy 83.681062 -227.225098) (xy 83.48091 -227.225098) (xy 83.48091 -227.27285)
			(xy 83.580986 -227.372672)
		)
		(stroke
			(width 0)
			(type solid)
		)
		(fill yes)
		(layer "In2.Cu")
		(net "M_C_CPU1_SA_DQS_DN<0>")
	)
	(gr_poly
		(pts
			(xy 83.700366 -225.656648) (xy 83.736942 -225.519996) (xy 83.600544 -225.48342) (xy 83.561936 -225.505772)
			(xy 83.662012 -225.679)
		)
		(stroke
			(width 0)
			(type solid)
		)
		(fill yes)
		(layer "In2.Cu")
		(net "M_C_CPU1_SA_DQ<1>")
	)
	(gr_poly
		(pts
			(xy 83.700366 -224.036636) (xy 83.736942 -223.899984) (xy 83.600544 -223.863408) (xy 83.561936 -223.88576)
			(xy 83.662012 -224.058988)
		)
		(stroke
			(width 0)
			(type solid)
		)
		(fill yes)
		(layer "In2.Cu")
		(net "M_C_CPU1_SA_DQ<0>")
	)
	(gr_poly
		(pts
			(xy 83.981036 -293.32428) (xy 83.981036 -293.27983) (xy 83.780884 -293.27983) (xy 83.780884 -293.32428)
			(xy 83.88096 -293.424356)
		)
		(stroke
			(width 0)
			(type solid)
		)
		(fill yes)
		(layer "In2.Cu")
		(net "M_C_CPU1_SB_DQ<31>")
	)
	(gr_poly
		(pts
			(xy 83.981036 -292.108128) (xy 83.88096 -292.008052) (xy 83.780884 -292.108128) (xy 83.780884 -292.152578)
			(xy 83.981036 -292.152578)
		)
		(stroke
			(width 0)
			(type solid)
		)
		(fill yes)
		(layer "In2.Cu")
		(net "M_C_CPU1_SB_DQ<28>")
	)
	(gr_poly
		(pts
			(xy 83.981036 -291.704522) (xy 83.981036 -291.65677) (xy 83.780884 -291.65677) (xy 83.780884 -291.704522)
			(xy 83.88096 -291.804344)
		)
		(stroke
			(width 0)
			(type solid)
		)
		(fill yes)
		(layer "In2.Cu")
		(net "M_C_CPU1_SB_DQS_DP<8>")
	)
	(gr_poly
		(pts
			(xy 83.981036 -290.487862) (xy 83.88096 -290.38804) (xy 83.780884 -290.487862) (xy 83.780884 -290.535614)
			(xy 83.981036 -290.535614)
		)
		(stroke
			(width 0)
			(type solid)
		)
		(fill yes)
		(layer "In2.Cu")
		(net "M_C_CPU1_SB_DQS_DP<3>")
	)
	(gr_poly
		(pts
			(xy 83.981036 -290.084256) (xy 83.981036 -290.039806) (xy 83.780884 -290.039806) (xy 83.780884 -290.084256)
			(xy 83.88096 -290.184332)
		)
		(stroke
			(width 0)
			(type solid)
		)
		(fill yes)
		(layer "In2.Cu")
		(net "M_C_CPU1_SB_DQ<27>")
	)
	(gr_poly
		(pts
			(xy 83.981036 -288.868104) (xy 83.88096 -288.768028) (xy 83.780884 -288.868104) (xy 83.780884 -288.912554)
			(xy 83.981036 -288.912554)
		)
		(stroke
			(width 0)
			(type solid)
		)
		(fill yes)
		(layer "In2.Cu")
		(net "M_C_CPU1_SB_DQ<24>")
	)
	(gr_poly
		(pts
			(xy 83.981036 -288.464498) (xy 83.981036 -288.420048) (xy 83.780884 -288.420048) (xy 83.780884 -288.464498)
			(xy 83.88096 -288.564574)
		)
		(stroke
			(width 0)
			(type solid)
		)
		(fill yes)
		(layer "In2.Cu")
		(net "M_C_CPU1_SB_DQ<23>")
	)
	(gr_poly
		(pts
			(xy 83.981036 -287.248092) (xy 83.88096 -287.148016) (xy 83.780884 -287.248092) (xy 83.780884 -287.292542)
			(xy 83.981036 -287.292542)
		)
		(stroke
			(width 0)
			(type solid)
		)
		(fill yes)
		(layer "In2.Cu")
		(net "M_C_CPU1_SB_DQ<20>")
	)
	(gr_poly
		(pts
			(xy 83.981036 -286.844486) (xy 83.981036 -286.796734) (xy 83.780884 -286.796734) (xy 83.780884 -286.844486)
			(xy 83.88096 -286.944562)
		)
		(stroke
			(width 0)
			(type solid)
		)
		(fill yes)
		(layer "In2.Cu")
		(net "M_C_CPU1_SB_DQS_DP<7>")
	)
	(gr_poly
		(pts
			(xy 83.981036 -285.62808) (xy 83.88096 -285.528258) (xy 83.780884 -285.62808) (xy 83.780884 -285.675832)
			(xy 83.981036 -285.675832)
		)
		(stroke
			(width 0)
			(type solid)
		)
		(fill yes)
		(layer "In2.Cu")
		(net "M_C_CPU1_SB_DQS_DP<2>")
	)
	(gr_poly
		(pts
			(xy 83.981036 -285.224474) (xy 83.981036 -285.180024) (xy 83.780884 -285.180024) (xy 83.780884 -285.224474)
			(xy 83.88096 -285.32455)
		)
		(stroke
			(width 0)
			(type solid)
		)
		(fill yes)
		(layer "In2.Cu")
		(net "M_C_CPU1_SB_DQ<19>")
	)
	(gr_poly
		(pts
			(xy 83.981036 -284.008322) (xy 83.88096 -283.908246) (xy 83.780884 -284.008322) (xy 83.780884 -284.052772)
			(xy 83.981036 -284.052772)
		)
		(stroke
			(width 0)
			(type solid)
		)
		(fill yes)
		(layer "In2.Cu")
		(net "M_C_CPU1_SB_DQ<16>")
	)
	(gr_poly
		(pts
			(xy 83.981036 -283.604462) (xy 83.981036 -283.560012) (xy 83.780884 -283.560012) (xy 83.780884 -283.604462)
			(xy 83.88096 -283.704538)
		)
		(stroke
			(width 0)
			(type solid)
		)
		(fill yes)
		(layer "In2.Cu")
		(net "M_C_CPU1_SB_DQ<15>")
	)
	(gr_poly
		(pts
			(xy 83.981036 -282.38831) (xy 83.88096 -282.288234) (xy 83.780884 -282.38831) (xy 83.780884 -282.43276)
			(xy 83.981036 -282.43276)
		)
		(stroke
			(width 0)
			(type solid)
		)
		(fill yes)
		(layer "In2.Cu")
		(net "M_C_CPU1_SB_DQ<12>")
	)
	(gr_poly
		(pts
			(xy 83.981036 -281.984704) (xy 83.981036 -281.936952) (xy 83.780884 -281.936952) (xy 83.780884 -281.984704)
			(xy 83.88096 -282.084526)
		)
		(stroke
			(width 0)
			(type solid)
		)
		(fill yes)
		(layer "In2.Cu")
		(net "M_C_CPU1_SB_DQS_DP<6>")
	)
	(gr_poly
		(pts
			(xy 83.981036 -280.768044) (xy 83.88096 -280.668222) (xy 83.780884 -280.768044) (xy 83.780884 -280.815796)
			(xy 83.981036 -280.815796)
		)
		(stroke
			(width 0)
			(type solid)
		)
		(fill yes)
		(layer "In2.Cu")
		(net "M_C_CPU1_SB_DQS_DP<1>")
	)
	(gr_poly
		(pts
			(xy 83.981036 -280.364438) (xy 83.981036 -280.319988) (xy 83.780884 -280.319988) (xy 83.780884 -280.364438)
			(xy 83.88096 -280.464514)
		)
		(stroke
			(width 0)
			(type solid)
		)
		(fill yes)
		(layer "In2.Cu")
		(net "M_C_CPU1_SB_DQ<11>")
	)
	(gr_poly
		(pts
			(xy 83.981036 -279.148286) (xy 83.88096 -279.04821) (xy 83.780884 -279.148286) (xy 83.780884 -279.192736)
			(xy 83.981036 -279.192736)
		)
		(stroke
			(width 0)
			(type solid)
		)
		(fill yes)
		(layer "In2.Cu")
		(net "M_C_CPU1_SB_DQ<8>")
	)
	(gr_poly
		(pts
			(xy 83.981036 -278.744426) (xy 83.981036 -278.699976) (xy 83.780884 -278.699976) (xy 83.780884 -278.744426)
			(xy 83.88096 -278.844502)
		)
		(stroke
			(width 0)
			(type solid)
		)
		(fill yes)
		(layer "In2.Cu")
		(net "M_C_CPU1_SB_DQ<7>")
	)
	(gr_poly
		(pts
			(xy 83.981036 -277.528274) (xy 83.88096 -277.428198) (xy 83.780884 -277.528274) (xy 83.780884 -277.572724)
			(xy 83.981036 -277.572724)
		)
		(stroke
			(width 0)
			(type solid)
		)
		(fill yes)
		(layer "In2.Cu")
		(net "M_C_CPU1_SB_DQ<4>")
	)
	(gr_poly
		(pts
			(xy 83.981036 -277.124668) (xy 83.981036 -277.076916) (xy 83.780884 -277.076916) (xy 83.780884 -277.124668)
			(xy 83.88096 -277.22449)
		)
		(stroke
			(width 0)
			(type solid)
		)
		(fill yes)
		(layer "In2.Cu")
		(net "M_C_CPU1_SB_DQS_DP<5>")
	)
	(gr_poly
		(pts
			(xy 83.981036 -275.908008) (xy 83.88096 -275.808186) (xy 83.780884 -275.908008) (xy 83.780884 -275.95576)
			(xy 83.981036 -275.95576)
		)
		(stroke
			(width 0)
			(type solid)
		)
		(fill yes)
		(layer "In2.Cu")
		(net "M_C_CPU1_SB_DQS_DP<0>")
	)
	(gr_poly
		(pts
			(xy 83.981036 -275.504402) (xy 83.981036 -275.459952) (xy 83.780884 -275.459952) (xy 83.780884 -275.504402)
			(xy 83.88096 -275.604478)
		)
		(stroke
			(width 0)
			(type solid)
		)
		(fill yes)
		(layer "In2.Cu")
		(net "M_C_CPU1_SB_DQ<3>")
	)
	(gr_poly
		(pts
			(xy 83.981036 -274.28825) (xy 83.88096 -274.188174) (xy 83.780884 -274.28825) (xy 83.780884 -274.3327)
			(xy 83.981036 -274.3327)
		)
		(stroke
			(width 0)
			(type solid)
		)
		(fill yes)
		(layer "In2.Cu")
		(net "M_C_CPU1_SB_DQ<0>")
	)
	(gr_poly
		(pts
			(xy 83.981036 -273.88439) (xy 83.981036 -273.83994) (xy 83.780884 -273.83994) (xy 83.780884 -273.88439)
			(xy 83.88096 -273.984466)
		)
		(stroke
			(width 0)
			(type solid)
		)
		(fill yes)
		(layer "In2.Cu")
		(net "M_C_CPU1_SB_CB<3>")
	)
	(gr_poly
		(pts
			(xy 83.981036 -272.668238) (xy 83.88096 -272.568162) (xy 83.780884 -272.668238) (xy 83.780884 -272.712688)
			(xy 83.981036 -272.712688)
		)
		(stroke
			(width 0)
			(type solid)
		)
		(fill yes)
		(layer "In2.Cu")
		(net "M_C_CPU1_SB_CB<0>")
	)
	(gr_poly
		(pts
			(xy 83.981036 -272.264632) (xy 83.981036 -272.21688) (xy 83.780884 -272.21688) (xy 83.780884 -272.264632)
			(xy 83.88096 -272.364454)
		)
		(stroke
			(width 0)
			(type solid)
		)
		(fill yes)
		(layer "In2.Cu")
		(net "M_C_CPU1_SB_DQS_DP<4>")
	)
	(gr_poly
		(pts
			(xy 83.981036 -271.047972) (xy 83.88096 -270.94815) (xy 83.780884 -271.047972) (xy 83.780884 -271.095724)
			(xy 83.981036 -271.095724)
		)
		(stroke
			(width 0)
			(type solid)
		)
		(fill yes)
		(layer "In2.Cu")
		(net "M_C_CPU1_SB_DQS_DP<9>")
	)
	(gr_poly
		(pts
			(xy 83.981036 -270.644366) (xy 83.981036 -270.599916) (xy 83.780884 -270.599916) (xy 83.780884 -270.644366)
			(xy 83.88096 -270.744442)
		)
		(stroke
			(width 0)
			(type solid)
		)
		(fill yes)
		(layer "In2.Cu")
		(net "M_C_CPU1_SB_CB<7>")
	)
	(gr_poly
		(pts
			(xy 83.981036 -269.428214) (xy 83.88096 -269.328138) (xy 83.780884 -269.428214) (xy 83.780884 -269.472664)
			(xy 83.981036 -269.472664)
		)
		(stroke
			(width 0)
			(type solid)
		)
		(fill yes)
		(layer "In2.Cu")
		(net "M_C_CPU1_SB_CB<4>")
	)
	(gr_poly
		(pts
			(xy 83.981036 -265.78433) (xy 83.981036 -265.73988) (xy 83.780884 -265.73988) (xy 83.780884 -265.78433)
			(xy 83.88096 -265.884406)
		)
		(stroke
			(width 0)
			(type solid)
		)
		(fill yes)
		(layer "In2.Cu")
		(net "M_C_CPU1_SB_CS_N<0>")
	)
	(gr_poly
		(pts
			(xy 83.981036 -264.568178) (xy 83.88096 -264.468102) (xy 83.780884 -264.568178) (xy 83.780884 -264.612628)
			(xy 83.981036 -264.612628)
		)
		(stroke
			(width 0)
			(type solid)
		)
		(fill yes)
		(layer "In2.Cu")
		(net "M_C_CPU1_SB_CA<6>")
	)
	(gr_poly
		(pts
			(xy 83.981036 -264.164318) (xy 83.981036 -264.119868) (xy 83.780884 -264.119868) (xy 83.780884 -264.164318)
			(xy 83.88096 -264.264394)
		)
		(stroke
			(width 0)
			(type solid)
		)
		(fill yes)
		(layer "In2.Cu")
		(net "M_C_CPU1_SB_CA<5>")
	)
	(gr_poly
		(pts
			(xy 83.981036 -262.948166) (xy 83.88096 -262.84809) (xy 83.780884 -262.948166) (xy 83.780884 -262.992616)
			(xy 83.981036 -262.992616)
		)
		(stroke
			(width 0)
			(type solid)
		)
		(fill yes)
		(layer "In2.Cu")
		(net "M_C_CPU1_SB_CA<2>")
	)
	(gr_poly
		(pts
			(xy 83.981036 -262.544306) (xy 83.981036 -262.499856) (xy 83.780884 -262.499856) (xy 83.780884 -262.544306)
			(xy 83.88096 -262.644382)
		)
		(stroke
			(width 0)
			(type solid)
		)
		(fill yes)
		(layer "In2.Cu")
		(net "M_C_CPU1_SB_CA<1>")
	)
	(gr_poly
		(pts
			(xy 83.987132 -267.801852) (xy 83.88731 -267.701776) (xy 83.787234 -267.801852) (xy 83.787234 -267.846302)
			(xy 83.987132 -267.846302)
		)
		(stroke
			(width 0)
			(type solid)
		)
		(fill yes)
		(layer "In2.Cu")
		(net "M_C_CPU1_SB_RSP<0>")
	)
	(gr_poly
		(pts
			(xy 84.07019 -225.39325) (xy 83.970114 -225.220022) (xy 83.93176 -225.242374) (xy 83.89493 -225.379026)
			(xy 84.031582 -225.415602)
		)
		(stroke
			(width 0)
			(type solid)
		)
		(fill yes)
		(layer "In2.Cu")
		(net "M_C_CPU1_SA_DQ<2>")
	)
	(gr_poly
		(pts
			(xy 84.151216 -256.026158) (xy 84.05114 -255.926336) (xy 83.951064 -256.026158) (xy 83.951064 -256.07391)
			(xy 84.151216 -256.07391)
		)
		(stroke
			(width 0)
			(type solid)
		)
		(fill yes)
		(layer "In2.Cu")
		(net "M_C_CPU1_CLK_DP<0>")
	)
	(gr_poly
		(pts
			(xy 84.151216 -255.622552) (xy 84.151216 -255.578102) (xy 83.951064 -255.578102) (xy 83.951064 -255.622552)
			(xy 84.05114 -255.722628)
		)
		(stroke
			(width 0)
			(type solid)
		)
		(fill yes)
		(layer "In2.Cu")
		(net "M_C_CPU1_SA_PAR")
	)
	(gr_poly
		(pts
			(xy 84.151216 -254.4064) (xy 84.05114 -254.306324) (xy 83.951064 -254.4064) (xy 83.951064 -254.45085)
			(xy 84.151216 -254.45085)
		)
		(stroke
			(width 0)
			(type solid)
		)
		(fill yes)
		(layer "In2.Cu")
		(net "M_C_CPU1_SA_CA<4>")
	)
	(gr_poly
		(pts
			(xy 84.151216 -254.00254) (xy 84.151216 -253.95809) (xy 83.951064 -253.95809) (xy 83.951064 -254.00254)
			(xy 84.05114 -254.102616)
		)
		(stroke
			(width 0)
			(type solid)
		)
		(fill yes)
		(layer "In2.Cu")
		(net "M_C_CPU1_SA_CA<3>")
	)
	(gr_poly
		(pts
			(xy 84.151216 -252.786388) (xy 84.05114 -252.686312) (xy 83.951064 -252.786388) (xy 83.951064 -252.830838)
			(xy 84.151216 -252.830838)
		)
		(stroke
			(width 0)
			(type solid)
		)
		(fill yes)
		(layer "In2.Cu")
		(net "M_C_CPU1_SA_CA<0>")
	)
	(gr_poly
		(pts
			(xy 84.151216 -252.382528) (xy 84.151216 -252.338078) (xy 83.951064 -252.338078) (xy 83.951064 -252.382528)
			(xy 84.05114 -252.482604)
		)
		(stroke
			(width 0)
			(type solid)
		)
		(fill yes)
		(layer "In2.Cu")
		(net "M_C_CPU1_SA_CS_N<1>")
	)
	(gr_poly
		(pts
			(xy 84.151216 -250.762516) (xy 84.151216 -250.718066) (xy 83.951064 -250.718066) (xy 83.951064 -250.762516)
			(xy 84.05114 -250.862592)
		)
		(stroke
			(width 0)
			(type solid)
		)
		(fill yes)
		(layer "In2.Cu")
		(net "M_C_CPU1_RESET_N")
	)
	(gr_poly
		(pts
			(xy 84.151216 -249.142504) (xy 84.151216 -249.098054) (xy 83.951064 -249.098054) (xy 83.951064 -249.142504)
			(xy 84.05114 -249.24258)
		)
		(stroke
			(width 0)
			(type solid)
		)
		(fill yes)
		(layer "In2.Cu")
		(net "M_C_CPU1_SA_CB<7>")
	)
	(gr_poly
		(pts
			(xy 84.151216 -247.926352) (xy 84.05114 -247.826276) (xy 83.951064 -247.926352) (xy 83.951064 -247.970802)
			(xy 84.151216 -247.970802)
		)
		(stroke
			(width 0)
			(type solid)
		)
		(fill yes)
		(layer "In2.Cu")
		(net "M_C_CPU1_SA_CB<4>")
	)
	(gr_poly
		(pts
			(xy 84.151216 -247.522746) (xy 84.151216 -247.474994) (xy 83.951064 -247.474994) (xy 83.951064 -247.522746)
			(xy 84.05114 -247.622568)
		)
		(stroke
			(width 0)
			(type solid)
		)
		(fill yes)
		(layer "In2.Cu")
		(net "M_C_CPU1_SA_DQS_DP<9>")
	)
	(gr_poly
		(pts
			(xy 84.151216 -246.306086) (xy 84.05114 -246.206264) (xy 83.951064 -246.306086) (xy 83.951064 -246.353838)
			(xy 84.151216 -246.353838)
		)
		(stroke
			(width 0)
			(type solid)
		)
		(fill yes)
		(layer "In2.Cu")
		(net "M_C_CPU1_SA_DQS_DP<4>")
	)
	(gr_poly
		(pts
			(xy 84.151216 -245.90248) (xy 84.151216 -245.85803) (xy 83.951064 -245.85803) (xy 83.951064 -245.90248)
			(xy 84.05114 -246.002556)
		)
		(stroke
			(width 0)
			(type solid)
		)
		(fill yes)
		(layer "In2.Cu")
		(net "M_C_CPU1_SA_CB<3>")
	)
	(gr_poly
		(pts
			(xy 84.151216 -244.686328) (xy 84.05114 -244.586252) (xy 83.951064 -244.686328) (xy 83.951064 -244.730778)
			(xy 84.151216 -244.730778)
		)
		(stroke
			(width 0)
			(type solid)
		)
		(fill yes)
		(layer "In2.Cu")
		(net "M_C_CPU1_SA_CB<0>")
	)
	(gr_poly
		(pts
			(xy 84.151216 -244.282468) (xy 84.151216 -244.238018) (xy 83.951064 -244.238018) (xy 83.951064 -244.282468)
			(xy 84.05114 -244.382544)
		)
		(stroke
			(width 0)
			(type solid)
		)
		(fill yes)
		(layer "In2.Cu")
		(net "M_C_CPU1_SA_DQ<31>")
	)
	(gr_poly
		(pts
			(xy 84.151216 -243.066316) (xy 84.05114 -242.96624) (xy 83.951064 -243.066316) (xy 83.951064 -243.110766)
			(xy 84.151216 -243.110766)
		)
		(stroke
			(width 0)
			(type solid)
		)
		(fill yes)
		(layer "In2.Cu")
		(net "M_C_CPU1_SA_DQ<28>")
	)
	(gr_poly
		(pts
			(xy 84.151216 -242.66271) (xy 84.151216 -242.614958) (xy 83.951064 -242.614958) (xy 83.951064 -242.66271)
			(xy 84.05114 -242.762532)
		)
		(stroke
			(width 0)
			(type solid)
		)
		(fill yes)
		(layer "In2.Cu")
		(net "M_C_CPU1_SA_DQS_DP<8>")
	)
	(gr_poly
		(pts
			(xy 84.151216 -241.44605) (xy 84.05114 -241.346228) (xy 83.951064 -241.44605) (xy 83.951064 -241.493802)
			(xy 84.151216 -241.493802)
		)
		(stroke
			(width 0)
			(type solid)
		)
		(fill yes)
		(layer "In2.Cu")
		(net "M_C_CPU1_SA_DQS_DP<3>")
	)
	(gr_poly
		(pts
			(xy 84.151216 -241.042444) (xy 84.151216 -240.997994) (xy 83.951064 -240.997994) (xy 83.951064 -241.042444)
			(xy 84.05114 -241.14252)
		)
		(stroke
			(width 0)
			(type solid)
		)
		(fill yes)
		(layer "In2.Cu")
		(net "M_C_CPU1_SA_DQ<27>")
	)
	(gr_poly
		(pts
			(xy 84.151216 -239.826292) (xy 84.05114 -239.726216) (xy 83.951064 -239.826292) (xy 83.951064 -239.870742)
			(xy 84.151216 -239.870742)
		)
		(stroke
			(width 0)
			(type solid)
		)
		(fill yes)
		(layer "In2.Cu")
		(net "M_C_CPU1_SA_DQ<24>")
	)
	(gr_poly
		(pts
			(xy 84.151216 -239.422432) (xy 84.151216 -239.377982) (xy 83.951064 -239.377982) (xy 83.951064 -239.422432)
			(xy 84.05114 -239.522508)
		)
		(stroke
			(width 0)
			(type solid)
		)
		(fill yes)
		(layer "In2.Cu")
		(net "M_C_CPU1_SA_DQ<23>")
	)
	(gr_poly
		(pts
			(xy 84.151216 -238.20628) (xy 84.05114 -238.106204) (xy 83.951064 -238.20628) (xy 83.951064 -238.25073)
			(xy 84.151216 -238.25073)
		)
		(stroke
			(width 0)
			(type solid)
		)
		(fill yes)
		(layer "In2.Cu")
		(net "M_C_CPU1_SA_DQ<20>")
	)
	(gr_poly
		(pts
			(xy 84.151216 -237.802674) (xy 84.151216 -237.754922) (xy 83.951064 -237.754922) (xy 83.951064 -237.802674)
			(xy 84.05114 -237.902496)
		)
		(stroke
			(width 0)
			(type solid)
		)
		(fill yes)
		(layer "In2.Cu")
		(net "M_C_CPU1_SA_DQS_DP<7>")
	)
	(gr_poly
		(pts
			(xy 84.151216 -236.586014) (xy 84.05114 -236.486192) (xy 83.951064 -236.586014) (xy 83.951064 -236.633766)
			(xy 84.151216 -236.633766)
		)
		(stroke
			(width 0)
			(type solid)
		)
		(fill yes)
		(layer "In2.Cu")
		(net "M_C_CPU1_SA_DQS_DP<2>")
	)
	(gr_poly
		(pts
			(xy 84.151216 -236.182408) (xy 84.151216 -236.137958) (xy 83.951064 -236.137958) (xy 83.951064 -236.182408)
			(xy 84.05114 -236.282484)
		)
		(stroke
			(width 0)
			(type solid)
		)
		(fill yes)
		(layer "In2.Cu")
		(net "M_C_CPU1_SA_DQ<19>")
	)
	(gr_poly
		(pts
			(xy 84.151216 -234.966256) (xy 84.05114 -234.86618) (xy 83.951064 -234.966256) (xy 83.951064 -235.010706)
			(xy 84.151216 -235.010706)
		)
		(stroke
			(width 0)
			(type solid)
		)
		(fill yes)
		(layer "In2.Cu")
		(net "M_C_CPU1_SA_DQ<16>")
	)
	(gr_poly
		(pts
			(xy 84.151216 -234.562396) (xy 84.151216 -234.517946) (xy 83.951064 -234.517946) (xy 83.951064 -234.562396)
			(xy 84.05114 -234.662472)
		)
		(stroke
			(width 0)
			(type solid)
		)
		(fill yes)
		(layer "In2.Cu")
		(net "M_C_CPU1_SA_DQ<15>")
	)
	(gr_poly
		(pts
			(xy 84.151216 -233.346244) (xy 84.05114 -233.246168) (xy 83.951064 -233.346244) (xy 83.951064 -233.390694)
			(xy 84.151216 -233.390694)
		)
		(stroke
			(width 0)
			(type solid)
		)
		(fill yes)
		(layer "In2.Cu")
		(net "M_C_CPU1_SA_DQ<12>")
	)
	(gr_poly
		(pts
			(xy 84.151216 -232.942638) (xy 84.151216 -232.894886) (xy 83.951064 -232.894886) (xy 83.951064 -232.942638)
			(xy 84.05114 -233.04246)
		)
		(stroke
			(width 0)
			(type solid)
		)
		(fill yes)
		(layer "In2.Cu")
		(net "M_C_CPU1_SA_DQS_DP<6>")
	)
	(gr_poly
		(pts
			(xy 84.151216 -231.725978) (xy 84.05114 -231.626156) (xy 83.951064 -231.725978) (xy 83.951064 -231.77373)
			(xy 84.151216 -231.77373)
		)
		(stroke
			(width 0)
			(type solid)
		)
		(fill yes)
		(layer "In2.Cu")
		(net "M_C_CPU1_SA_DQS_DP<1>")
	)
	(gr_poly
		(pts
			(xy 84.151216 -231.322626) (xy 84.151216 -231.278176) (xy 83.951064 -231.278176) (xy 83.951064 -231.322626)
			(xy 84.05114 -231.422702)
		)
		(stroke
			(width 0)
			(type solid)
		)
		(fill yes)
		(layer "In2.Cu")
		(net "M_C_CPU1_SA_DQ<11>")
	)
	(gr_poly
		(pts
			(xy 84.151216 -230.10622) (xy 84.05114 -230.006144) (xy 83.951064 -230.10622) (xy 83.951064 -230.15067)
			(xy 84.151216 -230.15067)
		)
		(stroke
			(width 0)
			(type solid)
		)
		(fill yes)
		(layer "In2.Cu")
		(net "M_C_CPU1_SA_DQ<8>")
	)
	(gr_poly
		(pts
			(xy 84.151216 -229.702614) (xy 84.151216 -229.658164) (xy 83.951064 -229.658164) (xy 83.951064 -229.702614)
			(xy 84.05114 -229.80269)
		)
		(stroke
			(width 0)
			(type solid)
		)
		(fill yes)
		(layer "In2.Cu")
		(net "M_C_CPU1_SA_DQ<7>")
	)
	(gr_poly
		(pts
			(xy 84.151216 -228.486462) (xy 84.05114 -228.386386) (xy 83.951064 -228.486462) (xy 83.951064 -228.530912)
			(xy 84.151216 -228.530912)
		)
		(stroke
			(width 0)
			(type solid)
		)
		(fill yes)
		(layer "In2.Cu")
		(net "M_C_CPU1_SA_DQ<4>")
	)
	(gr_poly
		(pts
			(xy 84.151216 -228.082856) (xy 84.151216 -228.035104) (xy 83.951064 -228.035104) (xy 83.951064 -228.082856)
			(xy 84.05114 -228.182678)
		)
		(stroke
			(width 0)
			(type solid)
		)
		(fill yes)
		(layer "In2.Cu")
		(net "M_C_CPU1_SA_DQS_DP<5>")
	)
	(gr_poly
		(pts
			(xy 84.151216 -226.866196) (xy 84.05114 -226.766374) (xy 83.951064 -226.866196) (xy 83.951064 -226.913948)
			(xy 84.151216 -226.913948)
		)
		(stroke
			(width 0)
			(type solid)
		)
		(fill yes)
		(layer "In2.Cu")
		(net "M_C_CPU1_SA_DQS_DP<0>")
	)
	(gr_poly
		(pts
			(xy 84.151216 -226.46259) (xy 84.151216 -226.41814) (xy 83.951064 -226.41814) (xy 83.951064 -226.46259)
			(xy 84.05114 -226.562666)
		)
		(stroke
			(width 0)
			(type solid)
		)
		(fill yes)
		(layer "In2.Cu")
		(net "M_C_CPU1_SA_DQ<3>")
	)
	(gr_poly
		(pts
			(xy 84.170266 -224.846642) (xy 84.206842 -224.70999) (xy 84.070444 -224.673414) (xy 84.031836 -224.695766)
			(xy 84.131912 -224.868994)
		)
		(stroke
			(width 0)
			(type solid)
		)
		(fill yes)
		(layer "In2.Cu")
		(net "M_C_CPU1_SA_DQ<0>")
	)
	(gr_poly
		(pts
			(xy 84.443824 -291.297868) (xy 84.343748 -291.198046) (xy 84.243926 -291.297868) (xy 84.243926 -291.34562)
			(xy 84.443824 -291.34562)
		)
		(stroke
			(width 0)
			(type solid)
		)
		(fill yes)
		(layer "In2.Cu")
		(net "M_C_CPU1_SB_DQS_DN<8>")
	)
	(gr_poly
		(pts
			(xy 84.44484 -266.991846) (xy 84.344764 -266.89177) (xy 84.244942 -266.991846) (xy 84.244942 -267.036296)
			(xy 84.44484 -267.036296)
		)
		(stroke
			(width 0)
			(type solid)
		)
		(fill yes)
		(layer "In2.Cu")
		(net "M_C_CPU1_SA_RSP<0>")
	)
	(gr_poly
		(pts
			(xy 84.45119 -292.918134) (xy 84.351114 -292.818058) (xy 84.251038 -292.918134) (xy 84.251038 -292.962584)
			(xy 84.45119 -292.962584)
		)
		(stroke
			(width 0)
			(type solid)
		)
		(fill yes)
		(layer "In2.Cu")
		(net "M_C_CPU1_SB_DQ<29>")
	)
	(gr_poly
		(pts
			(xy 84.45119 -292.514274) (xy 84.45119 -292.469824) (xy 84.251038 -292.469824) (xy 84.251038 -292.514274)
			(xy 84.351114 -292.61435)
		)
		(stroke
			(width 0)
			(type solid)
		)
		(fill yes)
		(layer "In2.Cu")
		(net "M_C_CPU1_SB_DQ<30>")
	)
	(gr_poly
		(pts
			(xy 84.45119 -290.894516) (xy 84.45119 -290.846764) (xy 84.251038 -290.846764) (xy 84.251038 -290.894516)
			(xy 84.351114 -290.994338)
		)
		(stroke
			(width 0)
			(type solid)
		)
		(fill yes)
		(layer "In2.Cu")
		(net "M_C_CPU1_SB_DQS_DN<3>")
	)
	(gr_poly
		(pts
			(xy 84.45119 -289.67811) (xy 84.351114 -289.578034) (xy 84.251038 -289.67811) (xy 84.251038 -289.72256)
			(xy 84.45119 -289.72256)
		)
		(stroke
			(width 0)
			(type solid)
		)
		(fill yes)
		(layer "In2.Cu")
		(net "M_C_CPU1_SB_DQ<25>")
	)
	(gr_poly
		(pts
			(xy 84.45119 -289.27425) (xy 84.45119 -289.2298) (xy 84.251038 -289.2298) (xy 84.251038 -289.27425)
			(xy 84.351114 -289.374326)
		)
		(stroke
			(width 0)
			(type solid)
		)
		(fill yes)
		(layer "In2.Cu")
		(net "M_C_CPU1_SB_DQ<26>")
	)
	(gr_poly
		(pts
			(xy 84.45119 -288.058098) (xy 84.351114 -287.958022) (xy 84.251038 -288.058098) (xy 84.251038 -288.102548)
			(xy 84.45119 -288.102548)
		)
		(stroke
			(width 0)
			(type solid)
		)
		(fill yes)
		(layer "In2.Cu")
		(net "M_C_CPU1_SB_DQ<21>")
	)
	(gr_poly
		(pts
			(xy 84.45119 -287.654492) (xy 84.45119 -287.610042) (xy 84.251038 -287.610042) (xy 84.251038 -287.654492)
			(xy 84.351114 -287.754568)
		)
		(stroke
			(width 0)
			(type solid)
		)
		(fill yes)
		(layer "In2.Cu")
		(net "M_C_CPU1_SB_DQ<22>")
	)
	(gr_poly
		(pts
			(xy 84.45119 -286.438086) (xy 84.351114 -286.33801) (xy 84.251038 -286.438086) (xy 84.251038 -286.485838)
			(xy 84.45119 -286.485838)
		)
		(stroke
			(width 0)
			(type solid)
		)
		(fill yes)
		(layer "In2.Cu")
		(net "M_C_CPU1_SB_DQS_DN<7>")
	)
	(gr_poly
		(pts
			(xy 84.45119 -286.034734) (xy 84.45119 -285.986982) (xy 84.251038 -285.986982) (xy 84.251038 -286.034734)
			(xy 84.351114 -286.134556)
		)
		(stroke
			(width 0)
			(type solid)
		)
		(fill yes)
		(layer "In2.Cu")
		(net "M_C_CPU1_SB_DQS_DN<2>")
	)
	(gr_poly
		(pts
			(xy 84.45119 -284.818328) (xy 84.351114 -284.718252) (xy 84.251038 -284.818328) (xy 84.251038 -284.862778)
			(xy 84.45119 -284.862778)
		)
		(stroke
			(width 0)
			(type solid)
		)
		(fill yes)
		(layer "In2.Cu")
		(net "M_C_CPU1_SB_DQ<17>")
	)
	(gr_poly
		(pts
			(xy 84.45119 -284.414468) (xy 84.45119 -284.370018) (xy 84.251038 -284.370018) (xy 84.251038 -284.414468)
			(xy 84.351114 -284.514544)
		)
		(stroke
			(width 0)
			(type solid)
		)
		(fill yes)
		(layer "In2.Cu")
		(net "M_C_CPU1_SB_DQ<18>")
	)
	(gr_poly
		(pts
			(xy 84.45119 -283.198316) (xy 84.351114 -283.09824) (xy 84.251038 -283.198316) (xy 84.251038 -283.242766)
			(xy 84.45119 -283.242766)
		)
		(stroke
			(width 0)
			(type solid)
		)
		(fill yes)
		(layer "In2.Cu")
		(net "M_C_CPU1_SB_DQ<13>")
	)
	(gr_poly
		(pts
			(xy 84.45119 -282.794456) (xy 84.45119 -282.750006) (xy 84.251038 -282.750006) (xy 84.251038 -282.794456)
			(xy 84.351114 -282.894532)
		)
		(stroke
			(width 0)
			(type solid)
		)
		(fill yes)
		(layer "In2.Cu")
		(net "M_C_CPU1_SB_DQ<14>")
	)
	(gr_poly
		(pts
			(xy 84.45119 -281.57805) (xy 84.351114 -281.478228) (xy 84.251038 -281.57805) (xy 84.251038 -281.625802)
			(xy 84.45119 -281.625802)
		)
		(stroke
			(width 0)
			(type solid)
		)
		(fill yes)
		(layer "In2.Cu")
		(net "M_C_CPU1_SB_DQS_DN<6>")
	)
	(gr_poly
		(pts
			(xy 84.45119 -281.174698) (xy 84.45119 -281.126946) (xy 84.251038 -281.126946) (xy 84.251038 -281.174698)
			(xy 84.351114 -281.27452)
		)
		(stroke
			(width 0)
			(type solid)
		)
		(fill yes)
		(layer "In2.Cu")
		(net "M_C_CPU1_SB_DQS_DN<1>")
	)
	(gr_poly
		(pts
			(xy 84.45119 -279.958292) (xy 84.351114 -279.858216) (xy 84.251038 -279.958292) (xy 84.251038 -280.002742)
			(xy 84.45119 -280.002742)
		)
		(stroke
			(width 0)
			(type solid)
		)
		(fill yes)
		(layer "In2.Cu")
		(net "M_C_CPU1_SB_DQ<9>")
	)
	(gr_poly
		(pts
			(xy 84.45119 -279.554432) (xy 84.45119 -279.509982) (xy 84.251038 -279.509982) (xy 84.251038 -279.554432)
			(xy 84.351114 -279.654508)
		)
		(stroke
			(width 0)
			(type solid)
		)
		(fill yes)
		(layer "In2.Cu")
		(net "M_C_CPU1_SB_DQ<10>")
	)
	(gr_poly
		(pts
			(xy 84.45119 -278.33828) (xy 84.351114 -278.238204) (xy 84.251038 -278.33828) (xy 84.251038 -278.38273)
			(xy 84.45119 -278.38273)
		)
		(stroke
			(width 0)
			(type solid)
		)
		(fill yes)
		(layer "In2.Cu")
		(net "M_C_CPU1_SB_DQ<5>")
	)
	(gr_poly
		(pts
			(xy 84.45119 -277.93442) (xy 84.45119 -277.88997) (xy 84.251038 -277.88997) (xy 84.251038 -277.93442)
			(xy 84.351114 -278.034496)
		)
		(stroke
			(width 0)
			(type solid)
		)
		(fill yes)
		(layer "In2.Cu")
		(net "M_C_CPU1_SB_DQ<6>")
	)
	(gr_poly
		(pts
			(xy 84.45119 -276.718014) (xy 84.351114 -276.618192) (xy 84.251038 -276.718014) (xy 84.251038 -276.765766)
			(xy 84.45119 -276.765766)
		)
		(stroke
			(width 0)
			(type solid)
		)
		(fill yes)
		(layer "In2.Cu")
		(net "M_C_CPU1_SB_DQS_DN<5>")
	)
	(gr_poly
		(pts
			(xy 84.45119 -276.314662) (xy 84.45119 -276.26691) (xy 84.251038 -276.26691) (xy 84.251038 -276.314662)
			(xy 84.351114 -276.414484)
		)
		(stroke
			(width 0)
			(type solid)
		)
		(fill yes)
		(layer "In2.Cu")
		(net "M_C_CPU1_SB_DQS_DN<0>")
	)
	(gr_poly
		(pts
			(xy 84.45119 -275.098256) (xy 84.351114 -274.99818) (xy 84.251038 -275.098256) (xy 84.251038 -275.142706)
			(xy 84.45119 -275.142706)
		)
		(stroke
			(width 0)
			(type solid)
		)
		(fill yes)
		(layer "In2.Cu")
		(net "M_C_CPU1_SB_DQ<1>")
	)
	(gr_poly
		(pts
			(xy 84.45119 -274.694396) (xy 84.45119 -274.649946) (xy 84.251038 -274.649946) (xy 84.251038 -274.694396)
			(xy 84.351114 -274.794472)
		)
		(stroke
			(width 0)
			(type solid)
		)
		(fill yes)
		(layer "In2.Cu")
		(net "M_C_CPU1_SB_DQ<2>")
	)
	(gr_poly
		(pts
			(xy 84.45119 -273.478244) (xy 84.351114 -273.378168) (xy 84.251038 -273.478244) (xy 84.251038 -273.522694)
			(xy 84.45119 -273.522694)
		)
		(stroke
			(width 0)
			(type solid)
		)
		(fill yes)
		(layer "In2.Cu")
		(net "M_C_CPU1_SB_CB<1>")
	)
	(gr_poly
		(pts
			(xy 84.45119 -273.074384) (xy 84.45119 -273.029934) (xy 84.251038 -273.029934) (xy 84.251038 -273.074384)
			(xy 84.351114 -273.17446)
		)
		(stroke
			(width 0)
			(type solid)
		)
		(fill yes)
		(layer "In2.Cu")
		(net "M_C_CPU1_SB_CB<2>")
	)
	(gr_poly
		(pts
			(xy 84.45119 -271.857978) (xy 84.351114 -271.758156) (xy 84.251038 -271.857978) (xy 84.251038 -271.90573)
			(xy 84.45119 -271.90573)
		)
		(stroke
			(width 0)
			(type solid)
		)
		(fill yes)
		(layer "In2.Cu")
		(net "M_C_CPU1_SB_DQS_DN<4>")
	)
	(gr_poly
		(pts
			(xy 84.45119 -271.454626) (xy 84.45119 -271.406874) (xy 84.251038 -271.406874) (xy 84.251038 -271.454626)
			(xy 84.351114 -271.554448)
		)
		(stroke
			(width 0)
			(type solid)
		)
		(fill yes)
		(layer "In2.Cu")
		(net "M_C_CPU1_SB_DQS_DN<9>")
	)
	(gr_poly
		(pts
			(xy 84.45119 -270.23822) (xy 84.351114 -270.138144) (xy 84.251038 -270.23822) (xy 84.251038 -270.28267)
			(xy 84.45119 -270.28267)
		)
		(stroke
			(width 0)
			(type solid)
		)
		(fill yes)
		(layer "In2.Cu")
		(net "M_C_CPU1_SB_CB<5>")
	)
	(gr_poly
		(pts
			(xy 84.45119 -269.83436) (xy 84.45119 -269.78991) (xy 84.251038 -269.78991) (xy 84.251038 -269.83436)
			(xy 84.351114 -269.934436)
		)
		(stroke
			(width 0)
			(type solid)
		)
		(fill yes)
		(layer "In2.Cu")
		(net "M_C_CPU1_SB_CB<6>")
	)
	(gr_poly
		(pts
			(xy 84.45119 -266.594336) (xy 84.45119 -266.549886) (xy 84.251038 -266.549886) (xy 84.251038 -266.594336)
			(xy 84.351114 -266.694412)
		)
		(stroke
			(width 0)
			(type solid)
		)
		(fill yes)
		(layer "In2.Cu")
		(net "M_C_CPU1_SB_CS_N<1>")
	)
	(gr_poly
		(pts
			(xy 84.45119 -264.974324) (xy 84.45119 -264.929874) (xy 84.251038 -264.929874) (xy 84.251038 -264.974324)
			(xy 84.351114 -265.0744)
		)
		(stroke
			(width 0)
			(type solid)
		)
		(fill yes)
		(layer "In2.Cu")
		(net "M_C_CPU1_SB_PAR")
	)
	(gr_poly
		(pts
			(xy 84.45119 -263.758172) (xy 84.351114 -263.658096) (xy 84.251038 -263.758172) (xy 84.251038 -263.802622)
			(xy 84.45119 -263.802622)
		)
		(stroke
			(width 0)
			(type solid)
		)
		(fill yes)
		(layer "In2.Cu")
		(net "M_C_CPU1_SB_CA<4>")
	)
	(gr_poly
		(pts
			(xy 84.45119 -263.354312) (xy 84.45119 -263.309862) (xy 84.251038 -263.309862) (xy 84.251038 -263.354312)
			(xy 84.351114 -263.454388)
		)
		(stroke
			(width 0)
			(type solid)
		)
		(fill yes)
		(layer "In2.Cu")
		(net "M_C_CPU1_SB_CA<3>")
	)
	(gr_poly
		(pts
			(xy 84.45119 -262.13816) (xy 84.351114 -262.038084) (xy 84.251038 -262.13816) (xy 84.251038 -262.18261)
			(xy 84.45119 -262.18261)
		)
		(stroke
			(width 0)
			(type solid)
		)
		(fill yes)
		(layer "In2.Cu")
		(net "M_C_CPU1_SB_CA<0>")
	)
	(gr_poly
		(pts
			(xy 84.620862 -246.712486) (xy 84.620862 -246.664988) (xy 84.420964 -246.664988) (xy 84.420964 -246.712486)
			(xy 84.520786 -246.812562)
		)
		(stroke
			(width 0)
			(type solid)
		)
		(fill yes)
		(layer "In2.Cu")
		(net "M_C_CPU1_SA_DQS_DN<4>")
	)
	(gr_poly
		(pts
			(xy 84.621116 -256.432812) (xy 84.621116 -256.38506) (xy 84.420964 -256.38506) (xy 84.420964 -256.432812)
			(xy 84.52104 -256.532634)
		)
		(stroke
			(width 0)
			(type solid)
		)
		(fill yes)
		(layer "In2.Cu")
		(net "M_C_CPU1_CLK_DN<0>")
	)
	(gr_poly
		(pts
			(xy 84.621116 -255.216406) (xy 84.52104 -255.11633) (xy 84.420964 -255.216406) (xy 84.420964 -255.260856)
			(xy 84.621116 -255.260856)
		)
		(stroke
			(width 0)
			(type solid)
		)
		(fill yes)
		(layer "In2.Cu")
		(net "M_C_CPU1_SA_CA<6>")
	)
	(gr_poly
		(pts
			(xy 84.621116 -254.812546) (xy 84.621116 -254.768096) (xy 84.420964 -254.768096) (xy 84.420964 -254.812546)
			(xy 84.52104 -254.912622)
		)
		(stroke
			(width 0)
			(type solid)
		)
		(fill yes)
		(layer "In2.Cu")
		(net "M_C_CPU1_SA_CA<5>")
	)
	(gr_poly
		(pts
			(xy 84.621116 -253.596394) (xy 84.52104 -253.496318) (xy 84.420964 -253.596394) (xy 84.420964 -253.640844)
			(xy 84.621116 -253.640844)
		)
		(stroke
			(width 0)
			(type solid)
		)
		(fill yes)
		(layer "In2.Cu")
		(net "M_C_CPU1_SA_CA<2>")
	)
	(gr_poly
		(pts
			(xy 84.621116 -253.192534) (xy 84.621116 -253.148084) (xy 84.420964 -253.148084) (xy 84.420964 -253.192534)
			(xy 84.52104 -253.29261)
		)
		(stroke
			(width 0)
			(type solid)
		)
		(fill yes)
		(layer "In2.Cu")
		(net "M_C_CPU1_SA_CA<1>")
	)
	(gr_poly
		(pts
			(xy 84.621116 -251.572522) (xy 84.621116 -251.528072) (xy 84.420964 -251.528072) (xy 84.420964 -251.572522)
			(xy 84.52104 -251.672598)
		)
		(stroke
			(width 0)
			(type solid)
		)
		(fill yes)
		(layer "In2.Cu")
		(net "M_C_CPU1_SA_CS_N<0>")
	)
	(gr_poly
		(pts
			(xy 84.621116 -250.35637) (xy 84.52104 -250.256294) (xy 84.420964 -250.35637) (xy 84.420964 -250.40082)
			(xy 84.621116 -250.40082)
		)
		(stroke
			(width 0)
			(type solid)
		)
		(fill yes)
		(layer "In2.Cu")
		(net "M_C_CPU1_ALERT_R_N")
	)
	(gr_poly
		(pts
			(xy 84.621116 -248.736358) (xy 84.52104 -248.636282) (xy 84.420964 -248.736358) (xy 84.420964 -248.780808)
			(xy 84.621116 -248.780808)
		)
		(stroke
			(width 0)
			(type solid)
		)
		(fill yes)
		(layer "In2.Cu")
		(net "M_C_CPU1_SA_CB<5>")
	)
	(gr_poly
		(pts
			(xy 84.621116 -248.332498) (xy 84.621116 -248.288048) (xy 84.420964 -248.288048) (xy 84.420964 -248.332498)
			(xy 84.52104 -248.432574)
		)
		(stroke
			(width 0)
			(type solid)
		)
		(fill yes)
		(layer "In2.Cu")
		(net "M_C_CPU1_SA_CB<6>")
	)
	(gr_poly
		(pts
			(xy 84.621116 -247.116092) (xy 84.52104 -247.01627) (xy 84.420964 -247.116092) (xy 84.420964 -247.163844)
			(xy 84.621116 -247.163844)
		)
		(stroke
			(width 0)
			(type solid)
		)
		(fill yes)
		(layer "In2.Cu")
		(net "M_C_CPU1_SA_DQS_DN<9>")
	)
	(gr_poly
		(pts
			(xy 84.621116 -245.496334) (xy 84.52104 -245.396258) (xy 84.420964 -245.496334) (xy 84.420964 -245.540784)
			(xy 84.621116 -245.540784)
		)
		(stroke
			(width 0)
			(type solid)
		)
		(fill yes)
		(layer "In2.Cu")
		(net "M_C_CPU1_SA_CB<1>")
	)
	(gr_poly
		(pts
			(xy 84.621116 -245.092474) (xy 84.621116 -245.048024) (xy 84.420964 -245.048024) (xy 84.420964 -245.092474)
			(xy 84.52104 -245.19255)
		)
		(stroke
			(width 0)
			(type solid)
		)
		(fill yes)
		(layer "In2.Cu")
		(net "M_C_CPU1_SA_CB<2>")
	)
	(gr_poly
		(pts
			(xy 84.621116 -243.876322) (xy 84.52104 -243.776246) (xy 84.420964 -243.876322) (xy 84.420964 -243.920772)
			(xy 84.621116 -243.920772)
		)
		(stroke
			(width 0)
			(type solid)
		)
		(fill yes)
		(layer "In2.Cu")
		(net "M_C_CPU1_SA_DQ<29>")
	)
	(gr_poly
		(pts
			(xy 84.621116 -243.472462) (xy 84.621116 -243.428012) (xy 84.420964 -243.428012) (xy 84.420964 -243.472462)
			(xy 84.52104 -243.572538)
		)
		(stroke
			(width 0)
			(type solid)
		)
		(fill yes)
		(layer "In2.Cu")
		(net "M_C_CPU1_SA_DQ<30>")
	)
	(gr_poly
		(pts
			(xy 84.621116 -242.256056) (xy 84.52104 -242.156234) (xy 84.420964 -242.256056) (xy 84.420964 -242.303808)
			(xy 84.621116 -242.303808)
		)
		(stroke
			(width 0)
			(type solid)
		)
		(fill yes)
		(layer "In2.Cu")
		(net "M_C_CPU1_SA_DQS_DN<8>")
	)
	(gr_poly
		(pts
			(xy 84.621116 -241.852704) (xy 84.621116 -241.804952) (xy 84.420964 -241.804952) (xy 84.420964 -241.852704)
			(xy 84.52104 -241.952526)
		)
		(stroke
			(width 0)
			(type solid)
		)
		(fill yes)
		(layer "In2.Cu")
		(net "M_C_CPU1_SA_DQS_DN<3>")
	)
	(gr_poly
		(pts
			(xy 84.621116 -240.636298) (xy 84.52104 -240.536222) (xy 84.420964 -240.636298) (xy 84.420964 -240.680748)
			(xy 84.621116 -240.680748)
		)
		(stroke
			(width 0)
			(type solid)
		)
		(fill yes)
		(layer "In2.Cu")
		(net "M_C_CPU1_SA_DQ<25>")
	)
	(gr_poly
		(pts
			(xy 84.621116 -240.232438) (xy 84.621116 -240.187988) (xy 84.420964 -240.187988) (xy 84.420964 -240.232438)
			(xy 84.52104 -240.332514)
		)
		(stroke
			(width 0)
			(type solid)
		)
		(fill yes)
		(layer "In2.Cu")
		(net "M_C_CPU1_SA_DQ<26>")
	)
	(gr_poly
		(pts
			(xy 84.621116 -239.016286) (xy 84.52104 -238.91621) (xy 84.420964 -239.016286) (xy 84.420964 -239.060736)
			(xy 84.621116 -239.060736)
		)
		(stroke
			(width 0)
			(type solid)
		)
		(fill yes)
		(layer "In2.Cu")
		(net "M_C_CPU1_SA_DQ<21>")
	)
	(gr_poly
		(pts
			(xy 84.621116 -238.612426) (xy 84.621116 -238.567976) (xy 84.420964 -238.567976) (xy 84.420964 -238.612426)
			(xy 84.52104 -238.712502)
		)
		(stroke
			(width 0)
			(type solid)
		)
		(fill yes)
		(layer "In2.Cu")
		(net "M_C_CPU1_SA_DQ<22>")
	)
	(gr_poly
		(pts
			(xy 84.621116 -237.39602) (xy 84.52104 -237.296198) (xy 84.420964 -237.39602) (xy 84.420964 -237.443772)
			(xy 84.621116 -237.443772)
		)
		(stroke
			(width 0)
			(type solid)
		)
		(fill yes)
		(layer "In2.Cu")
		(net "M_C_CPU1_SA_DQS_DN<7>")
	)
	(gr_poly
		(pts
			(xy 84.621116 -236.992668) (xy 84.621116 -236.944916) (xy 84.420964 -236.944916) (xy 84.420964 -236.992668)
			(xy 84.52104 -237.09249)
		)
		(stroke
			(width 0)
			(type solid)
		)
		(fill yes)
		(layer "In2.Cu")
		(net "M_C_CPU1_SA_DQS_DN<2>")
	)
	(gr_poly
		(pts
			(xy 84.621116 -235.776262) (xy 84.52104 -235.676186) (xy 84.420964 -235.776262) (xy 84.420964 -235.820712)
			(xy 84.621116 -235.820712)
		)
		(stroke
			(width 0)
			(type solid)
		)
		(fill yes)
		(layer "In2.Cu")
		(net "M_C_CPU1_SA_DQ<17>")
	)
	(gr_poly
		(pts
			(xy 84.621116 -235.372402) (xy 84.621116 -235.327952) (xy 84.420964 -235.327952) (xy 84.420964 -235.372402)
			(xy 84.52104 -235.472478)
		)
		(stroke
			(width 0)
			(type solid)
		)
		(fill yes)
		(layer "In2.Cu")
		(net "M_C_CPU1_SA_DQ<18>")
	)
	(gr_poly
		(pts
			(xy 84.621116 -234.15625) (xy 84.52104 -234.056174) (xy 84.420964 -234.15625) (xy 84.420964 -234.2007)
			(xy 84.621116 -234.2007)
		)
		(stroke
			(width 0)
			(type solid)
		)
		(fill yes)
		(layer "In2.Cu")
		(net "M_C_CPU1_SA_DQ<13>")
	)
	(gr_poly
		(pts
			(xy 84.621116 -233.75239) (xy 84.621116 -233.70794) (xy 84.420964 -233.70794) (xy 84.420964 -233.75239)
			(xy 84.52104 -233.852466)
		)
		(stroke
			(width 0)
			(type solid)
		)
		(fill yes)
		(layer "In2.Cu")
		(net "M_C_CPU1_SA_DQ<14>")
	)
	(gr_poly
		(pts
			(xy 84.621116 -232.535984) (xy 84.52104 -232.436162) (xy 84.420964 -232.535984) (xy 84.420964 -232.583736)
			(xy 84.621116 -232.583736)
		)
		(stroke
			(width 0)
			(type solid)
		)
		(fill yes)
		(layer "In2.Cu")
		(net "M_C_CPU1_SA_DQS_DN<6>")
	)
	(gr_poly
		(pts
			(xy 84.621116 -232.132632) (xy 84.621116 -232.08488) (xy 84.420964 -232.08488) (xy 84.420964 -232.132632)
			(xy 84.52104 -232.232454)
		)
		(stroke
			(width 0)
			(type solid)
		)
		(fill yes)
		(layer "In2.Cu")
		(net "M_C_CPU1_SA_DQS_DN<1>")
	)
	(gr_poly
		(pts
			(xy 84.621116 -230.916226) (xy 84.52104 -230.81615) (xy 84.420964 -230.916226) (xy 84.420964 -230.960676)
			(xy 84.621116 -230.960676)
		)
		(stroke
			(width 0)
			(type solid)
		)
		(fill yes)
		(layer "In2.Cu")
		(net "M_C_CPU1_SA_DQ<9>")
	)
	(gr_poly
		(pts
			(xy 84.621116 -230.51262) (xy 84.621116 -230.46817) (xy 84.420964 -230.46817) (xy 84.420964 -230.51262)
			(xy 84.52104 -230.612696)
		)
		(stroke
			(width 0)
			(type solid)
		)
		(fill yes)
		(layer "In2.Cu")
		(net "M_C_CPU1_SA_DQ<10>")
	)
	(gr_poly
		(pts
			(xy 84.621116 -229.296214) (xy 84.52104 -229.196138) (xy 84.420964 -229.296214) (xy 84.420964 -229.340664)
			(xy 84.621116 -229.340664)
		)
		(stroke
			(width 0)
			(type solid)
		)
		(fill yes)
		(layer "In2.Cu")
		(net "M_C_CPU1_SA_DQ<5>")
	)
	(gr_poly
		(pts
			(xy 84.621116 -228.892608) (xy 84.621116 -228.848158) (xy 84.420964 -228.848158) (xy 84.420964 -228.892608)
			(xy 84.52104 -228.992684)
		)
		(stroke
			(width 0)
			(type solid)
		)
		(fill yes)
		(layer "In2.Cu")
		(net "M_C_CPU1_SA_DQ<6>")
	)
	(gr_poly
		(pts
			(xy 84.621116 -227.676202) (xy 84.52104 -227.57638) (xy 84.420964 -227.676202) (xy 84.420964 -227.723954)
			(xy 84.621116 -227.723954)
		)
		(stroke
			(width 0)
			(type solid)
		)
		(fill yes)
		(layer "In2.Cu")
		(net "M_C_CPU1_SA_DQS_DN<5>")
	)
	(gr_poly
		(pts
			(xy 84.621116 -227.27285) (xy 84.621116 -227.225098) (xy 84.420964 -227.225098) (xy 84.420964 -227.27285)
			(xy 84.52104 -227.372672)
		)
		(stroke
			(width 0)
			(type solid)
		)
		(fill yes)
		(layer "In2.Cu")
		(net "M_C_CPU1_SA_DQS_DN<0>")
	)
	(gr_poly
		(pts
			(xy 84.621116 -226.056444) (xy 84.52104 -225.956368) (xy 84.420964 -226.056444) (xy 84.420964 -226.100894)
			(xy 84.621116 -226.100894)
		)
		(stroke
			(width 0)
			(type solid)
		)
		(fill yes)
		(layer "In2.Cu")
		(net "M_C_CPU1_SA_DQ<1>")
	)
	(gr_poly
		(pts
			(xy 84.621116 -225.652584) (xy 84.621116 -225.608134) (xy 84.420964 -225.608134) (xy 84.420964 -225.652584)
			(xy 84.52104 -225.75266)
		)
		(stroke
			(width 0)
			(type solid)
		)
		(fill yes)
		(layer "In2.Cu")
		(net "M_C_CPU1_SA_DQ<2>")
	)
	(gr_poly
		(pts
			(xy 84.92109 -293.32428) (xy 84.92109 -293.27983) (xy 84.720938 -293.27983) (xy 84.720938 -293.32428)
			(xy 84.821014 -293.424356)
		)
		(stroke
			(width 0)
			(type solid)
		)
		(fill yes)
		(layer "In2.Cu")
		(net "M_C_CPU1_SB_DQ<31>")
	)
	(gr_poly
		(pts
			(xy 84.92109 -292.108128) (xy 84.821014 -292.008052) (xy 84.720938 -292.108128) (xy 84.720938 -292.152578)
			(xy 84.92109 -292.152578)
		)
		(stroke
			(width 0)
			(type solid)
		)
		(fill yes)
		(layer "In2.Cu")
		(net "M_C_CPU1_SB_DQ<28>")
	)
	(gr_poly
		(pts
			(xy 84.92109 -291.704522) (xy 84.92109 -291.65677) (xy 84.720938 -291.65677) (xy 84.720938 -291.704522)
			(xy 84.821014 -291.804344)
		)
		(stroke
			(width 0)
			(type solid)
		)
		(fill yes)
		(layer "In2.Cu")
		(net "M_C_CPU1_SB_DQS_DP<8>")
	)
	(gr_poly
		(pts
			(xy 84.92109 -290.487862) (xy 84.821014 -290.38804) (xy 84.720938 -290.487862) (xy 84.720938 -290.535614)
			(xy 84.92109 -290.535614)
		)
		(stroke
			(width 0)
			(type solid)
		)
		(fill yes)
		(layer "In2.Cu")
		(net "M_C_CPU1_SB_DQS_DP<3>")
	)
	(gr_poly
		(pts
			(xy 84.92109 -290.084256) (xy 84.92109 -290.039806) (xy 84.720938 -290.039806) (xy 84.720938 -290.084256)
			(xy 84.821014 -290.184332)
		)
		(stroke
			(width 0)
			(type solid)
		)
		(fill yes)
		(layer "In2.Cu")
		(net "M_C_CPU1_SB_DQ<27>")
	)
	(gr_poly
		(pts
			(xy 84.92109 -288.868104) (xy 84.821014 -288.768028) (xy 84.720938 -288.868104) (xy 84.720938 -288.912554)
			(xy 84.92109 -288.912554)
		)
		(stroke
			(width 0)
			(type solid)
		)
		(fill yes)
		(layer "In2.Cu")
		(net "M_C_CPU1_SB_DQ<24>")
	)
	(gr_poly
		(pts
			(xy 84.92109 -288.464498) (xy 84.92109 -288.420048) (xy 84.720938 -288.420048) (xy 84.720938 -288.464498)
			(xy 84.821014 -288.564574)
		)
		(stroke
			(width 0)
			(type solid)
		)
		(fill yes)
		(layer "In2.Cu")
		(net "M_C_CPU1_SB_DQ<23>")
	)
	(gr_poly
		(pts
			(xy 84.92109 -287.248092) (xy 84.821014 -287.148016) (xy 84.720938 -287.248092) (xy 84.720938 -287.292542)
			(xy 84.92109 -287.292542)
		)
		(stroke
			(width 0)
			(type solid)
		)
		(fill yes)
		(layer "In2.Cu")
		(net "M_C_CPU1_SB_DQ<20>")
	)
	(gr_poly
		(pts
			(xy 84.92109 -286.844486) (xy 84.92109 -286.796734) (xy 84.720938 -286.796734) (xy 84.720938 -286.844486)
			(xy 84.821014 -286.944562)
		)
		(stroke
			(width 0)
			(type solid)
		)
		(fill yes)
		(layer "In2.Cu")
		(net "M_C_CPU1_SB_DQS_DP<7>")
	)
	(gr_poly
		(pts
			(xy 84.92109 -285.62808) (xy 84.821014 -285.528258) (xy 84.720938 -285.62808) (xy 84.720938 -285.675832)
			(xy 84.92109 -285.675832)
		)
		(stroke
			(width 0)
			(type solid)
		)
		(fill yes)
		(layer "In2.Cu")
		(net "M_C_CPU1_SB_DQS_DP<2>")
	)
	(gr_poly
		(pts
			(xy 84.92109 -285.224474) (xy 84.92109 -285.180024) (xy 84.720938 -285.180024) (xy 84.720938 -285.224474)
			(xy 84.821014 -285.32455)
		)
		(stroke
			(width 0)
			(type solid)
		)
		(fill yes)
		(layer "In2.Cu")
		(net "M_C_CPU1_SB_DQ<19>")
	)
	(gr_poly
		(pts
			(xy 84.92109 -284.008322) (xy 84.821014 -283.908246) (xy 84.720938 -284.008322) (xy 84.720938 -284.052772)
			(xy 84.92109 -284.052772)
		)
		(stroke
			(width 0)
			(type solid)
		)
		(fill yes)
		(layer "In2.Cu")
		(net "M_C_CPU1_SB_DQ<16>")
	)
	(gr_poly
		(pts
			(xy 84.92109 -283.604462) (xy 84.92109 -283.560012) (xy 84.720938 -283.560012) (xy 84.720938 -283.604462)
			(xy 84.821014 -283.704538)
		)
		(stroke
			(width 0)
			(type solid)
		)
		(fill yes)
		(layer "In2.Cu")
		(net "M_C_CPU1_SB_DQ<15>")
	)
	(gr_poly
		(pts
			(xy 84.92109 -282.38831) (xy 84.821014 -282.288234) (xy 84.720938 -282.38831) (xy 84.720938 -282.43276)
			(xy 84.92109 -282.43276)
		)
		(stroke
			(width 0)
			(type solid)
		)
		(fill yes)
		(layer "In2.Cu")
		(net "M_C_CPU1_SB_DQ<12>")
	)
	(gr_poly
		(pts
			(xy 84.92109 -281.984704) (xy 84.92109 -281.936952) (xy 84.720938 -281.936952) (xy 84.720938 -281.984704)
			(xy 84.821014 -282.084526)
		)
		(stroke
			(width 0)
			(type solid)
		)
		(fill yes)
		(layer "In2.Cu")
		(net "M_C_CPU1_SB_DQS_DP<6>")
	)
	(gr_poly
		(pts
			(xy 84.92109 -280.768044) (xy 84.821014 -280.668222) (xy 84.720938 -280.768044) (xy 84.720938 -280.815796)
			(xy 84.92109 -280.815796)
		)
		(stroke
			(width 0)
			(type solid)
		)
		(fill yes)
		(layer "In2.Cu")
		(net "M_C_CPU1_SB_DQS_DP<1>")
	)
	(gr_poly
		(pts
			(xy 84.92109 -280.364438) (xy 84.92109 -280.319988) (xy 84.720938 -280.319988) (xy 84.720938 -280.364438)
			(xy 84.821014 -280.464514)
		)
		(stroke
			(width 0)
			(type solid)
		)
		(fill yes)
		(layer "In2.Cu")
		(net "M_C_CPU1_SB_DQ<11>")
	)
	(gr_poly
		(pts
			(xy 84.92109 -279.148286) (xy 84.821014 -279.04821) (xy 84.720938 -279.148286) (xy 84.720938 -279.192736)
			(xy 84.92109 -279.192736)
		)
		(stroke
			(width 0)
			(type solid)
		)
		(fill yes)
		(layer "In2.Cu")
		(net "M_C_CPU1_SB_DQ<8>")
	)
	(gr_poly
		(pts
			(xy 84.92109 -278.744426) (xy 84.92109 -278.699976) (xy 84.720938 -278.699976) (xy 84.720938 -278.744426)
			(xy 84.821014 -278.844502)
		)
		(stroke
			(width 0)
			(type solid)
		)
		(fill yes)
		(layer "In2.Cu")
		(net "M_C_CPU1_SB_DQ<7>")
	)
	(gr_poly
		(pts
			(xy 84.92109 -277.528274) (xy 84.821014 -277.428198) (xy 84.720938 -277.528274) (xy 84.720938 -277.572724)
			(xy 84.92109 -277.572724)
		)
		(stroke
			(width 0)
			(type solid)
		)
		(fill yes)
		(layer "In2.Cu")
		(net "M_C_CPU1_SB_DQ<4>")
	)
	(gr_poly
		(pts
			(xy 84.92109 -277.124668) (xy 84.92109 -277.076916) (xy 84.720938 -277.076916) (xy 84.720938 -277.124668)
			(xy 84.821014 -277.22449)
		)
		(stroke
			(width 0)
			(type solid)
		)
		(fill yes)
		(layer "In2.Cu")
		(net "M_C_CPU1_SB_DQS_DP<5>")
	)
	(gr_poly
		(pts
			(xy 84.92109 -275.908008) (xy 84.821014 -275.808186) (xy 84.720938 -275.908008) (xy 84.720938 -275.95576)
			(xy 84.92109 -275.95576)
		)
		(stroke
			(width 0)
			(type solid)
		)
		(fill yes)
		(layer "In2.Cu")
		(net "M_C_CPU1_SB_DQS_DP<0>")
	)
	(gr_poly
		(pts
			(xy 84.92109 -275.504402) (xy 84.92109 -275.459952) (xy 84.720938 -275.459952) (xy 84.720938 -275.504402)
			(xy 84.821014 -275.604478)
		)
		(stroke
			(width 0)
			(type solid)
		)
		(fill yes)
		(layer "In2.Cu")
		(net "M_C_CPU1_SB_DQ<3>")
	)
	(gr_poly
		(pts
			(xy 84.92109 -274.28825) (xy 84.821014 -274.188174) (xy 84.720938 -274.28825) (xy 84.720938 -274.3327)
			(xy 84.92109 -274.3327)
		)
		(stroke
			(width 0)
			(type solid)
		)
		(fill yes)
		(layer "In2.Cu")
		(net "M_C_CPU1_SB_DQ<0>")
	)
	(gr_poly
		(pts
			(xy 84.92109 -273.88439) (xy 84.92109 -273.83994) (xy 84.720938 -273.83994) (xy 84.720938 -273.88439)
			(xy 84.821014 -273.984466)
		)
		(stroke
			(width 0)
			(type solid)
		)
		(fill yes)
		(layer "In2.Cu")
		(net "M_C_CPU1_SB_CB<3>")
	)
	(gr_poly
		(pts
			(xy 84.92109 -272.668238) (xy 84.821014 -272.568162) (xy 84.720938 -272.668238) (xy 84.720938 -272.712688)
			(xy 84.92109 -272.712688)
		)
		(stroke
			(width 0)
			(type solid)
		)
		(fill yes)
		(layer "In2.Cu")
		(net "M_C_CPU1_SB_CB<0>")
	)
	(gr_poly
		(pts
			(xy 84.92109 -272.264632) (xy 84.92109 -272.21688) (xy 84.720938 -272.21688) (xy 84.720938 -272.264632)
			(xy 84.821014 -272.364454)
		)
		(stroke
			(width 0)
			(type solid)
		)
		(fill yes)
		(layer "In2.Cu")
		(net "M_C_CPU1_SB_DQS_DP<4>")
	)
	(gr_poly
		(pts
			(xy 84.92109 -271.047972) (xy 84.821014 -270.94815) (xy 84.720938 -271.047972) (xy 84.720938 -271.095724)
			(xy 84.92109 -271.095724)
		)
		(stroke
			(width 0)
			(type solid)
		)
		(fill yes)
		(layer "In2.Cu")
		(net "M_C_CPU1_SB_DQS_DP<9>")
	)
	(gr_poly
		(pts
			(xy 84.92109 -270.644366) (xy 84.92109 -270.599916) (xy 84.720938 -270.599916) (xy 84.720938 -270.644366)
			(xy 84.821014 -270.744442)
		)
		(stroke
			(width 0)
			(type solid)
		)
		(fill yes)
		(layer "In2.Cu")
		(net "M_C_CPU1_SB_CB<7>")
	)
	(gr_poly
		(pts
			(xy 84.92109 -269.428214) (xy 84.821014 -269.328138) (xy 84.720938 -269.428214) (xy 84.720938 -269.472664)
			(xy 84.92109 -269.472664)
		)
		(stroke
			(width 0)
			(type solid)
		)
		(fill yes)
		(layer "In2.Cu")
		(net "M_C_CPU1_SB_CB<4>")
	)
	(gr_poly
		(pts
			(xy 84.92109 -267.801852) (xy 84.821014 -267.701776) (xy 84.720938 -267.801852) (xy 84.720938 -267.846302)
			(xy 84.92109 -267.846302)
		)
		(stroke
			(width 0)
			(type solid)
		)
		(fill yes)
		(layer "In2.Cu")
		(net "M_C_CPU1_SB_RSP<0>")
	)
	(gr_poly
		(pts
			(xy 84.92109 -265.78433) (xy 84.92109 -265.73988) (xy 84.720938 -265.73988) (xy 84.720938 -265.78433)
			(xy 84.821014 -265.884406)
		)
		(stroke
			(width 0)
			(type solid)
		)
		(fill yes)
		(layer "In2.Cu")
		(net "M_C_CPU1_SB_CS_N<0>")
	)
	(gr_poly
		(pts
			(xy 84.92109 -264.568178) (xy 84.821014 -264.468102) (xy 84.720938 -264.568178) (xy 84.720938 -264.612628)
			(xy 84.92109 -264.612628)
		)
		(stroke
			(width 0)
			(type solid)
		)
		(fill yes)
		(layer "In2.Cu")
		(net "M_C_CPU1_SB_CA<6>")
	)
	(gr_poly
		(pts
			(xy 84.92109 -264.164318) (xy 84.92109 -264.119868) (xy 84.720938 -264.119868) (xy 84.720938 -264.164318)
			(xy 84.821014 -264.264394)
		)
		(stroke
			(width 0)
			(type solid)
		)
		(fill yes)
		(layer "In2.Cu")
		(net "M_C_CPU1_SB_CA<5>")
	)
	(gr_poly
		(pts
			(xy 84.92109 -262.948166) (xy 84.821014 -262.84809) (xy 84.720938 -262.948166) (xy 84.720938 -262.992616)
			(xy 84.92109 -262.992616)
		)
		(stroke
			(width 0)
			(type solid)
		)
		(fill yes)
		(layer "In2.Cu")
		(net "M_C_CPU1_SB_CA<2>")
	)
	(gr_poly
		(pts
			(xy 84.92109 -262.544306) (xy 84.92109 -262.499856) (xy 84.720938 -262.499856) (xy 84.720938 -262.544306)
			(xy 84.821014 -262.644382)
		)
		(stroke
			(width 0)
			(type solid)
		)
		(fill yes)
		(layer "In2.Cu")
		(net "M_C_CPU1_SB_CA<1>")
	)
	(gr_poly
		(pts
			(xy 85.091016 -256.026158) (xy 84.99094 -255.926336) (xy 84.890864 -256.026158) (xy 84.890864 -256.07391)
			(xy 85.091016 -256.07391)
		)
		(stroke
			(width 0)
			(type solid)
		)
		(fill yes)
		(layer "In2.Cu")
		(net "M_C_CPU1_CLK_DP<0>")
	)
	(gr_poly
		(pts
			(xy 85.091016 -255.622552) (xy 85.091016 -255.578102) (xy 84.890864 -255.578102) (xy 84.890864 -255.622552)
			(xy 84.99094 -255.722628)
		)
		(stroke
			(width 0)
			(type solid)
		)
		(fill yes)
		(layer "In2.Cu")
		(net "M_C_CPU1_SA_PAR")
	)
	(gr_poly
		(pts
			(xy 85.091016 -254.4064) (xy 84.99094 -254.306324) (xy 84.890864 -254.4064) (xy 84.890864 -254.45085)
			(xy 85.091016 -254.45085)
		)
		(stroke
			(width 0)
			(type solid)
		)
		(fill yes)
		(layer "In2.Cu")
		(net "M_C_CPU1_SA_CA<4>")
	)
	(gr_poly
		(pts
			(xy 85.091016 -254.00254) (xy 85.091016 -253.95809) (xy 84.890864 -253.95809) (xy 84.890864 -254.00254)
			(xy 84.99094 -254.102616)
		)
		(stroke
			(width 0)
			(type solid)
		)
		(fill yes)
		(layer "In2.Cu")
		(net "M_C_CPU1_SA_CA<3>")
	)
	(gr_poly
		(pts
			(xy 85.091016 -252.786388) (xy 84.99094 -252.686312) (xy 84.890864 -252.786388) (xy 84.890864 -252.830838)
			(xy 85.091016 -252.830838)
		)
		(stroke
			(width 0)
			(type solid)
		)
		(fill yes)
		(layer "In2.Cu")
		(net "M_C_CPU1_SA_CA<0>")
	)
	(gr_poly
		(pts
			(xy 85.091016 -252.382528) (xy 85.091016 -252.338078) (xy 84.890864 -252.338078) (xy 84.890864 -252.382528)
			(xy 84.99094 -252.482604)
		)
		(stroke
			(width 0)
			(type solid)
		)
		(fill yes)
		(layer "In2.Cu")
		(net "M_C_CPU1_SA_CS_N<1>")
	)
	(gr_poly
		(pts
			(xy 85.091016 -250.762516) (xy 85.091016 -250.718066) (xy 84.890864 -250.718066) (xy 84.890864 -250.762516)
			(xy 84.99094 -250.862592)
		)
		(stroke
			(width 0)
			(type solid)
		)
		(fill yes)
		(layer "In2.Cu")
		(net "M_C_CPU1_RESET_N")
	)
	(gr_poly
		(pts
			(xy 85.091016 -249.142504) (xy 85.091016 -249.098054) (xy 84.890864 -249.098054) (xy 84.890864 -249.142504)
			(xy 84.99094 -249.24258)
		)
		(stroke
			(width 0)
			(type solid)
		)
		(fill yes)
		(layer "In2.Cu")
		(net "M_C_CPU1_SA_CB<7>")
	)
	(gr_poly
		(pts
			(xy 85.091016 -247.926352) (xy 84.99094 -247.826276) (xy 84.890864 -247.926352) (xy 84.890864 -247.970802)
			(xy 85.091016 -247.970802)
		)
		(stroke
			(width 0)
			(type solid)
		)
		(fill yes)
		(layer "In2.Cu")
		(net "M_C_CPU1_SA_CB<4>")
	)
	(gr_poly
		(pts
			(xy 85.091016 -247.522746) (xy 85.091016 -247.474994) (xy 84.890864 -247.474994) (xy 84.890864 -247.522746)
			(xy 84.99094 -247.622568)
		)
		(stroke
			(width 0)
			(type solid)
		)
		(fill yes)
		(layer "In2.Cu")
		(net "M_C_CPU1_SA_DQS_DP<9>")
	)
	(gr_poly
		(pts
			(xy 85.091016 -246.306086) (xy 84.99094 -246.206264) (xy 84.890864 -246.306086) (xy 84.890864 -246.353838)
			(xy 85.091016 -246.353838)
		)
		(stroke
			(width 0)
			(type solid)
		)
		(fill yes)
		(layer "In2.Cu")
		(net "M_C_CPU1_SA_DQS_DP<4>")
	)
	(gr_poly
		(pts
			(xy 85.091016 -245.90248) (xy 85.091016 -245.85803) (xy 84.890864 -245.85803) (xy 84.890864 -245.90248)
			(xy 84.99094 -246.002556)
		)
		(stroke
			(width 0)
			(type solid)
		)
		(fill yes)
		(layer "In2.Cu")
		(net "M_C_CPU1_SA_CB<3>")
	)
	(gr_poly
		(pts
			(xy 85.091016 -244.686328) (xy 84.99094 -244.586252) (xy 84.890864 -244.686328) (xy 84.890864 -244.730778)
			(xy 85.091016 -244.730778)
		)
		(stroke
			(width 0)
			(type solid)
		)
		(fill yes)
		(layer "In2.Cu")
		(net "M_C_CPU1_SA_CB<0>")
	)
	(gr_poly
		(pts
			(xy 85.091016 -244.282468) (xy 85.091016 -244.238018) (xy 84.890864 -244.238018) (xy 84.890864 -244.282468)
			(xy 84.99094 -244.382544)
		)
		(stroke
			(width 0)
			(type solid)
		)
		(fill yes)
		(layer "In2.Cu")
		(net "M_C_CPU1_SA_DQ<31>")
	)
	(gr_poly
		(pts
			(xy 85.091016 -243.066316) (xy 84.99094 -242.96624) (xy 84.890864 -243.066316) (xy 84.890864 -243.110766)
			(xy 85.091016 -243.110766)
		)
		(stroke
			(width 0)
			(type solid)
		)
		(fill yes)
		(layer "In2.Cu")
		(net "M_C_CPU1_SA_DQ<28>")
	)
	(gr_poly
		(pts
			(xy 85.091016 -242.66271) (xy 85.091016 -242.614958) (xy 84.890864 -242.614958) (xy 84.890864 -242.66271)
			(xy 84.99094 -242.762532)
		)
		(stroke
			(width 0)
			(type solid)
		)
		(fill yes)
		(layer "In2.Cu")
		(net "M_C_CPU1_SA_DQS_DP<8>")
	)
	(gr_poly
		(pts
			(xy 85.091016 -241.44605) (xy 84.99094 -241.346228) (xy 84.890864 -241.44605) (xy 84.890864 -241.493802)
			(xy 85.091016 -241.493802)
		)
		(stroke
			(width 0)
			(type solid)
		)
		(fill yes)
		(layer "In2.Cu")
		(net "M_C_CPU1_SA_DQS_DP<3>")
	)
	(gr_poly
		(pts
			(xy 85.091016 -241.042444) (xy 85.091016 -240.997994) (xy 84.890864 -240.997994) (xy 84.890864 -241.042444)
			(xy 84.99094 -241.14252)
		)
		(stroke
			(width 0)
			(type solid)
		)
		(fill yes)
		(layer "In2.Cu")
		(net "M_C_CPU1_SA_DQ<27>")
	)
	(gr_poly
		(pts
			(xy 85.091016 -239.826292) (xy 84.99094 -239.726216) (xy 84.890864 -239.826292) (xy 84.890864 -239.870742)
			(xy 85.091016 -239.870742)
		)
		(stroke
			(width 0)
			(type solid)
		)
		(fill yes)
		(layer "In2.Cu")
		(net "M_C_CPU1_SA_DQ<24>")
	)
	(gr_poly
		(pts
			(xy 85.091016 -239.422432) (xy 85.091016 -239.377982) (xy 84.890864 -239.377982) (xy 84.890864 -239.422432)
			(xy 84.99094 -239.522508)
		)
		(stroke
			(width 0)
			(type solid)
		)
		(fill yes)
		(layer "In2.Cu")
		(net "M_C_CPU1_SA_DQ<23>")
	)
	(gr_poly
		(pts
			(xy 85.091016 -238.20628) (xy 84.99094 -238.106204) (xy 84.890864 -238.20628) (xy 84.890864 -238.25073)
			(xy 85.091016 -238.25073)
		)
		(stroke
			(width 0)
			(type solid)
		)
		(fill yes)
		(layer "In2.Cu")
		(net "M_C_CPU1_SA_DQ<20>")
	)
	(gr_poly
		(pts
			(xy 85.091016 -237.802674) (xy 85.091016 -237.754922) (xy 84.890864 -237.754922) (xy 84.890864 -237.802674)
			(xy 84.99094 -237.902496)
		)
		(stroke
			(width 0)
			(type solid)
		)
		(fill yes)
		(layer "In2.Cu")
		(net "M_C_CPU1_SA_DQS_DP<7>")
	)
	(gr_poly
		(pts
			(xy 85.091016 -236.586014) (xy 84.99094 -236.486192) (xy 84.890864 -236.586014) (xy 84.890864 -236.633766)
			(xy 85.091016 -236.633766)
		)
		(stroke
			(width 0)
			(type solid)
		)
		(fill yes)
		(layer "In2.Cu")
		(net "M_C_CPU1_SA_DQS_DP<2>")
	)
	(gr_poly
		(pts
			(xy 85.091016 -236.182408) (xy 85.091016 -236.137958) (xy 84.890864 -236.137958) (xy 84.890864 -236.182408)
			(xy 84.99094 -236.282484)
		)
		(stroke
			(width 0)
			(type solid)
		)
		(fill yes)
		(layer "In2.Cu")
		(net "M_C_CPU1_SA_DQ<19>")
	)
	(gr_poly
		(pts
			(xy 85.091016 -234.966256) (xy 84.99094 -234.86618) (xy 84.890864 -234.966256) (xy 84.890864 -235.010706)
			(xy 85.091016 -235.010706)
		)
		(stroke
			(width 0)
			(type solid)
		)
		(fill yes)
		(layer "In2.Cu")
		(net "M_C_CPU1_SA_DQ<16>")
	)
	(gr_poly
		(pts
			(xy 85.091016 -234.562396) (xy 85.091016 -234.517946) (xy 84.890864 -234.517946) (xy 84.890864 -234.562396)
			(xy 84.99094 -234.662472)
		)
		(stroke
			(width 0)
			(type solid)
		)
		(fill yes)
		(layer "In2.Cu")
		(net "M_C_CPU1_SA_DQ<15>")
	)
	(gr_poly
		(pts
			(xy 85.091016 -233.346244) (xy 84.99094 -233.246168) (xy 84.890864 -233.346244) (xy 84.890864 -233.390694)
			(xy 85.091016 -233.390694)
		)
		(stroke
			(width 0)
			(type solid)
		)
		(fill yes)
		(layer "In2.Cu")
		(net "M_C_CPU1_SA_DQ<12>")
	)
	(gr_poly
		(pts
			(xy 85.091016 -232.942638) (xy 85.091016 -232.894886) (xy 84.890864 -232.894886) (xy 84.890864 -232.942638)
			(xy 84.99094 -233.04246)
		)
		(stroke
			(width 0)
			(type solid)
		)
		(fill yes)
		(layer "In2.Cu")
		(net "M_C_CPU1_SA_DQS_DP<6>")
	)
	(gr_poly
		(pts
			(xy 85.091016 -231.725978) (xy 84.99094 -231.626156) (xy 84.890864 -231.725978) (xy 84.890864 -231.77373)
			(xy 85.091016 -231.77373)
		)
		(stroke
			(width 0)
			(type solid)
		)
		(fill yes)
		(layer "In2.Cu")
		(net "M_C_CPU1_SA_DQS_DP<1>")
	)
	(gr_poly
		(pts
			(xy 85.091016 -231.322626) (xy 85.091016 -231.278176) (xy 84.890864 -231.278176) (xy 84.890864 -231.322626)
			(xy 84.99094 -231.422702)
		)
		(stroke
			(width 0)
			(type solid)
		)
		(fill yes)
		(layer "In2.Cu")
		(net "M_C_CPU1_SA_DQ<11>")
	)
	(gr_poly
		(pts
			(xy 85.091016 -230.10622) (xy 84.99094 -230.006144) (xy 84.890864 -230.10622) (xy 84.890864 -230.15067)
			(xy 85.091016 -230.15067)
		)
		(stroke
			(width 0)
			(type solid)
		)
		(fill yes)
		(layer "In2.Cu")
		(net "M_C_CPU1_SA_DQ<8>")
	)
	(gr_poly
		(pts
			(xy 85.091016 -229.702614) (xy 85.091016 -229.658164) (xy 84.890864 -229.658164) (xy 84.890864 -229.702614)
			(xy 84.99094 -229.80269)
		)
		(stroke
			(width 0)
			(type solid)
		)
		(fill yes)
		(layer "In2.Cu")
		(net "M_C_CPU1_SA_DQ<7>")
	)
	(gr_poly
		(pts
			(xy 85.091016 -228.486462) (xy 84.99094 -228.386386) (xy 84.890864 -228.486462) (xy 84.890864 -228.530912)
			(xy 85.091016 -228.530912)
		)
		(stroke
			(width 0)
			(type solid)
		)
		(fill yes)
		(layer "In2.Cu")
		(net "M_C_CPU1_SA_DQ<4>")
	)
	(gr_poly
		(pts
			(xy 85.091016 -228.082856) (xy 85.091016 -228.035104) (xy 84.890864 -228.035104) (xy 84.890864 -228.082856)
			(xy 84.99094 -228.182678)
		)
		(stroke
			(width 0)
			(type solid)
		)
		(fill yes)
		(layer "In2.Cu")
		(net "M_C_CPU1_SA_DQS_DP<5>")
	)
	(gr_poly
		(pts
			(xy 85.091016 -226.866196) (xy 84.99094 -226.766374) (xy 84.890864 -226.866196) (xy 84.890864 -226.913948)
			(xy 85.091016 -226.913948)
		)
		(stroke
			(width 0)
			(type solid)
		)
		(fill yes)
		(layer "In2.Cu")
		(net "M_C_CPU1_SA_DQS_DP<0>")
	)
	(gr_poly
		(pts
			(xy 85.091016 -226.46259) (xy 85.091016 -226.41814) (xy 84.890864 -226.41814) (xy 84.890864 -226.46259)
			(xy 84.99094 -226.562666)
		)
		(stroke
			(width 0)
			(type solid)
		)
		(fill yes)
		(layer "In2.Cu")
		(net "M_C_CPU1_SA_DQ<3>")
	)
	(gr_poly
		(pts
			(xy 85.091016 -225.246438) (xy 84.99094 -225.146362) (xy 84.890864 -225.246438) (xy 84.890864 -225.290888)
			(xy 85.091016 -225.290888)
		)
		(stroke
			(width 0)
			(type solid)
		)
		(fill yes)
		(layer "In2.Cu")
		(net "M_C_CPU1_SA_DQ<0>")
	)
	(gr_poly
		(pts
			(xy 85.39099 -292.918134) (xy 85.290914 -292.818058) (xy 85.190838 -292.918134) (xy 85.190838 -292.962584)
			(xy 85.39099 -292.962584)
		)
		(stroke
			(width 0)
			(type solid)
		)
		(fill yes)
		(layer "In2.Cu")
		(net "M_C_CPU1_SB_DQ<29>")
	)
	(gr_poly
		(pts
			(xy 85.39099 -292.514274) (xy 85.39099 -292.469824) (xy 85.190838 -292.469824) (xy 85.190838 -292.514274)
			(xy 85.290914 -292.61435)
		)
		(stroke
			(width 0)
			(type solid)
		)
		(fill yes)
		(layer "In2.Cu")
		(net "M_C_CPU1_SB_DQ<30>")
	)
	(gr_poly
		(pts
			(xy 85.39099 -290.894516) (xy 85.39099 -290.846764) (xy 85.190838 -290.846764) (xy 85.190838 -290.894516)
			(xy 85.290914 -290.994338)
		)
		(stroke
			(width 0)
			(type solid)
		)
		(fill yes)
		(layer "In2.Cu")
		(net "M_C_CPU1_SB_DQS_DN<3>")
	)
	(gr_poly
		(pts
			(xy 85.39099 -289.67811) (xy 85.290914 -289.578034) (xy 85.190838 -289.67811) (xy 85.190838 -289.72256)
			(xy 85.39099 -289.72256)
		)
		(stroke
			(width 0)
			(type solid)
		)
		(fill yes)
		(layer "In2.Cu")
		(net "M_C_CPU1_SB_DQ<25>")
	)
	(gr_poly
		(pts
			(xy 85.39099 -289.27425) (xy 85.39099 -289.2298) (xy 85.190838 -289.2298) (xy 85.190838 -289.27425)
			(xy 85.290914 -289.374326)
		)
		(stroke
			(width 0)
			(type solid)
		)
		(fill yes)
		(layer "In2.Cu")
		(net "M_C_CPU1_SB_DQ<26>")
	)
	(gr_poly
		(pts
			(xy 85.39099 -288.058098) (xy 85.290914 -287.958022) (xy 85.190838 -288.058098) (xy 85.190838 -288.102548)
			(xy 85.39099 -288.102548)
		)
		(stroke
			(width 0)
			(type solid)
		)
		(fill yes)
		(layer "In2.Cu")
		(net "M_C_CPU1_SB_DQ<21>")
	)
	(gr_poly
		(pts
			(xy 85.39099 -287.654492) (xy 85.39099 -287.610042) (xy 85.190838 -287.610042) (xy 85.190838 -287.654492)
			(xy 85.290914 -287.754568)
		)
		(stroke
			(width 0)
			(type solid)
		)
		(fill yes)
		(layer "In2.Cu")
		(net "M_C_CPU1_SB_DQ<22>")
	)
	(gr_poly
		(pts
			(xy 85.39099 -286.438086) (xy 85.290914 -286.33801) (xy 85.190838 -286.438086) (xy 85.190838 -286.485838)
			(xy 85.39099 -286.485838)
		)
		(stroke
			(width 0)
			(type solid)
		)
		(fill yes)
		(layer "In2.Cu")
		(net "M_C_CPU1_SB_DQS_DN<7>")
	)
	(gr_poly
		(pts
			(xy 85.39099 -286.034734) (xy 85.39099 -285.986982) (xy 85.190838 -285.986982) (xy 85.190838 -286.034734)
			(xy 85.290914 -286.134556)
		)
		(stroke
			(width 0)
			(type solid)
		)
		(fill yes)
		(layer "In2.Cu")
		(net "M_C_CPU1_SB_DQS_DN<2>")
	)
	(gr_poly
		(pts
			(xy 85.39099 -284.818328) (xy 85.290914 -284.718252) (xy 85.190838 -284.818328) (xy 85.190838 -284.862778)
			(xy 85.39099 -284.862778)
		)
		(stroke
			(width 0)
			(type solid)
		)
		(fill yes)
		(layer "In2.Cu")
		(net "M_C_CPU1_SB_DQ<17>")
	)
	(gr_poly
		(pts
			(xy 85.39099 -284.414468) (xy 85.39099 -284.370018) (xy 85.190838 -284.370018) (xy 85.190838 -284.414468)
			(xy 85.290914 -284.514544)
		)
		(stroke
			(width 0)
			(type solid)
		)
		(fill yes)
		(layer "In2.Cu")
		(net "M_C_CPU1_SB_DQ<18>")
	)
	(gr_poly
		(pts
			(xy 85.39099 -283.198316) (xy 85.290914 -283.09824) (xy 85.190838 -283.198316) (xy 85.190838 -283.242766)
			(xy 85.39099 -283.242766)
		)
		(stroke
			(width 0)
			(type solid)
		)
		(fill yes)
		(layer "In2.Cu")
		(net "M_C_CPU1_SB_DQ<13>")
	)
	(gr_poly
		(pts
			(xy 85.39099 -282.794456) (xy 85.39099 -282.750006) (xy 85.190838 -282.750006) (xy 85.190838 -282.794456)
			(xy 85.290914 -282.894532)
		)
		(stroke
			(width 0)
			(type solid)
		)
		(fill yes)
		(layer "In2.Cu")
		(net "M_C_CPU1_SB_DQ<14>")
	)
	(gr_poly
		(pts
			(xy 85.39099 -281.57805) (xy 85.290914 -281.478228) (xy 85.190838 -281.57805) (xy 85.190838 -281.625802)
			(xy 85.39099 -281.625802)
		)
		(stroke
			(width 0)
			(type solid)
		)
		(fill yes)
		(layer "In2.Cu")
		(net "M_C_CPU1_SB_DQS_DN<6>")
	)
	(gr_poly
		(pts
			(xy 85.39099 -281.174698) (xy 85.39099 -281.126946) (xy 85.190838 -281.126946) (xy 85.190838 -281.174698)
			(xy 85.290914 -281.27452)
		)
		(stroke
			(width 0)
			(type solid)
		)
		(fill yes)
		(layer "In2.Cu")
		(net "M_C_CPU1_SB_DQS_DN<1>")
	)
	(gr_poly
		(pts
			(xy 85.39099 -279.958292) (xy 85.290914 -279.858216) (xy 85.190838 -279.958292) (xy 85.190838 -280.002742)
			(xy 85.39099 -280.002742)
		)
		(stroke
			(width 0)
			(type solid)
		)
		(fill yes)
		(layer "In2.Cu")
		(net "M_C_CPU1_SB_DQ<9>")
	)
	(gr_poly
		(pts
			(xy 85.39099 -279.554432) (xy 85.39099 -279.509982) (xy 85.190838 -279.509982) (xy 85.190838 -279.554432)
			(xy 85.290914 -279.654508)
		)
		(stroke
			(width 0)
			(type solid)
		)
		(fill yes)
		(layer "In2.Cu")
		(net "M_C_CPU1_SB_DQ<10>")
	)
	(gr_poly
		(pts
			(xy 85.39099 -278.33828) (xy 85.290914 -278.238204) (xy 85.190838 -278.33828) (xy 85.190838 -278.38273)
			(xy 85.39099 -278.38273)
		)
		(stroke
			(width 0)
			(type solid)
		)
		(fill yes)
		(layer "In2.Cu")
		(net "M_C_CPU1_SB_DQ<5>")
	)
	(gr_poly
		(pts
			(xy 85.39099 -277.93442) (xy 85.39099 -277.88997) (xy 85.190838 -277.88997) (xy 85.190838 -277.93442)
			(xy 85.290914 -278.034496)
		)
		(stroke
			(width 0)
			(type solid)
		)
		(fill yes)
		(layer "In2.Cu")
		(net "M_C_CPU1_SB_DQ<6>")
	)
	(gr_poly
		(pts
			(xy 85.39099 -276.718014) (xy 85.290914 -276.618192) (xy 85.190838 -276.718014) (xy 85.190838 -276.765766)
			(xy 85.39099 -276.765766)
		)
		(stroke
			(width 0)
			(type solid)
		)
		(fill yes)
		(layer "In2.Cu")
		(net "M_C_CPU1_SB_DQS_DN<5>")
	)
	(gr_poly
		(pts
			(xy 85.39099 -276.314662) (xy 85.39099 -276.26691) (xy 85.190838 -276.26691) (xy 85.190838 -276.314662)
			(xy 85.290914 -276.414484)
		)
		(stroke
			(width 0)
			(type solid)
		)
		(fill yes)
		(layer "In2.Cu")
		(net "M_C_CPU1_SB_DQS_DN<0>")
	)
	(gr_poly
		(pts
			(xy 85.39099 -275.098256) (xy 85.290914 -274.99818) (xy 85.190838 -275.098256) (xy 85.190838 -275.142706)
			(xy 85.39099 -275.142706)
		)
		(stroke
			(width 0)
			(type solid)
		)
		(fill yes)
		(layer "In2.Cu")
		(net "M_C_CPU1_SB_DQ<1>")
	)
	(gr_poly
		(pts
			(xy 85.39099 -274.694396) (xy 85.39099 -274.649946) (xy 85.190838 -274.649946) (xy 85.190838 -274.694396)
			(xy 85.290914 -274.794472)
		)
		(stroke
			(width 0)
			(type solid)
		)
		(fill yes)
		(layer "In2.Cu")
		(net "M_C_CPU1_SB_DQ<2>")
	)
	(gr_poly
		(pts
			(xy 85.39099 -273.478244) (xy 85.290914 -273.378168) (xy 85.190838 -273.478244) (xy 85.190838 -273.522694)
			(xy 85.39099 -273.522694)
		)
		(stroke
			(width 0)
			(type solid)
		)
		(fill yes)
		(layer "In2.Cu")
		(net "M_C_CPU1_SB_CB<1>")
	)
	(gr_poly
		(pts
			(xy 85.39099 -273.074384) (xy 85.39099 -273.029934) (xy 85.190838 -273.029934) (xy 85.190838 -273.074384)
			(xy 85.290914 -273.17446)
		)
		(stroke
			(width 0)
			(type solid)
		)
		(fill yes)
		(layer "In2.Cu")
		(net "M_C_CPU1_SB_CB<2>")
	)
	(gr_poly
		(pts
			(xy 85.39099 -271.857978) (xy 85.290914 -271.758156) (xy 85.190838 -271.857978) (xy 85.190838 -271.90573)
			(xy 85.39099 -271.90573)
		)
		(stroke
			(width 0)
			(type solid)
		)
		(fill yes)
		(layer "In2.Cu")
		(net "M_C_CPU1_SB_DQS_DN<4>")
	)
	(gr_poly
		(pts
			(xy 85.39099 -271.454626) (xy 85.39099 -271.406874) (xy 85.190838 -271.406874) (xy 85.190838 -271.454626)
			(xy 85.290914 -271.554448)
		)
		(stroke
			(width 0)
			(type solid)
		)
		(fill yes)
		(layer "In2.Cu")
		(net "M_C_CPU1_SB_DQS_DN<9>")
	)
	(gr_poly
		(pts
			(xy 85.39099 -270.23822) (xy 85.290914 -270.138144) (xy 85.190838 -270.23822) (xy 85.190838 -270.28267)
			(xy 85.39099 -270.28267)
		)
		(stroke
			(width 0)
			(type solid)
		)
		(fill yes)
		(layer "In2.Cu")
		(net "M_C_CPU1_SB_CB<5>")
	)
	(gr_poly
		(pts
			(xy 85.39099 -269.83436) (xy 85.39099 -269.78991) (xy 85.190838 -269.78991) (xy 85.190838 -269.83436)
			(xy 85.290914 -269.934436)
		)
		(stroke
			(width 0)
			(type solid)
		)
		(fill yes)
		(layer "In2.Cu")
		(net "M_C_CPU1_SB_CB<6>")
	)
	(gr_poly
		(pts
			(xy 85.39099 -266.594336) (xy 85.39099 -266.549886) (xy 85.190838 -266.549886) (xy 85.190838 -266.594336)
			(xy 85.290914 -266.694412)
		)
		(stroke
			(width 0)
			(type solid)
		)
		(fill yes)
		(layer "In2.Cu")
		(net "M_C_CPU1_SB_CS_N<1>")
	)
	(gr_poly
		(pts
			(xy 85.39099 -264.974324) (xy 85.39099 -264.929874) (xy 85.190838 -264.929874) (xy 85.190838 -264.974324)
			(xy 85.290914 -265.0744)
		)
		(stroke
			(width 0)
			(type solid)
		)
		(fill yes)
		(layer "In2.Cu")
		(net "M_C_CPU1_SB_PAR")
	)
	(gr_poly
		(pts
			(xy 85.39099 -263.758172) (xy 85.290914 -263.658096) (xy 85.190838 -263.758172) (xy 85.190838 -263.802622)
			(xy 85.39099 -263.802622)
		)
		(stroke
			(width 0)
			(type solid)
		)
		(fill yes)
		(layer "In2.Cu")
		(net "M_C_CPU1_SB_CA<4>")
	)
	(gr_poly
		(pts
			(xy 85.39099 -263.354312) (xy 85.39099 -263.309862) (xy 85.190838 -263.309862) (xy 85.190838 -263.354312)
			(xy 85.290914 -263.454388)
		)
		(stroke
			(width 0)
			(type solid)
		)
		(fill yes)
		(layer "In2.Cu")
		(net "M_C_CPU1_SB_CA<3>")
	)
	(gr_poly
		(pts
			(xy 85.39099 -262.13816) (xy 85.290914 -262.038084) (xy 85.190838 -262.13816) (xy 85.190838 -262.18261)
			(xy 85.39099 -262.18261)
		)
		(stroke
			(width 0)
			(type solid)
		)
		(fill yes)
		(layer "In2.Cu")
		(net "M_C_CPU1_SB_CA<0>")
	)
	(gr_poly
		(pts
			(xy 85.397086 -266.991846) (xy 85.297264 -266.89177) (xy 85.197188 -266.991846) (xy 85.197188 -267.036296)
			(xy 85.397086 -267.036296)
		)
		(stroke
			(width 0)
			(type solid)
		)
		(fill yes)
		(layer "In2.Cu")
		(net "M_C_CPU1_SA_RSP<0>")
	)
	(gr_poly
		(pts
			(xy 85.398102 -291.297868) (xy 85.29828 -291.198046) (xy 85.198204 -291.297868) (xy 85.198204 -291.34562)
			(xy 85.398102 -291.34562)
		)
		(stroke
			(width 0)
			(type solid)
		)
		(fill yes)
		(layer "In2.Cu")
		(net "M_C_CPU1_SB_DQS_DN<8>")
	)
	(gr_poly
		(pts
			(xy 85.560916 -246.712486) (xy 85.560916 -246.664988) (xy 85.361018 -246.664988) (xy 85.361018 -246.712486)
			(xy 85.46084 -246.812562)
		)
		(stroke
			(width 0)
			(type solid)
		)
		(fill yes)
		(layer "In2.Cu")
		(net "M_C_CPU1_SA_DQS_DN<4>")
	)
	(gr_poly
		(pts
			(xy 85.56117 -256.432812) (xy 85.56117 -256.38506) (xy 85.361018 -256.38506) (xy 85.361018 -256.432812)
			(xy 85.461094 -256.532634)
		)
		(stroke
			(width 0)
			(type solid)
		)
		(fill yes)
		(layer "In2.Cu")
		(net "M_C_CPU1_CLK_DN<0>")
	)
	(gr_poly
		(pts
			(xy 85.56117 -255.216406) (xy 85.461094 -255.11633) (xy 85.361018 -255.216406) (xy 85.361018 -255.260856)
			(xy 85.56117 -255.260856)
		)
		(stroke
			(width 0)
			(type solid)
		)
		(fill yes)
		(layer "In2.Cu")
		(net "M_C_CPU1_SA_CA<6>")
	)
	(gr_poly
		(pts
			(xy 85.56117 -254.812546) (xy 85.56117 -254.768096) (xy 85.361018 -254.768096) (xy 85.361018 -254.812546)
			(xy 85.461094 -254.912622)
		)
		(stroke
			(width 0)
			(type solid)
		)
		(fill yes)
		(layer "In2.Cu")
		(net "M_C_CPU1_SA_CA<5>")
	)
	(gr_poly
		(pts
			(xy 85.56117 -253.596394) (xy 85.461094 -253.496318) (xy 85.361018 -253.596394) (xy 85.361018 -253.640844)
			(xy 85.56117 -253.640844)
		)
		(stroke
			(width 0)
			(type solid)
		)
		(fill yes)
		(layer "In2.Cu")
		(net "M_C_CPU1_SA_CA<2>")
	)
	(gr_poly
		(pts
			(xy 85.56117 -253.192534) (xy 85.56117 -253.148084) (xy 85.361018 -253.148084) (xy 85.361018 -253.192534)
			(xy 85.461094 -253.29261)
		)
		(stroke
			(width 0)
			(type solid)
		)
		(fill yes)
		(layer "In2.Cu")
		(net "M_C_CPU1_SA_CA<1>")
	)
	(gr_poly
		(pts
			(xy 85.56117 -251.572522) (xy 85.56117 -251.528072) (xy 85.361018 -251.528072) (xy 85.361018 -251.572522)
			(xy 85.461094 -251.672598)
		)
		(stroke
			(width 0)
			(type solid)
		)
		(fill yes)
		(layer "In2.Cu")
		(net "M_C_CPU1_SA_CS_N<0>")
	)
	(gr_poly
		(pts
			(xy 85.56117 -250.35637) (xy 85.461094 -250.256294) (xy 85.361018 -250.35637) (xy 85.361018 -250.40082)
			(xy 85.56117 -250.40082)
		)
		(stroke
			(width 0)
			(type solid)
		)
		(fill yes)
		(layer "In2.Cu")
		(net "M_C_CPU1_ALERT_R_N")
	)
	(gr_poly
		(pts
			(xy 85.56117 -248.736358) (xy 85.461094 -248.636282) (xy 85.361018 -248.736358) (xy 85.361018 -248.780808)
			(xy 85.56117 -248.780808)
		)
		(stroke
			(width 0)
			(type solid)
		)
		(fill yes)
		(layer "In2.Cu")
		(net "M_C_CPU1_SA_CB<5>")
	)
	(gr_poly
		(pts
			(xy 85.56117 -248.332498) (xy 85.56117 -248.288048) (xy 85.361018 -248.288048) (xy 85.361018 -248.332498)
			(xy 85.461094 -248.432574)
		)
		(stroke
			(width 0)
			(type solid)
		)
		(fill yes)
		(layer "In2.Cu")
		(net "M_C_CPU1_SA_CB<6>")
	)
	(gr_poly
		(pts
			(xy 85.56117 -247.116092) (xy 85.461094 -247.01627) (xy 85.361018 -247.116092) (xy 85.361018 -247.163844)
			(xy 85.56117 -247.163844)
		)
		(stroke
			(width 0)
			(type solid)
		)
		(fill yes)
		(layer "In2.Cu")
		(net "M_C_CPU1_SA_DQS_DN<9>")
	)
	(gr_poly
		(pts
			(xy 85.56117 -245.496334) (xy 85.461094 -245.396258) (xy 85.361018 -245.496334) (xy 85.361018 -245.540784)
			(xy 85.56117 -245.540784)
		)
		(stroke
			(width 0)
			(type solid)
		)
		(fill yes)
		(layer "In2.Cu")
		(net "M_C_CPU1_SA_CB<1>")
	)
	(gr_poly
		(pts
			(xy 85.56117 -245.092474) (xy 85.56117 -245.048024) (xy 85.361018 -245.048024) (xy 85.361018 -245.092474)
			(xy 85.461094 -245.19255)
		)
		(stroke
			(width 0)
			(type solid)
		)
		(fill yes)
		(layer "In2.Cu")
		(net "M_C_CPU1_SA_CB<2>")
	)
	(gr_poly
		(pts
			(xy 85.56117 -243.876322) (xy 85.461094 -243.776246) (xy 85.361018 -243.876322) (xy 85.361018 -243.920772)
			(xy 85.56117 -243.920772)
		)
		(stroke
			(width 0)
			(type solid)
		)
		(fill yes)
		(layer "In2.Cu")
		(net "M_C_CPU1_SA_DQ<29>")
	)
	(gr_poly
		(pts
			(xy 85.56117 -243.472462) (xy 85.56117 -243.428012) (xy 85.361018 -243.428012) (xy 85.361018 -243.472462)
			(xy 85.461094 -243.572538)
		)
		(stroke
			(width 0)
			(type solid)
		)
		(fill yes)
		(layer "In2.Cu")
		(net "M_C_CPU1_SA_DQ<30>")
	)
	(gr_poly
		(pts
			(xy 85.56117 -242.256056) (xy 85.461094 -242.156234) (xy 85.361018 -242.256056) (xy 85.361018 -242.303808)
			(xy 85.56117 -242.303808)
		)
		(stroke
			(width 0)
			(type solid)
		)
		(fill yes)
		(layer "In2.Cu")
		(net "M_C_CPU1_SA_DQS_DN<8>")
	)
	(gr_poly
		(pts
			(xy 85.56117 -241.852704) (xy 85.56117 -241.804952) (xy 85.361018 -241.804952) (xy 85.361018 -241.852704)
			(xy 85.461094 -241.952526)
		)
		(stroke
			(width 0)
			(type solid)
		)
		(fill yes)
		(layer "In2.Cu")
		(net "M_C_CPU1_SA_DQS_DN<3>")
	)
	(gr_poly
		(pts
			(xy 85.56117 -240.636298) (xy 85.461094 -240.536222) (xy 85.361018 -240.636298) (xy 85.361018 -240.680748)
			(xy 85.56117 -240.680748)
		)
		(stroke
			(width 0)
			(type solid)
		)
		(fill yes)
		(layer "In2.Cu")
		(net "M_C_CPU1_SA_DQ<25>")
	)
	(gr_poly
		(pts
			(xy 85.56117 -240.232438) (xy 85.56117 -240.187988) (xy 85.361018 -240.187988) (xy 85.361018 -240.232438)
			(xy 85.461094 -240.332514)
		)
		(stroke
			(width 0)
			(type solid)
		)
		(fill yes)
		(layer "In2.Cu")
		(net "M_C_CPU1_SA_DQ<26>")
	)
	(gr_poly
		(pts
			(xy 85.56117 -239.016286) (xy 85.461094 -238.91621) (xy 85.361018 -239.016286) (xy 85.361018 -239.060736)
			(xy 85.56117 -239.060736)
		)
		(stroke
			(width 0)
			(type solid)
		)
		(fill yes)
		(layer "In2.Cu")
		(net "M_C_CPU1_SA_DQ<21>")
	)
	(gr_poly
		(pts
			(xy 85.56117 -238.612426) (xy 85.56117 -238.567976) (xy 85.361018 -238.567976) (xy 85.361018 -238.612426)
			(xy 85.461094 -238.712502)
		)
		(stroke
			(width 0)
			(type solid)
		)
		(fill yes)
		(layer "In2.Cu")
		(net "M_C_CPU1_SA_DQ<22>")
	)
	(gr_poly
		(pts
			(xy 85.56117 -237.39602) (xy 85.461094 -237.296198) (xy 85.361018 -237.39602) (xy 85.361018 -237.443772)
			(xy 85.56117 -237.443772)
		)
		(stroke
			(width 0)
			(type solid)
		)
		(fill yes)
		(layer "In2.Cu")
		(net "M_C_CPU1_SA_DQS_DN<7>")
	)
	(gr_poly
		(pts
			(xy 85.56117 -236.992668) (xy 85.56117 -236.944916) (xy 85.361018 -236.944916) (xy 85.361018 -236.992668)
			(xy 85.461094 -237.09249)
		)
		(stroke
			(width 0)
			(type solid)
		)
		(fill yes)
		(layer "In2.Cu")
		(net "M_C_CPU1_SA_DQS_DN<2>")
	)
	(gr_poly
		(pts
			(xy 85.56117 -235.776262) (xy 85.461094 -235.676186) (xy 85.361018 -235.776262) (xy 85.361018 -235.820712)
			(xy 85.56117 -235.820712)
		)
		(stroke
			(width 0)
			(type solid)
		)
		(fill yes)
		(layer "In2.Cu")
		(net "M_C_CPU1_SA_DQ<17>")
	)
	(gr_poly
		(pts
			(xy 85.56117 -235.372402) (xy 85.56117 -235.327952) (xy 85.361018 -235.327952) (xy 85.361018 -235.372402)
			(xy 85.461094 -235.472478)
		)
		(stroke
			(width 0)
			(type solid)
		)
		(fill yes)
		(layer "In2.Cu")
		(net "M_C_CPU1_SA_DQ<18>")
	)
	(gr_poly
		(pts
			(xy 85.56117 -234.15625) (xy 85.461094 -234.056174) (xy 85.361018 -234.15625) (xy 85.361018 -234.2007)
			(xy 85.56117 -234.2007)
		)
		(stroke
			(width 0)
			(type solid)
		)
		(fill yes)
		(layer "In2.Cu")
		(net "M_C_CPU1_SA_DQ<13>")
	)
	(gr_poly
		(pts
			(xy 85.56117 -233.75239) (xy 85.56117 -233.70794) (xy 85.361018 -233.70794) (xy 85.361018 -233.75239)
			(xy 85.461094 -233.852466)
		)
		(stroke
			(width 0)
			(type solid)
		)
		(fill yes)
		(layer "In2.Cu")
		(net "M_C_CPU1_SA_DQ<14>")
	)
	(gr_poly
		(pts
			(xy 85.56117 -232.535984) (xy 85.461094 -232.436162) (xy 85.361018 -232.535984) (xy 85.361018 -232.583736)
			(xy 85.56117 -232.583736)
		)
		(stroke
			(width 0)
			(type solid)
		)
		(fill yes)
		(layer "In2.Cu")
		(net "M_C_CPU1_SA_DQS_DN<6>")
	)
	(gr_poly
		(pts
			(xy 85.56117 -232.132632) (xy 85.56117 -232.08488) (xy 85.361018 -232.08488) (xy 85.361018 -232.132632)
			(xy 85.461094 -232.232454)
		)
		(stroke
			(width 0)
			(type solid)
		)
		(fill yes)
		(layer "In2.Cu")
		(net "M_C_CPU1_SA_DQS_DN<1>")
	)
	(gr_poly
		(pts
			(xy 85.56117 -230.916226) (xy 85.461094 -230.81615) (xy 85.361018 -230.916226) (xy 85.361018 -230.960676)
			(xy 85.56117 -230.960676)
		)
		(stroke
			(width 0)
			(type solid)
		)
		(fill yes)
		(layer "In2.Cu")
		(net "M_C_CPU1_SA_DQ<9>")
	)
	(gr_poly
		(pts
			(xy 85.56117 -230.51262) (xy 85.56117 -230.46817) (xy 85.361018 -230.46817) (xy 85.361018 -230.51262)
			(xy 85.461094 -230.612696)
		)
		(stroke
			(width 0)
			(type solid)
		)
		(fill yes)
		(layer "In2.Cu")
		(net "M_C_CPU1_SA_DQ<10>")
	)
	(gr_poly
		(pts
			(xy 85.56117 -229.296214) (xy 85.461094 -229.196138) (xy 85.361018 -229.296214) (xy 85.361018 -229.340664)
			(xy 85.56117 -229.340664)
		)
		(stroke
			(width 0)
			(type solid)
		)
		(fill yes)
		(layer "In2.Cu")
		(net "M_C_CPU1_SA_DQ<5>")
	)
	(gr_poly
		(pts
			(xy 85.56117 -228.892608) (xy 85.56117 -228.848158) (xy 85.361018 -228.848158) (xy 85.361018 -228.892608)
			(xy 85.461094 -228.992684)
		)
		(stroke
			(width 0)
			(type solid)
		)
		(fill yes)
		(layer "In2.Cu")
		(net "M_C_CPU1_SA_DQ<6>")
	)
	(gr_poly
		(pts
			(xy 85.56117 -227.676202) (xy 85.461094 -227.57638) (xy 85.361018 -227.676202) (xy 85.361018 -227.723954)
			(xy 85.56117 -227.723954)
		)
		(stroke
			(width 0)
			(type solid)
		)
		(fill yes)
		(layer "In2.Cu")
		(net "M_C_CPU1_SA_DQS_DN<5>")
	)
	(gr_poly
		(pts
			(xy 85.56117 -227.27285) (xy 85.56117 -227.225098) (xy 85.361018 -227.225098) (xy 85.361018 -227.27285)
			(xy 85.461094 -227.372672)
		)
		(stroke
			(width 0)
			(type solid)
		)
		(fill yes)
		(layer "In2.Cu")
		(net "M_C_CPU1_SA_DQS_DN<0>")
	)
	(gr_poly
		(pts
			(xy 85.56117 -226.056444) (xy 85.461094 -225.956368) (xy 85.361018 -226.056444) (xy 85.361018 -226.100894)
			(xy 85.56117 -226.100894)
		)
		(stroke
			(width 0)
			(type solid)
		)
		(fill yes)
		(layer "In2.Cu")
		(net "M_C_CPU1_SA_DQ<1>")
	)
	(gr_poly
		(pts
			(xy 85.56117 -225.652584) (xy 85.56117 -225.608134) (xy 85.361018 -225.608134) (xy 85.361018 -225.652584)
			(xy 85.461094 -225.75266)
		)
		(stroke
			(width 0)
			(type solid)
		)
		(fill yes)
		(layer "In2.Cu")
		(net "M_C_CPU1_SA_DQ<2>")
	)
	(gr_poly
		(pts
			(xy 85.853778 -291.704268) (xy 85.853778 -291.65677) (xy 85.653626 -291.65677) (xy 85.653626 -291.704268)
			(xy 85.753702 -291.804344)
		)
		(stroke
			(width 0)
			(type solid)
		)
		(fill yes)
		(layer "In2.Cu")
		(net "M_C_CPU1_SB_DQS_DP<8>")
	)
	(gr_poly
		(pts
			(xy 85.854794 -267.801852) (xy 85.754718 -267.701776) (xy 85.654896 -267.801852) (xy 85.654896 -267.846302)
			(xy 85.854794 -267.846302)
		)
		(stroke
			(width 0)
			(type solid)
		)
		(fill yes)
		(layer "In2.Cu")
		(net "M_C_CPU1_SB_RSP<0>")
	)
	(gr_poly
		(pts
			(xy 85.861144 -293.32428) (xy 85.861144 -293.27983) (xy 85.660992 -293.27983) (xy 85.660992 -293.32428)
			(xy 85.761068 -293.424356)
		)
		(stroke
			(width 0)
			(type solid)
		)
		(fill yes)
		(layer "In2.Cu")
		(net "M_C_CPU1_SB_DQ<31>")
	)
	(gr_poly
		(pts
			(xy 85.861144 -292.108128) (xy 85.761068 -292.008052) (xy 85.660992 -292.108128) (xy 85.660992 -292.152578)
			(xy 85.861144 -292.152578)
		)
		(stroke
			(width 0)
			(type solid)
		)
		(fill yes)
		(layer "In2.Cu")
		(net "M_C_CPU1_SB_DQ<28>")
	)
	(gr_poly
		(pts
			(xy 85.861144 -290.487862) (xy 85.761068 -290.38804) (xy 85.660992 -290.487862) (xy 85.660992 -290.535614)
			(xy 85.861144 -290.535614)
		)
		(stroke
			(width 0)
			(type solid)
		)
		(fill yes)
		(layer "In2.Cu")
		(net "M_C_CPU1_SB_DQS_DP<3>")
	)
	(gr_poly
		(pts
			(xy 85.861144 -290.084256) (xy 85.861144 -290.039806) (xy 85.660992 -290.039806) (xy 85.660992 -290.084256)
			(xy 85.761068 -290.184332)
		)
		(stroke
			(width 0)
			(type solid)
		)
		(fill yes)
		(layer "In2.Cu")
		(net "M_C_CPU1_SB_DQ<27>")
	)
	(gr_poly
		(pts
			(xy 85.861144 -288.868104) (xy 85.761068 -288.768028) (xy 85.660992 -288.868104) (xy 85.660992 -288.912554)
			(xy 85.861144 -288.912554)
		)
		(stroke
			(width 0)
			(type solid)
		)
		(fill yes)
		(layer "In2.Cu")
		(net "M_C_CPU1_SB_DQ<24>")
	)
	(gr_poly
		(pts
			(xy 85.861144 -288.464498) (xy 85.861144 -288.420048) (xy 85.660992 -288.420048) (xy 85.660992 -288.464498)
			(xy 85.761068 -288.564574)
		)
		(stroke
			(width 0)
			(type solid)
		)
		(fill yes)
		(layer "In2.Cu")
		(net "M_C_CPU1_SB_DQ<23>")
	)
	(gr_poly
		(pts
			(xy 85.861144 -287.248092) (xy 85.761068 -287.148016) (xy 85.660992 -287.248092) (xy 85.660992 -287.292542)
			(xy 85.861144 -287.292542)
		)
		(stroke
			(width 0)
			(type solid)
		)
		(fill yes)
		(layer "In2.Cu")
		(net "M_C_CPU1_SB_DQ<20>")
	)
	(gr_poly
		(pts
			(xy 85.861144 -286.844486) (xy 85.861144 -286.796734) (xy 85.660992 -286.796734) (xy 85.660992 -286.844486)
			(xy 85.761068 -286.944562)
		)
		(stroke
			(width 0)
			(type solid)
		)
		(fill yes)
		(layer "In2.Cu")
		(net "M_C_CPU1_SB_DQS_DP<7>")
	)
	(gr_poly
		(pts
			(xy 85.861144 -285.62808) (xy 85.761068 -285.528258) (xy 85.660992 -285.62808) (xy 85.660992 -285.675832)
			(xy 85.861144 -285.675832)
		)
		(stroke
			(width 0)
			(type solid)
		)
		(fill yes)
		(layer "In2.Cu")
		(net "M_C_CPU1_SB_DQS_DP<2>")
	)
	(gr_poly
		(pts
			(xy 85.861144 -285.224474) (xy 85.861144 -285.180024) (xy 85.660992 -285.180024) (xy 85.660992 -285.224474)
			(xy 85.761068 -285.32455)
		)
		(stroke
			(width 0)
			(type solid)
		)
		(fill yes)
		(layer "In2.Cu")
		(net "M_C_CPU1_SB_DQ<19>")
	)
	(gr_poly
		(pts
			(xy 85.861144 -284.008322) (xy 85.761068 -283.908246) (xy 85.660992 -284.008322) (xy 85.660992 -284.052772)
			(xy 85.861144 -284.052772)
		)
		(stroke
			(width 0)
			(type solid)
		)
		(fill yes)
		(layer "In2.Cu")
		(net "M_C_CPU1_SB_DQ<16>")
	)
	(gr_poly
		(pts
			(xy 85.861144 -283.604462) (xy 85.861144 -283.560012) (xy 85.660992 -283.560012) (xy 85.660992 -283.604462)
			(xy 85.761068 -283.704538)
		)
		(stroke
			(width 0)
			(type solid)
		)
		(fill yes)
		(layer "In2.Cu")
		(net "M_C_CPU1_SB_DQ<15>")
	)
	(gr_poly
		(pts
			(xy 85.861144 -282.38831) (xy 85.761068 -282.288234) (xy 85.660992 -282.38831) (xy 85.660992 -282.43276)
			(xy 85.861144 -282.43276)
		)
		(stroke
			(width 0)
			(type solid)
		)
		(fill yes)
		(layer "In2.Cu")
		(net "M_C_CPU1_SB_DQ<12>")
	)
	(gr_poly
		(pts
			(xy 85.861144 -281.984704) (xy 85.861144 -281.936952) (xy 85.660992 -281.936952) (xy 85.660992 -281.984704)
			(xy 85.761068 -282.084526)
		)
		(stroke
			(width 0)
			(type solid)
		)
		(fill yes)
		(layer "In2.Cu")
		(net "M_C_CPU1_SB_DQS_DP<6>")
	)
	(gr_poly
		(pts
			(xy 85.861144 -280.768044) (xy 85.761068 -280.668222) (xy 85.660992 -280.768044) (xy 85.660992 -280.815796)
			(xy 85.861144 -280.815796)
		)
		(stroke
			(width 0)
			(type solid)
		)
		(fill yes)
		(layer "In2.Cu")
		(net "M_C_CPU1_SB_DQS_DP<1>")
	)
	(gr_poly
		(pts
			(xy 85.861144 -280.364438) (xy 85.861144 -280.319988) (xy 85.660992 -280.319988) (xy 85.660992 -280.364438)
			(xy 85.761068 -280.464514)
		)
		(stroke
			(width 0)
			(type solid)
		)
		(fill yes)
		(layer "In2.Cu")
		(net "M_C_CPU1_SB_DQ<11>")
	)
	(gr_poly
		(pts
			(xy 85.861144 -279.148286) (xy 85.761068 -279.04821) (xy 85.660992 -279.148286) (xy 85.660992 -279.192736)
			(xy 85.861144 -279.192736)
		)
		(stroke
			(width 0)
			(type solid)
		)
		(fill yes)
		(layer "In2.Cu")
		(net "M_C_CPU1_SB_DQ<8>")
	)
	(gr_poly
		(pts
			(xy 85.861144 -278.744426) (xy 85.861144 -278.699976) (xy 85.660992 -278.699976) (xy 85.660992 -278.744426)
			(xy 85.761068 -278.844502)
		)
		(stroke
			(width 0)
			(type solid)
		)
		(fill yes)
		(layer "In2.Cu")
		(net "M_C_CPU1_SB_DQ<7>")
	)
	(gr_poly
		(pts
			(xy 85.861144 -277.528274) (xy 85.761068 -277.428198) (xy 85.660992 -277.528274) (xy 85.660992 -277.572724)
			(xy 85.861144 -277.572724)
		)
		(stroke
			(width 0)
			(type solid)
		)
		(fill yes)
		(layer "In2.Cu")
		(net "M_C_CPU1_SB_DQ<4>")
	)
	(gr_poly
		(pts
			(xy 85.861144 -277.124668) (xy 85.861144 -277.076916) (xy 85.660992 -277.076916) (xy 85.660992 -277.124668)
			(xy 85.761068 -277.22449)
		)
		(stroke
			(width 0)
			(type solid)
		)
		(fill yes)
		(layer "In2.Cu")
		(net "M_C_CPU1_SB_DQS_DP<5>")
	)
	(gr_poly
		(pts
			(xy 85.861144 -275.908008) (xy 85.761068 -275.808186) (xy 85.660992 -275.908008) (xy 85.660992 -275.95576)
			(xy 85.861144 -275.95576)
		)
		(stroke
			(width 0)
			(type solid)
		)
		(fill yes)
		(layer "In2.Cu")
		(net "M_C_CPU1_SB_DQS_DP<0>")
	)
	(gr_poly
		(pts
			(xy 85.861144 -275.504402) (xy 85.861144 -275.459952) (xy 85.660992 -275.459952) (xy 85.660992 -275.504402)
			(xy 85.761068 -275.604478)
		)
		(stroke
			(width 0)
			(type solid)
		)
		(fill yes)
		(layer "In2.Cu")
		(net "M_C_CPU1_SB_DQ<3>")
	)
	(gr_poly
		(pts
			(xy 85.861144 -274.28825) (xy 85.761068 -274.188174) (xy 85.660992 -274.28825) (xy 85.660992 -274.3327)
			(xy 85.861144 -274.3327)
		)
		(stroke
			(width 0)
			(type solid)
		)
		(fill yes)
		(layer "In2.Cu")
		(net "M_C_CPU1_SB_DQ<0>")
	)
	(gr_poly
		(pts
			(xy 85.861144 -273.88439) (xy 85.861144 -273.83994) (xy 85.660992 -273.83994) (xy 85.660992 -273.88439)
			(xy 85.761068 -273.984466)
		)
		(stroke
			(width 0)
			(type solid)
		)
		(fill yes)
		(layer "In2.Cu")
		(net "M_C_CPU1_SB_CB<3>")
	)
	(gr_poly
		(pts
			(xy 85.861144 -272.668238) (xy 85.761068 -272.568162) (xy 85.660992 -272.668238) (xy 85.660992 -272.712688)
			(xy 85.861144 -272.712688)
		)
		(stroke
			(width 0)
			(type solid)
		)
		(fill yes)
		(layer "In2.Cu")
		(net "M_C_CPU1_SB_CB<0>")
	)
	(gr_poly
		(pts
			(xy 85.861144 -272.264632) (xy 85.861144 -272.21688) (xy 85.660992 -272.21688) (xy 85.660992 -272.264632)
			(xy 85.761068 -272.364454)
		)
		(stroke
			(width 0)
			(type solid)
		)
		(fill yes)
		(layer "In2.Cu")
		(net "M_C_CPU1_SB_DQS_DP<4>")
	)
	(gr_poly
		(pts
			(xy 85.861144 -271.047972) (xy 85.761068 -270.94815) (xy 85.660992 -271.047972) (xy 85.660992 -271.095724)
			(xy 85.861144 -271.095724)
		)
		(stroke
			(width 0)
			(type solid)
		)
		(fill yes)
		(layer "In2.Cu")
		(net "M_C_CPU1_SB_DQS_DP<9>")
	)
	(gr_poly
		(pts
			(xy 85.861144 -270.644366) (xy 85.861144 -270.599916) (xy 85.660992 -270.599916) (xy 85.660992 -270.644366)
			(xy 85.761068 -270.744442)
		)
		(stroke
			(width 0)
			(type solid)
		)
		(fill yes)
		(layer "In2.Cu")
		(net "M_C_CPU1_SB_CB<7>")
	)
	(gr_poly
		(pts
			(xy 85.861144 -269.428214) (xy 85.761068 -269.328138) (xy 85.660992 -269.428214) (xy 85.660992 -269.472664)
			(xy 85.861144 -269.472664)
		)
		(stroke
			(width 0)
			(type solid)
		)
		(fill yes)
		(layer "In2.Cu")
		(net "M_C_CPU1_SB_CB<4>")
	)
	(gr_poly
		(pts
			(xy 85.861144 -265.78433) (xy 85.861144 -265.73988) (xy 85.660992 -265.73988) (xy 85.660992 -265.78433)
			(xy 85.761068 -265.884406)
		)
		(stroke
			(width 0)
			(type solid)
		)
		(fill yes)
		(layer "In2.Cu")
		(net "M_C_CPU1_SB_CS_N<0>")
	)
	(gr_poly
		(pts
			(xy 85.861144 -264.568178) (xy 85.761068 -264.468102) (xy 85.660992 -264.568178) (xy 85.660992 -264.612628)
			(xy 85.861144 -264.612628)
		)
		(stroke
			(width 0)
			(type solid)
		)
		(fill yes)
		(layer "In2.Cu")
		(net "M_C_CPU1_SB_CA<6>")
	)
	(gr_poly
		(pts
			(xy 85.861144 -264.164318) (xy 85.861144 -264.119868) (xy 85.660992 -264.119868) (xy 85.660992 -264.164318)
			(xy 85.761068 -264.264394)
		)
		(stroke
			(width 0)
			(type solid)
		)
		(fill yes)
		(layer "In2.Cu")
		(net "M_C_CPU1_SB_CA<5>")
	)
	(gr_poly
		(pts
			(xy 85.861144 -262.948166) (xy 85.761068 -262.84809) (xy 85.660992 -262.948166) (xy 85.660992 -262.992616)
			(xy 85.861144 -262.992616)
		)
		(stroke
			(width 0)
			(type solid)
		)
		(fill yes)
		(layer "In2.Cu")
		(net "M_C_CPU1_SB_CA<2>")
	)
	(gr_poly
		(pts
			(xy 85.861144 -262.544306) (xy 85.861144 -262.499856) (xy 85.660992 -262.499856) (xy 85.660992 -262.544306)
			(xy 85.761068 -262.644382)
		)
		(stroke
			(width 0)
			(type solid)
		)
		(fill yes)
		(layer "In2.Cu")
		(net "M_C_CPU1_SB_CA<1>")
	)
	(gr_poly
		(pts
			(xy 86.03107 -256.026158) (xy 85.930994 -255.926336) (xy 85.830918 -256.026158) (xy 85.830918 -256.07391)
			(xy 86.03107 -256.07391)
		)
		(stroke
			(width 0)
			(type solid)
		)
		(fill yes)
		(layer "In2.Cu")
		(net "M_C_CPU1_CLK_DP<0>")
	)
	(gr_poly
		(pts
			(xy 86.03107 -255.622552) (xy 86.03107 -255.578102) (xy 85.830918 -255.578102) (xy 85.830918 -255.622552)
			(xy 85.930994 -255.722628)
		)
		(stroke
			(width 0)
			(type solid)
		)
		(fill yes)
		(layer "In2.Cu")
		(net "M_C_CPU1_SA_PAR")
	)
	(gr_poly
		(pts
			(xy 86.03107 -254.4064) (xy 85.930994 -254.306324) (xy 85.830918 -254.4064) (xy 85.830918 -254.45085)
			(xy 86.03107 -254.45085)
		)
		(stroke
			(width 0)
			(type solid)
		)
		(fill yes)
		(layer "In2.Cu")
		(net "M_C_CPU1_SA_CA<4>")
	)
	(gr_poly
		(pts
			(xy 86.03107 -254.00254) (xy 86.03107 -253.95809) (xy 85.830918 -253.95809) (xy 85.830918 -254.00254)
			(xy 85.930994 -254.102616)
		)
		(stroke
			(width 0)
			(type solid)
		)
		(fill yes)
		(layer "In2.Cu")
		(net "M_C_CPU1_SA_CA<3>")
	)
	(gr_poly
		(pts
			(xy 86.03107 -252.786388) (xy 85.930994 -252.686312) (xy 85.830918 -252.786388) (xy 85.830918 -252.830838)
			(xy 86.03107 -252.830838)
		)
		(stroke
			(width 0)
			(type solid)
		)
		(fill yes)
		(layer "In2.Cu")
		(net "M_C_CPU1_SA_CA<0>")
	)
	(gr_poly
		(pts
			(xy 86.03107 -252.382528) (xy 86.03107 -252.338078) (xy 85.830918 -252.338078) (xy 85.830918 -252.382528)
			(xy 85.930994 -252.482604)
		)
		(stroke
			(width 0)
			(type solid)
		)
		(fill yes)
		(layer "In2.Cu")
		(net "M_C_CPU1_SA_CS_N<1>")
	)
	(gr_poly
		(pts
			(xy 86.03107 -250.762516) (xy 86.03107 -250.718066) (xy 85.830918 -250.718066) (xy 85.830918 -250.762516)
			(xy 85.930994 -250.862592)
		)
		(stroke
			(width 0)
			(type solid)
		)
		(fill yes)
		(layer "In2.Cu")
		(net "M_C_CPU1_RESET_N")
	)
	(gr_poly
		(pts
			(xy 86.03107 -249.142504) (xy 86.03107 -249.098054) (xy 85.830918 -249.098054) (xy 85.830918 -249.142504)
			(xy 85.930994 -249.24258)
		)
		(stroke
			(width 0)
			(type solid)
		)
		(fill yes)
		(layer "In2.Cu")
		(net "M_C_CPU1_SA_CB<7>")
	)
	(gr_poly
		(pts
			(xy 86.03107 -247.926352) (xy 85.930994 -247.826276) (xy 85.830918 -247.926352) (xy 85.830918 -247.970802)
			(xy 86.03107 -247.970802)
		)
		(stroke
			(width 0)
			(type solid)
		)
		(fill yes)
		(layer "In2.Cu")
		(net "M_C_CPU1_SA_CB<4>")
	)
	(gr_poly
		(pts
			(xy 86.03107 -247.522746) (xy 86.03107 -247.474994) (xy 85.830918 -247.474994) (xy 85.830918 -247.522746)
			(xy 85.930994 -247.622568)
		)
		(stroke
			(width 0)
			(type solid)
		)
		(fill yes)
		(layer "In2.Cu")
		(net "M_C_CPU1_SA_DQS_DP<9>")
	)
	(gr_poly
		(pts
			(xy 86.03107 -246.306086) (xy 85.930994 -246.206264) (xy 85.830918 -246.306086) (xy 85.830918 -246.353838)
			(xy 86.03107 -246.353838)
		)
		(stroke
			(width 0)
			(type solid)
		)
		(fill yes)
		(layer "In2.Cu")
		(net "M_C_CPU1_SA_DQS_DP<4>")
	)
	(gr_poly
		(pts
			(xy 86.03107 -245.90248) (xy 86.03107 -245.85803) (xy 85.830918 -245.85803) (xy 85.830918 -245.90248)
			(xy 85.930994 -246.002556)
		)
		(stroke
			(width 0)
			(type solid)
		)
		(fill yes)
		(layer "In2.Cu")
		(net "M_C_CPU1_SA_CB<3>")
	)
	(gr_poly
		(pts
			(xy 86.03107 -244.686328) (xy 85.930994 -244.586252) (xy 85.830918 -244.686328) (xy 85.830918 -244.730778)
			(xy 86.03107 -244.730778)
		)
		(stroke
			(width 0)
			(type solid)
		)
		(fill yes)
		(layer "In2.Cu")
		(net "M_C_CPU1_SA_CB<0>")
	)
	(gr_poly
		(pts
			(xy 86.03107 -244.282468) (xy 86.03107 -244.238018) (xy 85.830918 -244.238018) (xy 85.830918 -244.282468)
			(xy 85.930994 -244.382544)
		)
		(stroke
			(width 0)
			(type solid)
		)
		(fill yes)
		(layer "In2.Cu")
		(net "M_C_CPU1_SA_DQ<31>")
	)
	(gr_poly
		(pts
			(xy 86.03107 -243.066316) (xy 85.930994 -242.96624) (xy 85.830918 -243.066316) (xy 85.830918 -243.110766)
			(xy 86.03107 -243.110766)
		)
		(stroke
			(width 0)
			(type solid)
		)
		(fill yes)
		(layer "In2.Cu")
		(net "M_C_CPU1_SA_DQ<28>")
	)
	(gr_poly
		(pts
			(xy 86.03107 -242.66271) (xy 86.03107 -242.614958) (xy 85.830918 -242.614958) (xy 85.830918 -242.66271)
			(xy 85.930994 -242.762532)
		)
		(stroke
			(width 0)
			(type solid)
		)
		(fill yes)
		(layer "In2.Cu")
		(net "M_C_CPU1_SA_DQS_DP<8>")
	)
	(gr_poly
		(pts
			(xy 86.03107 -241.44605) (xy 85.930994 -241.346228) (xy 85.830918 -241.44605) (xy 85.830918 -241.493802)
			(xy 86.03107 -241.493802)
		)
		(stroke
			(width 0)
			(type solid)
		)
		(fill yes)
		(layer "In2.Cu")
		(net "M_C_CPU1_SA_DQS_DP<3>")
	)
	(gr_poly
		(pts
			(xy 86.03107 -241.042444) (xy 86.03107 -240.997994) (xy 85.830918 -240.997994) (xy 85.830918 -241.042444)
			(xy 85.930994 -241.14252)
		)
		(stroke
			(width 0)
			(type solid)
		)
		(fill yes)
		(layer "In2.Cu")
		(net "M_C_CPU1_SA_DQ<27>")
	)
	(gr_poly
		(pts
			(xy 86.03107 -239.826292) (xy 85.930994 -239.726216) (xy 85.830918 -239.826292) (xy 85.830918 -239.870742)
			(xy 86.03107 -239.870742)
		)
		(stroke
			(width 0)
			(type solid)
		)
		(fill yes)
		(layer "In2.Cu")
		(net "M_C_CPU1_SA_DQ<24>")
	)
	(gr_poly
		(pts
			(xy 86.03107 -239.422432) (xy 86.03107 -239.377982) (xy 85.830918 -239.377982) (xy 85.830918 -239.422432)
			(xy 85.930994 -239.522508)
		)
		(stroke
			(width 0)
			(type solid)
		)
		(fill yes)
		(layer "In2.Cu")
		(net "M_C_CPU1_SA_DQ<23>")
	)
	(gr_poly
		(pts
			(xy 86.03107 -238.20628) (xy 85.930994 -238.106204) (xy 85.830918 -238.20628) (xy 85.830918 -238.25073)
			(xy 86.03107 -238.25073)
		)
		(stroke
			(width 0)
			(type solid)
		)
		(fill yes)
		(layer "In2.Cu")
		(net "M_C_CPU1_SA_DQ<20>")
	)
	(gr_poly
		(pts
			(xy 86.03107 -237.802674) (xy 86.03107 -237.754922) (xy 85.830918 -237.754922) (xy 85.830918 -237.802674)
			(xy 85.930994 -237.902496)
		)
		(stroke
			(width 0)
			(type solid)
		)
		(fill yes)
		(layer "In2.Cu")
		(net "M_C_CPU1_SA_DQS_DP<7>")
	)
	(gr_poly
		(pts
			(xy 86.03107 -236.586014) (xy 85.930994 -236.486192) (xy 85.830918 -236.586014) (xy 85.830918 -236.633766)
			(xy 86.03107 -236.633766)
		)
		(stroke
			(width 0)
			(type solid)
		)
		(fill yes)
		(layer "In2.Cu")
		(net "M_C_CPU1_SA_DQS_DP<2>")
	)
	(gr_poly
		(pts
			(xy 86.03107 -236.182408) (xy 86.03107 -236.137958) (xy 85.830918 -236.137958) (xy 85.830918 -236.182408)
			(xy 85.930994 -236.282484)
		)
		(stroke
			(width 0)
			(type solid)
		)
		(fill yes)
		(layer "In2.Cu")
		(net "M_C_CPU1_SA_DQ<19>")
	)
	(gr_poly
		(pts
			(xy 86.03107 -234.966256) (xy 85.930994 -234.86618) (xy 85.830918 -234.966256) (xy 85.830918 -235.010706)
			(xy 86.03107 -235.010706)
		)
		(stroke
			(width 0)
			(type solid)
		)
		(fill yes)
		(layer "In2.Cu")
		(net "M_C_CPU1_SA_DQ<16>")
	)
	(gr_poly
		(pts
			(xy 86.03107 -234.562396) (xy 86.03107 -234.517946) (xy 85.830918 -234.517946) (xy 85.830918 -234.562396)
			(xy 85.930994 -234.662472)
		)
		(stroke
			(width 0)
			(type solid)
		)
		(fill yes)
		(layer "In2.Cu")
		(net "M_C_CPU1_SA_DQ<15>")
	)
	(gr_poly
		(pts
			(xy 86.03107 -233.346244) (xy 85.930994 -233.246168) (xy 85.830918 -233.346244) (xy 85.830918 -233.390694)
			(xy 86.03107 -233.390694)
		)
		(stroke
			(width 0)
			(type solid)
		)
		(fill yes)
		(layer "In2.Cu")
		(net "M_C_CPU1_SA_DQ<12>")
	)
	(gr_poly
		(pts
			(xy 86.03107 -232.942638) (xy 86.03107 -232.894886) (xy 85.830918 -232.894886) (xy 85.830918 -232.942638)
			(xy 85.930994 -233.04246)
		)
		(stroke
			(width 0)
			(type solid)
		)
		(fill yes)
		(layer "In2.Cu")
		(net "M_C_CPU1_SA_DQS_DP<6>")
	)
	(gr_poly
		(pts
			(xy 86.03107 -231.725978) (xy 85.930994 -231.626156) (xy 85.830918 -231.725978) (xy 85.830918 -231.77373)
			(xy 86.03107 -231.77373)
		)
		(stroke
			(width 0)
			(type solid)
		)
		(fill yes)
		(layer "In2.Cu")
		(net "M_C_CPU1_SA_DQS_DP<1>")
	)
	(gr_poly
		(pts
			(xy 86.03107 -231.322626) (xy 86.03107 -231.278176) (xy 85.830918 -231.278176) (xy 85.830918 -231.322626)
			(xy 85.930994 -231.422702)
		)
		(stroke
			(width 0)
			(type solid)
		)
		(fill yes)
		(layer "In2.Cu")
		(net "M_C_CPU1_SA_DQ<11>")
	)
	(gr_poly
		(pts
			(xy 86.03107 -230.10622) (xy 85.930994 -230.006144) (xy 85.830918 -230.10622) (xy 85.830918 -230.15067)
			(xy 86.03107 -230.15067)
		)
		(stroke
			(width 0)
			(type solid)
		)
		(fill yes)
		(layer "In2.Cu")
		(net "M_C_CPU1_SA_DQ<8>")
	)
	(gr_poly
		(pts
			(xy 86.03107 -229.702614) (xy 86.03107 -229.658164) (xy 85.830918 -229.658164) (xy 85.830918 -229.702614)
			(xy 85.930994 -229.80269)
		)
		(stroke
			(width 0)
			(type solid)
		)
		(fill yes)
		(layer "In2.Cu")
		(net "M_C_CPU1_SA_DQ<7>")
	)
	(gr_poly
		(pts
			(xy 86.03107 -228.486462) (xy 85.930994 -228.386386) (xy 85.830918 -228.486462) (xy 85.830918 -228.530912)
			(xy 86.03107 -228.530912)
		)
		(stroke
			(width 0)
			(type solid)
		)
		(fill yes)
		(layer "In2.Cu")
		(net "M_C_CPU1_SA_DQ<4>")
	)
	(gr_poly
		(pts
			(xy 86.03107 -228.082856) (xy 86.03107 -228.035104) (xy 85.830918 -228.035104) (xy 85.830918 -228.082856)
			(xy 85.930994 -228.182678)
		)
		(stroke
			(width 0)
			(type solid)
		)
		(fill yes)
		(layer "In2.Cu")
		(net "M_C_CPU1_SA_DQS_DP<5>")
	)
	(gr_poly
		(pts
			(xy 86.03107 -226.866196) (xy 85.930994 -226.766374) (xy 85.830918 -226.866196) (xy 85.830918 -226.913948)
			(xy 86.03107 -226.913948)
		)
		(stroke
			(width 0)
			(type solid)
		)
		(fill yes)
		(layer "In2.Cu")
		(net "M_C_CPU1_SA_DQS_DP<0>")
	)
	(gr_poly
		(pts
			(xy 86.03107 -226.46259) (xy 86.03107 -226.41814) (xy 85.830918 -226.41814) (xy 85.830918 -226.46259)
			(xy 85.930994 -226.562666)
		)
		(stroke
			(width 0)
			(type solid)
		)
		(fill yes)
		(layer "In2.Cu")
		(net "M_C_CPU1_SA_DQ<3>")
	)
	(gr_poly
		(pts
			(xy 86.03107 -225.246438) (xy 85.930994 -225.146362) (xy 85.830918 -225.246438) (xy 85.830918 -225.290888)
			(xy 86.03107 -225.290888)
		)
		(stroke
			(width 0)
			(type solid)
		)
		(fill yes)
		(layer "In2.Cu")
		(net "M_C_CPU1_SA_DQ<0>")
	)
	(gr_poly
		(pts
			(xy 86.331044 -292.918134) (xy 86.230968 -292.818058) (xy 86.130892 -292.918134) (xy 86.130892 -292.962584)
			(xy 86.331044 -292.962584)
		)
		(stroke
			(width 0)
			(type solid)
		)
		(fill yes)
		(layer "In2.Cu")
		(net "M_C_CPU1_SB_DQ<29>")
	)
	(gr_poly
		(pts
			(xy 86.331044 -292.514274) (xy 86.331044 -292.469824) (xy 86.130892 -292.469824) (xy 86.130892 -292.514274)
			(xy 86.230968 -292.61435)
		)
		(stroke
			(width 0)
			(type solid)
		)
		(fill yes)
		(layer "In2.Cu")
		(net "M_C_CPU1_SB_DQ<30>")
	)
	(gr_poly
		(pts
			(xy 86.331044 -290.894516) (xy 86.331044 -290.846764) (xy 86.130892 -290.846764) (xy 86.130892 -290.894516)
			(xy 86.230968 -290.994338)
		)
		(stroke
			(width 0)
			(type solid)
		)
		(fill yes)
		(layer "In2.Cu")
		(net "M_C_CPU1_SB_DQS_DN<3>")
	)
	(gr_poly
		(pts
			(xy 86.331044 -289.67811) (xy 86.230968 -289.578034) (xy 86.130892 -289.67811) (xy 86.130892 -289.72256)
			(xy 86.331044 -289.72256)
		)
		(stroke
			(width 0)
			(type solid)
		)
		(fill yes)
		(layer "In2.Cu")
		(net "M_C_CPU1_SB_DQ<25>")
	)
	(gr_poly
		(pts
			(xy 86.331044 -289.27425) (xy 86.331044 -289.2298) (xy 86.130892 -289.2298) (xy 86.130892 -289.27425)
			(xy 86.230968 -289.374326)
		)
		(stroke
			(width 0)
			(type solid)
		)
		(fill yes)
		(layer "In2.Cu")
		(net "M_C_CPU1_SB_DQ<26>")
	)
	(gr_poly
		(pts
			(xy 86.331044 -288.058098) (xy 86.230968 -287.958022) (xy 86.130892 -288.058098) (xy 86.130892 -288.102548)
			(xy 86.331044 -288.102548)
		)
		(stroke
			(width 0)
			(type solid)
		)
		(fill yes)
		(layer "In2.Cu")
		(net "M_C_CPU1_SB_DQ<21>")
	)
	(gr_poly
		(pts
			(xy 86.331044 -287.654492) (xy 86.331044 -287.610042) (xy 86.130892 -287.610042) (xy 86.130892 -287.654492)
			(xy 86.230968 -287.754568)
		)
		(stroke
			(width 0)
			(type solid)
		)
		(fill yes)
		(layer "In2.Cu")
		(net "M_C_CPU1_SB_DQ<22>")
	)
	(gr_poly
		(pts
			(xy 86.331044 -286.438086) (xy 86.230968 -286.33801) (xy 86.130892 -286.438086) (xy 86.130892 -286.485838)
			(xy 86.331044 -286.485838)
		)
		(stroke
			(width 0)
			(type solid)
		)
		(fill yes)
		(layer "In2.Cu")
		(net "M_C_CPU1_SB_DQS_DN<7>")
	)
	(gr_poly
		(pts
			(xy 86.331044 -286.034734) (xy 86.331044 -285.986982) (xy 86.130892 -285.986982) (xy 86.130892 -286.034734)
			(xy 86.230968 -286.134556)
		)
		(stroke
			(width 0)
			(type solid)
		)
		(fill yes)
		(layer "In2.Cu")
		(net "M_C_CPU1_SB_DQS_DN<2>")
	)
	(gr_poly
		(pts
			(xy 86.331044 -284.818328) (xy 86.230968 -284.718252) (xy 86.130892 -284.818328) (xy 86.130892 -284.862778)
			(xy 86.331044 -284.862778)
		)
		(stroke
			(width 0)
			(type solid)
		)
		(fill yes)
		(layer "In2.Cu")
		(net "M_C_CPU1_SB_DQ<17>")
	)
	(gr_poly
		(pts
			(xy 86.331044 -284.414468) (xy 86.331044 -284.370018) (xy 86.130892 -284.370018) (xy 86.130892 -284.414468)
			(xy 86.230968 -284.514544)
		)
		(stroke
			(width 0)
			(type solid)
		)
		(fill yes)
		(layer "In2.Cu")
		(net "M_C_CPU1_SB_DQ<18>")
	)
	(gr_poly
		(pts
			(xy 86.331044 -283.198316) (xy 86.230968 -283.09824) (xy 86.130892 -283.198316) (xy 86.130892 -283.242766)
			(xy 86.331044 -283.242766)
		)
		(stroke
			(width 0)
			(type solid)
		)
		(fill yes)
		(layer "In2.Cu")
		(net "M_C_CPU1_SB_DQ<13>")
	)
	(gr_poly
		(pts
			(xy 86.331044 -282.794456) (xy 86.331044 -282.750006) (xy 86.130892 -282.750006) (xy 86.130892 -282.794456)
			(xy 86.230968 -282.894532)
		)
		(stroke
			(width 0)
			(type solid)
		)
		(fill yes)
		(layer "In2.Cu")
		(net "M_C_CPU1_SB_DQ<14>")
	)
	(gr_poly
		(pts
			(xy 86.331044 -281.57805) (xy 86.230968 -281.478228) (xy 86.130892 -281.57805) (xy 86.130892 -281.625802)
			(xy 86.331044 -281.625802)
		)
		(stroke
			(width 0)
			(type solid)
		)
		(fill yes)
		(layer "In2.Cu")
		(net "M_C_CPU1_SB_DQS_DN<6>")
	)
	(gr_poly
		(pts
			(xy 86.331044 -281.174698) (xy 86.331044 -281.126946) (xy 86.130892 -281.126946) (xy 86.130892 -281.174698)
			(xy 86.230968 -281.27452)
		)
		(stroke
			(width 0)
			(type solid)
		)
		(fill yes)
		(layer "In2.Cu")
		(net "M_C_CPU1_SB_DQS_DN<1>")
	)
	(gr_poly
		(pts
			(xy 86.331044 -279.958292) (xy 86.230968 -279.858216) (xy 86.130892 -279.958292) (xy 86.130892 -280.002742)
			(xy 86.331044 -280.002742)
		)
		(stroke
			(width 0)
			(type solid)
		)
		(fill yes)
		(layer "In2.Cu")
		(net "M_C_CPU1_SB_DQ<9>")
	)
	(gr_poly
		(pts
			(xy 86.331044 -279.554432) (xy 86.331044 -279.509982) (xy 86.130892 -279.509982) (xy 86.130892 -279.554432)
			(xy 86.230968 -279.654508)
		)
		(stroke
			(width 0)
			(type solid)
		)
		(fill yes)
		(layer "In2.Cu")
		(net "M_C_CPU1_SB_DQ<10>")
	)
	(gr_poly
		(pts
			(xy 86.331044 -278.33828) (xy 86.230968 -278.238204) (xy 86.130892 -278.33828) (xy 86.130892 -278.38273)
			(xy 86.331044 -278.38273)
		)
		(stroke
			(width 0)
			(type solid)
		)
		(fill yes)
		(layer "In2.Cu")
		(net "M_C_CPU1_SB_DQ<5>")
	)
	(gr_poly
		(pts
			(xy 86.331044 -277.93442) (xy 86.331044 -277.88997) (xy 86.130892 -277.88997) (xy 86.130892 -277.93442)
			(xy 86.230968 -278.034496)
		)
		(stroke
			(width 0)
			(type solid)
		)
		(fill yes)
		(layer "In2.Cu")
		(net "M_C_CPU1_SB_DQ<6>")
	)
	(gr_poly
		(pts
			(xy 86.331044 -276.718014) (xy 86.230968 -276.618192) (xy 86.130892 -276.718014) (xy 86.130892 -276.765766)
			(xy 86.331044 -276.765766)
		)
		(stroke
			(width 0)
			(type solid)
		)
		(fill yes)
		(layer "In2.Cu")
		(net "M_C_CPU1_SB_DQS_DN<5>")
	)
	(gr_poly
		(pts
			(xy 86.331044 -276.314662) (xy 86.331044 -276.26691) (xy 86.130892 -276.26691) (xy 86.130892 -276.314662)
			(xy 86.230968 -276.414484)
		)
		(stroke
			(width 0)
			(type solid)
		)
		(fill yes)
		(layer "In2.Cu")
		(net "M_C_CPU1_SB_DQS_DN<0>")
	)
	(gr_poly
		(pts
			(xy 86.331044 -275.098256) (xy 86.230968 -274.99818) (xy 86.130892 -275.098256) (xy 86.130892 -275.142706)
			(xy 86.331044 -275.142706)
		)
		(stroke
			(width 0)
			(type solid)
		)
		(fill yes)
		(layer "In2.Cu")
		(net "M_C_CPU1_SB_DQ<1>")
	)
	(gr_poly
		(pts
			(xy 86.331044 -274.694396) (xy 86.331044 -274.649946) (xy 86.130892 -274.649946) (xy 86.130892 -274.694396)
			(xy 86.230968 -274.794472)
		)
		(stroke
			(width 0)
			(type solid)
		)
		(fill yes)
		(layer "In2.Cu")
		(net "M_C_CPU1_SB_DQ<2>")
	)
	(gr_poly
		(pts
			(xy 86.331044 -273.478244) (xy 86.230968 -273.378168) (xy 86.130892 -273.478244) (xy 86.130892 -273.522694)
			(xy 86.331044 -273.522694)
		)
		(stroke
			(width 0)
			(type solid)
		)
		(fill yes)
		(layer "In2.Cu")
		(net "M_C_CPU1_SB_CB<1>")
	)
	(gr_poly
		(pts
			(xy 86.331044 -273.074384) (xy 86.331044 -273.029934) (xy 86.130892 -273.029934) (xy 86.130892 -273.074384)
			(xy 86.230968 -273.17446)
		)
		(stroke
			(width 0)
			(type solid)
		)
		(fill yes)
		(layer "In2.Cu")
		(net "M_C_CPU1_SB_CB<2>")
	)
	(gr_poly
		(pts
			(xy 86.331044 -271.857978) (xy 86.230968 -271.758156) (xy 86.130892 -271.857978) (xy 86.130892 -271.90573)
			(xy 86.331044 -271.90573)
		)
		(stroke
			(width 0)
			(type solid)
		)
		(fill yes)
		(layer "In2.Cu")
		(net "M_C_CPU1_SB_DQS_DN<4>")
	)
	(gr_poly
		(pts
			(xy 86.331044 -271.454626) (xy 86.331044 -271.406874) (xy 86.130892 -271.406874) (xy 86.130892 -271.454626)
			(xy 86.230968 -271.554448)
		)
		(stroke
			(width 0)
			(type solid)
		)
		(fill yes)
		(layer "In2.Cu")
		(net "M_C_CPU1_SB_DQS_DN<9>")
	)
	(gr_poly
		(pts
			(xy 86.331044 -270.23822) (xy 86.230968 -270.138144) (xy 86.130892 -270.23822) (xy 86.130892 -270.28267)
			(xy 86.331044 -270.28267)
		)
		(stroke
			(width 0)
			(type solid)
		)
		(fill yes)
		(layer "In2.Cu")
		(net "M_C_CPU1_SB_CB<5>")
	)
	(gr_poly
		(pts
			(xy 86.331044 -269.83436) (xy 86.331044 -269.78991) (xy 86.130892 -269.78991) (xy 86.130892 -269.83436)
			(xy 86.230968 -269.934436)
		)
		(stroke
			(width 0)
			(type solid)
		)
		(fill yes)
		(layer "In2.Cu")
		(net "M_C_CPU1_SB_CB<6>")
	)
	(gr_poly
		(pts
			(xy 86.331044 -266.594336) (xy 86.331044 -266.549886) (xy 86.130892 -266.549886) (xy 86.130892 -266.594336)
			(xy 86.230968 -266.694412)
		)
		(stroke
			(width 0)
			(type solid)
		)
		(fill yes)
		(layer "In2.Cu")
		(net "M_C_CPU1_SB_CS_N<1>")
	)
	(gr_poly
		(pts
			(xy 86.331044 -264.974324) (xy 86.331044 -264.929874) (xy 86.130892 -264.929874) (xy 86.130892 -264.974324)
			(xy 86.230968 -265.0744)
		)
		(stroke
			(width 0)
			(type solid)
		)
		(fill yes)
		(layer "In2.Cu")
		(net "M_C_CPU1_SB_PAR")
	)
	(gr_poly
		(pts
			(xy 86.331044 -263.758172) (xy 86.230968 -263.658096) (xy 86.130892 -263.758172) (xy 86.130892 -263.802622)
			(xy 86.331044 -263.802622)
		)
		(stroke
			(width 0)
			(type solid)
		)
		(fill yes)
		(layer "In2.Cu")
		(net "M_C_CPU1_SB_CA<4>")
	)
	(gr_poly
		(pts
			(xy 86.331044 -263.354312) (xy 86.331044 -263.309862) (xy 86.130892 -263.309862) (xy 86.130892 -263.354312)
			(xy 86.230968 -263.454388)
		)
		(stroke
			(width 0)
			(type solid)
		)
		(fill yes)
		(layer "In2.Cu")
		(net "M_C_CPU1_SB_CA<3>")
	)
	(gr_poly
		(pts
			(xy 86.331044 -262.13816) (xy 86.230968 -262.038084) (xy 86.130892 -262.13816) (xy 86.130892 -262.18261)
			(xy 86.331044 -262.18261)
		)
		(stroke
			(width 0)
			(type solid)
		)
		(fill yes)
		(layer "In2.Cu")
		(net "M_C_CPU1_SB_CA<0>")
	)
	(gr_poly
		(pts
			(xy 86.33714 -266.991846) (xy 86.237318 -266.89177) (xy 86.137242 -266.991846) (xy 86.137242 -267.036296)
			(xy 86.33714 -267.036296)
		)
		(stroke
			(width 0)
			(type solid)
		)
		(fill yes)
		(layer "In2.Cu")
		(net "M_C_CPU1_SA_RSP<0>")
	)
	(gr_poly
		(pts
			(xy 86.33841 -291.298122) (xy 86.238334 -291.198046) (xy 86.138258 -291.298122) (xy 86.138258 -291.34562)
			(xy 86.33841 -291.34562)
		)
		(stroke
			(width 0)
			(type solid)
		)
		(fill yes)
		(layer "In2.Cu")
		(net "M_C_CPU1_SB_DQS_DN<8>")
	)
	(gr_poly
		(pts
			(xy 86.50097 -246.712486) (xy 86.50097 -246.664988) (xy 86.301072 -246.664988) (xy 86.301072 -246.712486)
			(xy 86.400894 -246.812562)
		)
		(stroke
			(width 0)
			(type solid)
		)
		(fill yes)
		(layer "In2.Cu")
		(net "M_C_CPU1_SA_DQS_DN<4>")
	)
	(gr_poly
		(pts
			(xy 86.501224 -256.432812) (xy 86.501224 -256.38506) (xy 86.301072 -256.38506) (xy 86.301072 -256.432812)
			(xy 86.401148 -256.532634)
		)
		(stroke
			(width 0)
			(type solid)
		)
		(fill yes)
		(layer "In2.Cu")
		(net "M_C_CPU1_CLK_DN<0>")
	)
	(gr_poly
		(pts
			(xy 86.501224 -255.216406) (xy 86.401148 -255.11633) (xy 86.301072 -255.216406) (xy 86.301072 -255.260856)
			(xy 86.501224 -255.260856)
		)
		(stroke
			(width 0)
			(type solid)
		)
		(fill yes)
		(layer "In2.Cu")
		(net "M_C_CPU1_SA_CA<6>")
	)
	(gr_poly
		(pts
			(xy 86.501224 -254.812546) (xy 86.501224 -254.768096) (xy 86.301072 -254.768096) (xy 86.301072 -254.812546)
			(xy 86.401148 -254.912622)
		)
		(stroke
			(width 0)
			(type solid)
		)
		(fill yes)
		(layer "In2.Cu")
		(net "M_C_CPU1_SA_CA<5>")
	)
	(gr_poly
		(pts
			(xy 86.501224 -253.596394) (xy 86.401148 -253.496318) (xy 86.301072 -253.596394) (xy 86.301072 -253.640844)
			(xy 86.501224 -253.640844)
		)
		(stroke
			(width 0)
			(type solid)
		)
		(fill yes)
		(layer "In2.Cu")
		(net "M_C_CPU1_SA_CA<2>")
	)
	(gr_poly
		(pts
			(xy 86.501224 -253.192534) (xy 86.501224 -253.148084) (xy 86.301072 -253.148084) (xy 86.301072 -253.192534)
			(xy 86.401148 -253.29261)
		)
		(stroke
			(width 0)
			(type solid)
		)
		(fill yes)
		(layer "In2.Cu")
		(net "M_C_CPU1_SA_CA<1>")
	)
	(gr_poly
		(pts
			(xy 86.501224 -251.572522) (xy 86.501224 -251.528072) (xy 86.301072 -251.528072) (xy 86.301072 -251.572522)
			(xy 86.401148 -251.672598)
		)
		(stroke
			(width 0)
			(type solid)
		)
		(fill yes)
		(layer "In2.Cu")
		(net "M_C_CPU1_SA_CS_N<0>")
	)
	(gr_poly
		(pts
			(xy 86.501224 -250.35637) (xy 86.401148 -250.256294) (xy 86.301072 -250.35637) (xy 86.301072 -250.40082)
			(xy 86.501224 -250.40082)
		)
		(stroke
			(width 0)
			(type solid)
		)
		(fill yes)
		(layer "In2.Cu")
		(net "M_C_CPU1_ALERT_R_N")
	)
	(gr_poly
		(pts
			(xy 86.501224 -248.736358) (xy 86.401148 -248.636282) (xy 86.301072 -248.736358) (xy 86.301072 -248.780808)
			(xy 86.501224 -248.780808)
		)
		(stroke
			(width 0)
			(type solid)
		)
		(fill yes)
		(layer "In2.Cu")
		(net "M_C_CPU1_SA_CB<5>")
	)
	(gr_poly
		(pts
			(xy 86.501224 -248.332498) (xy 86.501224 -248.288048) (xy 86.301072 -248.288048) (xy 86.301072 -248.332498)
			(xy 86.401148 -248.432574)
		)
		(stroke
			(width 0)
			(type solid)
		)
		(fill yes)
		(layer "In2.Cu")
		(net "M_C_CPU1_SA_CB<6>")
	)
	(gr_poly
		(pts
			(xy 86.501224 -247.116092) (xy 86.401148 -247.01627) (xy 86.301072 -247.116092) (xy 86.301072 -247.163844)
			(xy 86.501224 -247.163844)
		)
		(stroke
			(width 0)
			(type solid)
		)
		(fill yes)
		(layer "In2.Cu")
		(net "M_C_CPU1_SA_DQS_DN<9>")
	)
	(gr_poly
		(pts
			(xy 86.501224 -245.496334) (xy 86.401148 -245.396258) (xy 86.301072 -245.496334) (xy 86.301072 -245.540784)
			(xy 86.501224 -245.540784)
		)
		(stroke
			(width 0)
			(type solid)
		)
		(fill yes)
		(layer "In2.Cu")
		(net "M_C_CPU1_SA_CB<1>")
	)
	(gr_poly
		(pts
			(xy 86.501224 -245.092474) (xy 86.501224 -245.048024) (xy 86.301072 -245.048024) (xy 86.301072 -245.092474)
			(xy 86.401148 -245.19255)
		)
		(stroke
			(width 0)
			(type solid)
		)
		(fill yes)
		(layer "In2.Cu")
		(net "M_C_CPU1_SA_CB<2>")
	)
	(gr_poly
		(pts
			(xy 86.501224 -243.876322) (xy 86.401148 -243.776246) (xy 86.301072 -243.876322) (xy 86.301072 -243.920772)
			(xy 86.501224 -243.920772)
		)
		(stroke
			(width 0)
			(type solid)
		)
		(fill yes)
		(layer "In2.Cu")
		(net "M_C_CPU1_SA_DQ<29>")
	)
	(gr_poly
		(pts
			(xy 86.501224 -243.472462) (xy 86.501224 -243.428012) (xy 86.301072 -243.428012) (xy 86.301072 -243.472462)
			(xy 86.401148 -243.572538)
		)
		(stroke
			(width 0)
			(type solid)
		)
		(fill yes)
		(layer "In2.Cu")
		(net "M_C_CPU1_SA_DQ<30>")
	)
	(gr_poly
		(pts
			(xy 86.501224 -242.256056) (xy 86.401148 -242.156234) (xy 86.301072 -242.256056) (xy 86.301072 -242.303808)
			(xy 86.501224 -242.303808)
		)
		(stroke
			(width 0)
			(type solid)
		)
		(fill yes)
		(layer "In2.Cu")
		(net "M_C_CPU1_SA_DQS_DN<8>")
	)
	(gr_poly
		(pts
			(xy 86.501224 -241.852704) (xy 86.501224 -241.804952) (xy 86.301072 -241.804952) (xy 86.301072 -241.852704)
			(xy 86.401148 -241.952526)
		)
		(stroke
			(width 0)
			(type solid)
		)
		(fill yes)
		(layer "In2.Cu")
		(net "M_C_CPU1_SA_DQS_DN<3>")
	)
	(gr_poly
		(pts
			(xy 86.501224 -240.636298) (xy 86.401148 -240.536222) (xy 86.301072 -240.636298) (xy 86.301072 -240.680748)
			(xy 86.501224 -240.680748)
		)
		(stroke
			(width 0)
			(type solid)
		)
		(fill yes)
		(layer "In2.Cu")
		(net "M_C_CPU1_SA_DQ<25>")
	)
	(gr_poly
		(pts
			(xy 86.501224 -240.232438) (xy 86.501224 -240.187988) (xy 86.301072 -240.187988) (xy 86.301072 -240.232438)
			(xy 86.401148 -240.332514)
		)
		(stroke
			(width 0)
			(type solid)
		)
		(fill yes)
		(layer "In2.Cu")
		(net "M_C_CPU1_SA_DQ<26>")
	)
	(gr_poly
		(pts
			(xy 86.501224 -239.016286) (xy 86.401148 -238.91621) (xy 86.301072 -239.016286) (xy 86.301072 -239.060736)
			(xy 86.501224 -239.060736)
		)
		(stroke
			(width 0)
			(type solid)
		)
		(fill yes)
		(layer "In2.Cu")
		(net "M_C_CPU1_SA_DQ<21>")
	)
	(gr_poly
		(pts
			(xy 86.501224 -238.612426) (xy 86.501224 -238.567976) (xy 86.301072 -238.567976) (xy 86.301072 -238.612426)
			(xy 86.401148 -238.712502)
		)
		(stroke
			(width 0)
			(type solid)
		)
		(fill yes)
		(layer "In2.Cu")
		(net "M_C_CPU1_SA_DQ<22>")
	)
	(gr_poly
		(pts
			(xy 86.501224 -237.39602) (xy 86.401148 -237.296198) (xy 86.301072 -237.39602) (xy 86.301072 -237.443772)
			(xy 86.501224 -237.443772)
		)
		(stroke
			(width 0)
			(type solid)
		)
		(fill yes)
		(layer "In2.Cu")
		(net "M_C_CPU1_SA_DQS_DN<7>")
	)
	(gr_poly
		(pts
			(xy 86.501224 -236.992668) (xy 86.501224 -236.944916) (xy 86.301072 -236.944916) (xy 86.301072 -236.992668)
			(xy 86.401148 -237.09249)
		)
		(stroke
			(width 0)
			(type solid)
		)
		(fill yes)
		(layer "In2.Cu")
		(net "M_C_CPU1_SA_DQS_DN<2>")
	)
	(gr_poly
		(pts
			(xy 86.501224 -235.776262) (xy 86.401148 -235.676186) (xy 86.301072 -235.776262) (xy 86.301072 -235.820712)
			(xy 86.501224 -235.820712)
		)
		(stroke
			(width 0)
			(type solid)
		)
		(fill yes)
		(layer "In2.Cu")
		(net "M_C_CPU1_SA_DQ<17>")
	)
	(gr_poly
		(pts
			(xy 86.501224 -235.372402) (xy 86.501224 -235.327952) (xy 86.301072 -235.327952) (xy 86.301072 -235.372402)
			(xy 86.401148 -235.472478)
		)
		(stroke
			(width 0)
			(type solid)
		)
		(fill yes)
		(layer "In2.Cu")
		(net "M_C_CPU1_SA_DQ<18>")
	)
	(gr_poly
		(pts
			(xy 86.501224 -234.15625) (xy 86.401148 -234.056174) (xy 86.301072 -234.15625) (xy 86.301072 -234.2007)
			(xy 86.501224 -234.2007)
		)
		(stroke
			(width 0)
			(type solid)
		)
		(fill yes)
		(layer "In2.Cu")
		(net "M_C_CPU1_SA_DQ<13>")
	)
	(gr_poly
		(pts
			(xy 86.501224 -233.75239) (xy 86.501224 -233.70794) (xy 86.301072 -233.70794) (xy 86.301072 -233.75239)
			(xy 86.401148 -233.852466)
		)
		(stroke
			(width 0)
			(type solid)
		)
		(fill yes)
		(layer "In2.Cu")
		(net "M_C_CPU1_SA_DQ<14>")
	)
	(gr_poly
		(pts
			(xy 86.501224 -232.535984) (xy 86.401148 -232.436162) (xy 86.301072 -232.535984) (xy 86.301072 -232.583736)
			(xy 86.501224 -232.583736)
		)
		(stroke
			(width 0)
			(type solid)
		)
		(fill yes)
		(layer "In2.Cu")
		(net "M_C_CPU1_SA_DQS_DN<6>")
	)
	(gr_poly
		(pts
			(xy 86.501224 -232.132632) (xy 86.501224 -232.08488) (xy 86.301072 -232.08488) (xy 86.301072 -232.132632)
			(xy 86.401148 -232.232454)
		)
		(stroke
			(width 0)
			(type solid)
		)
		(fill yes)
		(layer "In2.Cu")
		(net "M_C_CPU1_SA_DQS_DN<1>")
	)
	(gr_poly
		(pts
			(xy 86.501224 -230.916226) (xy 86.401148 -230.81615) (xy 86.301072 -230.916226) (xy 86.301072 -230.960676)
			(xy 86.501224 -230.960676)
		)
		(stroke
			(width 0)
			(type solid)
		)
		(fill yes)
		(layer "In2.Cu")
		(net "M_C_CPU1_SA_DQ<9>")
	)
	(gr_poly
		(pts
			(xy 86.501224 -230.51262) (xy 86.501224 -230.46817) (xy 86.301072 -230.46817) (xy 86.301072 -230.51262)
			(xy 86.401148 -230.612696)
		)
		(stroke
			(width 0)
			(type solid)
		)
		(fill yes)
		(layer "In2.Cu")
		(net "M_C_CPU1_SA_DQ<10>")
	)
	(gr_poly
		(pts
			(xy 86.501224 -229.296214) (xy 86.401148 -229.196138) (xy 86.301072 -229.296214) (xy 86.301072 -229.340664)
			(xy 86.501224 -229.340664)
		)
		(stroke
			(width 0)
			(type solid)
		)
		(fill yes)
		(layer "In2.Cu")
		(net "M_C_CPU1_SA_DQ<5>")
	)
	(gr_poly
		(pts
			(xy 86.501224 -228.892608) (xy 86.501224 -228.848158) (xy 86.301072 -228.848158) (xy 86.301072 -228.892608)
			(xy 86.401148 -228.992684)
		)
		(stroke
			(width 0)
			(type solid)
		)
		(fill yes)
		(layer "In2.Cu")
		(net "M_C_CPU1_SA_DQ<6>")
	)
	(gr_poly
		(pts
			(xy 86.501224 -227.676202) (xy 86.401148 -227.57638) (xy 86.301072 -227.676202) (xy 86.301072 -227.723954)
			(xy 86.501224 -227.723954)
		)
		(stroke
			(width 0)
			(type solid)
		)
		(fill yes)
		(layer "In2.Cu")
		(net "M_C_CPU1_SA_DQS_DN<5>")
	)
	(gr_poly
		(pts
			(xy 86.501224 -227.27285) (xy 86.501224 -227.225098) (xy 86.301072 -227.225098) (xy 86.301072 -227.27285)
			(xy 86.401148 -227.372672)
		)
		(stroke
			(width 0)
			(type solid)
		)
		(fill yes)
		(layer "In2.Cu")
		(net "M_C_CPU1_SA_DQS_DN<0>")
	)
	(gr_poly
		(pts
			(xy 86.501224 -226.056444) (xy 86.401148 -225.956368) (xy 86.301072 -226.056444) (xy 86.301072 -226.100894)
			(xy 86.501224 -226.100894)
		)
		(stroke
			(width 0)
			(type solid)
		)
		(fill yes)
		(layer "In2.Cu")
		(net "M_C_CPU1_SA_DQ<1>")
	)
	(gr_poly
		(pts
			(xy 86.501224 -225.652584) (xy 86.501224 -225.608134) (xy 86.301072 -225.608134) (xy 86.301072 -225.652584)
			(xy 86.401148 -225.75266)
		)
		(stroke
			(width 0)
			(type solid)
		)
		(fill yes)
		(layer "In2.Cu")
		(net "M_C_CPU1_SA_DQ<2>")
	)
	(gr_poly
		(pts
			(xy 86.793832 -291.704268) (xy 86.793832 -291.65677) (xy 86.593934 -291.65677) (xy 86.593934 -291.704268)
			(xy 86.693756 -291.804344)
		)
		(stroke
			(width 0)
			(type solid)
		)
		(fill yes)
		(layer "In2.Cu")
		(net "M_C_CPU1_SB_DQS_DP<8>")
	)
	(gr_poly
		(pts
			(xy 86.794848 -267.801852) (xy 86.694772 -267.701776) (xy 86.59495 -267.801852) (xy 86.59495 -267.846302)
			(xy 86.794848 -267.846302)
		)
		(stroke
			(width 0)
			(type solid)
		)
		(fill yes)
		(layer "In2.Cu")
		(net "M_C_CPU1_SB_RSP<0>")
	)
	(gr_poly
		(pts
			(xy 86.801198 -293.32428) (xy 86.801198 -293.27983) (xy 86.601046 -293.27983) (xy 86.601046 -293.32428)
			(xy 86.701122 -293.424356)
		)
		(stroke
			(width 0)
			(type solid)
		)
		(fill yes)
		(layer "In2.Cu")
		(net "M_C_CPU1_SB_DQ<31>")
	)
	(gr_poly
		(pts
			(xy 86.801198 -292.108128) (xy 86.701122 -292.008052) (xy 86.601046 -292.108128) (xy 86.601046 -292.152578)
			(xy 86.801198 -292.152578)
		)
		(stroke
			(width 0)
			(type solid)
		)
		(fill yes)
		(layer "In2.Cu")
		(net "M_C_CPU1_SB_DQ<28>")
	)
	(gr_poly
		(pts
			(xy 86.801198 -290.487862) (xy 86.701122 -290.38804) (xy 86.601046 -290.487862) (xy 86.601046 -290.535614)
			(xy 86.801198 -290.535614)
		)
		(stroke
			(width 0)
			(type solid)
		)
		(fill yes)
		(layer "In2.Cu")
		(net "M_C_CPU1_SB_DQS_DP<3>")
	)
	(gr_poly
		(pts
			(xy 86.801198 -290.084256) (xy 86.801198 -290.039806) (xy 86.601046 -290.039806) (xy 86.601046 -290.084256)
			(xy 86.701122 -290.184332)
		)
		(stroke
			(width 0)
			(type solid)
		)
		(fill yes)
		(layer "In2.Cu")
		(net "M_C_CPU1_SB_DQ<27>")
	)
	(gr_poly
		(pts
			(xy 86.801198 -288.868104) (xy 86.701122 -288.768028) (xy 86.601046 -288.868104) (xy 86.601046 -288.912554)
			(xy 86.801198 -288.912554)
		)
		(stroke
			(width 0)
			(type solid)
		)
		(fill yes)
		(layer "In2.Cu")
		(net "M_C_CPU1_SB_DQ<24>")
	)
	(gr_poly
		(pts
			(xy 86.801198 -288.464498) (xy 86.801198 -288.420048) (xy 86.601046 -288.420048) (xy 86.601046 -288.464498)
			(xy 86.701122 -288.564574)
		)
		(stroke
			(width 0)
			(type solid)
		)
		(fill yes)
		(layer "In2.Cu")
		(net "M_C_CPU1_SB_DQ<23>")
	)
	(gr_poly
		(pts
			(xy 86.801198 -287.248092) (xy 86.701122 -287.148016) (xy 86.601046 -287.248092) (xy 86.601046 -287.292542)
			(xy 86.801198 -287.292542)
		)
		(stroke
			(width 0)
			(type solid)
		)
		(fill yes)
		(layer "In2.Cu")
		(net "M_C_CPU1_SB_DQ<20>")
	)
	(gr_poly
		(pts
			(xy 86.801198 -286.844486) (xy 86.801198 -286.796734) (xy 86.601046 -286.796734) (xy 86.601046 -286.844486)
			(xy 86.701122 -286.944562)
		)
		(stroke
			(width 0)
			(type solid)
		)
		(fill yes)
		(layer "In2.Cu")
		(net "M_C_CPU1_SB_DQS_DP<7>")
	)
	(gr_poly
		(pts
			(xy 86.801198 -285.62808) (xy 86.701122 -285.528258) (xy 86.601046 -285.62808) (xy 86.601046 -285.675832)
			(xy 86.801198 -285.675832)
		)
		(stroke
			(width 0)
			(type solid)
		)
		(fill yes)
		(layer "In2.Cu")
		(net "M_C_CPU1_SB_DQS_DP<2>")
	)
	(gr_poly
		(pts
			(xy 86.801198 -285.224474) (xy 86.801198 -285.180024) (xy 86.601046 -285.180024) (xy 86.601046 -285.224474)
			(xy 86.701122 -285.32455)
		)
		(stroke
			(width 0)
			(type solid)
		)
		(fill yes)
		(layer "In2.Cu")
		(net "M_C_CPU1_SB_DQ<19>")
	)
	(gr_poly
		(pts
			(xy 86.801198 -284.008322) (xy 86.701122 -283.908246) (xy 86.601046 -284.008322) (xy 86.601046 -284.052772)
			(xy 86.801198 -284.052772)
		)
		(stroke
			(width 0)
			(type solid)
		)
		(fill yes)
		(layer "In2.Cu")
		(net "M_C_CPU1_SB_DQ<16>")
	)
	(gr_poly
		(pts
			(xy 86.801198 -283.604462) (xy 86.801198 -283.560012) (xy 86.601046 -283.560012) (xy 86.601046 -283.604462)
			(xy 86.701122 -283.704538)
		)
		(stroke
			(width 0)
			(type solid)
		)
		(fill yes)
		(layer "In2.Cu")
		(net "M_C_CPU1_SB_DQ<15>")
	)
	(gr_poly
		(pts
			(xy 86.801198 -282.38831) (xy 86.701122 -282.288234) (xy 86.601046 -282.38831) (xy 86.601046 -282.43276)
			(xy 86.801198 -282.43276)
		)
		(stroke
			(width 0)
			(type solid)
		)
		(fill yes)
		(layer "In2.Cu")
		(net "M_C_CPU1_SB_DQ<12>")
	)
	(gr_poly
		(pts
			(xy 86.801198 -281.984704) (xy 86.801198 -281.936952) (xy 86.601046 -281.936952) (xy 86.601046 -281.984704)
			(xy 86.701122 -282.084526)
		)
		(stroke
			(width 0)
			(type solid)
		)
		(fill yes)
		(layer "In2.Cu")
		(net "M_C_CPU1_SB_DQS_DP<6>")
	)
	(gr_poly
		(pts
			(xy 86.801198 -280.768044) (xy 86.701122 -280.668222) (xy 86.601046 -280.768044) (xy 86.601046 -280.815796)
			(xy 86.801198 -280.815796)
		)
		(stroke
			(width 0)
			(type solid)
		)
		(fill yes)
		(layer "In2.Cu")
		(net "M_C_CPU1_SB_DQS_DP<1>")
	)
	(gr_poly
		(pts
			(xy 86.801198 -280.364438) (xy 86.801198 -280.319988) (xy 86.601046 -280.319988) (xy 86.601046 -280.364438)
			(xy 86.701122 -280.464514)
		)
		(stroke
			(width 0)
			(type solid)
		)
		(fill yes)
		(layer "In2.Cu")
		(net "M_C_CPU1_SB_DQ<11>")
	)
	(gr_poly
		(pts
			(xy 86.801198 -279.148286) (xy 86.701122 -279.04821) (xy 86.601046 -279.148286) (xy 86.601046 -279.192736)
			(xy 86.801198 -279.192736)
		)
		(stroke
			(width 0)
			(type solid)
		)
		(fill yes)
		(layer "In2.Cu")
		(net "M_C_CPU1_SB_DQ<8>")
	)
	(gr_poly
		(pts
			(xy 86.801198 -278.744426) (xy 86.801198 -278.699976) (xy 86.601046 -278.699976) (xy 86.601046 -278.744426)
			(xy 86.701122 -278.844502)
		)
		(stroke
			(width 0)
			(type solid)
		)
		(fill yes)
		(layer "In2.Cu")
		(net "M_C_CPU1_SB_DQ<7>")
	)
	(gr_poly
		(pts
			(xy 86.801198 -277.528274) (xy 86.701122 -277.428198) (xy 86.601046 -277.528274) (xy 86.601046 -277.572724)
			(xy 86.801198 -277.572724)
		)
		(stroke
			(width 0)
			(type solid)
		)
		(fill yes)
		(layer "In2.Cu")
		(net "M_C_CPU1_SB_DQ<4>")
	)
	(gr_poly
		(pts
			(xy 86.801198 -277.124668) (xy 86.801198 -277.076916) (xy 86.601046 -277.076916) (xy 86.601046 -277.124668)
			(xy 86.701122 -277.22449)
		)
		(stroke
			(width 0)
			(type solid)
		)
		(fill yes)
		(layer "In2.Cu")
		(net "M_C_CPU1_SB_DQS_DP<5>")
	)
	(gr_poly
		(pts
			(xy 86.801198 -275.908008) (xy 86.701122 -275.808186) (xy 86.601046 -275.908008) (xy 86.601046 -275.95576)
			(xy 86.801198 -275.95576)
		)
		(stroke
			(width 0)
			(type solid)
		)
		(fill yes)
		(layer "In2.Cu")
		(net "M_C_CPU1_SB_DQS_DP<0>")
	)
	(gr_poly
		(pts
			(xy 86.801198 -275.504402) (xy 86.801198 -275.459952) (xy 86.601046 -275.459952) (xy 86.601046 -275.504402)
			(xy 86.701122 -275.604478)
		)
		(stroke
			(width 0)
			(type solid)
		)
		(fill yes)
		(layer "In2.Cu")
		(net "M_C_CPU1_SB_DQ<3>")
	)
	(gr_poly
		(pts
			(xy 86.801198 -274.28825) (xy 86.701122 -274.188174) (xy 86.601046 -274.28825) (xy 86.601046 -274.3327)
			(xy 86.801198 -274.3327)
		)
		(stroke
			(width 0)
			(type solid)
		)
		(fill yes)
		(layer "In2.Cu")
		(net "M_C_CPU1_SB_DQ<0>")
	)
	(gr_poly
		(pts
			(xy 86.801198 -273.88439) (xy 86.801198 -273.83994) (xy 86.601046 -273.83994) (xy 86.601046 -273.88439)
			(xy 86.701122 -273.984466)
		)
		(stroke
			(width 0)
			(type solid)
		)
		(fill yes)
		(layer "In2.Cu")
		(net "M_C_CPU1_SB_CB<3>")
	)
	(gr_poly
		(pts
			(xy 86.801198 -272.668238) (xy 86.701122 -272.568162) (xy 86.601046 -272.668238) (xy 86.601046 -272.712688)
			(xy 86.801198 -272.712688)
		)
		(stroke
			(width 0)
			(type solid)
		)
		(fill yes)
		(layer "In2.Cu")
		(net "M_C_CPU1_SB_CB<0>")
	)
	(gr_poly
		(pts
			(xy 86.801198 -272.264632) (xy 86.801198 -272.21688) (xy 86.601046 -272.21688) (xy 86.601046 -272.264632)
			(xy 86.701122 -272.364454)
		)
		(stroke
			(width 0)
			(type solid)
		)
		(fill yes)
		(layer "In2.Cu")
		(net "M_C_CPU1_SB_DQS_DP<4>")
	)
	(gr_poly
		(pts
			(xy 86.801198 -271.047972) (xy 86.701122 -270.94815) (xy 86.601046 -271.047972) (xy 86.601046 -271.095724)
			(xy 86.801198 -271.095724)
		)
		(stroke
			(width 0)
			(type solid)
		)
		(fill yes)
		(layer "In2.Cu")
		(net "M_C_CPU1_SB_DQS_DP<9>")
	)
	(gr_poly
		(pts
			(xy 86.801198 -270.644366) (xy 86.801198 -270.599916) (xy 86.601046 -270.599916) (xy 86.601046 -270.644366)
			(xy 86.701122 -270.744442)
		)
		(stroke
			(width 0)
			(type solid)
		)
		(fill yes)
		(layer "In2.Cu")
		(net "M_C_CPU1_SB_CB<7>")
	)
	(gr_poly
		(pts
			(xy 86.801198 -269.428214) (xy 86.701122 -269.328138) (xy 86.601046 -269.428214) (xy 86.601046 -269.472664)
			(xy 86.801198 -269.472664)
		)
		(stroke
			(width 0)
			(type solid)
		)
		(fill yes)
		(layer "In2.Cu")
		(net "M_C_CPU1_SB_CB<4>")
	)
	(gr_poly
		(pts
			(xy 86.801198 -265.78433) (xy 86.801198 -265.73988) (xy 86.601046 -265.73988) (xy 86.601046 -265.78433)
			(xy 86.701122 -265.884406)
		)
		(stroke
			(width 0)
			(type solid)
		)
		(fill yes)
		(layer "In2.Cu")
		(net "M_C_CPU1_SB_CS_N<0>")
	)
	(gr_poly
		(pts
			(xy 86.801198 -264.568178) (xy 86.701122 -264.468102) (xy 86.601046 -264.568178) (xy 86.601046 -264.612628)
			(xy 86.801198 -264.612628)
		)
		(stroke
			(width 0)
			(type solid)
		)
		(fill yes)
		(layer "In2.Cu")
		(net "M_C_CPU1_SB_CA<6>")
	)
	(gr_poly
		(pts
			(xy 86.801198 -264.164318) (xy 86.801198 -264.119868) (xy 86.601046 -264.119868) (xy 86.601046 -264.164318)
			(xy 86.701122 -264.264394)
		)
		(stroke
			(width 0)
			(type solid)
		)
		(fill yes)
		(layer "In2.Cu")
		(net "M_C_CPU1_SB_CA<5>")
	)
	(gr_poly
		(pts
			(xy 86.801198 -262.948166) (xy 86.701122 -262.84809) (xy 86.601046 -262.948166) (xy 86.601046 -262.992616)
			(xy 86.801198 -262.992616)
		)
		(stroke
			(width 0)
			(type solid)
		)
		(fill yes)
		(layer "In2.Cu")
		(net "M_C_CPU1_SB_CA<2>")
	)
	(gr_poly
		(pts
			(xy 86.801198 -262.544306) (xy 86.801198 -262.499856) (xy 86.601046 -262.499856) (xy 86.601046 -262.544306)
			(xy 86.701122 -262.644382)
		)
		(stroke
			(width 0)
			(type solid)
		)
		(fill yes)
		(layer "In2.Cu")
		(net "M_C_CPU1_SB_CA<1>")
	)
	(gr_poly
		(pts
			(xy 86.971124 -256.026158) (xy 86.871048 -255.926336) (xy 86.770972 -256.026158) (xy 86.770972 -256.07391)
			(xy 86.971124 -256.07391)
		)
		(stroke
			(width 0)
			(type solid)
		)
		(fill yes)
		(layer "In2.Cu")
		(net "M_C_CPU1_CLK_DP<0>")
	)
	(gr_poly
		(pts
			(xy 86.971124 -255.622552) (xy 86.971124 -255.578102) (xy 86.770972 -255.578102) (xy 86.770972 -255.622552)
			(xy 86.871048 -255.722628)
		)
		(stroke
			(width 0)
			(type solid)
		)
		(fill yes)
		(layer "In2.Cu")
		(net "M_C_CPU1_SA_PAR")
	)
	(gr_poly
		(pts
			(xy 86.971124 -254.4064) (xy 86.871048 -254.306324) (xy 86.770972 -254.4064) (xy 86.770972 -254.45085)
			(xy 86.971124 -254.45085)
		)
		(stroke
			(width 0)
			(type solid)
		)
		(fill yes)
		(layer "In2.Cu")
		(net "M_C_CPU1_SA_CA<4>")
	)
	(gr_poly
		(pts
			(xy 86.971124 -254.00254) (xy 86.971124 -253.95809) (xy 86.770972 -253.95809) (xy 86.770972 -254.00254)
			(xy 86.871048 -254.102616)
		)
		(stroke
			(width 0)
			(type solid)
		)
		(fill yes)
		(layer "In2.Cu")
		(net "M_C_CPU1_SA_CA<3>")
	)
	(gr_poly
		(pts
			(xy 86.971124 -252.786388) (xy 86.871048 -252.686312) (xy 86.770972 -252.786388) (xy 86.770972 -252.830838)
			(xy 86.971124 -252.830838)
		)
		(stroke
			(width 0)
			(type solid)
		)
		(fill yes)
		(layer "In2.Cu")
		(net "M_C_CPU1_SA_CA<0>")
	)
	(gr_poly
		(pts
			(xy 86.971124 -252.382528) (xy 86.971124 -252.338078) (xy 86.770972 -252.338078) (xy 86.770972 -252.382528)
			(xy 86.871048 -252.482604)
		)
		(stroke
			(width 0)
			(type solid)
		)
		(fill yes)
		(layer "In2.Cu")
		(net "M_C_CPU1_SA_CS_N<1>")
	)
	(gr_poly
		(pts
			(xy 86.971124 -250.762516) (xy 86.971124 -250.718066) (xy 86.770972 -250.718066) (xy 86.770972 -250.762516)
			(xy 86.871048 -250.862592)
		)
		(stroke
			(width 0)
			(type solid)
		)
		(fill yes)
		(layer "In2.Cu")
		(net "M_C_CPU1_RESET_N")
	)
	(gr_poly
		(pts
			(xy 86.971124 -249.142504) (xy 86.971124 -249.098054) (xy 86.770972 -249.098054) (xy 86.770972 -249.142504)
			(xy 86.871048 -249.24258)
		)
		(stroke
			(width 0)
			(type solid)
		)
		(fill yes)
		(layer "In2.Cu")
		(net "M_C_CPU1_SA_CB<7>")
	)
	(gr_poly
		(pts
			(xy 86.971124 -247.926352) (xy 86.871048 -247.826276) (xy 86.770972 -247.926352) (xy 86.770972 -247.970802)
			(xy 86.971124 -247.970802)
		)
		(stroke
			(width 0)
			(type solid)
		)
		(fill yes)
		(layer "In2.Cu")
		(net "M_C_CPU1_SA_CB<4>")
	)
	(gr_poly
		(pts
			(xy 86.971124 -247.522746) (xy 86.971124 -247.474994) (xy 86.770972 -247.474994) (xy 86.770972 -247.522746)
			(xy 86.871048 -247.622568)
		)
		(stroke
			(width 0)
			(type solid)
		)
		(fill yes)
		(layer "In2.Cu")
		(net "M_C_CPU1_SA_DQS_DP<9>")
	)
	(gr_poly
		(pts
			(xy 86.971124 -246.306086) (xy 86.871048 -246.206264) (xy 86.770972 -246.306086) (xy 86.770972 -246.353838)
			(xy 86.971124 -246.353838)
		)
		(stroke
			(width 0)
			(type solid)
		)
		(fill yes)
		(layer "In2.Cu")
		(net "M_C_CPU1_SA_DQS_DP<4>")
	)
	(gr_poly
		(pts
			(xy 86.971124 -245.90248) (xy 86.971124 -245.85803) (xy 86.770972 -245.85803) (xy 86.770972 -245.90248)
			(xy 86.871048 -246.002556)
		)
		(stroke
			(width 0)
			(type solid)
		)
		(fill yes)
		(layer "In2.Cu")
		(net "M_C_CPU1_SA_CB<3>")
	)
	(gr_poly
		(pts
			(xy 86.971124 -244.686328) (xy 86.871048 -244.586252) (xy 86.770972 -244.686328) (xy 86.770972 -244.730778)
			(xy 86.971124 -244.730778)
		)
		(stroke
			(width 0)
			(type solid)
		)
		(fill yes)
		(layer "In2.Cu")
		(net "M_C_CPU1_SA_CB<0>")
	)
	(gr_poly
		(pts
			(xy 86.971124 -244.282468) (xy 86.971124 -244.238018) (xy 86.770972 -244.238018) (xy 86.770972 -244.282468)
			(xy 86.871048 -244.382544)
		)
		(stroke
			(width 0)
			(type solid)
		)
		(fill yes)
		(layer "In2.Cu")
		(net "M_C_CPU1_SA_DQ<31>")
	)
	(gr_poly
		(pts
			(xy 86.971124 -243.066316) (xy 86.871048 -242.96624) (xy 86.770972 -243.066316) (xy 86.770972 -243.110766)
			(xy 86.971124 -243.110766)
		)
		(stroke
			(width 0)
			(type solid)
		)
		(fill yes)
		(layer "In2.Cu")
		(net "M_C_CPU1_SA_DQ<28>")
	)
	(gr_poly
		(pts
			(xy 86.971124 -242.66271) (xy 86.971124 -242.614958) (xy 86.770972 -242.614958) (xy 86.770972 -242.66271)
			(xy 86.871048 -242.762532)
		)
		(stroke
			(width 0)
			(type solid)
		)
		(fill yes)
		(layer "In2.Cu")
		(net "M_C_CPU1_SA_DQS_DP<8>")
	)
	(gr_poly
		(pts
			(xy 86.971124 -241.44605) (xy 86.871048 -241.346228) (xy 86.770972 -241.44605) (xy 86.770972 -241.493802)
			(xy 86.971124 -241.493802)
		)
		(stroke
			(width 0)
			(type solid)
		)
		(fill yes)
		(layer "In2.Cu")
		(net "M_C_CPU1_SA_DQS_DP<3>")
	)
	(gr_poly
		(pts
			(xy 86.971124 -241.042444) (xy 86.971124 -240.997994) (xy 86.770972 -240.997994) (xy 86.770972 -241.042444)
			(xy 86.871048 -241.14252)
		)
		(stroke
			(width 0)
			(type solid)
		)
		(fill yes)
		(layer "In2.Cu")
		(net "M_C_CPU1_SA_DQ<27>")
	)
	(gr_poly
		(pts
			(xy 86.971124 -239.826292) (xy 86.871048 -239.726216) (xy 86.770972 -239.826292) (xy 86.770972 -239.870742)
			(xy 86.971124 -239.870742)
		)
		(stroke
			(width 0)
			(type solid)
		)
		(fill yes)
		(layer "In2.Cu")
		(net "M_C_CPU1_SA_DQ<24>")
	)
	(gr_poly
		(pts
			(xy 86.971124 -239.422432) (xy 86.971124 -239.377982) (xy 86.770972 -239.377982) (xy 86.770972 -239.422432)
			(xy 86.871048 -239.522508)
		)
		(stroke
			(width 0)
			(type solid)
		)
		(fill yes)
		(layer "In2.Cu")
		(net "M_C_CPU1_SA_DQ<23>")
	)
	(gr_poly
		(pts
			(xy 86.971124 -238.20628) (xy 86.871048 -238.106204) (xy 86.770972 -238.20628) (xy 86.770972 -238.25073)
			(xy 86.971124 -238.25073)
		)
		(stroke
			(width 0)
			(type solid)
		)
		(fill yes)
		(layer "In2.Cu")
		(net "M_C_CPU1_SA_DQ<20>")
	)
	(gr_poly
		(pts
			(xy 86.971124 -237.802674) (xy 86.971124 -237.754922) (xy 86.770972 -237.754922) (xy 86.770972 -237.802674)
			(xy 86.871048 -237.902496)
		)
		(stroke
			(width 0)
			(type solid)
		)
		(fill yes)
		(layer "In2.Cu")
		(net "M_C_CPU1_SA_DQS_DP<7>")
	)
	(gr_poly
		(pts
			(xy 86.971124 -236.586014) (xy 86.871048 -236.486192) (xy 86.770972 -236.586014) (xy 86.770972 -236.633766)
			(xy 86.971124 -236.633766)
		)
		(stroke
			(width 0)
			(type solid)
		)
		(fill yes)
		(layer "In2.Cu")
		(net "M_C_CPU1_SA_DQS_DP<2>")
	)
	(gr_poly
		(pts
			(xy 86.971124 -236.182408) (xy 86.971124 -236.137958) (xy 86.770972 -236.137958) (xy 86.770972 -236.182408)
			(xy 86.871048 -236.282484)
		)
		(stroke
			(width 0)
			(type solid)
		)
		(fill yes)
		(layer "In2.Cu")
		(net "M_C_CPU1_SA_DQ<19>")
	)
	(gr_poly
		(pts
			(xy 86.971124 -234.966256) (xy 86.871048 -234.86618) (xy 86.770972 -234.966256) (xy 86.770972 -235.010706)
			(xy 86.971124 -235.010706)
		)
		(stroke
			(width 0)
			(type solid)
		)
		(fill yes)
		(layer "In2.Cu")
		(net "M_C_CPU1_SA_DQ<16>")
	)
	(gr_poly
		(pts
			(xy 86.971124 -234.562396) (xy 86.971124 -234.517946) (xy 86.770972 -234.517946) (xy 86.770972 -234.562396)
			(xy 86.871048 -234.662472)
		)
		(stroke
			(width 0)
			(type solid)
		)
		(fill yes)
		(layer "In2.Cu")
		(net "M_C_CPU1_SA_DQ<15>")
	)
	(gr_poly
		(pts
			(xy 86.971124 -233.346244) (xy 86.871048 -233.246168) (xy 86.770972 -233.346244) (xy 86.770972 -233.390694)
			(xy 86.971124 -233.390694)
		)
		(stroke
			(width 0)
			(type solid)
		)
		(fill yes)
		(layer "In2.Cu")
		(net "M_C_CPU1_SA_DQ<12>")
	)
	(gr_poly
		(pts
			(xy 86.971124 -232.942638) (xy 86.971124 -232.894886) (xy 86.770972 -232.894886) (xy 86.770972 -232.942638)
			(xy 86.871048 -233.04246)
		)
		(stroke
			(width 0)
			(type solid)
		)
		(fill yes)
		(layer "In2.Cu")
		(net "M_C_CPU1_SA_DQS_DP<6>")
	)
	(gr_poly
		(pts
			(xy 86.971124 -231.725978) (xy 86.871048 -231.626156) (xy 86.770972 -231.725978) (xy 86.770972 -231.77373)
			(xy 86.971124 -231.77373)
		)
		(stroke
			(width 0)
			(type solid)
		)
		(fill yes)
		(layer "In2.Cu")
		(net "M_C_CPU1_SA_DQS_DP<1>")
	)
	(gr_poly
		(pts
			(xy 86.971124 -231.322626) (xy 86.971124 -231.278176) (xy 86.770972 -231.278176) (xy 86.770972 -231.322626)
			(xy 86.871048 -231.422702)
		)
		(stroke
			(width 0)
			(type solid)
		)
		(fill yes)
		(layer "In2.Cu")
		(net "M_C_CPU1_SA_DQ<11>")
	)
	(gr_poly
		(pts
			(xy 86.971124 -230.10622) (xy 86.871048 -230.006144) (xy 86.770972 -230.10622) (xy 86.770972 -230.15067)
			(xy 86.971124 -230.15067)
		)
		(stroke
			(width 0)
			(type solid)
		)
		(fill yes)
		(layer "In2.Cu")
		(net "M_C_CPU1_SA_DQ<8>")
	)
	(gr_poly
		(pts
			(xy 86.971124 -229.702614) (xy 86.971124 -229.658164) (xy 86.770972 -229.658164) (xy 86.770972 -229.702614)
			(xy 86.871048 -229.80269)
		)
		(stroke
			(width 0)
			(type solid)
		)
		(fill yes)
		(layer "In2.Cu")
		(net "M_C_CPU1_SA_DQ<7>")
	)
	(gr_poly
		(pts
			(xy 86.971124 -228.486462) (xy 86.871048 -228.386386) (xy 86.770972 -228.486462) (xy 86.770972 -228.530912)
			(xy 86.971124 -228.530912)
		)
		(stroke
			(width 0)
			(type solid)
		)
		(fill yes)
		(layer "In2.Cu")
		(net "M_C_CPU1_SA_DQ<4>")
	)
	(gr_poly
		(pts
			(xy 86.971124 -228.082856) (xy 86.971124 -228.035104) (xy 86.770972 -228.035104) (xy 86.770972 -228.082856)
			(xy 86.871048 -228.182678)
		)
		(stroke
			(width 0)
			(type solid)
		)
		(fill yes)
		(layer "In2.Cu")
		(net "M_C_CPU1_SA_DQS_DP<5>")
	)
	(gr_poly
		(pts
			(xy 86.971124 -226.866196) (xy 86.871048 -226.766374) (xy 86.770972 -226.866196) (xy 86.770972 -226.913948)
			(xy 86.971124 -226.913948)
		)
		(stroke
			(width 0)
			(type solid)
		)
		(fill yes)
		(layer "In2.Cu")
		(net "M_C_CPU1_SA_DQS_DP<0>")
	)
	(gr_poly
		(pts
			(xy 86.971124 -226.46259) (xy 86.971124 -226.41814) (xy 86.770972 -226.41814) (xy 86.770972 -226.46259)
			(xy 86.871048 -226.562666)
		)
		(stroke
			(width 0)
			(type solid)
		)
		(fill yes)
		(layer "In2.Cu")
		(net "M_C_CPU1_SA_DQ<3>")
	)
	(gr_poly
		(pts
			(xy 86.971124 -225.246438) (xy 86.871048 -225.146362) (xy 86.770972 -225.246438) (xy 86.770972 -225.290888)
			(xy 86.971124 -225.290888)
		)
		(stroke
			(width 0)
			(type solid)
		)
		(fill yes)
		(layer "In2.Cu")
		(net "M_C_CPU1_SA_DQ<0>")
	)
	(gr_poly
		(pts
			(xy 87.271098 -292.918134) (xy 87.171022 -292.818058) (xy 87.070946 -292.918134) (xy 87.070946 -292.962584)
			(xy 87.271098 -292.962584)
		)
		(stroke
			(width 0)
			(type solid)
		)
		(fill yes)
		(layer "In2.Cu")
		(net "M_C_CPU1_SB_DQ<29>")
	)
	(gr_poly
		(pts
			(xy 87.271098 -292.514274) (xy 87.271098 -292.469824) (xy 87.070946 -292.469824) (xy 87.070946 -292.514274)
			(xy 87.171022 -292.61435)
		)
		(stroke
			(width 0)
			(type solid)
		)
		(fill yes)
		(layer "In2.Cu")
		(net "M_C_CPU1_SB_DQ<30>")
	)
	(gr_poly
		(pts
			(xy 87.271098 -291.297868) (xy 87.171022 -291.198046) (xy 87.070946 -291.297868) (xy 87.070946 -291.34562)
			(xy 87.271098 -291.34562)
		)
		(stroke
			(width 0)
			(type solid)
		)
		(fill yes)
		(layer "In2.Cu")
		(net "M_C_CPU1_SB_DQS_DN<8>")
	)
	(gr_poly
		(pts
			(xy 87.271098 -290.894516) (xy 87.271098 -290.846764) (xy 87.070946 -290.846764) (xy 87.070946 -290.894516)
			(xy 87.171022 -290.994338)
		)
		(stroke
			(width 0)
			(type solid)
		)
		(fill yes)
		(layer "In2.Cu")
		(net "M_C_CPU1_SB_DQS_DN<3>")
	)
	(gr_poly
		(pts
			(xy 87.271098 -289.67811) (xy 87.171022 -289.578034) (xy 87.070946 -289.67811) (xy 87.070946 -289.72256)
			(xy 87.271098 -289.72256)
		)
		(stroke
			(width 0)
			(type solid)
		)
		(fill yes)
		(layer "In2.Cu")
		(net "M_C_CPU1_SB_DQ<25>")
	)
	(gr_poly
		(pts
			(xy 87.271098 -289.27425) (xy 87.271098 -289.2298) (xy 87.070946 -289.2298) (xy 87.070946 -289.27425)
			(xy 87.171022 -289.374326)
		)
		(stroke
			(width 0)
			(type solid)
		)
		(fill yes)
		(layer "In2.Cu")
		(net "M_C_CPU1_SB_DQ<26>")
	)
	(gr_poly
		(pts
			(xy 87.271098 -288.058098) (xy 87.171022 -287.958022) (xy 87.070946 -288.058098) (xy 87.070946 -288.102548)
			(xy 87.271098 -288.102548)
		)
		(stroke
			(width 0)
			(type solid)
		)
		(fill yes)
		(layer "In2.Cu")
		(net "M_C_CPU1_SB_DQ<21>")
	)
	(gr_poly
		(pts
			(xy 87.271098 -287.654492) (xy 87.271098 -287.610042) (xy 87.070946 -287.610042) (xy 87.070946 -287.654492)
			(xy 87.171022 -287.754568)
		)
		(stroke
			(width 0)
			(type solid)
		)
		(fill yes)
		(layer "In2.Cu")
		(net "M_C_CPU1_SB_DQ<22>")
	)
	(gr_poly
		(pts
			(xy 87.271098 -286.438086) (xy 87.171022 -286.33801) (xy 87.070946 -286.438086) (xy 87.070946 -286.485838)
			(xy 87.271098 -286.485838)
		)
		(stroke
			(width 0)
			(type solid)
		)
		(fill yes)
		(layer "In2.Cu")
		(net "M_C_CPU1_SB_DQS_DN<7>")
	)
	(gr_poly
		(pts
			(xy 87.271098 -286.034734) (xy 87.271098 -285.986982) (xy 87.070946 -285.986982) (xy 87.070946 -286.034734)
			(xy 87.171022 -286.134556)
		)
		(stroke
			(width 0)
			(type solid)
		)
		(fill yes)
		(layer "In2.Cu")
		(net "M_C_CPU1_SB_DQS_DN<2>")
	)
	(gr_poly
		(pts
			(xy 87.271098 -284.818328) (xy 87.171022 -284.718252) (xy 87.070946 -284.818328) (xy 87.070946 -284.862778)
			(xy 87.271098 -284.862778)
		)
		(stroke
			(width 0)
			(type solid)
		)
		(fill yes)
		(layer "In2.Cu")
		(net "M_C_CPU1_SB_DQ<17>")
	)
	(gr_poly
		(pts
			(xy 87.271098 -284.414468) (xy 87.271098 -284.370018) (xy 87.070946 -284.370018) (xy 87.070946 -284.414468)
			(xy 87.171022 -284.514544)
		)
		(stroke
			(width 0)
			(type solid)
		)
		(fill yes)
		(layer "In2.Cu")
		(net "M_C_CPU1_SB_DQ<18>")
	)
	(gr_poly
		(pts
			(xy 87.271098 -283.198316) (xy 87.171022 -283.09824) (xy 87.070946 -283.198316) (xy 87.070946 -283.242766)
			(xy 87.271098 -283.242766)
		)
		(stroke
			(width 0)
			(type solid)
		)
		(fill yes)
		(layer "In2.Cu")
		(net "M_C_CPU1_SB_DQ<13>")
	)
	(gr_poly
		(pts
			(xy 87.271098 -282.794456) (xy 87.271098 -282.750006) (xy 87.070946 -282.750006) (xy 87.070946 -282.794456)
			(xy 87.171022 -282.894532)
		)
		(stroke
			(width 0)
			(type solid)
		)
		(fill yes)
		(layer "In2.Cu")
		(net "M_C_CPU1_SB_DQ<14>")
	)
	(gr_poly
		(pts
			(xy 87.271098 -281.57805) (xy 87.171022 -281.478228) (xy 87.070946 -281.57805) (xy 87.070946 -281.625802)
			(xy 87.271098 -281.625802)
		)
		(stroke
			(width 0)
			(type solid)
		)
		(fill yes)
		(layer "In2.Cu")
		(net "M_C_CPU1_SB_DQS_DN<6>")
	)
	(gr_poly
		(pts
			(xy 87.271098 -281.174698) (xy 87.271098 -281.126946) (xy 87.070946 -281.126946) (xy 87.070946 -281.174698)
			(xy 87.171022 -281.27452)
		)
		(stroke
			(width 0)
			(type solid)
		)
		(fill yes)
		(layer "In2.Cu")
		(net "M_C_CPU1_SB_DQS_DN<1>")
	)
	(gr_poly
		(pts
			(xy 87.271098 -279.958292) (xy 87.171022 -279.858216) (xy 87.070946 -279.958292) (xy 87.070946 -280.002742)
			(xy 87.271098 -280.002742)
		)
		(stroke
			(width 0)
			(type solid)
		)
		(fill yes)
		(layer "In2.Cu")
		(net "M_C_CPU1_SB_DQ<9>")
	)
	(gr_poly
		(pts
			(xy 87.271098 -279.554432) (xy 87.271098 -279.509982) (xy 87.070946 -279.509982) (xy 87.070946 -279.554432)
			(xy 87.171022 -279.654508)
		)
		(stroke
			(width 0)
			(type solid)
		)
		(fill yes)
		(layer "In2.Cu")
		(net "M_C_CPU1_SB_DQ<10>")
	)
	(gr_poly
		(pts
			(xy 87.271098 -278.33828) (xy 87.171022 -278.238204) (xy 87.070946 -278.33828) (xy 87.070946 -278.38273)
			(xy 87.271098 -278.38273)
		)
		(stroke
			(width 0)
			(type solid)
		)
		(fill yes)
		(layer "In2.Cu")
		(net "M_C_CPU1_SB_DQ<5>")
	)
	(gr_poly
		(pts
			(xy 87.271098 -277.93442) (xy 87.271098 -277.88997) (xy 87.070946 -277.88997) (xy 87.070946 -277.93442)
			(xy 87.171022 -278.034496)
		)
		(stroke
			(width 0)
			(type solid)
		)
		(fill yes)
		(layer "In2.Cu")
		(net "M_C_CPU1_SB_DQ<6>")
	)
	(gr_poly
		(pts
			(xy 87.271098 -276.718014) (xy 87.171022 -276.618192) (xy 87.070946 -276.718014) (xy 87.070946 -276.765766)
			(xy 87.271098 -276.765766)
		)
		(stroke
			(width 0)
			(type solid)
		)
		(fill yes)
		(layer "In2.Cu")
		(net "M_C_CPU1_SB_DQS_DN<5>")
	)
	(gr_poly
		(pts
			(xy 87.271098 -276.314662) (xy 87.271098 -276.26691) (xy 87.070946 -276.26691) (xy 87.070946 -276.314662)
			(xy 87.171022 -276.414484)
		)
		(stroke
			(width 0)
			(type solid)
		)
		(fill yes)
		(layer "In2.Cu")
		(net "M_C_CPU1_SB_DQS_DN<0>")
	)
	(gr_poly
		(pts
			(xy 87.271098 -275.098256) (xy 87.171022 -274.99818) (xy 87.070946 -275.098256) (xy 87.070946 -275.142706)
			(xy 87.271098 -275.142706)
		)
		(stroke
			(width 0)
			(type solid)
		)
		(fill yes)
		(layer "In2.Cu")
		(net "M_C_CPU1_SB_DQ<1>")
	)
	(gr_poly
		(pts
			(xy 87.271098 -274.694396) (xy 87.271098 -274.649946) (xy 87.070946 -274.649946) (xy 87.070946 -274.694396)
			(xy 87.171022 -274.794472)
		)
		(stroke
			(width 0)
			(type solid)
		)
		(fill yes)
		(layer "In2.Cu")
		(net "M_C_CPU1_SB_DQ<2>")
	)
	(gr_poly
		(pts
			(xy 87.271098 -273.478244) (xy 87.171022 -273.378168) (xy 87.070946 -273.478244) (xy 87.070946 -273.522694)
			(xy 87.271098 -273.522694)
		)
		(stroke
			(width 0)
			(type solid)
		)
		(fill yes)
		(layer "In2.Cu")
		(net "M_C_CPU1_SB_CB<1>")
	)
	(gr_poly
		(pts
			(xy 87.271098 -273.074384) (xy 87.271098 -273.029934) (xy 87.070946 -273.029934) (xy 87.070946 -273.074384)
			(xy 87.171022 -273.17446)
		)
		(stroke
			(width 0)
			(type solid)
		)
		(fill yes)
		(layer "In2.Cu")
		(net "M_C_CPU1_SB_CB<2>")
	)
	(gr_poly
		(pts
			(xy 87.271098 -271.857978) (xy 87.171022 -271.758156) (xy 87.070946 -271.857978) (xy 87.070946 -271.90573)
			(xy 87.271098 -271.90573)
		)
		(stroke
			(width 0)
			(type solid)
		)
		(fill yes)
		(layer "In2.Cu")
		(net "M_C_CPU1_SB_DQS_DN<4>")
	)
	(gr_poly
		(pts
			(xy 87.271098 -271.454626) (xy 87.271098 -271.406874) (xy 87.070946 -271.406874) (xy 87.070946 -271.454626)
			(xy 87.171022 -271.554448)
		)
		(stroke
			(width 0)
			(type solid)
		)
		(fill yes)
		(layer "In2.Cu")
		(net "M_C_CPU1_SB_DQS_DN<9>")
	)
	(gr_poly
		(pts
			(xy 87.271098 -270.23822) (xy 87.171022 -270.138144) (xy 87.070946 -270.23822) (xy 87.070946 -270.28267)
			(xy 87.271098 -270.28267)
		)
		(stroke
			(width 0)
			(type solid)
		)
		(fill yes)
		(layer "In2.Cu")
		(net "M_C_CPU1_SB_CB<5>")
	)
	(gr_poly
		(pts
			(xy 87.271098 -269.83436) (xy 87.271098 -269.78991) (xy 87.070946 -269.78991) (xy 87.070946 -269.83436)
			(xy 87.171022 -269.934436)
		)
		(stroke
			(width 0)
			(type solid)
		)
		(fill yes)
		(layer "In2.Cu")
		(net "M_C_CPU1_SB_CB<6>")
	)
	(gr_poly
		(pts
			(xy 87.271098 -266.991846) (xy 87.171022 -266.89177) (xy 87.070946 -266.991846) (xy 87.070946 -267.036296)
			(xy 87.271098 -267.036296)
		)
		(stroke
			(width 0)
			(type solid)
		)
		(fill yes)
		(layer "In2.Cu")
		(net "M_C_CPU1_SA_RSP<0>")
	)
	(gr_poly
		(pts
			(xy 87.271098 -266.594336) (xy 87.271098 -266.549886) (xy 87.070946 -266.549886) (xy 87.070946 -266.594336)
			(xy 87.171022 -266.694412)
		)
		(stroke
			(width 0)
			(type solid)
		)
		(fill yes)
		(layer "In2.Cu")
		(net "M_C_CPU1_SB_CS_N<1>")
	)
	(gr_poly
		(pts
			(xy 87.271098 -264.974324) (xy 87.271098 -264.929874) (xy 87.070946 -264.929874) (xy 87.070946 -264.974324)
			(xy 87.171022 -265.0744)
		)
		(stroke
			(width 0)
			(type solid)
		)
		(fill yes)
		(layer "In2.Cu")
		(net "M_C_CPU1_SB_PAR")
	)
	(gr_poly
		(pts
			(xy 87.271098 -263.758172) (xy 87.171022 -263.658096) (xy 87.070946 -263.758172) (xy 87.070946 -263.802622)
			(xy 87.271098 -263.802622)
		)
		(stroke
			(width 0)
			(type solid)
		)
		(fill yes)
		(layer "In2.Cu")
		(net "M_C_CPU1_SB_CA<4>")
	)
	(gr_poly
		(pts
			(xy 87.271098 -263.354312) (xy 87.271098 -263.309862) (xy 87.070946 -263.309862) (xy 87.070946 -263.354312)
			(xy 87.171022 -263.454388)
		)
		(stroke
			(width 0)
			(type solid)
		)
		(fill yes)
		(layer "In2.Cu")
		(net "M_C_CPU1_SB_CA<3>")
	)
	(gr_poly
		(pts
			(xy 87.271098 -262.13816) (xy 87.171022 -262.038084) (xy 87.070946 -262.13816) (xy 87.070946 -262.18261)
			(xy 87.271098 -262.18261)
		)
		(stroke
			(width 0)
			(type solid)
		)
		(fill yes)
		(layer "In2.Cu")
		(net "M_C_CPU1_SB_CA<0>")
	)
	(gr_poly
		(pts
			(xy 87.44077 -246.712486) (xy 87.44077 -246.664988) (xy 87.240872 -246.664988) (xy 87.240872 -246.712486)
			(xy 87.340694 -246.812562)
		)
		(stroke
			(width 0)
			(type solid)
		)
		(fill yes)
		(layer "In2.Cu")
		(net "M_C_CPU1_SA_DQS_DN<4>")
	)
	(gr_poly
		(pts
			(xy 87.441024 -256.432812) (xy 87.441024 -256.38506) (xy 87.240872 -256.38506) (xy 87.240872 -256.432812)
			(xy 87.340948 -256.532634)
		)
		(stroke
			(width 0)
			(type solid)
		)
		(fill yes)
		(layer "In2.Cu")
		(net "M_C_CPU1_CLK_DN<0>")
	)
	(gr_poly
		(pts
			(xy 87.441024 -255.216406) (xy 87.340948 -255.11633) (xy 87.240872 -255.216406) (xy 87.240872 -255.260856)
			(xy 87.441024 -255.260856)
		)
		(stroke
			(width 0)
			(type solid)
		)
		(fill yes)
		(layer "In2.Cu")
		(net "M_C_CPU1_SA_CA<6>")
	)
	(gr_poly
		(pts
			(xy 87.441024 -254.812546) (xy 87.441024 -254.768096) (xy 87.240872 -254.768096) (xy 87.240872 -254.812546)
			(xy 87.340948 -254.912622)
		)
		(stroke
			(width 0)
			(type solid)
		)
		(fill yes)
		(layer "In2.Cu")
		(net "M_C_CPU1_SA_CA<5>")
	)
	(gr_poly
		(pts
			(xy 87.441024 -253.596394) (xy 87.340948 -253.496318) (xy 87.240872 -253.596394) (xy 87.240872 -253.640844)
			(xy 87.441024 -253.640844)
		)
		(stroke
			(width 0)
			(type solid)
		)
		(fill yes)
		(layer "In2.Cu")
		(net "M_C_CPU1_SA_CA<2>")
	)
	(gr_poly
		(pts
			(xy 87.441024 -253.192534) (xy 87.441024 -253.148084) (xy 87.240872 -253.148084) (xy 87.240872 -253.192534)
			(xy 87.340948 -253.29261)
		)
		(stroke
			(width 0)
			(type solid)
		)
		(fill yes)
		(layer "In2.Cu")
		(net "M_C_CPU1_SA_CA<1>")
	)
	(gr_poly
		(pts
			(xy 87.441024 -251.572522) (xy 87.441024 -251.528072) (xy 87.240872 -251.528072) (xy 87.240872 -251.572522)
			(xy 87.340948 -251.672598)
		)
		(stroke
			(width 0)
			(type solid)
		)
		(fill yes)
		(layer "In2.Cu")
		(net "M_C_CPU1_SA_CS_N<0>")
	)
	(gr_poly
		(pts
			(xy 87.441024 -250.35637) (xy 87.340948 -250.256294) (xy 87.240872 -250.35637) (xy 87.240872 -250.40082)
			(xy 87.441024 -250.40082)
		)
		(stroke
			(width 0)
			(type solid)
		)
		(fill yes)
		(layer "In2.Cu")
		(net "M_C_CPU1_ALERT_R_N")
	)
	(gr_poly
		(pts
			(xy 87.441024 -248.736358) (xy 87.340948 -248.636282) (xy 87.240872 -248.736358) (xy 87.240872 -248.780808)
			(xy 87.441024 -248.780808)
		)
		(stroke
			(width 0)
			(type solid)
		)
		(fill yes)
		(layer "In2.Cu")
		(net "M_C_CPU1_SA_CB<5>")
	)
	(gr_poly
		(pts
			(xy 87.441024 -248.332498) (xy 87.441024 -248.288048) (xy 87.240872 -248.288048) (xy 87.240872 -248.332498)
			(xy 87.340948 -248.432574)
		)
		(stroke
			(width 0)
			(type solid)
		)
		(fill yes)
		(layer "In2.Cu")
		(net "M_C_CPU1_SA_CB<6>")
	)
	(gr_poly
		(pts
			(xy 87.441024 -247.116092) (xy 87.340948 -247.01627) (xy 87.240872 -247.116092) (xy 87.240872 -247.163844)
			(xy 87.441024 -247.163844)
		)
		(stroke
			(width 0)
			(type solid)
		)
		(fill yes)
		(layer "In2.Cu")
		(net "M_C_CPU1_SA_DQS_DN<9>")
	)
	(gr_poly
		(pts
			(xy 87.441024 -245.496334) (xy 87.340948 -245.396258) (xy 87.240872 -245.496334) (xy 87.240872 -245.540784)
			(xy 87.441024 -245.540784)
		)
		(stroke
			(width 0)
			(type solid)
		)
		(fill yes)
		(layer "In2.Cu")
		(net "M_C_CPU1_SA_CB<1>")
	)
	(gr_poly
		(pts
			(xy 87.441024 -245.092474) (xy 87.441024 -245.048024) (xy 87.240872 -245.048024) (xy 87.240872 -245.092474)
			(xy 87.340948 -245.19255)
		)
		(stroke
			(width 0)
			(type solid)
		)
		(fill yes)
		(layer "In2.Cu")
		(net "M_C_CPU1_SA_CB<2>")
	)
	(gr_poly
		(pts
			(xy 87.441024 -243.876322) (xy 87.340948 -243.776246) (xy 87.240872 -243.876322) (xy 87.240872 -243.920772)
			(xy 87.441024 -243.920772)
		)
		(stroke
			(width 0)
			(type solid)
		)
		(fill yes)
		(layer "In2.Cu")
		(net "M_C_CPU1_SA_DQ<29>")
	)
	(gr_poly
		(pts
			(xy 87.441024 -243.472462) (xy 87.441024 -243.428012) (xy 87.240872 -243.428012) (xy 87.240872 -243.472462)
			(xy 87.340948 -243.572538)
		)
		(stroke
			(width 0)
			(type solid)
		)
		(fill yes)
		(layer "In2.Cu")
		(net "M_C_CPU1_SA_DQ<30>")
	)
	(gr_poly
		(pts
			(xy 87.441024 -242.256056) (xy 87.340948 -242.156234) (xy 87.240872 -242.256056) (xy 87.240872 -242.303808)
			(xy 87.441024 -242.303808)
		)
		(stroke
			(width 0)
			(type solid)
		)
		(fill yes)
		(layer "In2.Cu")
		(net "M_C_CPU1_SA_DQS_DN<8>")
	)
	(gr_poly
		(pts
			(xy 87.441024 -241.852704) (xy 87.441024 -241.804952) (xy 87.240872 -241.804952) (xy 87.240872 -241.852704)
			(xy 87.340948 -241.952526)
		)
		(stroke
			(width 0)
			(type solid)
		)
		(fill yes)
		(layer "In2.Cu")
		(net "M_C_CPU1_SA_DQS_DN<3>")
	)
	(gr_poly
		(pts
			(xy 87.441024 -240.636298) (xy 87.340948 -240.536222) (xy 87.240872 -240.636298) (xy 87.240872 -240.680748)
			(xy 87.441024 -240.680748)
		)
		(stroke
			(width 0)
			(type solid)
		)
		(fill yes)
		(layer "In2.Cu")
		(net "M_C_CPU1_SA_DQ<25>")
	)
	(gr_poly
		(pts
			(xy 87.441024 -240.232438) (xy 87.441024 -240.187988) (xy 87.240872 -240.187988) (xy 87.240872 -240.232438)
			(xy 87.340948 -240.332514)
		)
		(stroke
			(width 0)
			(type solid)
		)
		(fill yes)
		(layer "In2.Cu")
		(net "M_C_CPU1_SA_DQ<26>")
	)
	(gr_poly
		(pts
			(xy 87.441024 -239.016286) (xy 87.340948 -238.91621) (xy 87.240872 -239.016286) (xy 87.240872 -239.060736)
			(xy 87.441024 -239.060736)
		)
		(stroke
			(width 0)
			(type solid)
		)
		(fill yes)
		(layer "In2.Cu")
		(net "M_C_CPU1_SA_DQ<21>")
	)
	(gr_poly
		(pts
			(xy 87.441024 -238.612426) (xy 87.441024 -238.567976) (xy 87.240872 -238.567976) (xy 87.240872 -238.612426)
			(xy 87.340948 -238.712502)
		)
		(stroke
			(width 0)
			(type solid)
		)
		(fill yes)
		(layer "In2.Cu")
		(net "M_C_CPU1_SA_DQ<22>")
	)
	(gr_poly
		(pts
			(xy 87.441024 -237.39602) (xy 87.340948 -237.296198) (xy 87.240872 -237.39602) (xy 87.240872 -237.443772)
			(xy 87.441024 -237.443772)
		)
		(stroke
			(width 0)
			(type solid)
		)
		(fill yes)
		(layer "In2.Cu")
		(net "M_C_CPU1_SA_DQS_DN<7>")
	)
	(gr_poly
		(pts
			(xy 87.441024 -236.992668) (xy 87.441024 -236.944916) (xy 87.240872 -236.944916) (xy 87.240872 -236.992668)
			(xy 87.340948 -237.09249)
		)
		(stroke
			(width 0)
			(type solid)
		)
		(fill yes)
		(layer "In2.Cu")
		(net "M_C_CPU1_SA_DQS_DN<2>")
	)
	(gr_poly
		(pts
			(xy 87.441024 -235.776262) (xy 87.340948 -235.676186) (xy 87.240872 -235.776262) (xy 87.240872 -235.820712)
			(xy 87.441024 -235.820712)
		)
		(stroke
			(width 0)
			(type solid)
		)
		(fill yes)
		(layer "In2.Cu")
		(net "M_C_CPU1_SA_DQ<17>")
	)
	(gr_poly
		(pts
			(xy 87.441024 -235.372402) (xy 87.441024 -235.327952) (xy 87.240872 -235.327952) (xy 87.240872 -235.372402)
			(xy 87.340948 -235.472478)
		)
		(stroke
			(width 0)
			(type solid)
		)
		(fill yes)
		(layer "In2.Cu")
		(net "M_C_CPU1_SA_DQ<18>")
	)
	(gr_poly
		(pts
			(xy 87.441024 -234.15625) (xy 87.340948 -234.056174) (xy 87.240872 -234.15625) (xy 87.240872 -234.2007)
			(xy 87.441024 -234.2007)
		)
		(stroke
			(width 0)
			(type solid)
		)
		(fill yes)
		(layer "In2.Cu")
		(net "M_C_CPU1_SA_DQ<13>")
	)
	(gr_poly
		(pts
			(xy 87.441024 -233.75239) (xy 87.441024 -233.70794) (xy 87.240872 -233.70794) (xy 87.240872 -233.75239)
			(xy 87.340948 -233.852466)
		)
		(stroke
			(width 0)
			(type solid)
		)
		(fill yes)
		(layer "In2.Cu")
		(net "M_C_CPU1_SA_DQ<14>")
	)
	(gr_poly
		(pts
			(xy 87.441024 -232.535984) (xy 87.340948 -232.436162) (xy 87.240872 -232.535984) (xy 87.240872 -232.583736)
			(xy 87.441024 -232.583736)
		)
		(stroke
			(width 0)
			(type solid)
		)
		(fill yes)
		(layer "In2.Cu")
		(net "M_C_CPU1_SA_DQS_DN<6>")
	)
	(gr_poly
		(pts
			(xy 87.441024 -232.132632) (xy 87.441024 -232.08488) (xy 87.240872 -232.08488) (xy 87.240872 -232.132632)
			(xy 87.340948 -232.232454)
		)
		(stroke
			(width 0)
			(type solid)
		)
		(fill yes)
		(layer "In2.Cu")
		(net "M_C_CPU1_SA_DQS_DN<1>")
	)
	(gr_poly
		(pts
			(xy 87.441024 -230.916226) (xy 87.340948 -230.81615) (xy 87.240872 -230.916226) (xy 87.240872 -230.960676)
			(xy 87.441024 -230.960676)
		)
		(stroke
			(width 0)
			(type solid)
		)
		(fill yes)
		(layer "In2.Cu")
		(net "M_C_CPU1_SA_DQ<9>")
	)
	(gr_poly
		(pts
			(xy 87.441024 -230.51262) (xy 87.441024 -230.46817) (xy 87.240872 -230.46817) (xy 87.240872 -230.51262)
			(xy 87.340948 -230.612696)
		)
		(stroke
			(width 0)
			(type solid)
		)
		(fill yes)
		(layer "In2.Cu")
		(net "M_C_CPU1_SA_DQ<10>")
	)
	(gr_poly
		(pts
			(xy 87.441024 -229.296214) (xy 87.340948 -229.196138) (xy 87.240872 -229.296214) (xy 87.240872 -229.340664)
			(xy 87.441024 -229.340664)
		)
		(stroke
			(width 0)
			(type solid)
		)
		(fill yes)
		(layer "In2.Cu")
		(net "M_C_CPU1_SA_DQ<5>")
	)
	(gr_poly
		(pts
			(xy 87.441024 -228.892608) (xy 87.441024 -228.848158) (xy 87.240872 -228.848158) (xy 87.240872 -228.892608)
			(xy 87.340948 -228.992684)
		)
		(stroke
			(width 0)
			(type solid)
		)
		(fill yes)
		(layer "In2.Cu")
		(net "M_C_CPU1_SA_DQ<6>")
	)
	(gr_poly
		(pts
			(xy 87.441024 -227.676202) (xy 87.340948 -227.57638) (xy 87.240872 -227.676202) (xy 87.240872 -227.723954)
			(xy 87.441024 -227.723954)
		)
		(stroke
			(width 0)
			(type solid)
		)
		(fill yes)
		(layer "In2.Cu")
		(net "M_C_CPU1_SA_DQS_DN<5>")
	)
	(gr_poly
		(pts
			(xy 87.441024 -227.27285) (xy 87.441024 -227.225098) (xy 87.240872 -227.225098) (xy 87.240872 -227.27285)
			(xy 87.340948 -227.372672)
		)
		(stroke
			(width 0)
			(type solid)
		)
		(fill yes)
		(layer "In2.Cu")
		(net "M_C_CPU1_SA_DQS_DN<0>")
	)
	(gr_poly
		(pts
			(xy 87.441024 -226.056444) (xy 87.340948 -225.956368) (xy 87.240872 -226.056444) (xy 87.240872 -226.100894)
			(xy 87.441024 -226.100894)
		)
		(stroke
			(width 0)
			(type solid)
		)
		(fill yes)
		(layer "In2.Cu")
		(net "M_C_CPU1_SA_DQ<1>")
	)
	(gr_poly
		(pts
			(xy 87.441024 -225.652584) (xy 87.441024 -225.608134) (xy 87.240872 -225.608134) (xy 87.240872 -225.652584)
			(xy 87.340948 -225.75266)
		)
		(stroke
			(width 0)
			(type solid)
		)
		(fill yes)
		(layer "In2.Cu")
		(net "M_C_CPU1_SA_DQ<2>")
	)
	(gr_poly
		(pts
			(xy 87.740998 -293.32428) (xy 87.740998 -293.27983) (xy 87.540846 -293.27983) (xy 87.540846 -293.32428)
			(xy 87.640922 -293.424356)
		)
		(stroke
			(width 0)
			(type solid)
		)
		(fill yes)
		(layer "In2.Cu")
		(net "M_C_CPU1_SB_DQ<31>")
	)
	(gr_poly
		(pts
			(xy 87.740998 -292.108128) (xy 87.640922 -292.008052) (xy 87.540846 -292.108128) (xy 87.540846 -292.152578)
			(xy 87.740998 -292.152578)
		)
		(stroke
			(width 0)
			(type solid)
		)
		(fill yes)
		(layer "In2.Cu")
		(net "M_C_CPU1_SB_DQ<28>")
	)
	(gr_poly
		(pts
			(xy 87.740998 -291.704522) (xy 87.740998 -291.65677) (xy 87.540846 -291.65677) (xy 87.540846 -291.704522)
			(xy 87.640922 -291.804344)
		)
		(stroke
			(width 0)
			(type solid)
		)
		(fill yes)
		(layer "In2.Cu")
		(net "M_C_CPU1_SB_DQS_DP<8>")
	)
	(gr_poly
		(pts
			(xy 87.740998 -290.487862) (xy 87.640922 -290.38804) (xy 87.540846 -290.487862) (xy 87.540846 -290.535614)
			(xy 87.740998 -290.535614)
		)
		(stroke
			(width 0)
			(type solid)
		)
		(fill yes)
		(layer "In2.Cu")
		(net "M_C_CPU1_SB_DQS_DP<3>")
	)
	(gr_poly
		(pts
			(xy 87.740998 -290.084256) (xy 87.740998 -290.039806) (xy 87.540846 -290.039806) (xy 87.540846 -290.084256)
			(xy 87.640922 -290.184332)
		)
		(stroke
			(width 0)
			(type solid)
		)
		(fill yes)
		(layer "In2.Cu")
		(net "M_C_CPU1_SB_DQ<27>")
	)
	(gr_poly
		(pts
			(xy 87.740998 -288.868104) (xy 87.640922 -288.768028) (xy 87.540846 -288.868104) (xy 87.540846 -288.912554)
			(xy 87.740998 -288.912554)
		)
		(stroke
			(width 0)
			(type solid)
		)
		(fill yes)
		(layer "In2.Cu")
		(net "M_C_CPU1_SB_DQ<24>")
	)
	(gr_poly
		(pts
			(xy 87.740998 -288.464498) (xy 87.740998 -288.420048) (xy 87.540846 -288.420048) (xy 87.540846 -288.464498)
			(xy 87.640922 -288.564574)
		)
		(stroke
			(width 0)
			(type solid)
		)
		(fill yes)
		(layer "In2.Cu")
		(net "M_C_CPU1_SB_DQ<23>")
	)
	(gr_poly
		(pts
			(xy 87.740998 -287.248092) (xy 87.640922 -287.148016) (xy 87.540846 -287.248092) (xy 87.540846 -287.292542)
			(xy 87.740998 -287.292542)
		)
		(stroke
			(width 0)
			(type solid)
		)
		(fill yes)
		(layer "In2.Cu")
		(net "M_C_CPU1_SB_DQ<20>")
	)
	(gr_poly
		(pts
			(xy 87.740998 -286.844486) (xy 87.740998 -286.796734) (xy 87.540846 -286.796734) (xy 87.540846 -286.844486)
			(xy 87.640922 -286.944562)
		)
		(stroke
			(width 0)
			(type solid)
		)
		(fill yes)
		(layer "In2.Cu")
		(net "M_C_CPU1_SB_DQS_DP<7>")
	)
	(gr_poly
		(pts
			(xy 87.740998 -285.62808) (xy 87.640922 -285.528258) (xy 87.540846 -285.62808) (xy 87.540846 -285.675832)
			(xy 87.740998 -285.675832)
		)
		(stroke
			(width 0)
			(type solid)
		)
		(fill yes)
		(layer "In2.Cu")
		(net "M_C_CPU1_SB_DQS_DP<2>")
	)
	(gr_poly
		(pts
			(xy 87.740998 -285.224474) (xy 87.740998 -285.180024) (xy 87.540846 -285.180024) (xy 87.540846 -285.224474)
			(xy 87.640922 -285.32455)
		)
		(stroke
			(width 0)
			(type solid)
		)
		(fill yes)
		(layer "In2.Cu")
		(net "M_C_CPU1_SB_DQ<19>")
	)
	(gr_poly
		(pts
			(xy 87.740998 -284.008322) (xy 87.640922 -283.908246) (xy 87.540846 -284.008322) (xy 87.540846 -284.052772)
			(xy 87.740998 -284.052772)
		)
		(stroke
			(width 0)
			(type solid)
		)
		(fill yes)
		(layer "In2.Cu")
		(net "M_C_CPU1_SB_DQ<16>")
	)
	(gr_poly
		(pts
			(xy 87.740998 -283.604462) (xy 87.740998 -283.560012) (xy 87.540846 -283.560012) (xy 87.540846 -283.604462)
			(xy 87.640922 -283.704538)
		)
		(stroke
			(width 0)
			(type solid)
		)
		(fill yes)
		(layer "In2.Cu")
		(net "M_C_CPU1_SB_DQ<15>")
	)
	(gr_poly
		(pts
			(xy 87.740998 -282.38831) (xy 87.640922 -282.288234) (xy 87.540846 -282.38831) (xy 87.540846 -282.43276)
			(xy 87.740998 -282.43276)
		)
		(stroke
			(width 0)
			(type solid)
		)
		(fill yes)
		(layer "In2.Cu")
		(net "M_C_CPU1_SB_DQ<12>")
	)
	(gr_poly
		(pts
			(xy 87.740998 -281.984704) (xy 87.740998 -281.936952) (xy 87.540846 -281.936952) (xy 87.540846 -281.984704)
			(xy 87.640922 -282.084526)
		)
		(stroke
			(width 0)
			(type solid)
		)
		(fill yes)
		(layer "In2.Cu")
		(net "M_C_CPU1_SB_DQS_DP<6>")
	)
	(gr_poly
		(pts
			(xy 87.740998 -280.768044) (xy 87.640922 -280.668222) (xy 87.540846 -280.768044) (xy 87.540846 -280.815796)
			(xy 87.740998 -280.815796)
		)
		(stroke
			(width 0)
			(type solid)
		)
		(fill yes)
		(layer "In2.Cu")
		(net "M_C_CPU1_SB_DQS_DP<1>")
	)
	(gr_poly
		(pts
			(xy 87.740998 -280.364438) (xy 87.740998 -280.319988) (xy 87.540846 -280.319988) (xy 87.540846 -280.364438)
			(xy 87.640922 -280.464514)
		)
		(stroke
			(width 0)
			(type solid)
		)
		(fill yes)
		(layer "In2.Cu")
		(net "M_C_CPU1_SB_DQ<11>")
	)
	(gr_poly
		(pts
			(xy 87.740998 -279.148286) (xy 87.640922 -279.04821) (xy 87.540846 -279.148286) (xy 87.540846 -279.192736)
			(xy 87.740998 -279.192736)
		)
		(stroke
			(width 0)
			(type solid)
		)
		(fill yes)
		(layer "In2.Cu")
		(net "M_C_CPU1_SB_DQ<8>")
	)
	(gr_poly
		(pts
			(xy 87.740998 -278.744426) (xy 87.740998 -278.699976) (xy 87.540846 -278.699976) (xy 87.540846 -278.744426)
			(xy 87.640922 -278.844502)
		)
		(stroke
			(width 0)
			(type solid)
		)
		(fill yes)
		(layer "In2.Cu")
		(net "M_C_CPU1_SB_DQ<7>")
	)
	(gr_poly
		(pts
			(xy 87.740998 -277.528274) (xy 87.640922 -277.428198) (xy 87.540846 -277.528274) (xy 87.540846 -277.572724)
			(xy 87.740998 -277.572724)
		)
		(stroke
			(width 0)
			(type solid)
		)
		(fill yes)
		(layer "In2.Cu")
		(net "M_C_CPU1_SB_DQ<4>")
	)
	(gr_poly
		(pts
			(xy 87.740998 -277.124668) (xy 87.740998 -277.076916) (xy 87.540846 -277.076916) (xy 87.540846 -277.124668)
			(xy 87.640922 -277.22449)
		)
		(stroke
			(width 0)
			(type solid)
		)
		(fill yes)
		(layer "In2.Cu")
		(net "M_C_CPU1_SB_DQS_DP<5>")
	)
	(gr_poly
		(pts
			(xy 87.740998 -275.908008) (xy 87.640922 -275.808186) (xy 87.540846 -275.908008) (xy 87.540846 -275.95576)
			(xy 87.740998 -275.95576)
		)
		(stroke
			(width 0)
			(type solid)
		)
		(fill yes)
		(layer "In2.Cu")
		(net "M_C_CPU1_SB_DQS_DP<0>")
	)
	(gr_poly
		(pts
			(xy 87.740998 -275.504402) (xy 87.740998 -275.459952) (xy 87.540846 -275.459952) (xy 87.540846 -275.504402)
			(xy 87.640922 -275.604478)
		)
		(stroke
			(width 0)
			(type solid)
		)
		(fill yes)
		(layer "In2.Cu")
		(net "M_C_CPU1_SB_DQ<3>")
	)
	(gr_poly
		(pts
			(xy 87.740998 -274.28825) (xy 87.640922 -274.188174) (xy 87.540846 -274.28825) (xy 87.540846 -274.3327)
			(xy 87.740998 -274.3327)
		)
		(stroke
			(width 0)
			(type solid)
		)
		(fill yes)
		(layer "In2.Cu")
		(net "M_C_CPU1_SB_DQ<0>")
	)
	(gr_poly
		(pts
			(xy 87.740998 -273.88439) (xy 87.740998 -273.83994) (xy 87.540846 -273.83994) (xy 87.540846 -273.88439)
			(xy 87.640922 -273.984466)
		)
		(stroke
			(width 0)
			(type solid)
		)
		(fill yes)
		(layer "In2.Cu")
		(net "M_C_CPU1_SB_CB<3>")
	)
	(gr_poly
		(pts
			(xy 87.740998 -272.668238) (xy 87.640922 -272.568162) (xy 87.540846 -272.668238) (xy 87.540846 -272.712688)
			(xy 87.740998 -272.712688)
		)
		(stroke
			(width 0)
			(type solid)
		)
		(fill yes)
		(layer "In2.Cu")
		(net "M_C_CPU1_SB_CB<0>")
	)
	(gr_poly
		(pts
			(xy 87.740998 -272.264632) (xy 87.740998 -272.21688) (xy 87.540846 -272.21688) (xy 87.540846 -272.264632)
			(xy 87.640922 -272.364454)
		)
		(stroke
			(width 0)
			(type solid)
		)
		(fill yes)
		(layer "In2.Cu")
		(net "M_C_CPU1_SB_DQS_DP<4>")
	)
	(gr_poly
		(pts
			(xy 87.740998 -271.047972) (xy 87.640922 -270.94815) (xy 87.540846 -271.047972) (xy 87.540846 -271.095724)
			(xy 87.740998 -271.095724)
		)
		(stroke
			(width 0)
			(type solid)
		)
		(fill yes)
		(layer "In2.Cu")
		(net "M_C_CPU1_SB_DQS_DP<9>")
	)
	(gr_poly
		(pts
			(xy 87.740998 -270.644366) (xy 87.740998 -270.599916) (xy 87.540846 -270.599916) (xy 87.540846 -270.644366)
			(xy 87.640922 -270.744442)
		)
		(stroke
			(width 0)
			(type solid)
		)
		(fill yes)
		(layer "In2.Cu")
		(net "M_C_CPU1_SB_CB<7>")
	)
	(gr_poly
		(pts
			(xy 87.740998 -269.428214) (xy 87.640922 -269.328138) (xy 87.540846 -269.428214) (xy 87.540846 -269.472664)
			(xy 87.740998 -269.472664)
		)
		(stroke
			(width 0)
			(type solid)
		)
		(fill yes)
		(layer "In2.Cu")
		(net "M_C_CPU1_SB_CB<4>")
	)
	(gr_poly
		(pts
			(xy 87.740998 -265.78433) (xy 87.740998 -265.73988) (xy 87.540846 -265.73988) (xy 87.540846 -265.78433)
			(xy 87.640922 -265.884406)
		)
		(stroke
			(width 0)
			(type solid)
		)
		(fill yes)
		(layer "In2.Cu")
		(net "M_C_CPU1_SB_CS_N<0>")
	)
	(gr_poly
		(pts
			(xy 87.740998 -264.568178) (xy 87.640922 -264.468102) (xy 87.540846 -264.568178) (xy 87.540846 -264.612628)
			(xy 87.740998 -264.612628)
		)
		(stroke
			(width 0)
			(type solid)
		)
		(fill yes)
		(layer "In2.Cu")
		(net "M_C_CPU1_SB_CA<6>")
	)
	(gr_poly
		(pts
			(xy 87.740998 -264.164318) (xy 87.740998 -264.119868) (xy 87.540846 -264.119868) (xy 87.540846 -264.164318)
			(xy 87.640922 -264.264394)
		)
		(stroke
			(width 0)
			(type solid)
		)
		(fill yes)
		(layer "In2.Cu")
		(net "M_C_CPU1_SB_CA<5>")
	)
	(gr_poly
		(pts
			(xy 87.740998 -262.948166) (xy 87.640922 -262.84809) (xy 87.540846 -262.948166) (xy 87.540846 -262.992616)
			(xy 87.740998 -262.992616)
		)
		(stroke
			(width 0)
			(type solid)
		)
		(fill yes)
		(layer "In2.Cu")
		(net "M_C_CPU1_SB_CA<2>")
	)
	(gr_poly
		(pts
			(xy 87.740998 -262.544306) (xy 87.740998 -262.499856) (xy 87.540846 -262.499856) (xy 87.540846 -262.544306)
			(xy 87.640922 -262.644382)
		)
		(stroke
			(width 0)
			(type solid)
		)
		(fill yes)
		(layer "In2.Cu")
		(net "M_C_CPU1_SB_CA<1>")
	)
	(gr_poly
		(pts
			(xy 87.747094 -267.801852) (xy 87.647272 -267.701776) (xy 87.547196 -267.801852) (xy 87.547196 -267.846302)
			(xy 87.747094 -267.846302)
		)
		(stroke
			(width 0)
			(type solid)
		)
		(fill yes)
		(layer "In2.Cu")
		(net "M_C_CPU1_SB_RSP<0>")
	)
	(gr_poly
		(pts
			(xy 87.911178 -256.026158) (xy 87.811102 -255.926336) (xy 87.711026 -256.026158) (xy 87.711026 -256.07391)
			(xy 87.911178 -256.07391)
		)
		(stroke
			(width 0)
			(type solid)
		)
		(fill yes)
		(layer "In2.Cu")
		(net "M_C_CPU1_CLK_DP<0>")
	)
	(gr_poly
		(pts
			(xy 87.911178 -255.622552) (xy 87.911178 -255.578102) (xy 87.711026 -255.578102) (xy 87.711026 -255.622552)
			(xy 87.811102 -255.722628)
		)
		(stroke
			(width 0)
			(type solid)
		)
		(fill yes)
		(layer "In2.Cu")
		(net "M_C_CPU1_SA_PAR")
	)
	(gr_poly
		(pts
			(xy 87.911178 -254.4064) (xy 87.811102 -254.306324) (xy 87.711026 -254.4064) (xy 87.711026 -254.45085)
			(xy 87.911178 -254.45085)
		)
		(stroke
			(width 0)
			(type solid)
		)
		(fill yes)
		(layer "In2.Cu")
		(net "M_C_CPU1_SA_CA<4>")
	)
	(gr_poly
		(pts
			(xy 87.911178 -254.00254) (xy 87.911178 -253.95809) (xy 87.711026 -253.95809) (xy 87.711026 -254.00254)
			(xy 87.811102 -254.102616)
		)
		(stroke
			(width 0)
			(type solid)
		)
		(fill yes)
		(layer "In2.Cu")
		(net "M_C_CPU1_SA_CA<3>")
	)
	(gr_poly
		(pts
			(xy 87.911178 -252.786388) (xy 87.811102 -252.686312) (xy 87.711026 -252.786388) (xy 87.711026 -252.830838)
			(xy 87.911178 -252.830838)
		)
		(stroke
			(width 0)
			(type solid)
		)
		(fill yes)
		(layer "In2.Cu")
		(net "M_C_CPU1_SA_CA<0>")
	)
	(gr_poly
		(pts
			(xy 87.911178 -252.382528) (xy 87.911178 -252.338078) (xy 87.711026 -252.338078) (xy 87.711026 -252.382528)
			(xy 87.811102 -252.482604)
		)
		(stroke
			(width 0)
			(type solid)
		)
		(fill yes)
		(layer "In2.Cu")
		(net "M_C_CPU1_SA_CS_N<1>")
	)
	(gr_poly
		(pts
			(xy 87.911178 -250.762516) (xy 87.911178 -250.718066) (xy 87.711026 -250.718066) (xy 87.711026 -250.762516)
			(xy 87.811102 -250.862592)
		)
		(stroke
			(width 0)
			(type solid)
		)
		(fill yes)
		(layer "In2.Cu")
		(net "M_C_CPU1_RESET_N")
	)
	(gr_poly
		(pts
			(xy 87.911178 -249.142504) (xy 87.911178 -249.098054) (xy 87.711026 -249.098054) (xy 87.711026 -249.142504)
			(xy 87.811102 -249.24258)
		)
		(stroke
			(width 0)
			(type solid)
		)
		(fill yes)
		(layer "In2.Cu")
		(net "M_C_CPU1_SA_CB<7>")
	)
	(gr_poly
		(pts
			(xy 87.911178 -247.926352) (xy 87.811102 -247.826276) (xy 87.711026 -247.926352) (xy 87.711026 -247.970802)
			(xy 87.911178 -247.970802)
		)
		(stroke
			(width 0)
			(type solid)
		)
		(fill yes)
		(layer "In2.Cu")
		(net "M_C_CPU1_SA_CB<4>")
	)
	(gr_poly
		(pts
			(xy 87.911178 -247.522746) (xy 87.911178 -247.474994) (xy 87.711026 -247.474994) (xy 87.711026 -247.522746)
			(xy 87.811102 -247.622568)
		)
		(stroke
			(width 0)
			(type solid)
		)
		(fill yes)
		(layer "In2.Cu")
		(net "M_C_CPU1_SA_DQS_DP<9>")
	)
	(gr_poly
		(pts
			(xy 87.911178 -246.306086) (xy 87.811102 -246.206264) (xy 87.711026 -246.306086) (xy 87.711026 -246.353838)
			(xy 87.911178 -246.353838)
		)
		(stroke
			(width 0)
			(type solid)
		)
		(fill yes)
		(layer "In2.Cu")
		(net "M_C_CPU1_SA_DQS_DP<4>")
	)
	(gr_poly
		(pts
			(xy 87.911178 -245.90248) (xy 87.911178 -245.85803) (xy 87.711026 -245.85803) (xy 87.711026 -245.90248)
			(xy 87.811102 -246.002556)
		)
		(stroke
			(width 0)
			(type solid)
		)
		(fill yes)
		(layer "In2.Cu")
		(net "M_C_CPU1_SA_CB<3>")
	)
	(gr_poly
		(pts
			(xy 87.911178 -244.686328) (xy 87.811102 -244.586252) (xy 87.711026 -244.686328) (xy 87.711026 -244.730778)
			(xy 87.911178 -244.730778)
		)
		(stroke
			(width 0)
			(type solid)
		)
		(fill yes)
		(layer "In2.Cu")
		(net "M_C_CPU1_SA_CB<0>")
	)
	(gr_poly
		(pts
			(xy 87.911178 -244.282468) (xy 87.911178 -244.238018) (xy 87.711026 -244.238018) (xy 87.711026 -244.282468)
			(xy 87.811102 -244.382544)
		)
		(stroke
			(width 0)
			(type solid)
		)
		(fill yes)
		(layer "In2.Cu")
		(net "M_C_CPU1_SA_DQ<31>")
	)
	(gr_poly
		(pts
			(xy 87.911178 -243.066316) (xy 87.811102 -242.96624) (xy 87.711026 -243.066316) (xy 87.711026 -243.110766)
			(xy 87.911178 -243.110766)
		)
		(stroke
			(width 0)
			(type solid)
		)
		(fill yes)
		(layer "In2.Cu")
		(net "M_C_CPU1_SA_DQ<28>")
	)
	(gr_poly
		(pts
			(xy 87.911178 -242.66271) (xy 87.911178 -242.614958) (xy 87.711026 -242.614958) (xy 87.711026 -242.66271)
			(xy 87.811102 -242.762532)
		)
		(stroke
			(width 0)
			(type solid)
		)
		(fill yes)
		(layer "In2.Cu")
		(net "M_C_CPU1_SA_DQS_DP<8>")
	)
	(gr_poly
		(pts
			(xy 87.911178 -241.44605) (xy 87.811102 -241.346228) (xy 87.711026 -241.44605) (xy 87.711026 -241.493802)
			(xy 87.911178 -241.493802)
		)
		(stroke
			(width 0)
			(type solid)
		)
		(fill yes)
		(layer "In2.Cu")
		(net "M_C_CPU1_SA_DQS_DP<3>")
	)
	(gr_poly
		(pts
			(xy 87.911178 -241.042444) (xy 87.911178 -240.997994) (xy 87.711026 -240.997994) (xy 87.711026 -241.042444)
			(xy 87.811102 -241.14252)
		)
		(stroke
			(width 0)
			(type solid)
		)
		(fill yes)
		(layer "In2.Cu")
		(net "M_C_CPU1_SA_DQ<27>")
	)
	(gr_poly
		(pts
			(xy 87.911178 -239.826292) (xy 87.811102 -239.726216) (xy 87.711026 -239.826292) (xy 87.711026 -239.870742)
			(xy 87.911178 -239.870742)
		)
		(stroke
			(width 0)
			(type solid)
		)
		(fill yes)
		(layer "In2.Cu")
		(net "M_C_CPU1_SA_DQ<24>")
	)
	(gr_poly
		(pts
			(xy 87.911178 -239.422432) (xy 87.911178 -239.377982) (xy 87.711026 -239.377982) (xy 87.711026 -239.422432)
			(xy 87.811102 -239.522508)
		)
		(stroke
			(width 0)
			(type solid)
		)
		(fill yes)
		(layer "In2.Cu")
		(net "M_C_CPU1_SA_DQ<23>")
	)
	(gr_poly
		(pts
			(xy 87.911178 -238.20628) (xy 87.811102 -238.106204) (xy 87.711026 -238.20628) (xy 87.711026 -238.25073)
			(xy 87.911178 -238.25073)
		)
		(stroke
			(width 0)
			(type solid)
		)
		(fill yes)
		(layer "In2.Cu")
		(net "M_C_CPU1_SA_DQ<20>")
	)
	(gr_poly
		(pts
			(xy 87.911178 -237.802674) (xy 87.911178 -237.754922) (xy 87.711026 -237.754922) (xy 87.711026 -237.802674)
			(xy 87.811102 -237.902496)
		)
		(stroke
			(width 0)
			(type solid)
		)
		(fill yes)
		(layer "In2.Cu")
		(net "M_C_CPU1_SA_DQS_DP<7>")
	)
	(gr_poly
		(pts
			(xy 87.911178 -236.586014) (xy 87.811102 -236.486192) (xy 87.711026 -236.586014) (xy 87.711026 -236.633766)
			(xy 87.911178 -236.633766)
		)
		(stroke
			(width 0)
			(type solid)
		)
		(fill yes)
		(layer "In2.Cu")
		(net "M_C_CPU1_SA_DQS_DP<2>")
	)
	(gr_poly
		(pts
			(xy 87.911178 -236.182408) (xy 87.911178 -236.137958) (xy 87.711026 -236.137958) (xy 87.711026 -236.182408)
			(xy 87.811102 -236.282484)
		)
		(stroke
			(width 0)
			(type solid)
		)
		(fill yes)
		(layer "In2.Cu")
		(net "M_C_CPU1_SA_DQ<19>")
	)
	(gr_poly
		(pts
			(xy 87.911178 -234.966256) (xy 87.811102 -234.86618) (xy 87.711026 -234.966256) (xy 87.711026 -235.010706)
			(xy 87.911178 -235.010706)
		)
		(stroke
			(width 0)
			(type solid)
		)
		(fill yes)
		(layer "In2.Cu")
		(net "M_C_CPU1_SA_DQ<16>")
	)
	(gr_poly
		(pts
			(xy 87.911178 -234.562396) (xy 87.911178 -234.517946) (xy 87.711026 -234.517946) (xy 87.711026 -234.562396)
			(xy 87.811102 -234.662472)
		)
		(stroke
			(width 0)
			(type solid)
		)
		(fill yes)
		(layer "In2.Cu")
		(net "M_C_CPU1_SA_DQ<15>")
	)
	(gr_poly
		(pts
			(xy 87.911178 -233.346244) (xy 87.811102 -233.246168) (xy 87.711026 -233.346244) (xy 87.711026 -233.390694)
			(xy 87.911178 -233.390694)
		)
		(stroke
			(width 0)
			(type solid)
		)
		(fill yes)
		(layer "In2.Cu")
		(net "M_C_CPU1_SA_DQ<12>")
	)
	(gr_poly
		(pts
			(xy 87.911178 -232.942638) (xy 87.911178 -232.894886) (xy 87.711026 -232.894886) (xy 87.711026 -232.942638)
			(xy 87.811102 -233.04246)
		)
		(stroke
			(width 0)
			(type solid)
		)
		(fill yes)
		(layer "In2.Cu")
		(net "M_C_CPU1_SA_DQS_DP<6>")
	)
	(gr_poly
		(pts
			(xy 87.911178 -231.725978) (xy 87.811102 -231.626156) (xy 87.711026 -231.725978) (xy 87.711026 -231.77373)
			(xy 87.911178 -231.77373)
		)
		(stroke
			(width 0)
			(type solid)
		)
		(fill yes)
		(layer "In2.Cu")
		(net "M_C_CPU1_SA_DQS_DP<1>")
	)
	(gr_poly
		(pts
			(xy 87.911178 -231.322626) (xy 87.911178 -231.278176) (xy 87.711026 -231.278176) (xy 87.711026 -231.322626)
			(xy 87.811102 -231.422702)
		)
		(stroke
			(width 0)
			(type solid)
		)
		(fill yes)
		(layer "In2.Cu")
		(net "M_C_CPU1_SA_DQ<11>")
	)
	(gr_poly
		(pts
			(xy 87.911178 -230.10622) (xy 87.811102 -230.006144) (xy 87.711026 -230.10622) (xy 87.711026 -230.15067)
			(xy 87.911178 -230.15067)
		)
		(stroke
			(width 0)
			(type solid)
		)
		(fill yes)
		(layer "In2.Cu")
		(net "M_C_CPU1_SA_DQ<8>")
	)
	(gr_poly
		(pts
			(xy 87.911178 -229.702614) (xy 87.911178 -229.658164) (xy 87.711026 -229.658164) (xy 87.711026 -229.702614)
			(xy 87.811102 -229.80269)
		)
		(stroke
			(width 0)
			(type solid)
		)
		(fill yes)
		(layer "In2.Cu")
		(net "M_C_CPU1_SA_DQ<7>")
	)
	(gr_poly
		(pts
			(xy 87.911178 -228.486462) (xy 87.811102 -228.386386) (xy 87.711026 -228.486462) (xy 87.711026 -228.530912)
			(xy 87.911178 -228.530912)
		)
		(stroke
			(width 0)
			(type solid)
		)
		(fill yes)
		(layer "In2.Cu")
		(net "M_C_CPU1_SA_DQ<4>")
	)
	(gr_poly
		(pts
			(xy 87.911178 -228.082856) (xy 87.911178 -228.035104) (xy 87.711026 -228.035104) (xy 87.711026 -228.082856)
			(xy 87.811102 -228.182678)
		)
		(stroke
			(width 0)
			(type solid)
		)
		(fill yes)
		(layer "In2.Cu")
		(net "M_C_CPU1_SA_DQS_DP<5>")
	)
	(gr_poly
		(pts
			(xy 87.911178 -226.866196) (xy 87.811102 -226.766374) (xy 87.711026 -226.866196) (xy 87.711026 -226.913948)
			(xy 87.911178 -226.913948)
		)
		(stroke
			(width 0)
			(type solid)
		)
		(fill yes)
		(layer "In2.Cu")
		(net "M_C_CPU1_SA_DQS_DP<0>")
	)
	(gr_poly
		(pts
			(xy 87.911178 -226.46259) (xy 87.911178 -226.41814) (xy 87.711026 -226.41814) (xy 87.711026 -226.46259)
			(xy 87.811102 -226.562666)
		)
		(stroke
			(width 0)
			(type solid)
		)
		(fill yes)
		(layer "In2.Cu")
		(net "M_C_CPU1_SA_DQ<3>")
	)
	(gr_poly
		(pts
			(xy 87.911178 -225.246438) (xy 87.811102 -225.146362) (xy 87.711026 -225.246438) (xy 87.711026 -225.290888)
			(xy 87.911178 -225.290888)
		)
		(stroke
			(width 0)
			(type solid)
		)
		(fill yes)
		(layer "In2.Cu")
		(net "M_C_CPU1_SA_DQ<0>")
	)
	(gr_poly
		(pts
			(xy 88.203786 -291.298122) (xy 88.10371 -291.198046) (xy 88.003634 -291.298122) (xy 88.003634 -291.34562)
			(xy 88.203786 -291.34562)
		)
		(stroke
			(width 0)
			(type solid)
		)
		(fill yes)
		(layer "In2.Cu")
		(net "M_C_CPU1_SB_DQS_DN<8>")
	)
	(gr_poly
		(pts
			(xy 88.204802 -266.991846) (xy 88.104726 -266.89177) (xy 88.004904 -266.991846) (xy 88.004904 -267.036296)
			(xy 88.204802 -267.036296)
		)
		(stroke
			(width 0)
			(type solid)
		)
		(fill yes)
		(layer "In2.Cu")
		(net "M_C_CPU1_SA_RSP<0>")
	)
	(gr_poly
		(pts
			(xy 88.211152 -292.918134) (xy 88.111076 -292.818058) (xy 88.011 -292.918134) (xy 88.011 -292.962584)
			(xy 88.211152 -292.962584)
		)
		(stroke
			(width 0)
			(type solid)
		)
		(fill yes)
		(layer "In2.Cu")
		(net "M_C_CPU1_SB_DQ<29>")
	)
	(gr_poly
		(pts
			(xy 88.211152 -292.514274) (xy 88.211152 -292.469824) (xy 88.011 -292.469824) (xy 88.011 -292.514274)
			(xy 88.111076 -292.61435)
		)
		(stroke
			(width 0)
			(type solid)
		)
		(fill yes)
		(layer "In2.Cu")
		(net "M_C_CPU1_SB_DQ<30>")
	)
	(gr_poly
		(pts
			(xy 88.211152 -290.894516) (xy 88.211152 -290.846764) (xy 88.011 -290.846764) (xy 88.011 -290.894516)
			(xy 88.111076 -290.994338)
		)
		(stroke
			(width 0)
			(type solid)
		)
		(fill yes)
		(layer "In2.Cu")
		(net "M_C_CPU1_SB_DQS_DN<3>")
	)
	(gr_poly
		(pts
			(xy 88.211152 -289.67811) (xy 88.111076 -289.578034) (xy 88.011 -289.67811) (xy 88.011 -289.72256)
			(xy 88.211152 -289.72256)
		)
		(stroke
			(width 0)
			(type solid)
		)
		(fill yes)
		(layer "In2.Cu")
		(net "M_C_CPU1_SB_DQ<25>")
	)
	(gr_poly
		(pts
			(xy 88.211152 -289.27425) (xy 88.211152 -289.2298) (xy 88.011 -289.2298) (xy 88.011 -289.27425) (xy 88.111076 -289.374326)
		)
		(stroke
			(width 0)
			(type solid)
		)
		(fill yes)
		(layer "In2.Cu")
		(net "M_C_CPU1_SB_DQ<26>")
	)
	(gr_poly
		(pts
			(xy 88.211152 -288.058098) (xy 88.111076 -287.958022) (xy 88.011 -288.058098) (xy 88.011 -288.102548)
			(xy 88.211152 -288.102548)
		)
		(stroke
			(width 0)
			(type solid)
		)
		(fill yes)
		(layer "In2.Cu")
		(net "M_C_CPU1_SB_DQ<21>")
	)
	(gr_poly
		(pts
			(xy 88.211152 -287.654492) (xy 88.211152 -287.610042) (xy 88.011 -287.610042) (xy 88.011 -287.654492)
			(xy 88.111076 -287.754568)
		)
		(stroke
			(width 0)
			(type solid)
		)
		(fill yes)
		(layer "In2.Cu")
		(net "M_C_CPU1_SB_DQ<22>")
	)
	(gr_poly
		(pts
			(xy 88.211152 -286.438086) (xy 88.111076 -286.33801) (xy 88.011 -286.438086) (xy 88.011 -286.485838)
			(xy 88.211152 -286.485838)
		)
		(stroke
			(width 0)
			(type solid)
		)
		(fill yes)
		(layer "In2.Cu")
		(net "M_C_CPU1_SB_DQS_DN<7>")
	)
	(gr_poly
		(pts
			(xy 88.211152 -286.034734) (xy 88.211152 -285.986982) (xy 88.011 -285.986982) (xy 88.011 -286.034734)
			(xy 88.111076 -286.134556)
		)
		(stroke
			(width 0)
			(type solid)
		)
		(fill yes)
		(layer "In2.Cu")
		(net "M_C_CPU1_SB_DQS_DN<2>")
	)
	(gr_poly
		(pts
			(xy 88.211152 -284.818328) (xy 88.111076 -284.718252) (xy 88.011 -284.818328) (xy 88.011 -284.862778)
			(xy 88.211152 -284.862778)
		)
		(stroke
			(width 0)
			(type solid)
		)
		(fill yes)
		(layer "In2.Cu")
		(net "M_C_CPU1_SB_DQ<17>")
	)
	(gr_poly
		(pts
			(xy 88.211152 -284.414468) (xy 88.211152 -284.370018) (xy 88.011 -284.370018) (xy 88.011 -284.414468)
			(xy 88.111076 -284.514544)
		)
		(stroke
			(width 0)
			(type solid)
		)
		(fill yes)
		(layer "In2.Cu")
		(net "M_C_CPU1_SB_DQ<18>")
	)
	(gr_poly
		(pts
			(xy 88.211152 -283.198316) (xy 88.111076 -283.09824) (xy 88.011 -283.198316) (xy 88.011 -283.242766)
			(xy 88.211152 -283.242766)
		)
		(stroke
			(width 0)
			(type solid)
		)
		(fill yes)
		(layer "In2.Cu")
		(net "M_C_CPU1_SB_DQ<13>")
	)
	(gr_poly
		(pts
			(xy 88.211152 -282.794456) (xy 88.211152 -282.750006) (xy 88.011 -282.750006) (xy 88.011 -282.794456)
			(xy 88.111076 -282.894532)
		)
		(stroke
			(width 0)
			(type solid)
		)
		(fill yes)
		(layer "In2.Cu")
		(net "M_C_CPU1_SB_DQ<14>")
	)
	(gr_poly
		(pts
			(xy 88.211152 -281.57805) (xy 88.111076 -281.478228) (xy 88.011 -281.57805) (xy 88.011 -281.625802)
			(xy 88.211152 -281.625802)
		)
		(stroke
			(width 0)
			(type solid)
		)
		(fill yes)
		(layer "In2.Cu")
		(net "M_C_CPU1_SB_DQS_DN<6>")
	)
	(gr_poly
		(pts
			(xy 88.211152 -281.174698) (xy 88.211152 -281.126946) (xy 88.011 -281.126946) (xy 88.011 -281.174698)
			(xy 88.111076 -281.27452)
		)
		(stroke
			(width 0)
			(type solid)
		)
		(fill yes)
		(layer "In2.Cu")
		(net "M_C_CPU1_SB_DQS_DN<1>")
	)
	(gr_poly
		(pts
			(xy 88.211152 -279.958292) (xy 88.111076 -279.858216) (xy 88.011 -279.958292) (xy 88.011 -280.002742)
			(xy 88.211152 -280.002742)
		)
		(stroke
			(width 0)
			(type solid)
		)
		(fill yes)
		(layer "In2.Cu")
		(net "M_C_CPU1_SB_DQ<9>")
	)
	(gr_poly
		(pts
			(xy 88.211152 -279.554432) (xy 88.211152 -279.509982) (xy 88.011 -279.509982) (xy 88.011 -279.554432)
			(xy 88.111076 -279.654508)
		)
		(stroke
			(width 0)
			(type solid)
		)
		(fill yes)
		(layer "In2.Cu")
		(net "M_C_CPU1_SB_DQ<10>")
	)
	(gr_poly
		(pts
			(xy 88.211152 -278.33828) (xy 88.111076 -278.238204) (xy 88.011 -278.33828) (xy 88.011 -278.38273)
			(xy 88.211152 -278.38273)
		)
		(stroke
			(width 0)
			(type solid)
		)
		(fill yes)
		(layer "In2.Cu")
		(net "M_C_CPU1_SB_DQ<5>")
	)
	(gr_poly
		(pts
			(xy 88.211152 -277.93442) (xy 88.211152 -277.88997) (xy 88.011 -277.88997) (xy 88.011 -277.93442)
			(xy 88.111076 -278.034496)
		)
		(stroke
			(width 0)
			(type solid)
		)
		(fill yes)
		(layer "In2.Cu")
		(net "M_C_CPU1_SB_DQ<6>")
	)
	(gr_poly
		(pts
			(xy 88.211152 -276.718014) (xy 88.111076 -276.618192) (xy 88.011 -276.718014) (xy 88.011 -276.765766)
			(xy 88.211152 -276.765766)
		)
		(stroke
			(width 0)
			(type solid)
		)
		(fill yes)
		(layer "In2.Cu")
		(net "M_C_CPU1_SB_DQS_DN<5>")
	)
	(gr_poly
		(pts
			(xy 88.211152 -276.314662) (xy 88.211152 -276.26691) (xy 88.011 -276.26691) (xy 88.011 -276.314662)
			(xy 88.111076 -276.414484)
		)
		(stroke
			(width 0)
			(type solid)
		)
		(fill yes)
		(layer "In2.Cu")
		(net "M_C_CPU1_SB_DQS_DN<0>")
	)
	(gr_poly
		(pts
			(xy 88.211152 -275.098256) (xy 88.111076 -274.99818) (xy 88.011 -275.098256) (xy 88.011 -275.142706)
			(xy 88.211152 -275.142706)
		)
		(stroke
			(width 0)
			(type solid)
		)
		(fill yes)
		(layer "In2.Cu")
		(net "M_C_CPU1_SB_DQ<1>")
	)
	(gr_poly
		(pts
			(xy 88.211152 -274.694396) (xy 88.211152 -274.649946) (xy 88.011 -274.649946) (xy 88.011 -274.694396)
			(xy 88.111076 -274.794472)
		)
		(stroke
			(width 0)
			(type solid)
		)
		(fill yes)
		(layer "In2.Cu")
		(net "M_C_CPU1_SB_DQ<2>")
	)
	(gr_poly
		(pts
			(xy 88.211152 -273.478244) (xy 88.111076 -273.378168) (xy 88.011 -273.478244) (xy 88.011 -273.522694)
			(xy 88.211152 -273.522694)
		)
		(stroke
			(width 0)
			(type solid)
		)
		(fill yes)
		(layer "In2.Cu")
		(net "M_C_CPU1_SB_CB<1>")
	)
	(gr_poly
		(pts
			(xy 88.211152 -273.074384) (xy 88.211152 -273.029934) (xy 88.011 -273.029934) (xy 88.011 -273.074384)
			(xy 88.111076 -273.17446)
		)
		(stroke
			(width 0)
			(type solid)
		)
		(fill yes)
		(layer "In2.Cu")
		(net "M_C_CPU1_SB_CB<2>")
	)
	(gr_poly
		(pts
			(xy 88.211152 -271.857978) (xy 88.111076 -271.758156) (xy 88.011 -271.857978) (xy 88.011 -271.90573)
			(xy 88.211152 -271.90573)
		)
		(stroke
			(width 0)
			(type solid)
		)
		(fill yes)
		(layer "In2.Cu")
		(net "M_C_CPU1_SB_DQS_DN<4>")
	)
	(gr_poly
		(pts
			(xy 88.211152 -271.454626) (xy 88.211152 -271.406874) (xy 88.011 -271.406874) (xy 88.011 -271.454626)
			(xy 88.111076 -271.554448)
		)
		(stroke
			(width 0)
			(type solid)
		)
		(fill yes)
		(layer "In2.Cu")
		(net "M_C_CPU1_SB_DQS_DN<9>")
	)
	(gr_poly
		(pts
			(xy 88.211152 -270.23822) (xy 88.111076 -270.138144) (xy 88.011 -270.23822) (xy 88.011 -270.28267)
			(xy 88.211152 -270.28267)
		)
		(stroke
			(width 0)
			(type solid)
		)
		(fill yes)
		(layer "In2.Cu")
		(net "M_C_CPU1_SB_CB<5>")
	)
	(gr_poly
		(pts
			(xy 88.211152 -269.83436) (xy 88.211152 -269.78991) (xy 88.011 -269.78991) (xy 88.011 -269.83436)
			(xy 88.111076 -269.934436)
		)
		(stroke
			(width 0)
			(type solid)
		)
		(fill yes)
		(layer "In2.Cu")
		(net "M_C_CPU1_SB_CB<6>")
	)
	(gr_poly
		(pts
			(xy 88.211152 -266.594336) (xy 88.211152 -266.549886) (xy 88.011 -266.549886) (xy 88.011 -266.594336)
			(xy 88.111076 -266.694412)
		)
		(stroke
			(width 0)
			(type solid)
		)
		(fill yes)
		(layer "In2.Cu")
		(net "M_C_CPU1_SB_CS_N<1>")
	)
	(gr_poly
		(pts
			(xy 88.211152 -264.974324) (xy 88.211152 -264.929874) (xy 88.011 -264.929874) (xy 88.011 -264.974324)
			(xy 88.111076 -265.0744)
		)
		(stroke
			(width 0)
			(type solid)
		)
		(fill yes)
		(layer "In2.Cu")
		(net "M_C_CPU1_SB_PAR")
	)
	(gr_poly
		(pts
			(xy 88.211152 -263.758172) (xy 88.111076 -263.658096) (xy 88.011 -263.758172) (xy 88.011 -263.802622)
			(xy 88.211152 -263.802622)
		)
		(stroke
			(width 0)
			(type solid)
		)
		(fill yes)
		(layer "In2.Cu")
		(net "M_C_CPU1_SB_CA<4>")
	)
	(gr_poly
		(pts
			(xy 88.211152 -263.354312) (xy 88.211152 -263.309862) (xy 88.011 -263.309862) (xy 88.011 -263.354312)
			(xy 88.111076 -263.454388)
		)
		(stroke
			(width 0)
			(type solid)
		)
		(fill yes)
		(layer "In2.Cu")
		(net "M_C_CPU1_SB_CA<3>")
	)
	(gr_poly
		(pts
			(xy 88.211152 -262.13816) (xy 88.111076 -262.038084) (xy 88.011 -262.13816) (xy 88.011 -262.18261)
			(xy 88.211152 -262.18261)
		)
		(stroke
			(width 0)
			(type solid)
		)
		(fill yes)
		(layer "In2.Cu")
		(net "M_C_CPU1_SB_CA<0>")
	)
	(gr_poly
		(pts
			(xy 88.380824 -246.712486) (xy 88.380824 -246.664988) (xy 88.180926 -246.664988) (xy 88.180926 -246.712486)
			(xy 88.280748 -246.812562)
		)
		(stroke
			(width 0)
			(type solid)
		)
		(fill yes)
		(layer "In2.Cu")
		(net "M_C_CPU1_SA_DQS_DN<4>")
	)
	(gr_poly
		(pts
			(xy 88.381078 -256.432812) (xy 88.381078 -256.38506) (xy 88.180926 -256.38506) (xy 88.180926 -256.432812)
			(xy 88.281002 -256.532634)
		)
		(stroke
			(width 0)
			(type solid)
		)
		(fill yes)
		(layer "In2.Cu")
		(net "M_C_CPU1_CLK_DN<0>")
	)
	(gr_poly
		(pts
			(xy 88.381078 -255.216406) (xy 88.281002 -255.11633) (xy 88.180926 -255.216406) (xy 88.180926 -255.260856)
			(xy 88.381078 -255.260856)
		)
		(stroke
			(width 0)
			(type solid)
		)
		(fill yes)
		(layer "In2.Cu")
		(net "M_C_CPU1_SA_CA<6>")
	)
	(gr_poly
		(pts
			(xy 88.381078 -254.812546) (xy 88.381078 -254.768096) (xy 88.180926 -254.768096) (xy 88.180926 -254.812546)
			(xy 88.281002 -254.912622)
		)
		(stroke
			(width 0)
			(type solid)
		)
		(fill yes)
		(layer "In2.Cu")
		(net "M_C_CPU1_SA_CA<5>")
	)
	(gr_poly
		(pts
			(xy 88.381078 -253.596394) (xy 88.281002 -253.496318) (xy 88.180926 -253.596394) (xy 88.180926 -253.640844)
			(xy 88.381078 -253.640844)
		)
		(stroke
			(width 0)
			(type solid)
		)
		(fill yes)
		(layer "In2.Cu")
		(net "M_C_CPU1_SA_CA<2>")
	)
	(gr_poly
		(pts
			(xy 88.381078 -253.192534) (xy 88.381078 -253.148084) (xy 88.180926 -253.148084) (xy 88.180926 -253.192534)
			(xy 88.281002 -253.29261)
		)
		(stroke
			(width 0)
			(type solid)
		)
		(fill yes)
		(layer "In2.Cu")
		(net "M_C_CPU1_SA_CA<1>")
	)
	(gr_poly
		(pts
			(xy 88.381078 -251.572522) (xy 88.381078 -251.528072) (xy 88.180926 -251.528072) (xy 88.180926 -251.572522)
			(xy 88.281002 -251.672598)
		)
		(stroke
			(width 0)
			(type solid)
		)
		(fill yes)
		(layer "In2.Cu")
		(net "M_C_CPU1_SA_CS_N<0>")
	)
	(gr_poly
		(pts
			(xy 88.381078 -250.35637) (xy 88.281002 -250.256294) (xy 88.180926 -250.35637) (xy 88.180926 -250.40082)
			(xy 88.381078 -250.40082)
		)
		(stroke
			(width 0)
			(type solid)
		)
		(fill yes)
		(layer "In2.Cu")
		(net "M_C_CPU1_ALERT_R_N")
	)
	(gr_poly
		(pts
			(xy 88.381078 -248.736358) (xy 88.281002 -248.636282) (xy 88.180926 -248.736358) (xy 88.180926 -248.780808)
			(xy 88.381078 -248.780808)
		)
		(stroke
			(width 0)
			(type solid)
		)
		(fill yes)
		(layer "In2.Cu")
		(net "M_C_CPU1_SA_CB<5>")
	)
	(gr_poly
		(pts
			(xy 88.381078 -248.332498) (xy 88.381078 -248.288048) (xy 88.180926 -248.288048) (xy 88.180926 -248.332498)
			(xy 88.281002 -248.432574)
		)
		(stroke
			(width 0)
			(type solid)
		)
		(fill yes)
		(layer "In2.Cu")
		(net "M_C_CPU1_SA_CB<6>")
	)
	(gr_poly
		(pts
			(xy 88.381078 -247.116092) (xy 88.281002 -247.01627) (xy 88.180926 -247.116092) (xy 88.180926 -247.163844)
			(xy 88.381078 -247.163844)
		)
		(stroke
			(width 0)
			(type solid)
		)
		(fill yes)
		(layer "In2.Cu")
		(net "M_C_CPU1_SA_DQS_DN<9>")
	)
	(gr_poly
		(pts
			(xy 88.381078 -245.496334) (xy 88.281002 -245.396258) (xy 88.180926 -245.496334) (xy 88.180926 -245.540784)
			(xy 88.381078 -245.540784)
		)
		(stroke
			(width 0)
			(type solid)
		)
		(fill yes)
		(layer "In2.Cu")
		(net "M_C_CPU1_SA_CB<1>")
	)
	(gr_poly
		(pts
			(xy 88.381078 -245.092474) (xy 88.381078 -245.048024) (xy 88.180926 -245.048024) (xy 88.180926 -245.092474)
			(xy 88.281002 -245.19255)
		)
		(stroke
			(width 0)
			(type solid)
		)
		(fill yes)
		(layer "In2.Cu")
		(net "M_C_CPU1_SA_CB<2>")
	)
	(gr_poly
		(pts
			(xy 88.381078 -243.876322) (xy 88.281002 -243.776246) (xy 88.180926 -243.876322) (xy 88.180926 -243.920772)
			(xy 88.381078 -243.920772)
		)
		(stroke
			(width 0)
			(type solid)
		)
		(fill yes)
		(layer "In2.Cu")
		(net "M_C_CPU1_SA_DQ<29>")
	)
	(gr_poly
		(pts
			(xy 88.381078 -243.472462) (xy 88.381078 -243.428012) (xy 88.180926 -243.428012) (xy 88.180926 -243.472462)
			(xy 88.281002 -243.572538)
		)
		(stroke
			(width 0)
			(type solid)
		)
		(fill yes)
		(layer "In2.Cu")
		(net "M_C_CPU1_SA_DQ<30>")
	)
	(gr_poly
		(pts
			(xy 88.381078 -242.256056) (xy 88.281002 -242.156234) (xy 88.180926 -242.256056) (xy 88.180926 -242.303808)
			(xy 88.381078 -242.303808)
		)
		(stroke
			(width 0)
			(type solid)
		)
		(fill yes)
		(layer "In2.Cu")
		(net "M_C_CPU1_SA_DQS_DN<8>")
	)
	(gr_poly
		(pts
			(xy 88.381078 -241.852704) (xy 88.381078 -241.804952) (xy 88.180926 -241.804952) (xy 88.180926 -241.852704)
			(xy 88.281002 -241.952526)
		)
		(stroke
			(width 0)
			(type solid)
		)
		(fill yes)
		(layer "In2.Cu")
		(net "M_C_CPU1_SA_DQS_DN<3>")
	)
	(gr_poly
		(pts
			(xy 88.381078 -240.636298) (xy 88.281002 -240.536222) (xy 88.180926 -240.636298) (xy 88.180926 -240.680748)
			(xy 88.381078 -240.680748)
		)
		(stroke
			(width 0)
			(type solid)
		)
		(fill yes)
		(layer "In2.Cu")
		(net "M_C_CPU1_SA_DQ<25>")
	)
	(gr_poly
		(pts
			(xy 88.381078 -240.232438) (xy 88.381078 -240.187988) (xy 88.180926 -240.187988) (xy 88.180926 -240.232438)
			(xy 88.281002 -240.332514)
		)
		(stroke
			(width 0)
			(type solid)
		)
		(fill yes)
		(layer "In2.Cu")
		(net "M_C_CPU1_SA_DQ<26>")
	)
	(gr_poly
		(pts
			(xy 88.381078 -239.016286) (xy 88.281002 -238.91621) (xy 88.180926 -239.016286) (xy 88.180926 -239.060736)
			(xy 88.381078 -239.060736)
		)
		(stroke
			(width 0)
			(type solid)
		)
		(fill yes)
		(layer "In2.Cu")
		(net "M_C_CPU1_SA_DQ<21>")
	)
	(gr_poly
		(pts
			(xy 88.381078 -238.612426) (xy 88.381078 -238.567976) (xy 88.180926 -238.567976) (xy 88.180926 -238.612426)
			(xy 88.281002 -238.712502)
		)
		(stroke
			(width 0)
			(type solid)
		)
		(fill yes)
		(layer "In2.Cu")
		(net "M_C_CPU1_SA_DQ<22>")
	)
	(gr_poly
		(pts
			(xy 88.381078 -237.39602) (xy 88.281002 -237.296198) (xy 88.180926 -237.39602) (xy 88.180926 -237.443772)
			(xy 88.381078 -237.443772)
		)
		(stroke
			(width 0)
			(type solid)
		)
		(fill yes)
		(layer "In2.Cu")
		(net "M_C_CPU1_SA_DQS_DN<7>")
	)
	(gr_poly
		(pts
			(xy 88.381078 -236.992668) (xy 88.381078 -236.944916) (xy 88.180926 -236.944916) (xy 88.180926 -236.992668)
			(xy 88.281002 -237.09249)
		)
		(stroke
			(width 0)
			(type solid)
		)
		(fill yes)
		(layer "In2.Cu")
		(net "M_C_CPU1_SA_DQS_DN<2>")
	)
	(gr_poly
		(pts
			(xy 88.381078 -235.776262) (xy 88.281002 -235.676186) (xy 88.180926 -235.776262) (xy 88.180926 -235.820712)
			(xy 88.381078 -235.820712)
		)
		(stroke
			(width 0)
			(type solid)
		)
		(fill yes)
		(layer "In2.Cu")
		(net "M_C_CPU1_SA_DQ<17>")
	)
	(gr_poly
		(pts
			(xy 88.381078 -235.372402) (xy 88.381078 -235.327952) (xy 88.180926 -235.327952) (xy 88.180926 -235.372402)
			(xy 88.281002 -235.472478)
		)
		(stroke
			(width 0)
			(type solid)
		)
		(fill yes)
		(layer "In2.Cu")
		(net "M_C_CPU1_SA_DQ<18>")
	)
	(gr_poly
		(pts
			(xy 88.381078 -234.15625) (xy 88.281002 -234.056174) (xy 88.180926 -234.15625) (xy 88.180926 -234.2007)
			(xy 88.381078 -234.2007)
		)
		(stroke
			(width 0)
			(type solid)
		)
		(fill yes)
		(layer "In2.Cu")
		(net "M_C_CPU1_SA_DQ<13>")
	)
	(gr_poly
		(pts
			(xy 88.381078 -233.75239) (xy 88.381078 -233.70794) (xy 88.180926 -233.70794) (xy 88.180926 -233.75239)
			(xy 88.281002 -233.852466)
		)
		(stroke
			(width 0)
			(type solid)
		)
		(fill yes)
		(layer "In2.Cu")
		(net "M_C_CPU1_SA_DQ<14>")
	)
	(gr_poly
		(pts
			(xy 88.381078 -232.535984) (xy 88.281002 -232.436162) (xy 88.180926 -232.535984) (xy 88.180926 -232.583736)
			(xy 88.381078 -232.583736)
		)
		(stroke
			(width 0)
			(type solid)
		)
		(fill yes)
		(layer "In2.Cu")
		(net "M_C_CPU1_SA_DQS_DN<6>")
	)
	(gr_poly
		(pts
			(xy 88.381078 -232.132632) (xy 88.381078 -232.08488) (xy 88.180926 -232.08488) (xy 88.180926 -232.132632)
			(xy 88.281002 -232.232454)
		)
		(stroke
			(width 0)
			(type solid)
		)
		(fill yes)
		(layer "In2.Cu")
		(net "M_C_CPU1_SA_DQS_DN<1>")
	)
	(gr_poly
		(pts
			(xy 88.381078 -230.916226) (xy 88.281002 -230.81615) (xy 88.180926 -230.916226) (xy 88.180926 -230.960676)
			(xy 88.381078 -230.960676)
		)
		(stroke
			(width 0)
			(type solid)
		)
		(fill yes)
		(layer "In2.Cu")
		(net "M_C_CPU1_SA_DQ<9>")
	)
	(gr_poly
		(pts
			(xy 88.381078 -230.51262) (xy 88.381078 -230.46817) (xy 88.180926 -230.46817) (xy 88.180926 -230.51262)
			(xy 88.281002 -230.612696)
		)
		(stroke
			(width 0)
			(type solid)
		)
		(fill yes)
		(layer "In2.Cu")
		(net "M_C_CPU1_SA_DQ<10>")
	)
	(gr_poly
		(pts
			(xy 88.381078 -229.296214) (xy 88.281002 -229.196138) (xy 88.180926 -229.296214) (xy 88.180926 -229.340664)
			(xy 88.381078 -229.340664)
		)
		(stroke
			(width 0)
			(type solid)
		)
		(fill yes)
		(layer "In2.Cu")
		(net "M_C_CPU1_SA_DQ<5>")
	)
	(gr_poly
		(pts
			(xy 88.381078 -228.892608) (xy 88.381078 -228.848158) (xy 88.180926 -228.848158) (xy 88.180926 -228.892608)
			(xy 88.281002 -228.992684)
		)
		(stroke
			(width 0)
			(type solid)
		)
		(fill yes)
		(layer "In2.Cu")
		(net "M_C_CPU1_SA_DQ<6>")
	)
	(gr_poly
		(pts
			(xy 88.381078 -227.676202) (xy 88.281002 -227.57638) (xy 88.180926 -227.676202) (xy 88.180926 -227.723954)
			(xy 88.381078 -227.723954)
		)
		(stroke
			(width 0)
			(type solid)
		)
		(fill yes)
		(layer "In2.Cu")
		(net "M_C_CPU1_SA_DQS_DN<5>")
	)
	(gr_poly
		(pts
			(xy 88.381078 -227.27285) (xy 88.381078 -227.225098) (xy 88.180926 -227.225098) (xy 88.180926 -227.27285)
			(xy 88.281002 -227.372672)
		)
		(stroke
			(width 0)
			(type solid)
		)
		(fill yes)
		(layer "In2.Cu")
		(net "M_C_CPU1_SA_DQS_DN<0>")
	)
	(gr_poly
		(pts
			(xy 88.381078 -226.056444) (xy 88.281002 -225.956368) (xy 88.180926 -226.056444) (xy 88.180926 -226.100894)
			(xy 88.381078 -226.100894)
		)
		(stroke
			(width 0)
			(type solid)
		)
		(fill yes)
		(layer "In2.Cu")
		(net "M_C_CPU1_SA_DQ<1>")
	)
	(gr_poly
		(pts
			(xy 88.381078 -225.652584) (xy 88.381078 -225.608134) (xy 88.180926 -225.608134) (xy 88.180926 -225.652584)
			(xy 88.281002 -225.75266)
		)
		(stroke
			(width 0)
			(type solid)
		)
		(fill yes)
		(layer "In2.Cu")
		(net "M_C_CPU1_SA_DQ<2>")
	)
	(gr_poly
		(pts
			(xy 88.681052 -293.32428) (xy 88.681052 -293.27983) (xy 88.4809 -293.27983) (xy 88.4809 -293.32428)
			(xy 88.580976 -293.424356)
		)
		(stroke
			(width 0)
			(type solid)
		)
		(fill yes)
		(layer "In2.Cu")
		(net "M_C_CPU1_SB_DQ<31>")
	)
	(gr_poly
		(pts
			(xy 88.681052 -292.108128) (xy 88.580976 -292.008052) (xy 88.4809 -292.108128) (xy 88.4809 -292.152578)
			(xy 88.681052 -292.152578)
		)
		(stroke
			(width 0)
			(type solid)
		)
		(fill yes)
		(layer "In2.Cu")
		(net "M_C_CPU1_SB_DQ<28>")
	)
	(gr_poly
		(pts
			(xy 88.681052 -291.704522) (xy 88.681052 -291.65677) (xy 88.4809 -291.65677) (xy 88.4809 -291.704522)
			(xy 88.580976 -291.804344)
		)
		(stroke
			(width 0)
			(type solid)
		)
		(fill yes)
		(layer "In2.Cu")
		(net "M_C_CPU1_SB_DQS_DP<8>")
	)
	(gr_poly
		(pts
			(xy 88.681052 -290.487862) (xy 88.580976 -290.38804) (xy 88.4809 -290.487862) (xy 88.4809 -290.535614)
			(xy 88.681052 -290.535614)
		)
		(stroke
			(width 0)
			(type solid)
		)
		(fill yes)
		(layer "In2.Cu")
		(net "M_C_CPU1_SB_DQS_DP<3>")
	)
	(gr_poly
		(pts
			(xy 88.681052 -290.084256) (xy 88.681052 -290.039806) (xy 88.4809 -290.039806) (xy 88.4809 -290.084256)
			(xy 88.580976 -290.184332)
		)
		(stroke
			(width 0)
			(type solid)
		)
		(fill yes)
		(layer "In2.Cu")
		(net "M_C_CPU1_SB_DQ<27>")
	)
	(gr_poly
		(pts
			(xy 88.681052 -288.868104) (xy 88.580976 -288.768028) (xy 88.4809 -288.868104) (xy 88.4809 -288.912554)
			(xy 88.681052 -288.912554)
		)
		(stroke
			(width 0)
			(type solid)
		)
		(fill yes)
		(layer "In2.Cu")
		(net "M_C_CPU1_SB_DQ<24>")
	)
	(gr_poly
		(pts
			(xy 88.681052 -288.464498) (xy 88.681052 -288.420048) (xy 88.4809 -288.420048) (xy 88.4809 -288.464498)
			(xy 88.580976 -288.564574)
		)
		(stroke
			(width 0)
			(type solid)
		)
		(fill yes)
		(layer "In2.Cu")
		(net "M_C_CPU1_SB_DQ<23>")
	)
	(gr_poly
		(pts
			(xy 88.681052 -287.248092) (xy 88.580976 -287.148016) (xy 88.4809 -287.248092) (xy 88.4809 -287.292542)
			(xy 88.681052 -287.292542)
		)
		(stroke
			(width 0)
			(type solid)
		)
		(fill yes)
		(layer "In2.Cu")
		(net "M_C_CPU1_SB_DQ<20>")
	)
	(gr_poly
		(pts
			(xy 88.681052 -286.844486) (xy 88.681052 -286.796734) (xy 88.4809 -286.796734) (xy 88.4809 -286.844486)
			(xy 88.580976 -286.944562)
		)
		(stroke
			(width 0)
			(type solid)
		)
		(fill yes)
		(layer "In2.Cu")
		(net "M_C_CPU1_SB_DQS_DP<7>")
	)
	(gr_poly
		(pts
			(xy 88.681052 -285.62808) (xy 88.580976 -285.528258) (xy 88.4809 -285.62808) (xy 88.4809 -285.675832)
			(xy 88.681052 -285.675832)
		)
		(stroke
			(width 0)
			(type solid)
		)
		(fill yes)
		(layer "In2.Cu")
		(net "M_C_CPU1_SB_DQS_DP<2>")
	)
	(gr_poly
		(pts
			(xy 88.681052 -285.224474) (xy 88.681052 -285.180024) (xy 88.4809 -285.180024) (xy 88.4809 -285.224474)
			(xy 88.580976 -285.32455)
		)
		(stroke
			(width 0)
			(type solid)
		)
		(fill yes)
		(layer "In2.Cu")
		(net "M_C_CPU1_SB_DQ<19>")
	)
	(gr_poly
		(pts
			(xy 88.681052 -284.008322) (xy 88.580976 -283.908246) (xy 88.4809 -284.008322) (xy 88.4809 -284.052772)
			(xy 88.681052 -284.052772)
		)
		(stroke
			(width 0)
			(type solid)
		)
		(fill yes)
		(layer "In2.Cu")
		(net "M_C_CPU1_SB_DQ<16>")
	)
	(gr_poly
		(pts
			(xy 88.681052 -283.604462) (xy 88.681052 -283.560012) (xy 88.4809 -283.560012) (xy 88.4809 -283.604462)
			(xy 88.580976 -283.704538)
		)
		(stroke
			(width 0)
			(type solid)
		)
		(fill yes)
		(layer "In2.Cu")
		(net "M_C_CPU1_SB_DQ<15>")
	)
	(gr_poly
		(pts
			(xy 88.681052 -282.38831) (xy 88.580976 -282.288234) (xy 88.4809 -282.38831) (xy 88.4809 -282.43276)
			(xy 88.681052 -282.43276)
		)
		(stroke
			(width 0)
			(type solid)
		)
		(fill yes)
		(layer "In2.Cu")
		(net "M_C_CPU1_SB_DQ<12>")
	)
	(gr_poly
		(pts
			(xy 88.681052 -281.984704) (xy 88.681052 -281.936952) (xy 88.4809 -281.936952) (xy 88.4809 -281.984704)
			(xy 88.580976 -282.084526)
		)
		(stroke
			(width 0)
			(type solid)
		)
		(fill yes)
		(layer "In2.Cu")
		(net "M_C_CPU1_SB_DQS_DP<6>")
	)
	(gr_poly
		(pts
			(xy 88.681052 -280.768044) (xy 88.580976 -280.668222) (xy 88.4809 -280.768044) (xy 88.4809 -280.815796)
			(xy 88.681052 -280.815796)
		)
		(stroke
			(width 0)
			(type solid)
		)
		(fill yes)
		(layer "In2.Cu")
		(net "M_C_CPU1_SB_DQS_DP<1>")
	)
	(gr_poly
		(pts
			(xy 88.681052 -280.364438) (xy 88.681052 -280.319988) (xy 88.4809 -280.319988) (xy 88.4809 -280.364438)
			(xy 88.580976 -280.464514)
		)
		(stroke
			(width 0)
			(type solid)
		)
		(fill yes)
		(layer "In2.Cu")
		(net "M_C_CPU1_SB_DQ<11>")
	)
	(gr_poly
		(pts
			(xy 88.681052 -279.148286) (xy 88.580976 -279.04821) (xy 88.4809 -279.148286) (xy 88.4809 -279.192736)
			(xy 88.681052 -279.192736)
		)
		(stroke
			(width 0)
			(type solid)
		)
		(fill yes)
		(layer "In2.Cu")
		(net "M_C_CPU1_SB_DQ<8>")
	)
	(gr_poly
		(pts
			(xy 88.681052 -278.744426) (xy 88.681052 -278.699976) (xy 88.4809 -278.699976) (xy 88.4809 -278.744426)
			(xy 88.580976 -278.844502)
		)
		(stroke
			(width 0)
			(type solid)
		)
		(fill yes)
		(layer "In2.Cu")
		(net "M_C_CPU1_SB_DQ<7>")
	)
	(gr_poly
		(pts
			(xy 88.681052 -277.528274) (xy 88.580976 -277.428198) (xy 88.4809 -277.528274) (xy 88.4809 -277.572724)
			(xy 88.681052 -277.572724)
		)
		(stroke
			(width 0)
			(type solid)
		)
		(fill yes)
		(layer "In2.Cu")
		(net "M_C_CPU1_SB_DQ<4>")
	)
	(gr_poly
		(pts
			(xy 88.681052 -277.124668) (xy 88.681052 -277.076916) (xy 88.4809 -277.076916) (xy 88.4809 -277.124668)
			(xy 88.580976 -277.22449)
		)
		(stroke
			(width 0)
			(type solid)
		)
		(fill yes)
		(layer "In2.Cu")
		(net "M_C_CPU1_SB_DQS_DP<5>")
	)
	(gr_poly
		(pts
			(xy 88.681052 -275.908008) (xy 88.580976 -275.808186) (xy 88.4809 -275.908008) (xy 88.4809 -275.95576)
			(xy 88.681052 -275.95576)
		)
		(stroke
			(width 0)
			(type solid)
		)
		(fill yes)
		(layer "In2.Cu")
		(net "M_C_CPU1_SB_DQS_DP<0>")
	)
	(gr_poly
		(pts
			(xy 88.681052 -275.504402) (xy 88.681052 -275.459952) (xy 88.4809 -275.459952) (xy 88.4809 -275.504402)
			(xy 88.580976 -275.604478)
		)
		(stroke
			(width 0)
			(type solid)
		)
		(fill yes)
		(layer "In2.Cu")
		(net "M_C_CPU1_SB_DQ<3>")
	)
	(gr_poly
		(pts
			(xy 88.681052 -274.28825) (xy 88.580976 -274.188174) (xy 88.4809 -274.28825) (xy 88.4809 -274.3327)
			(xy 88.681052 -274.3327)
		)
		(stroke
			(width 0)
			(type solid)
		)
		(fill yes)
		(layer "In2.Cu")
		(net "M_C_CPU1_SB_DQ<0>")
	)
	(gr_poly
		(pts
			(xy 88.681052 -273.88439) (xy 88.681052 -273.83994) (xy 88.4809 -273.83994) (xy 88.4809 -273.88439)
			(xy 88.580976 -273.984466)
		)
		(stroke
			(width 0)
			(type solid)
		)
		(fill yes)
		(layer "In2.Cu")
		(net "M_C_CPU1_SB_CB<3>")
	)
	(gr_poly
		(pts
			(xy 88.681052 -272.668238) (xy 88.580976 -272.568162) (xy 88.4809 -272.668238) (xy 88.4809 -272.712688)
			(xy 88.681052 -272.712688)
		)
		(stroke
			(width 0)
			(type solid)
		)
		(fill yes)
		(layer "In2.Cu")
		(net "M_C_CPU1_SB_CB<0>")
	)
	(gr_poly
		(pts
			(xy 88.681052 -272.264632) (xy 88.681052 -272.21688) (xy 88.4809 -272.21688) (xy 88.4809 -272.264632)
			(xy 88.580976 -272.364454)
		)
		(stroke
			(width 0)
			(type solid)
		)
		(fill yes)
		(layer "In2.Cu")
		(net "M_C_CPU1_SB_DQS_DP<4>")
	)
	(gr_poly
		(pts
			(xy 88.681052 -271.047972) (xy 88.580976 -270.94815) (xy 88.4809 -271.047972) (xy 88.4809 -271.095724)
			(xy 88.681052 -271.095724)
		)
		(stroke
			(width 0)
			(type solid)
		)
		(fill yes)
		(layer "In2.Cu")
		(net "M_C_CPU1_SB_DQS_DP<9>")
	)
	(gr_poly
		(pts
			(xy 88.681052 -270.644366) (xy 88.681052 -270.599916) (xy 88.4809 -270.599916) (xy 88.4809 -270.644366)
			(xy 88.580976 -270.744442)
		)
		(stroke
			(width 0)
			(type solid)
		)
		(fill yes)
		(layer "In2.Cu")
		(net "M_C_CPU1_SB_CB<7>")
	)
	(gr_poly
		(pts
			(xy 88.681052 -269.428214) (xy 88.580976 -269.328138) (xy 88.4809 -269.428214) (xy 88.4809 -269.472664)
			(xy 88.681052 -269.472664)
		)
		(stroke
			(width 0)
			(type solid)
		)
		(fill yes)
		(layer "In2.Cu")
		(net "M_C_CPU1_SB_CB<4>")
	)
	(gr_poly
		(pts
			(xy 88.681052 -265.78433) (xy 88.681052 -265.73988) (xy 88.4809 -265.73988) (xy 88.4809 -265.78433)
			(xy 88.580976 -265.884406)
		)
		(stroke
			(width 0)
			(type solid)
		)
		(fill yes)
		(layer "In2.Cu")
		(net "M_C_CPU1_SB_CS_N<0>")
	)
	(gr_poly
		(pts
			(xy 88.681052 -264.568178) (xy 88.580976 -264.468102) (xy 88.4809 -264.568178) (xy 88.4809 -264.612628)
			(xy 88.681052 -264.612628)
		)
		(stroke
			(width 0)
			(type solid)
		)
		(fill yes)
		(layer "In2.Cu")
		(net "M_C_CPU1_SB_CA<6>")
	)
	(gr_poly
		(pts
			(xy 88.681052 -264.164318) (xy 88.681052 -264.119868) (xy 88.4809 -264.119868) (xy 88.4809 -264.164318)
			(xy 88.580976 -264.264394)
		)
		(stroke
			(width 0)
			(type solid)
		)
		(fill yes)
		(layer "In2.Cu")
		(net "M_C_CPU1_SB_CA<5>")
	)
	(gr_poly
		(pts
			(xy 88.681052 -262.948166) (xy 88.580976 -262.84809) (xy 88.4809 -262.948166) (xy 88.4809 -262.992616)
			(xy 88.681052 -262.992616)
		)
		(stroke
			(width 0)
			(type solid)
		)
		(fill yes)
		(layer "In2.Cu")
		(net "M_C_CPU1_SB_CA<2>")
	)
	(gr_poly
		(pts
			(xy 88.681052 -262.544306) (xy 88.681052 -262.499856) (xy 88.4809 -262.499856) (xy 88.4809 -262.544306)
			(xy 88.580976 -262.644382)
		)
		(stroke
			(width 0)
			(type solid)
		)
		(fill yes)
		(layer "In2.Cu")
		(net "M_C_CPU1_SB_CA<1>")
	)
	(gr_poly
		(pts
			(xy 88.687148 -267.801852) (xy 88.587326 -267.701776) (xy 88.48725 -267.801852) (xy 88.48725 -267.846302)
			(xy 88.687148 -267.846302)
		)
		(stroke
			(width 0)
			(type solid)
		)
		(fill yes)
		(layer "In2.Cu")
		(net "M_C_CPU1_SB_RSP<0>")
	)
	(gr_poly
		(pts
			(xy 88.851232 -256.026158) (xy 88.751156 -255.926336) (xy 88.65108 -256.026158) (xy 88.65108 -256.07391)
			(xy 88.851232 -256.07391)
		)
		(stroke
			(width 0)
			(type solid)
		)
		(fill yes)
		(layer "In2.Cu")
		(net "M_C_CPU1_CLK_DP<0>")
	)
	(gr_poly
		(pts
			(xy 88.851232 -255.622552) (xy 88.851232 -255.578102) (xy 88.65108 -255.578102) (xy 88.65108 -255.622552)
			(xy 88.751156 -255.722628)
		)
		(stroke
			(width 0)
			(type solid)
		)
		(fill yes)
		(layer "In2.Cu")
		(net "M_C_CPU1_SA_PAR")
	)
	(gr_poly
		(pts
			(xy 88.851232 -254.4064) (xy 88.751156 -254.306324) (xy 88.65108 -254.4064) (xy 88.65108 -254.45085)
			(xy 88.851232 -254.45085)
		)
		(stroke
			(width 0)
			(type solid)
		)
		(fill yes)
		(layer "In2.Cu")
		(net "M_C_CPU1_SA_CA<4>")
	)
	(gr_poly
		(pts
			(xy 88.851232 -254.00254) (xy 88.851232 -253.95809) (xy 88.65108 -253.95809) (xy 88.65108 -254.00254)
			(xy 88.751156 -254.102616)
		)
		(stroke
			(width 0)
			(type solid)
		)
		(fill yes)
		(layer "In2.Cu")
		(net "M_C_CPU1_SA_CA<3>")
	)
	(gr_poly
		(pts
			(xy 88.851232 -252.786388) (xy 88.751156 -252.686312) (xy 88.65108 -252.786388) (xy 88.65108 -252.830838)
			(xy 88.851232 -252.830838)
		)
		(stroke
			(width 0)
			(type solid)
		)
		(fill yes)
		(layer "In2.Cu")
		(net "M_C_CPU1_SA_CA<0>")
	)
	(gr_poly
		(pts
			(xy 88.851232 -252.382528) (xy 88.851232 -252.338078) (xy 88.65108 -252.338078) (xy 88.65108 -252.382528)
			(xy 88.751156 -252.482604)
		)
		(stroke
			(width 0)
			(type solid)
		)
		(fill yes)
		(layer "In2.Cu")
		(net "M_C_CPU1_SA_CS_N<1>")
	)
	(gr_poly
		(pts
			(xy 88.851232 -250.762516) (xy 88.851232 -250.718066) (xy 88.65108 -250.718066) (xy 88.65108 -250.762516)
			(xy 88.751156 -250.862592)
		)
		(stroke
			(width 0)
			(type solid)
		)
		(fill yes)
		(layer "In2.Cu")
		(net "M_C_CPU1_RESET_N")
	)
	(gr_poly
		(pts
			(xy 88.851232 -249.142504) (xy 88.851232 -249.098054) (xy 88.65108 -249.098054) (xy 88.65108 -249.142504)
			(xy 88.751156 -249.24258)
		)
		(stroke
			(width 0)
			(type solid)
		)
		(fill yes)
		(layer "In2.Cu")
		(net "M_C_CPU1_SA_CB<7>")
	)
	(gr_poly
		(pts
			(xy 88.851232 -247.926352) (xy 88.751156 -247.826276) (xy 88.65108 -247.926352) (xy 88.65108 -247.970802)
			(xy 88.851232 -247.970802)
		)
		(stroke
			(width 0)
			(type solid)
		)
		(fill yes)
		(layer "In2.Cu")
		(net "M_C_CPU1_SA_CB<4>")
	)
	(gr_poly
		(pts
			(xy 88.851232 -247.522746) (xy 88.851232 -247.474994) (xy 88.65108 -247.474994) (xy 88.65108 -247.522746)
			(xy 88.751156 -247.622568)
		)
		(stroke
			(width 0)
			(type solid)
		)
		(fill yes)
		(layer "In2.Cu")
		(net "M_C_CPU1_SA_DQS_DP<9>")
	)
	(gr_poly
		(pts
			(xy 88.851232 -246.306086) (xy 88.751156 -246.206264) (xy 88.65108 -246.306086) (xy 88.65108 -246.353838)
			(xy 88.851232 -246.353838)
		)
		(stroke
			(width 0)
			(type solid)
		)
		(fill yes)
		(layer "In2.Cu")
		(net "M_C_CPU1_SA_DQS_DP<4>")
	)
	(gr_poly
		(pts
			(xy 88.851232 -245.90248) (xy 88.851232 -245.85803) (xy 88.65108 -245.85803) (xy 88.65108 -245.90248)
			(xy 88.751156 -246.002556)
		)
		(stroke
			(width 0)
			(type solid)
		)
		(fill yes)
		(layer "In2.Cu")
		(net "M_C_CPU1_SA_CB<3>")
	)
	(gr_poly
		(pts
			(xy 88.851232 -244.686328) (xy 88.751156 -244.586252) (xy 88.65108 -244.686328) (xy 88.65108 -244.730778)
			(xy 88.851232 -244.730778)
		)
		(stroke
			(width 0)
			(type solid)
		)
		(fill yes)
		(layer "In2.Cu")
		(net "M_C_CPU1_SA_CB<0>")
	)
	(gr_poly
		(pts
			(xy 88.851232 -244.282468) (xy 88.851232 -244.238018) (xy 88.65108 -244.238018) (xy 88.65108 -244.282468)
			(xy 88.751156 -244.382544)
		)
		(stroke
			(width 0)
			(type solid)
		)
		(fill yes)
		(layer "In2.Cu")
		(net "M_C_CPU1_SA_DQ<31>")
	)
	(gr_poly
		(pts
			(xy 88.851232 -243.066316) (xy 88.751156 -242.96624) (xy 88.65108 -243.066316) (xy 88.65108 -243.110766)
			(xy 88.851232 -243.110766)
		)
		(stroke
			(width 0)
			(type solid)
		)
		(fill yes)
		(layer "In2.Cu")
		(net "M_C_CPU1_SA_DQ<28>")
	)
	(gr_poly
		(pts
			(xy 88.851232 -242.66271) (xy 88.851232 -242.614958) (xy 88.65108 -242.614958) (xy 88.65108 -242.66271)
			(xy 88.751156 -242.762532)
		)
		(stroke
			(width 0)
			(type solid)
		)
		(fill yes)
		(layer "In2.Cu")
		(net "M_C_CPU1_SA_DQS_DP<8>")
	)
	(gr_poly
		(pts
			(xy 88.851232 -241.44605) (xy 88.751156 -241.346228) (xy 88.65108 -241.44605) (xy 88.65108 -241.493802)
			(xy 88.851232 -241.493802)
		)
		(stroke
			(width 0)
			(type solid)
		)
		(fill yes)
		(layer "In2.Cu")
		(net "M_C_CPU1_SA_DQS_DP<3>")
	)
	(gr_poly
		(pts
			(xy 88.851232 -241.042444) (xy 88.851232 -240.997994) (xy 88.65108 -240.997994) (xy 88.65108 -241.042444)
			(xy 88.751156 -241.14252)
		)
		(stroke
			(width 0)
			(type solid)
		)
		(fill yes)
		(layer "In2.Cu")
		(net "M_C_CPU1_SA_DQ<27>")
	)
	(gr_poly
		(pts
			(xy 88.851232 -239.826292) (xy 88.751156 -239.726216) (xy 88.65108 -239.826292) (xy 88.65108 -239.870742)
			(xy 88.851232 -239.870742)
		)
		(stroke
			(width 0)
			(type solid)
		)
		(fill yes)
		(layer "In2.Cu")
		(net "M_C_CPU1_SA_DQ<24>")
	)
	(gr_poly
		(pts
			(xy 88.851232 -239.422432) (xy 88.851232 -239.377982) (xy 88.65108 -239.377982) (xy 88.65108 -239.422432)
			(xy 88.751156 -239.522508)
		)
		(stroke
			(width 0)
			(type solid)
		)
		(fill yes)
		(layer "In2.Cu")
		(net "M_C_CPU1_SA_DQ<23>")
	)
	(gr_poly
		(pts
			(xy 88.851232 -238.20628) (xy 88.751156 -238.106204) (xy 88.65108 -238.20628) (xy 88.65108 -238.25073)
			(xy 88.851232 -238.25073)
		)
		(stroke
			(width 0)
			(type solid)
		)
		(fill yes)
		(layer "In2.Cu")
		(net "M_C_CPU1_SA_DQ<20>")
	)
	(gr_poly
		(pts
			(xy 88.851232 -237.802674) (xy 88.851232 -237.754922) (xy 88.65108 -237.754922) (xy 88.65108 -237.802674)
			(xy 88.751156 -237.902496)
		)
		(stroke
			(width 0)
			(type solid)
		)
		(fill yes)
		(layer "In2.Cu")
		(net "M_C_CPU1_SA_DQS_DP<7>")
	)
	(gr_poly
		(pts
			(xy 88.851232 -236.586014) (xy 88.751156 -236.486192) (xy 88.65108 -236.586014) (xy 88.65108 -236.633766)
			(xy 88.851232 -236.633766)
		)
		(stroke
			(width 0)
			(type solid)
		)
		(fill yes)
		(layer "In2.Cu")
		(net "M_C_CPU1_SA_DQS_DP<2>")
	)
	(gr_poly
		(pts
			(xy 88.851232 -236.182408) (xy 88.851232 -236.137958) (xy 88.65108 -236.137958) (xy 88.65108 -236.182408)
			(xy 88.751156 -236.282484)
		)
		(stroke
			(width 0)
			(type solid)
		)
		(fill yes)
		(layer "In2.Cu")
		(net "M_C_CPU1_SA_DQ<19>")
	)
	(gr_poly
		(pts
			(xy 88.851232 -234.966256) (xy 88.751156 -234.86618) (xy 88.65108 -234.966256) (xy 88.65108 -235.010706)
			(xy 88.851232 -235.010706)
		)
		(stroke
			(width 0)
			(type solid)
		)
		(fill yes)
		(layer "In2.Cu")
		(net "M_C_CPU1_SA_DQ<16>")
	)
	(gr_poly
		(pts
			(xy 88.851232 -234.562396) (xy 88.851232 -234.517946) (xy 88.65108 -234.517946) (xy 88.65108 -234.562396)
			(xy 88.751156 -234.662472)
		)
		(stroke
			(width 0)
			(type solid)
		)
		(fill yes)
		(layer "In2.Cu")
		(net "M_C_CPU1_SA_DQ<15>")
	)
	(gr_poly
		(pts
			(xy 88.851232 -233.346244) (xy 88.751156 -233.246168) (xy 88.65108 -233.346244) (xy 88.65108 -233.390694)
			(xy 88.851232 -233.390694)
		)
		(stroke
			(width 0)
			(type solid)
		)
		(fill yes)
		(layer "In2.Cu")
		(net "M_C_CPU1_SA_DQ<12>")
	)
	(gr_poly
		(pts
			(xy 88.851232 -232.942638) (xy 88.851232 -232.894886) (xy 88.65108 -232.894886) (xy 88.65108 -232.942638)
			(xy 88.751156 -233.04246)
		)
		(stroke
			(width 0)
			(type solid)
		)
		(fill yes)
		(layer "In2.Cu")
		(net "M_C_CPU1_SA_DQS_DP<6>")
	)
	(gr_poly
		(pts
			(xy 88.851232 -231.725978) (xy 88.751156 -231.626156) (xy 88.65108 -231.725978) (xy 88.65108 -231.77373)
			(xy 88.851232 -231.77373)
		)
		(stroke
			(width 0)
			(type solid)
		)
		(fill yes)
		(layer "In2.Cu")
		(net "M_C_CPU1_SA_DQS_DP<1>")
	)
	(gr_poly
		(pts
			(xy 88.851232 -231.322626) (xy 88.851232 -231.278176) (xy 88.65108 -231.278176) (xy 88.65108 -231.322626)
			(xy 88.751156 -231.422702)
		)
		(stroke
			(width 0)
			(type solid)
		)
		(fill yes)
		(layer "In2.Cu")
		(net "M_C_CPU1_SA_DQ<11>")
	)
	(gr_poly
		(pts
			(xy 88.851232 -230.10622) (xy 88.751156 -230.006144) (xy 88.65108 -230.10622) (xy 88.65108 -230.15067)
			(xy 88.851232 -230.15067)
		)
		(stroke
			(width 0)
			(type solid)
		)
		(fill yes)
		(layer "In2.Cu")
		(net "M_C_CPU1_SA_DQ<8>")
	)
	(gr_poly
		(pts
			(xy 88.851232 -229.702614) (xy 88.851232 -229.658164) (xy 88.65108 -229.658164) (xy 88.65108 -229.702614)
			(xy 88.751156 -229.80269)
		)
		(stroke
			(width 0)
			(type solid)
		)
		(fill yes)
		(layer "In2.Cu")
		(net "M_C_CPU1_SA_DQ<7>")
	)
	(gr_poly
		(pts
			(xy 88.851232 -228.486462) (xy 88.751156 -228.386386) (xy 88.65108 -228.486462) (xy 88.65108 -228.530912)
			(xy 88.851232 -228.530912)
		)
		(stroke
			(width 0)
			(type solid)
		)
		(fill yes)
		(layer "In2.Cu")
		(net "M_C_CPU1_SA_DQ<4>")
	)
	(gr_poly
		(pts
			(xy 88.851232 -228.082856) (xy 88.851232 -228.035104) (xy 88.65108 -228.035104) (xy 88.65108 -228.082856)
			(xy 88.751156 -228.182678)
		)
		(stroke
			(width 0)
			(type solid)
		)
		(fill yes)
		(layer "In2.Cu")
		(net "M_C_CPU1_SA_DQS_DP<5>")
	)
	(gr_poly
		(pts
			(xy 88.851232 -226.866196) (xy 88.751156 -226.766374) (xy 88.65108 -226.866196) (xy 88.65108 -226.913948)
			(xy 88.851232 -226.913948)
		)
		(stroke
			(width 0)
			(type solid)
		)
		(fill yes)
		(layer "In2.Cu")
		(net "M_C_CPU1_SA_DQS_DP<0>")
	)
	(gr_poly
		(pts
			(xy 88.851232 -226.46259) (xy 88.851232 -226.41814) (xy 88.65108 -226.41814) (xy 88.65108 -226.46259)
			(xy 88.751156 -226.562666)
		)
		(stroke
			(width 0)
			(type solid)
		)
		(fill yes)
		(layer "In2.Cu")
		(net "M_C_CPU1_SA_DQ<3>")
	)
	(gr_poly
		(pts
			(xy 88.851232 -225.246438) (xy 88.751156 -225.146362) (xy 88.65108 -225.246438) (xy 88.65108 -225.290888)
			(xy 88.851232 -225.290888)
		)
		(stroke
			(width 0)
			(type solid)
		)
		(fill yes)
		(layer "In2.Cu")
		(net "M_C_CPU1_SA_DQ<0>")
	)
	(gr_poly
		(pts
			(xy 89.14384 -291.297868) (xy 89.043764 -291.198046) (xy 88.943942 -291.297868) (xy 88.943942 -291.34562)
			(xy 89.14384 -291.34562)
		)
		(stroke
			(width 0)
			(type solid)
		)
		(fill yes)
		(layer "In2.Cu")
		(net "M_C_CPU1_SB_DQS_DN<8>")
	)
	(gr_poly
		(pts
			(xy 89.144856 -266.991846) (xy 89.04478 -266.89177) (xy 88.944958 -266.991846) (xy 88.944958 -267.036296)
			(xy 89.144856 -267.036296)
		)
		(stroke
			(width 0)
			(type solid)
		)
		(fill yes)
		(layer "In2.Cu")
		(net "M_C_CPU1_SA_RSP<0>")
	)
	(gr_poly
		(pts
			(xy 89.151206 -292.918134) (xy 89.05113 -292.818058) (xy 88.951054 -292.918134) (xy 88.951054 -292.962584)
			(xy 89.151206 -292.962584)
		)
		(stroke
			(width 0)
			(type solid)
		)
		(fill yes)
		(layer "In2.Cu")
		(net "M_C_CPU1_SB_DQ<29>")
	)
	(gr_poly
		(pts
			(xy 89.151206 -292.514274) (xy 89.151206 -292.469824) (xy 88.951054 -292.469824) (xy 88.951054 -292.514274)
			(xy 89.05113 -292.61435)
		)
		(stroke
			(width 0)
			(type solid)
		)
		(fill yes)
		(layer "In2.Cu")
		(net "M_C_CPU1_SB_DQ<30>")
	)
	(gr_poly
		(pts
			(xy 89.151206 -290.894516) (xy 89.151206 -290.846764) (xy 88.951054 -290.846764) (xy 88.951054 -290.894516)
			(xy 89.05113 -290.994338)
		)
		(stroke
			(width 0)
			(type solid)
		)
		(fill yes)
		(layer "In2.Cu")
		(net "M_C_CPU1_SB_DQS_DN<3>")
	)
	(gr_poly
		(pts
			(xy 89.151206 -289.67811) (xy 89.05113 -289.578034) (xy 88.951054 -289.67811) (xy 88.951054 -289.72256)
			(xy 89.151206 -289.72256)
		)
		(stroke
			(width 0)
			(type solid)
		)
		(fill yes)
		(layer "In2.Cu")
		(net "M_C_CPU1_SB_DQ<25>")
	)
	(gr_poly
		(pts
			(xy 89.151206 -289.27425) (xy 89.151206 -289.2298) (xy 88.951054 -289.2298) (xy 88.951054 -289.27425)
			(xy 89.05113 -289.374326)
		)
		(stroke
			(width 0)
			(type solid)
		)
		(fill yes)
		(layer "In2.Cu")
		(net "M_C_CPU1_SB_DQ<26>")
	)
	(gr_poly
		(pts
			(xy 89.151206 -288.058098) (xy 89.05113 -287.958022) (xy 88.951054 -288.058098) (xy 88.951054 -288.102548)
			(xy 89.151206 -288.102548)
		)
		(stroke
			(width 0)
			(type solid)
		)
		(fill yes)
		(layer "In2.Cu")
		(net "M_C_CPU1_SB_DQ<21>")
	)
	(gr_poly
		(pts
			(xy 89.151206 -287.654492) (xy 89.151206 -287.610042) (xy 88.951054 -287.610042) (xy 88.951054 -287.654492)
			(xy 89.05113 -287.754568)
		)
		(stroke
			(width 0)
			(type solid)
		)
		(fill yes)
		(layer "In2.Cu")
		(net "M_C_CPU1_SB_DQ<22>")
	)
	(gr_poly
		(pts
			(xy 89.151206 -286.438086) (xy 89.05113 -286.33801) (xy 88.951054 -286.438086) (xy 88.951054 -286.485838)
			(xy 89.151206 -286.485838)
		)
		(stroke
			(width 0)
			(type solid)
		)
		(fill yes)
		(layer "In2.Cu")
		(net "M_C_CPU1_SB_DQS_DN<7>")
	)
	(gr_poly
		(pts
			(xy 89.151206 -286.034734) (xy 89.151206 -285.986982) (xy 88.951054 -285.986982) (xy 88.951054 -286.034734)
			(xy 89.05113 -286.134556)
		)
		(stroke
			(width 0)
			(type solid)
		)
		(fill yes)
		(layer "In2.Cu")
		(net "M_C_CPU1_SB_DQS_DN<2>")
	)
	(gr_poly
		(pts
			(xy 89.151206 -284.818328) (xy 89.05113 -284.718252) (xy 88.951054 -284.818328) (xy 88.951054 -284.862778)
			(xy 89.151206 -284.862778)
		)
		(stroke
			(width 0)
			(type solid)
		)
		(fill yes)
		(layer "In2.Cu")
		(net "M_C_CPU1_SB_DQ<17>")
	)
	(gr_poly
		(pts
			(xy 89.151206 -284.414468) (xy 89.151206 -284.370018) (xy 88.951054 -284.370018) (xy 88.951054 -284.414468)
			(xy 89.05113 -284.514544)
		)
		(stroke
			(width 0)
			(type solid)
		)
		(fill yes)
		(layer "In2.Cu")
		(net "M_C_CPU1_SB_DQ<18>")
	)
	(gr_poly
		(pts
			(xy 89.151206 -283.198316) (xy 89.05113 -283.09824) (xy 88.951054 -283.198316) (xy 88.951054 -283.242766)
			(xy 89.151206 -283.242766)
		)
		(stroke
			(width 0)
			(type solid)
		)
		(fill yes)
		(layer "In2.Cu")
		(net "M_C_CPU1_SB_DQ<13>")
	)
	(gr_poly
		(pts
			(xy 89.151206 -282.794456) (xy 89.151206 -282.750006) (xy 88.951054 -282.750006) (xy 88.951054 -282.794456)
			(xy 89.05113 -282.894532)
		)
		(stroke
			(width 0)
			(type solid)
		)
		(fill yes)
		(layer "In2.Cu")
		(net "M_C_CPU1_SB_DQ<14>")
	)
	(gr_poly
		(pts
			(xy 89.151206 -281.57805) (xy 89.05113 -281.478228) (xy 88.951054 -281.57805) (xy 88.951054 -281.625802)
			(xy 89.151206 -281.625802)
		)
		(stroke
			(width 0)
			(type solid)
		)
		(fill yes)
		(layer "In2.Cu")
		(net "M_C_CPU1_SB_DQS_DN<6>")
	)
	(gr_poly
		(pts
			(xy 89.151206 -281.174698) (xy 89.151206 -281.126946) (xy 88.951054 -281.126946) (xy 88.951054 -281.174698)
			(xy 89.05113 -281.27452)
		)
		(stroke
			(width 0)
			(type solid)
		)
		(fill yes)
		(layer "In2.Cu")
		(net "M_C_CPU1_SB_DQS_DN<1>")
	)
	(gr_poly
		(pts
			(xy 89.151206 -279.958292) (xy 89.05113 -279.858216) (xy 88.951054 -279.958292) (xy 88.951054 -280.002742)
			(xy 89.151206 -280.002742)
		)
		(stroke
			(width 0)
			(type solid)
		)
		(fill yes)
		(layer "In2.Cu")
		(net "M_C_CPU1_SB_DQ<9>")
	)
	(gr_poly
		(pts
			(xy 89.151206 -279.554432) (xy 89.151206 -279.509982) (xy 88.951054 -279.509982) (xy 88.951054 -279.554432)
			(xy 89.05113 -279.654508)
		)
		(stroke
			(width 0)
			(type solid)
		)
		(fill yes)
		(layer "In2.Cu")
		(net "M_C_CPU1_SB_DQ<10>")
	)
	(gr_poly
		(pts
			(xy 89.151206 -278.33828) (xy 89.05113 -278.238204) (xy 88.951054 -278.33828) (xy 88.951054 -278.38273)
			(xy 89.151206 -278.38273)
		)
		(stroke
			(width 0)
			(type solid)
		)
		(fill yes)
		(layer "In2.Cu")
		(net "M_C_CPU1_SB_DQ<5>")
	)
	(gr_poly
		(pts
			(xy 89.151206 -277.93442) (xy 89.151206 -277.88997) (xy 88.951054 -277.88997) (xy 88.951054 -277.93442)
			(xy 89.05113 -278.034496)
		)
		(stroke
			(width 0)
			(type solid)
		)
		(fill yes)
		(layer "In2.Cu")
		(net "M_C_CPU1_SB_DQ<6>")
	)
	(gr_poly
		(pts
			(xy 89.151206 -276.718014) (xy 89.05113 -276.618192) (xy 88.951054 -276.718014) (xy 88.951054 -276.765766)
			(xy 89.151206 -276.765766)
		)
		(stroke
			(width 0)
			(type solid)
		)
		(fill yes)
		(layer "In2.Cu")
		(net "M_C_CPU1_SB_DQS_DN<5>")
	)
	(gr_poly
		(pts
			(xy 89.151206 -276.314662) (xy 89.151206 -276.26691) (xy 88.951054 -276.26691) (xy 88.951054 -276.314662)
			(xy 89.05113 -276.414484)
		)
		(stroke
			(width 0)
			(type solid)
		)
		(fill yes)
		(layer "In2.Cu")
		(net "M_C_CPU1_SB_DQS_DN<0>")
	)
	(gr_poly
		(pts
			(xy 89.151206 -275.098256) (xy 89.05113 -274.99818) (xy 88.951054 -275.098256) (xy 88.951054 -275.142706)
			(xy 89.151206 -275.142706)
		)
		(stroke
			(width 0)
			(type solid)
		)
		(fill yes)
		(layer "In2.Cu")
		(net "M_C_CPU1_SB_DQ<1>")
	)
	(gr_poly
		(pts
			(xy 89.151206 -274.694396) (xy 89.151206 -274.649946) (xy 88.951054 -274.649946) (xy 88.951054 -274.694396)
			(xy 89.05113 -274.794472)
		)
		(stroke
			(width 0)
			(type solid)
		)
		(fill yes)
		(layer "In2.Cu")
		(net "M_C_CPU1_SB_DQ<2>")
	)
	(gr_poly
		(pts
			(xy 89.151206 -273.478244) (xy 89.05113 -273.378168) (xy 88.951054 -273.478244) (xy 88.951054 -273.522694)
			(xy 89.151206 -273.522694)
		)
		(stroke
			(width 0)
			(type solid)
		)
		(fill yes)
		(layer "In2.Cu")
		(net "M_C_CPU1_SB_CB<1>")
	)
	(gr_poly
		(pts
			(xy 89.151206 -273.074384) (xy 89.151206 -273.029934) (xy 88.951054 -273.029934) (xy 88.951054 -273.074384)
			(xy 89.05113 -273.17446)
		)
		(stroke
			(width 0)
			(type solid)
		)
		(fill yes)
		(layer "In2.Cu")
		(net "M_C_CPU1_SB_CB<2>")
	)
	(gr_poly
		(pts
			(xy 89.151206 -271.857978) (xy 89.05113 -271.758156) (xy 88.951054 -271.857978) (xy 88.951054 -271.90573)
			(xy 89.151206 -271.90573)
		)
		(stroke
			(width 0)
			(type solid)
		)
		(fill yes)
		(layer "In2.Cu")
		(net "M_C_CPU1_SB_DQS_DN<4>")
	)
	(gr_poly
		(pts
			(xy 89.151206 -271.454626) (xy 89.151206 -271.406874) (xy 88.951054 -271.406874) (xy 88.951054 -271.454626)
			(xy 89.05113 -271.554448)
		)
		(stroke
			(width 0)
			(type solid)
		)
		(fill yes)
		(layer "In2.Cu")
		(net "M_C_CPU1_SB_DQS_DN<9>")
	)
	(gr_poly
		(pts
			(xy 89.151206 -270.23822) (xy 89.05113 -270.138144) (xy 88.951054 -270.23822) (xy 88.951054 -270.28267)
			(xy 89.151206 -270.28267)
		)
		(stroke
			(width 0)
			(type solid)
		)
		(fill yes)
		(layer "In2.Cu")
		(net "M_C_CPU1_SB_CB<5>")
	)
	(gr_poly
		(pts
			(xy 89.151206 -269.83436) (xy 89.151206 -269.78991) (xy 88.951054 -269.78991) (xy 88.951054 -269.83436)
			(xy 89.05113 -269.934436)
		)
		(stroke
			(width 0)
			(type solid)
		)
		(fill yes)
		(layer "In2.Cu")
		(net "M_C_CPU1_SB_CB<6>")
	)
	(gr_poly
		(pts
			(xy 89.151206 -266.594336) (xy 89.151206 -266.549886) (xy 88.951054 -266.549886) (xy 88.951054 -266.594336)
			(xy 89.05113 -266.694412)
		)
		(stroke
			(width 0)
			(type solid)
		)
		(fill yes)
		(layer "In2.Cu")
		(net "M_C_CPU1_SB_CS_N<1>")
	)
	(gr_poly
		(pts
			(xy 89.151206 -264.974324) (xy 89.151206 -264.929874) (xy 88.951054 -264.929874) (xy 88.951054 -264.974324)
			(xy 89.05113 -265.0744)
		)
		(stroke
			(width 0)
			(type solid)
		)
		(fill yes)
		(layer "In2.Cu")
		(net "M_C_CPU1_SB_PAR")
	)
	(gr_poly
		(pts
			(xy 89.151206 -263.758172) (xy 89.05113 -263.658096) (xy 88.951054 -263.758172) (xy 88.951054 -263.802622)
			(xy 89.151206 -263.802622)
		)
		(stroke
			(width 0)
			(type solid)
		)
		(fill yes)
		(layer "In2.Cu")
		(net "M_C_CPU1_SB_CA<4>")
	)
	(gr_poly
		(pts
			(xy 89.151206 -263.354312) (xy 89.151206 -263.309862) (xy 88.951054 -263.309862) (xy 88.951054 -263.354312)
			(xy 89.05113 -263.454388)
		)
		(stroke
			(width 0)
			(type solid)
		)
		(fill yes)
		(layer "In2.Cu")
		(net "M_C_CPU1_SB_CA<3>")
	)
	(gr_poly
		(pts
			(xy 89.151206 -262.13816) (xy 89.05113 -262.038084) (xy 88.951054 -262.13816) (xy 88.951054 -262.18261)
			(xy 89.151206 -262.18261)
		)
		(stroke
			(width 0)
			(type solid)
		)
		(fill yes)
		(layer "In2.Cu")
		(net "M_C_CPU1_SB_CA<0>")
	)
	(gr_poly
		(pts
			(xy 89.320878 -246.712486) (xy 89.320878 -246.664988) (xy 89.12098 -246.664988) (xy 89.12098 -246.712486)
			(xy 89.220802 -246.812562)
		)
		(stroke
			(width 0)
			(type solid)
		)
		(fill yes)
		(layer "In2.Cu")
		(net "M_C_CPU1_SA_DQS_DN<4>")
	)
	(gr_poly
		(pts
			(xy 89.321132 -256.432812) (xy 89.321132 -256.38506) (xy 89.12098 -256.38506) (xy 89.12098 -256.432812)
			(xy 89.221056 -256.532634)
		)
		(stroke
			(width 0)
			(type solid)
		)
		(fill yes)
		(layer "In2.Cu")
		(net "M_C_CPU1_CLK_DN<0>")
	)
	(gr_poly
		(pts
			(xy 89.321132 -255.216406) (xy 89.221056 -255.11633) (xy 89.12098 -255.216406) (xy 89.12098 -255.260856)
			(xy 89.321132 -255.260856)
		)
		(stroke
			(width 0)
			(type solid)
		)
		(fill yes)
		(layer "In2.Cu")
		(net "M_C_CPU1_SA_CA<6>")
	)
	(gr_poly
		(pts
			(xy 89.321132 -254.812546) (xy 89.321132 -254.768096) (xy 89.12098 -254.768096) (xy 89.12098 -254.812546)
			(xy 89.221056 -254.912622)
		)
		(stroke
			(width 0)
			(type solid)
		)
		(fill yes)
		(layer "In2.Cu")
		(net "M_C_CPU1_SA_CA<5>")
	)
	(gr_poly
		(pts
			(xy 89.321132 -253.596394) (xy 89.221056 -253.496318) (xy 89.12098 -253.596394) (xy 89.12098 -253.640844)
			(xy 89.321132 -253.640844)
		)
		(stroke
			(width 0)
			(type solid)
		)
		(fill yes)
		(layer "In2.Cu")
		(net "M_C_CPU1_SA_CA<2>")
	)
	(gr_poly
		(pts
			(xy 89.321132 -253.192534) (xy 89.321132 -253.148084) (xy 89.12098 -253.148084) (xy 89.12098 -253.192534)
			(xy 89.221056 -253.29261)
		)
		(stroke
			(width 0)
			(type solid)
		)
		(fill yes)
		(layer "In2.Cu")
		(net "M_C_CPU1_SA_CA<1>")
	)
	(gr_poly
		(pts
			(xy 89.321132 -251.572522) (xy 89.321132 -251.528072) (xy 89.12098 -251.528072) (xy 89.12098 -251.572522)
			(xy 89.221056 -251.672598)
		)
		(stroke
			(width 0)
			(type solid)
		)
		(fill yes)
		(layer "In2.Cu")
		(net "M_C_CPU1_SA_CS_N<0>")
	)
	(gr_poly
		(pts
			(xy 89.321132 -250.35637) (xy 89.221056 -250.256294) (xy 89.12098 -250.35637) (xy 89.12098 -250.40082)
			(xy 89.321132 -250.40082)
		)
		(stroke
			(width 0)
			(type solid)
		)
		(fill yes)
		(layer "In2.Cu")
		(net "M_C_CPU1_ALERT_R_N")
	)
	(gr_poly
		(pts
			(xy 89.321132 -248.736358) (xy 89.221056 -248.636282) (xy 89.12098 -248.736358) (xy 89.12098 -248.780808)
			(xy 89.321132 -248.780808)
		)
		(stroke
			(width 0)
			(type solid)
		)
		(fill yes)
		(layer "In2.Cu")
		(net "M_C_CPU1_SA_CB<5>")
	)
	(gr_poly
		(pts
			(xy 89.321132 -248.332498) (xy 89.321132 -248.288048) (xy 89.12098 -248.288048) (xy 89.12098 -248.332498)
			(xy 89.221056 -248.432574)
		)
		(stroke
			(width 0)
			(type solid)
		)
		(fill yes)
		(layer "In2.Cu")
		(net "M_C_CPU1_SA_CB<6>")
	)
	(gr_poly
		(pts
			(xy 89.321132 -247.116092) (xy 89.221056 -247.01627) (xy 89.12098 -247.116092) (xy 89.12098 -247.163844)
			(xy 89.321132 -247.163844)
		)
		(stroke
			(width 0)
			(type solid)
		)
		(fill yes)
		(layer "In2.Cu")
		(net "M_C_CPU1_SA_DQS_DN<9>")
	)
	(gr_poly
		(pts
			(xy 89.321132 -245.496334) (xy 89.221056 -245.396258) (xy 89.12098 -245.496334) (xy 89.12098 -245.540784)
			(xy 89.321132 -245.540784)
		)
		(stroke
			(width 0)
			(type solid)
		)
		(fill yes)
		(layer "In2.Cu")
		(net "M_C_CPU1_SA_CB<1>")
	)
	(gr_poly
		(pts
			(xy 89.321132 -245.092474) (xy 89.321132 -245.048024) (xy 89.12098 -245.048024) (xy 89.12098 -245.092474)
			(xy 89.221056 -245.19255)
		)
		(stroke
			(width 0)
			(type solid)
		)
		(fill yes)
		(layer "In2.Cu")
		(net "M_C_CPU1_SA_CB<2>")
	)
	(gr_poly
		(pts
			(xy 89.321132 -243.876322) (xy 89.221056 -243.776246) (xy 89.12098 -243.876322) (xy 89.12098 -243.920772)
			(xy 89.321132 -243.920772)
		)
		(stroke
			(width 0)
			(type solid)
		)
		(fill yes)
		(layer "In2.Cu")
		(net "M_C_CPU1_SA_DQ<29>")
	)
	(gr_poly
		(pts
			(xy 89.321132 -243.472462) (xy 89.321132 -243.428012) (xy 89.12098 -243.428012) (xy 89.12098 -243.472462)
			(xy 89.221056 -243.572538)
		)
		(stroke
			(width 0)
			(type solid)
		)
		(fill yes)
		(layer "In2.Cu")
		(net "M_C_CPU1_SA_DQ<30>")
	)
	(gr_poly
		(pts
			(xy 89.321132 -242.256056) (xy 89.221056 -242.156234) (xy 89.12098 -242.256056) (xy 89.12098 -242.303808)
			(xy 89.321132 -242.303808)
		)
		(stroke
			(width 0)
			(type solid)
		)
		(fill yes)
		(layer "In2.Cu")
		(net "M_C_CPU1_SA_DQS_DN<8>")
	)
	(gr_poly
		(pts
			(xy 89.321132 -241.852704) (xy 89.321132 -241.804952) (xy 89.12098 -241.804952) (xy 89.12098 -241.852704)
			(xy 89.221056 -241.952526)
		)
		(stroke
			(width 0)
			(type solid)
		)
		(fill yes)
		(layer "In2.Cu")
		(net "M_C_CPU1_SA_DQS_DN<3>")
	)
	(gr_poly
		(pts
			(xy 89.321132 -240.636298) (xy 89.221056 -240.536222) (xy 89.12098 -240.636298) (xy 89.12098 -240.680748)
			(xy 89.321132 -240.680748)
		)
		(stroke
			(width 0)
			(type solid)
		)
		(fill yes)
		(layer "In2.Cu")
		(net "M_C_CPU1_SA_DQ<25>")
	)
	(gr_poly
		(pts
			(xy 89.321132 -240.232438) (xy 89.321132 -240.187988) (xy 89.12098 -240.187988) (xy 89.12098 -240.232438)
			(xy 89.221056 -240.332514)
		)
		(stroke
			(width 0)
			(type solid)
		)
		(fill yes)
		(layer "In2.Cu")
		(net "M_C_CPU1_SA_DQ<26>")
	)
	(gr_poly
		(pts
			(xy 89.321132 -239.016286) (xy 89.221056 -238.91621) (xy 89.12098 -239.016286) (xy 89.12098 -239.060736)
			(xy 89.321132 -239.060736)
		)
		(stroke
			(width 0)
			(type solid)
		)
		(fill yes)
		(layer "In2.Cu")
		(net "M_C_CPU1_SA_DQ<21>")
	)
	(gr_poly
		(pts
			(xy 89.321132 -238.612426) (xy 89.321132 -238.567976) (xy 89.12098 -238.567976) (xy 89.12098 -238.612426)
			(xy 89.221056 -238.712502)
		)
		(stroke
			(width 0)
			(type solid)
		)
		(fill yes)
		(layer "In2.Cu")
		(net "M_C_CPU1_SA_DQ<22>")
	)
	(gr_poly
		(pts
			(xy 89.321132 -237.39602) (xy 89.221056 -237.296198) (xy 89.12098 -237.39602) (xy 89.12098 -237.443772)
			(xy 89.321132 -237.443772)
		)
		(stroke
			(width 0)
			(type solid)
		)
		(fill yes)
		(layer "In2.Cu")
		(net "M_C_CPU1_SA_DQS_DN<7>")
	)
	(gr_poly
		(pts
			(xy 89.321132 -236.992668) (xy 89.321132 -236.944916) (xy 89.12098 -236.944916) (xy 89.12098 -236.992668)
			(xy 89.221056 -237.09249)
		)
		(stroke
			(width 0)
			(type solid)
		)
		(fill yes)
		(layer "In2.Cu")
		(net "M_C_CPU1_SA_DQS_DN<2>")
	)
	(gr_poly
		(pts
			(xy 89.321132 -235.776262) (xy 89.221056 -235.676186) (xy 89.12098 -235.776262) (xy 89.12098 -235.820712)
			(xy 89.321132 -235.820712)
		)
		(stroke
			(width 0)
			(type solid)
		)
		(fill yes)
		(layer "In2.Cu")
		(net "M_C_CPU1_SA_DQ<17>")
	)
	(gr_poly
		(pts
			(xy 89.321132 -235.372402) (xy 89.321132 -235.327952) (xy 89.12098 -235.327952) (xy 89.12098 -235.372402)
			(xy 89.221056 -235.472478)
		)
		(stroke
			(width 0)
			(type solid)
		)
		(fill yes)
		(layer "In2.Cu")
		(net "M_C_CPU1_SA_DQ<18>")
	)
	(gr_poly
		(pts
			(xy 89.321132 -234.15625) (xy 89.221056 -234.056174) (xy 89.12098 -234.15625) (xy 89.12098 -234.2007)
			(xy 89.321132 -234.2007)
		)
		(stroke
			(width 0)
			(type solid)
		)
		(fill yes)
		(layer "In2.Cu")
		(net "M_C_CPU1_SA_DQ<13>")
	)
	(gr_poly
		(pts
			(xy 89.321132 -233.75239) (xy 89.321132 -233.70794) (xy 89.12098 -233.70794) (xy 89.12098 -233.75239)
			(xy 89.221056 -233.852466)
		)
		(stroke
			(width 0)
			(type solid)
		)
		(fill yes)
		(layer "In2.Cu")
		(net "M_C_CPU1_SA_DQ<14>")
	)
	(gr_poly
		(pts
			(xy 89.321132 -232.535984) (xy 89.221056 -232.436162) (xy 89.12098 -232.535984) (xy 89.12098 -232.583736)
			(xy 89.321132 -232.583736)
		)
		(stroke
			(width 0)
			(type solid)
		)
		(fill yes)
		(layer "In2.Cu")
		(net "M_C_CPU1_SA_DQS_DN<6>")
	)
	(gr_poly
		(pts
			(xy 89.321132 -232.132632) (xy 89.321132 -232.08488) (xy 89.12098 -232.08488) (xy 89.12098 -232.132632)
			(xy 89.221056 -232.232454)
		)
		(stroke
			(width 0)
			(type solid)
		)
		(fill yes)
		(layer "In2.Cu")
		(net "M_C_CPU1_SA_DQS_DN<1>")
	)
	(gr_poly
		(pts
			(xy 89.321132 -230.916226) (xy 89.221056 -230.81615) (xy 89.12098 -230.916226) (xy 89.12098 -230.960676)
			(xy 89.321132 -230.960676)
		)
		(stroke
			(width 0)
			(type solid)
		)
		(fill yes)
		(layer "In2.Cu")
		(net "M_C_CPU1_SA_DQ<9>")
	)
	(gr_poly
		(pts
			(xy 89.321132 -230.51262) (xy 89.321132 -230.46817) (xy 89.12098 -230.46817) (xy 89.12098 -230.51262)
			(xy 89.221056 -230.612696)
		)
		(stroke
			(width 0)
			(type solid)
		)
		(fill yes)
		(layer "In2.Cu")
		(net "M_C_CPU1_SA_DQ<10>")
	)
	(gr_poly
		(pts
			(xy 89.321132 -229.296214) (xy 89.221056 -229.196138) (xy 89.12098 -229.296214) (xy 89.12098 -229.340664)
			(xy 89.321132 -229.340664)
		)
		(stroke
			(width 0)
			(type solid)
		)
		(fill yes)
		(layer "In2.Cu")
		(net "M_C_CPU1_SA_DQ<5>")
	)
	(gr_poly
		(pts
			(xy 89.321132 -228.892608) (xy 89.321132 -228.848158) (xy 89.12098 -228.848158) (xy 89.12098 -228.892608)
			(xy 89.221056 -228.992684)
		)
		(stroke
			(width 0)
			(type solid)
		)
		(fill yes)
		(layer "In2.Cu")
		(net "M_C_CPU1_SA_DQ<6>")
	)
	(gr_poly
		(pts
			(xy 89.321132 -227.676202) (xy 89.221056 -227.57638) (xy 89.12098 -227.676202) (xy 89.12098 -227.723954)
			(xy 89.321132 -227.723954)
		)
		(stroke
			(width 0)
			(type solid)
		)
		(fill yes)
		(layer "In2.Cu")
		(net "M_C_CPU1_SA_DQS_DN<5>")
	)
	(gr_poly
		(pts
			(xy 89.321132 -227.27285) (xy 89.321132 -227.225098) (xy 89.12098 -227.225098) (xy 89.12098 -227.27285)
			(xy 89.221056 -227.372672)
		)
		(stroke
			(width 0)
			(type solid)
		)
		(fill yes)
		(layer "In2.Cu")
		(net "M_C_CPU1_SA_DQS_DN<0>")
	)
	(gr_poly
		(pts
			(xy 89.321132 -226.056444) (xy 89.221056 -225.956368) (xy 89.12098 -226.056444) (xy 89.12098 -226.100894)
			(xy 89.321132 -226.100894)
		)
		(stroke
			(width 0)
			(type solid)
		)
		(fill yes)
		(layer "In2.Cu")
		(net "M_C_CPU1_SA_DQ<1>")
	)
	(gr_poly
		(pts
			(xy 89.321132 -225.652584) (xy 89.321132 -225.608134) (xy 89.12098 -225.608134) (xy 89.12098 -225.652584)
			(xy 89.221056 -225.75266)
		)
		(stroke
			(width 0)
			(type solid)
		)
		(fill yes)
		(layer "In2.Cu")
		(net "M_C_CPU1_SA_DQ<2>")
	)
	(gr_poly
		(pts
			(xy 89.621106 -293.32428) (xy 89.621106 -293.27983) (xy 89.420954 -293.27983) (xy 89.420954 -293.32428)
			(xy 89.52103 -293.424356)
		)
		(stroke
			(width 0)
			(type solid)
		)
		(fill yes)
		(layer "In2.Cu")
		(net "M_C_CPU1_SB_DQ<31>")
	)
	(gr_poly
		(pts
			(xy 89.621106 -292.108128) (xy 89.52103 -292.008052) (xy 89.420954 -292.108128) (xy 89.420954 -292.152578)
			(xy 89.621106 -292.152578)
		)
		(stroke
			(width 0)
			(type solid)
		)
		(fill yes)
		(layer "In2.Cu")
		(net "M_C_CPU1_SB_DQ<28>")
	)
	(gr_poly
		(pts
			(xy 89.621106 -291.704522) (xy 89.621106 -291.65677) (xy 89.420954 -291.65677) (xy 89.420954 -291.704522)
			(xy 89.52103 -291.804344)
		)
		(stroke
			(width 0)
			(type solid)
		)
		(fill yes)
		(layer "In2.Cu")
		(net "M_C_CPU1_SB_DQS_DP<8>")
	)
	(gr_poly
		(pts
			(xy 89.621106 -290.487862) (xy 89.52103 -290.38804) (xy 89.420954 -290.487862) (xy 89.420954 -290.535614)
			(xy 89.621106 -290.535614)
		)
		(stroke
			(width 0)
			(type solid)
		)
		(fill yes)
		(layer "In2.Cu")
		(net "M_C_CPU1_SB_DQS_DP<3>")
	)
	(gr_poly
		(pts
			(xy 89.621106 -290.084256) (xy 89.621106 -290.039806) (xy 89.420954 -290.039806) (xy 89.420954 -290.084256)
			(xy 89.52103 -290.184332)
		)
		(stroke
			(width 0)
			(type solid)
		)
		(fill yes)
		(layer "In2.Cu")
		(net "M_C_CPU1_SB_DQ<27>")
	)
	(gr_poly
		(pts
			(xy 89.621106 -288.868104) (xy 89.52103 -288.768028) (xy 89.420954 -288.868104) (xy 89.420954 -288.912554)
			(xy 89.621106 -288.912554)
		)
		(stroke
			(width 0)
			(type solid)
		)
		(fill yes)
		(layer "In2.Cu")
		(net "M_C_CPU1_SB_DQ<24>")
	)
	(gr_poly
		(pts
			(xy 89.621106 -288.464498) (xy 89.621106 -288.420048) (xy 89.420954 -288.420048) (xy 89.420954 -288.464498)
			(xy 89.52103 -288.564574)
		)
		(stroke
			(width 0)
			(type solid)
		)
		(fill yes)
		(layer "In2.Cu")
		(net "M_C_CPU1_SB_DQ<23>")
	)
	(gr_poly
		(pts
			(xy 89.621106 -287.248092) (xy 89.52103 -287.148016) (xy 89.420954 -287.248092) (xy 89.420954 -287.292542)
			(xy 89.621106 -287.292542)
		)
		(stroke
			(width 0)
			(type solid)
		)
		(fill yes)
		(layer "In2.Cu")
		(net "M_C_CPU1_SB_DQ<20>")
	)
	(gr_poly
		(pts
			(xy 89.621106 -286.844486) (xy 89.621106 -286.796734) (xy 89.420954 -286.796734) (xy 89.420954 -286.844486)
			(xy 89.52103 -286.944562)
		)
		(stroke
			(width 0)
			(type solid)
		)
		(fill yes)
		(layer "In2.Cu")
		(net "M_C_CPU1_SB_DQS_DP<7>")
	)
	(gr_poly
		(pts
			(xy 89.621106 -285.62808) (xy 89.52103 -285.528258) (xy 89.420954 -285.62808) (xy 89.420954 -285.675832)
			(xy 89.621106 -285.675832)
		)
		(stroke
			(width 0)
			(type solid)
		)
		(fill yes)
		(layer "In2.Cu")
		(net "M_C_CPU1_SB_DQS_DP<2>")
	)
	(gr_poly
		(pts
			(xy 89.621106 -285.224474) (xy 89.621106 -285.180024) (xy 89.420954 -285.180024) (xy 89.420954 -285.224474)
			(xy 89.52103 -285.32455)
		)
		(stroke
			(width 0)
			(type solid)
		)
		(fill yes)
		(layer "In2.Cu")
		(net "M_C_CPU1_SB_DQ<19>")
	)
	(gr_poly
		(pts
			(xy 89.621106 -284.008322) (xy 89.52103 -283.908246) (xy 89.420954 -284.008322) (xy 89.420954 -284.052772)
			(xy 89.621106 -284.052772)
		)
		(stroke
			(width 0)
			(type solid)
		)
		(fill yes)
		(layer "In2.Cu")
		(net "M_C_CPU1_SB_DQ<16>")
	)
	(gr_poly
		(pts
			(xy 89.621106 -283.604462) (xy 89.621106 -283.560012) (xy 89.420954 -283.560012) (xy 89.420954 -283.604462)
			(xy 89.52103 -283.704538)
		)
		(stroke
			(width 0)
			(type solid)
		)
		(fill yes)
		(layer "In2.Cu")
		(net "M_C_CPU1_SB_DQ<15>")
	)
	(gr_poly
		(pts
			(xy 89.621106 -282.38831) (xy 89.52103 -282.288234) (xy 89.420954 -282.38831) (xy 89.420954 -282.43276)
			(xy 89.621106 -282.43276)
		)
		(stroke
			(width 0)
			(type solid)
		)
		(fill yes)
		(layer "In2.Cu")
		(net "M_C_CPU1_SB_DQ<12>")
	)
	(gr_poly
		(pts
			(xy 89.621106 -281.984704) (xy 89.621106 -281.936952) (xy 89.420954 -281.936952) (xy 89.420954 -281.984704)
			(xy 89.52103 -282.084526)
		)
		(stroke
			(width 0)
			(type solid)
		)
		(fill yes)
		(layer "In2.Cu")
		(net "M_C_CPU1_SB_DQS_DP<6>")
	)
	(gr_poly
		(pts
			(xy 89.621106 -280.768044) (xy 89.52103 -280.668222) (xy 89.420954 -280.768044) (xy 89.420954 -280.815796)
			(xy 89.621106 -280.815796)
		)
		(stroke
			(width 0)
			(type solid)
		)
		(fill yes)
		(layer "In2.Cu")
		(net "M_C_CPU1_SB_DQS_DP<1>")
	)
	(gr_poly
		(pts
			(xy 89.621106 -280.364438) (xy 89.621106 -280.319988) (xy 89.420954 -280.319988) (xy 89.420954 -280.364438)
			(xy 89.52103 -280.464514)
		)
		(stroke
			(width 0)
			(type solid)
		)
		(fill yes)
		(layer "In2.Cu")
		(net "M_C_CPU1_SB_DQ<11>")
	)
	(gr_poly
		(pts
			(xy 89.621106 -279.148286) (xy 89.52103 -279.04821) (xy 89.420954 -279.148286) (xy 89.420954 -279.192736)
			(xy 89.621106 -279.192736)
		)
		(stroke
			(width 0)
			(type solid)
		)
		(fill yes)
		(layer "In2.Cu")
		(net "M_C_CPU1_SB_DQ<8>")
	)
	(gr_poly
		(pts
			(xy 89.621106 -278.744426) (xy 89.621106 -278.699976) (xy 89.420954 -278.699976) (xy 89.420954 -278.744426)
			(xy 89.52103 -278.844502)
		)
		(stroke
			(width 0)
			(type solid)
		)
		(fill yes)
		(layer "In2.Cu")
		(net "M_C_CPU1_SB_DQ<7>")
	)
	(gr_poly
		(pts
			(xy 89.621106 -277.528274) (xy 89.52103 -277.428198) (xy 89.420954 -277.528274) (xy 89.420954 -277.572724)
			(xy 89.621106 -277.572724)
		)
		(stroke
			(width 0)
			(type solid)
		)
		(fill yes)
		(layer "In2.Cu")
		(net "M_C_CPU1_SB_DQ<4>")
	)
	(gr_poly
		(pts
			(xy 89.621106 -277.124668) (xy 89.621106 -277.076916) (xy 89.420954 -277.076916) (xy 89.420954 -277.124668)
			(xy 89.52103 -277.22449)
		)
		(stroke
			(width 0)
			(type solid)
		)
		(fill yes)
		(layer "In2.Cu")
		(net "M_C_CPU1_SB_DQS_DP<5>")
	)
	(gr_poly
		(pts
			(xy 89.621106 -275.908008) (xy 89.52103 -275.808186) (xy 89.420954 -275.908008) (xy 89.420954 -275.95576)
			(xy 89.621106 -275.95576)
		)
		(stroke
			(width 0)
			(type solid)
		)
		(fill yes)
		(layer "In2.Cu")
		(net "M_C_CPU1_SB_DQS_DP<0>")
	)
	(gr_poly
		(pts
			(xy 89.621106 -275.504402) (xy 89.621106 -275.459952) (xy 89.420954 -275.459952) (xy 89.420954 -275.504402)
			(xy 89.52103 -275.604478)
		)
		(stroke
			(width 0)
			(type solid)
		)
		(fill yes)
		(layer "In2.Cu")
		(net "M_C_CPU1_SB_DQ<3>")
	)
	(gr_poly
		(pts
			(xy 89.621106 -274.28825) (xy 89.52103 -274.188174) (xy 89.420954 -274.28825) (xy 89.420954 -274.3327)
			(xy 89.621106 -274.3327)
		)
		(stroke
			(width 0)
			(type solid)
		)
		(fill yes)
		(layer "In2.Cu")
		(net "M_C_CPU1_SB_DQ<0>")
	)
	(gr_poly
		(pts
			(xy 89.621106 -273.88439) (xy 89.621106 -273.83994) (xy 89.420954 -273.83994) (xy 89.420954 -273.88439)
			(xy 89.52103 -273.984466)
		)
		(stroke
			(width 0)
			(type solid)
		)
		(fill yes)
		(layer "In2.Cu")
		(net "M_C_CPU1_SB_CB<3>")
	)
	(gr_poly
		(pts
			(xy 89.621106 -272.668238) (xy 89.52103 -272.568162) (xy 89.420954 -272.668238) (xy 89.420954 -272.712688)
			(xy 89.621106 -272.712688)
		)
		(stroke
			(width 0)
			(type solid)
		)
		(fill yes)
		(layer "In2.Cu")
		(net "M_C_CPU1_SB_CB<0>")
	)
	(gr_poly
		(pts
			(xy 89.621106 -272.264632) (xy 89.621106 -272.21688) (xy 89.420954 -272.21688) (xy 89.420954 -272.264632)
			(xy 89.52103 -272.364454)
		)
		(stroke
			(width 0)
			(type solid)
		)
		(fill yes)
		(layer "In2.Cu")
		(net "M_C_CPU1_SB_DQS_DP<4>")
	)
	(gr_poly
		(pts
			(xy 89.621106 -271.047972) (xy 89.52103 -270.94815) (xy 89.420954 -271.047972) (xy 89.420954 -271.095724)
			(xy 89.621106 -271.095724)
		)
		(stroke
			(width 0)
			(type solid)
		)
		(fill yes)
		(layer "In2.Cu")
		(net "M_C_CPU1_SB_DQS_DP<9>")
	)
	(gr_poly
		(pts
			(xy 89.621106 -270.644366) (xy 89.621106 -270.599916) (xy 89.420954 -270.599916) (xy 89.420954 -270.644366)
			(xy 89.52103 -270.744442)
		)
		(stroke
			(width 0)
			(type solid)
		)
		(fill yes)
		(layer "In2.Cu")
		(net "M_C_CPU1_SB_CB<7>")
	)
	(gr_poly
		(pts
			(xy 89.621106 -269.428214) (xy 89.52103 -269.328138) (xy 89.420954 -269.428214) (xy 89.420954 -269.472664)
			(xy 89.621106 -269.472664)
		)
		(stroke
			(width 0)
			(type solid)
		)
		(fill yes)
		(layer "In2.Cu")
		(net "M_C_CPU1_SB_CB<4>")
	)
	(gr_poly
		(pts
			(xy 89.621106 -267.801852) (xy 89.52103 -267.701776) (xy 89.420954 -267.801852) (xy 89.420954 -267.846302)
			(xy 89.621106 -267.846302)
		)
		(stroke
			(width 0)
			(type solid)
		)
		(fill yes)
		(layer "In2.Cu")
		(net "M_C_CPU1_SB_RSP<0>")
	)
	(gr_poly
		(pts
			(xy 89.621106 -265.78433) (xy 89.621106 -265.73988) (xy 89.420954 -265.73988) (xy 89.420954 -265.78433)
			(xy 89.52103 -265.884406)
		)
		(stroke
			(width 0)
			(type solid)
		)
		(fill yes)
		(layer "In2.Cu")
		(net "M_C_CPU1_SB_CS_N<0>")
	)
	(gr_poly
		(pts
			(xy 89.621106 -264.568178) (xy 89.52103 -264.468102) (xy 89.420954 -264.568178) (xy 89.420954 -264.612628)
			(xy 89.621106 -264.612628)
		)
		(stroke
			(width 0)
			(type solid)
		)
		(fill yes)
		(layer "In2.Cu")
		(net "M_C_CPU1_SB_CA<6>")
	)
	(gr_poly
		(pts
			(xy 89.621106 -264.164318) (xy 89.621106 -264.119868) (xy 89.420954 -264.119868) (xy 89.420954 -264.164318)
			(xy 89.52103 -264.264394)
		)
		(stroke
			(width 0)
			(type solid)
		)
		(fill yes)
		(layer "In2.Cu")
		(net "M_C_CPU1_SB_CA<5>")
	)
	(gr_poly
		(pts
			(xy 89.621106 -262.948166) (xy 89.52103 -262.84809) (xy 89.420954 -262.948166) (xy 89.420954 -262.992616)
			(xy 89.621106 -262.992616)
		)
		(stroke
			(width 0)
			(type solid)
		)
		(fill yes)
		(layer "In2.Cu")
		(net "M_C_CPU1_SB_CA<2>")
	)
	(gr_poly
		(pts
			(xy 89.621106 -262.544306) (xy 89.621106 -262.499856) (xy 89.420954 -262.499856) (xy 89.420954 -262.544306)
			(xy 89.52103 -262.644382)
		)
		(stroke
			(width 0)
			(type solid)
		)
		(fill yes)
		(layer "In2.Cu")
		(net "M_C_CPU1_SB_CA<1>")
	)
	(gr_poly
		(pts
			(xy 89.791032 -256.026158) (xy 89.690956 -255.926336) (xy 89.59088 -256.026158) (xy 89.59088 -256.07391)
			(xy 89.791032 -256.07391)
		)
		(stroke
			(width 0)
			(type solid)
		)
		(fill yes)
		(layer "In2.Cu")
		(net "M_C_CPU1_CLK_DP<0>")
	)
	(gr_poly
		(pts
			(xy 89.791032 -255.622552) (xy 89.791032 -255.578102) (xy 89.59088 -255.578102) (xy 89.59088 -255.622552)
			(xy 89.690956 -255.722628)
		)
		(stroke
			(width 0)
			(type solid)
		)
		(fill yes)
		(layer "In2.Cu")
		(net "M_C_CPU1_SA_PAR")
	)
	(gr_poly
		(pts
			(xy 89.791032 -254.4064) (xy 89.690956 -254.306324) (xy 89.59088 -254.4064) (xy 89.59088 -254.45085)
			(xy 89.791032 -254.45085)
		)
		(stroke
			(width 0)
			(type solid)
		)
		(fill yes)
		(layer "In2.Cu")
		(net "M_C_CPU1_SA_CA<4>")
	)
	(gr_poly
		(pts
			(xy 89.791032 -254.00254) (xy 89.791032 -253.95809) (xy 89.59088 -253.95809) (xy 89.59088 -254.00254)
			(xy 89.690956 -254.102616)
		)
		(stroke
			(width 0)
			(type solid)
		)
		(fill yes)
		(layer "In2.Cu")
		(net "M_C_CPU1_SA_CA<3>")
	)
	(gr_poly
		(pts
			(xy 89.791032 -252.786388) (xy 89.690956 -252.686312) (xy 89.59088 -252.786388) (xy 89.59088 -252.830838)
			(xy 89.791032 -252.830838)
		)
		(stroke
			(width 0)
			(type solid)
		)
		(fill yes)
		(layer "In2.Cu")
		(net "M_C_CPU1_SA_CA<0>")
	)
	(gr_poly
		(pts
			(xy 89.791032 -252.382528) (xy 89.791032 -252.338078) (xy 89.59088 -252.338078) (xy 89.59088 -252.382528)
			(xy 89.690956 -252.482604)
		)
		(stroke
			(width 0)
			(type solid)
		)
		(fill yes)
		(layer "In2.Cu")
		(net "M_C_CPU1_SA_CS_N<1>")
	)
	(gr_poly
		(pts
			(xy 89.791032 -250.762516) (xy 89.791032 -250.718066) (xy 89.59088 -250.718066) (xy 89.59088 -250.762516)
			(xy 89.690956 -250.862592)
		)
		(stroke
			(width 0)
			(type solid)
		)
		(fill yes)
		(layer "In2.Cu")
		(net "M_C_CPU1_RESET_N")
	)
	(gr_poly
		(pts
			(xy 89.791032 -249.142504) (xy 89.791032 -249.098054) (xy 89.59088 -249.098054) (xy 89.59088 -249.142504)
			(xy 89.690956 -249.24258)
		)
		(stroke
			(width 0)
			(type solid)
		)
		(fill yes)
		(layer "In2.Cu")
		(net "M_C_CPU1_SA_CB<7>")
	)
	(gr_poly
		(pts
			(xy 89.791032 -247.926352) (xy 89.690956 -247.826276) (xy 89.59088 -247.926352) (xy 89.59088 -247.970802)
			(xy 89.791032 -247.970802)
		)
		(stroke
			(width 0)
			(type solid)
		)
		(fill yes)
		(layer "In2.Cu")
		(net "M_C_CPU1_SA_CB<4>")
	)
	(gr_poly
		(pts
			(xy 89.791032 -247.522746) (xy 89.791032 -247.474994) (xy 89.59088 -247.474994) (xy 89.59088 -247.522746)
			(xy 89.690956 -247.622568)
		)
		(stroke
			(width 0)
			(type solid)
		)
		(fill yes)
		(layer "In2.Cu")
		(net "M_C_CPU1_SA_DQS_DP<9>")
	)
	(gr_poly
		(pts
			(xy 89.791032 -245.90248) (xy 89.791032 -245.85803) (xy 89.59088 -245.85803) (xy 89.59088 -245.90248)
			(xy 89.690956 -246.002556)
		)
		(stroke
			(width 0)
			(type solid)
		)
		(fill yes)
		(layer "In2.Cu")
		(net "M_C_CPU1_SA_CB<3>")
	)
	(gr_poly
		(pts
			(xy 89.791032 -244.686328) (xy 89.690956 -244.586252) (xy 89.59088 -244.686328) (xy 89.59088 -244.730778)
			(xy 89.791032 -244.730778)
		)
		(stroke
			(width 0)
			(type solid)
		)
		(fill yes)
		(layer "In2.Cu")
		(net "M_C_CPU1_SA_CB<0>")
	)
	(gr_poly
		(pts
			(xy 89.791032 -244.282468) (xy 89.791032 -244.238018) (xy 89.59088 -244.238018) (xy 89.59088 -244.282468)
			(xy 89.690956 -244.382544)
		)
		(stroke
			(width 0)
			(type solid)
		)
		(fill yes)
		(layer "In2.Cu")
		(net "M_C_CPU1_SA_DQ<31>")
	)
	(gr_poly
		(pts
			(xy 89.791032 -243.066316) (xy 89.690956 -242.96624) (xy 89.59088 -243.066316) (xy 89.59088 -243.110766)
			(xy 89.791032 -243.110766)
		)
		(stroke
			(width 0)
			(type solid)
		)
		(fill yes)
		(layer "In2.Cu")
		(net "M_C_CPU1_SA_DQ<28>")
	)
	(gr_poly
		(pts
			(xy 89.791032 -242.66271) (xy 89.791032 -242.614958) (xy 89.59088 -242.614958) (xy 89.59088 -242.66271)
			(xy 89.690956 -242.762532)
		)
		(stroke
			(width 0)
			(type solid)
		)
		(fill yes)
		(layer "In2.Cu")
		(net "M_C_CPU1_SA_DQS_DP<8>")
	)
	(gr_poly
		(pts
			(xy 89.791032 -241.44605) (xy 89.690956 -241.346228) (xy 89.59088 -241.44605) (xy 89.59088 -241.493802)
			(xy 89.791032 -241.493802)
		)
		(stroke
			(width 0)
			(type solid)
		)
		(fill yes)
		(layer "In2.Cu")
		(net "M_C_CPU1_SA_DQS_DP<3>")
	)
	(gr_poly
		(pts
			(xy 89.791032 -241.042444) (xy 89.791032 -240.997994) (xy 89.59088 -240.997994) (xy 89.59088 -241.042444)
			(xy 89.690956 -241.14252)
		)
		(stroke
			(width 0)
			(type solid)
		)
		(fill yes)
		(layer "In2.Cu")
		(net "M_C_CPU1_SA_DQ<27>")
	)
	(gr_poly
		(pts
			(xy 89.791032 -239.826292) (xy 89.690956 -239.726216) (xy 89.59088 -239.826292) (xy 89.59088 -239.870742)
			(xy 89.791032 -239.870742)
		)
		(stroke
			(width 0)
			(type solid)
		)
		(fill yes)
		(layer "In2.Cu")
		(net "M_C_CPU1_SA_DQ<24>")
	)
	(gr_poly
		(pts
			(xy 89.791032 -239.422432) (xy 89.791032 -239.377982) (xy 89.59088 -239.377982) (xy 89.59088 -239.422432)
			(xy 89.690956 -239.522508)
		)
		(stroke
			(width 0)
			(type solid)
		)
		(fill yes)
		(layer "In2.Cu")
		(net "M_C_CPU1_SA_DQ<23>")
	)
	(gr_poly
		(pts
			(xy 89.791032 -238.20628) (xy 89.690956 -238.106204) (xy 89.59088 -238.20628) (xy 89.59088 -238.25073)
			(xy 89.791032 -238.25073)
		)
		(stroke
			(width 0)
			(type solid)
		)
		(fill yes)
		(layer "In2.Cu")
		(net "M_C_CPU1_SA_DQ<20>")
	)
	(gr_poly
		(pts
			(xy 89.791032 -237.802674) (xy 89.791032 -237.754922) (xy 89.59088 -237.754922) (xy 89.59088 -237.802674)
			(xy 89.690956 -237.902496)
		)
		(stroke
			(width 0)
			(type solid)
		)
		(fill yes)
		(layer "In2.Cu")
		(net "M_C_CPU1_SA_DQS_DP<7>")
	)
	(gr_poly
		(pts
			(xy 89.791032 -236.586014) (xy 89.690956 -236.486192) (xy 89.59088 -236.586014) (xy 89.59088 -236.633766)
			(xy 89.791032 -236.633766)
		)
		(stroke
			(width 0)
			(type solid)
		)
		(fill yes)
		(layer "In2.Cu")
		(net "M_C_CPU1_SA_DQS_DP<2>")
	)
	(gr_poly
		(pts
			(xy 89.791032 -236.182408) (xy 89.791032 -236.137958) (xy 89.59088 -236.137958) (xy 89.59088 -236.182408)
			(xy 89.690956 -236.282484)
		)
		(stroke
			(width 0)
			(type solid)
		)
		(fill yes)
		(layer "In2.Cu")
		(net "M_C_CPU1_SA_DQ<19>")
	)
	(gr_poly
		(pts
			(xy 89.791032 -234.966256) (xy 89.690956 -234.86618) (xy 89.59088 -234.966256) (xy 89.59088 -235.010706)
			(xy 89.791032 -235.010706)
		)
		(stroke
			(width 0)
			(type solid)
		)
		(fill yes)
		(layer "In2.Cu")
		(net "M_C_CPU1_SA_DQ<16>")
	)
	(gr_poly
		(pts
			(xy 89.791032 -234.562396) (xy 89.791032 -234.517946) (xy 89.59088 -234.517946) (xy 89.59088 -234.562396)
			(xy 89.690956 -234.662472)
		)
		(stroke
			(width 0)
			(type solid)
		)
		(fill yes)
		(layer "In2.Cu")
		(net "M_C_CPU1_SA_DQ<15>")
	)
	(gr_poly
		(pts
			(xy 89.791032 -233.346244) (xy 89.690956 -233.246168) (xy 89.59088 -233.346244) (xy 89.59088 -233.390694)
			(xy 89.791032 -233.390694)
		)
		(stroke
			(width 0)
			(type solid)
		)
		(fill yes)
		(layer "In2.Cu")
		(net "M_C_CPU1_SA_DQ<12>")
	)
	(gr_poly
		(pts
			(xy 89.791032 -232.942638) (xy 89.791032 -232.894886) (xy 89.59088 -232.894886) (xy 89.59088 -232.942638)
			(xy 89.690956 -233.04246)
		)
		(stroke
			(width 0)
			(type solid)
		)
		(fill yes)
		(layer "In2.Cu")
		(net "M_C_CPU1_SA_DQS_DP<6>")
	)
	(gr_poly
		(pts
			(xy 89.791032 -231.725978) (xy 89.690956 -231.626156) (xy 89.59088 -231.725978) (xy 89.59088 -231.77373)
			(xy 89.791032 -231.77373)
		)
		(stroke
			(width 0)
			(type solid)
		)
		(fill yes)
		(layer "In2.Cu")
		(net "M_C_CPU1_SA_DQS_DP<1>")
	)
	(gr_poly
		(pts
			(xy 89.791032 -231.322626) (xy 89.791032 -231.278176) (xy 89.59088 -231.278176) (xy 89.59088 -231.322626)
			(xy 89.690956 -231.422702)
		)
		(stroke
			(width 0)
			(type solid)
		)
		(fill yes)
		(layer "In2.Cu")
		(net "M_C_CPU1_SA_DQ<11>")
	)
	(gr_poly
		(pts
			(xy 89.791032 -230.10622) (xy 89.690956 -230.006144) (xy 89.59088 -230.10622) (xy 89.59088 -230.15067)
			(xy 89.791032 -230.15067)
		)
		(stroke
			(width 0)
			(type solid)
		)
		(fill yes)
		(layer "In2.Cu")
		(net "M_C_CPU1_SA_DQ<8>")
	)
	(gr_poly
		(pts
			(xy 89.791032 -229.702614) (xy 89.791032 -229.658164) (xy 89.59088 -229.658164) (xy 89.59088 -229.702614)
			(xy 89.690956 -229.80269)
		)
		(stroke
			(width 0)
			(type solid)
		)
		(fill yes)
		(layer "In2.Cu")
		(net "M_C_CPU1_SA_DQ<7>")
	)
	(gr_poly
		(pts
			(xy 89.791032 -228.486462) (xy 89.690956 -228.386386) (xy 89.59088 -228.486462) (xy 89.59088 -228.530912)
			(xy 89.791032 -228.530912)
		)
		(stroke
			(width 0)
			(type solid)
		)
		(fill yes)
		(layer "In2.Cu")
		(net "M_C_CPU1_SA_DQ<4>")
	)
	(gr_poly
		(pts
			(xy 89.791032 -228.082856) (xy 89.791032 -228.035104) (xy 89.59088 -228.035104) (xy 89.59088 -228.082856)
			(xy 89.690956 -228.182678)
		)
		(stroke
			(width 0)
			(type solid)
		)
		(fill yes)
		(layer "In2.Cu")
		(net "M_C_CPU1_SA_DQS_DP<5>")
	)
	(gr_poly
		(pts
			(xy 89.791032 -226.866196) (xy 89.690956 -226.766374) (xy 89.59088 -226.866196) (xy 89.59088 -226.913948)
			(xy 89.791032 -226.913948)
		)
		(stroke
			(width 0)
			(type solid)
		)
		(fill yes)
		(layer "In2.Cu")
		(net "M_C_CPU1_SA_DQS_DP<0>")
	)
	(gr_poly
		(pts
			(xy 89.791032 -226.46259) (xy 89.791032 -226.41814) (xy 89.59088 -226.41814) (xy 89.59088 -226.46259)
			(xy 89.690956 -226.562666)
		)
		(stroke
			(width 0)
			(type solid)
		)
		(fill yes)
		(layer "In2.Cu")
		(net "M_C_CPU1_SA_DQ<3>")
	)
	(gr_poly
		(pts
			(xy 89.791032 -225.246438) (xy 89.690956 -225.146362) (xy 89.59088 -225.246438) (xy 89.59088 -225.290888)
			(xy 89.791032 -225.290888)
		)
		(stroke
			(width 0)
			(type solid)
		)
		(fill yes)
		(layer "In2.Cu")
		(net "M_C_CPU1_SA_DQ<0>")
	)
	(gr_poly
		(pts
			(xy 89.791286 -246.306086) (xy 89.69121 -246.206264) (xy 89.591134 -246.306086) (xy 89.591134 -246.353838)
			(xy 89.791286 -246.353838)
		)
		(stroke
			(width 0)
			(type solid)
		)
		(fill yes)
		(layer "In2.Cu")
		(net "M_C_CPU1_SA_DQS_DP<4>")
	)
	(gr_poly
		(pts
			(xy 90.091006 -292.918134) (xy 89.99093 -292.818058) (xy 89.890854 -292.918134) (xy 89.890854 -292.962584)
			(xy 90.091006 -292.962584)
		)
		(stroke
			(width 0)
			(type solid)
		)
		(fill yes)
		(layer "In2.Cu")
		(net "M_C_CPU1_SB_DQ<29>")
	)
	(gr_poly
		(pts
			(xy 90.091006 -292.514274) (xy 90.091006 -292.469824) (xy 89.890854 -292.469824) (xy 89.890854 -292.514274)
			(xy 89.99093 -292.61435)
		)
		(stroke
			(width 0)
			(type solid)
		)
		(fill yes)
		(layer "In2.Cu")
		(net "M_C_CPU1_SB_DQ<30>")
	)
	(gr_poly
		(pts
			(xy 90.091006 -290.894516) (xy 90.091006 -290.846764) (xy 89.890854 -290.846764) (xy 89.890854 -290.894516)
			(xy 89.99093 -290.994338)
		)
		(stroke
			(width 0)
			(type solid)
		)
		(fill yes)
		(layer "In2.Cu")
		(net "M_C_CPU1_SB_DQS_DN<3>")
	)
	(gr_poly
		(pts
			(xy 90.091006 -289.67811) (xy 89.99093 -289.578034) (xy 89.890854 -289.67811) (xy 89.890854 -289.72256)
			(xy 90.091006 -289.72256)
		)
		(stroke
			(width 0)
			(type solid)
		)
		(fill yes)
		(layer "In2.Cu")
		(net "M_C_CPU1_SB_DQ<25>")
	)
	(gr_poly
		(pts
			(xy 90.091006 -289.27425) (xy 90.091006 -289.2298) (xy 89.890854 -289.2298) (xy 89.890854 -289.27425)
			(xy 89.99093 -289.374326)
		)
		(stroke
			(width 0)
			(type solid)
		)
		(fill yes)
		(layer "In2.Cu")
		(net "M_C_CPU1_SB_DQ<26>")
	)
	(gr_poly
		(pts
			(xy 90.091006 -288.058098) (xy 89.99093 -287.958022) (xy 89.890854 -288.058098) (xy 89.890854 -288.102548)
			(xy 90.091006 -288.102548)
		)
		(stroke
			(width 0)
			(type solid)
		)
		(fill yes)
		(layer "In2.Cu")
		(net "M_C_CPU1_SB_DQ<21>")
	)
	(gr_poly
		(pts
			(xy 90.091006 -287.654492) (xy 90.091006 -287.610042) (xy 89.890854 -287.610042) (xy 89.890854 -287.654492)
			(xy 89.99093 -287.754568)
		)
		(stroke
			(width 0)
			(type solid)
		)
		(fill yes)
		(layer "In2.Cu")
		(net "M_C_CPU1_SB_DQ<22>")
	)
	(gr_poly
		(pts
			(xy 90.091006 -286.438086) (xy 89.99093 -286.33801) (xy 89.890854 -286.438086) (xy 89.890854 -286.485838)
			(xy 90.091006 -286.485838)
		)
		(stroke
			(width 0)
			(type solid)
		)
		(fill yes)
		(layer "In2.Cu")
		(net "M_C_CPU1_SB_DQS_DN<7>")
	)
	(gr_poly
		(pts
			(xy 90.091006 -286.034734) (xy 90.091006 -285.986982) (xy 89.890854 -285.986982) (xy 89.890854 -286.034734)
			(xy 89.99093 -286.134556)
		)
		(stroke
			(width 0)
			(type solid)
		)
		(fill yes)
		(layer "In2.Cu")
		(net "M_C_CPU1_SB_DQS_DN<2>")
	)
	(gr_poly
		(pts
			(xy 90.091006 -284.818328) (xy 89.99093 -284.718252) (xy 89.890854 -284.818328) (xy 89.890854 -284.862778)
			(xy 90.091006 -284.862778)
		)
		(stroke
			(width 0)
			(type solid)
		)
		(fill yes)
		(layer "In2.Cu")
		(net "M_C_CPU1_SB_DQ<17>")
	)
	(gr_poly
		(pts
			(xy 90.091006 -284.414468) (xy 90.091006 -284.370018) (xy 89.890854 -284.370018) (xy 89.890854 -284.414468)
			(xy 89.99093 -284.514544)
		)
		(stroke
			(width 0)
			(type solid)
		)
		(fill yes)
		(layer "In2.Cu")
		(net "M_C_CPU1_SB_DQ<18>")
	)
	(gr_poly
		(pts
			(xy 90.091006 -283.198316) (xy 89.99093 -283.09824) (xy 89.890854 -283.198316) (xy 89.890854 -283.242766)
			(xy 90.091006 -283.242766)
		)
		(stroke
			(width 0)
			(type solid)
		)
		(fill yes)
		(layer "In2.Cu")
		(net "M_C_CPU1_SB_DQ<13>")
	)
	(gr_poly
		(pts
			(xy 90.091006 -282.794456) (xy 90.091006 -282.750006) (xy 89.890854 -282.750006) (xy 89.890854 -282.794456)
			(xy 89.99093 -282.894532)
		)
		(stroke
			(width 0)
			(type solid)
		)
		(fill yes)
		(layer "In2.Cu")
		(net "M_C_CPU1_SB_DQ<14>")
	)
	(gr_poly
		(pts
			(xy 90.091006 -281.57805) (xy 89.99093 -281.478228) (xy 89.890854 -281.57805) (xy 89.890854 -281.625802)
			(xy 90.091006 -281.625802)
		)
		(stroke
			(width 0)
			(type solid)
		)
		(fill yes)
		(layer "In2.Cu")
		(net "M_C_CPU1_SB_DQS_DN<6>")
	)
	(gr_poly
		(pts
			(xy 90.091006 -281.174698) (xy 90.091006 -281.126946) (xy 89.890854 -281.126946) (xy 89.890854 -281.174698)
			(xy 89.99093 -281.27452)
		)
		(stroke
			(width 0)
			(type solid)
		)
		(fill yes)
		(layer "In2.Cu")
		(net "M_C_CPU1_SB_DQS_DN<1>")
	)
	(gr_poly
		(pts
			(xy 90.091006 -279.958292) (xy 89.99093 -279.858216) (xy 89.890854 -279.958292) (xy 89.890854 -280.002742)
			(xy 90.091006 -280.002742)
		)
		(stroke
			(width 0)
			(type solid)
		)
		(fill yes)
		(layer "In2.Cu")
		(net "M_C_CPU1_SB_DQ<9>")
	)
	(gr_poly
		(pts
			(xy 90.091006 -279.554432) (xy 90.091006 -279.509982) (xy 89.890854 -279.509982) (xy 89.890854 -279.554432)
			(xy 89.99093 -279.654508)
		)
		(stroke
			(width 0)
			(type solid)
		)
		(fill yes)
		(layer "In2.Cu")
		(net "M_C_CPU1_SB_DQ<10>")
	)
	(gr_poly
		(pts
			(xy 90.091006 -278.33828) (xy 89.99093 -278.238204) (xy 89.890854 -278.33828) (xy 89.890854 -278.38273)
			(xy 90.091006 -278.38273)
		)
		(stroke
			(width 0)
			(type solid)
		)
		(fill yes)
		(layer "In2.Cu")
		(net "M_C_CPU1_SB_DQ<5>")
	)
	(gr_poly
		(pts
			(xy 90.091006 -277.93442) (xy 90.091006 -277.88997) (xy 89.890854 -277.88997) (xy 89.890854 -277.93442)
			(xy 89.99093 -278.034496)
		)
		(stroke
			(width 0)
			(type solid)
		)
		(fill yes)
		(layer "In2.Cu")
		(net "M_C_CPU1_SB_DQ<6>")
	)
	(gr_poly
		(pts
			(xy 90.091006 -276.718014) (xy 89.99093 -276.618192) (xy 89.890854 -276.718014) (xy 89.890854 -276.765766)
			(xy 90.091006 -276.765766)
		)
		(stroke
			(width 0)
			(type solid)
		)
		(fill yes)
		(layer "In2.Cu")
		(net "M_C_CPU1_SB_DQS_DN<5>")
	)
	(gr_poly
		(pts
			(xy 90.091006 -276.314662) (xy 90.091006 -276.26691) (xy 89.890854 -276.26691) (xy 89.890854 -276.314662)
			(xy 89.99093 -276.414484)
		)
		(stroke
			(width 0)
			(type solid)
		)
		(fill yes)
		(layer "In2.Cu")
		(net "M_C_CPU1_SB_DQS_DN<0>")
	)
	(gr_poly
		(pts
			(xy 90.091006 -275.098256) (xy 89.99093 -274.99818) (xy 89.890854 -275.098256) (xy 89.890854 -275.142706)
			(xy 90.091006 -275.142706)
		)
		(stroke
			(width 0)
			(type solid)
		)
		(fill yes)
		(layer "In2.Cu")
		(net "M_C_CPU1_SB_DQ<1>")
	)
	(gr_poly
		(pts
			(xy 90.091006 -274.694396) (xy 90.091006 -274.649946) (xy 89.890854 -274.649946) (xy 89.890854 -274.694396)
			(xy 89.99093 -274.794472)
		)
		(stroke
			(width 0)
			(type solid)
		)
		(fill yes)
		(layer "In2.Cu")
		(net "M_C_CPU1_SB_DQ<2>")
	)
	(gr_poly
		(pts
			(xy 90.091006 -273.478244) (xy 89.99093 -273.378168) (xy 89.890854 -273.478244) (xy 89.890854 -273.522694)
			(xy 90.091006 -273.522694)
		)
		(stroke
			(width 0)
			(type solid)
		)
		(fill yes)
		(layer "In2.Cu")
		(net "M_C_CPU1_SB_CB<1>")
	)
	(gr_poly
		(pts
			(xy 90.091006 -273.074384) (xy 90.091006 -273.029934) (xy 89.890854 -273.029934) (xy 89.890854 -273.074384)
			(xy 89.99093 -273.17446)
		)
		(stroke
			(width 0)
			(type solid)
		)
		(fill yes)
		(layer "In2.Cu")
		(net "M_C_CPU1_SB_CB<2>")
	)
	(gr_poly
		(pts
			(xy 90.091006 -271.857978) (xy 89.99093 -271.758156) (xy 89.890854 -271.857978) (xy 89.890854 -271.90573)
			(xy 90.091006 -271.90573)
		)
		(stroke
			(width 0)
			(type solid)
		)
		(fill yes)
		(layer "In2.Cu")
		(net "M_C_CPU1_SB_DQS_DN<4>")
	)
	(gr_poly
		(pts
			(xy 90.091006 -271.454626) (xy 90.091006 -271.406874) (xy 89.890854 -271.406874) (xy 89.890854 -271.454626)
			(xy 89.99093 -271.554448)
		)
		(stroke
			(width 0)
			(type solid)
		)
		(fill yes)
		(layer "In2.Cu")
		(net "M_C_CPU1_SB_DQS_DN<9>")
	)
	(gr_poly
		(pts
			(xy 90.091006 -270.23822) (xy 89.99093 -270.138144) (xy 89.890854 -270.23822) (xy 89.890854 -270.28267)
			(xy 90.091006 -270.28267)
		)
		(stroke
			(width 0)
			(type solid)
		)
		(fill yes)
		(layer "In2.Cu")
		(net "M_C_CPU1_SB_CB<5>")
	)
	(gr_poly
		(pts
			(xy 90.091006 -269.83436) (xy 90.091006 -269.78991) (xy 89.890854 -269.78991) (xy 89.890854 -269.83436)
			(xy 89.99093 -269.934436)
		)
		(stroke
			(width 0)
			(type solid)
		)
		(fill yes)
		(layer "In2.Cu")
		(net "M_C_CPU1_SB_CB<6>")
	)
	(gr_poly
		(pts
			(xy 90.091006 -266.594336) (xy 90.091006 -266.549886) (xy 89.890854 -266.549886) (xy 89.890854 -266.594336)
			(xy 89.99093 -266.694412)
		)
		(stroke
			(width 0)
			(type solid)
		)
		(fill yes)
		(layer "In2.Cu")
		(net "M_C_CPU1_SB_CS_N<1>")
	)
	(gr_poly
		(pts
			(xy 90.091006 -264.974324) (xy 90.091006 -264.929874) (xy 89.890854 -264.929874) (xy 89.890854 -264.974324)
			(xy 89.99093 -265.0744)
		)
		(stroke
			(width 0)
			(type solid)
		)
		(fill yes)
		(layer "In2.Cu")
		(net "M_C_CPU1_SB_PAR")
	)
	(gr_poly
		(pts
			(xy 90.091006 -263.758172) (xy 89.99093 -263.658096) (xy 89.890854 -263.758172) (xy 89.890854 -263.802622)
			(xy 90.091006 -263.802622)
		)
		(stroke
			(width 0)
			(type solid)
		)
		(fill yes)
		(layer "In2.Cu")
		(net "M_C_CPU1_SB_CA<4>")
	)
	(gr_poly
		(pts
			(xy 90.091006 -263.354312) (xy 90.091006 -263.309862) (xy 89.890854 -263.309862) (xy 89.890854 -263.354312)
			(xy 89.99093 -263.454388)
		)
		(stroke
			(width 0)
			(type solid)
		)
		(fill yes)
		(layer "In2.Cu")
		(net "M_C_CPU1_SB_CA<3>")
	)
	(gr_poly
		(pts
			(xy 90.091006 -262.13816) (xy 89.99093 -262.038084) (xy 89.890854 -262.13816) (xy 89.890854 -262.18261)
			(xy 90.091006 -262.18261)
		)
		(stroke
			(width 0)
			(type solid)
		)
		(fill yes)
		(layer "In2.Cu")
		(net "M_C_CPU1_SB_CA<0>")
	)
	(gr_poly
		(pts
			(xy 90.097102 -266.991846) (xy 89.99728 -266.89177) (xy 89.897204 -266.991846) (xy 89.897204 -267.036296)
			(xy 90.097102 -267.036296)
		)
		(stroke
			(width 0)
			(type solid)
		)
		(fill yes)
		(layer "In2.Cu")
		(net "M_C_CPU1_SA_RSP<0>")
	)
	(gr_poly
		(pts
			(xy 90.098118 -291.297868) (xy 89.998296 -291.198046) (xy 89.89822 -291.297868) (xy 89.89822 -291.34562)
			(xy 90.098118 -291.34562)
		)
		(stroke
			(width 0)
			(type solid)
		)
		(fill yes)
		(layer "In2.Cu")
		(net "M_C_CPU1_SB_DQS_DN<8>")
	)
	(gr_poly
		(pts
			(xy 90.260932 -246.712486) (xy 90.260932 -246.664988) (xy 90.061034 -246.664988) (xy 90.061034 -246.712486)
			(xy 90.160856 -246.812562)
		)
		(stroke
			(width 0)
			(type solid)
		)
		(fill yes)
		(layer "In2.Cu")
		(net "M_C_CPU1_SA_DQS_DN<4>")
	)
	(gr_poly
		(pts
			(xy 90.261186 -256.432812) (xy 90.261186 -256.38506) (xy 90.061034 -256.38506) (xy 90.061034 -256.432812)
			(xy 90.16111 -256.532634)
		)
		(stroke
			(width 0)
			(type solid)
		)
		(fill yes)
		(layer "In2.Cu")
		(net "M_C_CPU1_CLK_DN<0>")
	)
	(gr_poly
		(pts
			(xy 90.261186 -255.216406) (xy 90.16111 -255.11633) (xy 90.061034 -255.216406) (xy 90.061034 -255.260856)
			(xy 90.261186 -255.260856)
		)
		(stroke
			(width 0)
			(type solid)
		)
		(fill yes)
		(layer "In2.Cu")
		(net "M_C_CPU1_SA_CA<6>")
	)
	(gr_poly
		(pts
			(xy 90.261186 -254.812546) (xy 90.261186 -254.768096) (xy 90.061034 -254.768096) (xy 90.061034 -254.812546)
			(xy 90.16111 -254.912622)
		)
		(stroke
			(width 0)
			(type solid)
		)
		(fill yes)
		(layer "In2.Cu")
		(net "M_C_CPU1_SA_CA<5>")
	)
	(gr_poly
		(pts
			(xy 90.261186 -253.596394) (xy 90.16111 -253.496318) (xy 90.061034 -253.596394) (xy 90.061034 -253.640844)
			(xy 90.261186 -253.640844)
		)
		(stroke
			(width 0)
			(type solid)
		)
		(fill yes)
		(layer "In2.Cu")
		(net "M_C_CPU1_SA_CA<2>")
	)
	(gr_poly
		(pts
			(xy 90.261186 -253.192534) (xy 90.261186 -253.148084) (xy 90.061034 -253.148084) (xy 90.061034 -253.192534)
			(xy 90.16111 -253.29261)
		)
		(stroke
			(width 0)
			(type solid)
		)
		(fill yes)
		(layer "In2.Cu")
		(net "M_C_CPU1_SA_CA<1>")
	)
	(gr_poly
		(pts
			(xy 90.261186 -251.572522) (xy 90.261186 -251.528072) (xy 90.061034 -251.528072) (xy 90.061034 -251.572522)
			(xy 90.16111 -251.672598)
		)
		(stroke
			(width 0)
			(type solid)
		)
		(fill yes)
		(layer "In2.Cu")
		(net "M_C_CPU1_SA_CS_N<0>")
	)
	(gr_poly
		(pts
			(xy 90.261186 -250.35637) (xy 90.16111 -250.256294) (xy 90.061034 -250.35637) (xy 90.061034 -250.40082)
			(xy 90.261186 -250.40082)
		)
		(stroke
			(width 0)
			(type solid)
		)
		(fill yes)
		(layer "In2.Cu")
		(net "M_C_CPU1_ALERT_R_N")
	)
	(gr_poly
		(pts
			(xy 90.261186 -248.736358) (xy 90.16111 -248.636282) (xy 90.061034 -248.736358) (xy 90.061034 -248.780808)
			(xy 90.261186 -248.780808)
		)
		(stroke
			(width 0)
			(type solid)
		)
		(fill yes)
		(layer "In2.Cu")
		(net "M_C_CPU1_SA_CB<5>")
	)
	(gr_poly
		(pts
			(xy 90.261186 -248.332498) (xy 90.261186 -248.288048) (xy 90.061034 -248.288048) (xy 90.061034 -248.332498)
			(xy 90.16111 -248.432574)
		)
		(stroke
			(width 0)
			(type solid)
		)
		(fill yes)
		(layer "In2.Cu")
		(net "M_C_CPU1_SA_CB<6>")
	)
	(gr_poly
		(pts
			(xy 90.261186 -247.116092) (xy 90.16111 -247.01627) (xy 90.061034 -247.116092) (xy 90.061034 -247.163844)
			(xy 90.261186 -247.163844)
		)
		(stroke
			(width 0)
			(type solid)
		)
		(fill yes)
		(layer "In2.Cu")
		(net "M_C_CPU1_SA_DQS_DN<9>")
	)
	(gr_poly
		(pts
			(xy 90.261186 -245.496334) (xy 90.16111 -245.396258) (xy 90.061034 -245.496334) (xy 90.061034 -245.540784)
			(xy 90.261186 -245.540784)
		)
		(stroke
			(width 0)
			(type solid)
		)
		(fill yes)
		(layer "In2.Cu")
		(net "M_C_CPU1_SA_CB<1>")
	)
	(gr_poly
		(pts
			(xy 90.261186 -245.092474) (xy 90.261186 -245.048024) (xy 90.061034 -245.048024) (xy 90.061034 -245.092474)
			(xy 90.16111 -245.19255)
		)
		(stroke
			(width 0)
			(type solid)
		)
		(fill yes)
		(layer "In2.Cu")
		(net "M_C_CPU1_SA_CB<2>")
	)
	(gr_poly
		(pts
			(xy 90.261186 -243.876322) (xy 90.16111 -243.776246) (xy 90.061034 -243.876322) (xy 90.061034 -243.920772)
			(xy 90.261186 -243.920772)
		)
		(stroke
			(width 0)
			(type solid)
		)
		(fill yes)
		(layer "In2.Cu")
		(net "M_C_CPU1_SA_DQ<29>")
	)
	(gr_poly
		(pts
			(xy 90.261186 -243.472462) (xy 90.261186 -243.428012) (xy 90.061034 -243.428012) (xy 90.061034 -243.472462)
			(xy 90.16111 -243.572538)
		)
		(stroke
			(width 0)
			(type solid)
		)
		(fill yes)
		(layer "In2.Cu")
		(net "M_C_CPU1_SA_DQ<30>")
	)
	(gr_poly
		(pts
			(xy 90.261186 -242.256056) (xy 90.16111 -242.156234) (xy 90.061034 -242.256056) (xy 90.061034 -242.303808)
			(xy 90.261186 -242.303808)
		)
		(stroke
			(width 0)
			(type solid)
		)
		(fill yes)
		(layer "In2.Cu")
		(net "M_C_CPU1_SA_DQS_DN<8>")
	)
	(gr_poly
		(pts
			(xy 90.261186 -241.852704) (xy 90.261186 -241.804952) (xy 90.061034 -241.804952) (xy 90.061034 -241.852704)
			(xy 90.16111 -241.952526)
		)
		(stroke
			(width 0)
			(type solid)
		)
		(fill yes)
		(layer "In2.Cu")
		(net "M_C_CPU1_SA_DQS_DN<3>")
	)
	(gr_poly
		(pts
			(xy 90.261186 -240.636298) (xy 90.16111 -240.536222) (xy 90.061034 -240.636298) (xy 90.061034 -240.680748)
			(xy 90.261186 -240.680748)
		)
		(stroke
			(width 0)
			(type solid)
		)
		(fill yes)
		(layer "In2.Cu")
		(net "M_C_CPU1_SA_DQ<25>")
	)
	(gr_poly
		(pts
			(xy 90.261186 -240.232438) (xy 90.261186 -240.187988) (xy 90.061034 -240.187988) (xy 90.061034 -240.232438)
			(xy 90.16111 -240.332514)
		)
		(stroke
			(width 0)
			(type solid)
		)
		(fill yes)
		(layer "In2.Cu")
		(net "M_C_CPU1_SA_DQ<26>")
	)
	(gr_poly
		(pts
			(xy 90.261186 -239.016286) (xy 90.16111 -238.91621) (xy 90.061034 -239.016286) (xy 90.061034 -239.060736)
			(xy 90.261186 -239.060736)
		)
		(stroke
			(width 0)
			(type solid)
		)
		(fill yes)
		(layer "In2.Cu")
		(net "M_C_CPU1_SA_DQ<21>")
	)
	(gr_poly
		(pts
			(xy 90.261186 -238.612426) (xy 90.261186 -238.567976) (xy 90.061034 -238.567976) (xy 90.061034 -238.612426)
			(xy 90.16111 -238.712502)
		)
		(stroke
			(width 0)
			(type solid)
		)
		(fill yes)
		(layer "In2.Cu")
		(net "M_C_CPU1_SA_DQ<22>")
	)
	(gr_poly
		(pts
			(xy 90.261186 -237.39602) (xy 90.16111 -237.296198) (xy 90.061034 -237.39602) (xy 90.061034 -237.443772)
			(xy 90.261186 -237.443772)
		)
		(stroke
			(width 0)
			(type solid)
		)
		(fill yes)
		(layer "In2.Cu")
		(net "M_C_CPU1_SA_DQS_DN<7>")
	)
	(gr_poly
		(pts
			(xy 90.261186 -236.992668) (xy 90.261186 -236.944916) (xy 90.061034 -236.944916) (xy 90.061034 -236.992668)
			(xy 90.16111 -237.09249)
		)
		(stroke
			(width 0)
			(type solid)
		)
		(fill yes)
		(layer "In2.Cu")
		(net "M_C_CPU1_SA_DQS_DN<2>")
	)
	(gr_poly
		(pts
			(xy 90.261186 -235.776262) (xy 90.16111 -235.676186) (xy 90.061034 -235.776262) (xy 90.061034 -235.820712)
			(xy 90.261186 -235.820712)
		)
		(stroke
			(width 0)
			(type solid)
		)
		(fill yes)
		(layer "In2.Cu")
		(net "M_C_CPU1_SA_DQ<17>")
	)
	(gr_poly
		(pts
			(xy 90.261186 -235.372402) (xy 90.261186 -235.327952) (xy 90.061034 -235.327952) (xy 90.061034 -235.372402)
			(xy 90.16111 -235.472478)
		)
		(stroke
			(width 0)
			(type solid)
		)
		(fill yes)
		(layer "In2.Cu")
		(net "M_C_CPU1_SA_DQ<18>")
	)
	(gr_poly
		(pts
			(xy 90.261186 -234.15625) (xy 90.16111 -234.056174) (xy 90.061034 -234.15625) (xy 90.061034 -234.2007)
			(xy 90.261186 -234.2007)
		)
		(stroke
			(width 0)
			(type solid)
		)
		(fill yes)
		(layer "In2.Cu")
		(net "M_C_CPU1_SA_DQ<13>")
	)
	(gr_poly
		(pts
			(xy 90.261186 -233.75239) (xy 90.261186 -233.70794) (xy 90.061034 -233.70794) (xy 90.061034 -233.75239)
			(xy 90.16111 -233.852466)
		)
		(stroke
			(width 0)
			(type solid)
		)
		(fill yes)
		(layer "In2.Cu")
		(net "M_C_CPU1_SA_DQ<14>")
	)
	(gr_poly
		(pts
			(xy 90.261186 -232.535984) (xy 90.16111 -232.436162) (xy 90.061034 -232.535984) (xy 90.061034 -232.583736)
			(xy 90.261186 -232.583736)
		)
		(stroke
			(width 0)
			(type solid)
		)
		(fill yes)
		(layer "In2.Cu")
		(net "M_C_CPU1_SA_DQS_DN<6>")
	)
	(gr_poly
		(pts
			(xy 90.261186 -232.132632) (xy 90.261186 -232.08488) (xy 90.061034 -232.08488) (xy 90.061034 -232.132632)
			(xy 90.16111 -232.232454)
		)
		(stroke
			(width 0)
			(type solid)
		)
		(fill yes)
		(layer "In2.Cu")
		(net "M_C_CPU1_SA_DQS_DN<1>")
	)
	(gr_poly
		(pts
			(xy 90.261186 -230.916226) (xy 90.16111 -230.81615) (xy 90.061034 -230.916226) (xy 90.061034 -230.960676)
			(xy 90.261186 -230.960676)
		)
		(stroke
			(width 0)
			(type solid)
		)
		(fill yes)
		(layer "In2.Cu")
		(net "M_C_CPU1_SA_DQ<9>")
	)
	(gr_poly
		(pts
			(xy 90.261186 -230.51262) (xy 90.261186 -230.46817) (xy 90.061034 -230.46817) (xy 90.061034 -230.51262)
			(xy 90.16111 -230.612696)
		)
		(stroke
			(width 0)
			(type solid)
		)
		(fill yes)
		(layer "In2.Cu")
		(net "M_C_CPU1_SA_DQ<10>")
	)
	(gr_poly
		(pts
			(xy 90.261186 -229.296214) (xy 90.16111 -229.196138) (xy 90.061034 -229.296214) (xy 90.061034 -229.340664)
			(xy 90.261186 -229.340664)
		)
		(stroke
			(width 0)
			(type solid)
		)
		(fill yes)
		(layer "In2.Cu")
		(net "M_C_CPU1_SA_DQ<5>")
	)
	(gr_poly
		(pts
			(xy 90.261186 -228.892608) (xy 90.261186 -228.848158) (xy 90.061034 -228.848158) (xy 90.061034 -228.892608)
			(xy 90.16111 -228.992684)
		)
		(stroke
			(width 0)
			(type solid)
		)
		(fill yes)
		(layer "In2.Cu")
		(net "M_C_CPU1_SA_DQ<6>")
	)
	(gr_poly
		(pts
			(xy 90.261186 -227.676202) (xy 90.16111 -227.57638) (xy 90.061034 -227.676202) (xy 90.061034 -227.723954)
			(xy 90.261186 -227.723954)
		)
		(stroke
			(width 0)
			(type solid)
		)
		(fill yes)
		(layer "In2.Cu")
		(net "M_C_CPU1_SA_DQS_DN<5>")
	)
	(gr_poly
		(pts
			(xy 90.261186 -227.27285) (xy 90.261186 -227.225098) (xy 90.061034 -227.225098) (xy 90.061034 -227.27285)
			(xy 90.16111 -227.372672)
		)
		(stroke
			(width 0)
			(type solid)
		)
		(fill yes)
		(layer "In2.Cu")
		(net "M_C_CPU1_SA_DQS_DN<0>")
	)
	(gr_poly
		(pts
			(xy 90.261186 -226.056444) (xy 90.16111 -225.956368) (xy 90.061034 -226.056444) (xy 90.061034 -226.100894)
			(xy 90.261186 -226.100894)
		)
		(stroke
			(width 0)
			(type solid)
		)
		(fill yes)
		(layer "In2.Cu")
		(net "M_C_CPU1_SA_DQ<1>")
	)
	(gr_poly
		(pts
			(xy 90.261186 -225.652584) (xy 90.261186 -225.608134) (xy 90.061034 -225.608134) (xy 90.061034 -225.652584)
			(xy 90.16111 -225.75266)
		)
		(stroke
			(width 0)
			(type solid)
		)
		(fill yes)
		(layer "In2.Cu")
		(net "M_C_CPU1_SA_DQ<2>")
	)
	(gr_poly
		(pts
			(xy 90.553794 -291.704268) (xy 90.553794 -291.65677) (xy 90.353642 -291.65677) (xy 90.353642 -291.704268)
			(xy 90.453718 -291.804344)
		)
		(stroke
			(width 0)
			(type solid)
		)
		(fill yes)
		(layer "In2.Cu")
		(net "M_C_CPU1_SB_DQS_DP<8>")
	)
	(gr_poly
		(pts
			(xy 90.55481 -267.801852) (xy 90.454734 -267.701776) (xy 90.354912 -267.801852) (xy 90.354912 -267.846302)
			(xy 90.55481 -267.846302)
		)
		(stroke
			(width 0)
			(type solid)
		)
		(fill yes)
		(layer "In2.Cu")
		(net "M_C_CPU1_SB_RSP<0>")
	)
	(gr_poly
		(pts
			(xy 90.56116 -293.32428) (xy 90.56116 -293.27983) (xy 90.361008 -293.27983) (xy 90.361008 -293.32428)
			(xy 90.461084 -293.424356)
		)
		(stroke
			(width 0)
			(type solid)
		)
		(fill yes)
		(layer "In2.Cu")
		(net "M_C_CPU1_SB_DQ<31>")
	)
	(gr_poly
		(pts
			(xy 90.56116 -292.108128) (xy 90.461084 -292.008052) (xy 90.361008 -292.108128) (xy 90.361008 -292.152578)
			(xy 90.56116 -292.152578)
		)
		(stroke
			(width 0)
			(type solid)
		)
		(fill yes)
		(layer "In2.Cu")
		(net "M_C_CPU1_SB_DQ<28>")
	)
	(gr_poly
		(pts
			(xy 90.56116 -290.487862) (xy 90.461084 -290.38804) (xy 90.361008 -290.487862) (xy 90.361008 -290.535614)
			(xy 90.56116 -290.535614)
		)
		(stroke
			(width 0)
			(type solid)
		)
		(fill yes)
		(layer "In2.Cu")
		(net "M_C_CPU1_SB_DQS_DP<3>")
	)
	(gr_poly
		(pts
			(xy 90.56116 -290.084256) (xy 90.56116 -290.039806) (xy 90.361008 -290.039806) (xy 90.361008 -290.084256)
			(xy 90.461084 -290.184332)
		)
		(stroke
			(width 0)
			(type solid)
		)
		(fill yes)
		(layer "In2.Cu")
		(net "M_C_CPU1_SB_DQ<27>")
	)
	(gr_poly
		(pts
			(xy 90.56116 -288.868104) (xy 90.461084 -288.768028) (xy 90.361008 -288.868104) (xy 90.361008 -288.912554)
			(xy 90.56116 -288.912554)
		)
		(stroke
			(width 0)
			(type solid)
		)
		(fill yes)
		(layer "In2.Cu")
		(net "M_C_CPU1_SB_DQ<24>")
	)
	(gr_poly
		(pts
			(xy 90.56116 -288.464498) (xy 90.56116 -288.420048) (xy 90.361008 -288.420048) (xy 90.361008 -288.464498)
			(xy 90.461084 -288.564574)
		)
		(stroke
			(width 0)
			(type solid)
		)
		(fill yes)
		(layer "In2.Cu")
		(net "M_C_CPU1_SB_DQ<23>")
	)
	(gr_poly
		(pts
			(xy 90.56116 -287.248092) (xy 90.461084 -287.148016) (xy 90.361008 -287.248092) (xy 90.361008 -287.292542)
			(xy 90.56116 -287.292542)
		)
		(stroke
			(width 0)
			(type solid)
		)
		(fill yes)
		(layer "In2.Cu")
		(net "M_C_CPU1_SB_DQ<20>")
	)
	(gr_poly
		(pts
			(xy 90.56116 -286.844486) (xy 90.56116 -286.796734) (xy 90.361008 -286.796734) (xy 90.361008 -286.844486)
			(xy 90.461084 -286.944562)
		)
		(stroke
			(width 0)
			(type solid)
		)
		(fill yes)
		(layer "In2.Cu")
		(net "M_C_CPU1_SB_DQS_DP<7>")
	)
	(gr_poly
		(pts
			(xy 90.56116 -285.62808) (xy 90.461084 -285.528258) (xy 90.361008 -285.62808) (xy 90.361008 -285.675832)
			(xy 90.56116 -285.675832)
		)
		(stroke
			(width 0)
			(type solid)
		)
		(fill yes)
		(layer "In2.Cu")
		(net "M_C_CPU1_SB_DQS_DP<2>")
	)
	(gr_poly
		(pts
			(xy 90.56116 -285.224474) (xy 90.56116 -285.180024) (xy 90.361008 -285.180024) (xy 90.361008 -285.224474)
			(xy 90.461084 -285.32455)
		)
		(stroke
			(width 0)
			(type solid)
		)
		(fill yes)
		(layer "In2.Cu")
		(net "M_C_CPU1_SB_DQ<19>")
	)
	(gr_poly
		(pts
			(xy 90.56116 -284.008322) (xy 90.461084 -283.908246) (xy 90.361008 -284.008322) (xy 90.361008 -284.052772)
			(xy 90.56116 -284.052772)
		)
		(stroke
			(width 0)
			(type solid)
		)
		(fill yes)
		(layer "In2.Cu")
		(net "M_C_CPU1_SB_DQ<16>")
	)
	(gr_poly
		(pts
			(xy 90.56116 -283.604462) (xy 90.56116 -283.560012) (xy 90.361008 -283.560012) (xy 90.361008 -283.604462)
			(xy 90.461084 -283.704538)
		)
		(stroke
			(width 0)
			(type solid)
		)
		(fill yes)
		(layer "In2.Cu")
		(net "M_C_CPU1_SB_DQ<15>")
	)
	(gr_poly
		(pts
			(xy 90.56116 -282.38831) (xy 90.461084 -282.288234) (xy 90.361008 -282.38831) (xy 90.361008 -282.43276)
			(xy 90.56116 -282.43276)
		)
		(stroke
			(width 0)
			(type solid)
		)
		(fill yes)
		(layer "In2.Cu")
		(net "M_C_CPU1_SB_DQ<12>")
	)
	(gr_poly
		(pts
			(xy 90.56116 -281.984704) (xy 90.56116 -281.936952) (xy 90.361008 -281.936952) (xy 90.361008 -281.984704)
			(xy 90.461084 -282.084526)
		)
		(stroke
			(width 0)
			(type solid)
		)
		(fill yes)
		(layer "In2.Cu")
		(net "M_C_CPU1_SB_DQS_DP<6>")
	)
	(gr_poly
		(pts
			(xy 90.56116 -280.768044) (xy 90.461084 -280.668222) (xy 90.361008 -280.768044) (xy 90.361008 -280.815796)
			(xy 90.56116 -280.815796)
		)
		(stroke
			(width 0)
			(type solid)
		)
		(fill yes)
		(layer "In2.Cu")
		(net "M_C_CPU1_SB_DQS_DP<1>")
	)
	(gr_poly
		(pts
			(xy 90.56116 -280.364438) (xy 90.56116 -280.319988) (xy 90.361008 -280.319988) (xy 90.361008 -280.364438)
			(xy 90.461084 -280.464514)
		)
		(stroke
			(width 0)
			(type solid)
		)
		(fill yes)
		(layer "In2.Cu")
		(net "M_C_CPU1_SB_DQ<11>")
	)
	(gr_poly
		(pts
			(xy 90.56116 -279.148286) (xy 90.461084 -279.04821) (xy 90.361008 -279.148286) (xy 90.361008 -279.192736)
			(xy 90.56116 -279.192736)
		)
		(stroke
			(width 0)
			(type solid)
		)
		(fill yes)
		(layer "In2.Cu")
		(net "M_C_CPU1_SB_DQ<8>")
	)
	(gr_poly
		(pts
			(xy 90.56116 -278.744426) (xy 90.56116 -278.699976) (xy 90.361008 -278.699976) (xy 90.361008 -278.744426)
			(xy 90.461084 -278.844502)
		)
		(stroke
			(width 0)
			(type solid)
		)
		(fill yes)
		(layer "In2.Cu")
		(net "M_C_CPU1_SB_DQ<7>")
	)
	(gr_poly
		(pts
			(xy 90.56116 -277.528274) (xy 90.461084 -277.428198) (xy 90.361008 -277.528274) (xy 90.361008 -277.572724)
			(xy 90.56116 -277.572724)
		)
		(stroke
			(width 0)
			(type solid)
		)
		(fill yes)
		(layer "In2.Cu")
		(net "M_C_CPU1_SB_DQ<4>")
	)
	(gr_poly
		(pts
			(xy 90.56116 -277.124668) (xy 90.56116 -277.076916) (xy 90.361008 -277.076916) (xy 90.361008 -277.124668)
			(xy 90.461084 -277.22449)
		)
		(stroke
			(width 0)
			(type solid)
		)
		(fill yes)
		(layer "In2.Cu")
		(net "M_C_CPU1_SB_DQS_DP<5>")
	)
	(gr_poly
		(pts
			(xy 90.56116 -275.908008) (xy 90.461084 -275.808186) (xy 90.361008 -275.908008) (xy 90.361008 -275.95576)
			(xy 90.56116 -275.95576)
		)
		(stroke
			(width 0)
			(type solid)
		)
		(fill yes)
		(layer "In2.Cu")
		(net "M_C_CPU1_SB_DQS_DP<0>")
	)
	(gr_poly
		(pts
			(xy 90.56116 -275.504402) (xy 90.56116 -275.459952) (xy 90.361008 -275.459952) (xy 90.361008 -275.504402)
			(xy 90.461084 -275.604478)
		)
		(stroke
			(width 0)
			(type solid)
		)
		(fill yes)
		(layer "In2.Cu")
		(net "M_C_CPU1_SB_DQ<3>")
	)
	(gr_poly
		(pts
			(xy 90.56116 -274.28825) (xy 90.461084 -274.188174) (xy 90.361008 -274.28825) (xy 90.361008 -274.3327)
			(xy 90.56116 -274.3327)
		)
		(stroke
			(width 0)
			(type solid)
		)
		(fill yes)
		(layer "In2.Cu")
		(net "M_C_CPU1_SB_DQ<0>")
	)
	(gr_poly
		(pts
			(xy 90.56116 -273.88439) (xy 90.56116 -273.83994) (xy 90.361008 -273.83994) (xy 90.361008 -273.88439)
			(xy 90.461084 -273.984466)
		)
		(stroke
			(width 0)
			(type solid)
		)
		(fill yes)
		(layer "In2.Cu")
		(net "M_C_CPU1_SB_CB<3>")
	)
	(gr_poly
		(pts
			(xy 90.56116 -272.668238) (xy 90.461084 -272.568162) (xy 90.361008 -272.668238) (xy 90.361008 -272.712688)
			(xy 90.56116 -272.712688)
		)
		(stroke
			(width 0)
			(type solid)
		)
		(fill yes)
		(layer "In2.Cu")
		(net "M_C_CPU1_SB_CB<0>")
	)
	(gr_poly
		(pts
			(xy 90.56116 -272.264632) (xy 90.56116 -272.21688) (xy 90.361008 -272.21688) (xy 90.361008 -272.264632)
			(xy 90.461084 -272.364454)
		)
		(stroke
			(width 0)
			(type solid)
		)
		(fill yes)
		(layer "In2.Cu")
		(net "M_C_CPU1_SB_DQS_DP<4>")
	)
	(gr_poly
		(pts
			(xy 90.56116 -271.047972) (xy 90.461084 -270.94815) (xy 90.361008 -271.047972) (xy 90.361008 -271.095724)
			(xy 90.56116 -271.095724)
		)
		(stroke
			(width 0)
			(type solid)
		)
		(fill yes)
		(layer "In2.Cu")
		(net "M_C_CPU1_SB_DQS_DP<9>")
	)
	(gr_poly
		(pts
			(xy 90.56116 -270.644366) (xy 90.56116 -270.599916) (xy 90.361008 -270.599916) (xy 90.361008 -270.644366)
			(xy 90.461084 -270.744442)
		)
		(stroke
			(width 0)
			(type solid)
		)
		(fill yes)
		(layer "In2.Cu")
		(net "M_C_CPU1_SB_CB<7>")
	)
	(gr_poly
		(pts
			(xy 90.56116 -269.428214) (xy 90.461084 -269.328138) (xy 90.361008 -269.428214) (xy 90.361008 -269.472664)
			(xy 90.56116 -269.472664)
		)
		(stroke
			(width 0)
			(type solid)
		)
		(fill yes)
		(layer "In2.Cu")
		(net "M_C_CPU1_SB_CB<4>")
	)
	(gr_poly
		(pts
			(xy 90.56116 -265.78433) (xy 90.56116 -265.73988) (xy 90.361008 -265.73988) (xy 90.361008 -265.78433)
			(xy 90.461084 -265.884406)
		)
		(stroke
			(width 0)
			(type solid)
		)
		(fill yes)
		(layer "In2.Cu")
		(net "M_C_CPU1_SB_CS_N<0>")
	)
	(gr_poly
		(pts
			(xy 90.56116 -264.568178) (xy 90.461084 -264.468102) (xy 90.361008 -264.568178) (xy 90.361008 -264.612628)
			(xy 90.56116 -264.612628)
		)
		(stroke
			(width 0)
			(type solid)
		)
		(fill yes)
		(layer "In2.Cu")
		(net "M_C_CPU1_SB_CA<6>")
	)
	(gr_poly
		(pts
			(xy 90.56116 -264.164318) (xy 90.56116 -264.119868) (xy 90.361008 -264.119868) (xy 90.361008 -264.164318)
			(xy 90.461084 -264.264394)
		)
		(stroke
			(width 0)
			(type solid)
		)
		(fill yes)
		(layer "In2.Cu")
		(net "M_C_CPU1_SB_CA<5>")
	)
	(gr_poly
		(pts
			(xy 90.56116 -262.948166) (xy 90.461084 -262.84809) (xy 90.361008 -262.948166) (xy 90.361008 -262.992616)
			(xy 90.56116 -262.992616)
		)
		(stroke
			(width 0)
			(type solid)
		)
		(fill yes)
		(layer "In2.Cu")
		(net "M_C_CPU1_SB_CA<2>")
	)
	(gr_poly
		(pts
			(xy 90.56116 -262.544306) (xy 90.56116 -262.499856) (xy 90.361008 -262.499856) (xy 90.361008 -262.544306)
			(xy 90.461084 -262.644382)
		)
		(stroke
			(width 0)
			(type solid)
		)
		(fill yes)
		(layer "In2.Cu")
		(net "M_C_CPU1_SB_CA<1>")
	)
	(gr_poly
		(pts
			(xy 90.731086 -256.026158) (xy 90.63101 -255.926336) (xy 90.530934 -256.026158) (xy 90.530934 -256.07391)
			(xy 90.731086 -256.07391)
		)
		(stroke
			(width 0)
			(type solid)
		)
		(fill yes)
		(layer "In2.Cu")
		(net "M_C_CPU1_CLK_DP<0>")
	)
	(gr_poly
		(pts
			(xy 90.731086 -255.622552) (xy 90.731086 -255.578102) (xy 90.530934 -255.578102) (xy 90.530934 -255.622552)
			(xy 90.63101 -255.722628)
		)
		(stroke
			(width 0)
			(type solid)
		)
		(fill yes)
		(layer "In2.Cu")
		(net "M_C_CPU1_SA_PAR")
	)
	(gr_poly
		(pts
			(xy 90.731086 -254.4064) (xy 90.63101 -254.306324) (xy 90.530934 -254.4064) (xy 90.530934 -254.45085)
			(xy 90.731086 -254.45085)
		)
		(stroke
			(width 0)
			(type solid)
		)
		(fill yes)
		(layer "In2.Cu")
		(net "M_C_CPU1_SA_CA<4>")
	)
	(gr_poly
		(pts
			(xy 90.731086 -254.00254) (xy 90.731086 -253.95809) (xy 90.530934 -253.95809) (xy 90.530934 -254.00254)
			(xy 90.63101 -254.102616)
		)
		(stroke
			(width 0)
			(type solid)
		)
		(fill yes)
		(layer "In2.Cu")
		(net "M_C_CPU1_SA_CA<3>")
	)
	(gr_poly
		(pts
			(xy 90.731086 -252.786388) (xy 90.63101 -252.686312) (xy 90.530934 -252.786388) (xy 90.530934 -252.830838)
			(xy 90.731086 -252.830838)
		)
		(stroke
			(width 0)
			(type solid)
		)
		(fill yes)
		(layer "In2.Cu")
		(net "M_C_CPU1_SA_CA<0>")
	)
	(gr_poly
		(pts
			(xy 90.731086 -252.382528) (xy 90.731086 -252.338078) (xy 90.530934 -252.338078) (xy 90.530934 -252.382528)
			(xy 90.63101 -252.482604)
		)
		(stroke
			(width 0)
			(type solid)
		)
		(fill yes)
		(layer "In2.Cu")
		(net "M_C_CPU1_SA_CS_N<1>")
	)
	(gr_poly
		(pts
			(xy 90.731086 -250.762516) (xy 90.731086 -250.718066) (xy 90.530934 -250.718066) (xy 90.530934 -250.762516)
			(xy 90.63101 -250.862592)
		)
		(stroke
			(width 0)
			(type solid)
		)
		(fill yes)
		(layer "In2.Cu")
		(net "M_C_CPU1_RESET_N")
	)
	(gr_poly
		(pts
			(xy 90.731086 -249.142504) (xy 90.731086 -249.098054) (xy 90.530934 -249.098054) (xy 90.530934 -249.142504)
			(xy 90.63101 -249.24258)
		)
		(stroke
			(width 0)
			(type solid)
		)
		(fill yes)
		(layer "In2.Cu")
		(net "M_C_CPU1_SA_CB<7>")
	)
	(gr_poly
		(pts
			(xy 90.731086 -247.926352) (xy 90.63101 -247.826276) (xy 90.530934 -247.926352) (xy 90.530934 -247.970802)
			(xy 90.731086 -247.970802)
		)
		(stroke
			(width 0)
			(type solid)
		)
		(fill yes)
		(layer "In2.Cu")
		(net "M_C_CPU1_SA_CB<4>")
	)
	(gr_poly
		(pts
			(xy 90.731086 -247.522746) (xy 90.731086 -247.474994) (xy 90.530934 -247.474994) (xy 90.530934 -247.522746)
			(xy 90.63101 -247.622568)
		)
		(stroke
			(width 0)
			(type solid)
		)
		(fill yes)
		(layer "In2.Cu")
		(net "M_C_CPU1_SA_DQS_DP<9>")
	)
	(gr_poly
		(pts
			(xy 90.731086 -246.306086) (xy 90.63101 -246.206264) (xy 90.530934 -246.306086) (xy 90.530934 -246.353838)
			(xy 90.731086 -246.353838)
		)
		(stroke
			(width 0)
			(type solid)
		)
		(fill yes)
		(layer "In2.Cu")
		(net "M_C_CPU1_SA_DQS_DP<4>")
	)
	(gr_poly
		(pts
			(xy 90.731086 -245.90248) (xy 90.731086 -245.85803) (xy 90.530934 -245.85803) (xy 90.530934 -245.90248)
			(xy 90.63101 -246.002556)
		)
		(stroke
			(width 0)
			(type solid)
		)
		(fill yes)
		(layer "In2.Cu")
		(net "M_C_CPU1_SA_CB<3>")
	)
	(gr_poly
		(pts
			(xy 90.731086 -244.686328) (xy 90.63101 -244.586252) (xy 90.530934 -244.686328) (xy 90.530934 -244.730778)
			(xy 90.731086 -244.730778)
		)
		(stroke
			(width 0)
			(type solid)
		)
		(fill yes)
		(layer "In2.Cu")
		(net "M_C_CPU1_SA_CB<0>")
	)
	(gr_poly
		(pts
			(xy 90.731086 -244.282468) (xy 90.731086 -244.238018) (xy 90.530934 -244.238018) (xy 90.530934 -244.282468)
			(xy 90.63101 -244.382544)
		)
		(stroke
			(width 0)
			(type solid)
		)
		(fill yes)
		(layer "In2.Cu")
		(net "M_C_CPU1_SA_DQ<31>")
	)
	(gr_poly
		(pts
			(xy 90.731086 -243.066316) (xy 90.63101 -242.96624) (xy 90.530934 -243.066316) (xy 90.530934 -243.110766)
			(xy 90.731086 -243.110766)
		)
		(stroke
			(width 0)
			(type solid)
		)
		(fill yes)
		(layer "In2.Cu")
		(net "M_C_CPU1_SA_DQ<28>")
	)
	(gr_poly
		(pts
			(xy 90.731086 -242.66271) (xy 90.731086 -242.614958) (xy 90.530934 -242.614958) (xy 90.530934 -242.66271)
			(xy 90.63101 -242.762532)
		)
		(stroke
			(width 0)
			(type solid)
		)
		(fill yes)
		(layer "In2.Cu")
		(net "M_C_CPU1_SA_DQS_DP<8>")
	)
	(gr_poly
		(pts
			(xy 90.731086 -241.44605) (xy 90.63101 -241.346228) (xy 90.530934 -241.44605) (xy 90.530934 -241.493802)
			(xy 90.731086 -241.493802)
		)
		(stroke
			(width 0)
			(type solid)
		)
		(fill yes)
		(layer "In2.Cu")
		(net "M_C_CPU1_SA_DQS_DP<3>")
	)
	(gr_poly
		(pts
			(xy 90.731086 -241.042444) (xy 90.731086 -240.997994) (xy 90.530934 -240.997994) (xy 90.530934 -241.042444)
			(xy 90.63101 -241.14252)
		)
		(stroke
			(width 0)
			(type solid)
		)
		(fill yes)
		(layer "In2.Cu")
		(net "M_C_CPU1_SA_DQ<27>")
	)
	(gr_poly
		(pts
			(xy 90.731086 -239.826292) (xy 90.63101 -239.726216) (xy 90.530934 -239.826292) (xy 90.530934 -239.870742)
			(xy 90.731086 -239.870742)
		)
		(stroke
			(width 0)
			(type solid)
		)
		(fill yes)
		(layer "In2.Cu")
		(net "M_C_CPU1_SA_DQ<24>")
	)
	(gr_poly
		(pts
			(xy 90.731086 -239.422432) (xy 90.731086 -239.377982) (xy 90.530934 -239.377982) (xy 90.530934 -239.422432)
			(xy 90.63101 -239.522508)
		)
		(stroke
			(width 0)
			(type solid)
		)
		(fill yes)
		(layer "In2.Cu")
		(net "M_C_CPU1_SA_DQ<23>")
	)
	(gr_poly
		(pts
			(xy 90.731086 -238.20628) (xy 90.63101 -238.106204) (xy 90.530934 -238.20628) (xy 90.530934 -238.25073)
			(xy 90.731086 -238.25073)
		)
		(stroke
			(width 0)
			(type solid)
		)
		(fill yes)
		(layer "In2.Cu")
		(net "M_C_CPU1_SA_DQ<20>")
	)
	(gr_poly
		(pts
			(xy 90.731086 -237.802674) (xy 90.731086 -237.754922) (xy 90.530934 -237.754922) (xy 90.530934 -237.802674)
			(xy 90.63101 -237.902496)
		)
		(stroke
			(width 0)
			(type solid)
		)
		(fill yes)
		(layer "In2.Cu")
		(net "M_C_CPU1_SA_DQS_DP<7>")
	)
	(gr_poly
		(pts
			(xy 90.731086 -236.586014) (xy 90.63101 -236.486192) (xy 90.530934 -236.586014) (xy 90.530934 -236.633766)
			(xy 90.731086 -236.633766)
		)
		(stroke
			(width 0)
			(type solid)
		)
		(fill yes)
		(layer "In2.Cu")
		(net "M_C_CPU1_SA_DQS_DP<2>")
	)
	(gr_poly
		(pts
			(xy 90.731086 -236.182408) (xy 90.731086 -236.137958) (xy 90.530934 -236.137958) (xy 90.530934 -236.182408)
			(xy 90.63101 -236.282484)
		)
		(stroke
			(width 0)
			(type solid)
		)
		(fill yes)
		(layer "In2.Cu")
		(net "M_C_CPU1_SA_DQ<19>")
	)
	(gr_poly
		(pts
			(xy 90.731086 -234.966256) (xy 90.63101 -234.86618) (xy 90.530934 -234.966256) (xy 90.530934 -235.010706)
			(xy 90.731086 -235.010706)
		)
		(stroke
			(width 0)
			(type solid)
		)
		(fill yes)
		(layer "In2.Cu")
		(net "M_C_CPU1_SA_DQ<16>")
	)
	(gr_poly
		(pts
			(xy 90.731086 -234.562396) (xy 90.731086 -234.517946) (xy 90.530934 -234.517946) (xy 90.530934 -234.562396)
			(xy 90.63101 -234.662472)
		)
		(stroke
			(width 0)
			(type solid)
		)
		(fill yes)
		(layer "In2.Cu")
		(net "M_C_CPU1_SA_DQ<15>")
	)
	(gr_poly
		(pts
			(xy 90.731086 -233.346244) (xy 90.63101 -233.246168) (xy 90.530934 -233.346244) (xy 90.530934 -233.390694)
			(xy 90.731086 -233.390694)
		)
		(stroke
			(width 0)
			(type solid)
		)
		(fill yes)
		(layer "In2.Cu")
		(net "M_C_CPU1_SA_DQ<12>")
	)
	(gr_poly
		(pts
			(xy 90.731086 -232.942638) (xy 90.731086 -232.894886) (xy 90.530934 -232.894886) (xy 90.530934 -232.942638)
			(xy 90.63101 -233.04246)
		)
		(stroke
			(width 0)
			(type solid)
		)
		(fill yes)
		(layer "In2.Cu")
		(net "M_C_CPU1_SA_DQS_DP<6>")
	)
	(gr_poly
		(pts
			(xy 90.731086 -231.725978) (xy 90.63101 -231.626156) (xy 90.530934 -231.725978) (xy 90.530934 -231.77373)
			(xy 90.731086 -231.77373)
		)
		(stroke
			(width 0)
			(type solid)
		)
		(fill yes)
		(layer "In2.Cu")
		(net "M_C_CPU1_SA_DQS_DP<1>")
	)
	(gr_poly
		(pts
			(xy 90.731086 -231.322626) (xy 90.731086 -231.278176) (xy 90.530934 -231.278176) (xy 90.530934 -231.322626)
			(xy 90.63101 -231.422702)
		)
		(stroke
			(width 0)
			(type solid)
		)
		(fill yes)
		(layer "In2.Cu")
		(net "M_C_CPU1_SA_DQ<11>")
	)
	(gr_poly
		(pts
			(xy 90.731086 -230.10622) (xy 90.63101 -230.006144) (xy 90.530934 -230.10622) (xy 90.530934 -230.15067)
			(xy 90.731086 -230.15067)
		)
		(stroke
			(width 0)
			(type solid)
		)
		(fill yes)
		(layer "In2.Cu")
		(net "M_C_CPU1_SA_DQ<8>")
	)
	(gr_poly
		(pts
			(xy 90.731086 -229.702614) (xy 90.731086 -229.658164) (xy 90.530934 -229.658164) (xy 90.530934 -229.702614)
			(xy 90.63101 -229.80269)
		)
		(stroke
			(width 0)
			(type solid)
		)
		(fill yes)
		(layer "In2.Cu")
		(net "M_C_CPU1_SA_DQ<7>")
	)
	(gr_poly
		(pts
			(xy 90.731086 -228.486462) (xy 90.63101 -228.386386) (xy 90.530934 -228.486462) (xy 90.530934 -228.530912)
			(xy 90.731086 -228.530912)
		)
		(stroke
			(width 0)
			(type solid)
		)
		(fill yes)
		(layer "In2.Cu")
		(net "M_C_CPU1_SA_DQ<4>")
	)
	(gr_poly
		(pts
			(xy 90.731086 -228.082856) (xy 90.731086 -228.035104) (xy 90.530934 -228.035104) (xy 90.530934 -228.082856)
			(xy 90.63101 -228.182678)
		)
		(stroke
			(width 0)
			(type solid)
		)
		(fill yes)
		(layer "In2.Cu")
		(net "M_C_CPU1_SA_DQS_DP<5>")
	)
	(gr_poly
		(pts
			(xy 90.731086 -226.866196) (xy 90.63101 -226.766374) (xy 90.530934 -226.866196) (xy 90.530934 -226.913948)
			(xy 90.731086 -226.913948)
		)
		(stroke
			(width 0)
			(type solid)
		)
		(fill yes)
		(layer "In2.Cu")
		(net "M_C_CPU1_SA_DQS_DP<0>")
	)
	(gr_poly
		(pts
			(xy 90.731086 -226.46259) (xy 90.731086 -226.41814) (xy 90.530934 -226.41814) (xy 90.530934 -226.46259)
			(xy 90.63101 -226.562666)
		)
		(stroke
			(width 0)
			(type solid)
		)
		(fill yes)
		(layer "In2.Cu")
		(net "M_C_CPU1_SA_DQ<3>")
	)
	(gr_poly
		(pts
			(xy 90.731086 -225.246438) (xy 90.63101 -225.146362) (xy 90.530934 -225.246438) (xy 90.530934 -225.290888)
			(xy 90.731086 -225.290888)
		)
		(stroke
			(width 0)
			(type solid)
		)
		(fill yes)
		(layer "In2.Cu")
		(net "M_C_CPU1_SA_DQ<0>")
	)
	(gr_poly
		(pts
			(xy 91.03106 -292.918134) (xy 90.930984 -292.818058) (xy 90.830908 -292.918134) (xy 90.830908 -292.962584)
			(xy 91.03106 -292.962584)
		)
		(stroke
			(width 0)
			(type solid)
		)
		(fill yes)
		(layer "In2.Cu")
		(net "M_C_CPU1_SB_DQ<29>")
	)
	(gr_poly
		(pts
			(xy 91.03106 -292.514274) (xy 91.03106 -292.469824) (xy 90.830908 -292.469824) (xy 90.830908 -292.514274)
			(xy 90.930984 -292.61435)
		)
		(stroke
			(width 0)
			(type solid)
		)
		(fill yes)
		(layer "In2.Cu")
		(net "M_C_CPU1_SB_DQ<30>")
	)
	(gr_poly
		(pts
			(xy 91.03106 -290.894516) (xy 91.03106 -290.846764) (xy 90.830908 -290.846764) (xy 90.830908 -290.894516)
			(xy 90.930984 -290.994338)
		)
		(stroke
			(width 0)
			(type solid)
		)
		(fill yes)
		(layer "In2.Cu")
		(net "M_C_CPU1_SB_DQS_DN<3>")
	)
	(gr_poly
		(pts
			(xy 91.03106 -289.67811) (xy 90.930984 -289.578034) (xy 90.830908 -289.67811) (xy 90.830908 -289.72256)
			(xy 91.03106 -289.72256)
		)
		(stroke
			(width 0)
			(type solid)
		)
		(fill yes)
		(layer "In2.Cu")
		(net "M_C_CPU1_SB_DQ<25>")
	)
	(gr_poly
		(pts
			(xy 91.03106 -289.27425) (xy 91.03106 -289.2298) (xy 90.830908 -289.2298) (xy 90.830908 -289.27425)
			(xy 90.930984 -289.374326)
		)
		(stroke
			(width 0)
			(type solid)
		)
		(fill yes)
		(layer "In2.Cu")
		(net "M_C_CPU1_SB_DQ<26>")
	)
	(gr_poly
		(pts
			(xy 91.03106 -288.058098) (xy 90.930984 -287.958022) (xy 90.830908 -288.058098) (xy 90.830908 -288.102548)
			(xy 91.03106 -288.102548)
		)
		(stroke
			(width 0)
			(type solid)
		)
		(fill yes)
		(layer "In2.Cu")
		(net "M_C_CPU1_SB_DQ<21>")
	)
	(gr_poly
		(pts
			(xy 91.03106 -287.654492) (xy 91.03106 -287.610042) (xy 90.830908 -287.610042) (xy 90.830908 -287.654492)
			(xy 90.930984 -287.754568)
		)
		(stroke
			(width 0)
			(type solid)
		)
		(fill yes)
		(layer "In2.Cu")
		(net "M_C_CPU1_SB_DQ<22>")
	)
	(gr_poly
		(pts
			(xy 91.03106 -286.438086) (xy 90.930984 -286.33801) (xy 90.830908 -286.438086) (xy 90.830908 -286.485838)
			(xy 91.03106 -286.485838)
		)
		(stroke
			(width 0)
			(type solid)
		)
		(fill yes)
		(layer "In2.Cu")
		(net "M_C_CPU1_SB_DQS_DN<7>")
	)
	(gr_poly
		(pts
			(xy 91.03106 -286.034734) (xy 91.03106 -285.986982) (xy 90.830908 -285.986982) (xy 90.830908 -286.034734)
			(xy 90.930984 -286.134556)
		)
		(stroke
			(width 0)
			(type solid)
		)
		(fill yes)
		(layer "In2.Cu")
		(net "M_C_CPU1_SB_DQS_DN<2>")
	)
	(gr_poly
		(pts
			(xy 91.03106 -284.818328) (xy 90.930984 -284.718252) (xy 90.830908 -284.818328) (xy 90.830908 -284.862778)
			(xy 91.03106 -284.862778)
		)
		(stroke
			(width 0)
			(type solid)
		)
		(fill yes)
		(layer "In2.Cu")
		(net "M_C_CPU1_SB_DQ<17>")
	)
	(gr_poly
		(pts
			(xy 91.03106 -284.414468) (xy 91.03106 -284.370018) (xy 90.830908 -284.370018) (xy 90.830908 -284.414468)
			(xy 90.930984 -284.514544)
		)
		(stroke
			(width 0)
			(type solid)
		)
		(fill yes)
		(layer "In2.Cu")
		(net "M_C_CPU1_SB_DQ<18>")
	)
	(gr_poly
		(pts
			(xy 91.03106 -283.198316) (xy 90.930984 -283.09824) (xy 90.830908 -283.198316) (xy 90.830908 -283.242766)
			(xy 91.03106 -283.242766)
		)
		(stroke
			(width 0)
			(type solid)
		)
		(fill yes)
		(layer "In2.Cu")
		(net "M_C_CPU1_SB_DQ<13>")
	)
	(gr_poly
		(pts
			(xy 91.03106 -282.794456) (xy 91.03106 -282.750006) (xy 90.830908 -282.750006) (xy 90.830908 -282.794456)
			(xy 90.930984 -282.894532)
		)
		(stroke
			(width 0)
			(type solid)
		)
		(fill yes)
		(layer "In2.Cu")
		(net "M_C_CPU1_SB_DQ<14>")
	)
	(gr_poly
		(pts
			(xy 91.03106 -281.57805) (xy 90.930984 -281.478228) (xy 90.830908 -281.57805) (xy 90.830908 -281.625802)
			(xy 91.03106 -281.625802)
		)
		(stroke
			(width 0)
			(type solid)
		)
		(fill yes)
		(layer "In2.Cu")
		(net "M_C_CPU1_SB_DQS_DN<6>")
	)
	(gr_poly
		(pts
			(xy 91.03106 -281.174698) (xy 91.03106 -281.126946) (xy 90.830908 -281.126946) (xy 90.830908 -281.174698)
			(xy 90.930984 -281.27452)
		)
		(stroke
			(width 0)
			(type solid)
		)
		(fill yes)
		(layer "In2.Cu")
		(net "M_C_CPU1_SB_DQS_DN<1>")
	)
	(gr_poly
		(pts
			(xy 91.03106 -279.958292) (xy 90.930984 -279.858216) (xy 90.830908 -279.958292) (xy 90.830908 -280.002742)
			(xy 91.03106 -280.002742)
		)
		(stroke
			(width 0)
			(type solid)
		)
		(fill yes)
		(layer "In2.Cu")
		(net "M_C_CPU1_SB_DQ<9>")
	)
	(gr_poly
		(pts
			(xy 91.03106 -279.554432) (xy 91.03106 -279.509982) (xy 90.830908 -279.509982) (xy 90.830908 -279.554432)
			(xy 90.930984 -279.654508)
		)
		(stroke
			(width 0)
			(type solid)
		)
		(fill yes)
		(layer "In2.Cu")
		(net "M_C_CPU1_SB_DQ<10>")
	)
	(gr_poly
		(pts
			(xy 91.03106 -278.33828) (xy 90.930984 -278.238204) (xy 90.830908 -278.33828) (xy 90.830908 -278.38273)
			(xy 91.03106 -278.38273)
		)
		(stroke
			(width 0)
			(type solid)
		)
		(fill yes)
		(layer "In2.Cu")
		(net "M_C_CPU1_SB_DQ<5>")
	)
	(gr_poly
		(pts
			(xy 91.03106 -277.93442) (xy 91.03106 -277.88997) (xy 90.830908 -277.88997) (xy 90.830908 -277.93442)
			(xy 90.930984 -278.034496)
		)
		(stroke
			(width 0)
			(type solid)
		)
		(fill yes)
		(layer "In2.Cu")
		(net "M_C_CPU1_SB_DQ<6>")
	)
	(gr_poly
		(pts
			(xy 91.03106 -276.718014) (xy 90.930984 -276.618192) (xy 90.830908 -276.718014) (xy 90.830908 -276.765766)
			(xy 91.03106 -276.765766)
		)
		(stroke
			(width 0)
			(type solid)
		)
		(fill yes)
		(layer "In2.Cu")
		(net "M_C_CPU1_SB_DQS_DN<5>")
	)
	(gr_poly
		(pts
			(xy 91.03106 -276.314662) (xy 91.03106 -276.26691) (xy 90.830908 -276.26691) (xy 90.830908 -276.314662)
			(xy 90.930984 -276.414484)
		)
		(stroke
			(width 0)
			(type solid)
		)
		(fill yes)
		(layer "In2.Cu")
		(net "M_C_CPU1_SB_DQS_DN<0>")
	)
	(gr_poly
		(pts
			(xy 91.03106 -275.098256) (xy 90.930984 -274.99818) (xy 90.830908 -275.098256) (xy 90.830908 -275.142706)
			(xy 91.03106 -275.142706)
		)
		(stroke
			(width 0)
			(type solid)
		)
		(fill yes)
		(layer "In2.Cu")
		(net "M_C_CPU1_SB_DQ<1>")
	)
	(gr_poly
		(pts
			(xy 91.03106 -274.694396) (xy 91.03106 -274.649946) (xy 90.830908 -274.649946) (xy 90.830908 -274.694396)
			(xy 90.930984 -274.794472)
		)
		(stroke
			(width 0)
			(type solid)
		)
		(fill yes)
		(layer "In2.Cu")
		(net "M_C_CPU1_SB_DQ<2>")
	)
	(gr_poly
		(pts
			(xy 91.03106 -273.478244) (xy 90.930984 -273.378168) (xy 90.830908 -273.478244) (xy 90.830908 -273.522694)
			(xy 91.03106 -273.522694)
		)
		(stroke
			(width 0)
			(type solid)
		)
		(fill yes)
		(layer "In2.Cu")
		(net "M_C_CPU1_SB_CB<1>")
	)
	(gr_poly
		(pts
			(xy 91.03106 -273.074384) (xy 91.03106 -273.029934) (xy 90.830908 -273.029934) (xy 90.830908 -273.074384)
			(xy 90.930984 -273.17446)
		)
		(stroke
			(width 0)
			(type solid)
		)
		(fill yes)
		(layer "In2.Cu")
		(net "M_C_CPU1_SB_CB<2>")
	)
	(gr_poly
		(pts
			(xy 91.03106 -271.857978) (xy 90.930984 -271.758156) (xy 90.830908 -271.857978) (xy 90.830908 -271.90573)
			(xy 91.03106 -271.90573)
		)
		(stroke
			(width 0)
			(type solid)
		)
		(fill yes)
		(layer "In2.Cu")
		(net "M_C_CPU1_SB_DQS_DN<4>")
	)
	(gr_poly
		(pts
			(xy 91.03106 -271.454626) (xy 91.03106 -271.406874) (xy 90.830908 -271.406874) (xy 90.830908 -271.454626)
			(xy 90.930984 -271.554448)
		)
		(stroke
			(width 0)
			(type solid)
		)
		(fill yes)
		(layer "In2.Cu")
		(net "M_C_CPU1_SB_DQS_DN<9>")
	)
	(gr_poly
		(pts
			(xy 91.03106 -270.23822) (xy 90.930984 -270.138144) (xy 90.830908 -270.23822) (xy 90.830908 -270.28267)
			(xy 91.03106 -270.28267)
		)
		(stroke
			(width 0)
			(type solid)
		)
		(fill yes)
		(layer "In2.Cu")
		(net "M_C_CPU1_SB_CB<5>")
	)
	(gr_poly
		(pts
			(xy 91.03106 -269.83436) (xy 91.03106 -269.78991) (xy 90.830908 -269.78991) (xy 90.830908 -269.83436)
			(xy 90.930984 -269.934436)
		)
		(stroke
			(width 0)
			(type solid)
		)
		(fill yes)
		(layer "In2.Cu")
		(net "M_C_CPU1_SB_CB<6>")
	)
	(gr_poly
		(pts
			(xy 91.03106 -266.594336) (xy 91.03106 -266.549886) (xy 90.830908 -266.549886) (xy 90.830908 -266.594336)
			(xy 90.930984 -266.694412)
		)
		(stroke
			(width 0)
			(type solid)
		)
		(fill yes)
		(layer "In2.Cu")
		(net "M_C_CPU1_SB_CS_N<1>")
	)
	(gr_poly
		(pts
			(xy 91.03106 -264.974324) (xy 91.03106 -264.929874) (xy 90.830908 -264.929874) (xy 90.830908 -264.974324)
			(xy 90.930984 -265.0744)
		)
		(stroke
			(width 0)
			(type solid)
		)
		(fill yes)
		(layer "In2.Cu")
		(net "M_C_CPU1_SB_PAR")
	)
	(gr_poly
		(pts
			(xy 91.03106 -263.758172) (xy 90.930984 -263.658096) (xy 90.830908 -263.758172) (xy 90.830908 -263.802622)
			(xy 91.03106 -263.802622)
		)
		(stroke
			(width 0)
			(type solid)
		)
		(fill yes)
		(layer "In2.Cu")
		(net "M_C_CPU1_SB_CA<4>")
	)
	(gr_poly
		(pts
			(xy 91.03106 -263.354312) (xy 91.03106 -263.309862) (xy 90.830908 -263.309862) (xy 90.830908 -263.354312)
			(xy 90.930984 -263.454388)
		)
		(stroke
			(width 0)
			(type solid)
		)
		(fill yes)
		(layer "In2.Cu")
		(net "M_C_CPU1_SB_CA<3>")
	)
	(gr_poly
		(pts
			(xy 91.03106 -262.13816) (xy 90.930984 -262.038084) (xy 90.830908 -262.13816) (xy 90.830908 -262.18261)
			(xy 91.03106 -262.18261)
		)
		(stroke
			(width 0)
			(type solid)
		)
		(fill yes)
		(layer "In2.Cu")
		(net "M_C_CPU1_SB_CA<0>")
	)
	(gr_poly
		(pts
			(xy 91.037156 -266.991846) (xy 90.937334 -266.89177) (xy 90.837258 -266.991846) (xy 90.837258 -267.036296)
			(xy 91.037156 -267.036296)
		)
		(stroke
			(width 0)
			(type solid)
		)
		(fill yes)
		(layer "In2.Cu")
		(net "M_C_CPU1_SA_RSP<0>")
	)
	(gr_poly
		(pts
			(xy 91.038426 -291.298122) (xy 90.93835 -291.198046) (xy 90.838274 -291.298122) (xy 90.838274 -291.34562)
			(xy 91.038426 -291.34562)
		)
		(stroke
			(width 0)
			(type solid)
		)
		(fill yes)
		(layer "In2.Cu")
		(net "M_C_CPU1_SB_DQS_DN<8>")
	)
	(gr_poly
		(pts
			(xy 91.200732 -246.712486) (xy 91.200732 -246.664988) (xy 91.000834 -246.664988) (xy 91.000834 -246.712486)
			(xy 91.100656 -246.812562)
		)
		(stroke
			(width 0)
			(type solid)
		)
		(fill yes)
		(layer "In2.Cu")
		(net "M_C_CPU1_SA_DQS_DN<4>")
	)
	(gr_poly
		(pts
			(xy 91.200986 -256.432812) (xy 91.200986 -256.38506) (xy 91.000834 -256.38506) (xy 91.000834 -256.432812)
			(xy 91.10091 -256.532634)
		)
		(stroke
			(width 0)
			(type solid)
		)
		(fill yes)
		(layer "In2.Cu")
		(net "M_C_CPU1_CLK_DN<0>")
	)
	(gr_poly
		(pts
			(xy 91.200986 -255.216406) (xy 91.10091 -255.11633) (xy 91.000834 -255.216406) (xy 91.000834 -255.260856)
			(xy 91.200986 -255.260856)
		)
		(stroke
			(width 0)
			(type solid)
		)
		(fill yes)
		(layer "In2.Cu")
		(net "M_C_CPU1_SA_CA<6>")
	)
	(gr_poly
		(pts
			(xy 91.200986 -254.812546) (xy 91.200986 -254.768096) (xy 91.000834 -254.768096) (xy 91.000834 -254.812546)
			(xy 91.10091 -254.912622)
		)
		(stroke
			(width 0)
			(type solid)
		)
		(fill yes)
		(layer "In2.Cu")
		(net "M_C_CPU1_SA_CA<5>")
	)
	(gr_poly
		(pts
			(xy 91.200986 -253.596394) (xy 91.10091 -253.496318) (xy 91.000834 -253.596394) (xy 91.000834 -253.640844)
			(xy 91.200986 -253.640844)
		)
		(stroke
			(width 0)
			(type solid)
		)
		(fill yes)
		(layer "In2.Cu")
		(net "M_C_CPU1_SA_CA<2>")
	)
	(gr_poly
		(pts
			(xy 91.200986 -253.192534) (xy 91.200986 -253.148084) (xy 91.000834 -253.148084) (xy 91.000834 -253.192534)
			(xy 91.10091 -253.29261)
		)
		(stroke
			(width 0)
			(type solid)
		)
		(fill yes)
		(layer "In2.Cu")
		(net "M_C_CPU1_SA_CA<1>")
	)
	(gr_poly
		(pts
			(xy 91.200986 -248.736358) (xy 91.10091 -248.636282) (xy 91.000834 -248.736358) (xy 91.000834 -248.780808)
			(xy 91.200986 -248.780808)
		)
		(stroke
			(width 0)
			(type solid)
		)
		(fill yes)
		(layer "In2.Cu")
		(net "M_C_CPU1_SA_CB<5>")
	)
	(gr_poly
		(pts
			(xy 91.200986 -248.332498) (xy 91.200986 -248.288048) (xy 91.000834 -248.288048) (xy 91.000834 -248.332498)
			(xy 91.10091 -248.432574)
		)
		(stroke
			(width 0)
			(type solid)
		)
		(fill yes)
		(layer "In2.Cu")
		(net "M_C_CPU1_SA_CB<6>")
	)
	(gr_poly
		(pts
			(xy 91.200986 -247.116092) (xy 91.10091 -247.01627) (xy 91.000834 -247.116092) (xy 91.000834 -247.163844)
			(xy 91.200986 -247.163844)
		)
		(stroke
			(width 0)
			(type solid)
		)
		(fill yes)
		(layer "In2.Cu")
		(net "M_C_CPU1_SA_DQS_DN<9>")
	)
	(gr_poly
		(pts
			(xy 91.200986 -245.496334) (xy 91.10091 -245.396258) (xy 91.000834 -245.496334) (xy 91.000834 -245.540784)
			(xy 91.200986 -245.540784)
		)
		(stroke
			(width 0)
			(type solid)
		)
		(fill yes)
		(layer "In2.Cu")
		(net "M_C_CPU1_SA_CB<1>")
	)
	(gr_poly
		(pts
			(xy 91.200986 -245.092474) (xy 91.200986 -245.048024) (xy 91.000834 -245.048024) (xy 91.000834 -245.092474)
			(xy 91.10091 -245.19255)
		)
		(stroke
			(width 0)
			(type solid)
		)
		(fill yes)
		(layer "In2.Cu")
		(net "M_C_CPU1_SA_CB<2>")
	)
	(gr_poly
		(pts
			(xy 91.200986 -243.876322) (xy 91.10091 -243.776246) (xy 91.000834 -243.876322) (xy 91.000834 -243.920772)
			(xy 91.200986 -243.920772)
		)
		(stroke
			(width 0)
			(type solid)
		)
		(fill yes)
		(layer "In2.Cu")
		(net "M_C_CPU1_SA_DQ<29>")
	)
	(gr_poly
		(pts
			(xy 91.200986 -243.472462) (xy 91.200986 -243.428012) (xy 91.000834 -243.428012) (xy 91.000834 -243.472462)
			(xy 91.10091 -243.572538)
		)
		(stroke
			(width 0)
			(type solid)
		)
		(fill yes)
		(layer "In2.Cu")
		(net "M_C_CPU1_SA_DQ<30>")
	)
	(gr_poly
		(pts
			(xy 91.200986 -242.256056) (xy 91.10091 -242.156234) (xy 91.000834 -242.256056) (xy 91.000834 -242.303808)
			(xy 91.200986 -242.303808)
		)
		(stroke
			(width 0)
			(type solid)
		)
		(fill yes)
		(layer "In2.Cu")
		(net "M_C_CPU1_SA_DQS_DN<8>")
	)
	(gr_poly
		(pts
			(xy 91.200986 -241.852704) (xy 91.200986 -241.804952) (xy 91.000834 -241.804952) (xy 91.000834 -241.852704)
			(xy 91.10091 -241.952526)
		)
		(stroke
			(width 0)
			(type solid)
		)
		(fill yes)
		(layer "In2.Cu")
		(net "M_C_CPU1_SA_DQS_DN<3>")
	)
	(gr_poly
		(pts
			(xy 91.200986 -240.636298) (xy 91.10091 -240.536222) (xy 91.000834 -240.636298) (xy 91.000834 -240.680748)
			(xy 91.200986 -240.680748)
		)
		(stroke
			(width 0)
			(type solid)
		)
		(fill yes)
		(layer "In2.Cu")
		(net "M_C_CPU1_SA_DQ<25>")
	)
	(gr_poly
		(pts
			(xy 91.200986 -240.232438) (xy 91.200986 -240.187988) (xy 91.000834 -240.187988) (xy 91.000834 -240.232438)
			(xy 91.10091 -240.332514)
		)
		(stroke
			(width 0)
			(type solid)
		)
		(fill yes)
		(layer "In2.Cu")
		(net "M_C_CPU1_SA_DQ<26>")
	)
	(gr_poly
		(pts
			(xy 91.200986 -239.016286) (xy 91.10091 -238.91621) (xy 91.000834 -239.016286) (xy 91.000834 -239.060736)
			(xy 91.200986 -239.060736)
		)
		(stroke
			(width 0)
			(type solid)
		)
		(fill yes)
		(layer "In2.Cu")
		(net "M_C_CPU1_SA_DQ<21>")
	)
	(gr_poly
		(pts
			(xy 91.200986 -238.612426) (xy 91.200986 -238.567976) (xy 91.000834 -238.567976) (xy 91.000834 -238.612426)
			(xy 91.10091 -238.712502)
		)
		(stroke
			(width 0)
			(type solid)
		)
		(fill yes)
		(layer "In2.Cu")
		(net "M_C_CPU1_SA_DQ<22>")
	)
	(gr_poly
		(pts
			(xy 91.200986 -237.39602) (xy 91.10091 -237.296198) (xy 91.000834 -237.39602) (xy 91.000834 -237.443772)
			(xy 91.200986 -237.443772)
		)
		(stroke
			(width 0)
			(type solid)
		)
		(fill yes)
		(layer "In2.Cu")
		(net "M_C_CPU1_SA_DQS_DN<7>")
	)
	(gr_poly
		(pts
			(xy 91.200986 -236.992668) (xy 91.200986 -236.944916) (xy 91.000834 -236.944916) (xy 91.000834 -236.992668)
			(xy 91.10091 -237.09249)
		)
		(stroke
			(width 0)
			(type solid)
		)
		(fill yes)
		(layer "In2.Cu")
		(net "M_C_CPU1_SA_DQS_DN<2>")
	)
	(gr_poly
		(pts
			(xy 91.200986 -235.776262) (xy 91.10091 -235.676186) (xy 91.000834 -235.776262) (xy 91.000834 -235.820712)
			(xy 91.200986 -235.820712)
		)
		(stroke
			(width 0)
			(type solid)
		)
		(fill yes)
		(layer "In2.Cu")
		(net "M_C_CPU1_SA_DQ<17>")
	)
	(gr_poly
		(pts
			(xy 91.200986 -235.372402) (xy 91.200986 -235.327952) (xy 91.000834 -235.327952) (xy 91.000834 -235.372402)
			(xy 91.10091 -235.472478)
		)
		(stroke
			(width 0)
			(type solid)
		)
		(fill yes)
		(layer "In2.Cu")
		(net "M_C_CPU1_SA_DQ<18>")
	)
	(gr_poly
		(pts
			(xy 91.200986 -234.15625) (xy 91.10091 -234.056174) (xy 91.000834 -234.15625) (xy 91.000834 -234.2007)
			(xy 91.200986 -234.2007)
		)
		(stroke
			(width 0)
			(type solid)
		)
		(fill yes)
		(layer "In2.Cu")
		(net "M_C_CPU1_SA_DQ<13>")
	)
	(gr_poly
		(pts
			(xy 91.200986 -233.75239) (xy 91.200986 -233.70794) (xy 91.000834 -233.70794) (xy 91.000834 -233.75239)
			(xy 91.10091 -233.852466)
		)
		(stroke
			(width 0)
			(type solid)
		)
		(fill yes)
		(layer "In2.Cu")
		(net "M_C_CPU1_SA_DQ<14>")
	)
	(gr_poly
		(pts
			(xy 91.200986 -232.535984) (xy 91.10091 -232.436162) (xy 91.000834 -232.535984) (xy 91.000834 -232.583736)
			(xy 91.200986 -232.583736)
		)
		(stroke
			(width 0)
			(type solid)
		)
		(fill yes)
		(layer "In2.Cu")
		(net "M_C_CPU1_SA_DQS_DN<6>")
	)
	(gr_poly
		(pts
			(xy 91.200986 -232.132632) (xy 91.200986 -232.08488) (xy 91.000834 -232.08488) (xy 91.000834 -232.132632)
			(xy 91.10091 -232.232454)
		)
		(stroke
			(width 0)
			(type solid)
		)
		(fill yes)
		(layer "In2.Cu")
		(net "M_C_CPU1_SA_DQS_DN<1>")
	)
	(gr_poly
		(pts
			(xy 91.200986 -230.916226) (xy 91.10091 -230.81615) (xy 91.000834 -230.916226) (xy 91.000834 -230.960676)
			(xy 91.200986 -230.960676)
		)
		(stroke
			(width 0)
			(type solid)
		)
		(fill yes)
		(layer "In2.Cu")
		(net "M_C_CPU1_SA_DQ<9>")
	)
	(gr_poly
		(pts
			(xy 91.200986 -230.51262) (xy 91.200986 -230.46817) (xy 91.000834 -230.46817) (xy 91.000834 -230.51262)
			(xy 91.10091 -230.612696)
		)
		(stroke
			(width 0)
			(type solid)
		)
		(fill yes)
		(layer "In2.Cu")
		(net "M_C_CPU1_SA_DQ<10>")
	)
	(gr_poly
		(pts
			(xy 91.200986 -229.296214) (xy 91.10091 -229.196138) (xy 91.000834 -229.296214) (xy 91.000834 -229.340664)
			(xy 91.200986 -229.340664)
		)
		(stroke
			(width 0)
			(type solid)
		)
		(fill yes)
		(layer "In2.Cu")
		(net "M_C_CPU1_SA_DQ<5>")
	)
	(gr_poly
		(pts
			(xy 91.200986 -228.892608) (xy 91.200986 -228.848158) (xy 91.000834 -228.848158) (xy 91.000834 -228.892608)
			(xy 91.10091 -228.992684)
		)
		(stroke
			(width 0)
			(type solid)
		)
		(fill yes)
		(layer "In2.Cu")
		(net "M_C_CPU1_SA_DQ<6>")
	)
	(gr_poly
		(pts
			(xy 91.200986 -227.676202) (xy 91.10091 -227.57638) (xy 91.000834 -227.676202) (xy 91.000834 -227.723954)
			(xy 91.200986 -227.723954)
		)
		(stroke
			(width 0)
			(type solid)
		)
		(fill yes)
		(layer "In2.Cu")
		(net "M_C_CPU1_SA_DQS_DN<5>")
	)
	(gr_poly
		(pts
			(xy 91.200986 -227.27285) (xy 91.200986 -227.225098) (xy 91.000834 -227.225098) (xy 91.000834 -227.27285)
			(xy 91.10091 -227.372672)
		)
		(stroke
			(width 0)
			(type solid)
		)
		(fill yes)
		(layer "In2.Cu")
		(net "M_C_CPU1_SA_DQS_DN<0>")
	)
	(gr_poly
		(pts
			(xy 91.200986 -226.056444) (xy 91.10091 -225.956368) (xy 91.000834 -226.056444) (xy 91.000834 -226.100894)
			(xy 91.200986 -226.100894)
		)
		(stroke
			(width 0)
			(type solid)
		)
		(fill yes)
		(layer "In2.Cu")
		(net "M_C_CPU1_SA_DQ<1>")
	)
	(gr_poly
		(pts
			(xy 91.200986 -225.652584) (xy 91.200986 -225.608134) (xy 91.000834 -225.608134) (xy 91.000834 -225.652584)
			(xy 91.10091 -225.75266)
		)
		(stroke
			(width 0)
			(type solid)
		)
		(fill yes)
		(layer "In2.Cu")
		(net "M_C_CPU1_SA_DQ<2>")
	)
	(gr_poly
		(pts
			(xy 91.20124 -251.572522) (xy 91.20124 -251.528072) (xy 91.001088 -251.528072) (xy 91.001088 -251.572522)
			(xy 91.101164 -251.672598)
		)
		(stroke
			(width 0)
			(type solid)
		)
		(fill yes)
		(layer "In2.Cu")
		(net "M_C_CPU1_SA_CS_N<0>")
	)
	(gr_poly
		(pts
			(xy 91.20124 -250.35637) (xy 91.101164 -250.256294) (xy 91.001088 -250.35637) (xy 91.001088 -250.40082)
			(xy 91.20124 -250.40082)
		)
		(stroke
			(width 0)
			(type solid)
		)
		(fill yes)
		(layer "In2.Cu")
		(net "M_C_CPU1_ALERT_R_N")
	)
	(gr_poly
		(pts
			(xy 91.493848 -291.704268) (xy 91.493848 -291.65677) (xy 91.29395 -291.65677) (xy 91.29395 -291.704268)
			(xy 91.393772 -291.804344)
		)
		(stroke
			(width 0)
			(type solid)
		)
		(fill yes)
		(layer "In2.Cu")
		(net "M_C_CPU1_SB_DQS_DP<8>")
	)
	(gr_poly
		(pts
			(xy 91.494864 -267.801852) (xy 91.394788 -267.701776) (xy 91.294966 -267.801852) (xy 91.294966 -267.846302)
			(xy 91.494864 -267.846302)
		)
		(stroke
			(width 0)
			(type solid)
		)
		(fill yes)
		(layer "In2.Cu")
		(net "M_C_CPU1_SB_RSP<0>")
	)
	(gr_poly
		(pts
			(xy 91.501214 -293.32428) (xy 91.501214 -293.27983) (xy 91.301062 -293.27983) (xy 91.301062 -293.32428)
			(xy 91.401138 -293.424356)
		)
		(stroke
			(width 0)
			(type solid)
		)
		(fill yes)
		(layer "In2.Cu")
		(net "M_C_CPU1_SB_DQ<31>")
	)
	(gr_poly
		(pts
			(xy 91.501214 -292.108128) (xy 91.401138 -292.008052) (xy 91.301062 -292.108128) (xy 91.301062 -292.152578)
			(xy 91.501214 -292.152578)
		)
		(stroke
			(width 0)
			(type solid)
		)
		(fill yes)
		(layer "In2.Cu")
		(net "M_C_CPU1_SB_DQ<28>")
	)
	(gr_poly
		(pts
			(xy 91.501214 -290.487862) (xy 91.401138 -290.38804) (xy 91.301062 -290.487862) (xy 91.301062 -290.535614)
			(xy 91.501214 -290.535614)
		)
		(stroke
			(width 0)
			(type solid)
		)
		(fill yes)
		(layer "In2.Cu")
		(net "M_C_CPU1_SB_DQS_DP<3>")
	)
	(gr_poly
		(pts
			(xy 91.501214 -290.084256) (xy 91.501214 -290.039806) (xy 91.301062 -290.039806) (xy 91.301062 -290.084256)
			(xy 91.401138 -290.184332)
		)
		(stroke
			(width 0)
			(type solid)
		)
		(fill yes)
		(layer "In2.Cu")
		(net "M_C_CPU1_SB_DQ<27>")
	)
	(gr_poly
		(pts
			(xy 91.501214 -288.868104) (xy 91.401138 -288.768028) (xy 91.301062 -288.868104) (xy 91.301062 -288.912554)
			(xy 91.501214 -288.912554)
		)
		(stroke
			(width 0)
			(type solid)
		)
		(fill yes)
		(layer "In2.Cu")
		(net "M_C_CPU1_SB_DQ<24>")
	)
	(gr_poly
		(pts
			(xy 91.501214 -288.464498) (xy 91.501214 -288.420048) (xy 91.301062 -288.420048) (xy 91.301062 -288.464498)
			(xy 91.401138 -288.564574)
		)
		(stroke
			(width 0)
			(type solid)
		)
		(fill yes)
		(layer "In2.Cu")
		(net "M_C_CPU1_SB_DQ<23>")
	)
	(gr_poly
		(pts
			(xy 91.501214 -287.248092) (xy 91.401138 -287.148016) (xy 91.301062 -287.248092) (xy 91.301062 -287.292542)
			(xy 91.501214 -287.292542)
		)
		(stroke
			(width 0)
			(type solid)
		)
		(fill yes)
		(layer "In2.Cu")
		(net "M_C_CPU1_SB_DQ<20>")
	)
	(gr_poly
		(pts
			(xy 91.501214 -286.844486) (xy 91.501214 -286.796734) (xy 91.301062 -286.796734) (xy 91.301062 -286.844486)
			(xy 91.401138 -286.944562)
		)
		(stroke
			(width 0)
			(type solid)
		)
		(fill yes)
		(layer "In2.Cu")
		(net "M_C_CPU1_SB_DQS_DP<7>")
	)
	(gr_poly
		(pts
			(xy 91.501214 -285.62808) (xy 91.401138 -285.528258) (xy 91.301062 -285.62808) (xy 91.301062 -285.675832)
			(xy 91.501214 -285.675832)
		)
		(stroke
			(width 0)
			(type solid)
		)
		(fill yes)
		(layer "In2.Cu")
		(net "M_C_CPU1_SB_DQS_DP<2>")
	)
	(gr_poly
		(pts
			(xy 91.501214 -285.224474) (xy 91.501214 -285.180024) (xy 91.301062 -285.180024) (xy 91.301062 -285.224474)
			(xy 91.401138 -285.32455)
		)
		(stroke
			(width 0)
			(type solid)
		)
		(fill yes)
		(layer "In2.Cu")
		(net "M_C_CPU1_SB_DQ<19>")
	)
	(gr_poly
		(pts
			(xy 91.501214 -284.008322) (xy 91.401138 -283.908246) (xy 91.301062 -284.008322) (xy 91.301062 -284.052772)
			(xy 91.501214 -284.052772)
		)
		(stroke
			(width 0)
			(type solid)
		)
		(fill yes)
		(layer "In2.Cu")
		(net "M_C_CPU1_SB_DQ<16>")
	)
	(gr_poly
		(pts
			(xy 91.501214 -283.604462) (xy 91.501214 -283.560012) (xy 91.301062 -283.560012) (xy 91.301062 -283.604462)
			(xy 91.401138 -283.704538)
		)
		(stroke
			(width 0)
			(type solid)
		)
		(fill yes)
		(layer "In2.Cu")
		(net "M_C_CPU1_SB_DQ<15>")
	)
	(gr_poly
		(pts
			(xy 91.501214 -282.38831) (xy 91.401138 -282.288234) (xy 91.301062 -282.38831) (xy 91.301062 -282.43276)
			(xy 91.501214 -282.43276)
		)
		(stroke
			(width 0)
			(type solid)
		)
		(fill yes)
		(layer "In2.Cu")
		(net "M_C_CPU1_SB_DQ<12>")
	)
	(gr_poly
		(pts
			(xy 91.501214 -281.984704) (xy 91.501214 -281.936952) (xy 91.301062 -281.936952) (xy 91.301062 -281.984704)
			(xy 91.401138 -282.084526)
		)
		(stroke
			(width 0)
			(type solid)
		)
		(fill yes)
		(layer "In2.Cu")
		(net "M_C_CPU1_SB_DQS_DP<6>")
	)
	(gr_poly
		(pts
			(xy 91.501214 -280.768044) (xy 91.401138 -280.668222) (xy 91.301062 -280.768044) (xy 91.301062 -280.815796)
			(xy 91.501214 -280.815796)
		)
		(stroke
			(width 0)
			(type solid)
		)
		(fill yes)
		(layer "In2.Cu")
		(net "M_C_CPU1_SB_DQS_DP<1>")
	)
	(gr_poly
		(pts
			(xy 91.501214 -280.364438) (xy 91.501214 -280.319988) (xy 91.301062 -280.319988) (xy 91.301062 -280.364438)
			(xy 91.401138 -280.464514)
		)
		(stroke
			(width 0)
			(type solid)
		)
		(fill yes)
		(layer "In2.Cu")
		(net "M_C_CPU1_SB_DQ<11>")
	)
	(gr_poly
		(pts
			(xy 91.501214 -279.148286) (xy 91.401138 -279.04821) (xy 91.301062 -279.148286) (xy 91.301062 -279.192736)
			(xy 91.501214 -279.192736)
		)
		(stroke
			(width 0)
			(type solid)
		)
		(fill yes)
		(layer "In2.Cu")
		(net "M_C_CPU1_SB_DQ<8>")
	)
	(gr_poly
		(pts
			(xy 91.501214 -278.744426) (xy 91.501214 -278.699976) (xy 91.301062 -278.699976) (xy 91.301062 -278.744426)
			(xy 91.401138 -278.844502)
		)
		(stroke
			(width 0)
			(type solid)
		)
		(fill yes)
		(layer "In2.Cu")
		(net "M_C_CPU1_SB_DQ<7>")
	)
	(gr_poly
		(pts
			(xy 91.501214 -277.528274) (xy 91.401138 -277.428198) (xy 91.301062 -277.528274) (xy 91.301062 -277.572724)
			(xy 91.501214 -277.572724)
		)
		(stroke
			(width 0)
			(type solid)
		)
		(fill yes)
		(layer "In2.Cu")
		(net "M_C_CPU1_SB_DQ<4>")
	)
	(gr_poly
		(pts
			(xy 91.501214 -277.124668) (xy 91.501214 -277.076916) (xy 91.301062 -277.076916) (xy 91.301062 -277.124668)
			(xy 91.401138 -277.22449)
		)
		(stroke
			(width 0)
			(type solid)
		)
		(fill yes)
		(layer "In2.Cu")
		(net "M_C_CPU1_SB_DQS_DP<5>")
	)
	(gr_poly
		(pts
			(xy 91.501214 -275.908008) (xy 91.401138 -275.808186) (xy 91.301062 -275.908008) (xy 91.301062 -275.95576)
			(xy 91.501214 -275.95576)
		)
		(stroke
			(width 0)
			(type solid)
		)
		(fill yes)
		(layer "In2.Cu")
		(net "M_C_CPU1_SB_DQS_DP<0>")
	)
	(gr_poly
		(pts
			(xy 91.501214 -275.504402) (xy 91.501214 -275.459952) (xy 91.301062 -275.459952) (xy 91.301062 -275.504402)
			(xy 91.401138 -275.604478)
		)
		(stroke
			(width 0)
			(type solid)
		)
		(fill yes)
		(layer "In2.Cu")
		(net "M_C_CPU1_SB_DQ<3>")
	)
	(gr_poly
		(pts
			(xy 91.501214 -274.28825) (xy 91.401138 -274.188174) (xy 91.301062 -274.28825) (xy 91.301062 -274.3327)
			(xy 91.501214 -274.3327)
		)
		(stroke
			(width 0)
			(type solid)
		)
		(fill yes)
		(layer "In2.Cu")
		(net "M_C_CPU1_SB_DQ<0>")
	)
	(gr_poly
		(pts
			(xy 91.501214 -273.88439) (xy 91.501214 -273.83994) (xy 91.301062 -273.83994) (xy 91.301062 -273.88439)
			(xy 91.401138 -273.984466)
		)
		(stroke
			(width 0)
			(type solid)
		)
		(fill yes)
		(layer "In2.Cu")
		(net "M_C_CPU1_SB_CB<3>")
	)
	(gr_poly
		(pts
			(xy 91.501214 -272.668238) (xy 91.401138 -272.568162) (xy 91.301062 -272.668238) (xy 91.301062 -272.712688)
			(xy 91.501214 -272.712688)
		)
		(stroke
			(width 0)
			(type solid)
		)
		(fill yes)
		(layer "In2.Cu")
		(net "M_C_CPU1_SB_CB<0>")
	)
	(gr_poly
		(pts
			(xy 91.501214 -272.264632) (xy 91.501214 -272.21688) (xy 91.301062 -272.21688) (xy 91.301062 -272.264632)
			(xy 91.401138 -272.364454)
		)
		(stroke
			(width 0)
			(type solid)
		)
		(fill yes)
		(layer "In2.Cu")
		(net "M_C_CPU1_SB_DQS_DP<4>")
	)
	(gr_poly
		(pts
			(xy 91.501214 -271.047972) (xy 91.401138 -270.94815) (xy 91.301062 -271.047972) (xy 91.301062 -271.095724)
			(xy 91.501214 -271.095724)
		)
		(stroke
			(width 0)
			(type solid)
		)
		(fill yes)
		(layer "In2.Cu")
		(net "M_C_CPU1_SB_DQS_DP<9>")
	)
	(gr_poly
		(pts
			(xy 91.501214 -270.644366) (xy 91.501214 -270.599916) (xy 91.301062 -270.599916) (xy 91.301062 -270.644366)
			(xy 91.401138 -270.744442)
		)
		(stroke
			(width 0)
			(type solid)
		)
		(fill yes)
		(layer "In2.Cu")
		(net "M_C_CPU1_SB_CB<7>")
	)
	(gr_poly
		(pts
			(xy 91.501214 -269.428214) (xy 91.401138 -269.328138) (xy 91.301062 -269.428214) (xy 91.301062 -269.472664)
			(xy 91.501214 -269.472664)
		)
		(stroke
			(width 0)
			(type solid)
		)
		(fill yes)
		(layer "In2.Cu")
		(net "M_C_CPU1_SB_CB<4>")
	)
	(gr_poly
		(pts
			(xy 91.501214 -265.78433) (xy 91.501214 -265.73988) (xy 91.301062 -265.73988) (xy 91.301062 -265.78433)
			(xy 91.401138 -265.884406)
		)
		(stroke
			(width 0)
			(type solid)
		)
		(fill yes)
		(layer "In2.Cu")
		(net "M_C_CPU1_SB_CS_N<0>")
	)
	(gr_poly
		(pts
			(xy 91.501214 -264.568178) (xy 91.401138 -264.468102) (xy 91.301062 -264.568178) (xy 91.301062 -264.612628)
			(xy 91.501214 -264.612628)
		)
		(stroke
			(width 0)
			(type solid)
		)
		(fill yes)
		(layer "In2.Cu")
		(net "M_C_CPU1_SB_CA<6>")
	)
	(gr_poly
		(pts
			(xy 91.501214 -264.164318) (xy 91.501214 -264.119868) (xy 91.301062 -264.119868) (xy 91.301062 -264.164318)
			(xy 91.401138 -264.264394)
		)
		(stroke
			(width 0)
			(type solid)
		)
		(fill yes)
		(layer "In2.Cu")
		(net "M_C_CPU1_SB_CA<5>")
	)
	(gr_poly
		(pts
			(xy 91.501214 -262.948166) (xy 91.401138 -262.84809) (xy 91.301062 -262.948166) (xy 91.301062 -262.992616)
			(xy 91.501214 -262.992616)
		)
		(stroke
			(width 0)
			(type solid)
		)
		(fill yes)
		(layer "In2.Cu")
		(net "M_C_CPU1_SB_CA<2>")
	)
	(gr_poly
		(pts
			(xy 91.501214 -262.544306) (xy 91.501214 -262.499856) (xy 91.301062 -262.499856) (xy 91.301062 -262.544306)
			(xy 91.401138 -262.644382)
		)
		(stroke
			(width 0)
			(type solid)
		)
		(fill yes)
		(layer "In2.Cu")
		(net "M_C_CPU1_SB_CA<1>")
	)
	(gr_poly
		(pts
			(xy 91.67114 -256.026158) (xy 91.571064 -255.926336) (xy 91.470988 -256.026158) (xy 91.470988 -256.07391)
			(xy 91.67114 -256.07391)
		)
		(stroke
			(width 0)
			(type solid)
		)
		(fill yes)
		(layer "In2.Cu")
		(net "M_C_CPU1_CLK_DP<0>")
	)
	(gr_poly
		(pts
			(xy 91.67114 -255.622552) (xy 91.67114 -255.578102) (xy 91.470988 -255.578102) (xy 91.470988 -255.622552)
			(xy 91.571064 -255.722628)
		)
		(stroke
			(width 0)
			(type solid)
		)
		(fill yes)
		(layer "In2.Cu")
		(net "M_C_CPU1_SA_PAR")
	)
	(gr_poly
		(pts
			(xy 91.67114 -254.4064) (xy 91.571064 -254.306324) (xy 91.470988 -254.4064) (xy 91.470988 -254.45085)
			(xy 91.67114 -254.45085)
		)
		(stroke
			(width 0)
			(type solid)
		)
		(fill yes)
		(layer "In2.Cu")
		(net "M_C_CPU1_SA_CA<4>")
	)
	(gr_poly
		(pts
			(xy 91.67114 -254.00254) (xy 91.67114 -253.95809) (xy 91.470988 -253.95809) (xy 91.470988 -254.00254)
			(xy 91.571064 -254.102616)
		)
		(stroke
			(width 0)
			(type solid)
		)
		(fill yes)
		(layer "In2.Cu")
		(net "M_C_CPU1_SA_CA<3>")
	)
	(gr_poly
		(pts
			(xy 91.67114 -252.786388) (xy 91.571064 -252.686312) (xy 91.470988 -252.786388) (xy 91.470988 -252.830838)
			(xy 91.67114 -252.830838)
		)
		(stroke
			(width 0)
			(type solid)
		)
		(fill yes)
		(layer "In2.Cu")
		(net "M_C_CPU1_SA_CA<0>")
	)
	(gr_poly
		(pts
			(xy 91.67114 -252.382528) (xy 91.67114 -252.338078) (xy 91.470988 -252.338078) (xy 91.470988 -252.382528)
			(xy 91.571064 -252.482604)
		)
		(stroke
			(width 0)
			(type solid)
		)
		(fill yes)
		(layer "In2.Cu")
		(net "M_C_CPU1_SA_CS_N<1>")
	)
	(gr_poly
		(pts
			(xy 91.67114 -250.762516) (xy 91.67114 -250.718066) (xy 91.470988 -250.718066) (xy 91.470988 -250.762516)
			(xy 91.571064 -250.862592)
		)
		(stroke
			(width 0)
			(type solid)
		)
		(fill yes)
		(layer "In2.Cu")
		(net "M_C_CPU1_RESET_N")
	)
	(gr_poly
		(pts
			(xy 91.67114 -249.142504) (xy 91.67114 -249.098054) (xy 91.470988 -249.098054) (xy 91.470988 -249.142504)
			(xy 91.571064 -249.24258)
		)
		(stroke
			(width 0)
			(type solid)
		)
		(fill yes)
		(layer "In2.Cu")
		(net "M_C_CPU1_SA_CB<7>")
	)
	(gr_poly
		(pts
			(xy 91.67114 -247.926352) (xy 91.571064 -247.826276) (xy 91.470988 -247.926352) (xy 91.470988 -247.970802)
			(xy 91.67114 -247.970802)
		)
		(stroke
			(width 0)
			(type solid)
		)
		(fill yes)
		(layer "In2.Cu")
		(net "M_C_CPU1_SA_CB<4>")
	)
	(gr_poly
		(pts
			(xy 91.67114 -247.522746) (xy 91.67114 -247.474994) (xy 91.470988 -247.474994) (xy 91.470988 -247.522746)
			(xy 91.571064 -247.622568)
		)
		(stroke
			(width 0)
			(type solid)
		)
		(fill yes)
		(layer "In2.Cu")
		(net "M_C_CPU1_SA_DQS_DP<9>")
	)
	(gr_poly
		(pts
			(xy 91.67114 -246.306086) (xy 91.571064 -246.206264) (xy 91.470988 -246.306086) (xy 91.470988 -246.353838)
			(xy 91.67114 -246.353838)
		)
		(stroke
			(width 0)
			(type solid)
		)
		(fill yes)
		(layer "In2.Cu")
		(net "M_C_CPU1_SA_DQS_DP<4>")
	)
	(gr_poly
		(pts
			(xy 91.67114 -245.90248) (xy 91.67114 -245.85803) (xy 91.470988 -245.85803) (xy 91.470988 -245.90248)
			(xy 91.571064 -246.002556)
		)
		(stroke
			(width 0)
			(type solid)
		)
		(fill yes)
		(layer "In2.Cu")
		(net "M_C_CPU1_SA_CB<3>")
	)
	(gr_poly
		(pts
			(xy 91.67114 -244.686328) (xy 91.571064 -244.586252) (xy 91.470988 -244.686328) (xy 91.470988 -244.730778)
			(xy 91.67114 -244.730778)
		)
		(stroke
			(width 0)
			(type solid)
		)
		(fill yes)
		(layer "In2.Cu")
		(net "M_C_CPU1_SA_CB<0>")
	)
	(gr_poly
		(pts
			(xy 91.67114 -244.282468) (xy 91.67114 -244.238018) (xy 91.470988 -244.238018) (xy 91.470988 -244.282468)
			(xy 91.571064 -244.382544)
		)
		(stroke
			(width 0)
			(type solid)
		)
		(fill yes)
		(layer "In2.Cu")
		(net "M_C_CPU1_SA_DQ<31>")
	)
	(gr_poly
		(pts
			(xy 91.67114 -243.066316) (xy 91.571064 -242.96624) (xy 91.470988 -243.066316) (xy 91.470988 -243.110766)
			(xy 91.67114 -243.110766)
		)
		(stroke
			(width 0)
			(type solid)
		)
		(fill yes)
		(layer "In2.Cu")
		(net "M_C_CPU1_SA_DQ<28>")
	)
	(gr_poly
		(pts
			(xy 91.67114 -242.66271) (xy 91.67114 -242.614958) (xy 91.470988 -242.614958) (xy 91.470988 -242.66271)
			(xy 91.571064 -242.762532)
		)
		(stroke
			(width 0)
			(type solid)
		)
		(fill yes)
		(layer "In2.Cu")
		(net "M_C_CPU1_SA_DQS_DP<8>")
	)
	(gr_poly
		(pts
			(xy 91.67114 -241.44605) (xy 91.571064 -241.346228) (xy 91.470988 -241.44605) (xy 91.470988 -241.493802)
			(xy 91.67114 -241.493802)
		)
		(stroke
			(width 0)
			(type solid)
		)
		(fill yes)
		(layer "In2.Cu")
		(net "M_C_CPU1_SA_DQS_DP<3>")
	)
	(gr_poly
		(pts
			(xy 91.67114 -241.042444) (xy 91.67114 -240.997994) (xy 91.470988 -240.997994) (xy 91.470988 -241.042444)
			(xy 91.571064 -241.14252)
		)
		(stroke
			(width 0)
			(type solid)
		)
		(fill yes)
		(layer "In2.Cu")
		(net "M_C_CPU1_SA_DQ<27>")
	)
	(gr_poly
		(pts
			(xy 91.67114 -239.826292) (xy 91.571064 -239.726216) (xy 91.470988 -239.826292) (xy 91.470988 -239.870742)
			(xy 91.67114 -239.870742)
		)
		(stroke
			(width 0)
			(type solid)
		)
		(fill yes)
		(layer "In2.Cu")
		(net "M_C_CPU1_SA_DQ<24>")
	)
	(gr_poly
		(pts
			(xy 91.67114 -239.422432) (xy 91.67114 -239.377982) (xy 91.470988 -239.377982) (xy 91.470988 -239.422432)
			(xy 91.571064 -239.522508)
		)
		(stroke
			(width 0)
			(type solid)
		)
		(fill yes)
		(layer "In2.Cu")
		(net "M_C_CPU1_SA_DQ<23>")
	)
	(gr_poly
		(pts
			(xy 91.67114 -238.20628) (xy 91.571064 -238.106204) (xy 91.470988 -238.20628) (xy 91.470988 -238.25073)
			(xy 91.67114 -238.25073)
		)
		(stroke
			(width 0)
			(type solid)
		)
		(fill yes)
		(layer "In2.Cu")
		(net "M_C_CPU1_SA_DQ<20>")
	)
	(gr_poly
		(pts
			(xy 91.67114 -237.802674) (xy 91.67114 -237.754922) (xy 91.470988 -237.754922) (xy 91.470988 -237.802674)
			(xy 91.571064 -237.902496)
		)
		(stroke
			(width 0)
			(type solid)
		)
		(fill yes)
		(layer "In2.Cu")
		(net "M_C_CPU1_SA_DQS_DP<7>")
	)
	(gr_poly
		(pts
			(xy 91.67114 -236.586014) (xy 91.571064 -236.486192) (xy 91.470988 -236.586014) (xy 91.470988 -236.633766)
			(xy 91.67114 -236.633766)
		)
		(stroke
			(width 0)
			(type solid)
		)
		(fill yes)
		(layer "In2.Cu")
		(net "M_C_CPU1_SA_DQS_DP<2>")
	)
	(gr_poly
		(pts
			(xy 91.67114 -236.182408) (xy 91.67114 -236.137958) (xy 91.470988 -236.137958) (xy 91.470988 -236.182408)
			(xy 91.571064 -236.282484)
		)
		(stroke
			(width 0)
			(type solid)
		)
		(fill yes)
		(layer "In2.Cu")
		(net "M_C_CPU1_SA_DQ<19>")
	)
	(gr_poly
		(pts
			(xy 91.67114 -234.966256) (xy 91.571064 -234.86618) (xy 91.470988 -234.966256) (xy 91.470988 -235.010706)
			(xy 91.67114 -235.010706)
		)
		(stroke
			(width 0)
			(type solid)
		)
		(fill yes)
		(layer "In2.Cu")
		(net "M_C_CPU1_SA_DQ<16>")
	)
	(gr_poly
		(pts
			(xy 91.67114 -234.562396) (xy 91.67114 -234.517946) (xy 91.470988 -234.517946) (xy 91.470988 -234.562396)
			(xy 91.571064 -234.662472)
		)
		(stroke
			(width 0)
			(type solid)
		)
		(fill yes)
		(layer "In2.Cu")
		(net "M_C_CPU1_SA_DQ<15>")
	)
	(gr_poly
		(pts
			(xy 91.67114 -233.346244) (xy 91.571064 -233.246168) (xy 91.470988 -233.346244) (xy 91.470988 -233.390694)
			(xy 91.67114 -233.390694)
		)
		(stroke
			(width 0)
			(type solid)
		)
		(fill yes)
		(layer "In2.Cu")
		(net "M_C_CPU1_SA_DQ<12>")
	)
	(gr_poly
		(pts
			(xy 91.67114 -232.942638) (xy 91.67114 -232.894886) (xy 91.470988 -232.894886) (xy 91.470988 -232.942638)
			(xy 91.571064 -233.04246)
		)
		(stroke
			(width 0)
			(type solid)
		)
		(fill yes)
		(layer "In2.Cu")
		(net "M_C_CPU1_SA_DQS_DP<6>")
	)
	(gr_poly
		(pts
			(xy 91.67114 -231.725978) (xy 91.571064 -231.626156) (xy 91.470988 -231.725978) (xy 91.470988 -231.77373)
			(xy 91.67114 -231.77373)
		)
		(stroke
			(width 0)
			(type solid)
		)
		(fill yes)
		(layer "In2.Cu")
		(net "M_C_CPU1_SA_DQS_DP<1>")
	)
	(gr_poly
		(pts
			(xy 91.67114 -231.322626) (xy 91.67114 -231.278176) (xy 91.470988 -231.278176) (xy 91.470988 -231.322626)
			(xy 91.571064 -231.422702)
		)
		(stroke
			(width 0)
			(type solid)
		)
		(fill yes)
		(layer "In2.Cu")
		(net "M_C_CPU1_SA_DQ<11>")
	)
	(gr_poly
		(pts
			(xy 91.67114 -230.10622) (xy 91.571064 -230.006144) (xy 91.470988 -230.10622) (xy 91.470988 -230.15067)
			(xy 91.67114 -230.15067)
		)
		(stroke
			(width 0)
			(type solid)
		)
		(fill yes)
		(layer "In2.Cu")
		(net "M_C_CPU1_SA_DQ<8>")
	)
	(gr_poly
		(pts
			(xy 91.67114 -229.702614) (xy 91.67114 -229.658164) (xy 91.470988 -229.658164) (xy 91.470988 -229.702614)
			(xy 91.571064 -229.80269)
		)
		(stroke
			(width 0)
			(type solid)
		)
		(fill yes)
		(layer "In2.Cu")
		(net "M_C_CPU1_SA_DQ<7>")
	)
	(gr_poly
		(pts
			(xy 91.67114 -228.486462) (xy 91.571064 -228.386386) (xy 91.470988 -228.486462) (xy 91.470988 -228.530912)
			(xy 91.67114 -228.530912)
		)
		(stroke
			(width 0)
			(type solid)
		)
		(fill yes)
		(layer "In2.Cu")
		(net "M_C_CPU1_SA_DQ<4>")
	)
	(gr_poly
		(pts
			(xy 91.67114 -228.082856) (xy 91.67114 -228.035104) (xy 91.470988 -228.035104) (xy 91.470988 -228.082856)
			(xy 91.571064 -228.182678)
		)
		(stroke
			(width 0)
			(type solid)
		)
		(fill yes)
		(layer "In2.Cu")
		(net "M_C_CPU1_SA_DQS_DP<5>")
	)
	(gr_poly
		(pts
			(xy 91.67114 -226.866196) (xy 91.571064 -226.766374) (xy 91.470988 -226.866196) (xy 91.470988 -226.913948)
			(xy 91.67114 -226.913948)
		)
		(stroke
			(width 0)
			(type solid)
		)
		(fill yes)
		(layer "In2.Cu")
		(net "M_C_CPU1_SA_DQS_DP<0>")
	)
	(gr_poly
		(pts
			(xy 91.67114 -226.46259) (xy 91.67114 -226.41814) (xy 91.470988 -226.41814) (xy 91.470988 -226.46259)
			(xy 91.571064 -226.562666)
		)
		(stroke
			(width 0)
			(type solid)
		)
		(fill yes)
		(layer "In2.Cu")
		(net "M_C_CPU1_SA_DQ<3>")
	)
	(gr_poly
		(pts
			(xy 91.67114 -225.246438) (xy 91.571064 -225.146362) (xy 91.470988 -225.246438) (xy 91.470988 -225.290888)
			(xy 91.67114 -225.290888)
		)
		(stroke
			(width 0)
			(type solid)
		)
		(fill yes)
		(layer "In2.Cu")
		(net "M_C_CPU1_SA_DQ<0>")
	)
	(gr_poly
		(pts
			(xy 91.971114 -292.918134) (xy 91.871038 -292.818058) (xy 91.770962 -292.918134) (xy 91.770962 -292.962584)
			(xy 91.971114 -292.962584)
		)
		(stroke
			(width 0)
			(type solid)
		)
		(fill yes)
		(layer "In2.Cu")
		(net "M_C_CPU1_SB_DQ<29>")
	)
	(gr_poly
		(pts
			(xy 91.971114 -292.514274) (xy 91.971114 -292.469824) (xy 91.770962 -292.469824) (xy 91.770962 -292.514274)
			(xy 91.871038 -292.61435)
		)
		(stroke
			(width 0)
			(type solid)
		)
		(fill yes)
		(layer "In2.Cu")
		(net "M_C_CPU1_SB_DQ<30>")
	)
	(gr_poly
		(pts
			(xy 91.971114 -291.297868) (xy 91.871038 -291.198046) (xy 91.770962 -291.297868) (xy 91.770962 -291.34562)
			(xy 91.971114 -291.34562)
		)
		(stroke
			(width 0)
			(type solid)
		)
		(fill yes)
		(layer "In2.Cu")
		(net "M_C_CPU1_SB_DQS_DN<8>")
	)
	(gr_poly
		(pts
			(xy 91.971114 -290.894516) (xy 91.971114 -290.846764) (xy 91.770962 -290.846764) (xy 91.770962 -290.894516)
			(xy 91.871038 -290.994338)
		)
		(stroke
			(width 0)
			(type solid)
		)
		(fill yes)
		(layer "In2.Cu")
		(net "M_C_CPU1_SB_DQS_DN<3>")
	)
	(gr_poly
		(pts
			(xy 91.971114 -289.67811) (xy 91.871038 -289.578034) (xy 91.770962 -289.67811) (xy 91.770962 -289.72256)
			(xy 91.971114 -289.72256)
		)
		(stroke
			(width 0)
			(type solid)
		)
		(fill yes)
		(layer "In2.Cu")
		(net "M_C_CPU1_SB_DQ<25>")
	)
	(gr_poly
		(pts
			(xy 91.971114 -289.27425) (xy 91.971114 -289.2298) (xy 91.770962 -289.2298) (xy 91.770962 -289.27425)
			(xy 91.871038 -289.374326)
		)
		(stroke
			(width 0)
			(type solid)
		)
		(fill yes)
		(layer "In2.Cu")
		(net "M_C_CPU1_SB_DQ<26>")
	)
	(gr_poly
		(pts
			(xy 91.971114 -288.058098) (xy 91.871038 -287.958022) (xy 91.770962 -288.058098) (xy 91.770962 -288.102548)
			(xy 91.971114 -288.102548)
		)
		(stroke
			(width 0)
			(type solid)
		)
		(fill yes)
		(layer "In2.Cu")
		(net "M_C_CPU1_SB_DQ<21>")
	)
	(gr_poly
		(pts
			(xy 91.971114 -287.654492) (xy 91.971114 -287.610042) (xy 91.770962 -287.610042) (xy 91.770962 -287.654492)
			(xy 91.871038 -287.754568)
		)
		(stroke
			(width 0)
			(type solid)
		)
		(fill yes)
		(layer "In2.Cu")
		(net "M_C_CPU1_SB_DQ<22>")
	)
	(gr_poly
		(pts
			(xy 91.971114 -286.438086) (xy 91.871038 -286.33801) (xy 91.770962 -286.438086) (xy 91.770962 -286.485838)
			(xy 91.971114 -286.485838)
		)
		(stroke
			(width 0)
			(type solid)
		)
		(fill yes)
		(layer "In2.Cu")
		(net "M_C_CPU1_SB_DQS_DN<7>")
	)
	(gr_poly
		(pts
			(xy 91.971114 -286.034734) (xy 91.971114 -285.986982) (xy 91.770962 -285.986982) (xy 91.770962 -286.034734)
			(xy 91.871038 -286.134556)
		)
		(stroke
			(width 0)
			(type solid)
		)
		(fill yes)
		(layer "In2.Cu")
		(net "M_C_CPU1_SB_DQS_DN<2>")
	)
	(gr_poly
		(pts
			(xy 91.971114 -284.818328) (xy 91.871038 -284.718252) (xy 91.770962 -284.818328) (xy 91.770962 -284.862778)
			(xy 91.971114 -284.862778)
		)
		(stroke
			(width 0)
			(type solid)
		)
		(fill yes)
		(layer "In2.Cu")
		(net "M_C_CPU1_SB_DQ<17>")
	)
	(gr_poly
		(pts
			(xy 91.971114 -284.414468) (xy 91.971114 -284.370018) (xy 91.770962 -284.370018) (xy 91.770962 -284.414468)
			(xy 91.871038 -284.514544)
		)
		(stroke
			(width 0)
			(type solid)
		)
		(fill yes)
		(layer "In2.Cu")
		(net "M_C_CPU1_SB_DQ<18>")
	)
	(gr_poly
		(pts
			(xy 91.971114 -283.198316) (xy 91.871038 -283.09824) (xy 91.770962 -283.198316) (xy 91.770962 -283.242766)
			(xy 91.971114 -283.242766)
		)
		(stroke
			(width 0)
			(type solid)
		)
		(fill yes)
		(layer "In2.Cu")
		(net "M_C_CPU1_SB_DQ<13>")
	)
	(gr_poly
		(pts
			(xy 91.971114 -282.794456) (xy 91.971114 -282.750006) (xy 91.770962 -282.750006) (xy 91.770962 -282.794456)
			(xy 91.871038 -282.894532)
		)
		(stroke
			(width 0)
			(type solid)
		)
		(fill yes)
		(layer "In2.Cu")
		(net "M_C_CPU1_SB_DQ<14>")
	)
	(gr_poly
		(pts
			(xy 91.971114 -281.57805) (xy 91.871038 -281.478228) (xy 91.770962 -281.57805) (xy 91.770962 -281.625802)
			(xy 91.971114 -281.625802)
		)
		(stroke
			(width 0)
			(type solid)
		)
		(fill yes)
		(layer "In2.Cu")
		(net "M_C_CPU1_SB_DQS_DN<6>")
	)
	(gr_poly
		(pts
			(xy 91.971114 -281.174698) (xy 91.971114 -281.126946) (xy 91.770962 -281.126946) (xy 91.770962 -281.174698)
			(xy 91.871038 -281.27452)
		)
		(stroke
			(width 0)
			(type solid)
		)
		(fill yes)
		(layer "In2.Cu")
		(net "M_C_CPU1_SB_DQS_DN<1>")
	)
	(gr_poly
		(pts
			(xy 91.971114 -279.958292) (xy 91.871038 -279.858216) (xy 91.770962 -279.958292) (xy 91.770962 -280.002742)
			(xy 91.971114 -280.002742)
		)
		(stroke
			(width 0)
			(type solid)
		)
		(fill yes)
		(layer "In2.Cu")
		(net "M_C_CPU1_SB_DQ<9>")
	)
	(gr_poly
		(pts
			(xy 91.971114 -279.554432) (xy 91.971114 -279.509982) (xy 91.770962 -279.509982) (xy 91.770962 -279.554432)
			(xy 91.871038 -279.654508)
		)
		(stroke
			(width 0)
			(type solid)
		)
		(fill yes)
		(layer "In2.Cu")
		(net "M_C_CPU1_SB_DQ<10>")
	)
	(gr_poly
		(pts
			(xy 91.971114 -278.33828) (xy 91.871038 -278.238204) (xy 91.770962 -278.33828) (xy 91.770962 -278.38273)
			(xy 91.971114 -278.38273)
		)
		(stroke
			(width 0)
			(type solid)
		)
		(fill yes)
		(layer "In2.Cu")
		(net "M_C_CPU1_SB_DQ<5>")
	)
	(gr_poly
		(pts
			(xy 91.971114 -277.93442) (xy 91.971114 -277.88997) (xy 91.770962 -277.88997) (xy 91.770962 -277.93442)
			(xy 91.871038 -278.034496)
		)
		(stroke
			(width 0)
			(type solid)
		)
		(fill yes)
		(layer "In2.Cu")
		(net "M_C_CPU1_SB_DQ<6>")
	)
	(gr_poly
		(pts
			(xy 91.971114 -276.718014) (xy 91.871038 -276.618192) (xy 91.770962 -276.718014) (xy 91.770962 -276.765766)
			(xy 91.971114 -276.765766)
		)
		(stroke
			(width 0)
			(type solid)
		)
		(fill yes)
		(layer "In2.Cu")
		(net "M_C_CPU1_SB_DQS_DN<5>")
	)
	(gr_poly
		(pts
			(xy 91.971114 -276.314662) (xy 91.971114 -276.26691) (xy 91.770962 -276.26691) (xy 91.770962 -276.314662)
			(xy 91.871038 -276.414484)
		)
		(stroke
			(width 0)
			(type solid)
		)
		(fill yes)
		(layer "In2.Cu")
		(net "M_C_CPU1_SB_DQS_DN<0>")
	)
	(gr_poly
		(pts
			(xy 91.971114 -275.098256) (xy 91.871038 -274.99818) (xy 91.770962 -275.098256) (xy 91.770962 -275.142706)
			(xy 91.971114 -275.142706)
		)
		(stroke
			(width 0)
			(type solid)
		)
		(fill yes)
		(layer "In2.Cu")
		(net "M_C_CPU1_SB_DQ<1>")
	)
	(gr_poly
		(pts
			(xy 91.971114 -274.694396) (xy 91.971114 -274.649946) (xy 91.770962 -274.649946) (xy 91.770962 -274.694396)
			(xy 91.871038 -274.794472)
		)
		(stroke
			(width 0)
			(type solid)
		)
		(fill yes)
		(layer "In2.Cu")
		(net "M_C_CPU1_SB_DQ<2>")
	)
	(gr_poly
		(pts
			(xy 91.971114 -273.478244) (xy 91.871038 -273.378168) (xy 91.770962 -273.478244) (xy 91.770962 -273.522694)
			(xy 91.971114 -273.522694)
		)
		(stroke
			(width 0)
			(type solid)
		)
		(fill yes)
		(layer "In2.Cu")
		(net "M_C_CPU1_SB_CB<1>")
	)
	(gr_poly
		(pts
			(xy 91.971114 -273.074384) (xy 91.971114 -273.029934) (xy 91.770962 -273.029934) (xy 91.770962 -273.074384)
			(xy 91.871038 -273.17446)
		)
		(stroke
			(width 0)
			(type solid)
		)
		(fill yes)
		(layer "In2.Cu")
		(net "M_C_CPU1_SB_CB<2>")
	)
	(gr_poly
		(pts
			(xy 91.971114 -271.857978) (xy 91.871038 -271.758156) (xy 91.770962 -271.857978) (xy 91.770962 -271.90573)
			(xy 91.971114 -271.90573)
		)
		(stroke
			(width 0)
			(type solid)
		)
		(fill yes)
		(layer "In2.Cu")
		(net "M_C_CPU1_SB_DQS_DN<4>")
	)
	(gr_poly
		(pts
			(xy 91.971114 -271.454626) (xy 91.971114 -271.406874) (xy 91.770962 -271.406874) (xy 91.770962 -271.454626)
			(xy 91.871038 -271.554448)
		)
		(stroke
			(width 0)
			(type solid)
		)
		(fill yes)
		(layer "In2.Cu")
		(net "M_C_CPU1_SB_DQS_DN<9>")
	)
	(gr_poly
		(pts
			(xy 91.971114 -270.23822) (xy 91.871038 -270.138144) (xy 91.770962 -270.23822) (xy 91.770962 -270.28267)
			(xy 91.971114 -270.28267)
		)
		(stroke
			(width 0)
			(type solid)
		)
		(fill yes)
		(layer "In2.Cu")
		(net "M_C_CPU1_SB_CB<5>")
	)
	(gr_poly
		(pts
			(xy 91.971114 -269.83436) (xy 91.971114 -269.78991) (xy 91.770962 -269.78991) (xy 91.770962 -269.83436)
			(xy 91.871038 -269.934436)
		)
		(stroke
			(width 0)
			(type solid)
		)
		(fill yes)
		(layer "In2.Cu")
		(net "M_C_CPU1_SB_CB<6>")
	)
	(gr_poly
		(pts
			(xy 91.971114 -266.991846) (xy 91.871038 -266.89177) (xy 91.770962 -266.991846) (xy 91.770962 -267.036296)
			(xy 91.971114 -267.036296)
		)
		(stroke
			(width 0)
			(type solid)
		)
		(fill yes)
		(layer "In2.Cu")
		(net "M_C_CPU1_SA_RSP<0>")
	)
	(gr_poly
		(pts
			(xy 91.971114 -266.594336) (xy 91.971114 -266.549886) (xy 91.770962 -266.549886) (xy 91.770962 -266.594336)
			(xy 91.871038 -266.694412)
		)
		(stroke
			(width 0)
			(type solid)
		)
		(fill yes)
		(layer "In2.Cu")
		(net "M_C_CPU1_SB_CS_N<1>")
	)
	(gr_poly
		(pts
			(xy 91.971114 -264.974324) (xy 91.971114 -264.929874) (xy 91.770962 -264.929874) (xy 91.770962 -264.974324)
			(xy 91.871038 -265.0744)
		)
		(stroke
			(width 0)
			(type solid)
		)
		(fill yes)
		(layer "In2.Cu")
		(net "M_C_CPU1_SB_PAR")
	)
	(gr_poly
		(pts
			(xy 91.971114 -263.758172) (xy 91.871038 -263.658096) (xy 91.770962 -263.758172) (xy 91.770962 -263.802622)
			(xy 91.971114 -263.802622)
		)
		(stroke
			(width 0)
			(type solid)
		)
		(fill yes)
		(layer "In2.Cu")
		(net "M_C_CPU1_SB_CA<4>")
	)
	(gr_poly
		(pts
			(xy 91.971114 -263.354312) (xy 91.971114 -263.309862) (xy 91.770962 -263.309862) (xy 91.770962 -263.354312)
			(xy 91.871038 -263.454388)
		)
		(stroke
			(width 0)
			(type solid)
		)
		(fill yes)
		(layer "In2.Cu")
		(net "M_C_CPU1_SB_CA<3>")
	)
	(gr_poly
		(pts
			(xy 91.971114 -262.13816) (xy 91.871038 -262.038084) (xy 91.770962 -262.13816) (xy 91.770962 -262.18261)
			(xy 91.971114 -262.18261)
		)
		(stroke
			(width 0)
			(type solid)
		)
		(fill yes)
		(layer "In2.Cu")
		(net "M_C_CPU1_SB_CA<0>")
	)
	(gr_poly
		(pts
			(xy 92.140786 -246.712486) (xy 92.140786 -246.664988) (xy 91.940888 -246.664988) (xy 91.940888 -246.712486)
			(xy 92.04071 -246.812562)
		)
		(stroke
			(width 0)
			(type solid)
		)
		(fill yes)
		(layer "In2.Cu")
		(net "M_C_CPU1_SA_DQS_DN<4>")
	)
	(gr_poly
		(pts
			(xy 92.14104 -256.432812) (xy 92.14104 -256.38506) (xy 91.940888 -256.38506) (xy 91.940888 -256.432812)
			(xy 92.040964 -256.532634)
		)
		(stroke
			(width 0)
			(type solid)
		)
		(fill yes)
		(layer "In2.Cu")
		(net "M_C_CPU1_CLK_DN<0>")
	)
	(gr_poly
		(pts
			(xy 92.14104 -255.216406) (xy 92.040964 -255.11633) (xy 91.940888 -255.216406) (xy 91.940888 -255.260856)
			(xy 92.14104 -255.260856)
		)
		(stroke
			(width 0)
			(type solid)
		)
		(fill yes)
		(layer "In2.Cu")
		(net "M_C_CPU1_SA_CA<6>")
	)
	(gr_poly
		(pts
			(xy 92.14104 -254.812546) (xy 92.14104 -254.768096) (xy 91.940888 -254.768096) (xy 91.940888 -254.812546)
			(xy 92.040964 -254.912622)
		)
		(stroke
			(width 0)
			(type solid)
		)
		(fill yes)
		(layer "In2.Cu")
		(net "M_C_CPU1_SA_CA<5>")
	)
	(gr_poly
		(pts
			(xy 92.14104 -253.596394) (xy 92.040964 -253.496318) (xy 91.940888 -253.596394) (xy 91.940888 -253.640844)
			(xy 92.14104 -253.640844)
		)
		(stroke
			(width 0)
			(type solid)
		)
		(fill yes)
		(layer "In2.Cu")
		(net "M_C_CPU1_SA_CA<2>")
	)
	(gr_poly
		(pts
			(xy 92.14104 -253.192534) (xy 92.14104 -253.148084) (xy 91.940888 -253.148084) (xy 91.940888 -253.192534)
			(xy 92.040964 -253.29261)
		)
		(stroke
			(width 0)
			(type solid)
		)
		(fill yes)
		(layer "In2.Cu")
		(net "M_C_CPU1_SA_CA<1>")
	)
	(gr_poly
		(pts
			(xy 92.14104 -251.572522) (xy 92.14104 -251.528072) (xy 91.940888 -251.528072) (xy 91.940888 -251.572522)
			(xy 92.040964 -251.672598)
		)
		(stroke
			(width 0)
			(type solid)
		)
		(fill yes)
		(layer "In2.Cu")
		(net "M_C_CPU1_SA_CS_N<0>")
	)
	(gr_poly
		(pts
			(xy 92.14104 -250.35637) (xy 92.040964 -250.256294) (xy 91.940888 -250.35637) (xy 91.940888 -250.40082)
			(xy 92.14104 -250.40082)
		)
		(stroke
			(width 0)
			(type solid)
		)
		(fill yes)
		(layer "In2.Cu")
		(net "M_C_CPU1_ALERT_R_N")
	)
	(gr_poly
		(pts
			(xy 92.14104 -248.736358) (xy 92.040964 -248.636282) (xy 91.940888 -248.736358) (xy 91.940888 -248.780808)
			(xy 92.14104 -248.780808)
		)
		(stroke
			(width 0)
			(type solid)
		)
		(fill yes)
		(layer "In2.Cu")
		(net "M_C_CPU1_SA_CB<5>")
	)
	(gr_poly
		(pts
			(xy 92.14104 -248.332498) (xy 92.14104 -248.288048) (xy 91.940888 -248.288048) (xy 91.940888 -248.332498)
			(xy 92.040964 -248.432574)
		)
		(stroke
			(width 0)
			(type solid)
		)
		(fill yes)
		(layer "In2.Cu")
		(net "M_C_CPU1_SA_CB<6>")
	)
	(gr_poly
		(pts
			(xy 92.14104 -247.116092) (xy 92.040964 -247.01627) (xy 91.940888 -247.116092) (xy 91.940888 -247.163844)
			(xy 92.14104 -247.163844)
		)
		(stroke
			(width 0)
			(type solid)
		)
		(fill yes)
		(layer "In2.Cu")
		(net "M_C_CPU1_SA_DQS_DN<9>")
	)
	(gr_poly
		(pts
			(xy 92.14104 -245.496334) (xy 92.040964 -245.396258) (xy 91.940888 -245.496334) (xy 91.940888 -245.540784)
			(xy 92.14104 -245.540784)
		)
		(stroke
			(width 0)
			(type solid)
		)
		(fill yes)
		(layer "In2.Cu")
		(net "M_C_CPU1_SA_CB<1>")
	)
	(gr_poly
		(pts
			(xy 92.14104 -245.092474) (xy 92.14104 -245.048024) (xy 91.940888 -245.048024) (xy 91.940888 -245.092474)
			(xy 92.040964 -245.19255)
		)
		(stroke
			(width 0)
			(type solid)
		)
		(fill yes)
		(layer "In2.Cu")
		(net "M_C_CPU1_SA_CB<2>")
	)
	(gr_poly
		(pts
			(xy 92.14104 -243.876322) (xy 92.040964 -243.776246) (xy 91.940888 -243.876322) (xy 91.940888 -243.920772)
			(xy 92.14104 -243.920772)
		)
		(stroke
			(width 0)
			(type solid)
		)
		(fill yes)
		(layer "In2.Cu")
		(net "M_C_CPU1_SA_DQ<29>")
	)
	(gr_poly
		(pts
			(xy 92.14104 -243.472462) (xy 92.14104 -243.428012) (xy 91.940888 -243.428012) (xy 91.940888 -243.472462)
			(xy 92.040964 -243.572538)
		)
		(stroke
			(width 0)
			(type solid)
		)
		(fill yes)
		(layer "In2.Cu")
		(net "M_C_CPU1_SA_DQ<30>")
	)
	(gr_poly
		(pts
			(xy 92.14104 -242.256056) (xy 92.040964 -242.156234) (xy 91.940888 -242.256056) (xy 91.940888 -242.303808)
			(xy 92.14104 -242.303808)
		)
		(stroke
			(width 0)
			(type solid)
		)
		(fill yes)
		(layer "In2.Cu")
		(net "M_C_CPU1_SA_DQS_DN<8>")
	)
	(gr_poly
		(pts
			(xy 92.14104 -241.852704) (xy 92.14104 -241.804952) (xy 91.940888 -241.804952) (xy 91.940888 -241.852704)
			(xy 92.040964 -241.952526)
		)
		(stroke
			(width 0)
			(type solid)
		)
		(fill yes)
		(layer "In2.Cu")
		(net "M_C_CPU1_SA_DQS_DN<3>")
	)
	(gr_poly
		(pts
			(xy 92.14104 -240.636298) (xy 92.040964 -240.536222) (xy 91.940888 -240.636298) (xy 91.940888 -240.680748)
			(xy 92.14104 -240.680748)
		)
		(stroke
			(width 0)
			(type solid)
		)
		(fill yes)
		(layer "In2.Cu")
		(net "M_C_CPU1_SA_DQ<25>")
	)
	(gr_poly
		(pts
			(xy 92.14104 -240.232438) (xy 92.14104 -240.187988) (xy 91.940888 -240.187988) (xy 91.940888 -240.232438)
			(xy 92.040964 -240.332514)
		)
		(stroke
			(width 0)
			(type solid)
		)
		(fill yes)
		(layer "In2.Cu")
		(net "M_C_CPU1_SA_DQ<26>")
	)
	(gr_poly
		(pts
			(xy 92.14104 -239.016286) (xy 92.040964 -238.91621) (xy 91.940888 -239.016286) (xy 91.940888 -239.060736)
			(xy 92.14104 -239.060736)
		)
		(stroke
			(width 0)
			(type solid)
		)
		(fill yes)
		(layer "In2.Cu")
		(net "M_C_CPU1_SA_DQ<21>")
	)
	(gr_poly
		(pts
			(xy 92.14104 -238.612426) (xy 92.14104 -238.567976) (xy 91.940888 -238.567976) (xy 91.940888 -238.612426)
			(xy 92.040964 -238.712502)
		)
		(stroke
			(width 0)
			(type solid)
		)
		(fill yes)
		(layer "In2.Cu")
		(net "M_C_CPU1_SA_DQ<22>")
	)
	(gr_poly
		(pts
			(xy 92.14104 -237.39602) (xy 92.040964 -237.296198) (xy 91.940888 -237.39602) (xy 91.940888 -237.443772)
			(xy 92.14104 -237.443772)
		)
		(stroke
			(width 0)
			(type solid)
		)
		(fill yes)
		(layer "In2.Cu")
		(net "M_C_CPU1_SA_DQS_DN<7>")
	)
	(gr_poly
		(pts
			(xy 92.14104 -236.992668) (xy 92.14104 -236.944916) (xy 91.940888 -236.944916) (xy 91.940888 -236.992668)
			(xy 92.040964 -237.09249)
		)
		(stroke
			(width 0)
			(type solid)
		)
		(fill yes)
		(layer "In2.Cu")
		(net "M_C_CPU1_SA_DQS_DN<2>")
	)
	(gr_poly
		(pts
			(xy 92.14104 -235.776262) (xy 92.040964 -235.676186) (xy 91.940888 -235.776262) (xy 91.940888 -235.820712)
			(xy 92.14104 -235.820712)
		)
		(stroke
			(width 0)
			(type solid)
		)
		(fill yes)
		(layer "In2.Cu")
		(net "M_C_CPU1_SA_DQ<17>")
	)
	(gr_poly
		(pts
			(xy 92.14104 -235.372402) (xy 92.14104 -235.327952) (xy 91.940888 -235.327952) (xy 91.940888 -235.372402)
			(xy 92.040964 -235.472478)
		)
		(stroke
			(width 0)
			(type solid)
		)
		(fill yes)
		(layer "In2.Cu")
		(net "M_C_CPU1_SA_DQ<18>")
	)
	(gr_poly
		(pts
			(xy 92.14104 -234.15625) (xy 92.040964 -234.056174) (xy 91.940888 -234.15625) (xy 91.940888 -234.2007)
			(xy 92.14104 -234.2007)
		)
		(stroke
			(width 0)
			(type solid)
		)
		(fill yes)
		(layer "In2.Cu")
		(net "M_C_CPU1_SA_DQ<13>")
	)
	(gr_poly
		(pts
			(xy 92.14104 -233.75239) (xy 92.14104 -233.70794) (xy 91.940888 -233.70794) (xy 91.940888 -233.75239)
			(xy 92.040964 -233.852466)
		)
		(stroke
			(width 0)
			(type solid)
		)
		(fill yes)
		(layer "In2.Cu")
		(net "M_C_CPU1_SA_DQ<14>")
	)
	(gr_poly
		(pts
			(xy 92.14104 -232.535984) (xy 92.040964 -232.436162) (xy 91.940888 -232.535984) (xy 91.940888 -232.583736)
			(xy 92.14104 -232.583736)
		)
		(stroke
			(width 0)
			(type solid)
		)
		(fill yes)
		(layer "In2.Cu")
		(net "M_C_CPU1_SA_DQS_DN<6>")
	)
	(gr_poly
		(pts
			(xy 92.14104 -232.132632) (xy 92.14104 -232.08488) (xy 91.940888 -232.08488) (xy 91.940888 -232.132632)
			(xy 92.040964 -232.232454)
		)
		(stroke
			(width 0)
			(type solid)
		)
		(fill yes)
		(layer "In2.Cu")
		(net "M_C_CPU1_SA_DQS_DN<1>")
	)
	(gr_poly
		(pts
			(xy 92.14104 -230.916226) (xy 92.040964 -230.81615) (xy 91.940888 -230.916226) (xy 91.940888 -230.960676)
			(xy 92.14104 -230.960676)
		)
		(stroke
			(width 0)
			(type solid)
		)
		(fill yes)
		(layer "In2.Cu")
		(net "M_C_CPU1_SA_DQ<9>")
	)
	(gr_poly
		(pts
			(xy 92.14104 -230.51262) (xy 92.14104 -230.46817) (xy 91.940888 -230.46817) (xy 91.940888 -230.51262)
			(xy 92.040964 -230.612696)
		)
		(stroke
			(width 0)
			(type solid)
		)
		(fill yes)
		(layer "In2.Cu")
		(net "M_C_CPU1_SA_DQ<10>")
	)
	(gr_poly
		(pts
			(xy 92.14104 -229.296214) (xy 92.040964 -229.196138) (xy 91.940888 -229.296214) (xy 91.940888 -229.340664)
			(xy 92.14104 -229.340664)
		)
		(stroke
			(width 0)
			(type solid)
		)
		(fill yes)
		(layer "In2.Cu")
		(net "M_C_CPU1_SA_DQ<5>")
	)
	(gr_poly
		(pts
			(xy 92.14104 -228.892608) (xy 92.14104 -228.848158) (xy 91.940888 -228.848158) (xy 91.940888 -228.892608)
			(xy 92.040964 -228.992684)
		)
		(stroke
			(width 0)
			(type solid)
		)
		(fill yes)
		(layer "In2.Cu")
		(net "M_C_CPU1_SA_DQ<6>")
	)
	(gr_poly
		(pts
			(xy 92.14104 -227.676202) (xy 92.040964 -227.57638) (xy 91.940888 -227.676202) (xy 91.940888 -227.723954)
			(xy 92.14104 -227.723954)
		)
		(stroke
			(width 0)
			(type solid)
		)
		(fill yes)
		(layer "In2.Cu")
		(net "M_C_CPU1_SA_DQS_DN<5>")
	)
	(gr_poly
		(pts
			(xy 92.14104 -227.27285) (xy 92.14104 -227.225098) (xy 91.940888 -227.225098) (xy 91.940888 -227.27285)
			(xy 92.040964 -227.372672)
		)
		(stroke
			(width 0)
			(type solid)
		)
		(fill yes)
		(layer "In2.Cu")
		(net "M_C_CPU1_SA_DQS_DN<0>")
	)
	(gr_poly
		(pts
			(xy 92.14104 -226.056444) (xy 92.040964 -225.956368) (xy 91.940888 -226.056444) (xy 91.940888 -226.100894)
			(xy 92.14104 -226.100894)
		)
		(stroke
			(width 0)
			(type solid)
		)
		(fill yes)
		(layer "In2.Cu")
		(net "M_C_CPU1_SA_DQ<1>")
	)
	(gr_poly
		(pts
			(xy 92.14104 -225.652584) (xy 92.14104 -225.608134) (xy 91.940888 -225.608134) (xy 91.940888 -225.652584)
			(xy 92.040964 -225.75266)
		)
		(stroke
			(width 0)
			(type solid)
		)
		(fill yes)
		(layer "In2.Cu")
		(net "M_C_CPU1_SA_DQ<2>")
	)
	(gr_poly
		(pts
			(xy 92.441014 -293.32428) (xy 92.441014 -293.27983) (xy 92.240862 -293.27983) (xy 92.240862 -293.32428)
			(xy 92.340938 -293.424356)
		)
		(stroke
			(width 0)
			(type solid)
		)
		(fill yes)
		(layer "In2.Cu")
		(net "M_C_CPU1_SB_DQ<31>")
	)
	(gr_poly
		(pts
			(xy 92.441014 -292.108128) (xy 92.340938 -292.008052) (xy 92.240862 -292.108128) (xy 92.240862 -292.152578)
			(xy 92.441014 -292.152578)
		)
		(stroke
			(width 0)
			(type solid)
		)
		(fill yes)
		(layer "In2.Cu")
		(net "M_C_CPU1_SB_DQ<28>")
	)
	(gr_poly
		(pts
			(xy 92.441014 -291.704522) (xy 92.441014 -291.65677) (xy 92.240862 -291.65677) (xy 92.240862 -291.704522)
			(xy 92.340938 -291.804344)
		)
		(stroke
			(width 0)
			(type solid)
		)
		(fill yes)
		(layer "In2.Cu")
		(net "M_C_CPU1_SB_DQS_DP<8>")
	)
	(gr_poly
		(pts
			(xy 92.441014 -290.487862) (xy 92.340938 -290.38804) (xy 92.240862 -290.487862) (xy 92.240862 -290.535614)
			(xy 92.441014 -290.535614)
		)
		(stroke
			(width 0)
			(type solid)
		)
		(fill yes)
		(layer "In2.Cu")
		(net "M_C_CPU1_SB_DQS_DP<3>")
	)
	(gr_poly
		(pts
			(xy 92.441014 -290.084256) (xy 92.441014 -290.039806) (xy 92.240862 -290.039806) (xy 92.240862 -290.084256)
			(xy 92.340938 -290.184332)
		)
		(stroke
			(width 0)
			(type solid)
		)
		(fill yes)
		(layer "In2.Cu")
		(net "M_C_CPU1_SB_DQ<27>")
	)
	(gr_poly
		(pts
			(xy 92.441014 -288.868104) (xy 92.340938 -288.768028) (xy 92.240862 -288.868104) (xy 92.240862 -288.912554)
			(xy 92.441014 -288.912554)
		)
		(stroke
			(width 0)
			(type solid)
		)
		(fill yes)
		(layer "In2.Cu")
		(net "M_C_CPU1_SB_DQ<24>")
	)
	(gr_poly
		(pts
			(xy 92.441014 -288.464498) (xy 92.441014 -288.420048) (xy 92.240862 -288.420048) (xy 92.240862 -288.464498)
			(xy 92.340938 -288.564574)
		)
		(stroke
			(width 0)
			(type solid)
		)
		(fill yes)
		(layer "In2.Cu")
		(net "M_C_CPU1_SB_DQ<23>")
	)
	(gr_poly
		(pts
			(xy 92.441014 -287.248092) (xy 92.340938 -287.148016) (xy 92.240862 -287.248092) (xy 92.240862 -287.292542)
			(xy 92.441014 -287.292542)
		)
		(stroke
			(width 0)
			(type solid)
		)
		(fill yes)
		(layer "In2.Cu")
		(net "M_C_CPU1_SB_DQ<20>")
	)
	(gr_poly
		(pts
			(xy 92.441014 -286.844486) (xy 92.441014 -286.796734) (xy 92.240862 -286.796734) (xy 92.240862 -286.844486)
			(xy 92.340938 -286.944562)
		)
		(stroke
			(width 0)
			(type solid)
		)
		(fill yes)
		(layer "In2.Cu")
		(net "M_C_CPU1_SB_DQS_DP<7>")
	)
	(gr_poly
		(pts
			(xy 92.441014 -285.62808) (xy 92.340938 -285.528258) (xy 92.240862 -285.62808) (xy 92.240862 -285.675832)
			(xy 92.441014 -285.675832)
		)
		(stroke
			(width 0)
			(type solid)
		)
		(fill yes)
		(layer "In2.Cu")
		(net "M_C_CPU1_SB_DQS_DP<2>")
	)
	(gr_poly
		(pts
			(xy 92.441014 -285.224474) (xy 92.441014 -285.180024) (xy 92.240862 -285.180024) (xy 92.240862 -285.224474)
			(xy 92.340938 -285.32455)
		)
		(stroke
			(width 0)
			(type solid)
		)
		(fill yes)
		(layer "In2.Cu")
		(net "M_C_CPU1_SB_DQ<19>")
	)
	(gr_poly
		(pts
			(xy 92.441014 -284.008322) (xy 92.340938 -283.908246) (xy 92.240862 -284.008322) (xy 92.240862 -284.052772)
			(xy 92.441014 -284.052772)
		)
		(stroke
			(width 0)
			(type solid)
		)
		(fill yes)
		(layer "In2.Cu")
		(net "M_C_CPU1_SB_DQ<16>")
	)
	(gr_poly
		(pts
			(xy 92.441014 -283.604462) (xy 92.441014 -283.560012) (xy 92.240862 -283.560012) (xy 92.240862 -283.604462)
			(xy 92.340938 -283.704538)
		)
		(stroke
			(width 0)
			(type solid)
		)
		(fill yes)
		(layer "In2.Cu")
		(net "M_C_CPU1_SB_DQ<15>")
	)
	(gr_poly
		(pts
			(xy 92.441014 -282.38831) (xy 92.340938 -282.288234) (xy 92.240862 -282.38831) (xy 92.240862 -282.43276)
			(xy 92.441014 -282.43276)
		)
		(stroke
			(width 0)
			(type solid)
		)
		(fill yes)
		(layer "In2.Cu")
		(net "M_C_CPU1_SB_DQ<12>")
	)
	(gr_poly
		(pts
			(xy 92.441014 -281.984704) (xy 92.441014 -281.936952) (xy 92.240862 -281.936952) (xy 92.240862 -281.984704)
			(xy 92.340938 -282.084526)
		)
		(stroke
			(width 0)
			(type solid)
		)
		(fill yes)
		(layer "In2.Cu")
		(net "M_C_CPU1_SB_DQS_DP<6>")
	)
	(gr_poly
		(pts
			(xy 92.441014 -280.768044) (xy 92.340938 -280.668222) (xy 92.240862 -280.768044) (xy 92.240862 -280.815796)
			(xy 92.441014 -280.815796)
		)
		(stroke
			(width 0)
			(type solid)
		)
		(fill yes)
		(layer "In2.Cu")
		(net "M_C_CPU1_SB_DQS_DP<1>")
	)
	(gr_poly
		(pts
			(xy 92.441014 -280.364438) (xy 92.441014 -280.319988) (xy 92.240862 -280.319988) (xy 92.240862 -280.364438)
			(xy 92.340938 -280.464514)
		)
		(stroke
			(width 0)
			(type solid)
		)
		(fill yes)
		(layer "In2.Cu")
		(net "M_C_CPU1_SB_DQ<11>")
	)
	(gr_poly
		(pts
			(xy 92.441014 -279.148286) (xy 92.340938 -279.04821) (xy 92.240862 -279.148286) (xy 92.240862 -279.192736)
			(xy 92.441014 -279.192736)
		)
		(stroke
			(width 0)
			(type solid)
		)
		(fill yes)
		(layer "In2.Cu")
		(net "M_C_CPU1_SB_DQ<8>")
	)
	(gr_poly
		(pts
			(xy 92.441014 -278.744426) (xy 92.441014 -278.699976) (xy 92.240862 -278.699976) (xy 92.240862 -278.744426)
			(xy 92.340938 -278.844502)
		)
		(stroke
			(width 0)
			(type solid)
		)
		(fill yes)
		(layer "In2.Cu")
		(net "M_C_CPU1_SB_DQ<7>")
	)
	(gr_poly
		(pts
			(xy 92.441014 -277.528274) (xy 92.340938 -277.428198) (xy 92.240862 -277.528274) (xy 92.240862 -277.572724)
			(xy 92.441014 -277.572724)
		)
		(stroke
			(width 0)
			(type solid)
		)
		(fill yes)
		(layer "In2.Cu")
		(net "M_C_CPU1_SB_DQ<4>")
	)
	(gr_poly
		(pts
			(xy 92.441014 -277.124668) (xy 92.441014 -277.076916) (xy 92.240862 -277.076916) (xy 92.240862 -277.124668)
			(xy 92.340938 -277.22449)
		)
		(stroke
			(width 0)
			(type solid)
		)
		(fill yes)
		(layer "In2.Cu")
		(net "M_C_CPU1_SB_DQS_DP<5>")
	)
	(gr_poly
		(pts
			(xy 92.441014 -275.908008) (xy 92.340938 -275.808186) (xy 92.240862 -275.908008) (xy 92.240862 -275.95576)
			(xy 92.441014 -275.95576)
		)
		(stroke
			(width 0)
			(type solid)
		)
		(fill yes)
		(layer "In2.Cu")
		(net "M_C_CPU1_SB_DQS_DP<0>")
	)
	(gr_poly
		(pts
			(xy 92.441014 -275.504402) (xy 92.441014 -275.459952) (xy 92.240862 -275.459952) (xy 92.240862 -275.504402)
			(xy 92.340938 -275.604478)
		)
		(stroke
			(width 0)
			(type solid)
		)
		(fill yes)
		(layer "In2.Cu")
		(net "M_C_CPU1_SB_DQ<3>")
	)
	(gr_poly
		(pts
			(xy 92.441014 -274.28825) (xy 92.340938 -274.188174) (xy 92.240862 -274.28825) (xy 92.240862 -274.3327)
			(xy 92.441014 -274.3327)
		)
		(stroke
			(width 0)
			(type solid)
		)
		(fill yes)
		(layer "In2.Cu")
		(net "M_C_CPU1_SB_DQ<0>")
	)
	(gr_poly
		(pts
			(xy 92.441014 -273.88439) (xy 92.441014 -273.83994) (xy 92.240862 -273.83994) (xy 92.240862 -273.88439)
			(xy 92.340938 -273.984466)
		)
		(stroke
			(width 0)
			(type solid)
		)
		(fill yes)
		(layer "In2.Cu")
		(net "M_C_CPU1_SB_CB<3>")
	)
	(gr_poly
		(pts
			(xy 92.441014 -272.668238) (xy 92.340938 -272.568162) (xy 92.240862 -272.668238) (xy 92.240862 -272.712688)
			(xy 92.441014 -272.712688)
		)
		(stroke
			(width 0)
			(type solid)
		)
		(fill yes)
		(layer "In2.Cu")
		(net "M_C_CPU1_SB_CB<0>")
	)
	(gr_poly
		(pts
			(xy 92.441014 -272.264632) (xy 92.441014 -272.21688) (xy 92.240862 -272.21688) (xy 92.240862 -272.264632)
			(xy 92.340938 -272.364454)
		)
		(stroke
			(width 0)
			(type solid)
		)
		(fill yes)
		(layer "In2.Cu")
		(net "M_C_CPU1_SB_DQS_DP<4>")
	)
	(gr_poly
		(pts
			(xy 92.441014 -271.047972) (xy 92.340938 -270.94815) (xy 92.240862 -271.047972) (xy 92.240862 -271.095724)
			(xy 92.441014 -271.095724)
		)
		(stroke
			(width 0)
			(type solid)
		)
		(fill yes)
		(layer "In2.Cu")
		(net "M_C_CPU1_SB_DQS_DP<9>")
	)
	(gr_poly
		(pts
			(xy 92.441014 -270.644366) (xy 92.441014 -270.599916) (xy 92.240862 -270.599916) (xy 92.240862 -270.644366)
			(xy 92.340938 -270.744442)
		)
		(stroke
			(width 0)
			(type solid)
		)
		(fill yes)
		(layer "In2.Cu")
		(net "M_C_CPU1_SB_CB<7>")
	)
	(gr_poly
		(pts
			(xy 92.441014 -269.428214) (xy 92.340938 -269.328138) (xy 92.240862 -269.428214) (xy 92.240862 -269.472664)
			(xy 92.441014 -269.472664)
		)
		(stroke
			(width 0)
			(type solid)
		)
		(fill yes)
		(layer "In2.Cu")
		(net "M_C_CPU1_SB_CB<4>")
	)
	(gr_poly
		(pts
			(xy 92.441014 -265.78433) (xy 92.441014 -265.73988) (xy 92.240862 -265.73988) (xy 92.240862 -265.78433)
			(xy 92.340938 -265.884406)
		)
		(stroke
			(width 0)
			(type solid)
		)
		(fill yes)
		(layer "In2.Cu")
		(net "M_C_CPU1_SB_CS_N<0>")
	)
	(gr_poly
		(pts
			(xy 92.441014 -264.568178) (xy 92.340938 -264.468102) (xy 92.240862 -264.568178) (xy 92.240862 -264.612628)
			(xy 92.441014 -264.612628)
		)
		(stroke
			(width 0)
			(type solid)
		)
		(fill yes)
		(layer "In2.Cu")
		(net "M_C_CPU1_SB_CA<6>")
	)
	(gr_poly
		(pts
			(xy 92.441014 -264.164318) (xy 92.441014 -264.119868) (xy 92.240862 -264.119868) (xy 92.240862 -264.164318)
			(xy 92.340938 -264.264394)
		)
		(stroke
			(width 0)
			(type solid)
		)
		(fill yes)
		(layer "In2.Cu")
		(net "M_C_CPU1_SB_CA<5>")
	)
	(gr_poly
		(pts
			(xy 92.441014 -262.948166) (xy 92.340938 -262.84809) (xy 92.240862 -262.948166) (xy 92.240862 -262.992616)
			(xy 92.441014 -262.992616)
		)
		(stroke
			(width 0)
			(type solid)
		)
		(fill yes)
		(layer "In2.Cu")
		(net "M_C_CPU1_SB_CA<2>")
	)
	(gr_poly
		(pts
			(xy 92.441014 -262.544306) (xy 92.441014 -262.499856) (xy 92.240862 -262.499856) (xy 92.240862 -262.544306)
			(xy 92.340938 -262.644382)
		)
		(stroke
			(width 0)
			(type solid)
		)
		(fill yes)
		(layer "In2.Cu")
		(net "M_C_CPU1_SB_CA<1>")
	)
	(gr_poly
		(pts
			(xy 92.44711 -267.801852) (xy 92.347288 -267.701776) (xy 92.247212 -267.801852) (xy 92.247212 -267.846302)
			(xy 92.44711 -267.846302)
		)
		(stroke
			(width 0)
			(type solid)
		)
		(fill yes)
		(layer "In2.Cu")
		(net "M_C_CPU1_SB_RSP<0>")
	)
	(gr_poly
		(pts
			(xy 92.611194 -256.026158) (xy 92.511118 -255.926336) (xy 92.411042 -256.026158) (xy 92.411042 -256.07391)
			(xy 92.611194 -256.07391)
		)
		(stroke
			(width 0)
			(type solid)
		)
		(fill yes)
		(layer "In2.Cu")
		(net "M_C_CPU1_CLK_DP<0>")
	)
	(gr_poly
		(pts
			(xy 92.611194 -255.622552) (xy 92.611194 -255.578102) (xy 92.411042 -255.578102) (xy 92.411042 -255.622552)
			(xy 92.511118 -255.722628)
		)
		(stroke
			(width 0)
			(type solid)
		)
		(fill yes)
		(layer "In2.Cu")
		(net "M_C_CPU1_SA_PAR")
	)
	(gr_poly
		(pts
			(xy 92.611194 -254.4064) (xy 92.511118 -254.306324) (xy 92.411042 -254.4064) (xy 92.411042 -254.45085)
			(xy 92.611194 -254.45085)
		)
		(stroke
			(width 0)
			(type solid)
		)
		(fill yes)
		(layer "In2.Cu")
		(net "M_C_CPU1_SA_CA<4>")
	)
	(gr_poly
		(pts
			(xy 92.611194 -254.00254) (xy 92.611194 -253.95809) (xy 92.411042 -253.95809) (xy 92.411042 -254.00254)
			(xy 92.511118 -254.102616)
		)
		(stroke
			(width 0)
			(type solid)
		)
		(fill yes)
		(layer "In2.Cu")
		(net "M_C_CPU1_SA_CA<3>")
	)
	(gr_poly
		(pts
			(xy 92.611194 -252.786388) (xy 92.511118 -252.686312) (xy 92.411042 -252.786388) (xy 92.411042 -252.830838)
			(xy 92.611194 -252.830838)
		)
		(stroke
			(width 0)
			(type solid)
		)
		(fill yes)
		(layer "In2.Cu")
		(net "M_C_CPU1_SA_CA<0>")
	)
	(gr_poly
		(pts
			(xy 92.611194 -252.382528) (xy 92.611194 -252.338078) (xy 92.411042 -252.338078) (xy 92.411042 -252.382528)
			(xy 92.511118 -252.482604)
		)
		(stroke
			(width 0)
			(type solid)
		)
		(fill yes)
		(layer "In2.Cu")
		(net "M_C_CPU1_SA_CS_N<1>")
	)
	(gr_poly
		(pts
			(xy 92.611194 -250.762516) (xy 92.611194 -250.718066) (xy 92.411042 -250.718066) (xy 92.411042 -250.762516)
			(xy 92.511118 -250.862592)
		)
		(stroke
			(width 0)
			(type solid)
		)
		(fill yes)
		(layer "In2.Cu")
		(net "M_C_CPU1_RESET_N")
	)
	(gr_poly
		(pts
			(xy 92.611194 -249.142504) (xy 92.611194 -249.098054) (xy 92.411042 -249.098054) (xy 92.411042 -249.142504)
			(xy 92.511118 -249.24258)
		)
		(stroke
			(width 0)
			(type solid)
		)
		(fill yes)
		(layer "In2.Cu")
		(net "M_C_CPU1_SA_CB<7>")
	)
	(gr_poly
		(pts
			(xy 92.611194 -247.926352) (xy 92.511118 -247.826276) (xy 92.411042 -247.926352) (xy 92.411042 -247.970802)
			(xy 92.611194 -247.970802)
		)
		(stroke
			(width 0)
			(type solid)
		)
		(fill yes)
		(layer "In2.Cu")
		(net "M_C_CPU1_SA_CB<4>")
	)
	(gr_poly
		(pts
			(xy 92.611194 -247.522746) (xy 92.611194 -247.474994) (xy 92.411042 -247.474994) (xy 92.411042 -247.522746)
			(xy 92.511118 -247.622568)
		)
		(stroke
			(width 0)
			(type solid)
		)
		(fill yes)
		(layer "In2.Cu")
		(net "M_C_CPU1_SA_DQS_DP<9>")
	)
	(gr_poly
		(pts
			(xy 92.611194 -246.306086) (xy 92.511118 -246.206264) (xy 92.411042 -246.306086) (xy 92.411042 -246.353838)
			(xy 92.611194 -246.353838)
		)
		(stroke
			(width 0)
			(type solid)
		)
		(fill yes)
		(layer "In2.Cu")
		(net "M_C_CPU1_SA_DQS_DP<4>")
	)
	(gr_poly
		(pts
			(xy 92.611194 -245.90248) (xy 92.611194 -245.85803) (xy 92.411042 -245.85803) (xy 92.411042 -245.90248)
			(xy 92.511118 -246.002556)
		)
		(stroke
			(width 0)
			(type solid)
		)
		(fill yes)
		(layer "In2.Cu")
		(net "M_C_CPU1_SA_CB<3>")
	)
	(gr_poly
		(pts
			(xy 92.611194 -244.686328) (xy 92.511118 -244.586252) (xy 92.411042 -244.686328) (xy 92.411042 -244.730778)
			(xy 92.611194 -244.730778)
		)
		(stroke
			(width 0)
			(type solid)
		)
		(fill yes)
		(layer "In2.Cu")
		(net "M_C_CPU1_SA_CB<0>")
	)
	(gr_poly
		(pts
			(xy 92.611194 -244.282468) (xy 92.611194 -244.238018) (xy 92.411042 -244.238018) (xy 92.411042 -244.282468)
			(xy 92.511118 -244.382544)
		)
		(stroke
			(width 0)
			(type solid)
		)
		(fill yes)
		(layer "In2.Cu")
		(net "M_C_CPU1_SA_DQ<31>")
	)
	(gr_poly
		(pts
			(xy 92.611194 -243.066316) (xy 92.511118 -242.96624) (xy 92.411042 -243.066316) (xy 92.411042 -243.110766)
			(xy 92.611194 -243.110766)
		)
		(stroke
			(width 0)
			(type solid)
		)
		(fill yes)
		(layer "In2.Cu")
		(net "M_C_CPU1_SA_DQ<28>")
	)
	(gr_poly
		(pts
			(xy 92.611194 -242.66271) (xy 92.611194 -242.614958) (xy 92.411042 -242.614958) (xy 92.411042 -242.66271)
			(xy 92.511118 -242.762532)
		)
		(stroke
			(width 0)
			(type solid)
		)
		(fill yes)
		(layer "In2.Cu")
		(net "M_C_CPU1_SA_DQS_DP<8>")
	)
	(gr_poly
		(pts
			(xy 92.611194 -241.44605) (xy 92.511118 -241.346228) (xy 92.411042 -241.44605) (xy 92.411042 -241.493802)
			(xy 92.611194 -241.493802)
		)
		(stroke
			(width 0)
			(type solid)
		)
		(fill yes)
		(layer "In2.Cu")
		(net "M_C_CPU1_SA_DQS_DP<3>")
	)
	(gr_poly
		(pts
			(xy 92.611194 -241.042444) (xy 92.611194 -240.997994) (xy 92.411042 -240.997994) (xy 92.411042 -241.042444)
			(xy 92.511118 -241.14252)
		)
		(stroke
			(width 0)
			(type solid)
		)
		(fill yes)
		(layer "In2.Cu")
		(net "M_C_CPU1_SA_DQ<27>")
	)
	(gr_poly
		(pts
			(xy 92.611194 -239.826292) (xy 92.511118 -239.726216) (xy 92.411042 -239.826292) (xy 92.411042 -239.870742)
			(xy 92.611194 -239.870742)
		)
		(stroke
			(width 0)
			(type solid)
		)
		(fill yes)
		(layer "In2.Cu")
		(net "M_C_CPU1_SA_DQ<24>")
	)
	(gr_poly
		(pts
			(xy 92.611194 -239.422432) (xy 92.611194 -239.377982) (xy 92.411042 -239.377982) (xy 92.411042 -239.422432)
			(xy 92.511118 -239.522508)
		)
		(stroke
			(width 0)
			(type solid)
		)
		(fill yes)
		(layer "In2.Cu")
		(net "M_C_CPU1_SA_DQ<23>")
	)
	(gr_poly
		(pts
			(xy 92.611194 -238.20628) (xy 92.511118 -238.106204) (xy 92.411042 -238.20628) (xy 92.411042 -238.25073)
			(xy 92.611194 -238.25073)
		)
		(stroke
			(width 0)
			(type solid)
		)
		(fill yes)
		(layer "In2.Cu")
		(net "M_C_CPU1_SA_DQ<20>")
	)
	(gr_poly
		(pts
			(xy 92.611194 -237.802674) (xy 92.611194 -237.754922) (xy 92.411042 -237.754922) (xy 92.411042 -237.802674)
			(xy 92.511118 -237.902496)
		)
		(stroke
			(width 0)
			(type solid)
		)
		(fill yes)
		(layer "In2.Cu")
		(net "M_C_CPU1_SA_DQS_DP<7>")
	)
	(gr_poly
		(pts
			(xy 92.611194 -236.586014) (xy 92.511118 -236.486192) (xy 92.411042 -236.586014) (xy 92.411042 -236.633766)
			(xy 92.611194 -236.633766)
		)
		(stroke
			(width 0)
			(type solid)
		)
		(fill yes)
		(layer "In2.Cu")
		(net "M_C_CPU1_SA_DQS_DP<2>")
	)
	(gr_poly
		(pts
			(xy 92.611194 -236.182408) (xy 92.611194 -236.137958) (xy 92.411042 -236.137958) (xy 92.411042 -236.182408)
			(xy 92.511118 -236.282484)
		)
		(stroke
			(width 0)
			(type solid)
		)
		(fill yes)
		(layer "In2.Cu")
		(net "M_C_CPU1_SA_DQ<19>")
	)
	(gr_poly
		(pts
			(xy 92.611194 -234.966256) (xy 92.511118 -234.86618) (xy 92.411042 -234.966256) (xy 92.411042 -235.010706)
			(xy 92.611194 -235.010706)
		)
		(stroke
			(width 0)
			(type solid)
		)
		(fill yes)
		(layer "In2.Cu")
		(net "M_C_CPU1_SA_DQ<16>")
	)
	(gr_poly
		(pts
			(xy 92.611194 -234.562396) (xy 92.611194 -234.517946) (xy 92.411042 -234.517946) (xy 92.411042 -234.562396)
			(xy 92.511118 -234.662472)
		)
		(stroke
			(width 0)
			(type solid)
		)
		(fill yes)
		(layer "In2.Cu")
		(net "M_C_CPU1_SA_DQ<15>")
	)
	(gr_poly
		(pts
			(xy 92.611194 -233.346244) (xy 92.511118 -233.246168) (xy 92.411042 -233.346244) (xy 92.411042 -233.390694)
			(xy 92.611194 -233.390694)
		)
		(stroke
			(width 0)
			(type solid)
		)
		(fill yes)
		(layer "In2.Cu")
		(net "M_C_CPU1_SA_DQ<12>")
	)
	(gr_poly
		(pts
			(xy 92.611194 -232.942638) (xy 92.611194 -232.894886) (xy 92.411042 -232.894886) (xy 92.411042 -232.942638)
			(xy 92.511118 -233.04246)
		)
		(stroke
			(width 0)
			(type solid)
		)
		(fill yes)
		(layer "In2.Cu")
		(net "M_C_CPU1_SA_DQS_DP<6>")
	)
	(gr_poly
		(pts
			(xy 92.611194 -231.725978) (xy 92.511118 -231.626156) (xy 92.411042 -231.725978) (xy 92.411042 -231.77373)
			(xy 92.611194 -231.77373)
		)
		(stroke
			(width 0)
			(type solid)
		)
		(fill yes)
		(layer "In2.Cu")
		(net "M_C_CPU1_SA_DQS_DP<1>")
	)
	(gr_poly
		(pts
			(xy 92.611194 -231.322626) (xy 92.611194 -231.278176) (xy 92.411042 -231.278176) (xy 92.411042 -231.322626)
			(xy 92.511118 -231.422702)
		)
		(stroke
			(width 0)
			(type solid)
		)
		(fill yes)
		(layer "In2.Cu")
		(net "M_C_CPU1_SA_DQ<11>")
	)
	(gr_poly
		(pts
			(xy 92.611194 -230.10622) (xy 92.511118 -230.006144) (xy 92.411042 -230.10622) (xy 92.411042 -230.15067)
			(xy 92.611194 -230.15067)
		)
		(stroke
			(width 0)
			(type solid)
		)
		(fill yes)
		(layer "In2.Cu")
		(net "M_C_CPU1_SA_DQ<8>")
	)
	(gr_poly
		(pts
			(xy 92.611194 -229.702614) (xy 92.611194 -229.658164) (xy 92.411042 -229.658164) (xy 92.411042 -229.702614)
			(xy 92.511118 -229.80269)
		)
		(stroke
			(width 0)
			(type solid)
		)
		(fill yes)
		(layer "In2.Cu")
		(net "M_C_CPU1_SA_DQ<7>")
	)
	(gr_poly
		(pts
			(xy 92.611194 -228.486462) (xy 92.511118 -228.386386) (xy 92.411042 -228.486462) (xy 92.411042 -228.530912)
			(xy 92.611194 -228.530912)
		)
		(stroke
			(width 0)
			(type solid)
		)
		(fill yes)
		(layer "In2.Cu")
		(net "M_C_CPU1_SA_DQ<4>")
	)
	(gr_poly
		(pts
			(xy 92.611194 -228.082856) (xy 92.611194 -228.035104) (xy 92.411042 -228.035104) (xy 92.411042 -228.082856)
			(xy 92.511118 -228.182678)
		)
		(stroke
			(width 0)
			(type solid)
		)
		(fill yes)
		(layer "In2.Cu")
		(net "M_C_CPU1_SA_DQS_DP<5>")
	)
	(gr_poly
		(pts
			(xy 92.611194 -226.866196) (xy 92.511118 -226.766374) (xy 92.411042 -226.866196) (xy 92.411042 -226.913948)
			(xy 92.611194 -226.913948)
		)
		(stroke
			(width 0)
			(type solid)
		)
		(fill yes)
		(layer "In2.Cu")
		(net "M_C_CPU1_SA_DQS_DP<0>")
	)
	(gr_poly
		(pts
			(xy 92.611194 -226.46259) (xy 92.611194 -226.41814) (xy 92.411042 -226.41814) (xy 92.411042 -226.46259)
			(xy 92.511118 -226.562666)
		)
		(stroke
			(width 0)
			(type solid)
		)
		(fill yes)
		(layer "In2.Cu")
		(net "M_C_CPU1_SA_DQ<3>")
	)
	(gr_poly
		(pts
			(xy 92.611194 -225.246438) (xy 92.511118 -225.146362) (xy 92.411042 -225.246438) (xy 92.411042 -225.290888)
			(xy 92.611194 -225.290888)
		)
		(stroke
			(width 0)
			(type solid)
		)
		(fill yes)
		(layer "In2.Cu")
		(net "M_C_CPU1_SA_DQ<0>")
	)
	(gr_poly
		(pts
			(xy 92.903802 -291.298122) (xy 92.803726 -291.198046) (xy 92.70365 -291.298122) (xy 92.70365 -291.34562)
			(xy 92.903802 -291.34562)
		)
		(stroke
			(width 0)
			(type solid)
		)
		(fill yes)
		(layer "In2.Cu")
		(net "M_C_CPU1_SB_DQS_DN<8>")
	)
	(gr_poly
		(pts
			(xy 92.904818 -266.991846) (xy 92.804742 -266.89177) (xy 92.70492 -266.991846) (xy 92.70492 -267.036296)
			(xy 92.904818 -267.036296)
		)
		(stroke
			(width 0)
			(type solid)
		)
		(fill yes)
		(layer "In2.Cu")
		(net "M_C_CPU1_SA_RSP<0>")
	)
	(gr_poly
		(pts
			(xy 92.911168 -292.918134) (xy 92.811092 -292.818058) (xy 92.711016 -292.918134) (xy 92.711016 -292.962584)
			(xy 92.911168 -292.962584)
		)
		(stroke
			(width 0)
			(type solid)
		)
		(fill yes)
		(layer "In2.Cu")
		(net "M_C_CPU1_SB_DQ<29>")
	)
	(gr_poly
		(pts
			(xy 92.911168 -292.514274) (xy 92.911168 -292.469824) (xy 92.711016 -292.469824) (xy 92.711016 -292.514274)
			(xy 92.811092 -292.61435)
		)
		(stroke
			(width 0)
			(type solid)
		)
		(fill yes)
		(layer "In2.Cu")
		(net "M_C_CPU1_SB_DQ<30>")
	)
	(gr_poly
		(pts
			(xy 92.911168 -290.894516) (xy 92.911168 -290.846764) (xy 92.711016 -290.846764) (xy 92.711016 -290.894516)
			(xy 92.811092 -290.994338)
		)
		(stroke
			(width 0)
			(type solid)
		)
		(fill yes)
		(layer "In2.Cu")
		(net "M_C_CPU1_SB_DQS_DN<3>")
	)
	(gr_poly
		(pts
			(xy 92.911168 -289.67811) (xy 92.811092 -289.578034) (xy 92.711016 -289.67811) (xy 92.711016 -289.72256)
			(xy 92.911168 -289.72256)
		)
		(stroke
			(width 0)
			(type solid)
		)
		(fill yes)
		(layer "In2.Cu")
		(net "M_C_CPU1_SB_DQ<25>")
	)
	(gr_poly
		(pts
			(xy 92.911168 -289.27425) (xy 92.911168 -289.2298) (xy 92.711016 -289.2298) (xy 92.711016 -289.27425)
			(xy 92.811092 -289.374326)
		)
		(stroke
			(width 0)
			(type solid)
		)
		(fill yes)
		(layer "In2.Cu")
		(net "M_C_CPU1_SB_DQ<26>")
	)
	(gr_poly
		(pts
			(xy 92.911168 -288.058098) (xy 92.811092 -287.958022) (xy 92.711016 -288.058098) (xy 92.711016 -288.102548)
			(xy 92.911168 -288.102548)
		)
		(stroke
			(width 0)
			(type solid)
		)
		(fill yes)
		(layer "In2.Cu")
		(net "M_C_CPU1_SB_DQ<21>")
	)
	(gr_poly
		(pts
			(xy 92.911168 -287.654492) (xy 92.911168 -287.610042) (xy 92.711016 -287.610042) (xy 92.711016 -287.654492)
			(xy 92.811092 -287.754568)
		)
		(stroke
			(width 0)
			(type solid)
		)
		(fill yes)
		(layer "In2.Cu")
		(net "M_C_CPU1_SB_DQ<22>")
	)
	(gr_poly
		(pts
			(xy 92.911168 -286.438086) (xy 92.811092 -286.33801) (xy 92.711016 -286.438086) (xy 92.711016 -286.485838)
			(xy 92.911168 -286.485838)
		)
		(stroke
			(width 0)
			(type solid)
		)
		(fill yes)
		(layer "In2.Cu")
		(net "M_C_CPU1_SB_DQS_DN<7>")
	)
	(gr_poly
		(pts
			(xy 92.911168 -286.034734) (xy 92.911168 -285.986982) (xy 92.711016 -285.986982) (xy 92.711016 -286.034734)
			(xy 92.811092 -286.134556)
		)
		(stroke
			(width 0)
			(type solid)
		)
		(fill yes)
		(layer "In2.Cu")
		(net "M_C_CPU1_SB_DQS_DN<2>")
	)
	(gr_poly
		(pts
			(xy 92.911168 -284.818328) (xy 92.811092 -284.718252) (xy 92.711016 -284.818328) (xy 92.711016 -284.862778)
			(xy 92.911168 -284.862778)
		)
		(stroke
			(width 0)
			(type solid)
		)
		(fill yes)
		(layer "In2.Cu")
		(net "M_C_CPU1_SB_DQ<17>")
	)
	(gr_poly
		(pts
			(xy 92.911168 -284.414468) (xy 92.911168 -284.370018) (xy 92.711016 -284.370018) (xy 92.711016 -284.414468)
			(xy 92.811092 -284.514544)
		)
		(stroke
			(width 0)
			(type solid)
		)
		(fill yes)
		(layer "In2.Cu")
		(net "M_C_CPU1_SB_DQ<18>")
	)
	(gr_poly
		(pts
			(xy 92.911168 -283.198316) (xy 92.811092 -283.09824) (xy 92.711016 -283.198316) (xy 92.711016 -283.242766)
			(xy 92.911168 -283.242766)
		)
		(stroke
			(width 0)
			(type solid)
		)
		(fill yes)
		(layer "In2.Cu")
		(net "M_C_CPU1_SB_DQ<13>")
	)
	(gr_poly
		(pts
			(xy 92.911168 -282.794456) (xy 92.911168 -282.750006) (xy 92.711016 -282.750006) (xy 92.711016 -282.794456)
			(xy 92.811092 -282.894532)
		)
		(stroke
			(width 0)
			(type solid)
		)
		(fill yes)
		(layer "In2.Cu")
		(net "M_C_CPU1_SB_DQ<14>")
	)
	(gr_poly
		(pts
			(xy 92.911168 -281.57805) (xy 92.811092 -281.478228) (xy 92.711016 -281.57805) (xy 92.711016 -281.625802)
			(xy 92.911168 -281.625802)
		)
		(stroke
			(width 0)
			(type solid)
		)
		(fill yes)
		(layer "In2.Cu")
		(net "M_C_CPU1_SB_DQS_DN<6>")
	)
	(gr_poly
		(pts
			(xy 92.911168 -281.174698) (xy 92.911168 -281.126946) (xy 92.711016 -281.126946) (xy 92.711016 -281.174698)
			(xy 92.811092 -281.27452)
		)
		(stroke
			(width 0)
			(type solid)
		)
		(fill yes)
		(layer "In2.Cu")
		(net "M_C_CPU1_SB_DQS_DN<1>")
	)
	(gr_poly
		(pts
			(xy 92.911168 -279.958292) (xy 92.811092 -279.858216) (xy 92.711016 -279.958292) (xy 92.711016 -280.002742)
			(xy 92.911168 -280.002742)
		)
		(stroke
			(width 0)
			(type solid)
		)
		(fill yes)
		(layer "In2.Cu")
		(net "M_C_CPU1_SB_DQ<9>")
	)
	(gr_poly
		(pts
			(xy 92.911168 -279.554432) (xy 92.911168 -279.509982) (xy 92.711016 -279.509982) (xy 92.711016 -279.554432)
			(xy 92.811092 -279.654508)
		)
		(stroke
			(width 0)
			(type solid)
		)
		(fill yes)
		(layer "In2.Cu")
		(net "M_C_CPU1_SB_DQ<10>")
	)
	(gr_poly
		(pts
			(xy 92.911168 -278.33828) (xy 92.811092 -278.238204) (xy 92.711016 -278.33828) (xy 92.711016 -278.38273)
			(xy 92.911168 -278.38273)
		)
		(stroke
			(width 0)
			(type solid)
		)
		(fill yes)
		(layer "In2.Cu")
		(net "M_C_CPU1_SB_DQ<5>")
	)
	(gr_poly
		(pts
			(xy 92.911168 -277.93442) (xy 92.911168 -277.88997) (xy 92.711016 -277.88997) (xy 92.711016 -277.93442)
			(xy 92.811092 -278.034496)
		)
		(stroke
			(width 0)
			(type solid)
		)
		(fill yes)
		(layer "In2.Cu")
		(net "M_C_CPU1_SB_DQ<6>")
	)
	(gr_poly
		(pts
			(xy 92.911168 -276.718014) (xy 92.811092 -276.618192) (xy 92.711016 -276.718014) (xy 92.711016 -276.765766)
			(xy 92.911168 -276.765766)
		)
		(stroke
			(width 0)
			(type solid)
		)
		(fill yes)
		(layer "In2.Cu")
		(net "M_C_CPU1_SB_DQS_DN<5>")
	)
	(gr_poly
		(pts
			(xy 92.911168 -276.314662) (xy 92.911168 -276.26691) (xy 92.711016 -276.26691) (xy 92.711016 -276.314662)
			(xy 92.811092 -276.414484)
		)
		(stroke
			(width 0)
			(type solid)
		)
		(fill yes)
		(layer "In2.Cu")
		(net "M_C_CPU1_SB_DQS_DN<0>")
	)
	(gr_poly
		(pts
			(xy 92.911168 -275.098256) (xy 92.811092 -274.99818) (xy 92.711016 -275.098256) (xy 92.711016 -275.142706)
			(xy 92.911168 -275.142706)
		)
		(stroke
			(width 0)
			(type solid)
		)
		(fill yes)
		(layer "In2.Cu")
		(net "M_C_CPU1_SB_DQ<1>")
	)
	(gr_poly
		(pts
			(xy 92.911168 -274.694396) (xy 92.911168 -274.649946) (xy 92.711016 -274.649946) (xy 92.711016 -274.694396)
			(xy 92.811092 -274.794472)
		)
		(stroke
			(width 0)
			(type solid)
		)
		(fill yes)
		(layer "In2.Cu")
		(net "M_C_CPU1_SB_DQ<2>")
	)
	(gr_poly
		(pts
			(xy 92.911168 -273.478244) (xy 92.811092 -273.378168) (xy 92.711016 -273.478244) (xy 92.711016 -273.522694)
			(xy 92.911168 -273.522694)
		)
		(stroke
			(width 0)
			(type solid)
		)
		(fill yes)
		(layer "In2.Cu")
		(net "M_C_CPU1_SB_CB<1>")
	)
	(gr_poly
		(pts
			(xy 92.911168 -273.074384) (xy 92.911168 -273.029934) (xy 92.711016 -273.029934) (xy 92.711016 -273.074384)
			(xy 92.811092 -273.17446)
		)
		(stroke
			(width 0)
			(type solid)
		)
		(fill yes)
		(layer "In2.Cu")
		(net "M_C_CPU1_SB_CB<2>")
	)
	(gr_poly
		(pts
			(xy 92.911168 -271.857978) (xy 92.811092 -271.758156) (xy 92.711016 -271.857978) (xy 92.711016 -271.90573)
			(xy 92.911168 -271.90573)
		)
		(stroke
			(width 0)
			(type solid)
		)
		(fill yes)
		(layer "In2.Cu")
		(net "M_C_CPU1_SB_DQS_DN<4>")
	)
	(gr_poly
		(pts
			(xy 92.911168 -271.454626) (xy 92.911168 -271.406874) (xy 92.711016 -271.406874) (xy 92.711016 -271.454626)
			(xy 92.811092 -271.554448)
		)
		(stroke
			(width 0)
			(type solid)
		)
		(fill yes)
		(layer "In2.Cu")
		(net "M_C_CPU1_SB_DQS_DN<9>")
	)
	(gr_poly
		(pts
			(xy 92.911168 -270.23822) (xy 92.811092 -270.138144) (xy 92.711016 -270.23822) (xy 92.711016 -270.28267)
			(xy 92.911168 -270.28267)
		)
		(stroke
			(width 0)
			(type solid)
		)
		(fill yes)
		(layer "In2.Cu")
		(net "M_C_CPU1_SB_CB<5>")
	)
	(gr_poly
		(pts
			(xy 92.911168 -269.83436) (xy 92.911168 -269.78991) (xy 92.711016 -269.78991) (xy 92.711016 -269.83436)
			(xy 92.811092 -269.934436)
		)
		(stroke
			(width 0)
			(type solid)
		)
		(fill yes)
		(layer "In2.Cu")
		(net "M_C_CPU1_SB_CB<6>")
	)
	(gr_poly
		(pts
			(xy 92.911168 -266.594336) (xy 92.911168 -266.549886) (xy 92.711016 -266.549886) (xy 92.711016 -266.594336)
			(xy 92.811092 -266.694412)
		)
		(stroke
			(width 0)
			(type solid)
		)
		(fill yes)
		(layer "In2.Cu")
		(net "M_C_CPU1_SB_CS_N<1>")
	)
	(gr_poly
		(pts
			(xy 92.911168 -264.974324) (xy 92.911168 -264.929874) (xy 92.711016 -264.929874) (xy 92.711016 -264.974324)
			(xy 92.811092 -265.0744)
		)
		(stroke
			(width 0)
			(type solid)
		)
		(fill yes)
		(layer "In2.Cu")
		(net "M_C_CPU1_SB_PAR")
	)
	(gr_poly
		(pts
			(xy 92.911168 -263.758172) (xy 92.811092 -263.658096) (xy 92.711016 -263.758172) (xy 92.711016 -263.802622)
			(xy 92.911168 -263.802622)
		)
		(stroke
			(width 0)
			(type solid)
		)
		(fill yes)
		(layer "In2.Cu")
		(net "M_C_CPU1_SB_CA<4>")
	)
	(gr_poly
		(pts
			(xy 92.911168 -263.354312) (xy 92.911168 -263.309862) (xy 92.711016 -263.309862) (xy 92.711016 -263.354312)
			(xy 92.811092 -263.454388)
		)
		(stroke
			(width 0)
			(type solid)
		)
		(fill yes)
		(layer "In2.Cu")
		(net "M_C_CPU1_SB_CA<3>")
	)
	(gr_poly
		(pts
			(xy 92.911168 -262.13816) (xy 92.811092 -262.038084) (xy 92.711016 -262.13816) (xy 92.711016 -262.18261)
			(xy 92.911168 -262.18261)
		)
		(stroke
			(width 0)
			(type solid)
		)
		(fill yes)
		(layer "In2.Cu")
		(net "M_C_CPU1_SB_CA<0>")
	)
	(gr_poly
		(pts
			(xy 93.08084 -246.712486) (xy 93.08084 -246.664988) (xy 92.880942 -246.664988) (xy 92.880942 -246.712486)
			(xy 92.980764 -246.812562)
		)
		(stroke
			(width 0)
			(type solid)
		)
		(fill yes)
		(layer "In2.Cu")
		(net "M_C_CPU1_SA_DQS_DN<4>")
	)
	(gr_poly
		(pts
			(xy 93.081094 -256.432812) (xy 93.081094 -256.38506) (xy 92.880942 -256.38506) (xy 92.880942 -256.432812)
			(xy 92.981018 -256.532634)
		)
		(stroke
			(width 0)
			(type solid)
		)
		(fill yes)
		(layer "In2.Cu")
		(net "M_C_CPU1_CLK_DN<0>")
	)
	(gr_poly
		(pts
			(xy 93.081094 -255.216406) (xy 92.981018 -255.11633) (xy 92.880942 -255.216406) (xy 92.880942 -255.260856)
			(xy 93.081094 -255.260856)
		)
		(stroke
			(width 0)
			(type solid)
		)
		(fill yes)
		(layer "In2.Cu")
		(net "M_C_CPU1_SA_CA<6>")
	)
	(gr_poly
		(pts
			(xy 93.081094 -254.812546) (xy 93.081094 -254.768096) (xy 92.880942 -254.768096) (xy 92.880942 -254.812546)
			(xy 92.981018 -254.912622)
		)
		(stroke
			(width 0)
			(type solid)
		)
		(fill yes)
		(layer "In2.Cu")
		(net "M_C_CPU1_SA_CA<5>")
	)
	(gr_poly
		(pts
			(xy 93.081094 -253.596394) (xy 92.981018 -253.496318) (xy 92.880942 -253.596394) (xy 92.880942 -253.640844)
			(xy 93.081094 -253.640844)
		)
		(stroke
			(width 0)
			(type solid)
		)
		(fill yes)
		(layer "In2.Cu")
		(net "M_C_CPU1_SA_CA<2>")
	)
	(gr_poly
		(pts
			(xy 93.081094 -253.192534) (xy 93.081094 -253.148084) (xy 92.880942 -253.148084) (xy 92.880942 -253.192534)
			(xy 92.981018 -253.29261)
		)
		(stroke
			(width 0)
			(type solid)
		)
		(fill yes)
		(layer "In2.Cu")
		(net "M_C_CPU1_SA_CA<1>")
	)
	(gr_poly
		(pts
			(xy 93.081094 -251.572522) (xy 93.081094 -251.528072) (xy 92.880942 -251.528072) (xy 92.880942 -251.572522)
			(xy 92.981018 -251.672598)
		)
		(stroke
			(width 0)
			(type solid)
		)
		(fill yes)
		(layer "In2.Cu")
		(net "M_C_CPU1_SA_CS_N<0>")
	)
	(gr_poly
		(pts
			(xy 93.081094 -250.35637) (xy 92.981018 -250.256294) (xy 92.880942 -250.35637) (xy 92.880942 -250.40082)
			(xy 93.081094 -250.40082)
		)
		(stroke
			(width 0)
			(type solid)
		)
		(fill yes)
		(layer "In2.Cu")
		(net "M_C_CPU1_ALERT_R_N")
	)
	(gr_poly
		(pts
			(xy 93.081094 -248.736358) (xy 92.981018 -248.636282) (xy 92.880942 -248.736358) (xy 92.880942 -248.780808)
			(xy 93.081094 -248.780808)
		)
		(stroke
			(width 0)
			(type solid)
		)
		(fill yes)
		(layer "In2.Cu")
		(net "M_C_CPU1_SA_CB<5>")
	)
	(gr_poly
		(pts
			(xy 93.081094 -248.332498) (xy 93.081094 -248.288048) (xy 92.880942 -248.288048) (xy 92.880942 -248.332498)
			(xy 92.981018 -248.432574)
		)
		(stroke
			(width 0)
			(type solid)
		)
		(fill yes)
		(layer "In2.Cu")
		(net "M_C_CPU1_SA_CB<6>")
	)
	(gr_poly
		(pts
			(xy 93.081094 -247.116092) (xy 92.981018 -247.01627) (xy 92.880942 -247.116092) (xy 92.880942 -247.163844)
			(xy 93.081094 -247.163844)
		)
		(stroke
			(width 0)
			(type solid)
		)
		(fill yes)
		(layer "In2.Cu")
		(net "M_C_CPU1_SA_DQS_DN<9>")
	)
	(gr_poly
		(pts
			(xy 93.081094 -245.496334) (xy 92.981018 -245.396258) (xy 92.880942 -245.496334) (xy 92.880942 -245.540784)
			(xy 93.081094 -245.540784)
		)
		(stroke
			(width 0)
			(type solid)
		)
		(fill yes)
		(layer "In2.Cu")
		(net "M_C_CPU1_SA_CB<1>")
	)
	(gr_poly
		(pts
			(xy 93.081094 -245.092474) (xy 93.081094 -245.048024) (xy 92.880942 -245.048024) (xy 92.880942 -245.092474)
			(xy 92.981018 -245.19255)
		)
		(stroke
			(width 0)
			(type solid)
		)
		(fill yes)
		(layer "In2.Cu")
		(net "M_C_CPU1_SA_CB<2>")
	)
	(gr_poly
		(pts
			(xy 93.081094 -243.876322) (xy 92.981018 -243.776246) (xy 92.880942 -243.876322) (xy 92.880942 -243.920772)
			(xy 93.081094 -243.920772)
		)
		(stroke
			(width 0)
			(type solid)
		)
		(fill yes)
		(layer "In2.Cu")
		(net "M_C_CPU1_SA_DQ<29>")
	)
	(gr_poly
		(pts
			(xy 93.081094 -243.472462) (xy 93.081094 -243.428012) (xy 92.880942 -243.428012) (xy 92.880942 -243.472462)
			(xy 92.981018 -243.572538)
		)
		(stroke
			(width 0)
			(type solid)
		)
		(fill yes)
		(layer "In2.Cu")
		(net "M_C_CPU1_SA_DQ<30>")
	)
	(gr_poly
		(pts
			(xy 93.081094 -242.256056) (xy 92.981018 -242.156234) (xy 92.880942 -242.256056) (xy 92.880942 -242.303808)
			(xy 93.081094 -242.303808)
		)
		(stroke
			(width 0)
			(type solid)
		)
		(fill yes)
		(layer "In2.Cu")
		(net "M_C_CPU1_SA_DQS_DN<8>")
	)
	(gr_poly
		(pts
			(xy 93.081094 -241.852704) (xy 93.081094 -241.804952) (xy 92.880942 -241.804952) (xy 92.880942 -241.852704)
			(xy 92.981018 -241.952526)
		)
		(stroke
			(width 0)
			(type solid)
		)
		(fill yes)
		(layer "In2.Cu")
		(net "M_C_CPU1_SA_DQS_DN<3>")
	)
	(gr_poly
		(pts
			(xy 93.081094 -240.636298) (xy 92.981018 -240.536222) (xy 92.880942 -240.636298) (xy 92.880942 -240.680748)
			(xy 93.081094 -240.680748)
		)
		(stroke
			(width 0)
			(type solid)
		)
		(fill yes)
		(layer "In2.Cu")
		(net "M_C_CPU1_SA_DQ<25>")
	)
	(gr_poly
		(pts
			(xy 93.081094 -240.232438) (xy 93.081094 -240.187988) (xy 92.880942 -240.187988) (xy 92.880942 -240.232438)
			(xy 92.981018 -240.332514)
		)
		(stroke
			(width 0)
			(type solid)
		)
		(fill yes)
		(layer "In2.Cu")
		(net "M_C_CPU1_SA_DQ<26>")
	)
	(gr_poly
		(pts
			(xy 93.081094 -239.016286) (xy 92.981018 -238.91621) (xy 92.880942 -239.016286) (xy 92.880942 -239.060736)
			(xy 93.081094 -239.060736)
		)
		(stroke
			(width 0)
			(type solid)
		)
		(fill yes)
		(layer "In2.Cu")
		(net "M_C_CPU1_SA_DQ<21>")
	)
	(gr_poly
		(pts
			(xy 93.081094 -238.612426) (xy 93.081094 -238.567976) (xy 92.880942 -238.567976) (xy 92.880942 -238.612426)
			(xy 92.981018 -238.712502)
		)
		(stroke
			(width 0)
			(type solid)
		)
		(fill yes)
		(layer "In2.Cu")
		(net "M_C_CPU1_SA_DQ<22>")
	)
	(gr_poly
		(pts
			(xy 93.081094 -237.39602) (xy 92.981018 -237.296198) (xy 92.880942 -237.39602) (xy 92.880942 -237.443772)
			(xy 93.081094 -237.443772)
		)
		(stroke
			(width 0)
			(type solid)
		)
		(fill yes)
		(layer "In2.Cu")
		(net "M_C_CPU1_SA_DQS_DN<7>")
	)
	(gr_poly
		(pts
			(xy 93.081094 -236.992668) (xy 93.081094 -236.944916) (xy 92.880942 -236.944916) (xy 92.880942 -236.992668)
			(xy 92.981018 -237.09249)
		)
		(stroke
			(width 0)
			(type solid)
		)
		(fill yes)
		(layer "In2.Cu")
		(net "M_C_CPU1_SA_DQS_DN<2>")
	)
	(gr_poly
		(pts
			(xy 93.081094 -235.776262) (xy 92.981018 -235.676186) (xy 92.880942 -235.776262) (xy 92.880942 -235.820712)
			(xy 93.081094 -235.820712)
		)
		(stroke
			(width 0)
			(type solid)
		)
		(fill yes)
		(layer "In2.Cu")
		(net "M_C_CPU1_SA_DQ<17>")
	)
	(gr_poly
		(pts
			(xy 93.081094 -235.372402) (xy 93.081094 -235.327952) (xy 92.880942 -235.327952) (xy 92.880942 -235.372402)
			(xy 92.981018 -235.472478)
		)
		(stroke
			(width 0)
			(type solid)
		)
		(fill yes)
		(layer "In2.Cu")
		(net "M_C_CPU1_SA_DQ<18>")
	)
	(gr_poly
		(pts
			(xy 93.081094 -234.15625) (xy 92.981018 -234.056174) (xy 92.880942 -234.15625) (xy 92.880942 -234.2007)
			(xy 93.081094 -234.2007)
		)
		(stroke
			(width 0)
			(type solid)
		)
		(fill yes)
		(layer "In2.Cu")
		(net "M_C_CPU1_SA_DQ<13>")
	)
	(gr_poly
		(pts
			(xy 93.081094 -233.75239) (xy 93.081094 -233.70794) (xy 92.880942 -233.70794) (xy 92.880942 -233.75239)
			(xy 92.981018 -233.852466)
		)
		(stroke
			(width 0)
			(type solid)
		)
		(fill yes)
		(layer "In2.Cu")
		(net "M_C_CPU1_SA_DQ<14>")
	)
	(gr_poly
		(pts
			(xy 93.081094 -232.535984) (xy 92.981018 -232.436162) (xy 92.880942 -232.535984) (xy 92.880942 -232.583736)
			(xy 93.081094 -232.583736)
		)
		(stroke
			(width 0)
			(type solid)
		)
		(fill yes)
		(layer "In2.Cu")
		(net "M_C_CPU1_SA_DQS_DN<6>")
	)
	(gr_poly
		(pts
			(xy 93.081094 -232.132632) (xy 93.081094 -232.08488) (xy 92.880942 -232.08488) (xy 92.880942 -232.132632)
			(xy 92.981018 -232.232454)
		)
		(stroke
			(width 0)
			(type solid)
		)
		(fill yes)
		(layer "In2.Cu")
		(net "M_C_CPU1_SA_DQS_DN<1>")
	)
	(gr_poly
		(pts
			(xy 93.081094 -230.916226) (xy 92.981018 -230.81615) (xy 92.880942 -230.916226) (xy 92.880942 -230.960676)
			(xy 93.081094 -230.960676)
		)
		(stroke
			(width 0)
			(type solid)
		)
		(fill yes)
		(layer "In2.Cu")
		(net "M_C_CPU1_SA_DQ<9>")
	)
	(gr_poly
		(pts
			(xy 93.081094 -230.51262) (xy 93.081094 -230.46817) (xy 92.880942 -230.46817) (xy 92.880942 -230.51262)
			(xy 92.981018 -230.612696)
		)
		(stroke
			(width 0)
			(type solid)
		)
		(fill yes)
		(layer "In2.Cu")
		(net "M_C_CPU1_SA_DQ<10>")
	)
	(gr_poly
		(pts
			(xy 93.081094 -229.296214) (xy 92.981018 -229.196138) (xy 92.880942 -229.296214) (xy 92.880942 -229.340664)
			(xy 93.081094 -229.340664)
		)
		(stroke
			(width 0)
			(type solid)
		)
		(fill yes)
		(layer "In2.Cu")
		(net "M_C_CPU1_SA_DQ<5>")
	)
	(gr_poly
		(pts
			(xy 93.081094 -228.892608) (xy 93.081094 -228.848158) (xy 92.880942 -228.848158) (xy 92.880942 -228.892608)
			(xy 92.981018 -228.992684)
		)
		(stroke
			(width 0)
			(type solid)
		)
		(fill yes)
		(layer "In2.Cu")
		(net "M_C_CPU1_SA_DQ<6>")
	)
	(gr_poly
		(pts
			(xy 93.081094 -227.676202) (xy 92.981018 -227.57638) (xy 92.880942 -227.676202) (xy 92.880942 -227.723954)
			(xy 93.081094 -227.723954)
		)
		(stroke
			(width 0)
			(type solid)
		)
		(fill yes)
		(layer "In2.Cu")
		(net "M_C_CPU1_SA_DQS_DN<5>")
	)
	(gr_poly
		(pts
			(xy 93.081094 -227.27285) (xy 93.081094 -227.225098) (xy 92.880942 -227.225098) (xy 92.880942 -227.27285)
			(xy 92.981018 -227.372672)
		)
		(stroke
			(width 0)
			(type solid)
		)
		(fill yes)
		(layer "In2.Cu")
		(net "M_C_CPU1_SA_DQS_DN<0>")
	)
	(gr_poly
		(pts
			(xy 93.081094 -226.056444) (xy 92.981018 -225.956368) (xy 92.880942 -226.056444) (xy 92.880942 -226.100894)
			(xy 93.081094 -226.100894)
		)
		(stroke
			(width 0)
			(type solid)
		)
		(fill yes)
		(layer "In2.Cu")
		(net "M_C_CPU1_SA_DQ<1>")
	)
	(gr_poly
		(pts
			(xy 93.081094 -225.652584) (xy 93.081094 -225.608134) (xy 92.880942 -225.608134) (xy 92.880942 -225.652584)
			(xy 92.981018 -225.75266)
		)
		(stroke
			(width 0)
			(type solid)
		)
		(fill yes)
		(layer "In2.Cu")
		(net "M_C_CPU1_SA_DQ<2>")
	)
	(gr_poly
		(pts
			(xy 93.381068 -293.32428) (xy 93.381068 -293.27983) (xy 93.180916 -293.27983) (xy 93.180916 -293.32428)
			(xy 93.280992 -293.424356)
		)
		(stroke
			(width 0)
			(type solid)
		)
		(fill yes)
		(layer "In2.Cu")
		(net "M_C_CPU1_SB_DQ<31>")
	)
	(gr_poly
		(pts
			(xy 93.381068 -292.108128) (xy 93.280992 -292.008052) (xy 93.180916 -292.108128) (xy 93.180916 -292.152578)
			(xy 93.381068 -292.152578)
		)
		(stroke
			(width 0)
			(type solid)
		)
		(fill yes)
		(layer "In2.Cu")
		(net "M_C_CPU1_SB_DQ<28>")
	)
	(gr_poly
		(pts
			(xy 93.381068 -291.704522) (xy 93.381068 -291.65677) (xy 93.180916 -291.65677) (xy 93.180916 -291.704522)
			(xy 93.280992 -291.804344)
		)
		(stroke
			(width 0)
			(type solid)
		)
		(fill yes)
		(layer "In2.Cu")
		(net "M_C_CPU1_SB_DQS_DP<8>")
	)
	(gr_poly
		(pts
			(xy 93.381068 -290.487862) (xy 93.280992 -290.38804) (xy 93.180916 -290.487862) (xy 93.180916 -290.535614)
			(xy 93.381068 -290.535614)
		)
		(stroke
			(width 0)
			(type solid)
		)
		(fill yes)
		(layer "In2.Cu")
		(net "M_C_CPU1_SB_DQS_DP<3>")
	)
	(gr_poly
		(pts
			(xy 93.381068 -290.084256) (xy 93.381068 -290.039806) (xy 93.180916 -290.039806) (xy 93.180916 -290.084256)
			(xy 93.280992 -290.184332)
		)
		(stroke
			(width 0)
			(type solid)
		)
		(fill yes)
		(layer "In2.Cu")
		(net "M_C_CPU1_SB_DQ<27>")
	)
	(gr_poly
		(pts
			(xy 93.381068 -288.868104) (xy 93.280992 -288.768028) (xy 93.180916 -288.868104) (xy 93.180916 -288.912554)
			(xy 93.381068 -288.912554)
		)
		(stroke
			(width 0)
			(type solid)
		)
		(fill yes)
		(layer "In2.Cu")
		(net "M_C_CPU1_SB_DQ<24>")
	)
	(gr_poly
		(pts
			(xy 93.381068 -288.464498) (xy 93.381068 -288.420048) (xy 93.180916 -288.420048) (xy 93.180916 -288.464498)
			(xy 93.280992 -288.564574)
		)
		(stroke
			(width 0)
			(type solid)
		)
		(fill yes)
		(layer "In2.Cu")
		(net "M_C_CPU1_SB_DQ<23>")
	)
	(gr_poly
		(pts
			(xy 93.381068 -287.248092) (xy 93.280992 -287.148016) (xy 93.180916 -287.248092) (xy 93.180916 -287.292542)
			(xy 93.381068 -287.292542)
		)
		(stroke
			(width 0)
			(type solid)
		)
		(fill yes)
		(layer "In2.Cu")
		(net "M_C_CPU1_SB_DQ<20>")
	)
	(gr_poly
		(pts
			(xy 93.381068 -286.844486) (xy 93.381068 -286.796734) (xy 93.180916 -286.796734) (xy 93.180916 -286.844486)
			(xy 93.280992 -286.944562)
		)
		(stroke
			(width 0)
			(type solid)
		)
		(fill yes)
		(layer "In2.Cu")
		(net "M_C_CPU1_SB_DQS_DP<7>")
	)
	(gr_poly
		(pts
			(xy 93.381068 -285.62808) (xy 93.280992 -285.528258) (xy 93.180916 -285.62808) (xy 93.180916 -285.675832)
			(xy 93.381068 -285.675832)
		)
		(stroke
			(width 0)
			(type solid)
		)
		(fill yes)
		(layer "In2.Cu")
		(net "M_C_CPU1_SB_DQS_DP<2>")
	)
	(gr_poly
		(pts
			(xy 93.381068 -285.224474) (xy 93.381068 -285.180024) (xy 93.180916 -285.180024) (xy 93.180916 -285.224474)
			(xy 93.280992 -285.32455)
		)
		(stroke
			(width 0)
			(type solid)
		)
		(fill yes)
		(layer "In2.Cu")
		(net "M_C_CPU1_SB_DQ<19>")
	)
	(gr_poly
		(pts
			(xy 93.381068 -284.008322) (xy 93.280992 -283.908246) (xy 93.180916 -284.008322) (xy 93.180916 -284.052772)
			(xy 93.381068 -284.052772)
		)
		(stroke
			(width 0)
			(type solid)
		)
		(fill yes)
		(layer "In2.Cu")
		(net "M_C_CPU1_SB_DQ<16>")
	)
	(gr_poly
		(pts
			(xy 93.381068 -283.604462) (xy 93.381068 -283.560012) (xy 93.180916 -283.560012) (xy 93.180916 -283.604462)
			(xy 93.280992 -283.704538)
		)
		(stroke
			(width 0)
			(type solid)
		)
		(fill yes)
		(layer "In2.Cu")
		(net "M_C_CPU1_SB_DQ<15>")
	)
	(gr_poly
		(pts
			(xy 93.381068 -282.38831) (xy 93.280992 -282.288234) (xy 93.180916 -282.38831) (xy 93.180916 -282.43276)
			(xy 93.381068 -282.43276)
		)
		(stroke
			(width 0)
			(type solid)
		)
		(fill yes)
		(layer "In2.Cu")
		(net "M_C_CPU1_SB_DQ<12>")
	)
	(gr_poly
		(pts
			(xy 93.381068 -281.984704) (xy 93.381068 -281.936952) (xy 93.180916 -281.936952) (xy 93.180916 -281.984704)
			(xy 93.280992 -282.084526)
		)
		(stroke
			(width 0)
			(type solid)
		)
		(fill yes)
		(layer "In2.Cu")
		(net "M_C_CPU1_SB_DQS_DP<6>")
	)
	(gr_poly
		(pts
			(xy 93.381068 -280.768044) (xy 93.280992 -280.668222) (xy 93.180916 -280.768044) (xy 93.180916 -280.815796)
			(xy 93.381068 -280.815796)
		)
		(stroke
			(width 0)
			(type solid)
		)
		(fill yes)
		(layer "In2.Cu")
		(net "M_C_CPU1_SB_DQS_DP<1>")
	)
	(gr_poly
		(pts
			(xy 93.381068 -280.364438) (xy 93.381068 -280.319988) (xy 93.180916 -280.319988) (xy 93.180916 -280.364438)
			(xy 93.280992 -280.464514)
		)
		(stroke
			(width 0)
			(type solid)
		)
		(fill yes)
		(layer "In2.Cu")
		(net "M_C_CPU1_SB_DQ<11>")
	)
	(gr_poly
		(pts
			(xy 93.381068 -279.148286) (xy 93.280992 -279.04821) (xy 93.180916 -279.148286) (xy 93.180916 -279.192736)
			(xy 93.381068 -279.192736)
		)
		(stroke
			(width 0)
			(type solid)
		)
		(fill yes)
		(layer "In2.Cu")
		(net "M_C_CPU1_SB_DQ<8>")
	)
	(gr_poly
		(pts
			(xy 93.381068 -278.744426) (xy 93.381068 -278.699976) (xy 93.180916 -278.699976) (xy 93.180916 -278.744426)
			(xy 93.280992 -278.844502)
		)
		(stroke
			(width 0)
			(type solid)
		)
		(fill yes)
		(layer "In2.Cu")
		(net "M_C_CPU1_SB_DQ<7>")
	)
	(gr_poly
		(pts
			(xy 93.381068 -277.528274) (xy 93.280992 -277.428198) (xy 93.180916 -277.528274) (xy 93.180916 -277.572724)
			(xy 93.381068 -277.572724)
		)
		(stroke
			(width 0)
			(type solid)
		)
		(fill yes)
		(layer "In2.Cu")
		(net "M_C_CPU1_SB_DQ<4>")
	)
	(gr_poly
		(pts
			(xy 93.381068 -277.124668) (xy 93.381068 -277.076916) (xy 93.180916 -277.076916) (xy 93.180916 -277.124668)
			(xy 93.280992 -277.22449)
		)
		(stroke
			(width 0)
			(type solid)
		)
		(fill yes)
		(layer "In2.Cu")
		(net "M_C_CPU1_SB_DQS_DP<5>")
	)
	(gr_poly
		(pts
			(xy 93.381068 -275.908008) (xy 93.280992 -275.808186) (xy 93.180916 -275.908008) (xy 93.180916 -275.95576)
			(xy 93.381068 -275.95576)
		)
		(stroke
			(width 0)
			(type solid)
		)
		(fill yes)
		(layer "In2.Cu")
		(net "M_C_CPU1_SB_DQS_DP<0>")
	)
	(gr_poly
		(pts
			(xy 93.381068 -275.504402) (xy 93.381068 -275.459952) (xy 93.180916 -275.459952) (xy 93.180916 -275.504402)
			(xy 93.280992 -275.604478)
		)
		(stroke
			(width 0)
			(type solid)
		)
		(fill yes)
		(layer "In2.Cu")
		(net "M_C_CPU1_SB_DQ<3>")
	)
	(gr_poly
		(pts
			(xy 93.381068 -274.28825) (xy 93.280992 -274.188174) (xy 93.180916 -274.28825) (xy 93.180916 -274.3327)
			(xy 93.381068 -274.3327)
		)
		(stroke
			(width 0)
			(type solid)
		)
		(fill yes)
		(layer "In2.Cu")
		(net "M_C_CPU1_SB_DQ<0>")
	)
	(gr_poly
		(pts
			(xy 93.381068 -273.88439) (xy 93.381068 -273.83994) (xy 93.180916 -273.83994) (xy 93.180916 -273.88439)
			(xy 93.280992 -273.984466)
		)
		(stroke
			(width 0)
			(type solid)
		)
		(fill yes)
		(layer "In2.Cu")
		(net "M_C_CPU1_SB_CB<3>")
	)
	(gr_poly
		(pts
			(xy 93.381068 -272.668238) (xy 93.280992 -272.568162) (xy 93.180916 -272.668238) (xy 93.180916 -272.712688)
			(xy 93.381068 -272.712688)
		)
		(stroke
			(width 0)
			(type solid)
		)
		(fill yes)
		(layer "In2.Cu")
		(net "M_C_CPU1_SB_CB<0>")
	)
	(gr_poly
		(pts
			(xy 93.381068 -272.264632) (xy 93.381068 -272.21688) (xy 93.180916 -272.21688) (xy 93.180916 -272.264632)
			(xy 93.280992 -272.364454)
		)
		(stroke
			(width 0)
			(type solid)
		)
		(fill yes)
		(layer "In2.Cu")
		(net "M_C_CPU1_SB_DQS_DP<4>")
	)
	(gr_poly
		(pts
			(xy 93.381068 -271.047972) (xy 93.280992 -270.94815) (xy 93.180916 -271.047972) (xy 93.180916 -271.095724)
			(xy 93.381068 -271.095724)
		)
		(stroke
			(width 0)
			(type solid)
		)
		(fill yes)
		(layer "In2.Cu")
		(net "M_C_CPU1_SB_DQS_DP<9>")
	)
	(gr_poly
		(pts
			(xy 93.381068 -270.644366) (xy 93.381068 -270.599916) (xy 93.180916 -270.599916) (xy 93.180916 -270.644366)
			(xy 93.280992 -270.744442)
		)
		(stroke
			(width 0)
			(type solid)
		)
		(fill yes)
		(layer "In2.Cu")
		(net "M_C_CPU1_SB_CB<7>")
	)
	(gr_poly
		(pts
			(xy 93.381068 -269.428214) (xy 93.280992 -269.328138) (xy 93.180916 -269.428214) (xy 93.180916 -269.472664)
			(xy 93.381068 -269.472664)
		)
		(stroke
			(width 0)
			(type solid)
		)
		(fill yes)
		(layer "In2.Cu")
		(net "M_C_CPU1_SB_CB<4>")
	)
	(gr_poly
		(pts
			(xy 93.381068 -265.78433) (xy 93.381068 -265.73988) (xy 93.180916 -265.73988) (xy 93.180916 -265.78433)
			(xy 93.280992 -265.884406)
		)
		(stroke
			(width 0)
			(type solid)
		)
		(fill yes)
		(layer "In2.Cu")
		(net "M_C_CPU1_SB_CS_N<0>")
	)
	(gr_poly
		(pts
			(xy 93.381068 -264.568178) (xy 93.280992 -264.468102) (xy 93.180916 -264.568178) (xy 93.180916 -264.612628)
			(xy 93.381068 -264.612628)
		)
		(stroke
			(width 0)
			(type solid)
		)
		(fill yes)
		(layer "In2.Cu")
		(net "M_C_CPU1_SB_CA<6>")
	)
	(gr_poly
		(pts
			(xy 93.381068 -264.164318) (xy 93.381068 -264.119868) (xy 93.180916 -264.119868) (xy 93.180916 -264.164318)
			(xy 93.280992 -264.264394)
		)
		(stroke
			(width 0)
			(type solid)
		)
		(fill yes)
		(layer "In2.Cu")
		(net "M_C_CPU1_SB_CA<5>")
	)
	(gr_poly
		(pts
			(xy 93.381068 -262.948166) (xy 93.280992 -262.84809) (xy 93.180916 -262.948166) (xy 93.180916 -262.992616)
			(xy 93.381068 -262.992616)
		)
		(stroke
			(width 0)
			(type solid)
		)
		(fill yes)
		(layer "In2.Cu")
		(net "M_C_CPU1_SB_CA<2>")
	)
	(gr_poly
		(pts
			(xy 93.381068 -262.544306) (xy 93.381068 -262.499856) (xy 93.180916 -262.499856) (xy 93.180916 -262.544306)
			(xy 93.280992 -262.644382)
		)
		(stroke
			(width 0)
			(type solid)
		)
		(fill yes)
		(layer "In2.Cu")
		(net "M_C_CPU1_SB_CA<1>")
	)
	(gr_poly
		(pts
			(xy 93.387164 -267.801852) (xy 93.287342 -267.701776) (xy 93.187266 -267.801852) (xy 93.187266 -267.846302)
			(xy 93.387164 -267.846302)
		)
		(stroke
			(width 0)
			(type solid)
		)
		(fill yes)
		(layer "In2.Cu")
		(net "M_C_CPU1_SB_RSP<0>")
	)
	(gr_poly
		(pts
			(xy 93.550994 -256.026158) (xy 93.450918 -255.926336) (xy 93.350842 -256.026158) (xy 93.350842 -256.07391)
			(xy 93.550994 -256.07391)
		)
		(stroke
			(width 0)
			(type solid)
		)
		(fill yes)
		(layer "In2.Cu")
		(net "M_C_CPU1_CLK_DP<0>")
	)
	(gr_poly
		(pts
			(xy 93.550994 -255.622552) (xy 93.550994 -255.578102) (xy 93.350842 -255.578102) (xy 93.350842 -255.622552)
			(xy 93.450918 -255.722628)
		)
		(stroke
			(width 0)
			(type solid)
		)
		(fill yes)
		(layer "In2.Cu")
		(net "M_C_CPU1_SA_PAR")
	)
	(gr_poly
		(pts
			(xy 93.550994 -254.4064) (xy 93.450918 -254.306324) (xy 93.350842 -254.4064) (xy 93.350842 -254.45085)
			(xy 93.550994 -254.45085)
		)
		(stroke
			(width 0)
			(type solid)
		)
		(fill yes)
		(layer "In2.Cu")
		(net "M_C_CPU1_SA_CA<4>")
	)
	(gr_poly
		(pts
			(xy 93.550994 -254.00254) (xy 93.550994 -253.95809) (xy 93.350842 -253.95809) (xy 93.350842 -254.00254)
			(xy 93.450918 -254.102616)
		)
		(stroke
			(width 0)
			(type solid)
		)
		(fill yes)
		(layer "In2.Cu")
		(net "M_C_CPU1_SA_CA<3>")
	)
	(gr_poly
		(pts
			(xy 93.550994 -252.786388) (xy 93.450918 -252.686312) (xy 93.350842 -252.786388) (xy 93.350842 -252.830838)
			(xy 93.550994 -252.830838)
		)
		(stroke
			(width 0)
			(type solid)
		)
		(fill yes)
		(layer "In2.Cu")
		(net "M_C_CPU1_SA_CA<0>")
	)
	(gr_poly
		(pts
			(xy 93.550994 -252.382528) (xy 93.550994 -252.338078) (xy 93.350842 -252.338078) (xy 93.350842 -252.382528)
			(xy 93.450918 -252.482604)
		)
		(stroke
			(width 0)
			(type solid)
		)
		(fill yes)
		(layer "In2.Cu")
		(net "M_C_CPU1_SA_CS_N<1>")
	)
	(gr_poly
		(pts
			(xy 93.550994 -250.762516) (xy 93.550994 -250.718066) (xy 93.350842 -250.718066) (xy 93.350842 -250.762516)
			(xy 93.450918 -250.862592)
		)
		(stroke
			(width 0)
			(type solid)
		)
		(fill yes)
		(layer "In2.Cu")
		(net "M_C_CPU1_RESET_N")
	)
	(gr_poly
		(pts
			(xy 93.550994 -249.142504) (xy 93.550994 -249.098054) (xy 93.350842 -249.098054) (xy 93.350842 -249.142504)
			(xy 93.450918 -249.24258)
		)
		(stroke
			(width 0)
			(type solid)
		)
		(fill yes)
		(layer "In2.Cu")
		(net "M_C_CPU1_SA_CB<7>")
	)
	(gr_poly
		(pts
			(xy 93.550994 -247.926352) (xy 93.450918 -247.826276) (xy 93.350842 -247.926352) (xy 93.350842 -247.970802)
			(xy 93.550994 -247.970802)
		)
		(stroke
			(width 0)
			(type solid)
		)
		(fill yes)
		(layer "In2.Cu")
		(net "M_C_CPU1_SA_CB<4>")
	)
	(gr_poly
		(pts
			(xy 93.550994 -247.522746) (xy 93.550994 -247.474994) (xy 93.350842 -247.474994) (xy 93.350842 -247.522746)
			(xy 93.450918 -247.622568)
		)
		(stroke
			(width 0)
			(type solid)
		)
		(fill yes)
		(layer "In2.Cu")
		(net "M_C_CPU1_SA_DQS_DP<9>")
	)
	(gr_poly
		(pts
			(xy 93.550994 -245.90248) (xy 93.550994 -245.85803) (xy 93.350842 -245.85803) (xy 93.350842 -245.90248)
			(xy 93.450918 -246.002556)
		)
		(stroke
			(width 0)
			(type solid)
		)
		(fill yes)
		(layer "In2.Cu")
		(net "M_C_CPU1_SA_CB<3>")
	)
	(gr_poly
		(pts
			(xy 93.550994 -244.686328) (xy 93.450918 -244.586252) (xy 93.350842 -244.686328) (xy 93.350842 -244.730778)
			(xy 93.550994 -244.730778)
		)
		(stroke
			(width 0)
			(type solid)
		)
		(fill yes)
		(layer "In2.Cu")
		(net "M_C_CPU1_SA_CB<0>")
	)
	(gr_poly
		(pts
			(xy 93.550994 -244.282468) (xy 93.550994 -244.238018) (xy 93.350842 -244.238018) (xy 93.350842 -244.282468)
			(xy 93.450918 -244.382544)
		)
		(stroke
			(width 0)
			(type solid)
		)
		(fill yes)
		(layer "In2.Cu")
		(net "M_C_CPU1_SA_DQ<31>")
	)
	(gr_poly
		(pts
			(xy 93.550994 -243.066316) (xy 93.450918 -242.96624) (xy 93.350842 -243.066316) (xy 93.350842 -243.110766)
			(xy 93.550994 -243.110766)
		)
		(stroke
			(width 0)
			(type solid)
		)
		(fill yes)
		(layer "In2.Cu")
		(net "M_C_CPU1_SA_DQ<28>")
	)
	(gr_poly
		(pts
			(xy 93.550994 -242.66271) (xy 93.550994 -242.614958) (xy 93.350842 -242.614958) (xy 93.350842 -242.66271)
			(xy 93.450918 -242.762532)
		)
		(stroke
			(width 0)
			(type solid)
		)
		(fill yes)
		(layer "In2.Cu")
		(net "M_C_CPU1_SA_DQS_DP<8>")
	)
	(gr_poly
		(pts
			(xy 93.550994 -241.44605) (xy 93.450918 -241.346228) (xy 93.350842 -241.44605) (xy 93.350842 -241.493802)
			(xy 93.550994 -241.493802)
		)
		(stroke
			(width 0)
			(type solid)
		)
		(fill yes)
		(layer "In2.Cu")
		(net "M_C_CPU1_SA_DQS_DP<3>")
	)
	(gr_poly
		(pts
			(xy 93.550994 -241.042444) (xy 93.550994 -240.997994) (xy 93.350842 -240.997994) (xy 93.350842 -241.042444)
			(xy 93.450918 -241.14252)
		)
		(stroke
			(width 0)
			(type solid)
		)
		(fill yes)
		(layer "In2.Cu")
		(net "M_C_CPU1_SA_DQ<27>")
	)
	(gr_poly
		(pts
			(xy 93.550994 -239.826292) (xy 93.450918 -239.726216) (xy 93.350842 -239.826292) (xy 93.350842 -239.870742)
			(xy 93.550994 -239.870742)
		)
		(stroke
			(width 0)
			(type solid)
		)
		(fill yes)
		(layer "In2.Cu")
		(net "M_C_CPU1_SA_DQ<24>")
	)
	(gr_poly
		(pts
			(xy 93.550994 -239.422432) (xy 93.550994 -239.377982) (xy 93.350842 -239.377982) (xy 93.350842 -239.422432)
			(xy 93.450918 -239.522508)
		)
		(stroke
			(width 0)
			(type solid)
		)
		(fill yes)
		(layer "In2.Cu")
		(net "M_C_CPU1_SA_DQ<23>")
	)
	(gr_poly
		(pts
			(xy 93.550994 -238.20628) (xy 93.450918 -238.106204) (xy 93.350842 -238.20628) (xy 93.350842 -238.25073)
			(xy 93.550994 -238.25073)
		)
		(stroke
			(width 0)
			(type solid)
		)
		(fill yes)
		(layer "In2.Cu")
		(net "M_C_CPU1_SA_DQ<20>")
	)
	(gr_poly
		(pts
			(xy 93.550994 -237.802674) (xy 93.550994 -237.754922) (xy 93.350842 -237.754922) (xy 93.350842 -237.802674)
			(xy 93.450918 -237.902496)
		)
		(stroke
			(width 0)
			(type solid)
		)
		(fill yes)
		(layer "In2.Cu")
		(net "M_C_CPU1_SA_DQS_DP<7>")
	)
	(gr_poly
		(pts
			(xy 93.550994 -236.586014) (xy 93.450918 -236.486192) (xy 93.350842 -236.586014) (xy 93.350842 -236.633766)
			(xy 93.550994 -236.633766)
		)
		(stroke
			(width 0)
			(type solid)
		)
		(fill yes)
		(layer "In2.Cu")
		(net "M_C_CPU1_SA_DQS_DP<2>")
	)
	(gr_poly
		(pts
			(xy 93.550994 -236.182408) (xy 93.550994 -236.137958) (xy 93.350842 -236.137958) (xy 93.350842 -236.182408)
			(xy 93.450918 -236.282484)
		)
		(stroke
			(width 0)
			(type solid)
		)
		(fill yes)
		(layer "In2.Cu")
		(net "M_C_CPU1_SA_DQ<19>")
	)
	(gr_poly
		(pts
			(xy 93.550994 -234.966256) (xy 93.450918 -234.86618) (xy 93.350842 -234.966256) (xy 93.350842 -235.010706)
			(xy 93.550994 -235.010706)
		)
		(stroke
			(width 0)
			(type solid)
		)
		(fill yes)
		(layer "In2.Cu")
		(net "M_C_CPU1_SA_DQ<16>")
	)
	(gr_poly
		(pts
			(xy 93.550994 -234.562396) (xy 93.550994 -234.517946) (xy 93.350842 -234.517946) (xy 93.350842 -234.562396)
			(xy 93.450918 -234.662472)
		)
		(stroke
			(width 0)
			(type solid)
		)
		(fill yes)
		(layer "In2.Cu")
		(net "M_C_CPU1_SA_DQ<15>")
	)
	(gr_poly
		(pts
			(xy 93.550994 -233.346244) (xy 93.450918 -233.246168) (xy 93.350842 -233.346244) (xy 93.350842 -233.390694)
			(xy 93.550994 -233.390694)
		)
		(stroke
			(width 0)
			(type solid)
		)
		(fill yes)
		(layer "In2.Cu")
		(net "M_C_CPU1_SA_DQ<12>")
	)
	(gr_poly
		(pts
			(xy 93.550994 -232.942638) (xy 93.550994 -232.894886) (xy 93.350842 -232.894886) (xy 93.350842 -232.942638)
			(xy 93.450918 -233.04246)
		)
		(stroke
			(width 0)
			(type solid)
		)
		(fill yes)
		(layer "In2.Cu")
		(net "M_C_CPU1_SA_DQS_DP<6>")
	)
	(gr_poly
		(pts
			(xy 93.550994 -231.725978) (xy 93.450918 -231.626156) (xy 93.350842 -231.725978) (xy 93.350842 -231.77373)
			(xy 93.550994 -231.77373)
		)
		(stroke
			(width 0)
			(type solid)
		)
		(fill yes)
		(layer "In2.Cu")
		(net "M_C_CPU1_SA_DQS_DP<1>")
	)
	(gr_poly
		(pts
			(xy 93.550994 -231.322626) (xy 93.550994 -231.278176) (xy 93.350842 -231.278176) (xy 93.350842 -231.322626)
			(xy 93.450918 -231.422702)
		)
		(stroke
			(width 0)
			(type solid)
		)
		(fill yes)
		(layer "In2.Cu")
		(net "M_C_CPU1_SA_DQ<11>")
	)
	(gr_poly
		(pts
			(xy 93.550994 -230.10622) (xy 93.450918 -230.006144) (xy 93.350842 -230.10622) (xy 93.350842 -230.15067)
			(xy 93.550994 -230.15067)
		)
		(stroke
			(width 0)
			(type solid)
		)
		(fill yes)
		(layer "In2.Cu")
		(net "M_C_CPU1_SA_DQ<8>")
	)
	(gr_poly
		(pts
			(xy 93.550994 -229.702614) (xy 93.550994 -229.658164) (xy 93.350842 -229.658164) (xy 93.350842 -229.702614)
			(xy 93.450918 -229.80269)
		)
		(stroke
			(width 0)
			(type solid)
		)
		(fill yes)
		(layer "In2.Cu")
		(net "M_C_CPU1_SA_DQ<7>")
	)
	(gr_poly
		(pts
			(xy 93.550994 -228.486462) (xy 93.450918 -228.386386) (xy 93.350842 -228.486462) (xy 93.350842 -228.530912)
			(xy 93.550994 -228.530912)
		)
		(stroke
			(width 0)
			(type solid)
		)
		(fill yes)
		(layer "In2.Cu")
		(net "M_C_CPU1_SA_DQ<4>")
	)
	(gr_poly
		(pts
			(xy 93.550994 -228.082856) (xy 93.550994 -228.035104) (xy 93.350842 -228.035104) (xy 93.350842 -228.082856)
			(xy 93.450918 -228.182678)
		)
		(stroke
			(width 0)
			(type solid)
		)
		(fill yes)
		(layer "In2.Cu")
		(net "M_C_CPU1_SA_DQS_DP<5>")
	)
	(gr_poly
		(pts
			(xy 93.550994 -226.866196) (xy 93.450918 -226.766374) (xy 93.350842 -226.866196) (xy 93.350842 -226.913948)
			(xy 93.550994 -226.913948)
		)
		(stroke
			(width 0)
			(type solid)
		)
		(fill yes)
		(layer "In2.Cu")
		(net "M_C_CPU1_SA_DQS_DP<0>")
	)
	(gr_poly
		(pts
			(xy 93.550994 -226.46259) (xy 93.550994 -226.41814) (xy 93.350842 -226.41814) (xy 93.350842 -226.46259)
			(xy 93.450918 -226.562666)
		)
		(stroke
			(width 0)
			(type solid)
		)
		(fill yes)
		(layer "In2.Cu")
		(net "M_C_CPU1_SA_DQ<3>")
	)
	(gr_poly
		(pts
			(xy 93.550994 -225.246438) (xy 93.450918 -225.146362) (xy 93.350842 -225.246438) (xy 93.350842 -225.290888)
			(xy 93.550994 -225.290888)
		)
		(stroke
			(width 0)
			(type solid)
		)
		(fill yes)
		(layer "In2.Cu")
		(net "M_C_CPU1_SA_DQ<0>")
	)
	(gr_poly
		(pts
			(xy 93.551248 -246.306086) (xy 93.451172 -246.206264) (xy 93.351096 -246.306086) (xy 93.351096 -246.353838)
			(xy 93.551248 -246.353838)
		)
		(stroke
			(width 0)
			(type solid)
		)
		(fill yes)
		(layer "In2.Cu")
		(net "M_C_CPU1_SA_DQS_DP<4>")
	)
	(gr_poly
		(pts
			(xy 93.843856 -291.297868) (xy 93.74378 -291.198046) (xy 93.643958 -291.297868) (xy 93.643958 -291.34562)
			(xy 93.843856 -291.34562)
		)
		(stroke
			(width 0)
			(type solid)
		)
		(fill yes)
		(layer "In2.Cu")
		(net "M_C_CPU1_SB_DQS_DN<8>")
	)
	(gr_poly
		(pts
			(xy 93.844872 -266.991846) (xy 93.744796 -266.89177) (xy 93.644974 -266.991846) (xy 93.644974 -267.036296)
			(xy 93.844872 -267.036296)
		)
		(stroke
			(width 0)
			(type solid)
		)
		(fill yes)
		(layer "In2.Cu")
		(net "M_C_CPU1_SA_RSP<0>")
	)
	(gr_poly
		(pts
			(xy 93.851222 -292.918134) (xy 93.751146 -292.818058) (xy 93.65107 -292.918134) (xy 93.65107 -292.962584)
			(xy 93.851222 -292.962584)
		)
		(stroke
			(width 0)
			(type solid)
		)
		(fill yes)
		(layer "In2.Cu")
		(net "M_C_CPU1_SB_DQ<29>")
	)
	(gr_poly
		(pts
			(xy 93.851222 -292.514274) (xy 93.851222 -292.469824) (xy 93.65107 -292.469824) (xy 93.65107 -292.514274)
			(xy 93.751146 -292.61435)
		)
		(stroke
			(width 0)
			(type solid)
		)
		(fill yes)
		(layer "In2.Cu")
		(net "M_C_CPU1_SB_DQ<30>")
	)
	(gr_poly
		(pts
			(xy 93.851222 -290.894516) (xy 93.851222 -290.846764) (xy 93.65107 -290.846764) (xy 93.65107 -290.894516)
			(xy 93.751146 -290.994338)
		)
		(stroke
			(width 0)
			(type solid)
		)
		(fill yes)
		(layer "In2.Cu")
		(net "M_C_CPU1_SB_DQS_DN<3>")
	)
	(gr_poly
		(pts
			(xy 93.851222 -289.67811) (xy 93.751146 -289.578034) (xy 93.65107 -289.67811) (xy 93.65107 -289.72256)
			(xy 93.851222 -289.72256)
		)
		(stroke
			(width 0)
			(type solid)
		)
		(fill yes)
		(layer "In2.Cu")
		(net "M_C_CPU1_SB_DQ<25>")
	)
	(gr_poly
		(pts
			(xy 93.851222 -289.27425) (xy 93.851222 -289.2298) (xy 93.65107 -289.2298) (xy 93.65107 -289.27425)
			(xy 93.751146 -289.374326)
		)
		(stroke
			(width 0)
			(type solid)
		)
		(fill yes)
		(layer "In2.Cu")
		(net "M_C_CPU1_SB_DQ<26>")
	)
	(gr_poly
		(pts
			(xy 93.851222 -288.058098) (xy 93.751146 -287.958022) (xy 93.65107 -288.058098) (xy 93.65107 -288.102548)
			(xy 93.851222 -288.102548)
		)
		(stroke
			(width 0)
			(type solid)
		)
		(fill yes)
		(layer "In2.Cu")
		(net "M_C_CPU1_SB_DQ<21>")
	)
	(gr_poly
		(pts
			(xy 93.851222 -287.654492) (xy 93.851222 -287.610042) (xy 93.65107 -287.610042) (xy 93.65107 -287.654492)
			(xy 93.751146 -287.754568)
		)
		(stroke
			(width 0)
			(type solid)
		)
		(fill yes)
		(layer "In2.Cu")
		(net "M_C_CPU1_SB_DQ<22>")
	)
	(gr_poly
		(pts
			(xy 93.851222 -286.438086) (xy 93.751146 -286.33801) (xy 93.65107 -286.438086) (xy 93.65107 -286.485838)
			(xy 93.851222 -286.485838)
		)
		(stroke
			(width 0)
			(type solid)
		)
		(fill yes)
		(layer "In2.Cu")
		(net "M_C_CPU1_SB_DQS_DN<7>")
	)
	(gr_poly
		(pts
			(xy 93.851222 -286.034734) (xy 93.851222 -285.986982) (xy 93.65107 -285.986982) (xy 93.65107 -286.034734)
			(xy 93.751146 -286.134556)
		)
		(stroke
			(width 0)
			(type solid)
		)
		(fill yes)
		(layer "In2.Cu")
		(net "M_C_CPU1_SB_DQS_DN<2>")
	)
	(gr_poly
		(pts
			(xy 93.851222 -284.818328) (xy 93.751146 -284.718252) (xy 93.65107 -284.818328) (xy 93.65107 -284.862778)
			(xy 93.851222 -284.862778)
		)
		(stroke
			(width 0)
			(type solid)
		)
		(fill yes)
		(layer "In2.Cu")
		(net "M_C_CPU1_SB_DQ<17>")
	)
	(gr_poly
		(pts
			(xy 93.851222 -284.414468) (xy 93.851222 -284.370018) (xy 93.65107 -284.370018) (xy 93.65107 -284.414468)
			(xy 93.751146 -284.514544)
		)
		(stroke
			(width 0)
			(type solid)
		)
		(fill yes)
		(layer "In2.Cu")
		(net "M_C_CPU1_SB_DQ<18>")
	)
	(gr_poly
		(pts
			(xy 93.851222 -283.198316) (xy 93.751146 -283.09824) (xy 93.65107 -283.198316) (xy 93.65107 -283.242766)
			(xy 93.851222 -283.242766)
		)
		(stroke
			(width 0)
			(type solid)
		)
		(fill yes)
		(layer "In2.Cu")
		(net "M_C_CPU1_SB_DQ<13>")
	)
	(gr_poly
		(pts
			(xy 93.851222 -282.794456) (xy 93.851222 -282.750006) (xy 93.65107 -282.750006) (xy 93.65107 -282.794456)
			(xy 93.751146 -282.894532)
		)
		(stroke
			(width 0)
			(type solid)
		)
		(fill yes)
		(layer "In2.Cu")
		(net "M_C_CPU1_SB_DQ<14>")
	)
	(gr_poly
		(pts
			(xy 93.851222 -281.57805) (xy 93.751146 -281.478228) (xy 93.65107 -281.57805) (xy 93.65107 -281.625802)
			(xy 93.851222 -281.625802)
		)
		(stroke
			(width 0)
			(type solid)
		)
		(fill yes)
		(layer "In2.Cu")
		(net "M_C_CPU1_SB_DQS_DN<6>")
	)
	(gr_poly
		(pts
			(xy 93.851222 -281.174698) (xy 93.851222 -281.126946) (xy 93.65107 -281.126946) (xy 93.65107 -281.174698)
			(xy 93.751146 -281.27452)
		)
		(stroke
			(width 0)
			(type solid)
		)
		(fill yes)
		(layer "In2.Cu")
		(net "M_C_CPU1_SB_DQS_DN<1>")
	)
	(gr_poly
		(pts
			(xy 93.851222 -279.958292) (xy 93.751146 -279.858216) (xy 93.65107 -279.958292) (xy 93.65107 -280.002742)
			(xy 93.851222 -280.002742)
		)
		(stroke
			(width 0)
			(type solid)
		)
		(fill yes)
		(layer "In2.Cu")
		(net "M_C_CPU1_SB_DQ<9>")
	)
	(gr_poly
		(pts
			(xy 93.851222 -279.554432) (xy 93.851222 -279.509982) (xy 93.65107 -279.509982) (xy 93.65107 -279.554432)
			(xy 93.751146 -279.654508)
		)
		(stroke
			(width 0)
			(type solid)
		)
		(fill yes)
		(layer "In2.Cu")
		(net "M_C_CPU1_SB_DQ<10>")
	)
	(gr_poly
		(pts
			(xy 93.851222 -278.33828) (xy 93.751146 -278.238204) (xy 93.65107 -278.33828) (xy 93.65107 -278.38273)
			(xy 93.851222 -278.38273)
		)
		(stroke
			(width 0)
			(type solid)
		)
		(fill yes)
		(layer "In2.Cu")
		(net "M_C_CPU1_SB_DQ<5>")
	)
	(gr_poly
		(pts
			(xy 93.851222 -277.93442) (xy 93.851222 -277.88997) (xy 93.65107 -277.88997) (xy 93.65107 -277.93442)
			(xy 93.751146 -278.034496)
		)
		(stroke
			(width 0)
			(type solid)
		)
		(fill yes)
		(layer "In2.Cu")
		(net "M_C_CPU1_SB_DQ<6>")
	)
	(gr_poly
		(pts
			(xy 93.851222 -276.718014) (xy 93.751146 -276.618192) (xy 93.65107 -276.718014) (xy 93.65107 -276.765766)
			(xy 93.851222 -276.765766)
		)
		(stroke
			(width 0)
			(type solid)
		)
		(fill yes)
		(layer "In2.Cu")
		(net "M_C_CPU1_SB_DQS_DN<5>")
	)
	(gr_poly
		(pts
			(xy 93.851222 -276.314662) (xy 93.851222 -276.26691) (xy 93.65107 -276.26691) (xy 93.65107 -276.314662)
			(xy 93.751146 -276.414484)
		)
		(stroke
			(width 0)
			(type solid)
		)
		(fill yes)
		(layer "In2.Cu")
		(net "M_C_CPU1_SB_DQS_DN<0>")
	)
	(gr_poly
		(pts
			(xy 93.851222 -275.098256) (xy 93.751146 -274.99818) (xy 93.65107 -275.098256) (xy 93.65107 -275.142706)
			(xy 93.851222 -275.142706)
		)
		(stroke
			(width 0)
			(type solid)
		)
		(fill yes)
		(layer "In2.Cu")
		(net "M_C_CPU1_SB_DQ<1>")
	)
	(gr_poly
		(pts
			(xy 93.851222 -274.694396) (xy 93.851222 -274.649946) (xy 93.65107 -274.649946) (xy 93.65107 -274.694396)
			(xy 93.751146 -274.794472)
		)
		(stroke
			(width 0)
			(type solid)
		)
		(fill yes)
		(layer "In2.Cu")
		(net "M_C_CPU1_SB_DQ<2>")
	)
	(gr_poly
		(pts
			(xy 93.851222 -273.478244) (xy 93.751146 -273.378168) (xy 93.65107 -273.478244) (xy 93.65107 -273.522694)
			(xy 93.851222 -273.522694)
		)
		(stroke
			(width 0)
			(type solid)
		)
		(fill yes)
		(layer "In2.Cu")
		(net "M_C_CPU1_SB_CB<1>")
	)
	(gr_poly
		(pts
			(xy 93.851222 -273.074384) (xy 93.851222 -273.029934) (xy 93.65107 -273.029934) (xy 93.65107 -273.074384)
			(xy 93.751146 -273.17446)
		)
		(stroke
			(width 0)
			(type solid)
		)
		(fill yes)
		(layer "In2.Cu")
		(net "M_C_CPU1_SB_CB<2>")
	)
	(gr_poly
		(pts
			(xy 93.851222 -271.857978) (xy 93.751146 -271.758156) (xy 93.65107 -271.857978) (xy 93.65107 -271.90573)
			(xy 93.851222 -271.90573)
		)
		(stroke
			(width 0)
			(type solid)
		)
		(fill yes)
		(layer "In2.Cu")
		(net "M_C_CPU1_SB_DQS_DN<4>")
	)
	(gr_poly
		(pts
			(xy 93.851222 -271.454626) (xy 93.851222 -271.406874) (xy 93.65107 -271.406874) (xy 93.65107 -271.454626)
			(xy 93.751146 -271.554448)
		)
		(stroke
			(width 0)
			(type solid)
		)
		(fill yes)
		(layer "In2.Cu")
		(net "M_C_CPU1_SB_DQS_DN<9>")
	)
	(gr_poly
		(pts
			(xy 93.851222 -270.23822) (xy 93.751146 -270.138144) (xy 93.65107 -270.23822) (xy 93.65107 -270.28267)
			(xy 93.851222 -270.28267)
		)
		(stroke
			(width 0)
			(type solid)
		)
		(fill yes)
		(layer "In2.Cu")
		(net "M_C_CPU1_SB_CB<5>")
	)
	(gr_poly
		(pts
			(xy 93.851222 -269.83436) (xy 93.851222 -269.78991) (xy 93.65107 -269.78991) (xy 93.65107 -269.83436)
			(xy 93.751146 -269.934436)
		)
		(stroke
			(width 0)
			(type solid)
		)
		(fill yes)
		(layer "In2.Cu")
		(net "M_C_CPU1_SB_CB<6>")
	)
	(gr_poly
		(pts
			(xy 93.851222 -266.594336) (xy 93.851222 -266.549886) (xy 93.65107 -266.549886) (xy 93.65107 -266.594336)
			(xy 93.751146 -266.694412)
		)
		(stroke
			(width 0)
			(type solid)
		)
		(fill yes)
		(layer "In2.Cu")
		(net "M_C_CPU1_SB_CS_N<1>")
	)
	(gr_poly
		(pts
			(xy 93.851222 -264.974324) (xy 93.851222 -264.929874) (xy 93.65107 -264.929874) (xy 93.65107 -264.974324)
			(xy 93.751146 -265.0744)
		)
		(stroke
			(width 0)
			(type solid)
		)
		(fill yes)
		(layer "In2.Cu")
		(net "M_C_CPU1_SB_PAR")
	)
	(gr_poly
		(pts
			(xy 93.851222 -263.758172) (xy 93.751146 -263.658096) (xy 93.65107 -263.758172) (xy 93.65107 -263.802622)
			(xy 93.851222 -263.802622)
		)
		(stroke
			(width 0)
			(type solid)
		)
		(fill yes)
		(layer "In2.Cu")
		(net "M_C_CPU1_SB_CA<4>")
	)
	(gr_poly
		(pts
			(xy 93.851222 -263.354312) (xy 93.851222 -263.309862) (xy 93.65107 -263.309862) (xy 93.65107 -263.354312)
			(xy 93.751146 -263.454388)
		)
		(stroke
			(width 0)
			(type solid)
		)
		(fill yes)
		(layer "In2.Cu")
		(net "M_C_CPU1_SB_CA<3>")
	)
	(gr_poly
		(pts
			(xy 93.851222 -262.13816) (xy 93.751146 -262.038084) (xy 93.65107 -262.13816) (xy 93.65107 -262.18261)
			(xy 93.851222 -262.18261)
		)
		(stroke
			(width 0)
			(type solid)
		)
		(fill yes)
		(layer "In2.Cu")
		(net "M_C_CPU1_SB_CA<0>")
	)
	(gr_poly
		(pts
			(xy 93.96857 -256.439416) (xy 93.972888 -256.391918) (xy 93.773498 -256.374392) (xy 93.769434 -256.42189)
			(xy 93.860366 -256.530094)
		)
		(stroke
			(width 0)
			(type solid)
		)
		(fill yes)
		(layer "In2.Cu")
		(net "M_C_CPU1_CLK_DN<0>")
	)
	(gr_poly
		(pts
			(xy 93.96857 -246.71909) (xy 93.972888 -246.671592) (xy 93.773498 -246.654066) (xy 93.769434 -246.701564)
			(xy 93.860366 -246.810022)
		)
		(stroke
			(width 0)
			(type solid)
		)
		(fill yes)
		(layer "In2.Cu")
		(net "M_C_CPU1_SA_DQS_DN<4>")
	)
	(gr_poly
		(pts
			(xy 93.96857 -241.859308) (xy 93.972888 -241.81181) (xy 93.773498 -241.794284) (xy 93.769434 -241.841782)
			(xy 93.860366 -241.949986)
		)
		(stroke
			(width 0)
			(type solid)
		)
		(fill yes)
		(layer "In2.Cu")
		(net "M_C_CPU1_SA_DQS_DN<3>")
	)
	(gr_poly
		(pts
			(xy 93.96857 -236.999272) (xy 93.972888 -236.951774) (xy 93.773498 -236.934248) (xy 93.769434 -236.981746)
			(xy 93.860366 -237.08995)
		)
		(stroke
			(width 0)
			(type solid)
		)
		(fill yes)
		(layer "In2.Cu")
		(net "M_C_CPU1_SA_DQS_DN<2>")
	)
	(gr_poly
		(pts
			(xy 93.96857 -232.139236) (xy 93.972888 -232.091738) (xy 93.773498 -232.074212) (xy 93.769434 -232.12171)
			(xy 93.860366 -232.229914)
		)
		(stroke
			(width 0)
			(type solid)
		)
		(fill yes)
		(layer "In2.Cu")
		(net "M_C_CPU1_SA_DQS_DN<1>")
	)
	(gr_poly
		(pts
			(xy 93.979492 -227.280216) (xy 93.98381 -227.232718) (xy 93.78442 -227.215192) (xy 93.780356 -227.26269)
			(xy 93.871288 -227.371148)
		)
		(stroke
			(width 0)
			(type solid)
		)
		(fill yes)
		(layer "In2.Cu")
		(net "M_C_CPU1_SA_DQS_DN<0>")
	)
	(gr_poly
		(pts
			(xy 93.981524 -254.820166) (xy 93.985334 -254.775716) (xy 93.786198 -254.758444) (xy 93.782388 -254.80264)
			(xy 93.87332 -254.911098)
		)
		(stroke
			(width 0)
			(type solid)
		)
		(fill yes)
		(layer "In2.Cu")
		(net "M_C_CPU1_SA_CA<5>")
	)
	(gr_poly
		(pts
			(xy 93.981524 -253.200154) (xy 93.985334 -253.155704) (xy 93.786198 -253.138432) (xy 93.782388 -253.182628)
			(xy 93.87332 -253.291086)
		)
		(stroke
			(width 0)
			(type solid)
		)
		(fill yes)
		(layer "In2.Cu")
		(net "M_C_CPU1_SA_CA<1>")
	)
	(gr_poly
		(pts
			(xy 93.981524 -251.580142) (xy 93.985334 -251.535692) (xy 93.786198 -251.51842) (xy 93.782388 -251.562616)
			(xy 93.87332 -251.671074)
		)
		(stroke
			(width 0)
			(type solid)
		)
		(fill yes)
		(layer "In2.Cu")
		(net "M_C_CPU1_SA_CS_N<0>")
	)
	(gr_poly
		(pts
			(xy 93.981524 -248.340118) (xy 93.985334 -248.295668) (xy 93.786198 -248.278396) (xy 93.782388 -248.322592)
			(xy 93.87332 -248.43105)
		)
		(stroke
			(width 0)
			(type solid)
		)
		(fill yes)
		(layer "In2.Cu")
		(net "M_C_CPU1_SA_CB<6>")
	)
	(gr_poly
		(pts
			(xy 93.981524 -245.100094) (xy 93.985334 -245.055644) (xy 93.786198 -245.038372) (xy 93.782388 -245.082568)
			(xy 93.87332 -245.191026)
		)
		(stroke
			(width 0)
			(type solid)
		)
		(fill yes)
		(layer "In2.Cu")
		(net "M_C_CPU1_SA_CB<2>")
	)
	(gr_poly
		(pts
			(xy 93.981524 -243.480082) (xy 93.985334 -243.435632) (xy 93.786198 -243.41836) (xy 93.782388 -243.462556)
			(xy 93.87332 -243.571014)
		)
		(stroke
			(width 0)
			(type solid)
		)
		(fill yes)
		(layer "In2.Cu")
		(net "M_C_CPU1_SA_DQ<30>")
	)
	(gr_poly
		(pts
			(xy 93.981524 -240.240058) (xy 93.985334 -240.195608) (xy 93.786198 -240.178336) (xy 93.782388 -240.222532)
			(xy 93.87332 -240.33099)
		)
		(stroke
			(width 0)
			(type solid)
		)
		(fill yes)
		(layer "In2.Cu")
		(net "M_C_CPU1_SA_DQ<26>")
	)
	(gr_poly
		(pts
			(xy 93.981524 -238.620046) (xy 93.985334 -238.575596) (xy 93.786198 -238.558324) (xy 93.782388 -238.60252)
			(xy 93.87332 -238.710978)
		)
		(stroke
			(width 0)
			(type solid)
		)
		(fill yes)
		(layer "In2.Cu")
		(net "M_C_CPU1_SA_DQ<22>")
	)
	(gr_poly
		(pts
			(xy 93.981524 -235.380022) (xy 93.985334 -235.335572) (xy 93.786198 -235.3183) (xy 93.782388 -235.362496)
			(xy 93.87332 -235.470954)
		)
		(stroke
			(width 0)
			(type solid)
		)
		(fill yes)
		(layer "In2.Cu")
		(net "M_C_CPU1_SA_DQ<18>")
	)
	(gr_poly
		(pts
			(xy 93.981524 -233.76001) (xy 93.985334 -233.71556) (xy 93.786198 -233.698288) (xy 93.782388 -233.742484)
			(xy 93.87332 -233.850942)
		)
		(stroke
			(width 0)
			(type solid)
		)
		(fill yes)
		(layer "In2.Cu")
		(net "M_C_CPU1_SA_DQ<14>")
	)
	(gr_poly
		(pts
			(xy 93.981524 -230.52024) (xy 93.985334 -230.47579) (xy 93.786198 -230.458518) (xy 93.782388 -230.502714)
			(xy 93.87332 -230.611172)
		)
		(stroke
			(width 0)
			(type solid)
		)
		(fill yes)
		(layer "In2.Cu")
		(net "M_C_CPU1_SA_DQ<10>")
	)
	(gr_poly
		(pts
			(xy 93.981524 -228.900228) (xy 93.985334 -228.855778) (xy 93.786198 -228.838506) (xy 93.782388 -228.882702)
			(xy 93.87332 -228.99116)
		)
		(stroke
			(width 0)
			(type solid)
		)
		(fill yes)
		(layer "In2.Cu")
		(net "M_C_CPU1_SA_DQ<6>")
	)
	(gr_poly
		(pts
			(xy 93.981524 -225.660204) (xy 93.985334 -225.615754) (xy 93.786198 -225.598482) (xy 93.782388 -225.642678)
			(xy 93.87332 -225.751136)
		)
		(stroke
			(width 0)
			(type solid)
		)
		(fill yes)
		(layer "In2.Cu")
		(net "M_C_CPU1_SA_DQ<2>")
	)
	(gr_poly
		(pts
			(xy 94.021148 -255.216406) (xy 93.921072 -255.11633) (xy 93.820996 -255.216406) (xy 93.820996 -255.260856)
			(xy 94.021148 -255.260856)
		)
		(stroke
			(width 0)
			(type solid)
		)
		(fill yes)
		(layer "In2.Cu")
		(net "M_C_CPU1_SA_CA<6>")
	)
	(gr_poly
		(pts
			(xy 94.021148 -253.596394) (xy 93.921072 -253.496318) (xy 93.820996 -253.596394) (xy 93.820996 -253.640844)
			(xy 94.021148 -253.640844)
		)
		(stroke
			(width 0)
			(type solid)
		)
		(fill yes)
		(layer "In2.Cu")
		(net "M_C_CPU1_SA_CA<2>")
	)
	(gr_poly
		(pts
			(xy 94.021148 -250.35637) (xy 93.921072 -250.256294) (xy 93.820996 -250.35637) (xy 93.820996 -250.40082)
			(xy 94.021148 -250.40082)
		)
		(stroke
			(width 0)
			(type solid)
		)
		(fill yes)
		(layer "In2.Cu")
		(net "M_C_CPU1_ALERT_R_N")
	)
	(gr_poly
		(pts
			(xy 94.021148 -248.736358) (xy 93.921072 -248.636282) (xy 93.820996 -248.736358) (xy 93.820996 -248.780808)
			(xy 94.021148 -248.780808)
		)
		(stroke
			(width 0)
			(type solid)
		)
		(fill yes)
		(layer "In2.Cu")
		(net "M_C_CPU1_SA_CB<5>")
	)
	(gr_poly
		(pts
			(xy 94.021148 -247.116092) (xy 93.921072 -247.01627) (xy 93.820996 -247.116092) (xy 93.820996 -247.163844)
			(xy 94.021148 -247.163844)
		)
		(stroke
			(width 0)
			(type solid)
		)
		(fill yes)
		(layer "In2.Cu")
		(net "M_C_CPU1_SA_DQS_DN<9>")
	)
	(gr_poly
		(pts
			(xy 94.021148 -245.496334) (xy 93.921072 -245.396258) (xy 93.820996 -245.496334) (xy 93.820996 -245.540784)
			(xy 94.021148 -245.540784)
		)
		(stroke
			(width 0)
			(type solid)
		)
		(fill yes)
		(layer "In2.Cu")
		(net "M_C_CPU1_SA_CB<1>")
	)
	(gr_poly
		(pts
			(xy 94.021148 -243.876322) (xy 93.921072 -243.776246) (xy 93.820996 -243.876322) (xy 93.820996 -243.920772)
			(xy 94.021148 -243.920772)
		)
		(stroke
			(width 0)
			(type solid)
		)
		(fill yes)
		(layer "In2.Cu")
		(net "M_C_CPU1_SA_DQ<29>")
	)
	(gr_poly
		(pts
			(xy 94.021148 -242.256056) (xy 93.921072 -242.156234) (xy 93.820996 -242.256056) (xy 93.820996 -242.303808)
			(xy 94.021148 -242.303808)
		)
		(stroke
			(width 0)
			(type solid)
		)
		(fill yes)
		(layer "In2.Cu")
		(net "M_C_CPU1_SA_DQS_DN<8>")
	)
	(gr_poly
		(pts
			(xy 94.021148 -240.636298) (xy 93.921072 -240.536222) (xy 93.820996 -240.636298) (xy 93.820996 -240.680748)
			(xy 94.021148 -240.680748)
		)
		(stroke
			(width 0)
			(type solid)
		)
		(fill yes)
		(layer "In2.Cu")
		(net "M_C_CPU1_SA_DQ<25>")
	)
	(gr_poly
		(pts
			(xy 94.021148 -239.016286) (xy 93.921072 -238.91621) (xy 93.820996 -239.016286) (xy 93.820996 -239.060736)
			(xy 94.021148 -239.060736)
		)
		(stroke
			(width 0)
			(type solid)
		)
		(fill yes)
		(layer "In2.Cu")
		(net "M_C_CPU1_SA_DQ<21>")
	)
	(gr_poly
		(pts
			(xy 94.021148 -237.39602) (xy 93.921072 -237.296198) (xy 93.820996 -237.39602) (xy 93.820996 -237.443772)
			(xy 94.021148 -237.443772)
		)
		(stroke
			(width 0)
			(type solid)
		)
		(fill yes)
		(layer "In2.Cu")
		(net "M_C_CPU1_SA_DQS_DN<7>")
	)
	(gr_poly
		(pts
			(xy 94.021148 -235.776262) (xy 93.921072 -235.676186) (xy 93.820996 -235.776262) (xy 93.820996 -235.820712)
			(xy 94.021148 -235.820712)
		)
		(stroke
			(width 0)
			(type solid)
		)
		(fill yes)
		(layer "In2.Cu")
		(net "M_C_CPU1_SA_DQ<17>")
	)
	(gr_poly
		(pts
			(xy 94.021148 -234.15625) (xy 93.921072 -234.056174) (xy 93.820996 -234.15625) (xy 93.820996 -234.2007)
			(xy 94.021148 -234.2007)
		)
		(stroke
			(width 0)
			(type solid)
		)
		(fill yes)
		(layer "In2.Cu")
		(net "M_C_CPU1_SA_DQ<13>")
	)
	(gr_poly
		(pts
			(xy 94.021148 -232.535984) (xy 93.921072 -232.436162) (xy 93.820996 -232.535984) (xy 93.820996 -232.583736)
			(xy 94.021148 -232.583736)
		)
		(stroke
			(width 0)
			(type solid)
		)
		(fill yes)
		(layer "In2.Cu")
		(net "M_C_CPU1_SA_DQS_DN<6>")
	)
	(gr_poly
		(pts
			(xy 94.021148 -230.916226) (xy 93.921072 -230.81615) (xy 93.820996 -230.916226) (xy 93.820996 -230.960676)
			(xy 94.021148 -230.960676)
		)
		(stroke
			(width 0)
			(type solid)
		)
		(fill yes)
		(layer "In2.Cu")
		(net "M_C_CPU1_SA_DQ<9>")
	)
	(gr_poly
		(pts
			(xy 94.021148 -229.296214) (xy 93.921072 -229.196138) (xy 93.820996 -229.296214) (xy 93.820996 -229.340664)
			(xy 94.021148 -229.340664)
		)
		(stroke
			(width 0)
			(type solid)
		)
		(fill yes)
		(layer "In2.Cu")
		(net "M_C_CPU1_SA_DQ<5>")
	)
	(gr_poly
		(pts
			(xy 94.021148 -227.676202) (xy 93.921072 -227.57638) (xy 93.820996 -227.676202) (xy 93.820996 -227.723954)
			(xy 94.021148 -227.723954)
		)
		(stroke
			(width 0)
			(type solid)
		)
		(fill yes)
		(layer "In2.Cu")
		(net "M_C_CPU1_SA_DQS_DN<5>")
	)
	(gr_poly
		(pts
			(xy 94.021148 -226.056444) (xy 93.921072 -225.956368) (xy 93.820996 -226.056444) (xy 93.820996 -226.100894)
			(xy 94.021148 -226.100894)
		)
		(stroke
			(width 0)
			(type solid)
		)
		(fill yes)
		(layer "In2.Cu")
		(net "M_C_CPU1_SA_DQ<1>")
	)
	(gr_poly
		(pts
			(xy 94.273116 -280.808938) (xy 94.268798 -280.76144) (xy 94.160594 -280.670508) (xy 94.069662 -280.778966)
			(xy 94.073726 -280.826464)
		)
		(stroke
			(width 0)
			(type solid)
		)
		(fill yes)
		(layer "In2.Cu")
		(net "M_C_CPU1_SB_DQS_DP<1>")
	)
	(gr_poly
		(pts
			(xy 94.283022 -267.838936) (xy 94.278958 -267.794486) (xy 94.170754 -267.703554) (xy 94.079822 -267.812012)
			(xy 94.083632 -267.856208)
		)
		(stroke
			(width 0)
			(type solid)
		)
		(fill yes)
		(layer "In2.Cu")
		(net "M_C_CPU1_SB_RSP<0>")
	)
	(gr_poly
		(pts
			(xy 94.28353 -290.527994) (xy 94.279466 -290.480496) (xy 94.171262 -290.389564) (xy 94.08033 -290.498022)
			(xy 94.084394 -290.54552)
		)
		(stroke
			(width 0)
			(type solid)
		)
		(fill yes)
		(layer "In2.Cu")
		(net "M_C_CPU1_SB_DQS_DP<3>")
	)
	(gr_poly
		(pts
			(xy 94.28353 -285.668212) (xy 94.279466 -285.620714) (xy 94.171262 -285.529782) (xy 94.08033 -285.63824)
			(xy 94.084394 -285.685484)
		)
		(stroke
			(width 0)
			(type solid)
		)
		(fill yes)
		(layer "In2.Cu")
		(net "M_C_CPU1_SB_DQS_DP<2>")
	)
	(gr_poly
		(pts
			(xy 94.28353 -275.94814) (xy 94.279466 -275.900642) (xy 94.171262 -275.80971) (xy 94.08033 -275.918168)
			(xy 94.084394 -275.965412)
		)
		(stroke
			(width 0)
			(type solid)
		)
		(fill yes)
		(layer "In2.Cu")
		(net "M_C_CPU1_SB_DQS_DP<0>")
	)
	(gr_poly
		(pts
			(xy 94.28353 -271.088104) (xy 94.279466 -271.040606) (xy 94.171262 -270.949674) (xy 94.08033 -271.058132)
			(xy 94.084394 -271.105376)
		)
		(stroke
			(width 0)
			(type solid)
		)
		(fill yes)
		(layer "In2.Cu")
		(net "M_C_CPU1_SB_DQS_DP<9>")
	)
	(gr_poly
		(pts
			(xy 94.285562 -292.144958) (xy 94.281498 -292.100508) (xy 94.173294 -292.009576) (xy 94.082362 -292.118034)
			(xy 94.086172 -292.16223)
		)
		(stroke
			(width 0)
			(type solid)
		)
		(fill yes)
		(layer "In2.Cu")
		(net "M_C_CPU1_SB_DQ<28>")
	)
	(gr_poly
		(pts
			(xy 94.285562 -288.904934) (xy 94.281498 -288.860484) (xy 94.173294 -288.769552) (xy 94.082362 -288.87801)
			(xy 94.086172 -288.922206)
		)
		(stroke
			(width 0)
			(type solid)
		)
		(fill yes)
		(layer "In2.Cu")
		(net "M_C_CPU1_SB_DQ<24>")
	)
	(gr_poly
		(pts
			(xy 94.285562 -287.284922) (xy 94.281498 -287.240472) (xy 94.173294 -287.14954) (xy 94.082362 -287.257998)
			(xy 94.086172 -287.302194)
		)
		(stroke
			(width 0)
			(type solid)
		)
		(fill yes)
		(layer "In2.Cu")
		(net "M_C_CPU1_SB_DQ<20>")
	)
	(gr_poly
		(pts
			(xy 94.285562 -284.045152) (xy 94.281498 -284.000702) (xy 94.173294 -283.90977) (xy 94.082362 -284.018228)
			(xy 94.086172 -284.062424)
		)
		(stroke
			(width 0)
			(type solid)
		)
		(fill yes)
		(layer "In2.Cu")
		(net "M_C_CPU1_SB_DQ<16>")
	)
	(gr_poly
		(pts
			(xy 94.285562 -282.42514) (xy 94.281498 -282.38069) (xy 94.173294 -282.289758) (xy 94.082362 -282.398216)
			(xy 94.086172 -282.442412)
		)
		(stroke
			(width 0)
			(type solid)
		)
		(fill yes)
		(layer "In2.Cu")
		(net "M_C_CPU1_SB_DQ<12>")
	)
	(gr_poly
		(pts
			(xy 94.285562 -279.185116) (xy 94.281498 -279.140666) (xy 94.173294 -279.049734) (xy 94.082362 -279.158192)
			(xy 94.086172 -279.202388)
		)
		(stroke
			(width 0)
			(type solid)
		)
		(fill yes)
		(layer "In2.Cu")
		(net "M_C_CPU1_SB_DQ<8>")
	)
	(gr_poly
		(pts
			(xy 94.285562 -277.565104) (xy 94.281498 -277.520654) (xy 94.173294 -277.429722) (xy 94.082362 -277.53818)
			(xy 94.086172 -277.582376)
		)
		(stroke
			(width 0)
			(type solid)
		)
		(fill yes)
		(layer "In2.Cu")
		(net "M_C_CPU1_SB_DQ<4>")
	)
	(gr_poly
		(pts
			(xy 94.285562 -274.32508) (xy 94.281498 -274.28063) (xy 94.173294 -274.189698) (xy 94.082362 -274.298156)
			(xy 94.086172 -274.342352)
		)
		(stroke
			(width 0)
			(type solid)
		)
		(fill yes)
		(layer "In2.Cu")
		(net "M_C_CPU1_SB_DQ<0>")
	)
	(gr_poly
		(pts
			(xy 94.285562 -272.705068) (xy 94.281498 -272.660618) (xy 94.173294 -272.569686) (xy 94.082362 -272.678144)
			(xy 94.086172 -272.72234)
		)
		(stroke
			(width 0)
			(type solid)
		)
		(fill yes)
		(layer "In2.Cu")
		(net "M_C_CPU1_SB_CB<0>")
	)
	(gr_poly
		(pts
			(xy 94.285562 -269.465044) (xy 94.281498 -269.420594) (xy 94.173294 -269.329662) (xy 94.082362 -269.43812)
			(xy 94.086172 -269.482316)
		)
		(stroke
			(width 0)
			(type solid)
		)
		(fill yes)
		(layer "In2.Cu")
		(net "M_C_CPU1_SB_CB<4>")
	)
	(gr_poly
		(pts
			(xy 94.285562 -264.605008) (xy 94.281498 -264.560558) (xy 94.173294 -264.469626) (xy 94.082362 -264.578084)
			(xy 94.086172 -264.62228)
		)
		(stroke
			(width 0)
			(type solid)
		)
		(fill yes)
		(layer "In2.Cu")
		(net "M_C_CPU1_SB_CA<6>")
	)
	(gr_poly
		(pts
			(xy 94.285562 -262.984996) (xy 94.281498 -262.940546) (xy 94.173294 -262.849614) (xy 94.082362 -262.958072)
			(xy 94.086172 -263.002268)
		)
		(stroke
			(width 0)
			(type solid)
		)
		(fill yes)
		(layer "In2.Cu")
		(net "M_C_CPU1_SB_CA<2>")
	)
	(gr_poly
		(pts
			(xy 94.321122 -293.32428) (xy 94.321122 -293.27983) (xy 94.12097 -293.27983) (xy 94.12097 -293.32428)
			(xy 94.221046 -293.424356)
		)
		(stroke
			(width 0)
			(type solid)
		)
		(fill yes)
		(layer "In2.Cu")
		(net "M_C_CPU1_SB_DQ<31>")
	)
	(gr_poly
		(pts
			(xy 94.321122 -291.704522) (xy 94.321122 -291.65677) (xy 94.12097 -291.65677) (xy 94.12097 -291.704522)
			(xy 94.221046 -291.804344)
		)
		(stroke
			(width 0)
			(type solid)
		)
		(fill yes)
		(layer "In2.Cu")
		(net "M_C_CPU1_SB_DQS_DP<8>")
	)
	(gr_poly
		(pts
			(xy 94.321122 -290.084256) (xy 94.321122 -290.039806) (xy 94.12097 -290.039806) (xy 94.12097 -290.084256)
			(xy 94.221046 -290.184332)
		)
		(stroke
			(width 0)
			(type solid)
		)
		(fill yes)
		(layer "In2.Cu")
		(net "M_C_CPU1_SB_DQ<27>")
	)
	(gr_poly
		(pts
			(xy 94.321122 -288.464498) (xy 94.321122 -288.420048) (xy 94.12097 -288.420048) (xy 94.12097 -288.464498)
			(xy 94.221046 -288.564574)
		)
		(stroke
			(width 0)
			(type solid)
		)
		(fill yes)
		(layer "In2.Cu")
		(net "M_C_CPU1_SB_DQ<23>")
	)
	(gr_poly
		(pts
			(xy 94.321122 -286.844486) (xy 94.321122 -286.796734) (xy 94.12097 -286.796734) (xy 94.12097 -286.844486)
			(xy 94.221046 -286.944562)
		)
		(stroke
			(width 0)
			(type solid)
		)
		(fill yes)
		(layer "In2.Cu")
		(net "M_C_CPU1_SB_DQS_DP<7>")
	)
	(gr_poly
		(pts
			(xy 94.321122 -285.224474) (xy 94.321122 -285.180024) (xy 94.12097 -285.180024) (xy 94.12097 -285.224474)
			(xy 94.221046 -285.32455)
		)
		(stroke
			(width 0)
			(type solid)
		)
		(fill yes)
		(layer "In2.Cu")
		(net "M_C_CPU1_SB_DQ<19>")
	)
	(gr_poly
		(pts
			(xy 94.321122 -283.604462) (xy 94.321122 -283.560012) (xy 94.12097 -283.560012) (xy 94.12097 -283.604462)
			(xy 94.221046 -283.704538)
		)
		(stroke
			(width 0)
			(type solid)
		)
		(fill yes)
		(layer "In2.Cu")
		(net "M_C_CPU1_SB_DQ<15>")
	)
	(gr_poly
		(pts
			(xy 94.321122 -281.984704) (xy 94.321122 -281.936952) (xy 94.12097 -281.936952) (xy 94.12097 -281.984704)
			(xy 94.221046 -282.084526)
		)
		(stroke
			(width 0)
			(type solid)
		)
		(fill yes)
		(layer "In2.Cu")
		(net "M_C_CPU1_SB_DQS_DP<6>")
	)
	(gr_poly
		(pts
			(xy 94.321122 -280.364438) (xy 94.321122 -280.319988) (xy 94.12097 -280.319988) (xy 94.12097 -280.364438)
			(xy 94.221046 -280.464514)
		)
		(stroke
			(width 0)
			(type solid)
		)
		(fill yes)
		(layer "In2.Cu")
		(net "M_C_CPU1_SB_DQ<11>")
	)
	(gr_poly
		(pts
			(xy 94.321122 -278.744426) (xy 94.321122 -278.699976) (xy 94.12097 -278.699976) (xy 94.12097 -278.744426)
			(xy 94.221046 -278.844502)
		)
		(stroke
			(width 0)
			(type solid)
		)
		(fill yes)
		(layer "In2.Cu")
		(net "M_C_CPU1_SB_DQ<7>")
	)
	(gr_poly
		(pts
			(xy 94.321122 -277.124668) (xy 94.321122 -277.076916) (xy 94.12097 -277.076916) (xy 94.12097 -277.124668)
			(xy 94.221046 -277.22449)
		)
		(stroke
			(width 0)
			(type solid)
		)
		(fill yes)
		(layer "In2.Cu")
		(net "M_C_CPU1_SB_DQS_DP<5>")
	)
	(gr_poly
		(pts
			(xy 94.321122 -275.504402) (xy 94.321122 -275.459952) (xy 94.12097 -275.459952) (xy 94.12097 -275.504402)
			(xy 94.221046 -275.604478)
		)
		(stroke
			(width 0)
			(type solid)
		)
		(fill yes)
		(layer "In2.Cu")
		(net "M_C_CPU1_SB_DQ<3>")
	)
	(gr_poly
		(pts
			(xy 94.321122 -273.88439) (xy 94.321122 -273.83994) (xy 94.12097 -273.83994) (xy 94.12097 -273.88439)
			(xy 94.221046 -273.984466)
		)
		(stroke
			(width 0)
			(type solid)
		)
		(fill yes)
		(layer "In2.Cu")
		(net "M_C_CPU1_SB_CB<3>")
	)
	(gr_poly
		(pts
			(xy 94.321122 -272.264632) (xy 94.321122 -272.21688) (xy 94.12097 -272.21688) (xy 94.12097 -272.264632)
			(xy 94.221046 -272.364454)
		)
		(stroke
			(width 0)
			(type solid)
		)
		(fill yes)
		(layer "In2.Cu")
		(net "M_C_CPU1_SB_DQS_DP<4>")
	)
	(gr_poly
		(pts
			(xy 94.321122 -270.644366) (xy 94.321122 -270.599916) (xy 94.12097 -270.599916) (xy 94.12097 -270.644366)
			(xy 94.221046 -270.744442)
		)
		(stroke
			(width 0)
			(type solid)
		)
		(fill yes)
		(layer "In2.Cu")
		(net "M_C_CPU1_SB_CB<7>")
	)
	(gr_poly
		(pts
			(xy 94.321122 -265.78433) (xy 94.321122 -265.73988) (xy 94.12097 -265.73988) (xy 94.12097 -265.78433)
			(xy 94.221046 -265.884406)
		)
		(stroke
			(width 0)
			(type solid)
		)
		(fill yes)
		(layer "In2.Cu")
		(net "M_C_CPU1_SB_CS_N<0>")
	)
	(gr_poly
		(pts
			(xy 94.321122 -264.164318) (xy 94.321122 -264.119868) (xy 94.12097 -264.119868) (xy 94.12097 -264.164318)
			(xy 94.221046 -264.264394)
		)
		(stroke
			(width 0)
			(type solid)
		)
		(fill yes)
		(layer "In2.Cu")
		(net "M_C_CPU1_SB_CA<5>")
	)
	(gr_poly
		(pts
			(xy 94.321122 -262.544306) (xy 94.321122 -262.499856) (xy 94.12097 -262.499856) (xy 94.12097 -262.544306)
			(xy 94.221046 -262.644382)
		)
		(stroke
			(width 0)
			(type solid)
		)
		(fill yes)
		(layer "In2.Cu")
		(net "M_C_CPU1_SB_CA<1>")
	)
	(gr_poly
		(pts
			(xy 94.491048 -255.622552) (xy 94.491048 -255.578102) (xy 94.290896 -255.578102) (xy 94.290896 -255.622552)
			(xy 94.390972 -255.722628)
		)
		(stroke
			(width 0)
			(type solid)
		)
		(fill yes)
		(layer "In2.Cu")
		(net "M_C_CPU1_SA_PAR")
	)
	(gr_poly
		(pts
			(xy 94.491048 -254.00254) (xy 94.491048 -253.95809) (xy 94.290896 -253.95809) (xy 94.290896 -254.00254)
			(xy 94.390972 -254.102616)
		)
		(stroke
			(width 0)
			(type solid)
		)
		(fill yes)
		(layer "In2.Cu")
		(net "M_C_CPU1_SA_CA<3>")
	)
	(gr_poly
		(pts
			(xy 94.491048 -252.382528) (xy 94.491048 -252.338078) (xy 94.290896 -252.338078) (xy 94.290896 -252.382528)
			(xy 94.390972 -252.482604)
		)
		(stroke
			(width 0)
			(type solid)
		)
		(fill yes)
		(layer "In2.Cu")
		(net "M_C_CPU1_SA_CS_N<1>")
	)
	(gr_poly
		(pts
			(xy 94.491048 -250.762516) (xy 94.491048 -250.718066) (xy 94.290896 -250.718066) (xy 94.290896 -250.762516)
			(xy 94.390972 -250.862592)
		)
		(stroke
			(width 0)
			(type solid)
		)
		(fill yes)
		(layer "In2.Cu")
		(net "M_C_CPU1_RESET_N")
	)
	(gr_poly
		(pts
			(xy 94.491048 -249.142504) (xy 94.491048 -249.098054) (xy 94.290896 -249.098054) (xy 94.290896 -249.142504)
			(xy 94.390972 -249.24258)
		)
		(stroke
			(width 0)
			(type solid)
		)
		(fill yes)
		(layer "In2.Cu")
		(net "M_C_CPU1_SA_CB<7>")
	)
	(gr_poly
		(pts
			(xy 94.491048 -247.522746) (xy 94.491048 -247.474994) (xy 94.290896 -247.474994) (xy 94.290896 -247.522746)
			(xy 94.390972 -247.622568)
		)
		(stroke
			(width 0)
			(type solid)
		)
		(fill yes)
		(layer "In2.Cu")
		(net "M_C_CPU1_SA_DQS_DP<9>")
	)
	(gr_poly
		(pts
			(xy 94.491048 -245.90248) (xy 94.491048 -245.85803) (xy 94.290896 -245.85803) (xy 94.290896 -245.90248)
			(xy 94.390972 -246.002556)
		)
		(stroke
			(width 0)
			(type solid)
		)
		(fill yes)
		(layer "In2.Cu")
		(net "M_C_CPU1_SA_CB<3>")
	)
	(gr_poly
		(pts
			(xy 94.491048 -244.282468) (xy 94.491048 -244.238018) (xy 94.290896 -244.238018) (xy 94.290896 -244.282468)
			(xy 94.390972 -244.382544)
		)
		(stroke
			(width 0)
			(type solid)
		)
		(fill yes)
		(layer "In2.Cu")
		(net "M_C_CPU1_SA_DQ<31>")
	)
	(gr_poly
		(pts
			(xy 94.491048 -242.66271) (xy 94.491048 -242.614958) (xy 94.290896 -242.614958) (xy 94.290896 -242.66271)
			(xy 94.390972 -242.762532)
		)
		(stroke
			(width 0)
			(type solid)
		)
		(fill yes)
		(layer "In2.Cu")
		(net "M_C_CPU1_SA_DQS_DP<8>")
	)
	(gr_poly
		(pts
			(xy 94.491048 -241.042444) (xy 94.491048 -240.997994) (xy 94.290896 -240.997994) (xy 94.290896 -241.042444)
			(xy 94.390972 -241.14252)
		)
		(stroke
			(width 0)
			(type solid)
		)
		(fill yes)
		(layer "In2.Cu")
		(net "M_C_CPU1_SA_DQ<27>")
	)
	(gr_poly
		(pts
			(xy 94.491048 -239.422432) (xy 94.491048 -239.377982) (xy 94.290896 -239.377982) (xy 94.290896 -239.422432)
			(xy 94.390972 -239.522508)
		)
		(stroke
			(width 0)
			(type solid)
		)
		(fill yes)
		(layer "In2.Cu")
		(net "M_C_CPU1_SA_DQ<23>")
	)
	(gr_poly
		(pts
			(xy 94.491048 -237.802674) (xy 94.491048 -237.754922) (xy 94.290896 -237.754922) (xy 94.290896 -237.802674)
			(xy 94.390972 -237.902496)
		)
		(stroke
			(width 0)
			(type solid)
		)
		(fill yes)
		(layer "In2.Cu")
		(net "M_C_CPU1_SA_DQS_DP<7>")
	)
	(gr_poly
		(pts
			(xy 94.491048 -236.182408) (xy 94.491048 -236.137958) (xy 94.290896 -236.137958) (xy 94.290896 -236.182408)
			(xy 94.390972 -236.282484)
		)
		(stroke
			(width 0)
			(type solid)
		)
		(fill yes)
		(layer "In2.Cu")
		(net "M_C_CPU1_SA_DQ<19>")
	)
	(gr_poly
		(pts
			(xy 94.491048 -234.562396) (xy 94.491048 -234.517946) (xy 94.290896 -234.517946) (xy 94.290896 -234.562396)
			(xy 94.390972 -234.662472)
		)
		(stroke
			(width 0)
			(type solid)
		)
		(fill yes)
		(layer "In2.Cu")
		(net "M_C_CPU1_SA_DQ<15>")
	)
	(gr_poly
		(pts
			(xy 94.491048 -232.942638) (xy 94.491048 -232.894886) (xy 94.290896 -232.894886) (xy 94.290896 -232.942638)
			(xy 94.390972 -233.04246)
		)
		(stroke
			(width 0)
			(type solid)
		)
		(fill yes)
		(layer "In2.Cu")
		(net "M_C_CPU1_SA_DQS_DP<6>")
	)
	(gr_poly
		(pts
			(xy 94.491048 -231.322626) (xy 94.491048 -231.278176) (xy 94.290896 -231.278176) (xy 94.290896 -231.322626)
			(xy 94.390972 -231.422702)
		)
		(stroke
			(width 0)
			(type solid)
		)
		(fill yes)
		(layer "In2.Cu")
		(net "M_C_CPU1_SA_DQ<11>")
	)
	(gr_poly
		(pts
			(xy 94.491048 -229.702614) (xy 94.491048 -229.658164) (xy 94.290896 -229.658164) (xy 94.290896 -229.702614)
			(xy 94.390972 -229.80269)
		)
		(stroke
			(width 0)
			(type solid)
		)
		(fill yes)
		(layer "In2.Cu")
		(net "M_C_CPU1_SA_DQ<7>")
	)
	(gr_poly
		(pts
			(xy 94.491048 -228.082856) (xy 94.491048 -228.035104) (xy 94.290896 -228.035104) (xy 94.290896 -228.082856)
			(xy 94.390972 -228.182678)
		)
		(stroke
			(width 0)
			(type solid)
		)
		(fill yes)
		(layer "In2.Cu")
		(net "M_C_CPU1_SA_DQS_DP<5>")
	)
	(gr_poly
		(pts
			(xy 94.491048 -226.46259) (xy 94.491048 -226.41814) (xy 94.290896 -226.41814) (xy 94.290896 -226.46259)
			(xy 94.390972 -226.562666)
		)
		(stroke
			(width 0)
			(type solid)
		)
		(fill yes)
		(layer "In2.Cu")
		(net "M_C_CPU1_SA_DQ<3>")
	)
	(gr_poly
		(pts
			(xy 94.791022 -292.918134) (xy 94.690946 -292.818058) (xy 94.59087 -292.918134) (xy 94.59087 -292.962584)
			(xy 94.791022 -292.962584)
		)
		(stroke
			(width 0)
			(type solid)
		)
		(fill yes)
		(layer "In2.Cu")
		(net "M_C_CPU1_SB_DQ<29>")
	)
	(gr_poly
		(pts
			(xy 94.791022 -289.67811) (xy 94.690946 -289.578034) (xy 94.59087 -289.67811) (xy 94.59087 -289.72256)
			(xy 94.791022 -289.72256)
		)
		(stroke
			(width 0)
			(type solid)
		)
		(fill yes)
		(layer "In2.Cu")
		(net "M_C_CPU1_SB_DQ<25>")
	)
	(gr_poly
		(pts
			(xy 94.791022 -288.058098) (xy 94.690946 -287.958022) (xy 94.59087 -288.058098) (xy 94.59087 -288.102548)
			(xy 94.791022 -288.102548)
		)
		(stroke
			(width 0)
			(type solid)
		)
		(fill yes)
		(layer "In2.Cu")
		(net "M_C_CPU1_SB_DQ<21>")
	)
	(gr_poly
		(pts
			(xy 94.791022 -286.438086) (xy 94.690946 -286.33801) (xy 94.59087 -286.438086) (xy 94.59087 -286.485838)
			(xy 94.791022 -286.485838)
		)
		(stroke
			(width 0)
			(type solid)
		)
		(fill yes)
		(layer "In2.Cu")
		(net "M_C_CPU1_SB_DQS_DN<7>")
	)
	(gr_poly
		(pts
			(xy 94.791022 -284.818328) (xy 94.690946 -284.718252) (xy 94.59087 -284.818328) (xy 94.59087 -284.862778)
			(xy 94.791022 -284.862778)
		)
		(stroke
			(width 0)
			(type solid)
		)
		(fill yes)
		(layer "In2.Cu")
		(net "M_C_CPU1_SB_DQ<17>")
	)
	(gr_poly
		(pts
			(xy 94.791022 -283.198316) (xy 94.690946 -283.09824) (xy 94.59087 -283.198316) (xy 94.59087 -283.242766)
			(xy 94.791022 -283.242766)
		)
		(stroke
			(width 0)
			(type solid)
		)
		(fill yes)
		(layer "In2.Cu")
		(net "M_C_CPU1_SB_DQ<13>")
	)
	(gr_poly
		(pts
			(xy 94.791022 -281.57805) (xy 94.690946 -281.478228) (xy 94.59087 -281.57805) (xy 94.59087 -281.625802)
			(xy 94.791022 -281.625802)
		)
		(stroke
			(width 0)
			(type solid)
		)
		(fill yes)
		(layer "In2.Cu")
		(net "M_C_CPU1_SB_DQS_DN<6>")
	)
	(gr_poly
		(pts
			(xy 94.791022 -279.958292) (xy 94.690946 -279.858216) (xy 94.59087 -279.958292) (xy 94.59087 -280.002742)
			(xy 94.791022 -280.002742)
		)
		(stroke
			(width 0)
			(type solid)
		)
		(fill yes)
		(layer "In2.Cu")
		(net "M_C_CPU1_SB_DQ<9>")
	)
	(gr_poly
		(pts
			(xy 94.791022 -278.33828) (xy 94.690946 -278.238204) (xy 94.59087 -278.33828) (xy 94.59087 -278.38273)
			(xy 94.791022 -278.38273)
		)
		(stroke
			(width 0)
			(type solid)
		)
		(fill yes)
		(layer "In2.Cu")
		(net "M_C_CPU1_SB_DQ<5>")
	)
	(gr_poly
		(pts
			(xy 94.791022 -276.718014) (xy 94.690946 -276.618192) (xy 94.59087 -276.718014) (xy 94.59087 -276.765766)
			(xy 94.791022 -276.765766)
		)
		(stroke
			(width 0)
			(type solid)
		)
		(fill yes)
		(layer "In2.Cu")
		(net "M_C_CPU1_SB_DQS_DN<5>")
	)
	(gr_poly
		(pts
			(xy 94.791022 -275.098256) (xy 94.690946 -274.99818) (xy 94.59087 -275.098256) (xy 94.59087 -275.142706)
			(xy 94.791022 -275.142706)
		)
		(stroke
			(width 0)
			(type solid)
		)
		(fill yes)
		(layer "In2.Cu")
		(net "M_C_CPU1_SB_DQ<1>")
	)
	(gr_poly
		(pts
			(xy 94.791022 -273.478244) (xy 94.690946 -273.378168) (xy 94.59087 -273.478244) (xy 94.59087 -273.522694)
			(xy 94.791022 -273.522694)
		)
		(stroke
			(width 0)
			(type solid)
		)
		(fill yes)
		(layer "In2.Cu")
		(net "M_C_CPU1_SB_CB<1>")
	)
	(gr_poly
		(pts
			(xy 94.791022 -271.857978) (xy 94.690946 -271.758156) (xy 94.59087 -271.857978) (xy 94.59087 -271.90573)
			(xy 94.791022 -271.90573)
		)
		(stroke
			(width 0)
			(type solid)
		)
		(fill yes)
		(layer "In2.Cu")
		(net "M_C_CPU1_SB_DQS_DN<4>")
	)
	(gr_poly
		(pts
			(xy 94.791022 -270.23822) (xy 94.690946 -270.138144) (xy 94.59087 -270.23822) (xy 94.59087 -270.28267)
			(xy 94.791022 -270.28267)
		)
		(stroke
			(width 0)
			(type solid)
		)
		(fill yes)
		(layer "In2.Cu")
		(net "M_C_CPU1_SB_CB<5>")
	)
	(gr_poly
		(pts
			(xy 94.791022 -263.758172) (xy 94.690946 -263.658096) (xy 94.59087 -263.758172) (xy 94.59087 -263.802622)
			(xy 94.791022 -263.802622)
		)
		(stroke
			(width 0)
			(type solid)
		)
		(fill yes)
		(layer "In2.Cu")
		(net "M_C_CPU1_SB_CA<4>")
	)
	(gr_poly
		(pts
			(xy 94.791022 -262.13816) (xy 94.690946 -262.038084) (xy 94.59087 -262.13816) (xy 94.59087 -262.18261)
			(xy 94.791022 -262.18261)
		)
		(stroke
			(width 0)
			(type solid)
		)
		(fill yes)
		(layer "In2.Cu")
		(net "M_C_CPU1_SB_CA<0>")
	)
	(gr_poly
		(pts
			(xy 94.797118 -266.991846) (xy 94.697296 -266.89177) (xy 94.59722 -266.991846) (xy 94.59722 -267.036296)
			(xy 94.797118 -267.036296)
		)
		(stroke
			(width 0)
			(type solid)
		)
		(fill yes)
		(layer "In2.Cu")
		(net "M_C_CPU1_SA_RSP<0>")
	)
	(gr_poly
		(pts
			(xy 94.798134 -291.297868) (xy 94.698312 -291.198046) (xy 94.598236 -291.297868) (xy 94.598236 -291.34562)
			(xy 94.798134 -291.34562)
		)
		(stroke
			(width 0)
			(type solid)
		)
		(fill yes)
		(layer "In2.Cu")
		(net "M_C_CPU1_SB_DQS_DN<8>")
	)
	(gr_poly
		(pts
			(xy 94.961202 -255.216406) (xy 94.861126 -255.11633) (xy 94.76105 -255.216406) (xy 94.76105 -255.260856)
			(xy 94.961202 -255.260856)
		)
		(stroke
			(width 0)
			(type solid)
		)
		(fill yes)
		(layer "In2.Cu")
		(net "M_C_CPU1_SA_CA<6>")
	)
	(gr_poly
		(pts
			(xy 94.961202 -253.596394) (xy 94.861126 -253.496318) (xy 94.76105 -253.596394) (xy 94.76105 -253.640844)
			(xy 94.961202 -253.640844)
		)
		(stroke
			(width 0)
			(type solid)
		)
		(fill yes)
		(layer "In2.Cu")
		(net "M_C_CPU1_SA_CA<2>")
	)
	(gr_poly
		(pts
			(xy 94.961202 -250.35637) (xy 94.861126 -250.256294) (xy 94.76105 -250.35637) (xy 94.76105 -250.40082)
			(xy 94.961202 -250.40082)
		)
		(stroke
			(width 0)
			(type solid)
		)
		(fill yes)
		(layer "In2.Cu")
		(net "M_C_CPU1_ALERT_R_N")
	)
	(gr_poly
		(pts
			(xy 94.961202 -248.736358) (xy 94.861126 -248.636282) (xy 94.76105 -248.736358) (xy 94.76105 -248.780808)
			(xy 94.961202 -248.780808)
		)
		(stroke
			(width 0)
			(type solid)
		)
		(fill yes)
		(layer "In2.Cu")
		(net "M_C_CPU1_SA_CB<5>")
	)
	(gr_poly
		(pts
			(xy 94.961202 -247.116092) (xy 94.861126 -247.01627) (xy 94.76105 -247.116092) (xy 94.76105 -247.163844)
			(xy 94.961202 -247.163844)
		)
		(stroke
			(width 0)
			(type solid)
		)
		(fill yes)
		(layer "In2.Cu")
		(net "M_C_CPU1_SA_DQS_DN<9>")
	)
	(gr_poly
		(pts
			(xy 94.961202 -245.496334) (xy 94.861126 -245.396258) (xy 94.76105 -245.496334) (xy 94.76105 -245.540784)
			(xy 94.961202 -245.540784)
		)
		(stroke
			(width 0)
			(type solid)
		)
		(fill yes)
		(layer "In2.Cu")
		(net "M_C_CPU1_SA_CB<1>")
	)
	(gr_poly
		(pts
			(xy 94.961202 -243.876322) (xy 94.861126 -243.776246) (xy 94.76105 -243.876322) (xy 94.76105 -243.920772)
			(xy 94.961202 -243.920772)
		)
		(stroke
			(width 0)
			(type solid)
		)
		(fill yes)
		(layer "In2.Cu")
		(net "M_C_CPU1_SA_DQ<29>")
	)
	(gr_poly
		(pts
			(xy 94.961202 -242.256056) (xy 94.861126 -242.156234) (xy 94.76105 -242.256056) (xy 94.76105 -242.303808)
			(xy 94.961202 -242.303808)
		)
		(stroke
			(width 0)
			(type solid)
		)
		(fill yes)
		(layer "In2.Cu")
		(net "M_C_CPU1_SA_DQS_DN<8>")
	)
	(gr_poly
		(pts
			(xy 94.961202 -240.636298) (xy 94.861126 -240.536222) (xy 94.76105 -240.636298) (xy 94.76105 -240.680748)
			(xy 94.961202 -240.680748)
		)
		(stroke
			(width 0)
			(type solid)
		)
		(fill yes)
		(layer "In2.Cu")
		(net "M_C_CPU1_SA_DQ<25>")
	)
	(gr_poly
		(pts
			(xy 94.961202 -239.016286) (xy 94.861126 -238.91621) (xy 94.76105 -239.016286) (xy 94.76105 -239.060736)
			(xy 94.961202 -239.060736)
		)
		(stroke
			(width 0)
			(type solid)
		)
		(fill yes)
		(layer "In2.Cu")
		(net "M_C_CPU1_SA_DQ<21>")
	)
	(gr_poly
		(pts
			(xy 94.961202 -237.39602) (xy 94.861126 -237.296198) (xy 94.76105 -237.39602) (xy 94.76105 -237.443772)
			(xy 94.961202 -237.443772)
		)
		(stroke
			(width 0)
			(type solid)
		)
		(fill yes)
		(layer "In2.Cu")
		(net "M_C_CPU1_SA_DQS_DN<7>")
	)
	(gr_poly
		(pts
			(xy 94.961202 -235.776262) (xy 94.861126 -235.676186) (xy 94.76105 -235.776262) (xy 94.76105 -235.820712)
			(xy 94.961202 -235.820712)
		)
		(stroke
			(width 0)
			(type solid)
		)
		(fill yes)
		(layer "In2.Cu")
		(net "M_C_CPU1_SA_DQ<17>")
	)
	(gr_poly
		(pts
			(xy 94.961202 -234.15625) (xy 94.861126 -234.056174) (xy 94.76105 -234.15625) (xy 94.76105 -234.2007)
			(xy 94.961202 -234.2007)
		)
		(stroke
			(width 0)
			(type solid)
		)
		(fill yes)
		(layer "In2.Cu")
		(net "M_C_CPU1_SA_DQ<13>")
	)
	(gr_poly
		(pts
			(xy 94.961202 -232.535984) (xy 94.861126 -232.436162) (xy 94.76105 -232.535984) (xy 94.76105 -232.583736)
			(xy 94.961202 -232.583736)
		)
		(stroke
			(width 0)
			(type solid)
		)
		(fill yes)
		(layer "In2.Cu")
		(net "M_C_CPU1_SA_DQS_DN<6>")
	)
	(gr_poly
		(pts
			(xy 94.961202 -230.916226) (xy 94.861126 -230.81615) (xy 94.76105 -230.916226) (xy 94.76105 -230.960676)
			(xy 94.961202 -230.960676)
		)
		(stroke
			(width 0)
			(type solid)
		)
		(fill yes)
		(layer "In2.Cu")
		(net "M_C_CPU1_SA_DQ<9>")
	)
	(gr_poly
		(pts
			(xy 94.961202 -229.296214) (xy 94.861126 -229.196138) (xy 94.76105 -229.296214) (xy 94.76105 -229.340664)
			(xy 94.961202 -229.340664)
		)
		(stroke
			(width 0)
			(type solid)
		)
		(fill yes)
		(layer "In2.Cu")
		(net "M_C_CPU1_SA_DQ<5>")
	)
	(gr_poly
		(pts
			(xy 94.961202 -227.676202) (xy 94.861126 -227.57638) (xy 94.76105 -227.676202) (xy 94.76105 -227.723954)
			(xy 94.961202 -227.723954)
		)
		(stroke
			(width 0)
			(type solid)
		)
		(fill yes)
		(layer "In2.Cu")
		(net "M_C_CPU1_SA_DQS_DN<5>")
	)
	(gr_poly
		(pts
			(xy 94.961202 -226.056444) (xy 94.861126 -225.956368) (xy 94.76105 -226.056444) (xy 94.76105 -226.100894)
			(xy 94.961202 -226.100894)
		)
		(stroke
			(width 0)
			(type solid)
		)
		(fill yes)
		(layer "In2.Cu")
		(net "M_C_CPU1_SA_DQ<1>")
	)
	(gr_poly
		(pts
			(xy 95.25381 -291.704268) (xy 95.25381 -291.65677) (xy 95.053658 -291.65677) (xy 95.053658 -291.704268)
			(xy 95.153734 -291.804344)
		)
		(stroke
			(width 0)
			(type solid)
		)
		(fill yes)
		(layer "In2.Cu")
		(net "M_C_CPU1_SB_DQS_DP<8>")
	)
	(gr_poly
		(pts
			(xy 95.261176 -293.32428) (xy 95.261176 -293.27983) (xy 95.061024 -293.27983) (xy 95.061024 -293.32428)
			(xy 95.1611 -293.424356)
		)
		(stroke
			(width 0)
			(type solid)
		)
		(fill yes)
		(layer "In2.Cu")
		(net "M_C_CPU1_SB_DQ<31>")
	)
	(gr_poly
		(pts
			(xy 95.261176 -290.084256) (xy 95.261176 -290.039806) (xy 95.061024 -290.039806) (xy 95.061024 -290.084256)
			(xy 95.1611 -290.184332)
		)
		(stroke
			(width 0)
			(type solid)
		)
		(fill yes)
		(layer "In2.Cu")
		(net "M_C_CPU1_SB_DQ<27>")
	)
	(gr_poly
		(pts
			(xy 95.261176 -288.464498) (xy 95.261176 -288.420048) (xy 95.061024 -288.420048) (xy 95.061024 -288.464498)
			(xy 95.1611 -288.564574)
		)
		(stroke
			(width 0)
			(type solid)
		)
		(fill yes)
		(layer "In2.Cu")
		(net "M_C_CPU1_SB_DQ<23>")
	)
	(gr_poly
		(pts
			(xy 95.261176 -286.844486) (xy 95.261176 -286.796734) (xy 95.061024 -286.796734) (xy 95.061024 -286.844486)
			(xy 95.1611 -286.944562)
		)
		(stroke
			(width 0)
			(type solid)
		)
		(fill yes)
		(layer "In2.Cu")
		(net "M_C_CPU1_SB_DQS_DP<7>")
	)
	(gr_poly
		(pts
			(xy 95.261176 -285.224474) (xy 95.261176 -285.180024) (xy 95.061024 -285.180024) (xy 95.061024 -285.224474)
			(xy 95.1611 -285.32455)
		)
		(stroke
			(width 0)
			(type solid)
		)
		(fill yes)
		(layer "In2.Cu")
		(net "M_C_CPU1_SB_DQ<19>")
	)
	(gr_poly
		(pts
			(xy 95.261176 -283.604462) (xy 95.261176 -283.560012) (xy 95.061024 -283.560012) (xy 95.061024 -283.604462)
			(xy 95.1611 -283.704538)
		)
		(stroke
			(width 0)
			(type solid)
		)
		(fill yes)
		(layer "In2.Cu")
		(net "M_C_CPU1_SB_DQ<15>")
	)
	(gr_poly
		(pts
			(xy 95.261176 -281.984704) (xy 95.261176 -281.936952) (xy 95.061024 -281.936952) (xy 95.061024 -281.984704)
			(xy 95.1611 -282.084526)
		)
		(stroke
			(width 0)
			(type solid)
		)
		(fill yes)
		(layer "In2.Cu")
		(net "M_C_CPU1_SB_DQS_DP<6>")
	)
	(gr_poly
		(pts
			(xy 95.261176 -280.364438) (xy 95.261176 -280.319988) (xy 95.061024 -280.319988) (xy 95.061024 -280.364438)
			(xy 95.1611 -280.464514)
		)
		(stroke
			(width 0)
			(type solid)
		)
		(fill yes)
		(layer "In2.Cu")
		(net "M_C_CPU1_SB_DQ<11>")
	)
	(gr_poly
		(pts
			(xy 95.261176 -278.744426) (xy 95.261176 -278.699976) (xy 95.061024 -278.699976) (xy 95.061024 -278.744426)
			(xy 95.1611 -278.844502)
		)
		(stroke
			(width 0)
			(type solid)
		)
		(fill yes)
		(layer "In2.Cu")
		(net "M_C_CPU1_SB_DQ<7>")
	)
	(gr_poly
		(pts
			(xy 95.261176 -277.124668) (xy 95.261176 -277.076916) (xy 95.061024 -277.076916) (xy 95.061024 -277.124668)
			(xy 95.1611 -277.22449)
		)
		(stroke
			(width 0)
			(type solid)
		)
		(fill yes)
		(layer "In2.Cu")
		(net "M_C_CPU1_SB_DQS_DP<5>")
	)
	(gr_poly
		(pts
			(xy 95.261176 -275.504402) (xy 95.261176 -275.459952) (xy 95.061024 -275.459952) (xy 95.061024 -275.504402)
			(xy 95.1611 -275.604478)
		)
		(stroke
			(width 0)
			(type solid)
		)
		(fill yes)
		(layer "In2.Cu")
		(net "M_C_CPU1_SB_DQ<3>")
	)
	(gr_poly
		(pts
			(xy 95.261176 -273.88439) (xy 95.261176 -273.83994) (xy 95.061024 -273.83994) (xy 95.061024 -273.88439)
			(xy 95.1611 -273.984466)
		)
		(stroke
			(width 0)
			(type solid)
		)
		(fill yes)
		(layer "In2.Cu")
		(net "M_C_CPU1_SB_CB<3>")
	)
	(gr_poly
		(pts
			(xy 95.261176 -272.264632) (xy 95.261176 -272.21688) (xy 95.061024 -272.21688) (xy 95.061024 -272.264632)
			(xy 95.1611 -272.364454)
		)
		(stroke
			(width 0)
			(type solid)
		)
		(fill yes)
		(layer "In2.Cu")
		(net "M_C_CPU1_SB_DQS_DP<4>")
	)
	(gr_poly
		(pts
			(xy 95.261176 -270.644366) (xy 95.261176 -270.599916) (xy 95.061024 -270.599916) (xy 95.061024 -270.644366)
			(xy 95.1611 -270.744442)
		)
		(stroke
			(width 0)
			(type solid)
		)
		(fill yes)
		(layer "In2.Cu")
		(net "M_C_CPU1_SB_CB<7>")
	)
	(gr_poly
		(pts
			(xy 95.261176 -265.78433) (xy 95.261176 -265.73988) (xy 95.061024 -265.73988) (xy 95.061024 -265.78433)
			(xy 95.1611 -265.884406)
		)
		(stroke
			(width 0)
			(type solid)
		)
		(fill yes)
		(layer "In2.Cu")
		(net "M_C_CPU1_SB_CS_N<0>")
	)
	(gr_poly
		(pts
			(xy 95.261176 -264.164318) (xy 95.261176 -264.119868) (xy 95.061024 -264.119868) (xy 95.061024 -264.164318)
			(xy 95.1611 -264.264394)
		)
		(stroke
			(width 0)
			(type solid)
		)
		(fill yes)
		(layer "In2.Cu")
		(net "M_C_CPU1_SB_CA<5>")
	)
	(gr_poly
		(pts
			(xy 95.261176 -262.544306) (xy 95.261176 -262.499856) (xy 95.061024 -262.499856) (xy 95.061024 -262.544306)
			(xy 95.1611 -262.644382)
		)
		(stroke
			(width 0)
			(type solid)
		)
		(fill yes)
		(layer "In2.Cu")
		(net "M_C_CPU1_SB_CA<1>")
	)
	(gr_poly
		(pts
			(xy 95.378778 -247.52935) (xy 95.383096 -247.481852) (xy 95.183706 -247.46458) (xy 95.179642 -247.511824)
			(xy 95.270574 -247.620282)
		)
		(stroke
			(width 0)
			(type solid)
		)
		(fill yes)
		(layer "In2.Cu")
		(net "M_C_CPU1_SA_DQS_DP<9>")
	)
	(gr_poly
		(pts
			(xy 95.378778 -242.669314) (xy 95.383096 -242.621816) (xy 95.183706 -242.604544) (xy 95.179642 -242.651788)
			(xy 95.270574 -242.760246)
		)
		(stroke
			(width 0)
			(type solid)
		)
		(fill yes)
		(layer "In2.Cu")
		(net "M_C_CPU1_SA_DQS_DP<8>")
	)
	(gr_poly
		(pts
			(xy 95.378778 -237.809278) (xy 95.383096 -237.76178) (xy 95.183706 -237.744508) (xy 95.179642 -237.791752)
			(xy 95.270574 -237.90021)
		)
		(stroke
			(width 0)
			(type solid)
		)
		(fill yes)
		(layer "In2.Cu")
		(net "M_C_CPU1_SA_DQS_DP<7>")
	)
	(gr_poly
		(pts
			(xy 95.378778 -232.949242) (xy 95.383096 -232.901744) (xy 95.183706 -232.884472) (xy 95.179642 -232.931716)
			(xy 95.270574 -233.040174)
		)
		(stroke
			(width 0)
			(type solid)
		)
		(fill yes)
		(layer "In2.Cu")
		(net "M_C_CPU1_SA_DQS_DP<6>")
	)
	(gr_poly
		(pts
			(xy 95.389446 -228.090222) (xy 95.39351 -228.042724) (xy 95.194374 -228.025452) (xy 95.19031 -228.072696)
			(xy 95.281242 -228.181154)
		)
		(stroke
			(width 0)
			(type solid)
		)
		(fill yes)
		(layer "In2.Cu")
		(net "M_C_CPU1_SA_DQS_DP<5>")
	)
	(gr_poly
		(pts
			(xy 95.391478 -255.630172) (xy 95.395542 -255.585722) (xy 95.196152 -255.56845) (xy 95.192342 -255.612646)
			(xy 95.283274 -255.721104)
		)
		(stroke
			(width 0)
			(type solid)
		)
		(fill yes)
		(layer "In2.Cu")
		(net "M_C_CPU1_SA_PAR")
	)
	(gr_poly
		(pts
			(xy 95.391478 -254.01016) (xy 95.395542 -253.96571) (xy 95.196152 -253.948438) (xy 95.192342 -253.992634)
			(xy 95.283274 -254.101092)
		)
		(stroke
			(width 0)
			(type solid)
		)
		(fill yes)
		(layer "In2.Cu")
		(net "M_C_CPU1_SA_CA<3>")
	)
	(gr_poly
		(pts
			(xy 95.391478 -252.390148) (xy 95.395542 -252.345698) (xy 95.196152 -252.328426) (xy 95.192342 -252.372622)
			(xy 95.283274 -252.48108)
		)
		(stroke
			(width 0)
			(type solid)
		)
		(fill yes)
		(layer "In2.Cu")
		(net "M_C_CPU1_SA_CS_N<1>")
	)
	(gr_poly
		(pts
			(xy 95.391478 -250.770136) (xy 95.395542 -250.725686) (xy 95.196152 -250.708414) (xy 95.192342 -250.75261)
			(xy 95.283274 -250.861068)
		)
		(stroke
			(width 0)
			(type solid)
		)
		(fill yes)
		(layer "In2.Cu")
		(net "M_C_CPU1_RESET_N")
	)
	(gr_poly
		(pts
			(xy 95.391478 -249.150124) (xy 95.395542 -249.105674) (xy 95.196152 -249.088402) (xy 95.192342 -249.132598)
			(xy 95.283274 -249.241056)
		)
		(stroke
			(width 0)
			(type solid)
		)
		(fill yes)
		(layer "In2.Cu")
		(net "M_C_CPU1_SA_CB<7>")
	)
	(gr_poly
		(pts
			(xy 95.391478 -245.9101) (xy 95.395542 -245.86565) (xy 95.196152 -245.848378) (xy 95.192342 -245.892574)
			(xy 95.283274 -246.001032)
		)
		(stroke
			(width 0)
			(type solid)
		)
		(fill yes)
		(layer "In2.Cu")
		(net "M_C_CPU1_SA_CB<3>")
	)
	(gr_poly
		(pts
			(xy 95.391478 -244.290088) (xy 95.395542 -244.245638) (xy 95.196152 -244.228366) (xy 95.192342 -244.272562)
			(xy 95.283274 -244.38102)
		)
		(stroke
			(width 0)
			(type solid)
		)
		(fill yes)
		(layer "In2.Cu")
		(net "M_C_CPU1_SA_DQ<31>")
	)
	(gr_poly
		(pts
			(xy 95.391478 -241.050064) (xy 95.395542 -241.005614) (xy 95.196152 -240.988342) (xy 95.192342 -241.032538)
			(xy 95.283274 -241.140996)
		)
		(stroke
			(width 0)
			(type solid)
		)
		(fill yes)
		(layer "In2.Cu")
		(net "M_C_CPU1_SA_DQ<27>")
	)
	(gr_poly
		(pts
			(xy 95.391478 -239.430052) (xy 95.395542 -239.385602) (xy 95.196152 -239.36833) (xy 95.192342 -239.412526)
			(xy 95.283274 -239.520984)
		)
		(stroke
			(width 0)
			(type solid)
		)
		(fill yes)
		(layer "In2.Cu")
		(net "M_C_CPU1_SA_DQ<23>")
	)
	(gr_poly
		(pts
			(xy 95.391478 -236.190028) (xy 95.395542 -236.145578) (xy 95.196152 -236.128306) (xy 95.192342 -236.172502)
			(xy 95.283274 -236.28096)
		)
		(stroke
			(width 0)
			(type solid)
		)
		(fill yes)
		(layer "In2.Cu")
		(net "M_C_CPU1_SA_DQ<19>")
	)
	(gr_poly
		(pts
			(xy 95.391478 -234.570016) (xy 95.395542 -234.525566) (xy 95.196152 -234.508294) (xy 95.192342 -234.55249)
			(xy 95.283274 -234.660948)
		)
		(stroke
			(width 0)
			(type solid)
		)
		(fill yes)
		(layer "In2.Cu")
		(net "M_C_CPU1_SA_DQ<15>")
	)
	(gr_poly
		(pts
			(xy 95.391478 -226.47021) (xy 95.395542 -226.42576) (xy 95.196152 -226.408488) (xy 95.192342 -226.452684)
			(xy 95.283274 -226.561142)
		)
		(stroke
			(width 0)
			(type solid)
		)
		(fill yes)
		(layer "In2.Cu")
		(net "M_C_CPU1_SA_DQ<3>")
	)
	(gr_poly
		(pts
			(xy 95.391732 -231.329992) (xy 95.395542 -231.285796) (xy 95.196406 -231.268524) (xy 95.192342 -231.31272)
			(xy 95.283274 -231.420924)
		)
		(stroke
			(width 0)
			(type solid)
		)
		(fill yes)
		(layer "In2.Cu")
		(net "M_C_CPU1_SA_DQ<11>")
	)
	(gr_poly
		(pts
			(xy 95.391732 -229.710234) (xy 95.395542 -229.665784) (xy 95.196406 -229.648512) (xy 95.192342 -229.692708)
			(xy 95.283274 -229.800912)
		)
		(stroke
			(width 0)
			(type solid)
		)
		(fill yes)
		(layer "In2.Cu")
		(net "M_C_CPU1_SA_DQ<7>")
	)
	(gr_poly
		(pts
			(xy 95.682816 -291.338762) (xy 95.678498 -291.291264) (xy 95.570294 -291.200332) (xy 95.479362 -291.30879)
			(xy 95.483426 -291.356288)
		)
		(stroke
			(width 0)
			(type solid)
		)
		(fill yes)
		(layer "In2.Cu")
		(net "M_C_CPU1_SB_DQS_DN<8>")
	)
	(gr_poly
		(pts
			(xy 95.682816 -271.898872) (xy 95.678498 -271.851374) (xy 95.570294 -271.760442) (xy 95.479362 -271.8689)
			(xy 95.483426 -271.916144)
		)
		(stroke
			(width 0)
			(type solid)
		)
		(fill yes)
		(layer "In2.Cu")
		(net "M_C_CPU1_SB_DQS_DN<4>")
	)
	(gr_poly
		(pts
			(xy 95.693738 -286.477964) (xy 95.689674 -286.43072) (xy 95.581216 -286.339788) (xy 95.490284 -286.447992)
			(xy 95.494602 -286.49549)
		)
		(stroke
			(width 0)
			(type solid)
		)
		(fill yes)
		(layer "In2.Cu")
		(net "M_C_CPU1_SB_DQS_DN<7>")
	)
	(gr_poly
		(pts
			(xy 95.693738 -281.618182) (xy 95.689674 -281.570684) (xy 95.581216 -281.479752) (xy 95.490284 -281.587956)
			(xy 95.494602 -281.635454)
		)
		(stroke
			(width 0)
			(type solid)
		)
		(fill yes)
		(layer "In2.Cu")
		(net "M_C_CPU1_SB_DQS_DN<6>")
	)
	(gr_poly
		(pts
			(xy 95.693738 -276.758146) (xy 95.689674 -276.710648) (xy 95.581216 -276.619716) (xy 95.490284 -276.72792)
			(xy 95.494602 -276.775418)
		)
		(stroke
			(width 0)
			(type solid)
		)
		(fill yes)
		(layer "In2.Cu")
		(net "M_C_CPU1_SB_DQS_DN<5>")
	)
	(gr_poly
		(pts
			(xy 95.695262 -292.954964) (xy 95.691452 -292.910768) (xy 95.582994 -292.819836) (xy 95.492062 -292.92804)
			(xy 95.496126 -292.972236)
		)
		(stroke
			(width 0)
			(type solid)
		)
		(fill yes)
		(layer "In2.Cu")
		(net "M_C_CPU1_SB_DQ<29>")
	)
	(gr_poly
		(pts
			(xy 95.695262 -289.71494) (xy 95.691452 -289.670744) (xy 95.582994 -289.579812) (xy 95.492062 -289.688016)
			(xy 95.496126 -289.732212)
		)
		(stroke
			(width 0)
			(type solid)
		)
		(fill yes)
		(layer "In2.Cu")
		(net "M_C_CPU1_SB_DQ<25>")
	)
	(gr_poly
		(pts
			(xy 95.695262 -284.855158) (xy 95.691452 -284.810708) (xy 95.582994 -284.72003) (xy 95.492062 -284.828234)
			(xy 95.496126 -284.87243)
		)
		(stroke
			(width 0)
			(type solid)
		)
		(fill yes)
		(layer "In2.Cu")
		(net "M_C_CPU1_SB_DQ<17>")
	)
	(gr_poly
		(pts
			(xy 95.695262 -283.235146) (xy 95.691452 -283.190696) (xy 95.582994 -283.100018) (xy 95.492062 -283.208222)
			(xy 95.496126 -283.252418)
		)
		(stroke
			(width 0)
			(type solid)
		)
		(fill yes)
		(layer "In2.Cu")
		(net "M_C_CPU1_SB_DQ<13>")
	)
	(gr_poly
		(pts
			(xy 95.695262 -279.995122) (xy 95.691452 -279.950672) (xy 95.582994 -279.859994) (xy 95.492062 -279.968198)
			(xy 95.496126 -280.012394)
		)
		(stroke
			(width 0)
			(type solid)
		)
		(fill yes)
		(layer "In2.Cu")
		(net "M_C_CPU1_SB_DQ<9>")
	)
	(gr_poly
		(pts
			(xy 95.695262 -278.37511) (xy 95.691452 -278.33066) (xy 95.582994 -278.239982) (xy 95.492062 -278.348186)
			(xy 95.496126 -278.392382)
		)
		(stroke
			(width 0)
			(type solid)
		)
		(fill yes)
		(layer "In2.Cu")
		(net "M_C_CPU1_SB_DQ<5>")
	)
	(gr_poly
		(pts
			(xy 95.695262 -275.135086) (xy 95.691452 -275.090636) (xy 95.582994 -274.999958) (xy 95.492062 -275.108162)
			(xy 95.496126 -275.152358)
		)
		(stroke
			(width 0)
			(type solid)
		)
		(fill yes)
		(layer "In2.Cu")
		(net "M_C_CPU1_SB_DQ<1>")
	)
	(gr_poly
		(pts
			(xy 95.695262 -273.515074) (xy 95.691452 -273.470624) (xy 95.582994 -273.379946) (xy 95.492062 -273.48815)
			(xy 95.496126 -273.532346)
		)
		(stroke
			(width 0)
			(type solid)
		)
		(fill yes)
		(layer "In2.Cu")
		(net "M_C_CPU1_SB_CB<1>")
	)
	(gr_poly
		(pts
			(xy 95.695262 -270.27505) (xy 95.691452 -270.2306) (xy 95.582994 -270.139922) (xy 95.492062 -270.248126)
			(xy 95.496126 -270.292322)
		)
		(stroke
			(width 0)
			(type solid)
		)
		(fill yes)
		(layer "In2.Cu")
		(net "M_C_CPU1_SB_CB<5>")
	)
	(gr_poly
		(pts
			(xy 95.695262 -263.795002) (xy 95.691452 -263.750552) (xy 95.582994 -263.659874) (xy 95.492062 -263.768078)
			(xy 95.496126 -263.812274)
		)
		(stroke
			(width 0)
			(type solid)
		)
		(fill yes)
		(layer "In2.Cu")
		(net "M_C_CPU1_SB_CA<4>")
	)
	(gr_poly
		(pts
			(xy 95.695262 -262.17499) (xy 95.691452 -262.13054) (xy 95.582994 -262.039862) (xy 95.492062 -262.148066)
			(xy 95.496126 -262.192262)
		)
		(stroke
			(width 0)
			(type solid)
		)
		(fill yes)
		(layer "In2.Cu")
		(net "M_C_CPU1_SB_CA<0>")
	)
	(gr_poly
		(pts
			(xy 95.695516 -288.094928) (xy 95.691706 -288.050732) (xy 95.583248 -287.9598) (xy 95.492316 -288.068004)
			(xy 95.49638 -288.1122)
		)
		(stroke
			(width 0)
			(type solid)
		)
		(fill yes)
		(layer "In2.Cu")
		(net "M_C_CPU1_SB_DQ<21>")
	)
	(gr_poly
		(pts
			(xy 95.699072 -267.028422) (xy 95.695262 -266.983972) (xy 95.587058 -266.89304) (xy 95.496126 -267.001498)
			(xy 95.499936 -267.045694)
		)
		(stroke
			(width 0)
			(type solid)
		)
		(fill yes)
		(layer "In2.Cu")
		(net "M_C_CPU1_SA_RSP<0>")
	)
	(gr_poly
		(pts
			(xy 128.363472 -231.31272) (xy 128.359408 -231.268524) (xy 128.160272 -231.285796) (xy 128.164082 -231.329992)
			(xy 128.27254 -231.420924)
		)
		(stroke
			(width 0)
			(type solid)
		)
		(fill yes)
		(layer "In2.Cu")
		(net "M_I_CPU1_SA_DQ<11>")
	)
	(gr_poly
		(pts
			(xy 128.363472 -229.692708) (xy 128.359408 -229.648512) (xy 128.160272 -229.665784) (xy 128.164082 -229.710234)
			(xy 128.27254 -229.800912)
		)
		(stroke
			(width 0)
			(type solid)
		)
		(fill yes)
		(layer "In2.Cu")
		(net "M_I_CPU1_SA_DQ<7>")
	)
	(gr_poly
		(pts
			(xy 128.363726 -255.612646) (xy 128.359662 -255.56845) (xy 128.160526 -255.585722) (xy 128.164336 -255.630172)
			(xy 128.272794 -255.72085)
		)
		(stroke
			(width 0)
			(type solid)
		)
		(fill yes)
		(layer "In2.Cu")
		(net "M_I_CPU1_SA_PAR")
	)
	(gr_poly
		(pts
			(xy 128.363726 -253.992634) (xy 128.359662 -253.948438) (xy 128.160526 -253.96571) (xy 128.164336 -254.01016)
			(xy 128.272794 -254.100838)
		)
		(stroke
			(width 0)
			(type solid)
		)
		(fill yes)
		(layer "In2.Cu")
		(net "M_I_CPU1_SA_CA<3>")
	)
	(gr_poly
		(pts
			(xy 128.363726 -250.75261) (xy 128.359662 -250.708414) (xy 128.160526 -250.725686) (xy 128.164336 -250.770136)
			(xy 128.272794 -250.860814)
		)
		(stroke
			(width 0)
			(type solid)
		)
		(fill yes)
		(layer "In2.Cu")
		(net "M_I_CPU1_RESET_N")
	)
	(gr_poly
		(pts
			(xy 128.363726 -249.132598) (xy 128.359662 -249.088402) (xy 128.160526 -249.105674) (xy 128.164336 -249.14987)
			(xy 128.272794 -249.240802)
		)
		(stroke
			(width 0)
			(type solid)
		)
		(fill yes)
		(layer "In2.Cu")
		(net "M_I_CPU1_SA_CB<7>")
	)
	(gr_poly
		(pts
			(xy 128.363726 -245.892574) (xy 128.359662 -245.848378) (xy 128.160526 -245.86565) (xy 128.164336 -245.9101)
			(xy 128.272794 -246.000778)
		)
		(stroke
			(width 0)
			(type solid)
		)
		(fill yes)
		(layer "In2.Cu")
		(net "M_I_CPU1_SA_CB<3>")
	)
	(gr_poly
		(pts
			(xy 128.363726 -244.272562) (xy 128.359662 -244.228366) (xy 128.160526 -244.245638) (xy 128.164336 -244.289834)
			(xy 128.272794 -244.380766)
		)
		(stroke
			(width 0)
			(type solid)
		)
		(fill yes)
		(layer "In2.Cu")
		(net "M_I_CPU1_SA_DQ<31>")
	)
	(gr_poly
		(pts
			(xy 128.363726 -241.032538) (xy 128.359662 -240.988342) (xy 128.160526 -241.005614) (xy 128.164336 -241.050064)
			(xy 128.272794 -241.140742)
		)
		(stroke
			(width 0)
			(type solid)
		)
		(fill yes)
		(layer "In2.Cu")
		(net "M_I_CPU1_SA_DQ<27>")
	)
	(gr_poly
		(pts
			(xy 128.363726 -239.412526) (xy 128.359662 -239.36833) (xy 128.160526 -239.385602) (xy 128.164336 -239.430052)
			(xy 128.272794 -239.52073)
		)
		(stroke
			(width 0)
			(type solid)
		)
		(fill yes)
		(layer "In2.Cu")
		(net "M_I_CPU1_SA_DQ<23>")
	)
	(gr_poly
		(pts
			(xy 128.363726 -236.172502) (xy 128.359662 -236.128306) (xy 128.160526 -236.145578) (xy 128.164336 -236.190028)
			(xy 128.272794 -236.280706)
		)
		(stroke
			(width 0)
			(type solid)
		)
		(fill yes)
		(layer "In2.Cu")
		(net "M_I_CPU1_SA_DQ<19>")
	)
	(gr_poly
		(pts
			(xy 128.363726 -234.55249) (xy 128.359662 -234.508294) (xy 128.160526 -234.525566) (xy 128.164336 -234.570016)
			(xy 128.272794 -234.660694)
		)
		(stroke
			(width 0)
			(type solid)
		)
		(fill yes)
		(layer "In2.Cu")
		(net "M_I_CPU1_SA_DQ<15>")
	)
	(gr_poly
		(pts
			(xy 128.363726 -226.452684) (xy 128.359662 -226.408488) (xy 128.160526 -226.42576) (xy 128.164336 -226.469956)
			(xy 128.272794 -226.560888)
		)
		(stroke
			(width 0)
			(type solid)
		)
		(fill yes)
		(layer "In2.Cu")
		(net "M_I_CPU1_SA_DQ<3>")
	)
	(gr_poly
		(pts
			(xy 128.376426 -247.511824) (xy 128.372362 -247.46458) (xy 128.172972 -247.481852) (xy 128.17729 -247.52935)
			(xy 128.285494 -247.620282)
		)
		(stroke
			(width 0)
			(type solid)
		)
		(fill yes)
		(layer "In2.Cu")
		(net "M_I_CPU1_SA_DQS_DP<9>")
	)
	(gr_poly
		(pts
			(xy 128.376426 -242.651788) (xy 128.372362 -242.604544) (xy 128.172972 -242.621816) (xy 128.17729 -242.669314)
			(xy 128.285494 -242.760246)
		)
		(stroke
			(width 0)
			(type solid)
		)
		(fill yes)
		(layer "In2.Cu")
		(net "M_I_CPU1_SA_DQS_DP<8>")
	)
	(gr_poly
		(pts
			(xy 128.376426 -237.791752) (xy 128.372362 -237.744508) (xy 128.172972 -237.76178) (xy 128.17729 -237.809278)
			(xy 128.285494 -237.90021)
		)
		(stroke
			(width 0)
			(type solid)
		)
		(fill yes)
		(layer "In2.Cu")
		(net "M_I_CPU1_SA_DQS_DP<7>")
	)
	(gr_poly
		(pts
			(xy 128.376426 -232.931716) (xy 128.372362 -232.884472) (xy 128.172972 -232.901744) (xy 128.17729 -232.949242)
			(xy 128.285494 -233.040174)
		)
		(stroke
			(width 0)
			(type solid)
		)
		(fill yes)
		(layer "In2.Cu")
		(net "M_I_CPU1_SA_DQS_DP<6>")
	)
	(gr_poly
		(pts
			(xy 128.376426 -228.071934) (xy 128.372362 -228.024436) (xy 128.172972 -228.041962) (xy 128.17729 -228.08946)
			(xy 128.285494 -228.180392)
		)
		(stroke
			(width 0)
			(type solid)
		)
		(fill yes)
		(layer "In2.Cu")
		(net "M_I_CPU1_SA_DQS_DP<5>")
	)
	(gr_poly
		(pts
			(xy 128.663446 -292.92804) (xy 128.572514 -292.819582) (xy 128.46431 -292.910514) (xy 128.460246 -292.954964)
			(xy 128.659636 -292.972236)
		)
		(stroke
			(width 0)
			(type solid)
		)
		(fill yes)
		(layer "In2.Cu")
		(net "M_I_CPU1_SB_DQ<29>")
	)
	(gr_poly
		(pts
			(xy 128.663446 -289.688016) (xy 128.572514 -289.579558) (xy 128.46431 -289.67049) (xy 128.460246 -289.71494)
			(xy 128.659636 -289.732212)
		)
		(stroke
			(width 0)
			(type solid)
		)
		(fill yes)
		(layer "In2.Cu")
		(net "M_I_CPU1_SB_DQ<25>")
	)
	(gr_poly
		(pts
			(xy 128.663446 -288.068004) (xy 128.572514 -287.9598) (xy 128.464056 -288.050732) (xy 128.460246 -288.094928)
			(xy 128.659382 -288.1122)
		)
		(stroke
			(width 0)
			(type solid)
		)
		(fill yes)
		(layer "In2.Cu")
		(net "M_I_CPU1_SB_DQ<21>")
	)
	(gr_poly
		(pts
			(xy 128.663446 -284.828234) (xy 128.572514 -284.719776) (xy 128.46431 -284.810708) (xy 128.460246 -284.855158)
			(xy 128.659636 -284.87243)
		)
		(stroke
			(width 0)
			(type solid)
		)
		(fill yes)
		(layer "In2.Cu")
		(net "M_I_CPU1_SB_DQ<17>")
	)
	(gr_poly
		(pts
			(xy 128.663446 -283.208222) (xy 128.572514 -283.099764) (xy 128.46431 -283.190696) (xy 128.460246 -283.235146)
			(xy 128.659636 -283.252418)
		)
		(stroke
			(width 0)
			(type solid)
		)
		(fill yes)
		(layer "In2.Cu")
		(net "M_I_CPU1_SB_DQ<13>")
	)
	(gr_poly
		(pts
			(xy 128.663446 -279.968198) (xy 128.572514 -279.85974) (xy 128.46431 -279.950672) (xy 128.460246 -279.995122)
			(xy 128.659636 -280.012394)
		)
		(stroke
			(width 0)
			(type solid)
		)
		(fill yes)
		(layer "In2.Cu")
		(net "M_I_CPU1_SB_DQ<9>")
	)
	(gr_poly
		(pts
			(xy 128.663446 -278.348186) (xy 128.572514 -278.239728) (xy 128.46431 -278.33066) (xy 128.460246 -278.37511)
			(xy 128.659636 -278.392382)
		)
		(stroke
			(width 0)
			(type solid)
		)
		(fill yes)
		(layer "In2.Cu")
		(net "M_I_CPU1_SB_DQ<5>")
	)
	(gr_poly
		(pts
			(xy 128.663446 -275.108162) (xy 128.572514 -274.999704) (xy 128.46431 -275.090636) (xy 128.460246 -275.135086)
			(xy 128.659636 -275.152358)
		)
		(stroke
			(width 0)
			(type solid)
		)
		(fill yes)
		(layer "In2.Cu")
		(net "M_I_CPU1_SB_DQ<1>")
	)
	(gr_poly
		(pts
			(xy 128.663446 -273.48815) (xy 128.572514 -273.379692) (xy 128.46431 -273.470624) (xy 128.460246 -273.515074)
			(xy 128.659636 -273.532346)
		)
		(stroke
			(width 0)
			(type solid)
		)
		(fill yes)
		(layer "In2.Cu")
		(net "M_I_CPU1_SB_CB<1>")
	)
	(gr_poly
		(pts
			(xy 128.663446 -270.248126) (xy 128.572514 -270.139668) (xy 128.46431 -270.2306) (xy 128.460246 -270.27505)
			(xy 128.659636 -270.292322)
		)
		(stroke
			(width 0)
			(type solid)
		)
		(fill yes)
		(layer "In2.Cu")
		(net "M_I_CPU1_SB_CB<5>")
	)
	(gr_poly
		(pts
			(xy 128.663446 -267.008102) (xy 128.572514 -266.899644) (xy 128.46431 -266.990576) (xy 128.460246 -267.035026)
			(xy 128.659636 -267.052298)
		)
		(stroke
			(width 0)
			(type solid)
		)
		(fill yes)
		(layer "In2.Cu")
		(net "M_I_CPU1_SA_RSP<0>")
	)
	(gr_poly
		(pts
			(xy 128.663446 -265.38809) (xy 128.572514 -265.279632) (xy 128.46431 -265.370564) (xy 128.460246 -265.415014)
			(xy 128.659636 -265.432286)
		)
		(stroke
			(width 0)
			(type solid)
		)
		(fill yes)
		(layer "In2.Cu")
		(net "M_I_CPU1_SB_PAR")
	)
	(gr_poly
		(pts
			(xy 128.663446 -263.768078) (xy 128.572514 -263.65962) (xy 128.46431 -263.750552) (xy 128.460246 -263.795002)
			(xy 128.659636 -263.812274)
		)
		(stroke
			(width 0)
			(type solid)
		)
		(fill yes)
		(layer "In2.Cu")
		(net "M_I_CPU1_SB_CA<4>")
	)
	(gr_poly
		(pts
			(xy 128.663446 -262.148066) (xy 128.572514 -262.039608) (xy 128.46431 -262.13054) (xy 128.460246 -262.17499)
			(xy 128.659636 -262.192262)
		)
		(stroke
			(width 0)
			(type solid)
		)
		(fill yes)
		(layer "In2.Cu")
		(net "M_I_CPU1_SB_CA<0>")
	)
	(gr_poly
		(pts
			(xy 128.665478 -291.308028) (xy 128.574546 -291.19957) (xy 128.466342 -291.290502) (xy 128.462278 -291.338)
			(xy 128.661414 -291.355272)
		)
		(stroke
			(width 0)
			(type solid)
		)
		(fill yes)
		(layer "In2.Cu")
		(net "M_I_CPU1_SB_DQS_DN<8>")
	)
	(gr_poly
		(pts
			(xy 128.665478 -286.448246) (xy 128.574546 -286.339788) (xy 128.466342 -286.43072) (xy 128.462278 -286.478218)
			(xy 128.661414 -286.49549)
		)
		(stroke
			(width 0)
			(type solid)
		)
		(fill yes)
		(layer "In2.Cu")
		(net "M_I_CPU1_SB_DQS_DN<7>")
	)
	(gr_poly
		(pts
			(xy 128.665478 -281.58821) (xy 128.574546 -281.479752) (xy 128.466342 -281.570684) (xy 128.462278 -281.618182)
			(xy 128.661414 -281.635708)
		)
		(stroke
			(width 0)
			(type solid)
		)
		(fill yes)
		(layer "In2.Cu")
		(net "M_I_CPU1_SB_DQS_DN<6>")
	)
	(gr_poly
		(pts
			(xy 128.665478 -271.868138) (xy 128.574546 -271.75968) (xy 128.466342 -271.850612) (xy 128.462278 -271.89811)
			(xy 128.661414 -271.915636)
		)
		(stroke
			(width 0)
			(type solid)
		)
		(fill yes)
		(layer "In2.Cu")
		(net "M_I_CPU1_SB_DQS_DN<4>")
	)
	(gr_poly
		(pts
			(xy 128.676146 -276.728936) (xy 128.585214 -276.620478) (xy 128.47701 -276.71141) (xy 128.472692 -276.758908)
			(xy 128.672082 -276.77618)
		)
		(stroke
			(width 0)
			(type solid)
		)
		(fill yes)
		(layer "In2.Cu")
		(net "M_I_CPU1_SB_DQS_DN<5>")
	)
	(gr_poly
		(pts
			(xy 128.794764 -255.216406) (xy 128.694688 -255.11633) (xy 128.594612 -255.216406) (xy 128.594612 -255.260856)
			(xy 128.794764 -255.260856)
		)
		(stroke
			(width 0)
			(type solid)
		)
		(fill yes)
		(layer "In2.Cu")
		(net "M_I_CPU1_SA_CA<6>")
	)
	(gr_poly
		(pts
			(xy 128.794764 -253.596394) (xy 128.694688 -253.496318) (xy 128.594612 -253.596394) (xy 128.594612 -253.640844)
			(xy 128.794764 -253.640844)
		)
		(stroke
			(width 0)
			(type solid)
		)
		(fill yes)
		(layer "In2.Cu")
		(net "M_I_CPU1_SA_CA<2>")
	)
	(gr_poly
		(pts
			(xy 128.794764 -251.976382) (xy 128.694688 -251.876306) (xy 128.594612 -251.976382) (xy 128.594612 -252.020832)
			(xy 128.794764 -252.020832)
		)
		(stroke
			(width 0)
			(type solid)
		)
		(fill yes)
		(layer "In2.Cu")
		(net "M_I_CPU1_SA_CS_N<1>")
	)
	(gr_poly
		(pts
			(xy 128.794764 -250.35637) (xy 128.694688 -250.256294) (xy 128.594612 -250.35637) (xy 128.594612 -250.40082)
			(xy 128.794764 -250.40082)
		)
		(stroke
			(width 0)
			(type solid)
		)
		(fill yes)
		(layer "In2.Cu")
		(net "M_I_CPU1_ALERT_R_N")
	)
	(gr_poly
		(pts
			(xy 128.794764 -248.736358) (xy 128.694688 -248.636282) (xy 128.594612 -248.736358) (xy 128.594612 -248.780808)
			(xy 128.794764 -248.780808)
		)
		(stroke
			(width 0)
			(type solid)
		)
		(fill yes)
		(layer "In2.Cu")
		(net "M_I_CPU1_SA_CB<5>")
	)
	(gr_poly
		(pts
			(xy 128.794764 -247.116092) (xy 128.694688 -247.01627) (xy 128.594612 -247.116092) (xy 128.594612 -247.163844)
			(xy 128.794764 -247.163844)
		)
		(stroke
			(width 0)
			(type solid)
		)
		(fill yes)
		(layer "In2.Cu")
		(net "M_I_CPU1_SA_DQS_DN<9>")
	)
	(gr_poly
		(pts
			(xy 128.794764 -245.496334) (xy 128.694688 -245.396258) (xy 128.594612 -245.496334) (xy 128.594612 -245.540784)
			(xy 128.794764 -245.540784)
		)
		(stroke
			(width 0)
			(type solid)
		)
		(fill yes)
		(layer "In2.Cu")
		(net "M_I_CPU1_SA_CB<1>")
	)
	(gr_poly
		(pts
			(xy 128.794764 -243.876322) (xy 128.694688 -243.776246) (xy 128.594612 -243.876322) (xy 128.594612 -243.920772)
			(xy 128.794764 -243.920772)
		)
		(stroke
			(width 0)
			(type solid)
		)
		(fill yes)
		(layer "In2.Cu")
		(net "M_I_CPU1_SA_DQ<29>")
	)
	(gr_poly
		(pts
			(xy 128.794764 -242.256056) (xy 128.694688 -242.156234) (xy 128.594612 -242.256056) (xy 128.594612 -242.303808)
			(xy 128.794764 -242.303808)
		)
		(stroke
			(width 0)
			(type solid)
		)
		(fill yes)
		(layer "In2.Cu")
		(net "M_I_CPU1_SA_DQS_DN<8>")
	)
	(gr_poly
		(pts
			(xy 128.794764 -240.636298) (xy 128.694688 -240.536222) (xy 128.594612 -240.636298) (xy 128.594612 -240.680748)
			(xy 128.794764 -240.680748)
		)
		(stroke
			(width 0)
			(type solid)
		)
		(fill yes)
		(layer "In2.Cu")
		(net "M_I_CPU1_SA_DQ<25>")
	)
	(gr_poly
		(pts
			(xy 128.794764 -239.016286) (xy 128.694688 -238.91621) (xy 128.594612 -239.016286) (xy 128.594612 -239.060736)
			(xy 128.794764 -239.060736)
		)
		(stroke
			(width 0)
			(type solid)
		)
		(fill yes)
		(layer "In2.Cu")
		(net "M_I_CPU1_SA_DQ<21>")
	)
	(gr_poly
		(pts
			(xy 128.794764 -237.39602) (xy 128.694688 -237.296198) (xy 128.594612 -237.39602) (xy 128.594612 -237.443772)
			(xy 128.794764 -237.443772)
		)
		(stroke
			(width 0)
			(type solid)
		)
		(fill yes)
		(layer "In2.Cu")
		(net "M_I_CPU1_SA_DQS_DN<7>")
	)
	(gr_poly
		(pts
			(xy 128.794764 -235.776262) (xy 128.694688 -235.676186) (xy 128.594612 -235.776262) (xy 128.594612 -235.820712)
			(xy 128.794764 -235.820712)
		)
		(stroke
			(width 0)
			(type solid)
		)
		(fill yes)
		(layer "In2.Cu")
		(net "M_I_CPU1_SA_DQ<17>")
	)
	(gr_poly
		(pts
			(xy 128.794764 -234.15625) (xy 128.694688 -234.056174) (xy 128.594612 -234.15625) (xy 128.594612 -234.2007)
			(xy 128.794764 -234.2007)
		)
		(stroke
			(width 0)
			(type solid)
		)
		(fill yes)
		(layer "In2.Cu")
		(net "M_I_CPU1_SA_DQ<13>")
	)
	(gr_poly
		(pts
			(xy 128.794764 -232.535984) (xy 128.694688 -232.436162) (xy 128.594612 -232.535984) (xy 128.594612 -232.583736)
			(xy 128.794764 -232.583736)
		)
		(stroke
			(width 0)
			(type solid)
		)
		(fill yes)
		(layer "In2.Cu")
		(net "M_I_CPU1_SA_DQS_DN<6>")
	)
	(gr_poly
		(pts
			(xy 128.794764 -230.916226) (xy 128.694688 -230.81615) (xy 128.594612 -230.916226) (xy 128.594612 -230.960676)
			(xy 128.794764 -230.960676)
		)
		(stroke
			(width 0)
			(type solid)
		)
		(fill yes)
		(layer "In2.Cu")
		(net "M_I_CPU1_SA_DQ<9>")
	)
	(gr_poly
		(pts
			(xy 128.794764 -229.296214) (xy 128.694688 -229.196138) (xy 128.594612 -229.296214) (xy 128.594612 -229.340664)
			(xy 128.794764 -229.340664)
		)
		(stroke
			(width 0)
			(type solid)
		)
		(fill yes)
		(layer "In2.Cu")
		(net "M_I_CPU1_SA_DQ<5>")
	)
	(gr_poly
		(pts
			(xy 128.794764 -227.676202) (xy 128.694688 -227.57638) (xy 128.594612 -227.676202) (xy 128.594612 -227.723954)
			(xy 128.794764 -227.723954)
		)
		(stroke
			(width 0)
			(type solid)
		)
		(fill yes)
		(layer "In2.Cu")
		(net "M_I_CPU1_SA_DQS_DN<5>")
	)
	(gr_poly
		(pts
			(xy 128.794764 -226.056444) (xy 128.694688 -225.956368) (xy 128.594612 -226.056444) (xy 128.594612 -226.100894)
			(xy 128.794764 -226.100894)
		)
		(stroke
			(width 0)
			(type solid)
		)
		(fill yes)
		(layer "In2.Cu")
		(net "M_I_CPU1_SA_DQ<1>")
	)
	(gr_poly
		(pts
			(xy 129.094738 -293.32428) (xy 129.094738 -293.27983) (xy 128.894586 -293.27983) (xy 128.894586 -293.32428)
			(xy 128.994662 -293.424356)
		)
		(stroke
			(width 0)
			(type solid)
		)
		(fill yes)
		(layer "In2.Cu")
		(net "M_I_CPU1_SB_DQ<31>")
	)
	(gr_poly
		(pts
			(xy 129.094738 -291.704522) (xy 129.094738 -291.65677) (xy 128.894586 -291.65677) (xy 128.894586 -291.704522)
			(xy 128.994662 -291.804344)
		)
		(stroke
			(width 0)
			(type solid)
		)
		(fill yes)
		(layer "In2.Cu")
		(net "M_I_CPU1_SB_DQS_DP<8>")
	)
	(gr_poly
		(pts
			(xy 129.094738 -290.084256) (xy 129.094738 -290.039806) (xy 128.894586 -290.039806) (xy 128.894586 -290.084256)
			(xy 128.994662 -290.184332)
		)
		(stroke
			(width 0)
			(type solid)
		)
		(fill yes)
		(layer "In2.Cu")
		(net "M_I_CPU1_SB_DQ<27>")
	)
	(gr_poly
		(pts
			(xy 129.094738 -288.464498) (xy 129.094738 -288.420048) (xy 128.894586 -288.420048) (xy 128.894586 -288.464498)
			(xy 128.994662 -288.564574)
		)
		(stroke
			(width 0)
			(type solid)
		)
		(fill yes)
		(layer "In2.Cu")
		(net "M_I_CPU1_SB_DQ<23>")
	)
	(gr_poly
		(pts
			(xy 129.094738 -286.844486) (xy 129.094738 -286.796734) (xy 128.894586 -286.796734) (xy 128.894586 -286.844486)
			(xy 128.994662 -286.944562)
		)
		(stroke
			(width 0)
			(type solid)
		)
		(fill yes)
		(layer "In2.Cu")
		(net "M_I_CPU1_SB_DQS_DP<7>")
	)
	(gr_poly
		(pts
			(xy 129.094738 -285.224474) (xy 129.094738 -285.180024) (xy 128.894586 -285.180024) (xy 128.894586 -285.224474)
			(xy 128.994662 -285.32455)
		)
		(stroke
			(width 0)
			(type solid)
		)
		(fill yes)
		(layer "In2.Cu")
		(net "M_I_CPU1_SB_DQ<19>")
	)
	(gr_poly
		(pts
			(xy 129.094738 -283.604462) (xy 129.094738 -283.560012) (xy 128.894586 -283.560012) (xy 128.894586 -283.604462)
			(xy 128.994662 -283.704538)
		)
		(stroke
			(width 0)
			(type solid)
		)
		(fill yes)
		(layer "In2.Cu")
		(net "M_I_CPU1_SB_DQ<15>")
	)
	(gr_poly
		(pts
			(xy 129.094738 -281.984704) (xy 129.094738 -281.936952) (xy 128.894586 -281.936952) (xy 128.894586 -281.984704)
			(xy 128.994662 -282.084526)
		)
		(stroke
			(width 0)
			(type solid)
		)
		(fill yes)
		(layer "In2.Cu")
		(net "M_I_CPU1_SB_DQS_DP<6>")
	)
	(gr_poly
		(pts
			(xy 129.094738 -280.364438) (xy 129.094738 -280.319988) (xy 128.894586 -280.319988) (xy 128.894586 -280.364438)
			(xy 128.994662 -280.464514)
		)
		(stroke
			(width 0)
			(type solid)
		)
		(fill yes)
		(layer "In2.Cu")
		(net "M_I_CPU1_SB_DQ<11>")
	)
	(gr_poly
		(pts
			(xy 129.094738 -278.744426) (xy 129.094738 -278.699976) (xy 128.894586 -278.699976) (xy 128.894586 -278.744426)
			(xy 128.994662 -278.844502)
		)
		(stroke
			(width 0)
			(type solid)
		)
		(fill yes)
		(layer "In2.Cu")
		(net "M_I_CPU1_SB_DQ<7>")
	)
	(gr_poly
		(pts
			(xy 129.094738 -277.124668) (xy 129.094738 -277.076916) (xy 128.894586 -277.076916) (xy 128.894586 -277.124668)
			(xy 128.994662 -277.22449)
		)
		(stroke
			(width 0)
			(type solid)
		)
		(fill yes)
		(layer "In2.Cu")
		(net "M_I_CPU1_SB_DQS_DP<5>")
	)
	(gr_poly
		(pts
			(xy 129.094738 -275.504402) (xy 129.094738 -275.459952) (xy 128.894586 -275.459952) (xy 128.894586 -275.504402)
			(xy 128.994662 -275.604478)
		)
		(stroke
			(width 0)
			(type solid)
		)
		(fill yes)
		(layer "In2.Cu")
		(net "M_I_CPU1_SB_DQ<3>")
	)
	(gr_poly
		(pts
			(xy 129.094738 -273.88439) (xy 129.094738 -273.83994) (xy 128.894586 -273.83994) (xy 128.894586 -273.88439)
			(xy 128.994662 -273.984466)
		)
		(stroke
			(width 0)
			(type solid)
		)
		(fill yes)
		(layer "In2.Cu")
		(net "M_I_CPU1_SB_CB<3>")
	)
	(gr_poly
		(pts
			(xy 129.094738 -272.264632) (xy 129.094738 -272.21688) (xy 128.894586 -272.21688) (xy 128.894586 -272.264632)
			(xy 128.994662 -272.364454)
		)
		(stroke
			(width 0)
			(type solid)
		)
		(fill yes)
		(layer "In2.Cu")
		(net "M_I_CPU1_SB_DQS_DP<4>")
	)
	(gr_poly
		(pts
			(xy 129.094738 -270.644366) (xy 129.094738 -270.599916) (xy 128.894586 -270.599916) (xy 128.894586 -270.644366)
			(xy 128.994662 -270.744442)
		)
		(stroke
			(width 0)
			(type solid)
		)
		(fill yes)
		(layer "In2.Cu")
		(net "M_I_CPU1_SB_CB<7>")
	)
	(gr_poly
		(pts
			(xy 129.094738 -265.78433) (xy 129.094738 -265.73988) (xy 128.894586 -265.73988) (xy 128.894586 -265.78433)
			(xy 128.994662 -265.884406)
		)
		(stroke
			(width 0)
			(type solid)
		)
		(fill yes)
		(layer "In2.Cu")
		(net "M_I_CPU1_SB_CS_N<0>")
	)
	(gr_poly
		(pts
			(xy 129.094738 -264.164318) (xy 129.094738 -264.119868) (xy 128.894586 -264.119868) (xy 128.894586 -264.164318)
			(xy 128.994662 -264.264394)
		)
		(stroke
			(width 0)
			(type solid)
		)
		(fill yes)
		(layer "In2.Cu")
		(net "M_I_CPU1_SB_CA<5>")
	)
	(gr_poly
		(pts
			(xy 129.094738 -262.544306) (xy 129.094738 -262.499856) (xy 128.894586 -262.499856) (xy 128.894586 -262.544306)
			(xy 128.994662 -262.644382)
		)
		(stroke
			(width 0)
			(type solid)
		)
		(fill yes)
		(layer "In2.Cu")
		(net "M_I_CPU1_SB_CA<1>")
	)
	(gr_poly
		(pts
			(xy 129.264918 -255.622552) (xy 129.264918 -255.578102) (xy 129.064766 -255.578102) (xy 129.064766 -255.622552)
			(xy 129.164842 -255.722628)
		)
		(stroke
			(width 0)
			(type solid)
		)
		(fill yes)
		(layer "In2.Cu")
		(net "M_I_CPU1_SA_PAR")
	)
	(gr_poly
		(pts
			(xy 129.264918 -254.00254) (xy 129.264918 -253.95809) (xy 129.064766 -253.95809) (xy 129.064766 -254.00254)
			(xy 129.164842 -254.102616)
		)
		(stroke
			(width 0)
			(type solid)
		)
		(fill yes)
		(layer "In2.Cu")
		(net "M_I_CPU1_SA_CA<3>")
	)
	(gr_poly
		(pts
			(xy 129.264918 -250.762516) (xy 129.264918 -250.718066) (xy 129.064766 -250.718066) (xy 129.064766 -250.762516)
			(xy 129.164842 -250.862592)
		)
		(stroke
			(width 0)
			(type solid)
		)
		(fill yes)
		(layer "In2.Cu")
		(net "M_I_CPU1_RESET_N")
	)
	(gr_poly
		(pts
			(xy 129.264918 -249.142504) (xy 129.264918 -249.098054) (xy 129.064766 -249.098054) (xy 129.064766 -249.142504)
			(xy 129.164842 -249.24258)
		)
		(stroke
			(width 0)
			(type solid)
		)
		(fill yes)
		(layer "In2.Cu")
		(net "M_I_CPU1_SA_CB<7>")
	)
	(gr_poly
		(pts
			(xy 129.264918 -247.522746) (xy 129.264918 -247.474994) (xy 129.064766 -247.474994) (xy 129.064766 -247.522746)
			(xy 129.164842 -247.622568)
		)
		(stroke
			(width 0)
			(type solid)
		)
		(fill yes)
		(layer "In2.Cu")
		(net "M_I_CPU1_SA_DQS_DP<9>")
	)
	(gr_poly
		(pts
			(xy 129.264918 -245.90248) (xy 129.264918 -245.85803) (xy 129.064766 -245.85803) (xy 129.064766 -245.90248)
			(xy 129.164842 -246.002556)
		)
		(stroke
			(width 0)
			(type solid)
		)
		(fill yes)
		(layer "In2.Cu")
		(net "M_I_CPU1_SA_CB<3>")
	)
	(gr_poly
		(pts
			(xy 129.264918 -244.282468) (xy 129.264918 -244.238018) (xy 129.064766 -244.238018) (xy 129.064766 -244.282468)
			(xy 129.164842 -244.382544)
		)
		(stroke
			(width 0)
			(type solid)
		)
		(fill yes)
		(layer "In2.Cu")
		(net "M_I_CPU1_SA_DQ<31>")
	)
	(gr_poly
		(pts
			(xy 129.264918 -242.66271) (xy 129.264918 -242.614958) (xy 129.064766 -242.614958) (xy 129.064766 -242.66271)
			(xy 129.164842 -242.762532)
		)
		(stroke
			(width 0)
			(type solid)
		)
		(fill yes)
		(layer "In2.Cu")
		(net "M_I_CPU1_SA_DQS_DP<8>")
	)
	(gr_poly
		(pts
			(xy 129.264918 -241.042444) (xy 129.264918 -240.997994) (xy 129.064766 -240.997994) (xy 129.064766 -241.042444)
			(xy 129.164842 -241.14252)
		)
		(stroke
			(width 0)
			(type solid)
		)
		(fill yes)
		(layer "In2.Cu")
		(net "M_I_CPU1_SA_DQ<27>")
	)
	(gr_poly
		(pts
			(xy 129.264918 -239.422432) (xy 129.264918 -239.377982) (xy 129.064766 -239.377982) (xy 129.064766 -239.422432)
			(xy 129.164842 -239.522508)
		)
		(stroke
			(width 0)
			(type solid)
		)
		(fill yes)
		(layer "In2.Cu")
		(net "M_I_CPU1_SA_DQ<23>")
	)
	(gr_poly
		(pts
			(xy 129.264918 -237.802674) (xy 129.264918 -237.754922) (xy 129.064766 -237.754922) (xy 129.064766 -237.802674)
			(xy 129.164842 -237.902496)
		)
		(stroke
			(width 0)
			(type solid)
		)
		(fill yes)
		(layer "In2.Cu")
		(net "M_I_CPU1_SA_DQS_DP<7>")
	)
	(gr_poly
		(pts
			(xy 129.264918 -236.182408) (xy 129.264918 -236.137958) (xy 129.064766 -236.137958) (xy 129.064766 -236.182408)
			(xy 129.164842 -236.282484)
		)
		(stroke
			(width 0)
			(type solid)
		)
		(fill yes)
		(layer "In2.Cu")
		(net "M_I_CPU1_SA_DQ<19>")
	)
	(gr_poly
		(pts
			(xy 129.264918 -234.562396) (xy 129.264918 -234.517946) (xy 129.064766 -234.517946) (xy 129.064766 -234.562396)
			(xy 129.164842 -234.662472)
		)
		(stroke
			(width 0)
			(type solid)
		)
		(fill yes)
		(layer "In2.Cu")
		(net "M_I_CPU1_SA_DQ<15>")
	)
	(gr_poly
		(pts
			(xy 129.264918 -232.942638) (xy 129.264918 -232.894886) (xy 129.064766 -232.894886) (xy 129.064766 -232.942638)
			(xy 129.164842 -233.04246)
		)
		(stroke
			(width 0)
			(type solid)
		)
		(fill yes)
		(layer "In2.Cu")
		(net "M_I_CPU1_SA_DQS_DP<6>")
	)
	(gr_poly
		(pts
			(xy 129.264918 -231.322626) (xy 129.264918 -231.278176) (xy 129.064766 -231.278176) (xy 129.064766 -231.322626)
			(xy 129.164842 -231.422702)
		)
		(stroke
			(width 0)
			(type solid)
		)
		(fill yes)
		(layer "In2.Cu")
		(net "M_I_CPU1_SA_DQ<11>")
	)
	(gr_poly
		(pts
			(xy 129.264918 -229.702614) (xy 129.264918 -229.658164) (xy 129.064766 -229.658164) (xy 129.064766 -229.702614)
			(xy 129.164842 -229.80269)
		)
		(stroke
			(width 0)
			(type solid)
		)
		(fill yes)
		(layer "In2.Cu")
		(net "M_I_CPU1_SA_DQ<7>")
	)
	(gr_poly
		(pts
			(xy 129.264918 -228.082856) (xy 129.264918 -228.035104) (xy 129.064766 -228.035104) (xy 129.064766 -228.082856)
			(xy 129.164842 -228.182678)
		)
		(stroke
			(width 0)
			(type solid)
		)
		(fill yes)
		(layer "In2.Cu")
		(net "M_I_CPU1_SA_DQS_DP<5>")
	)
	(gr_poly
		(pts
			(xy 129.264918 -226.46259) (xy 129.264918 -226.41814) (xy 129.064766 -226.41814) (xy 129.064766 -226.46259)
			(xy 129.164842 -226.562666)
		)
		(stroke
			(width 0)
			(type solid)
		)
		(fill yes)
		(layer "In2.Cu")
		(net "M_I_CPU1_SA_DQ<3>")
	)
	(gr_poly
		(pts
			(xy 129.564892 -292.918134) (xy 129.464816 -292.818058) (xy 129.36474 -292.918134) (xy 129.36474 -292.962584)
			(xy 129.564892 -292.962584)
		)
		(stroke
			(width 0)
			(type solid)
		)
		(fill yes)
		(layer "In2.Cu")
		(net "M_I_CPU1_SB_DQ<29>")
	)
	(gr_poly
		(pts
			(xy 129.564892 -291.297868) (xy 129.464816 -291.198046) (xy 129.36474 -291.297868) (xy 129.36474 -291.34562)
			(xy 129.564892 -291.34562)
		)
		(stroke
			(width 0)
			(type solid)
		)
		(fill yes)
		(layer "In2.Cu")
		(net "M_I_CPU1_SB_DQS_DN<8>")
	)
	(gr_poly
		(pts
			(xy 129.564892 -289.67811) (xy 129.464816 -289.578034) (xy 129.36474 -289.67811) (xy 129.36474 -289.72256)
			(xy 129.564892 -289.72256)
		)
		(stroke
			(width 0)
			(type solid)
		)
		(fill yes)
		(layer "In2.Cu")
		(net "M_I_CPU1_SB_DQ<25>")
	)
	(gr_poly
		(pts
			(xy 129.564892 -288.058098) (xy 129.464816 -287.958022) (xy 129.36474 -288.058098) (xy 129.36474 -288.102548)
			(xy 129.564892 -288.102548)
		)
		(stroke
			(width 0)
			(type solid)
		)
		(fill yes)
		(layer "In2.Cu")
		(net "M_I_CPU1_SB_DQ<21>")
	)
	(gr_poly
		(pts
			(xy 129.564892 -286.438086) (xy 129.464816 -286.33801) (xy 129.36474 -286.438086) (xy 129.36474 -286.485838)
			(xy 129.564892 -286.485838)
		)
		(stroke
			(width 0)
			(type solid)
		)
		(fill yes)
		(layer "In2.Cu")
		(net "M_I_CPU1_SB_DQS_DN<7>")
	)
	(gr_poly
		(pts
			(xy 129.564892 -284.818328) (xy 129.464816 -284.718252) (xy 129.36474 -284.818328) (xy 129.36474 -284.862778)
			(xy 129.564892 -284.862778)
		)
		(stroke
			(width 0)
			(type solid)
		)
		(fill yes)
		(layer "In2.Cu")
		(net "M_I_CPU1_SB_DQ<17>")
	)
	(gr_poly
		(pts
			(xy 129.564892 -283.198316) (xy 129.464816 -283.09824) (xy 129.36474 -283.198316) (xy 129.36474 -283.242766)
			(xy 129.564892 -283.242766)
		)
		(stroke
			(width 0)
			(type solid)
		)
		(fill yes)
		(layer "In2.Cu")
		(net "M_I_CPU1_SB_DQ<13>")
	)
	(gr_poly
		(pts
			(xy 129.564892 -281.57805) (xy 129.464816 -281.478228) (xy 129.36474 -281.57805) (xy 129.36474 -281.625802)
			(xy 129.564892 -281.625802)
		)
		(stroke
			(width 0)
			(type solid)
		)
		(fill yes)
		(layer "In2.Cu")
		(net "M_I_CPU1_SB_DQS_DN<6>")
	)
	(gr_poly
		(pts
			(xy 129.564892 -279.958292) (xy 129.464816 -279.858216) (xy 129.36474 -279.958292) (xy 129.36474 -280.002742)
			(xy 129.564892 -280.002742)
		)
		(stroke
			(width 0)
			(type solid)
		)
		(fill yes)
		(layer "In2.Cu")
		(net "M_I_CPU1_SB_DQ<9>")
	)
	(gr_poly
		(pts
			(xy 129.564892 -278.33828) (xy 129.464816 -278.238204) (xy 129.36474 -278.33828) (xy 129.36474 -278.38273)
			(xy 129.564892 -278.38273)
		)
		(stroke
			(width 0)
			(type solid)
		)
		(fill yes)
		(layer "In2.Cu")
		(net "M_I_CPU1_SB_DQ<5>")
	)
	(gr_poly
		(pts
			(xy 129.564892 -276.718014) (xy 129.464816 -276.618192) (xy 129.36474 -276.718014) (xy 129.36474 -276.765766)
			(xy 129.564892 -276.765766)
		)
		(stroke
			(width 0)
			(type solid)
		)
		(fill yes)
		(layer "In2.Cu")
		(net "M_I_CPU1_SB_DQS_DN<5>")
	)
	(gr_poly
		(pts
			(xy 129.564892 -275.098256) (xy 129.464816 -274.99818) (xy 129.36474 -275.098256) (xy 129.36474 -275.142706)
			(xy 129.564892 -275.142706)
		)
		(stroke
			(width 0)
			(type solid)
		)
		(fill yes)
		(layer "In2.Cu")
		(net "M_I_CPU1_SB_DQ<1>")
	)
	(gr_poly
		(pts
			(xy 129.564892 -273.478244) (xy 129.464816 -273.378168) (xy 129.36474 -273.478244) (xy 129.36474 -273.522694)
			(xy 129.564892 -273.522694)
		)
		(stroke
			(width 0)
			(type solid)
		)
		(fill yes)
		(layer "In2.Cu")
		(net "M_I_CPU1_SB_CB<1>")
	)
	(gr_poly
		(pts
			(xy 129.564892 -271.857978) (xy 129.464816 -271.758156) (xy 129.36474 -271.857978) (xy 129.36474 -271.90573)
			(xy 129.564892 -271.90573)
		)
		(stroke
			(width 0)
			(type solid)
		)
		(fill yes)
		(layer "In2.Cu")
		(net "M_I_CPU1_SB_DQS_DN<4>")
	)
	(gr_poly
		(pts
			(xy 129.564892 -270.23822) (xy 129.464816 -270.138144) (xy 129.36474 -270.23822) (xy 129.36474 -270.28267)
			(xy 129.564892 -270.28267)
		)
		(stroke
			(width 0)
			(type solid)
		)
		(fill yes)
		(layer "In2.Cu")
		(net "M_I_CPU1_SB_CB<5>")
	)
	(gr_poly
		(pts
			(xy 129.564892 -266.998196) (xy 129.464816 -266.89812) (xy 129.36474 -266.998196) (xy 129.36474 -267.042646)
			(xy 129.564892 -267.042646)
		)
		(stroke
			(width 0)
			(type solid)
		)
		(fill yes)
		(layer "In2.Cu")
		(net "M_I_CPU1_SA_RSP<0>")
	)
	(gr_poly
		(pts
			(xy 129.564892 -265.378184) (xy 129.464816 -265.278108) (xy 129.36474 -265.378184) (xy 129.36474 -265.422634)
			(xy 129.564892 -265.422634)
		)
		(stroke
			(width 0)
			(type solid)
		)
		(fill yes)
		(layer "In2.Cu")
		(net "M_I_CPU1_SB_PAR")
	)
	(gr_poly
		(pts
			(xy 129.564892 -263.758172) (xy 129.464816 -263.658096) (xy 129.36474 -263.758172) (xy 129.36474 -263.802622)
			(xy 129.564892 -263.802622)
		)
		(stroke
			(width 0)
			(type solid)
		)
		(fill yes)
		(layer "In2.Cu")
		(net "M_I_CPU1_SB_CA<4>")
	)
	(gr_poly
		(pts
			(xy 129.564892 -262.13816) (xy 129.464816 -262.038084) (xy 129.36474 -262.13816) (xy 129.36474 -262.18261)
			(xy 129.564892 -262.18261)
		)
		(stroke
			(width 0)
			(type solid)
		)
		(fill yes)
		(layer "In2.Cu")
		(net "M_I_CPU1_SB_CA<0>")
	)
	(gr_poly
		(pts
			(xy 129.734818 -255.216406) (xy 129.634742 -255.11633) (xy 129.534666 -255.216406) (xy 129.534666 -255.260856)
			(xy 129.734818 -255.260856)
		)
		(stroke
			(width 0)
			(type solid)
		)
		(fill yes)
		(layer "In2.Cu")
		(net "M_I_CPU1_SA_CA<6>")
	)
	(gr_poly
		(pts
			(xy 129.734818 -253.596394) (xy 129.634742 -253.496318) (xy 129.534666 -253.596394) (xy 129.534666 -253.640844)
			(xy 129.734818 -253.640844)
		)
		(stroke
			(width 0)
			(type solid)
		)
		(fill yes)
		(layer "In2.Cu")
		(net "M_I_CPU1_SA_CA<2>")
	)
	(gr_poly
		(pts
			(xy 129.734818 -251.976382) (xy 129.634742 -251.876306) (xy 129.534666 -251.976382) (xy 129.534666 -252.020832)
			(xy 129.734818 -252.020832)
		)
		(stroke
			(width 0)
			(type solid)
		)
		(fill yes)
		(layer "In2.Cu")
		(net "M_I_CPU1_SA_CS_N<1>")
	)
	(gr_poly
		(pts
			(xy 129.734818 -250.35637) (xy 129.634742 -250.256294) (xy 129.534666 -250.35637) (xy 129.534666 -250.40082)
			(xy 129.734818 -250.40082)
		)
		(stroke
			(width 0)
			(type solid)
		)
		(fill yes)
		(layer "In2.Cu")
		(net "M_I_CPU1_ALERT_R_N")
	)
	(gr_poly
		(pts
			(xy 129.734818 -248.736358) (xy 129.634742 -248.636282) (xy 129.534666 -248.736358) (xy 129.534666 -248.780808)
			(xy 129.734818 -248.780808)
		)
		(stroke
			(width 0)
			(type solid)
		)
		(fill yes)
		(layer "In2.Cu")
		(net "M_I_CPU1_SA_CB<5>")
	)
	(gr_poly
		(pts
			(xy 129.734818 -247.116092) (xy 129.634742 -247.01627) (xy 129.534666 -247.116092) (xy 129.534666 -247.163844)
			(xy 129.734818 -247.163844)
		)
		(stroke
			(width 0)
			(type solid)
		)
		(fill yes)
		(layer "In2.Cu")
		(net "M_I_CPU1_SA_DQS_DN<9>")
	)
	(gr_poly
		(pts
			(xy 129.734818 -245.496334) (xy 129.634742 -245.396258) (xy 129.534666 -245.496334) (xy 129.534666 -245.540784)
			(xy 129.734818 -245.540784)
		)
		(stroke
			(width 0)
			(type solid)
		)
		(fill yes)
		(layer "In2.Cu")
		(net "M_I_CPU1_SA_CB<1>")
	)
	(gr_poly
		(pts
			(xy 129.734818 -243.876322) (xy 129.634742 -243.776246) (xy 129.534666 -243.876322) (xy 129.534666 -243.920772)
			(xy 129.734818 -243.920772)
		)
		(stroke
			(width 0)
			(type solid)
		)
		(fill yes)
		(layer "In2.Cu")
		(net "M_I_CPU1_SA_DQ<29>")
	)
	(gr_poly
		(pts
			(xy 129.734818 -242.256056) (xy 129.634742 -242.156234) (xy 129.534666 -242.256056) (xy 129.534666 -242.303808)
			(xy 129.734818 -242.303808)
		)
		(stroke
			(width 0)
			(type solid)
		)
		(fill yes)
		(layer "In2.Cu")
		(net "M_I_CPU1_SA_DQS_DN<8>")
	)
	(gr_poly
		(pts
			(xy 129.734818 -240.636298) (xy 129.634742 -240.536222) (xy 129.534666 -240.636298) (xy 129.534666 -240.680748)
			(xy 129.734818 -240.680748)
		)
		(stroke
			(width 0)
			(type solid)
		)
		(fill yes)
		(layer "In2.Cu")
		(net "M_I_CPU1_SA_DQ<25>")
	)
	(gr_poly
		(pts
			(xy 129.734818 -239.016286) (xy 129.634742 -238.91621) (xy 129.534666 -239.016286) (xy 129.534666 -239.060736)
			(xy 129.734818 -239.060736)
		)
		(stroke
			(width 0)
			(type solid)
		)
		(fill yes)
		(layer "In2.Cu")
		(net "M_I_CPU1_SA_DQ<21>")
	)
	(gr_poly
		(pts
			(xy 129.734818 -237.39602) (xy 129.634742 -237.296198) (xy 129.534666 -237.39602) (xy 129.534666 -237.443772)
			(xy 129.734818 -237.443772)
		)
		(stroke
			(width 0)
			(type solid)
		)
		(fill yes)
		(layer "In2.Cu")
		(net "M_I_CPU1_SA_DQS_DN<7>")
	)
	(gr_poly
		(pts
			(xy 129.734818 -235.776262) (xy 129.634742 -235.676186) (xy 129.534666 -235.776262) (xy 129.534666 -235.820712)
			(xy 129.734818 -235.820712)
		)
		(stroke
			(width 0)
			(type solid)
		)
		(fill yes)
		(layer "In2.Cu")
		(net "M_I_CPU1_SA_DQ<17>")
	)
	(gr_poly
		(pts
			(xy 129.734818 -234.15625) (xy 129.634742 -234.056174) (xy 129.534666 -234.15625) (xy 129.534666 -234.2007)
			(xy 129.734818 -234.2007)
		)
		(stroke
			(width 0)
			(type solid)
		)
		(fill yes)
		(layer "In2.Cu")
		(net "M_I_CPU1_SA_DQ<13>")
	)
	(gr_poly
		(pts
			(xy 129.734818 -232.535984) (xy 129.634742 -232.436162) (xy 129.534666 -232.535984) (xy 129.534666 -232.583736)
			(xy 129.734818 -232.583736)
		)
		(stroke
			(width 0)
			(type solid)
		)
		(fill yes)
		(layer "In2.Cu")
		(net "M_I_CPU1_SA_DQS_DN<6>")
	)
	(gr_poly
		(pts
			(xy 129.734818 -230.916226) (xy 129.634742 -230.81615) (xy 129.534666 -230.916226) (xy 129.534666 -230.960676)
			(xy 129.734818 -230.960676)
		)
		(stroke
			(width 0)
			(type solid)
		)
		(fill yes)
		(layer "In2.Cu")
		(net "M_I_CPU1_SA_DQ<9>")
	)
	(gr_poly
		(pts
			(xy 129.734818 -229.296214) (xy 129.634742 -229.196138) (xy 129.534666 -229.296214) (xy 129.534666 -229.340664)
			(xy 129.734818 -229.340664)
		)
		(stroke
			(width 0)
			(type solid)
		)
		(fill yes)
		(layer "In2.Cu")
		(net "M_I_CPU1_SA_DQ<5>")
	)
	(gr_poly
		(pts
			(xy 129.734818 -227.676202) (xy 129.634742 -227.57638) (xy 129.534666 -227.676202) (xy 129.534666 -227.723954)
			(xy 129.734818 -227.723954)
		)
		(stroke
			(width 0)
			(type solid)
		)
		(fill yes)
		(layer "In2.Cu")
		(net "M_I_CPU1_SA_DQS_DN<5>")
	)
	(gr_poly
		(pts
			(xy 129.734818 -226.056444) (xy 129.634742 -225.956368) (xy 129.534666 -226.056444) (xy 129.534666 -226.100894)
			(xy 129.734818 -226.100894)
		)
		(stroke
			(width 0)
			(type solid)
		)
		(fill yes)
		(layer "In2.Cu")
		(net "M_I_CPU1_SA_DQ<1>")
	)
	(gr_poly
		(pts
			(xy 129.773426 -254.80264) (xy 129.769616 -254.758444) (xy 129.570226 -254.775716) (xy 129.57429 -254.820166)
			(xy 129.682494 -254.911098)
		)
		(stroke
			(width 0)
			(type solid)
		)
		(fill yes)
		(layer "In2.Cu")
		(net "M_I_CPU1_SA_CA<5>")
	)
	(gr_poly
		(pts
			(xy 129.773426 -253.182628) (xy 129.769616 -253.138432) (xy 129.570226 -253.155704) (xy 129.57429 -253.200154)
			(xy 129.682494 -253.291086)
		)
		(stroke
			(width 0)
			(type solid)
		)
		(fill yes)
		(layer "In2.Cu")
		(net "M_I_CPU1_SA_CA<1>")
	)
	(gr_poly
		(pts
			(xy 129.773426 -248.322592) (xy 129.769616 -248.278396) (xy 129.570226 -248.295668) (xy 129.57429 -248.340118)
			(xy 129.682494 -248.43105)
		)
		(stroke
			(width 0)
			(type solid)
		)
		(fill yes)
		(layer "In2.Cu")
		(net "M_I_CPU1_SA_CB<6>")
	)
	(gr_poly
		(pts
			(xy 129.773426 -245.082568) (xy 129.769616 -245.038372) (xy 129.570226 -245.055644) (xy 129.57429 -245.100094)
			(xy 129.682494 -245.191026)
		)
		(stroke
			(width 0)
			(type solid)
		)
		(fill yes)
		(layer "In2.Cu")
		(net "M_I_CPU1_SA_CB<2>")
	)
	(gr_poly
		(pts
			(xy 129.773426 -243.462556) (xy 129.769616 -243.41836) (xy 129.570226 -243.435632) (xy 129.57429 -243.480082)
			(xy 129.682494 -243.571014)
		)
		(stroke
			(width 0)
			(type solid)
		)
		(fill yes)
		(layer "In2.Cu")
		(net "M_I_CPU1_SA_DQ<30>")
	)
	(gr_poly
		(pts
			(xy 129.773426 -240.222532) (xy 129.769616 -240.178336) (xy 129.570226 -240.195608) (xy 129.57429 -240.240058)
			(xy 129.682494 -240.33099)
		)
		(stroke
			(width 0)
			(type solid)
		)
		(fill yes)
		(layer "In2.Cu")
		(net "M_I_CPU1_SA_DQ<26>")
	)
	(gr_poly
		(pts
			(xy 129.773426 -238.60252) (xy 129.769616 -238.558324) (xy 129.570226 -238.575596) (xy 129.57429 -238.620046)
			(xy 129.682494 -238.710978)
		)
		(stroke
			(width 0)
			(type solid)
		)
		(fill yes)
		(layer "In2.Cu")
		(net "M_I_CPU1_SA_DQ<22>")
	)
	(gr_poly
		(pts
			(xy 129.773426 -235.362496) (xy 129.769616 -235.3183) (xy 129.570226 -235.335572) (xy 129.57429 -235.380022)
			(xy 129.682494 -235.470954)
		)
		(stroke
			(width 0)
			(type solid)
		)
		(fill yes)
		(layer "In2.Cu")
		(net "M_I_CPU1_SA_DQ<18>")
	)
	(gr_poly
		(pts
			(xy 129.773426 -233.742484) (xy 129.769616 -233.698288) (xy 129.570226 -233.71556) (xy 129.57429 -233.76001)
			(xy 129.682494 -233.850942)
		)
		(stroke
			(width 0)
			(type solid)
		)
		(fill yes)
		(layer "In2.Cu")
		(net "M_I_CPU1_SA_DQ<14>")
	)
	(gr_poly
		(pts
			(xy 129.773426 -230.502714) (xy 129.769616 -230.458518) (xy 129.570226 -230.47579) (xy 129.57429 -230.52024)
			(xy 129.682494 -230.611172)
		)
		(stroke
			(width 0)
			(type solid)
		)
		(fill yes)
		(layer "In2.Cu")
		(net "M_I_CPU1_SA_DQ<10>")
	)
	(gr_poly
		(pts
			(xy 129.773426 -228.882702) (xy 129.769616 -228.838506) (xy 129.570226 -228.855778) (xy 129.57429 -228.900228)
			(xy 129.682494 -228.99116)
		)
		(stroke
			(width 0)
			(type solid)
		)
		(fill yes)
		(layer "In2.Cu")
		(net "M_I_CPU1_SA_DQ<6>")
	)
	(gr_poly
		(pts
			(xy 129.773426 -225.642678) (xy 129.769616 -225.598482) (xy 129.570226 -225.615754) (xy 129.57429 -225.660204)
			(xy 129.682494 -225.751136)
		)
		(stroke
			(width 0)
			(type solid)
		)
		(fill yes)
		(layer "In2.Cu")
		(net "M_I_CPU1_SA_DQ<2>")
	)
	(gr_poly
		(pts
			(xy 129.786126 -256.42189) (xy 129.782062 -256.374392) (xy 129.582672 -256.391918) (xy 129.58699 -256.439416)
			(xy 129.695194 -256.530348)
		)
		(stroke
			(width 0)
			(type solid)
		)
		(fill yes)
		(layer "In2.Cu")
		(net "M_I_CPU1_CLK_DN<0>")
	)
	(gr_poly
		(pts
			(xy 129.786126 -246.701818) (xy 129.782062 -246.65432) (xy 129.582672 -246.671846) (xy 129.58699 -246.719344)
			(xy 129.695194 -246.810276)
		)
		(stroke
			(width 0)
			(type solid)
		)
		(fill yes)
		(layer "In2.Cu")
		(net "M_I_CPU1_SA_DQS_DN<4>")
	)
	(gr_poly
		(pts
			(xy 129.786126 -241.841782) (xy 129.782062 -241.794284) (xy 129.582672 -241.81181) (xy 129.58699 -241.859308)
			(xy 129.695194 -241.95024)
		)
		(stroke
			(width 0)
			(type solid)
		)
		(fill yes)
		(layer "In2.Cu")
		(net "M_I_CPU1_SA_DQS_DN<3>")
	)
	(gr_poly
		(pts
			(xy 129.786126 -236.981746) (xy 129.782062 -236.934502) (xy 129.582672 -236.951774) (xy 129.58699 -236.999272)
			(xy 129.695194 -237.090204)
		)
		(stroke
			(width 0)
			(type solid)
		)
		(fill yes)
		(layer "In2.Cu")
		(net "M_I_CPU1_SA_DQS_DN<2>")
	)
	(gr_poly
		(pts
			(xy 129.786126 -232.12171) (xy 129.782062 -232.074466) (xy 129.582672 -232.091738) (xy 129.58699 -232.139236)
			(xy 129.695194 -232.230168)
		)
		(stroke
			(width 0)
			(type solid)
		)
		(fill yes)
		(layer "In2.Cu")
		(net "M_I_CPU1_SA_DQS_DN<1>")
	)
	(gr_poly
		(pts
			(xy 129.786126 -227.261928) (xy 129.782062 -227.214684) (xy 129.582672 -227.231956) (xy 129.58699 -227.279454)
			(xy 129.695194 -227.370386)
		)
		(stroke
			(width 0)
			(type solid)
		)
		(fill yes)
		(layer "In2.Cu")
		(net "M_I_CPU1_SA_DQS_DN<0>")
	)
	(gr_poly
		(pts
			(xy 130.034792 -293.32428) (xy 130.034792 -293.27983) (xy 129.83464 -293.27983) (xy 129.83464 -293.32428)
			(xy 129.934716 -293.424356)
		)
		(stroke
			(width 0)
			(type solid)
		)
		(fill yes)
		(layer "In2.Cu")
		(net "M_I_CPU1_SB_DQ<31>")
	)
	(gr_poly
		(pts
			(xy 130.034792 -291.704522) (xy 130.034792 -291.65677) (xy 129.83464 -291.65677) (xy 129.83464 -291.704522)
			(xy 129.934716 -291.804344)
		)
		(stroke
			(width 0)
			(type solid)
		)
		(fill yes)
		(layer "In2.Cu")
		(net "M_I_CPU1_SB_DQS_DP<8>")
	)
	(gr_poly
		(pts
			(xy 130.034792 -290.084256) (xy 130.034792 -290.039806) (xy 129.83464 -290.039806) (xy 129.83464 -290.084256)
			(xy 129.934716 -290.184332)
		)
		(stroke
			(width 0)
			(type solid)
		)
		(fill yes)
		(layer "In2.Cu")
		(net "M_I_CPU1_SB_DQ<27>")
	)
	(gr_poly
		(pts
			(xy 130.034792 -288.464498) (xy 130.034792 -288.420048) (xy 129.83464 -288.420048) (xy 129.83464 -288.464498)
			(xy 129.934716 -288.564574)
		)
		(stroke
			(width 0)
			(type solid)
		)
		(fill yes)
		(layer "In2.Cu")
		(net "M_I_CPU1_SB_DQ<23>")
	)
	(gr_poly
		(pts
			(xy 130.034792 -286.844486) (xy 130.034792 -286.796734) (xy 129.83464 -286.796734) (xy 129.83464 -286.844486)
			(xy 129.934716 -286.944562)
		)
		(stroke
			(width 0)
			(type solid)
		)
		(fill yes)
		(layer "In2.Cu")
		(net "M_I_CPU1_SB_DQS_DP<7>")
	)
	(gr_poly
		(pts
			(xy 130.034792 -285.224474) (xy 130.034792 -285.180024) (xy 129.83464 -285.180024) (xy 129.83464 -285.224474)
			(xy 129.934716 -285.32455)
		)
		(stroke
			(width 0)
			(type solid)
		)
		(fill yes)
		(layer "In2.Cu")
		(net "M_I_CPU1_SB_DQ<19>")
	)
	(gr_poly
		(pts
			(xy 130.034792 -283.604462) (xy 130.034792 -283.560012) (xy 129.83464 -283.560012) (xy 129.83464 -283.604462)
			(xy 129.934716 -283.704538)
		)
		(stroke
			(width 0)
			(type solid)
		)
		(fill yes)
		(layer "In2.Cu")
		(net "M_I_CPU1_SB_DQ<15>")
	)
	(gr_poly
		(pts
			(xy 130.034792 -281.984704) (xy 130.034792 -281.936952) (xy 129.83464 -281.936952) (xy 129.83464 -281.984704)
			(xy 129.934716 -282.084526)
		)
		(stroke
			(width 0)
			(type solid)
		)
		(fill yes)
		(layer "In2.Cu")
		(net "M_I_CPU1_SB_DQS_DP<6>")
	)
	(gr_poly
		(pts
			(xy 130.034792 -280.364438) (xy 130.034792 -280.319988) (xy 129.83464 -280.319988) (xy 129.83464 -280.364438)
			(xy 129.934716 -280.464514)
		)
		(stroke
			(width 0)
			(type solid)
		)
		(fill yes)
		(layer "In2.Cu")
		(net "M_I_CPU1_SB_DQ<11>")
	)
	(gr_poly
		(pts
			(xy 130.034792 -278.744426) (xy 130.034792 -278.699976) (xy 129.83464 -278.699976) (xy 129.83464 -278.744426)
			(xy 129.934716 -278.844502)
		)
		(stroke
			(width 0)
			(type solid)
		)
		(fill yes)
		(layer "In2.Cu")
		(net "M_I_CPU1_SB_DQ<7>")
	)
	(gr_poly
		(pts
			(xy 130.034792 -277.124668) (xy 130.034792 -277.076916) (xy 129.83464 -277.076916) (xy 129.83464 -277.124668)
			(xy 129.934716 -277.22449)
		)
		(stroke
			(width 0)
			(type solid)
		)
		(fill yes)
		(layer "In2.Cu")
		(net "M_I_CPU1_SB_DQS_DP<5>")
	)
	(gr_poly
		(pts
			(xy 130.034792 -275.504402) (xy 130.034792 -275.459952) (xy 129.83464 -275.459952) (xy 129.83464 -275.504402)
			(xy 129.934716 -275.604478)
		)
		(stroke
			(width 0)
			(type solid)
		)
		(fill yes)
		(layer "In2.Cu")
		(net "M_I_CPU1_SB_DQ<3>")
	)
	(gr_poly
		(pts
			(xy 130.034792 -273.88439) (xy 130.034792 -273.83994) (xy 129.83464 -273.83994) (xy 129.83464 -273.88439)
			(xy 129.934716 -273.984466)
		)
		(stroke
			(width 0)
			(type solid)
		)
		(fill yes)
		(layer "In2.Cu")
		(net "M_I_CPU1_SB_CB<3>")
	)
	(gr_poly
		(pts
			(xy 130.034792 -272.264632) (xy 130.034792 -272.21688) (xy 129.83464 -272.21688) (xy 129.83464 -272.264632)
			(xy 129.934716 -272.364454)
		)
		(stroke
			(width 0)
			(type solid)
		)
		(fill yes)
		(layer "In2.Cu")
		(net "M_I_CPU1_SB_DQS_DP<4>")
	)
	(gr_poly
		(pts
			(xy 130.034792 -270.644366) (xy 130.034792 -270.599916) (xy 129.83464 -270.599916) (xy 129.83464 -270.644366)
			(xy 129.934716 -270.744442)
		)
		(stroke
			(width 0)
			(type solid)
		)
		(fill yes)
		(layer "In2.Cu")
		(net "M_I_CPU1_SB_CB<7>")
	)
	(gr_poly
		(pts
			(xy 130.034792 -265.78433) (xy 130.034792 -265.73988) (xy 129.83464 -265.73988) (xy 129.83464 -265.78433)
			(xy 129.934716 -265.884406)
		)
		(stroke
			(width 0)
			(type solid)
		)
		(fill yes)
		(layer "In2.Cu")
		(net "M_I_CPU1_SB_CS_N<0>")
	)
	(gr_poly
		(pts
			(xy 130.034792 -264.164318) (xy 130.034792 -264.119868) (xy 129.83464 -264.119868) (xy 129.83464 -264.164318)
			(xy 129.934716 -264.264394)
		)
		(stroke
			(width 0)
			(type solid)
		)
		(fill yes)
		(layer "In2.Cu")
		(net "M_I_CPU1_SB_CA<5>")
	)
	(gr_poly
		(pts
			(xy 130.034792 -262.544306) (xy 130.034792 -262.499856) (xy 129.83464 -262.499856) (xy 129.83464 -262.544306)
			(xy 129.934716 -262.644382)
		)
		(stroke
			(width 0)
			(type solid)
		)
		(fill yes)
		(layer "In2.Cu")
		(net "M_I_CPU1_SB_CA<1>")
	)
	(gr_poly
		(pts
			(xy 130.0734 -292.118034) (xy 129.982468 -292.009576) (xy 129.874264 -292.100508) (xy 129.870454 -292.144958)
			(xy 130.06959 -292.16223)
		)
		(stroke
			(width 0)
			(type solid)
		)
		(fill yes)
		(layer "In2.Cu")
		(net "M_I_CPU1_SB_DQ<28>")
	)
	(gr_poly
		(pts
			(xy 130.0734 -288.87801) (xy 129.982468 -288.769552) (xy 129.874264 -288.860484) (xy 129.870454 -288.904934)
			(xy 130.06959 -288.922206)
		)
		(stroke
			(width 0)
			(type solid)
		)
		(fill yes)
		(layer "In2.Cu")
		(net "M_I_CPU1_SB_DQ<24>")
	)
	(gr_poly
		(pts
			(xy 130.0734 -287.257998) (xy 129.982468 -287.14954) (xy 129.874264 -287.240472) (xy 129.870454 -287.284922)
			(xy 130.06959 -287.302194)
		)
		(stroke
			(width 0)
			(type solid)
		)
		(fill yes)
		(layer "In2.Cu")
		(net "M_I_CPU1_SB_DQ<20>")
	)
	(gr_poly
		(pts
			(xy 130.0734 -284.018228) (xy 129.982468 -283.90977) (xy 129.874264 -284.000702) (xy 129.870454 -284.045152)
			(xy 130.06959 -284.062424)
		)
		(stroke
			(width 0)
			(type solid)
		)
		(fill yes)
		(layer "In2.Cu")
		(net "M_I_CPU1_SB_DQ<16>")
	)
	(gr_poly
		(pts
			(xy 130.0734 -282.398216) (xy 129.982468 -282.289758) (xy 129.874264 -282.38069) (xy 129.870454 -282.42514)
			(xy 130.06959 -282.442412)
		)
		(stroke
			(width 0)
			(type solid)
		)
		(fill yes)
		(layer "In2.Cu")
		(net "M_I_CPU1_SB_DQ<12>")
	)
	(gr_poly
		(pts
			(xy 130.0734 -279.158192) (xy 129.982468 -279.049734) (xy 129.874264 -279.140666) (xy 129.870454 -279.185116)
			(xy 130.06959 -279.202388)
		)
		(stroke
			(width 0)
			(type solid)
		)
		(fill yes)
		(layer "In2.Cu")
		(net "M_I_CPU1_SB_DQ<8>")
	)
	(gr_poly
		(pts
			(xy 130.0734 -277.53818) (xy 129.982468 -277.429722) (xy 129.874264 -277.520654) (xy 129.870454 -277.565104)
			(xy 130.06959 -277.582376)
		)
		(stroke
			(width 0)
			(type solid)
		)
		(fill yes)
		(layer "In2.Cu")
		(net "M_I_CPU1_SB_DQ<4>")
	)
	(gr_poly
		(pts
			(xy 130.0734 -274.298156) (xy 129.982468 -274.189698) (xy 129.874264 -274.28063) (xy 129.870454 -274.32508)
			(xy 130.06959 -274.342352)
		)
		(stroke
			(width 0)
			(type solid)
		)
		(fill yes)
		(layer "In2.Cu")
		(net "M_I_CPU1_SB_DQ<0>")
	)
	(gr_poly
		(pts
			(xy 130.0734 -272.678144) (xy 129.982468 -272.569686) (xy 129.874264 -272.660618) (xy 129.870454 -272.705068)
			(xy 130.06959 -272.72234)
		)
		(stroke
			(width 0)
			(type solid)
		)
		(fill yes)
		(layer "In2.Cu")
		(net "M_I_CPU1_SB_CB<0>")
	)
	(gr_poly
		(pts
			(xy 130.0734 -269.43812) (xy 129.982468 -269.329662) (xy 129.874264 -269.420594) (xy 129.870454 -269.465044)
			(xy 130.06959 -269.482316)
		)
		(stroke
			(width 0)
			(type solid)
		)
		(fill yes)
		(layer "In2.Cu")
		(net "M_I_CPU1_SB_CB<4>")
	)
	(gr_poly
		(pts
			(xy 130.0734 -264.578084) (xy 129.982468 -264.469626) (xy 129.874264 -264.560558) (xy 129.870454 -264.605008)
			(xy 130.06959 -264.62228)
		)
		(stroke
			(width 0)
			(type solid)
		)
		(fill yes)
		(layer "In2.Cu")
		(net "M_I_CPU1_SB_CA<6>")
	)
	(gr_poly
		(pts
			(xy 130.0734 -262.958072) (xy 129.982468 -262.849614) (xy 129.874264 -262.940546) (xy 129.870454 -262.984996)
			(xy 130.06959 -263.002268)
		)
		(stroke
			(width 0)
			(type solid)
		)
		(fill yes)
		(layer "In2.Cu")
		(net "M_I_CPU1_SB_CA<2>")
	)
	(gr_poly
		(pts
			(xy 130.075432 -285.63824) (xy 129.9845 -285.529782) (xy 129.876296 -285.620714) (xy 129.871978 -285.668212)
			(xy 130.071368 -285.685484)
		)
		(stroke
			(width 0)
			(type solid)
		)
		(fill yes)
		(layer "In2.Cu")
		(net "M_I_CPU1_SB_DQS_DP<2>")
	)
	(gr_poly
		(pts
			(xy 130.075432 -280.778204) (xy 129.9845 -280.669746) (xy 129.876296 -280.760678) (xy 129.871978 -280.808176)
			(xy 130.071368 -280.825448)
		)
		(stroke
			(width 0)
			(type solid)
		)
		(fill yes)
		(layer "In2.Cu")
		(net "M_I_CPU1_SB_DQS_DP<1>")
	)
	(gr_poly
		(pts
			(xy 130.075432 -275.918168) (xy 129.9845 -275.80971) (xy 129.876296 -275.900642) (xy 129.871978 -275.94814)
			(xy 130.071368 -275.965412)
		)
		(stroke
			(width 0)
			(type solid)
		)
		(fill yes)
		(layer "In2.Cu")
		(net "M_I_CPU1_SB_DQS_DP<0>")
	)
	(gr_poly
		(pts
			(xy 130.075432 -271.058132) (xy 129.9845 -270.949674) (xy 129.876296 -271.040606) (xy 129.871978 -271.088104)
			(xy 130.071368 -271.105376)
		)
		(stroke
			(width 0)
			(type solid)
		)
		(fill yes)
		(layer "In2.Cu")
		(net "M_I_CPU1_SB_DQS_DP<9>")
	)
	(gr_poly
		(pts
			(xy 130.086354 -290.498784) (xy 129.995422 -290.39058) (xy 129.887218 -290.481512) (xy 129.8829 -290.528756)
			(xy 130.08229 -290.546282)
		)
		(stroke
			(width 0)
			(type solid)
		)
		(fill yes)
		(layer "In2.Cu")
		(net "M_I_CPU1_SB_DQS_DP<3>")
	)
	(gr_poly
		(pts
			(xy 130.204718 -256.026158) (xy 130.104642 -255.926336) (xy 130.004566 -256.026158) (xy 130.004566 -256.07391)
			(xy 130.204718 -256.07391)
		)
		(stroke
			(width 0)
			(type solid)
		)
		(fill yes)
		(layer "In2.Cu")
		(net "M_I_CPU1_CLK_DP<0>")
	)
	(gr_poly
		(pts
			(xy 130.204718 -255.622552) (xy 130.204718 -255.578102) (xy 130.004566 -255.578102) (xy 130.004566 -255.622552)
			(xy 130.104642 -255.722628)
		)
		(stroke
			(width 0)
			(type solid)
		)
		(fill yes)
		(layer "In2.Cu")
		(net "M_I_CPU1_SA_PAR")
	)
	(gr_poly
		(pts
			(xy 130.204718 -254.4064) (xy 130.104642 -254.306324) (xy 130.004566 -254.4064) (xy 130.004566 -254.45085)
			(xy 130.204718 -254.45085)
		)
		(stroke
			(width 0)
			(type solid)
		)
		(fill yes)
		(layer "In2.Cu")
		(net "M_I_CPU1_SA_CA<4>")
	)
	(gr_poly
		(pts
			(xy 130.204718 -254.00254) (xy 130.204718 -253.95809) (xy 130.004566 -253.95809) (xy 130.004566 -254.00254)
			(xy 130.104642 -254.102616)
		)
		(stroke
			(width 0)
			(type solid)
		)
		(fill yes)
		(layer "In2.Cu")
		(net "M_I_CPU1_SA_CA<3>")
	)
	(gr_poly
		(pts
			(xy 130.204718 -252.786388) (xy 130.104642 -252.686312) (xy 130.004566 -252.786388) (xy 130.004566 -252.830838)
			(xy 130.204718 -252.830838)
		)
		(stroke
			(width 0)
			(type solid)
		)
		(fill yes)
		(layer "In2.Cu")
		(net "M_I_CPU1_SA_CA<0>")
	)
	(gr_poly
		(pts
			(xy 130.204718 -251.166376) (xy 130.104642 -251.0663) (xy 130.004566 -251.166376) (xy 130.004566 -251.210826)
			(xy 130.204718 -251.210826)
		)
		(stroke
			(width 0)
			(type solid)
		)
		(fill yes)
		(layer "In2.Cu")
		(net "M_I_CPU1_SA_CS_N<0>")
	)
	(gr_poly
		(pts
			(xy 130.204718 -250.762516) (xy 130.204718 -250.718066) (xy 130.004566 -250.718066) (xy 130.004566 -250.762516)
			(xy 130.104642 -250.862592)
		)
		(stroke
			(width 0)
			(type solid)
		)
		(fill yes)
		(layer "In2.Cu")
		(net "M_I_CPU1_RESET_N")
	)
	(gr_poly
		(pts
			(xy 130.204718 -249.142504) (xy 130.204718 -249.098054) (xy 130.004566 -249.098054) (xy 130.004566 -249.142504)
			(xy 130.104642 -249.24258)
		)
		(stroke
			(width 0)
			(type solid)
		)
		(fill yes)
		(layer "In2.Cu")
		(net "M_I_CPU1_SA_CB<7>")
	)
	(gr_poly
		(pts
			(xy 130.204718 -247.926352) (xy 130.104642 -247.826276) (xy 130.004566 -247.926352) (xy 130.004566 -247.970802)
			(xy 130.204718 -247.970802)
		)
		(stroke
			(width 0)
			(type solid)
		)
		(fill yes)
		(layer "In2.Cu")
		(net "M_I_CPU1_SA_CB<4>")
	)
	(gr_poly
		(pts
			(xy 130.204718 -247.522746) (xy 130.204718 -247.474994) (xy 130.004566 -247.474994) (xy 130.004566 -247.522746)
			(xy 130.104642 -247.622568)
		)
		(stroke
			(width 0)
			(type solid)
		)
		(fill yes)
		(layer "In2.Cu")
		(net "M_I_CPU1_SA_DQS_DP<9>")
	)
	(gr_poly
		(pts
			(xy 130.204718 -246.306086) (xy 130.104642 -246.206264) (xy 130.004566 -246.306086) (xy 130.004566 -246.353838)
			(xy 130.204718 -246.353838)
		)
		(stroke
			(width 0)
			(type solid)
		)
		(fill yes)
		(layer "In2.Cu")
		(net "M_I_CPU1_SA_DQS_DP<4>")
	)
	(gr_poly
		(pts
			(xy 130.204718 -245.90248) (xy 130.204718 -245.85803) (xy 130.004566 -245.85803) (xy 130.004566 -245.90248)
			(xy 130.104642 -246.002556)
		)
		(stroke
			(width 0)
			(type solid)
		)
		(fill yes)
		(layer "In2.Cu")
		(net "M_I_CPU1_SA_CB<3>")
	)
	(gr_poly
		(pts
			(xy 130.204718 -244.686328) (xy 130.104642 -244.586252) (xy 130.004566 -244.686328) (xy 130.004566 -244.730778)
			(xy 130.204718 -244.730778)
		)
		(stroke
			(width 0)
			(type solid)
		)
		(fill yes)
		(layer "In2.Cu")
		(net "M_I_CPU1_SA_CB<0>")
	)
	(gr_poly
		(pts
			(xy 130.204718 -244.282468) (xy 130.204718 -244.238018) (xy 130.004566 -244.238018) (xy 130.004566 -244.282468)
			(xy 130.104642 -244.382544)
		)
		(stroke
			(width 0)
			(type solid)
		)
		(fill yes)
		(layer "In2.Cu")
		(net "M_I_CPU1_SA_DQ<31>")
	)
	(gr_poly
		(pts
			(xy 130.204718 -243.066316) (xy 130.104642 -242.96624) (xy 130.004566 -243.066316) (xy 130.004566 -243.110766)
			(xy 130.204718 -243.110766)
		)
		(stroke
			(width 0)
			(type solid)
		)
		(fill yes)
		(layer "In2.Cu")
		(net "M_I_CPU1_SA_DQ<28>")
	)
	(gr_poly
		(pts
			(xy 130.204718 -242.66271) (xy 130.204718 -242.614958) (xy 130.004566 -242.614958) (xy 130.004566 -242.66271)
			(xy 130.104642 -242.762532)
		)
		(stroke
			(width 0)
			(type solid)
		)
		(fill yes)
		(layer "In2.Cu")
		(net "M_I_CPU1_SA_DQS_DP<8>")
	)
	(gr_poly
		(pts
			(xy 130.204718 -241.44605) (xy 130.104642 -241.346228) (xy 130.004566 -241.44605) (xy 130.004566 -241.493802)
			(xy 130.204718 -241.493802)
		)
		(stroke
			(width 0)
			(type solid)
		)
		(fill yes)
		(layer "In2.Cu")
		(net "M_I_CPU1_SA_DQS_DP<3>")
	)
	(gr_poly
		(pts
			(xy 130.204718 -241.042444) (xy 130.204718 -240.997994) (xy 130.004566 -240.997994) (xy 130.004566 -241.042444)
			(xy 130.104642 -241.14252)
		)
		(stroke
			(width 0)
			(type solid)
		)
		(fill yes)
		(layer "In2.Cu")
		(net "M_I_CPU1_SA_DQ<27>")
	)
	(gr_poly
		(pts
			(xy 130.204718 -239.826292) (xy 130.104642 -239.726216) (xy 130.004566 -239.826292) (xy 130.004566 -239.870742)
			(xy 130.204718 -239.870742)
		)
		(stroke
			(width 0)
			(type solid)
		)
		(fill yes)
		(layer "In2.Cu")
		(net "M_I_CPU1_SA_DQ<24>")
	)
	(gr_poly
		(pts
			(xy 130.204718 -239.422432) (xy 130.204718 -239.377982) (xy 130.004566 -239.377982) (xy 130.004566 -239.422432)
			(xy 130.104642 -239.522508)
		)
		(stroke
			(width 0)
			(type solid)
		)
		(fill yes)
		(layer "In2.Cu")
		(net "M_I_CPU1_SA_DQ<23>")
	)
	(gr_poly
		(pts
			(xy 130.204718 -238.20628) (xy 130.104642 -238.106204) (xy 130.004566 -238.20628) (xy 130.004566 -238.25073)
			(xy 130.204718 -238.25073)
		)
		(stroke
			(width 0)
			(type solid)
		)
		(fill yes)
		(layer "In2.Cu")
		(net "M_I_CPU1_SA_DQ<20>")
	)
	(gr_poly
		(pts
			(xy 130.204718 -237.802674) (xy 130.204718 -237.754922) (xy 130.004566 -237.754922) (xy 130.004566 -237.802674)
			(xy 130.104642 -237.902496)
		)
		(stroke
			(width 0)
			(type solid)
		)
		(fill yes)
		(layer "In2.Cu")
		(net "M_I_CPU1_SA_DQS_DP<7>")
	)
	(gr_poly
		(pts
			(xy 130.204718 -236.586014) (xy 130.104642 -236.486192) (xy 130.004566 -236.586014) (xy 130.004566 -236.633766)
			(xy 130.204718 -236.633766)
		)
		(stroke
			(width 0)
			(type solid)
		)
		(fill yes)
		(layer "In2.Cu")
		(net "M_I_CPU1_SA_DQS_DP<2>")
	)
	(gr_poly
		(pts
			(xy 130.204718 -236.182408) (xy 130.204718 -236.137958) (xy 130.004566 -236.137958) (xy 130.004566 -236.182408)
			(xy 130.104642 -236.282484)
		)
		(stroke
			(width 0)
			(type solid)
		)
		(fill yes)
		(layer "In2.Cu")
		(net "M_I_CPU1_SA_DQ<19>")
	)
	(gr_poly
		(pts
			(xy 130.204718 -234.966256) (xy 130.104642 -234.86618) (xy 130.004566 -234.966256) (xy 130.004566 -235.010706)
			(xy 130.204718 -235.010706)
		)
		(stroke
			(width 0)
			(type solid)
		)
		(fill yes)
		(layer "In2.Cu")
		(net "M_I_CPU1_SA_DQ<16>")
	)
	(gr_poly
		(pts
			(xy 130.204718 -234.562396) (xy 130.204718 -234.517946) (xy 130.004566 -234.517946) (xy 130.004566 -234.562396)
			(xy 130.104642 -234.662472)
		)
		(stroke
			(width 0)
			(type solid)
		)
		(fill yes)
		(layer "In2.Cu")
		(net "M_I_CPU1_SA_DQ<15>")
	)
	(gr_poly
		(pts
			(xy 130.204718 -233.346244) (xy 130.104642 -233.246168) (xy 130.004566 -233.346244) (xy 130.004566 -233.390694)
			(xy 130.204718 -233.390694)
		)
		(stroke
			(width 0)
			(type solid)
		)
		(fill yes)
		(layer "In2.Cu")
		(net "M_I_CPU1_SA_DQ<12>")
	)
	(gr_poly
		(pts
			(xy 130.204718 -232.942638) (xy 130.204718 -232.894886) (xy 130.004566 -232.894886) (xy 130.004566 -232.942638)
			(xy 130.104642 -233.04246)
		)
		(stroke
			(width 0)
			(type solid)
		)
		(fill yes)
		(layer "In2.Cu")
		(net "M_I_CPU1_SA_DQS_DP<6>")
	)
	(gr_poly
		(pts
			(xy 130.204718 -231.725978) (xy 130.104642 -231.626156) (xy 130.004566 -231.725978) (xy 130.004566 -231.77373)
			(xy 130.204718 -231.77373)
		)
		(stroke
			(width 0)
			(type solid)
		)
		(fill yes)
		(layer "In2.Cu")
		(net "M_I_CPU1_SA_DQS_DP<1>")
	)
	(gr_poly
		(pts
			(xy 130.204718 -231.322626) (xy 130.204718 -231.278176) (xy 130.004566 -231.278176) (xy 130.004566 -231.322626)
			(xy 130.104642 -231.422702)
		)
		(stroke
			(width 0)
			(type solid)
		)
		(fill yes)
		(layer "In2.Cu")
		(net "M_I_CPU1_SA_DQ<11>")
	)
	(gr_poly
		(pts
			(xy 130.204718 -230.10622) (xy 130.104642 -230.006144) (xy 130.004566 -230.10622) (xy 130.004566 -230.15067)
			(xy 130.204718 -230.15067)
		)
		(stroke
			(width 0)
			(type solid)
		)
		(fill yes)
		(layer "In2.Cu")
		(net "M_I_CPU1_SA_DQ<8>")
	)
	(gr_poly
		(pts
			(xy 130.204718 -229.702614) (xy 130.204718 -229.658164) (xy 130.004566 -229.658164) (xy 130.004566 -229.702614)
			(xy 130.104642 -229.80269)
		)
		(stroke
			(width 0)
			(type solid)
		)
		(fill yes)
		(layer "In2.Cu")
		(net "M_I_CPU1_SA_DQ<7>")
	)
	(gr_poly
		(pts
			(xy 130.204718 -228.486462) (xy 130.104642 -228.386386) (xy 130.004566 -228.486462) (xy 130.004566 -228.530912)
			(xy 130.204718 -228.530912)
		)
		(stroke
			(width 0)
			(type solid)
		)
		(fill yes)
		(layer "In2.Cu")
		(net "M_I_CPU1_SA_DQ<4>")
	)
	(gr_poly
		(pts
			(xy 130.204718 -228.082856) (xy 130.204718 -228.035104) (xy 130.004566 -228.035104) (xy 130.004566 -228.082856)
			(xy 130.104642 -228.182678)
		)
		(stroke
			(width 0)
			(type solid)
		)
		(fill yes)
		(layer "In2.Cu")
		(net "M_I_CPU1_SA_DQS_DP<5>")
	)
	(gr_poly
		(pts
			(xy 130.204718 -226.866196) (xy 130.104642 -226.766374) (xy 130.004566 -226.866196) (xy 130.004566 -226.913948)
			(xy 130.204718 -226.913948)
		)
		(stroke
			(width 0)
			(type solid)
		)
		(fill yes)
		(layer "In2.Cu")
		(net "M_I_CPU1_SA_DQS_DP<0>")
	)
	(gr_poly
		(pts
			(xy 130.204718 -226.46259) (xy 130.204718 -226.41814) (xy 130.004566 -226.41814) (xy 130.004566 -226.46259)
			(xy 130.104642 -226.562666)
		)
		(stroke
			(width 0)
			(type solid)
		)
		(fill yes)
		(layer "In2.Cu")
		(net "M_I_CPU1_SA_DQ<3>")
	)
	(gr_poly
		(pts
			(xy 130.204718 -225.246438) (xy 130.104642 -225.146362) (xy 130.004566 -225.246438) (xy 130.004566 -225.290888)
			(xy 130.204718 -225.290888)
		)
		(stroke
			(width 0)
			(type solid)
		)
		(fill yes)
		(layer "In2.Cu")
		(net "M_I_CPU1_SA_DQ<0>")
	)
	(gr_poly
		(pts
			(xy 130.504946 -292.918134) (xy 130.40487 -292.818058) (xy 130.304794 -292.918134) (xy 130.304794 -292.962584)
			(xy 130.504946 -292.962584)
		)
		(stroke
			(width 0)
			(type solid)
		)
		(fill yes)
		(layer "In2.Cu")
		(net "M_I_CPU1_SB_DQ<29>")
	)
	(gr_poly
		(pts
			(xy 130.504946 -292.514274) (xy 130.504946 -292.469824) (xy 130.304794 -292.469824) (xy 130.304794 -292.514274)
			(xy 130.40487 -292.61435)
		)
		(stroke
			(width 0)
			(type solid)
		)
		(fill yes)
		(layer "In2.Cu")
		(net "M_I_CPU1_SB_DQ<30>")
	)
	(gr_poly
		(pts
			(xy 130.504946 -291.297868) (xy 130.40487 -291.198046) (xy 130.304794 -291.297868) (xy 130.304794 -291.34562)
			(xy 130.504946 -291.34562)
		)
		(stroke
			(width 0)
			(type solid)
		)
		(fill yes)
		(layer "In2.Cu")
		(net "M_I_CPU1_SB_DQS_DN<8>")
	)
	(gr_poly
		(pts
			(xy 130.504946 -290.894516) (xy 130.504946 -290.846764) (xy 130.304794 -290.846764) (xy 130.304794 -290.894516)
			(xy 130.40487 -290.994338)
		)
		(stroke
			(width 0)
			(type solid)
		)
		(fill yes)
		(layer "In2.Cu")
		(net "M_I_CPU1_SB_DQS_DN<3>")
	)
	(gr_poly
		(pts
			(xy 130.504946 -289.67811) (xy 130.40487 -289.578034) (xy 130.304794 -289.67811) (xy 130.304794 -289.72256)
			(xy 130.504946 -289.72256)
		)
		(stroke
			(width 0)
			(type solid)
		)
		(fill yes)
		(layer "In2.Cu")
		(net "M_I_CPU1_SB_DQ<25>")
	)
	(gr_poly
		(pts
			(xy 130.504946 -289.27425) (xy 130.504946 -289.2298) (xy 130.304794 -289.2298) (xy 130.304794 -289.27425)
			(xy 130.40487 -289.374326)
		)
		(stroke
			(width 0)
			(type solid)
		)
		(fill yes)
		(layer "In2.Cu")
		(net "M_I_CPU1_SB_DQ<26>")
	)
	(gr_poly
		(pts
			(xy 130.504946 -288.058098) (xy 130.40487 -287.958022) (xy 130.304794 -288.058098) (xy 130.304794 -288.102548)
			(xy 130.504946 -288.102548)
		)
		(stroke
			(width 0)
			(type solid)
		)
		(fill yes)
		(layer "In2.Cu")
		(net "M_I_CPU1_SB_DQ<21>")
	)
	(gr_poly
		(pts
			(xy 130.504946 -287.654492) (xy 130.504946 -287.610042) (xy 130.304794 -287.610042) (xy 130.304794 -287.654492)
			(xy 130.40487 -287.754568)
		)
		(stroke
			(width 0)
			(type solid)
		)
		(fill yes)
		(layer "In2.Cu")
		(net "M_I_CPU1_SB_DQ<22>")
	)
	(gr_poly
		(pts
			(xy 130.504946 -286.438086) (xy 130.40487 -286.33801) (xy 130.304794 -286.438086) (xy 130.304794 -286.485838)
			(xy 130.504946 -286.485838)
		)
		(stroke
			(width 0)
			(type solid)
		)
		(fill yes)
		(layer "In2.Cu")
		(net "M_I_CPU1_SB_DQS_DN<7>")
	)
	(gr_poly
		(pts
			(xy 130.504946 -286.034734) (xy 130.504946 -285.986982) (xy 130.304794 -285.986982) (xy 130.304794 -286.034734)
			(xy 130.40487 -286.134556)
		)
		(stroke
			(width 0)
			(type solid)
		)
		(fill yes)
		(layer "In2.Cu")
		(net "M_I_CPU1_SB_DQS_DN<2>")
	)
	(gr_poly
		(pts
			(xy 130.504946 -284.818328) (xy 130.40487 -284.718252) (xy 130.304794 -284.818328) (xy 130.304794 -284.862778)
			(xy 130.504946 -284.862778)
		)
		(stroke
			(width 0)
			(type solid)
		)
		(fill yes)
		(layer "In2.Cu")
		(net "M_I_CPU1_SB_DQ<17>")
	)
	(gr_poly
		(pts
			(xy 130.504946 -284.414468) (xy 130.504946 -284.370018) (xy 130.304794 -284.370018) (xy 130.304794 -284.414468)
			(xy 130.40487 -284.514544)
		)
		(stroke
			(width 0)
			(type solid)
		)
		(fill yes)
		(layer "In2.Cu")
		(net "M_I_CPU1_SB_DQ<18>")
	)
	(gr_poly
		(pts
			(xy 130.504946 -283.198316) (xy 130.40487 -283.09824) (xy 130.304794 -283.198316) (xy 130.304794 -283.242766)
			(xy 130.504946 -283.242766)
		)
		(stroke
			(width 0)
			(type solid)
		)
		(fill yes)
		(layer "In2.Cu")
		(net "M_I_CPU1_SB_DQ<13>")
	)
	(gr_poly
		(pts
			(xy 130.504946 -282.794456) (xy 130.504946 -282.750006) (xy 130.304794 -282.750006) (xy 130.304794 -282.794456)
			(xy 130.40487 -282.894532)
		)
		(stroke
			(width 0)
			(type solid)
		)
		(fill yes)
		(layer "In2.Cu")
		(net "M_I_CPU1_SB_DQ<14>")
	)
	(gr_poly
		(pts
			(xy 130.504946 -281.57805) (xy 130.40487 -281.478228) (xy 130.304794 -281.57805) (xy 130.304794 -281.625802)
			(xy 130.504946 -281.625802)
		)
		(stroke
			(width 0)
			(type solid)
		)
		(fill yes)
		(layer "In2.Cu")
		(net "M_I_CPU1_SB_DQS_DN<6>")
	)
	(gr_poly
		(pts
			(xy 130.504946 -281.174698) (xy 130.504946 -281.126946) (xy 130.304794 -281.126946) (xy 130.304794 -281.174698)
			(xy 130.40487 -281.27452)
		)
		(stroke
			(width 0)
			(type solid)
		)
		(fill yes)
		(layer "In2.Cu")
		(net "M_I_CPU1_SB_DQS_DN<1>")
	)
	(gr_poly
		(pts
			(xy 130.504946 -279.958292) (xy 130.40487 -279.858216) (xy 130.304794 -279.958292) (xy 130.304794 -280.002742)
			(xy 130.504946 -280.002742)
		)
		(stroke
			(width 0)
			(type solid)
		)
		(fill yes)
		(layer "In2.Cu")
		(net "M_I_CPU1_SB_DQ<9>")
	)
	(gr_poly
		(pts
			(xy 130.504946 -279.554432) (xy 130.504946 -279.509982) (xy 130.304794 -279.509982) (xy 130.304794 -279.554432)
			(xy 130.40487 -279.654508)
		)
		(stroke
			(width 0)
			(type solid)
		)
		(fill yes)
		(layer "In2.Cu")
		(net "M_I_CPU1_SB_DQ<10>")
	)
	(gr_poly
		(pts
			(xy 130.504946 -278.33828) (xy 130.40487 -278.238204) (xy 130.304794 -278.33828) (xy 130.304794 -278.38273)
			(xy 130.504946 -278.38273)
		)
		(stroke
			(width 0)
			(type solid)
		)
		(fill yes)
		(layer "In2.Cu")
		(net "M_I_CPU1_SB_DQ<5>")
	)
	(gr_poly
		(pts
			(xy 130.504946 -277.93442) (xy 130.504946 -277.88997) (xy 130.304794 -277.88997) (xy 130.304794 -277.93442)
			(xy 130.40487 -278.034496)
		)
		(stroke
			(width 0)
			(type solid)
		)
		(fill yes)
		(layer "In2.Cu")
		(net "M_I_CPU1_SB_DQ<6>")
	)
	(gr_poly
		(pts
			(xy 130.504946 -276.718014) (xy 130.40487 -276.618192) (xy 130.304794 -276.718014) (xy 130.304794 -276.765766)
			(xy 130.504946 -276.765766)
		)
		(stroke
			(width 0)
			(type solid)
		)
		(fill yes)
		(layer "In2.Cu")
		(net "M_I_CPU1_SB_DQS_DN<5>")
	)
	(gr_poly
		(pts
			(xy 130.504946 -276.314662) (xy 130.504946 -276.26691) (xy 130.304794 -276.26691) (xy 130.304794 -276.314662)
			(xy 130.40487 -276.414484)
		)
		(stroke
			(width 0)
			(type solid)
		)
		(fill yes)
		(layer "In2.Cu")
		(net "M_I_CPU1_SB_DQS_DN<0>")
	)
	(gr_poly
		(pts
			(xy 130.504946 -275.098256) (xy 130.40487 -274.99818) (xy 130.304794 -275.098256) (xy 130.304794 -275.142706)
			(xy 130.504946 -275.142706)
		)
		(stroke
			(width 0)
			(type solid)
		)
		(fill yes)
		(layer "In2.Cu")
		(net "M_I_CPU1_SB_DQ<1>")
	)
	(gr_poly
		(pts
			(xy 130.504946 -274.694396) (xy 130.504946 -274.649946) (xy 130.304794 -274.649946) (xy 130.304794 -274.694396)
			(xy 130.40487 -274.794472)
		)
		(stroke
			(width 0)
			(type solid)
		)
		(fill yes)
		(layer "In2.Cu")
		(net "M_I_CPU1_SB_DQ<2>")
	)
	(gr_poly
		(pts
			(xy 130.504946 -273.478244) (xy 130.40487 -273.378168) (xy 130.304794 -273.478244) (xy 130.304794 -273.522694)
			(xy 130.504946 -273.522694)
		)
		(stroke
			(width 0)
			(type solid)
		)
		(fill yes)
		(layer "In2.Cu")
		(net "M_I_CPU1_SB_CB<1>")
	)
	(gr_poly
		(pts
			(xy 130.504946 -273.074384) (xy 130.504946 -273.029934) (xy 130.304794 -273.029934) (xy 130.304794 -273.074384)
			(xy 130.40487 -273.17446)
		)
		(stroke
			(width 0)
			(type solid)
		)
		(fill yes)
		(layer "In2.Cu")
		(net "M_I_CPU1_SB_CB<2>")
	)
	(gr_poly
		(pts
			(xy 130.504946 -271.857978) (xy 130.40487 -271.758156) (xy 130.304794 -271.857978) (xy 130.304794 -271.90573)
			(xy 130.504946 -271.90573)
		)
		(stroke
			(width 0)
			(type solid)
		)
		(fill yes)
		(layer "In2.Cu")
		(net "M_I_CPU1_SB_DQS_DN<4>")
	)
	(gr_poly
		(pts
			(xy 130.504946 -271.454626) (xy 130.504946 -271.406874) (xy 130.304794 -271.406874) (xy 130.304794 -271.454626)
			(xy 130.40487 -271.554448)
		)
		(stroke
			(width 0)
			(type solid)
		)
		(fill yes)
		(layer "In2.Cu")
		(net "M_I_CPU1_SB_DQS_DN<9>")
	)
	(gr_poly
		(pts
			(xy 130.504946 -270.23822) (xy 130.40487 -270.138144) (xy 130.304794 -270.23822) (xy 130.304794 -270.28267)
			(xy 130.504946 -270.28267)
		)
		(stroke
			(width 0)
			(type solid)
		)
		(fill yes)
		(layer "In2.Cu")
		(net "M_I_CPU1_SB_CB<5>")
	)
	(gr_poly
		(pts
			(xy 130.504946 -269.83436) (xy 130.504946 -269.78991) (xy 130.304794 -269.78991) (xy 130.304794 -269.83436)
			(xy 130.40487 -269.934436)
		)
		(stroke
			(width 0)
			(type solid)
		)
		(fill yes)
		(layer "In2.Cu")
		(net "M_I_CPU1_SB_CB<6>")
	)
	(gr_poly
		(pts
			(xy 130.504946 -266.998196) (xy 130.40487 -266.89812) (xy 130.304794 -266.998196) (xy 130.304794 -267.042646)
			(xy 130.504946 -267.042646)
		)
		(stroke
			(width 0)
			(type solid)
		)
		(fill yes)
		(layer "In2.Cu")
		(net "M_I_CPU1_SA_RSP<0>")
	)
	(gr_poly
		(pts
			(xy 130.504946 -266.594336) (xy 130.504946 -266.549886) (xy 130.304794 -266.549886) (xy 130.304794 -266.594336)
			(xy 130.40487 -266.694412)
		)
		(stroke
			(width 0)
			(type solid)
		)
		(fill yes)
		(layer "In2.Cu")
		(net "M_I_CPU1_SB_CS_N<1>")
	)
	(gr_poly
		(pts
			(xy 130.504946 -265.378184) (xy 130.40487 -265.278108) (xy 130.304794 -265.378184) (xy 130.304794 -265.422634)
			(xy 130.504946 -265.422634)
		)
		(stroke
			(width 0)
			(type solid)
		)
		(fill yes)
		(layer "In2.Cu")
		(net "M_I_CPU1_SB_PAR")
	)
	(gr_poly
		(pts
			(xy 130.504946 -263.758172) (xy 130.40487 -263.658096) (xy 130.304794 -263.758172) (xy 130.304794 -263.802622)
			(xy 130.504946 -263.802622)
		)
		(stroke
			(width 0)
			(type solid)
		)
		(fill yes)
		(layer "In2.Cu")
		(net "M_I_CPU1_SB_CA<4>")
	)
	(gr_poly
		(pts
			(xy 130.504946 -263.354312) (xy 130.504946 -263.309862) (xy 130.304794 -263.309862) (xy 130.304794 -263.354312)
			(xy 130.40487 -263.454388)
		)
		(stroke
			(width 0)
			(type solid)
		)
		(fill yes)
		(layer "In2.Cu")
		(net "M_I_CPU1_SB_CA<3>")
	)
	(gr_poly
		(pts
			(xy 130.504946 -262.13816) (xy 130.40487 -262.038084) (xy 130.304794 -262.13816) (xy 130.304794 -262.18261)
			(xy 130.504946 -262.18261)
		)
		(stroke
			(width 0)
			(type solid)
		)
		(fill yes)
		(layer "In2.Cu")
		(net "M_I_CPU1_SB_CA<0>")
	)
	(gr_poly
		(pts
			(xy 130.674872 -256.432812) (xy 130.674872 -256.38506) (xy 130.47472 -256.38506) (xy 130.47472 -256.432812)
			(xy 130.574796 -256.532634)
		)
		(stroke
			(width 0)
			(type solid)
		)
		(fill yes)
		(layer "In2.Cu")
		(net "M_I_CPU1_CLK_DN<0>")
	)
	(gr_poly
		(pts
			(xy 130.674872 -255.216406) (xy 130.574796 -255.11633) (xy 130.47472 -255.216406) (xy 130.47472 -255.260856)
			(xy 130.674872 -255.260856)
		)
		(stroke
			(width 0)
			(type solid)
		)
		(fill yes)
		(layer "In2.Cu")
		(net "M_I_CPU1_SA_CA<6>")
	)
	(gr_poly
		(pts
			(xy 130.674872 -254.812546) (xy 130.674872 -254.768096) (xy 130.47472 -254.768096) (xy 130.47472 -254.812546)
			(xy 130.574796 -254.912622)
		)
		(stroke
			(width 0)
			(type solid)
		)
		(fill yes)
		(layer "In2.Cu")
		(net "M_I_CPU1_SA_CA<5>")
	)
	(gr_poly
		(pts
			(xy 130.674872 -253.596394) (xy 130.574796 -253.496318) (xy 130.47472 -253.596394) (xy 130.47472 -253.640844)
			(xy 130.674872 -253.640844)
		)
		(stroke
			(width 0)
			(type solid)
		)
		(fill yes)
		(layer "In2.Cu")
		(net "M_I_CPU1_SA_CA<2>")
	)
	(gr_poly
		(pts
			(xy 130.674872 -253.192534) (xy 130.674872 -253.148084) (xy 130.47472 -253.148084) (xy 130.47472 -253.192534)
			(xy 130.574796 -253.29261)
		)
		(stroke
			(width 0)
			(type solid)
		)
		(fill yes)
		(layer "In2.Cu")
		(net "M_I_CPU1_SA_CA<1>")
	)
	(gr_poly
		(pts
			(xy 130.674872 -251.976382) (xy 130.574796 -251.876306) (xy 130.47472 -251.976382) (xy 130.47472 -252.020832)
			(xy 130.674872 -252.020832)
		)
		(stroke
			(width 0)
			(type solid)
		)
		(fill yes)
		(layer "In2.Cu")
		(net "M_I_CPU1_SA_CS_N<1>")
	)
	(gr_poly
		(pts
			(xy 130.674872 -250.35637) (xy 130.574796 -250.256294) (xy 130.47472 -250.35637) (xy 130.47472 -250.40082)
			(xy 130.674872 -250.40082)
		)
		(stroke
			(width 0)
			(type solid)
		)
		(fill yes)
		(layer "In2.Cu")
		(net "M_I_CPU1_ALERT_R_N")
	)
	(gr_poly
		(pts
			(xy 130.674872 -248.736358) (xy 130.574796 -248.636282) (xy 130.47472 -248.736358) (xy 130.47472 -248.780808)
			(xy 130.674872 -248.780808)
		)
		(stroke
			(width 0)
			(type solid)
		)
		(fill yes)
		(layer "In2.Cu")
		(net "M_I_CPU1_SA_CB<5>")
	)
	(gr_poly
		(pts
			(xy 130.674872 -248.332498) (xy 130.674872 -248.288048) (xy 130.47472 -248.288048) (xy 130.47472 -248.332498)
			(xy 130.574796 -248.432574)
		)
		(stroke
			(width 0)
			(type solid)
		)
		(fill yes)
		(layer "In2.Cu")
		(net "M_I_CPU1_SA_CB<6>")
	)
	(gr_poly
		(pts
			(xy 130.674872 -247.116092) (xy 130.574796 -247.01627) (xy 130.47472 -247.116092) (xy 130.47472 -247.163844)
			(xy 130.674872 -247.163844)
		)
		(stroke
			(width 0)
			(type solid)
		)
		(fill yes)
		(layer "In2.Cu")
		(net "M_I_CPU1_SA_DQS_DN<9>")
	)
	(gr_poly
		(pts
			(xy 130.674872 -246.71274) (xy 130.674872 -246.664988) (xy 130.47472 -246.664988) (xy 130.47472 -246.71274)
			(xy 130.574796 -246.812562)
		)
		(stroke
			(width 0)
			(type solid)
		)
		(fill yes)
		(layer "In2.Cu")
		(net "M_I_CPU1_SA_DQS_DN<4>")
	)
	(gr_poly
		(pts
			(xy 130.674872 -245.496334) (xy 130.574796 -245.396258) (xy 130.47472 -245.496334) (xy 130.47472 -245.540784)
			(xy 130.674872 -245.540784)
		)
		(stroke
			(width 0)
			(type solid)
		)
		(fill yes)
		(layer "In2.Cu")
		(net "M_I_CPU1_SA_CB<1>")
	)
	(gr_poly
		(pts
			(xy 130.674872 -245.092474) (xy 130.674872 -245.048024) (xy 130.47472 -245.048024) (xy 130.47472 -245.092474)
			(xy 130.574796 -245.19255)
		)
		(stroke
			(width 0)
			(type solid)
		)
		(fill yes)
		(layer "In2.Cu")
		(net "M_I_CPU1_SA_CB<2>")
	)
	(gr_poly
		(pts
			(xy 130.674872 -243.876322) (xy 130.574796 -243.776246) (xy 130.47472 -243.876322) (xy 130.47472 -243.920772)
			(xy 130.674872 -243.920772)
		)
		(stroke
			(width 0)
			(type solid)
		)
		(fill yes)
		(layer "In2.Cu")
		(net "M_I_CPU1_SA_DQ<29>")
	)
	(gr_poly
		(pts
			(xy 130.674872 -243.472462) (xy 130.674872 -243.428012) (xy 130.47472 -243.428012) (xy 130.47472 -243.472462)
			(xy 130.574796 -243.572538)
		)
		(stroke
			(width 0)
			(type solid)
		)
		(fill yes)
		(layer "In2.Cu")
		(net "M_I_CPU1_SA_DQ<30>")
	)
	(gr_poly
		(pts
			(xy 130.674872 -242.256056) (xy 130.574796 -242.156234) (xy 130.47472 -242.256056) (xy 130.47472 -242.303808)
			(xy 130.674872 -242.303808)
		)
		(stroke
			(width 0)
			(type solid)
		)
		(fill yes)
		(layer "In2.Cu")
		(net "M_I_CPU1_SA_DQS_DN<8>")
	)
	(gr_poly
		(pts
			(xy 130.674872 -241.852704) (xy 130.674872 -241.804952) (xy 130.47472 -241.804952) (xy 130.47472 -241.852704)
			(xy 130.574796 -241.952526)
		)
		(stroke
			(width 0)
			(type solid)
		)
		(fill yes)
		(layer "In2.Cu")
		(net "M_I_CPU1_SA_DQS_DN<3>")
	)
	(gr_poly
		(pts
			(xy 130.674872 -240.636298) (xy 130.574796 -240.536222) (xy 130.47472 -240.636298) (xy 130.47472 -240.680748)
			(xy 130.674872 -240.680748)
		)
		(stroke
			(width 0)
			(type solid)
		)
		(fill yes)
		(layer "In2.Cu")
		(net "M_I_CPU1_SA_DQ<25>")
	)
	(gr_poly
		(pts
			(xy 130.674872 -240.232438) (xy 130.674872 -240.187988) (xy 130.47472 -240.187988) (xy 130.47472 -240.232438)
			(xy 130.574796 -240.332514)
		)
		(stroke
			(width 0)
			(type solid)
		)
		(fill yes)
		(layer "In2.Cu")
		(net "M_I_CPU1_SA_DQ<26>")
	)
	(gr_poly
		(pts
			(xy 130.674872 -239.016286) (xy 130.574796 -238.91621) (xy 130.47472 -239.016286) (xy 130.47472 -239.060736)
			(xy 130.674872 -239.060736)
		)
		(stroke
			(width 0)
			(type solid)
		)
		(fill yes)
		(layer "In2.Cu")
		(net "M_I_CPU1_SA_DQ<21>")
	)
	(gr_poly
		(pts
			(xy 130.674872 -238.612426) (xy 130.674872 -238.567976) (xy 130.47472 -238.567976) (xy 130.47472 -238.612426)
			(xy 130.574796 -238.712502)
		)
		(stroke
			(width 0)
			(type solid)
		)
		(fill yes)
		(layer "In2.Cu")
		(net "M_I_CPU1_SA_DQ<22>")
	)
	(gr_poly
		(pts
			(xy 130.674872 -237.39602) (xy 130.574796 -237.296198) (xy 130.47472 -237.39602) (xy 130.47472 -237.443772)
			(xy 130.674872 -237.443772)
		)
		(stroke
			(width 0)
			(type solid)
		)
		(fill yes)
		(layer "In2.Cu")
		(net "M_I_CPU1_SA_DQS_DN<7>")
	)
	(gr_poly
		(pts
			(xy 130.674872 -236.992668) (xy 130.674872 -236.944916) (xy 130.47472 -236.944916) (xy 130.47472 -236.992668)
			(xy 130.574796 -237.09249)
		)
		(stroke
			(width 0)
			(type solid)
		)
		(fill yes)
		(layer "In2.Cu")
		(net "M_I_CPU1_SA_DQS_DN<2>")
	)
	(gr_poly
		(pts
			(xy 130.674872 -235.776262) (xy 130.574796 -235.676186) (xy 130.47472 -235.776262) (xy 130.47472 -235.820712)
			(xy 130.674872 -235.820712)
		)
		(stroke
			(width 0)
			(type solid)
		)
		(fill yes)
		(layer "In2.Cu")
		(net "M_I_CPU1_SA_DQ<17>")
	)
	(gr_poly
		(pts
			(xy 130.674872 -235.372402) (xy 130.674872 -235.327952) (xy 130.47472 -235.327952) (xy 130.47472 -235.372402)
			(xy 130.574796 -235.472478)
		)
		(stroke
			(width 0)
			(type solid)
		)
		(fill yes)
		(layer "In2.Cu")
		(net "M_I_CPU1_SA_DQ<18>")
	)
	(gr_poly
		(pts
			(xy 130.674872 -234.15625) (xy 130.574796 -234.056174) (xy 130.47472 -234.15625) (xy 130.47472 -234.2007)
			(xy 130.674872 -234.2007)
		)
		(stroke
			(width 0)
			(type solid)
		)
		(fill yes)
		(layer "In2.Cu")
		(net "M_I_CPU1_SA_DQ<13>")
	)
	(gr_poly
		(pts
			(xy 130.674872 -233.75239) (xy 130.674872 -233.70794) (xy 130.47472 -233.70794) (xy 130.47472 -233.75239)
			(xy 130.574796 -233.852466)
		)
		(stroke
			(width 0)
			(type solid)
		)
		(fill yes)
		(layer "In2.Cu")
		(net "M_I_CPU1_SA_DQ<14>")
	)
	(gr_poly
		(pts
			(xy 130.674872 -232.535984) (xy 130.574796 -232.436162) (xy 130.47472 -232.535984) (xy 130.47472 -232.583736)
			(xy 130.674872 -232.583736)
		)
		(stroke
			(width 0)
			(type solid)
		)
		(fill yes)
		(layer "In2.Cu")
		(net "M_I_CPU1_SA_DQS_DN<6>")
	)
	(gr_poly
		(pts
			(xy 130.674872 -232.132632) (xy 130.674872 -232.08488) (xy 130.47472 -232.08488) (xy 130.47472 -232.132632)
			(xy 130.574796 -232.232454)
		)
		(stroke
			(width 0)
			(type solid)
		)
		(fill yes)
		(layer "In2.Cu")
		(net "M_I_CPU1_SA_DQS_DN<1>")
	)
	(gr_poly
		(pts
			(xy 130.674872 -230.916226) (xy 130.574796 -230.81615) (xy 130.47472 -230.916226) (xy 130.47472 -230.960676)
			(xy 130.674872 -230.960676)
		)
		(stroke
			(width 0)
			(type solid)
		)
		(fill yes)
		(layer "In2.Cu")
		(net "M_I_CPU1_SA_DQ<9>")
	)
	(gr_poly
		(pts
			(xy 130.674872 -230.51262) (xy 130.674872 -230.46817) (xy 130.47472 -230.46817) (xy 130.47472 -230.51262)
			(xy 130.574796 -230.612696)
		)
		(stroke
			(width 0)
			(type solid)
		)
		(fill yes)
		(layer "In2.Cu")
		(net "M_I_CPU1_SA_DQ<10>")
	)
	(gr_poly
		(pts
			(xy 130.674872 -229.296214) (xy 130.574796 -229.196138) (xy 130.47472 -229.296214) (xy 130.47472 -229.340664)
			(xy 130.674872 -229.340664)
		)
		(stroke
			(width 0)
			(type solid)
		)
		(fill yes)
		(layer "In2.Cu")
		(net "M_I_CPU1_SA_DQ<5>")
	)
	(gr_poly
		(pts
			(xy 130.674872 -228.892608) (xy 130.674872 -228.848158) (xy 130.47472 -228.848158) (xy 130.47472 -228.892608)
			(xy 130.574796 -228.992684)
		)
		(stroke
			(width 0)
			(type solid)
		)
		(fill yes)
		(layer "In2.Cu")
		(net "M_I_CPU1_SA_DQ<6>")
	)
	(gr_poly
		(pts
			(xy 130.674872 -227.676202) (xy 130.574796 -227.57638) (xy 130.47472 -227.676202) (xy 130.47472 -227.723954)
			(xy 130.674872 -227.723954)
		)
		(stroke
			(width 0)
			(type solid)
		)
		(fill yes)
		(layer "In2.Cu")
		(net "M_I_CPU1_SA_DQS_DN<5>")
	)
	(gr_poly
		(pts
			(xy 130.674872 -227.27285) (xy 130.674872 -227.225098) (xy 130.47472 -227.225098) (xy 130.47472 -227.27285)
			(xy 130.574796 -227.372672)
		)
		(stroke
			(width 0)
			(type solid)
		)
		(fill yes)
		(layer "In2.Cu")
		(net "M_I_CPU1_SA_DQS_DN<0>")
	)
	(gr_poly
		(pts
			(xy 130.674872 -226.056444) (xy 130.574796 -225.956368) (xy 130.47472 -226.056444) (xy 130.47472 -226.100894)
			(xy 130.674872 -226.100894)
		)
		(stroke
			(width 0)
			(type solid)
		)
		(fill yes)
		(layer "In2.Cu")
		(net "M_I_CPU1_SA_DQ<1>")
	)
	(gr_poly
		(pts
			(xy 130.674872 -225.652584) (xy 130.674872 -225.608134) (xy 130.47472 -225.608134) (xy 130.47472 -225.652584)
			(xy 130.574796 -225.75266)
		)
		(stroke
			(width 0)
			(type solid)
		)
		(fill yes)
		(layer "In2.Cu")
		(net "M_I_CPU1_SA_DQ<2>")
	)
	(gr_poly
		(pts
			(xy 130.974846 -293.32428) (xy 130.974846 -293.27983) (xy 130.774694 -293.27983) (xy 130.774694 -293.32428)
			(xy 130.87477 -293.424356)
		)
		(stroke
			(width 0)
			(type solid)
		)
		(fill yes)
		(layer "In2.Cu")
		(net "M_I_CPU1_SB_DQ<31>")
	)
	(gr_poly
		(pts
			(xy 130.974846 -292.108128) (xy 130.87477 -292.008052) (xy 130.774694 -292.108128) (xy 130.774694 -292.152578)
			(xy 130.974846 -292.152578)
		)
		(stroke
			(width 0)
			(type solid)
		)
		(fill yes)
		(layer "In2.Cu")
		(net "M_I_CPU1_SB_DQ<28>")
	)
	(gr_poly
		(pts
			(xy 130.974846 -291.704522) (xy 130.974846 -291.65677) (xy 130.774694 -291.65677) (xy 130.774694 -291.704522)
			(xy 130.87477 -291.804344)
		)
		(stroke
			(width 0)
			(type solid)
		)
		(fill yes)
		(layer "In2.Cu")
		(net "M_I_CPU1_SB_DQS_DP<8>")
	)
	(gr_poly
		(pts
			(xy 130.974846 -290.487862) (xy 130.87477 -290.38804) (xy 130.774694 -290.487862) (xy 130.774694 -290.535614)
			(xy 130.974846 -290.535614)
		)
		(stroke
			(width 0)
			(type solid)
		)
		(fill yes)
		(layer "In2.Cu")
		(net "M_I_CPU1_SB_DQS_DP<3>")
	)
	(gr_poly
		(pts
			(xy 130.974846 -290.084256) (xy 130.974846 -290.039806) (xy 130.774694 -290.039806) (xy 130.774694 -290.084256)
			(xy 130.87477 -290.184332)
		)
		(stroke
			(width 0)
			(type solid)
		)
		(fill yes)
		(layer "In2.Cu")
		(net "M_I_CPU1_SB_DQ<27>")
	)
	(gr_poly
		(pts
			(xy 130.974846 -288.868104) (xy 130.87477 -288.768028) (xy 130.774694 -288.868104) (xy 130.774694 -288.912554)
			(xy 130.974846 -288.912554)
		)
		(stroke
			(width 0)
			(type solid)
		)
		(fill yes)
		(layer "In2.Cu")
		(net "M_I_CPU1_SB_DQ<24>")
	)
	(gr_poly
		(pts
			(xy 130.974846 -288.464498) (xy 130.974846 -288.420048) (xy 130.774694 -288.420048) (xy 130.774694 -288.464498)
			(xy 130.87477 -288.564574)
		)
		(stroke
			(width 0)
			(type solid)
		)
		(fill yes)
		(layer "In2.Cu")
		(net "M_I_CPU1_SB_DQ<23>")
	)
	(gr_poly
		(pts
			(xy 130.974846 -287.248092) (xy 130.87477 -287.148016) (xy 130.774694 -287.248092) (xy 130.774694 -287.292542)
			(xy 130.974846 -287.292542)
		)
		(stroke
			(width 0)
			(type solid)
		)
		(fill yes)
		(layer "In2.Cu")
		(net "M_I_CPU1_SB_DQ<20>")
	)
	(gr_poly
		(pts
			(xy 130.974846 -286.844486) (xy 130.974846 -286.796734) (xy 130.774694 -286.796734) (xy 130.774694 -286.844486)
			(xy 130.87477 -286.944562)
		)
		(stroke
			(width 0)
			(type solid)
		)
		(fill yes)
		(layer "In2.Cu")
		(net "M_I_CPU1_SB_DQS_DP<7>")
	)
	(gr_poly
		(pts
			(xy 130.974846 -285.62808) (xy 130.87477 -285.528258) (xy 130.774694 -285.62808) (xy 130.774694 -285.675832)
			(xy 130.974846 -285.675832)
		)
		(stroke
			(width 0)
			(type solid)
		)
		(fill yes)
		(layer "In2.Cu")
		(net "M_I_CPU1_SB_DQS_DP<2>")
	)
	(gr_poly
		(pts
			(xy 130.974846 -285.224474) (xy 130.974846 -285.180024) (xy 130.774694 -285.180024) (xy 130.774694 -285.224474)
			(xy 130.87477 -285.32455)
		)
		(stroke
			(width 0)
			(type solid)
		)
		(fill yes)
		(layer "In2.Cu")
		(net "M_I_CPU1_SB_DQ<19>")
	)
	(gr_poly
		(pts
			(xy 130.974846 -284.008322) (xy 130.87477 -283.908246) (xy 130.774694 -284.008322) (xy 130.774694 -284.052772)
			(xy 130.974846 -284.052772)
		)
		(stroke
			(width 0)
			(type solid)
		)
		(fill yes)
		(layer "In2.Cu")
		(net "M_I_CPU1_SB_DQ<16>")
	)
	(gr_poly
		(pts
			(xy 130.974846 -283.604462) (xy 130.974846 -283.560012) (xy 130.774694 -283.560012) (xy 130.774694 -283.604462)
			(xy 130.87477 -283.704538)
		)
		(stroke
			(width 0)
			(type solid)
		)
		(fill yes)
		(layer "In2.Cu")
		(net "M_I_CPU1_SB_DQ<15>")
	)
	(gr_poly
		(pts
			(xy 130.974846 -282.38831) (xy 130.87477 -282.288234) (xy 130.774694 -282.38831) (xy 130.774694 -282.43276)
			(xy 130.974846 -282.43276)
		)
		(stroke
			(width 0)
			(type solid)
		)
		(fill yes)
		(layer "In2.Cu")
		(net "M_I_CPU1_SB_DQ<12>")
	)
	(gr_poly
		(pts
			(xy 130.974846 -281.984704) (xy 130.974846 -281.936952) (xy 130.774694 -281.936952) (xy 130.774694 -281.984704)
			(xy 130.87477 -282.084526)
		)
		(stroke
			(width 0)
			(type solid)
		)
		(fill yes)
		(layer "In2.Cu")
		(net "M_I_CPU1_SB_DQS_DP<6>")
	)
	(gr_poly
		(pts
			(xy 130.974846 -280.768044) (xy 130.87477 -280.668222) (xy 130.774694 -280.768044) (xy 130.774694 -280.815796)
			(xy 130.974846 -280.815796)
		)
		(stroke
			(width 0)
			(type solid)
		)
		(fill yes)
		(layer "In2.Cu")
		(net "M_I_CPU1_SB_DQS_DP<1>")
	)
	(gr_poly
		(pts
			(xy 130.974846 -280.364438) (xy 130.974846 -280.319988) (xy 130.774694 -280.319988) (xy 130.774694 -280.364438)
			(xy 130.87477 -280.464514)
		)
		(stroke
			(width 0)
			(type solid)
		)
		(fill yes)
		(layer "In2.Cu")
		(net "M_I_CPU1_SB_DQ<11>")
	)
	(gr_poly
		(pts
			(xy 130.974846 -279.148286) (xy 130.87477 -279.04821) (xy 130.774694 -279.148286) (xy 130.774694 -279.192736)
			(xy 130.974846 -279.192736)
		)
		(stroke
			(width 0)
			(type solid)
		)
		(fill yes)
		(layer "In2.Cu")
		(net "M_I_CPU1_SB_DQ<8>")
	)
	(gr_poly
		(pts
			(xy 130.974846 -278.744426) (xy 130.974846 -278.699976) (xy 130.774694 -278.699976) (xy 130.774694 -278.744426)
			(xy 130.87477 -278.844502)
		)
		(stroke
			(width 0)
			(type solid)
		)
		(fill yes)
		(layer "In2.Cu")
		(net "M_I_CPU1_SB_DQ<7>")
	)
	(gr_poly
		(pts
			(xy 130.974846 -277.528274) (xy 130.87477 -277.428198) (xy 130.774694 -277.528274) (xy 130.774694 -277.572724)
			(xy 130.974846 -277.572724)
		)
		(stroke
			(width 0)
			(type solid)
		)
		(fill yes)
		(layer "In2.Cu")
		(net "M_I_CPU1_SB_DQ<4>")
	)
	(gr_poly
		(pts
			(xy 130.974846 -277.124668) (xy 130.974846 -277.076916) (xy 130.774694 -277.076916) (xy 130.774694 -277.124668)
			(xy 130.87477 -277.22449)
		)
		(stroke
			(width 0)
			(type solid)
		)
		(fill yes)
		(layer "In2.Cu")
		(net "M_I_CPU1_SB_DQS_DP<5>")
	)
	(gr_poly
		(pts
			(xy 130.974846 -275.908008) (xy 130.87477 -275.808186) (xy 130.774694 -275.908008) (xy 130.774694 -275.95576)
			(xy 130.974846 -275.95576)
		)
		(stroke
			(width 0)
			(type solid)
		)
		(fill yes)
		(layer "In2.Cu")
		(net "M_I_CPU1_SB_DQS_DP<0>")
	)
	(gr_poly
		(pts
			(xy 130.974846 -275.504402) (xy 130.974846 -275.459952) (xy 130.774694 -275.459952) (xy 130.774694 -275.504402)
			(xy 130.87477 -275.604478)
		)
		(stroke
			(width 0)
			(type solid)
		)
		(fill yes)
		(layer "In2.Cu")
		(net "M_I_CPU1_SB_DQ<3>")
	)
	(gr_poly
		(pts
			(xy 130.974846 -274.28825) (xy 130.87477 -274.188174) (xy 130.774694 -274.28825) (xy 130.774694 -274.3327)
			(xy 130.974846 -274.3327)
		)
		(stroke
			(width 0)
			(type solid)
		)
		(fill yes)
		(layer "In2.Cu")
		(net "M_I_CPU1_SB_DQ<0>")
	)
	(gr_poly
		(pts
			(xy 130.974846 -273.88439) (xy 130.974846 -273.83994) (xy 130.774694 -273.83994) (xy 130.774694 -273.88439)
			(xy 130.87477 -273.984466)
		)
		(stroke
			(width 0)
			(type solid)
		)
		(fill yes)
		(layer "In2.Cu")
		(net "M_I_CPU1_SB_CB<3>")
	)
	(gr_poly
		(pts
			(xy 130.974846 -272.668238) (xy 130.87477 -272.568162) (xy 130.774694 -272.668238) (xy 130.774694 -272.712688)
			(xy 130.974846 -272.712688)
		)
		(stroke
			(width 0)
			(type solid)
		)
		(fill yes)
		(layer "In2.Cu")
		(net "M_I_CPU1_SB_CB<0>")
	)
	(gr_poly
		(pts
			(xy 130.974846 -272.264632) (xy 130.974846 -272.21688) (xy 130.774694 -272.21688) (xy 130.774694 -272.264632)
			(xy 130.87477 -272.364454)
		)
		(stroke
			(width 0)
			(type solid)
		)
		(fill yes)
		(layer "In2.Cu")
		(net "M_I_CPU1_SB_DQS_DP<4>")
	)
	(gr_poly
		(pts
			(xy 130.974846 -271.047972) (xy 130.87477 -270.94815) (xy 130.774694 -271.047972) (xy 130.774694 -271.095724)
			(xy 130.974846 -271.095724)
		)
		(stroke
			(width 0)
			(type solid)
		)
		(fill yes)
		(layer "In2.Cu")
		(net "M_I_CPU1_SB_DQS_DP<9>")
	)
	(gr_poly
		(pts
			(xy 130.974846 -270.644366) (xy 130.974846 -270.599916) (xy 130.774694 -270.599916) (xy 130.774694 -270.644366)
			(xy 130.87477 -270.744442)
		)
		(stroke
			(width 0)
			(type solid)
		)
		(fill yes)
		(layer "In2.Cu")
		(net "M_I_CPU1_SB_CB<7>")
	)
	(gr_poly
		(pts
			(xy 130.974846 -269.428214) (xy 130.87477 -269.328138) (xy 130.774694 -269.428214) (xy 130.774694 -269.472664)
			(xy 130.974846 -269.472664)
		)
		(stroke
			(width 0)
			(type solid)
		)
		(fill yes)
		(layer "In2.Cu")
		(net "M_I_CPU1_SB_CB<4>")
	)
	(gr_poly
		(pts
			(xy 130.974846 -267.404342) (xy 130.974846 -267.359892) (xy 130.774694 -267.359892) (xy 130.774694 -267.404342)
			(xy 130.87477 -267.504418)
		)
		(stroke
			(width 0)
			(type solid)
		)
		(fill yes)
		(layer "In2.Cu")
		(net "M_I_CPU1_SB_RSP<0>")
	)
	(gr_poly
		(pts
			(xy 130.974846 -265.78433) (xy 130.974846 -265.73988) (xy 130.774694 -265.73988) (xy 130.774694 -265.78433)
			(xy 130.87477 -265.884406)
		)
		(stroke
			(width 0)
			(type solid)
		)
		(fill yes)
		(layer "In2.Cu")
		(net "M_I_CPU1_SB_CS_N<0>")
	)
	(gr_poly
		(pts
			(xy 130.974846 -264.568178) (xy 130.87477 -264.468102) (xy 130.774694 -264.568178) (xy 130.774694 -264.612628)
			(xy 130.974846 -264.612628)
		)
		(stroke
			(width 0)
			(type solid)
		)
		(fill yes)
		(layer "In2.Cu")
		(net "M_I_CPU1_SB_CA<6>")
	)
	(gr_poly
		(pts
			(xy 130.974846 -264.164318) (xy 130.974846 -264.119868) (xy 130.774694 -264.119868) (xy 130.774694 -264.164318)
			(xy 130.87477 -264.264394)
		)
		(stroke
			(width 0)
			(type solid)
		)
		(fill yes)
		(layer "In2.Cu")
		(net "M_I_CPU1_SB_CA<5>")
	)
	(gr_poly
		(pts
			(xy 130.974846 -262.948166) (xy 130.87477 -262.84809) (xy 130.774694 -262.948166) (xy 130.774694 -262.992616)
			(xy 130.974846 -262.992616)
		)
		(stroke
			(width 0)
			(type solid)
		)
		(fill yes)
		(layer "In2.Cu")
		(net "M_I_CPU1_SB_CA<2>")
	)
	(gr_poly
		(pts
			(xy 130.974846 -262.544306) (xy 130.974846 -262.499856) (xy 130.774694 -262.499856) (xy 130.774694 -262.544306)
			(xy 130.87477 -262.644382)
		)
		(stroke
			(width 0)
			(type solid)
		)
		(fill yes)
		(layer "In2.Cu")
		(net "M_I_CPU1_SB_CA<1>")
	)
	(gr_poly
		(pts
			(xy 131.144772 -256.026158) (xy 131.044696 -255.926336) (xy 130.94462 -256.026158) (xy 130.94462 -256.07391)
			(xy 131.144772 -256.07391)
		)
		(stroke
			(width 0)
			(type solid)
		)
		(fill yes)
		(layer "In2.Cu")
		(net "M_I_CPU1_CLK_DP<0>")
	)
	(gr_poly
		(pts
			(xy 131.144772 -255.622552) (xy 131.144772 -255.578102) (xy 130.94462 -255.578102) (xy 130.94462 -255.622552)
			(xy 131.044696 -255.722628)
		)
		(stroke
			(width 0)
			(type solid)
		)
		(fill yes)
		(layer "In2.Cu")
		(net "M_I_CPU1_SA_PAR")
	)
	(gr_poly
		(pts
			(xy 131.144772 -254.4064) (xy 131.044696 -254.306324) (xy 130.94462 -254.4064) (xy 130.94462 -254.45085)
			(xy 131.144772 -254.45085)
		)
		(stroke
			(width 0)
			(type solid)
		)
		(fill yes)
		(layer "In2.Cu")
		(net "M_I_CPU1_SA_CA<4>")
	)
	(gr_poly
		(pts
			(xy 131.144772 -254.00254) (xy 131.144772 -253.95809) (xy 130.94462 -253.95809) (xy 130.94462 -254.00254)
			(xy 131.044696 -254.102616)
		)
		(stroke
			(width 0)
			(type solid)
		)
		(fill yes)
		(layer "In2.Cu")
		(net "M_I_CPU1_SA_CA<3>")
	)
	(gr_poly
		(pts
			(xy 131.144772 -252.786388) (xy 131.044696 -252.686312) (xy 130.94462 -252.786388) (xy 130.94462 -252.830838)
			(xy 131.144772 -252.830838)
		)
		(stroke
			(width 0)
			(type solid)
		)
		(fill yes)
		(layer "In2.Cu")
		(net "M_I_CPU1_SA_CA<0>")
	)
	(gr_poly
		(pts
			(xy 131.144772 -251.166376) (xy 131.044696 -251.0663) (xy 130.94462 -251.166376) (xy 130.94462 -251.210826)
			(xy 131.144772 -251.210826)
		)
		(stroke
			(width 0)
			(type solid)
		)
		(fill yes)
		(layer "In2.Cu")
		(net "M_I_CPU1_SA_CS_N<0>")
	)
	(gr_poly
		(pts
			(xy 131.144772 -250.762516) (xy 131.144772 -250.718066) (xy 130.94462 -250.718066) (xy 130.94462 -250.762516)
			(xy 131.044696 -250.862592)
		)
		(stroke
			(width 0)
			(type solid)
		)
		(fill yes)
		(layer "In2.Cu")
		(net "M_I_CPU1_RESET_N")
	)
	(gr_poly
		(pts
			(xy 131.144772 -249.142504) (xy 131.144772 -249.098054) (xy 130.94462 -249.098054) (xy 130.94462 -249.142504)
			(xy 131.044696 -249.24258)
		)
		(stroke
			(width 0)
			(type solid)
		)
		(fill yes)
		(layer "In2.Cu")
		(net "M_I_CPU1_SA_CB<7>")
	)
	(gr_poly
		(pts
			(xy 131.144772 -247.926352) (xy 131.044696 -247.826276) (xy 130.94462 -247.926352) (xy 130.94462 -247.970802)
			(xy 131.144772 -247.970802)
		)
		(stroke
			(width 0)
			(type solid)
		)
		(fill yes)
		(layer "In2.Cu")
		(net "M_I_CPU1_SA_CB<4>")
	)
	(gr_poly
		(pts
			(xy 131.144772 -247.522746) (xy 131.144772 -247.474994) (xy 130.94462 -247.474994) (xy 130.94462 -247.522746)
			(xy 131.044696 -247.622568)
		)
		(stroke
			(width 0)
			(type solid)
		)
		(fill yes)
		(layer "In2.Cu")
		(net "M_I_CPU1_SA_DQS_DP<9>")
	)
	(gr_poly
		(pts
			(xy 131.144772 -246.306086) (xy 131.044696 -246.206264) (xy 130.94462 -246.306086) (xy 130.94462 -246.353838)
			(xy 131.144772 -246.353838)
		)
		(stroke
			(width 0)
			(type solid)
		)
		(fill yes)
		(layer "In2.Cu")
		(net "M_I_CPU1_SA_DQS_DP<4>")
	)
	(gr_poly
		(pts
			(xy 131.144772 -245.90248) (xy 131.144772 -245.85803) (xy 130.94462 -245.85803) (xy 130.94462 -245.90248)
			(xy 131.044696 -246.002556)
		)
		(stroke
			(width 0)
			(type solid)
		)
		(fill yes)
		(layer "In2.Cu")
		(net "M_I_CPU1_SA_CB<3>")
	)
	(gr_poly
		(pts
			(xy 131.144772 -244.686328) (xy 131.044696 -244.586252) (xy 130.94462 -244.686328) (xy 130.94462 -244.730778)
			(xy 131.144772 -244.730778)
		)
		(stroke
			(width 0)
			(type solid)
		)
		(fill yes)
		(layer "In2.Cu")
		(net "M_I_CPU1_SA_CB<0>")
	)
	(gr_poly
		(pts
			(xy 131.144772 -244.282468) (xy 131.144772 -244.238018) (xy 130.94462 -244.238018) (xy 130.94462 -244.282468)
			(xy 131.044696 -244.382544)
		)
		(stroke
			(width 0)
			(type solid)
		)
		(fill yes)
		(layer "In2.Cu")
		(net "M_I_CPU1_SA_DQ<31>")
	)
	(gr_poly
		(pts
			(xy 131.144772 -243.066316) (xy 131.044696 -242.96624) (xy 130.94462 -243.066316) (xy 130.94462 -243.110766)
			(xy 131.144772 -243.110766)
		)
		(stroke
			(width 0)
			(type solid)
		)
		(fill yes)
		(layer "In2.Cu")
		(net "M_I_CPU1_SA_DQ<28>")
	)
	(gr_poly
		(pts
			(xy 131.144772 -242.66271) (xy 131.144772 -242.614958) (xy 130.94462 -242.614958) (xy 130.94462 -242.66271)
			(xy 131.044696 -242.762532)
		)
		(stroke
			(width 0)
			(type solid)
		)
		(fill yes)
		(layer "In2.Cu")
		(net "M_I_CPU1_SA_DQS_DP<8>")
	)
	(gr_poly
		(pts
			(xy 131.144772 -241.44605) (xy 131.044696 -241.346228) (xy 130.94462 -241.44605) (xy 130.94462 -241.493802)
			(xy 131.144772 -241.493802)
		)
		(stroke
			(width 0)
			(type solid)
		)
		(fill yes)
		(layer "In2.Cu")
		(net "M_I_CPU1_SA_DQS_DP<3>")
	)
	(gr_poly
		(pts
			(xy 131.144772 -241.042444) (xy 131.144772 -240.997994) (xy 130.94462 -240.997994) (xy 130.94462 -241.042444)
			(xy 131.044696 -241.14252)
		)
		(stroke
			(width 0)
			(type solid)
		)
		(fill yes)
		(layer "In2.Cu")
		(net "M_I_CPU1_SA_DQ<27>")
	)
	(gr_poly
		(pts
			(xy 131.144772 -239.826292) (xy 131.044696 -239.726216) (xy 130.94462 -239.826292) (xy 130.94462 -239.870742)
			(xy 131.144772 -239.870742)
		)
		(stroke
			(width 0)
			(type solid)
		)
		(fill yes)
		(layer "In2.Cu")
		(net "M_I_CPU1_SA_DQ<24>")
	)
	(gr_poly
		(pts
			(xy 131.144772 -239.422432) (xy 131.144772 -239.377982) (xy 130.94462 -239.377982) (xy 130.94462 -239.422432)
			(xy 131.044696 -239.522508)
		)
		(stroke
			(width 0)
			(type solid)
		)
		(fill yes)
		(layer "In2.Cu")
		(net "M_I_CPU1_SA_DQ<23>")
	)
	(gr_poly
		(pts
			(xy 131.144772 -238.20628) (xy 131.044696 -238.106204) (xy 130.94462 -238.20628) (xy 130.94462 -238.25073)
			(xy 131.144772 -238.25073)
		)
		(stroke
			(width 0)
			(type solid)
		)
		(fill yes)
		(layer "In2.Cu")
		(net "M_I_CPU1_SA_DQ<20>")
	)
	(gr_poly
		(pts
			(xy 131.144772 -237.802674) (xy 131.144772 -237.754922) (xy 130.94462 -237.754922) (xy 130.94462 -237.802674)
			(xy 131.044696 -237.902496)
		)
		(stroke
			(width 0)
			(type solid)
		)
		(fill yes)
		(layer "In2.Cu")
		(net "M_I_CPU1_SA_DQS_DP<7>")
	)
	(gr_poly
		(pts
			(xy 131.144772 -236.586014) (xy 131.044696 -236.486192) (xy 130.94462 -236.586014) (xy 130.94462 -236.633766)
			(xy 131.144772 -236.633766)
		)
		(stroke
			(width 0)
			(type solid)
		)
		(fill yes)
		(layer "In2.Cu")
		(net "M_I_CPU1_SA_DQS_DP<2>")
	)
	(gr_poly
		(pts
			(xy 131.144772 -236.182408) (xy 131.144772 -236.137958) (xy 130.94462 -236.137958) (xy 130.94462 -236.182408)
			(xy 131.044696 -236.282484)
		)
		(stroke
			(width 0)
			(type solid)
		)
		(fill yes)
		(layer "In2.Cu")
		(net "M_I_CPU1_SA_DQ<19>")
	)
	(gr_poly
		(pts
			(xy 131.144772 -234.966256) (xy 131.044696 -234.86618) (xy 130.94462 -234.966256) (xy 130.94462 -235.010706)
			(xy 131.144772 -235.010706)
		)
		(stroke
			(width 0)
			(type solid)
		)
		(fill yes)
		(layer "In2.Cu")
		(net "M_I_CPU1_SA_DQ<16>")
	)
	(gr_poly
		(pts
			(xy 131.144772 -234.562396) (xy 131.144772 -234.517946) (xy 130.94462 -234.517946) (xy 130.94462 -234.562396)
			(xy 131.044696 -234.662472)
		)
		(stroke
			(width 0)
			(type solid)
		)
		(fill yes)
		(layer "In2.Cu")
		(net "M_I_CPU1_SA_DQ<15>")
	)
	(gr_poly
		(pts
			(xy 131.144772 -233.346244) (xy 131.044696 -233.246168) (xy 130.94462 -233.346244) (xy 130.94462 -233.390694)
			(xy 131.144772 -233.390694)
		)
		(stroke
			(width 0)
			(type solid)
		)
		(fill yes)
		(layer "In2.Cu")
		(net "M_I_CPU1_SA_DQ<12>")
	)
	(gr_poly
		(pts
			(xy 131.144772 -232.942638) (xy 131.144772 -232.894886) (xy 130.94462 -232.894886) (xy 130.94462 -232.942638)
			(xy 131.044696 -233.04246)
		)
		(stroke
			(width 0)
			(type solid)
		)
		(fill yes)
		(layer "In2.Cu")
		(net "M_I_CPU1_SA_DQS_DP<6>")
	)
	(gr_poly
		(pts
			(xy 131.144772 -231.725978) (xy 131.044696 -231.626156) (xy 130.94462 -231.725978) (xy 130.94462 -231.77373)
			(xy 131.144772 -231.77373)
		)
		(stroke
			(width 0)
			(type solid)
		)
		(fill yes)
		(layer "In2.Cu")
		(net "M_I_CPU1_SA_DQS_DP<1>")
	)
	(gr_poly
		(pts
			(xy 131.144772 -231.322626) (xy 131.144772 -231.278176) (xy 130.94462 -231.278176) (xy 130.94462 -231.322626)
			(xy 131.044696 -231.422702)
		)
		(stroke
			(width 0)
			(type solid)
		)
		(fill yes)
		(layer "In2.Cu")
		(net "M_I_CPU1_SA_DQ<11>")
	)
	(gr_poly
		(pts
			(xy 131.144772 -230.10622) (xy 131.044696 -230.006144) (xy 130.94462 -230.10622) (xy 130.94462 -230.15067)
			(xy 131.144772 -230.15067)
		)
		(stroke
			(width 0)
			(type solid)
		)
		(fill yes)
		(layer "In2.Cu")
		(net "M_I_CPU1_SA_DQ<8>")
	)
	(gr_poly
		(pts
			(xy 131.144772 -229.702614) (xy 131.144772 -229.658164) (xy 130.94462 -229.658164) (xy 130.94462 -229.702614)
			(xy 131.044696 -229.80269)
		)
		(stroke
			(width 0)
			(type solid)
		)
		(fill yes)
		(layer "In2.Cu")
		(net "M_I_CPU1_SA_DQ<7>")
	)
	(gr_poly
		(pts
			(xy 131.144772 -228.486462) (xy 131.044696 -228.386386) (xy 130.94462 -228.486462) (xy 130.94462 -228.530912)
			(xy 131.144772 -228.530912)
		)
		(stroke
			(width 0)
			(type solid)
		)
		(fill yes)
		(layer "In2.Cu")
		(net "M_I_CPU1_SA_DQ<4>")
	)
	(gr_poly
		(pts
			(xy 131.144772 -228.082856) (xy 131.144772 -228.035104) (xy 130.94462 -228.035104) (xy 130.94462 -228.082856)
			(xy 131.044696 -228.182678)
		)
		(stroke
			(width 0)
			(type solid)
		)
		(fill yes)
		(layer "In2.Cu")
		(net "M_I_CPU1_SA_DQS_DP<5>")
	)
	(gr_poly
		(pts
			(xy 131.144772 -226.866196) (xy 131.044696 -226.766374) (xy 130.94462 -226.866196) (xy 130.94462 -226.913948)
			(xy 131.144772 -226.913948)
		)
		(stroke
			(width 0)
			(type solid)
		)
		(fill yes)
		(layer "In2.Cu")
		(net "M_I_CPU1_SA_DQS_DP<0>")
	)
	(gr_poly
		(pts
			(xy 131.144772 -226.46259) (xy 131.144772 -226.41814) (xy 130.94462 -226.41814) (xy 130.94462 -226.46259)
			(xy 131.044696 -226.562666)
		)
		(stroke
			(width 0)
			(type solid)
		)
		(fill yes)
		(layer "In2.Cu")
		(net "M_I_CPU1_SA_DQ<3>")
	)
	(gr_poly
		(pts
			(xy 131.144772 -225.246438) (xy 131.044696 -225.146362) (xy 130.94462 -225.246438) (xy 130.94462 -225.290888)
			(xy 131.144772 -225.290888)
		)
		(stroke
			(width 0)
			(type solid)
		)
		(fill yes)
		(layer "In2.Cu")
		(net "M_I_CPU1_SA_DQ<0>")
	)
	(gr_poly
		(pts
			(xy 131.444746 -292.918134) (xy 131.34467 -292.818058) (xy 131.244594 -292.918134) (xy 131.244594 -292.962584)
			(xy 131.444746 -292.962584)
		)
		(stroke
			(width 0)
			(type solid)
		)
		(fill yes)
		(layer "In2.Cu")
		(net "M_I_CPU1_SB_DQ<29>")
	)
	(gr_poly
		(pts
			(xy 131.444746 -292.514274) (xy 131.444746 -292.469824) (xy 131.244594 -292.469824) (xy 131.244594 -292.514274)
			(xy 131.34467 -292.61435)
		)
		(stroke
			(width 0)
			(type solid)
		)
		(fill yes)
		(layer "In2.Cu")
		(net "M_I_CPU1_SB_DQ<30>")
	)
	(gr_poly
		(pts
			(xy 131.444746 -291.297868) (xy 131.34467 -291.198046) (xy 131.244594 -291.297868) (xy 131.244594 -291.34562)
			(xy 131.444746 -291.34562)
		)
		(stroke
			(width 0)
			(type solid)
		)
		(fill yes)
		(layer "In2.Cu")
		(net "M_I_CPU1_SB_DQS_DN<8>")
	)
	(gr_poly
		(pts
			(xy 131.444746 -290.894516) (xy 131.444746 -290.846764) (xy 131.244594 -290.846764) (xy 131.244594 -290.894516)
			(xy 131.34467 -290.994338)
		)
		(stroke
			(width 0)
			(type solid)
		)
		(fill yes)
		(layer "In2.Cu")
		(net "M_I_CPU1_SB_DQS_DN<3>")
	)
	(gr_poly
		(pts
			(xy 131.444746 -289.67811) (xy 131.34467 -289.578034) (xy 131.244594 -289.67811) (xy 131.244594 -289.72256)
			(xy 131.444746 -289.72256)
		)
		(stroke
			(width 0)
			(type solid)
		)
		(fill yes)
		(layer "In2.Cu")
		(net "M_I_CPU1_SB_DQ<25>")
	)
	(gr_poly
		(pts
			(xy 131.444746 -289.27425) (xy 131.444746 -289.2298) (xy 131.244594 -289.2298) (xy 131.244594 -289.27425)
			(xy 131.34467 -289.374326)
		)
		(stroke
			(width 0)
			(type solid)
		)
		(fill yes)
		(layer "In2.Cu")
		(net "M_I_CPU1_SB_DQ<26>")
	)
	(gr_poly
		(pts
			(xy 131.444746 -288.058098) (xy 131.34467 -287.958022) (xy 131.244594 -288.058098) (xy 131.244594 -288.102548)
			(xy 131.444746 -288.102548)
		)
		(stroke
			(width 0)
			(type solid)
		)
		(fill yes)
		(layer "In2.Cu")
		(net "M_I_CPU1_SB_DQ<21>")
	)
	(gr_poly
		(pts
			(xy 131.444746 -287.654492) (xy 131.444746 -287.610042) (xy 131.244594 -287.610042) (xy 131.244594 -287.654492)
			(xy 131.34467 -287.754568)
		)
		(stroke
			(width 0)
			(type solid)
		)
		(fill yes)
		(layer "In2.Cu")
		(net "M_I_CPU1_SB_DQ<22>")
	)
	(gr_poly
		(pts
			(xy 131.444746 -286.438086) (xy 131.34467 -286.33801) (xy 131.244594 -286.438086) (xy 131.244594 -286.485838)
			(xy 131.444746 -286.485838)
		)
		(stroke
			(width 0)
			(type solid)
		)
		(fill yes)
		(layer "In2.Cu")
		(net "M_I_CPU1_SB_DQS_DN<7>")
	)
	(gr_poly
		(pts
			(xy 131.444746 -286.034734) (xy 131.444746 -285.986982) (xy 131.244594 -285.986982) (xy 131.244594 -286.034734)
			(xy 131.34467 -286.134556)
		)
		(stroke
			(width 0)
			(type solid)
		)
		(fill yes)
		(layer "In2.Cu")
		(net "M_I_CPU1_SB_DQS_DN<2>")
	)
	(gr_poly
		(pts
			(xy 131.444746 -284.818328) (xy 131.34467 -284.718252) (xy 131.244594 -284.818328) (xy 131.244594 -284.862778)
			(xy 131.444746 -284.862778)
		)
		(stroke
			(width 0)
			(type solid)
		)
		(fill yes)
		(layer "In2.Cu")
		(net "M_I_CPU1_SB_DQ<17>")
	)
	(gr_poly
		(pts
			(xy 131.444746 -284.414468) (xy 131.444746 -284.370018) (xy 131.244594 -284.370018) (xy 131.244594 -284.414468)
			(xy 131.34467 -284.514544)
		)
		(stroke
			(width 0)
			(type solid)
		)
		(fill yes)
		(layer "In2.Cu")
		(net "M_I_CPU1_SB_DQ<18>")
	)
	(gr_poly
		(pts
			(xy 131.444746 -283.198316) (xy 131.34467 -283.09824) (xy 131.244594 -283.198316) (xy 131.244594 -283.242766)
			(xy 131.444746 -283.242766)
		)
		(stroke
			(width 0)
			(type solid)
		)
		(fill yes)
		(layer "In2.Cu")
		(net "M_I_CPU1_SB_DQ<13>")
	)
	(gr_poly
		(pts
			(xy 131.444746 -282.794456) (xy 131.444746 -282.750006) (xy 131.244594 -282.750006) (xy 131.244594 -282.794456)
			(xy 131.34467 -282.894532)
		)
		(stroke
			(width 0)
			(type solid)
		)
		(fill yes)
		(layer "In2.Cu")
		(net "M_I_CPU1_SB_DQ<14>")
	)
	(gr_poly
		(pts
			(xy 131.444746 -281.57805) (xy 131.34467 -281.478228) (xy 131.244594 -281.57805) (xy 131.244594 -281.625802)
			(xy 131.444746 -281.625802)
		)
		(stroke
			(width 0)
			(type solid)
		)
		(fill yes)
		(layer "In2.Cu")
		(net "M_I_CPU1_SB_DQS_DN<6>")
	)
	(gr_poly
		(pts
			(xy 131.444746 -281.174698) (xy 131.444746 -281.126946) (xy 131.244594 -281.126946) (xy 131.244594 -281.174698)
			(xy 131.34467 -281.27452)
		)
		(stroke
			(width 0)
			(type solid)
		)
		(fill yes)
		(layer "In2.Cu")
		(net "M_I_CPU1_SB_DQS_DN<1>")
	)
	(gr_poly
		(pts
			(xy 131.444746 -279.958292) (xy 131.34467 -279.858216) (xy 131.244594 -279.958292) (xy 131.244594 -280.002742)
			(xy 131.444746 -280.002742)
		)
		(stroke
			(width 0)
			(type solid)
		)
		(fill yes)
		(layer "In2.Cu")
		(net "M_I_CPU1_SB_DQ<9>")
	)
	(gr_poly
		(pts
			(xy 131.444746 -279.554432) (xy 131.444746 -279.509982) (xy 131.244594 -279.509982) (xy 131.244594 -279.554432)
			(xy 131.34467 -279.654508)
		)
		(stroke
			(width 0)
			(type solid)
		)
		(fill yes)
		(layer "In2.Cu")
		(net "M_I_CPU1_SB_DQ<10>")
	)
	(gr_poly
		(pts
			(xy 131.444746 -278.33828) (xy 131.34467 -278.238204) (xy 131.244594 -278.33828) (xy 131.244594 -278.38273)
			(xy 131.444746 -278.38273)
		)
		(stroke
			(width 0)
			(type solid)
		)
		(fill yes)
		(layer "In2.Cu")
		(net "M_I_CPU1_SB_DQ<5>")
	)
	(gr_poly
		(pts
			(xy 131.444746 -277.93442) (xy 131.444746 -277.88997) (xy 131.244594 -277.88997) (xy 131.244594 -277.93442)
			(xy 131.34467 -278.034496)
		)
		(stroke
			(width 0)
			(type solid)
		)
		(fill yes)
		(layer "In2.Cu")
		(net "M_I_CPU1_SB_DQ<6>")
	)
	(gr_poly
		(pts
			(xy 131.444746 -276.718014) (xy 131.34467 -276.618192) (xy 131.244594 -276.718014) (xy 131.244594 -276.765766)
			(xy 131.444746 -276.765766)
		)
		(stroke
			(width 0)
			(type solid)
		)
		(fill yes)
		(layer "In2.Cu")
		(net "M_I_CPU1_SB_DQS_DN<5>")
	)
	(gr_poly
		(pts
			(xy 131.444746 -276.314662) (xy 131.444746 -276.26691) (xy 131.244594 -276.26691) (xy 131.244594 -276.314662)
			(xy 131.34467 -276.414484)
		)
		(stroke
			(width 0)
			(type solid)
		)
		(fill yes)
		(layer "In2.Cu")
		(net "M_I_CPU1_SB_DQS_DN<0>")
	)
	(gr_poly
		(pts
			(xy 131.444746 -275.098256) (xy 131.34467 -274.99818) (xy 131.244594 -275.098256) (xy 131.244594 -275.142706)
			(xy 131.444746 -275.142706)
		)
		(stroke
			(width 0)
			(type solid)
		)
		(fill yes)
		(layer "In2.Cu")
		(net "M_I_CPU1_SB_DQ<1>")
	)
	(gr_poly
		(pts
			(xy 131.444746 -274.694396) (xy 131.444746 -274.649946) (xy 131.244594 -274.649946) (xy 131.244594 -274.694396)
			(xy 131.34467 -274.794472)
		)
		(stroke
			(width 0)
			(type solid)
		)
		(fill yes)
		(layer "In2.Cu")
		(net "M_I_CPU1_SB_DQ<2>")
	)
	(gr_poly
		(pts
			(xy 131.444746 -273.478244) (xy 131.34467 -273.378168) (xy 131.244594 -273.478244) (xy 131.244594 -273.522694)
			(xy 131.444746 -273.522694)
		)
		(stroke
			(width 0)
			(type solid)
		)
		(fill yes)
		(layer "In2.Cu")
		(net "M_I_CPU1_SB_CB<1>")
	)
	(gr_poly
		(pts
			(xy 131.444746 -273.074384) (xy 131.444746 -273.029934) (xy 131.244594 -273.029934) (xy 131.244594 -273.074384)
			(xy 131.34467 -273.17446)
		)
		(stroke
			(width 0)
			(type solid)
		)
		(fill yes)
		(layer "In2.Cu")
		(net "M_I_CPU1_SB_CB<2>")
	)
	(gr_poly
		(pts
			(xy 131.444746 -271.857978) (xy 131.34467 -271.758156) (xy 131.244594 -271.857978) (xy 131.244594 -271.90573)
			(xy 131.444746 -271.90573)
		)
		(stroke
			(width 0)
			(type solid)
		)
		(fill yes)
		(layer "In2.Cu")
		(net "M_I_CPU1_SB_DQS_DN<4>")
	)
	(gr_poly
		(pts
			(xy 131.444746 -271.454626) (xy 131.444746 -271.406874) (xy 131.244594 -271.406874) (xy 131.244594 -271.454626)
			(xy 131.34467 -271.554448)
		)
		(stroke
			(width 0)
			(type solid)
		)
		(fill yes)
		(layer "In2.Cu")
		(net "M_I_CPU1_SB_DQS_DN<9>")
	)
	(gr_poly
		(pts
			(xy 131.444746 -270.23822) (xy 131.34467 -270.138144) (xy 131.244594 -270.23822) (xy 131.244594 -270.28267)
			(xy 131.444746 -270.28267)
		)
		(stroke
			(width 0)
			(type solid)
		)
		(fill yes)
		(layer "In2.Cu")
		(net "M_I_CPU1_SB_CB<5>")
	)
	(gr_poly
		(pts
			(xy 131.444746 -269.83436) (xy 131.444746 -269.78991) (xy 131.244594 -269.78991) (xy 131.244594 -269.83436)
			(xy 131.34467 -269.934436)
		)
		(stroke
			(width 0)
			(type solid)
		)
		(fill yes)
		(layer "In2.Cu")
		(net "M_I_CPU1_SB_CB<6>")
	)
	(gr_poly
		(pts
			(xy 131.444746 -266.998196) (xy 131.34467 -266.89812) (xy 131.244594 -266.998196) (xy 131.244594 -267.042646)
			(xy 131.444746 -267.042646)
		)
		(stroke
			(width 0)
			(type solid)
		)
		(fill yes)
		(layer "In2.Cu")
		(net "M_I_CPU1_SA_RSP<0>")
	)
	(gr_poly
		(pts
			(xy 131.444746 -266.594336) (xy 131.444746 -266.549886) (xy 131.244594 -266.549886) (xy 131.244594 -266.594336)
			(xy 131.34467 -266.694412)
		)
		(stroke
			(width 0)
			(type solid)
		)
		(fill yes)
		(layer "In2.Cu")
		(net "M_I_CPU1_SB_CS_N<1>")
	)
	(gr_poly
		(pts
			(xy 131.444746 -265.378184) (xy 131.34467 -265.278108) (xy 131.244594 -265.378184) (xy 131.244594 -265.422634)
			(xy 131.444746 -265.422634)
		)
		(stroke
			(width 0)
			(type solid)
		)
		(fill yes)
		(layer "In2.Cu")
		(net "M_I_CPU1_SB_PAR")
	)
	(gr_poly
		(pts
			(xy 131.444746 -263.758172) (xy 131.34467 -263.658096) (xy 131.244594 -263.758172) (xy 131.244594 -263.802622)
			(xy 131.444746 -263.802622)
		)
		(stroke
			(width 0)
			(type solid)
		)
		(fill yes)
		(layer "In2.Cu")
		(net "M_I_CPU1_SB_CA<4>")
	)
	(gr_poly
		(pts
			(xy 131.444746 -263.354312) (xy 131.444746 -263.309862) (xy 131.244594 -263.309862) (xy 131.244594 -263.354312)
			(xy 131.34467 -263.454388)
		)
		(stroke
			(width 0)
			(type solid)
		)
		(fill yes)
		(layer "In2.Cu")
		(net "M_I_CPU1_SB_CA<3>")
	)
	(gr_poly
		(pts
			(xy 131.444746 -262.13816) (xy 131.34467 -262.038084) (xy 131.244594 -262.13816) (xy 131.244594 -262.18261)
			(xy 131.444746 -262.18261)
		)
		(stroke
			(width 0)
			(type solid)
		)
		(fill yes)
		(layer "In2.Cu")
		(net "M_I_CPU1_SB_CA<0>")
	)
	(gr_poly
		(pts
			(xy 131.614926 -256.432812) (xy 131.614926 -256.38506) (xy 131.414774 -256.38506) (xy 131.414774 -256.432812)
			(xy 131.51485 -256.532634)
		)
		(stroke
			(width 0)
			(type solid)
		)
		(fill yes)
		(layer "In2.Cu")
		(net "M_I_CPU1_CLK_DN<0>")
	)
	(gr_poly
		(pts
			(xy 131.614926 -255.216406) (xy 131.51485 -255.11633) (xy 131.414774 -255.216406) (xy 131.414774 -255.260856)
			(xy 131.614926 -255.260856)
		)
		(stroke
			(width 0)
			(type solid)
		)
		(fill yes)
		(layer "In2.Cu")
		(net "M_I_CPU1_SA_CA<6>")
	)
	(gr_poly
		(pts
			(xy 131.614926 -254.812546) (xy 131.614926 -254.768096) (xy 131.414774 -254.768096) (xy 131.414774 -254.812546)
			(xy 131.51485 -254.912622)
		)
		(stroke
			(width 0)
			(type solid)
		)
		(fill yes)
		(layer "In2.Cu")
		(net "M_I_CPU1_SA_CA<5>")
	)
	(gr_poly
		(pts
			(xy 131.614926 -253.596394) (xy 131.51485 -253.496318) (xy 131.414774 -253.596394) (xy 131.414774 -253.640844)
			(xy 131.614926 -253.640844)
		)
		(stroke
			(width 0)
			(type solid)
		)
		(fill yes)
		(layer "In2.Cu")
		(net "M_I_CPU1_SA_CA<2>")
	)
	(gr_poly
		(pts
			(xy 131.614926 -253.192534) (xy 131.614926 -253.148084) (xy 131.414774 -253.148084) (xy 131.414774 -253.192534)
			(xy 131.51485 -253.29261)
		)
		(stroke
			(width 0)
			(type solid)
		)
		(fill yes)
		(layer "In2.Cu")
		(net "M_I_CPU1_SA_CA<1>")
	)
	(gr_poly
		(pts
			(xy 131.614926 -251.976382) (xy 131.51485 -251.876306) (xy 131.414774 -251.976382) (xy 131.414774 -252.020832)
			(xy 131.614926 -252.020832)
		)
		(stroke
			(width 0)
			(type solid)
		)
		(fill yes)
		(layer "In2.Cu")
		(net "M_I_CPU1_SA_CS_N<1>")
	)
	(gr_poly
		(pts
			(xy 131.614926 -250.35637) (xy 131.51485 -250.256294) (xy 131.414774 -250.35637) (xy 131.414774 -250.40082)
			(xy 131.614926 -250.40082)
		)
		(stroke
			(width 0)
			(type solid)
		)
		(fill yes)
		(layer "In2.Cu")
		(net "M_I_CPU1_ALERT_R_N")
	)
	(gr_poly
		(pts
			(xy 131.614926 -248.736358) (xy 131.51485 -248.636282) (xy 131.414774 -248.736358) (xy 131.414774 -248.780808)
			(xy 131.614926 -248.780808)
		)
		(stroke
			(width 0)
			(type solid)
		)
		(fill yes)
		(layer "In2.Cu")
		(net "M_I_CPU1_SA_CB<5>")
	)
	(gr_poly
		(pts
			(xy 131.614926 -248.332498) (xy 131.614926 -248.288048) (xy 131.414774 -248.288048) (xy 131.414774 -248.332498)
			(xy 131.51485 -248.432574)
		)
		(stroke
			(width 0)
			(type solid)
		)
		(fill yes)
		(layer "In2.Cu")
		(net "M_I_CPU1_SA_CB<6>")
	)
	(gr_poly
		(pts
			(xy 131.614926 -247.116092) (xy 131.51485 -247.01627) (xy 131.414774 -247.116092) (xy 131.414774 -247.163844)
			(xy 131.614926 -247.163844)
		)
		(stroke
			(width 0)
			(type solid)
		)
		(fill yes)
		(layer "In2.Cu")
		(net "M_I_CPU1_SA_DQS_DN<9>")
	)
	(gr_poly
		(pts
			(xy 131.614926 -246.71274) (xy 131.614926 -246.664988) (xy 131.414774 -246.664988) (xy 131.414774 -246.71274)
			(xy 131.51485 -246.812562)
		)
		(stroke
			(width 0)
			(type solid)
		)
		(fill yes)
		(layer "In2.Cu")
		(net "M_I_CPU1_SA_DQS_DN<4>")
	)
	(gr_poly
		(pts
			(xy 131.614926 -245.496334) (xy 131.51485 -245.396258) (xy 131.414774 -245.496334) (xy 131.414774 -245.540784)
			(xy 131.614926 -245.540784)
		)
		(stroke
			(width 0)
			(type solid)
		)
		(fill yes)
		(layer "In2.Cu")
		(net "M_I_CPU1_SA_CB<1>")
	)
	(gr_poly
		(pts
			(xy 131.614926 -245.092474) (xy 131.614926 -245.048024) (xy 131.414774 -245.048024) (xy 131.414774 -245.092474)
			(xy 131.51485 -245.19255)
		)
		(stroke
			(width 0)
			(type solid)
		)
		(fill yes)
		(layer "In2.Cu")
		(net "M_I_CPU1_SA_CB<2>")
	)
	(gr_poly
		(pts
			(xy 131.614926 -243.876322) (xy 131.51485 -243.776246) (xy 131.414774 -243.876322) (xy 131.414774 -243.920772)
			(xy 131.614926 -243.920772)
		)
		(stroke
			(width 0)
			(type solid)
		)
		(fill yes)
		(layer "In2.Cu")
		(net "M_I_CPU1_SA_DQ<29>")
	)
	(gr_poly
		(pts
			(xy 131.614926 -243.472462) (xy 131.614926 -243.428012) (xy 131.414774 -243.428012) (xy 131.414774 -243.472462)
			(xy 131.51485 -243.572538)
		)
		(stroke
			(width 0)
			(type solid)
		)
		(fill yes)
		(layer "In2.Cu")
		(net "M_I_CPU1_SA_DQ<30>")
	)
	(gr_poly
		(pts
			(xy 131.614926 -242.256056) (xy 131.51485 -242.156234) (xy 131.414774 -242.256056) (xy 131.414774 -242.303808)
			(xy 131.614926 -242.303808)
		)
		(stroke
			(width 0)
			(type solid)
		)
		(fill yes)
		(layer "In2.Cu")
		(net "M_I_CPU1_SA_DQS_DN<8>")
	)
	(gr_poly
		(pts
			(xy 131.614926 -241.852704) (xy 131.614926 -241.804952) (xy 131.414774 -241.804952) (xy 131.414774 -241.852704)
			(xy 131.51485 -241.952526)
		)
		(stroke
			(width 0)
			(type solid)
		)
		(fill yes)
		(layer "In2.Cu")
		(net "M_I_CPU1_SA_DQS_DN<3>")
	)
	(gr_poly
		(pts
			(xy 131.614926 -240.636298) (xy 131.51485 -240.536222) (xy 131.414774 -240.636298) (xy 131.414774 -240.680748)
			(xy 131.614926 -240.680748)
		)
		(stroke
			(width 0)
			(type solid)
		)
		(fill yes)
		(layer "In2.Cu")
		(net "M_I_CPU1_SA_DQ<25>")
	)
	(gr_poly
		(pts
			(xy 131.614926 -240.232438) (xy 131.614926 -240.187988) (xy 131.414774 -240.187988) (xy 131.414774 -240.232438)
			(xy 131.51485 -240.332514)
		)
		(stroke
			(width 0)
			(type solid)
		)
		(fill yes)
		(layer "In2.Cu")
		(net "M_I_CPU1_SA_DQ<26>")
	)
	(gr_poly
		(pts
			(xy 131.614926 -239.016286) (xy 131.51485 -238.91621) (xy 131.414774 -239.016286) (xy 131.414774 -239.060736)
			(xy 131.614926 -239.060736)
		)
		(stroke
			(width 0)
			(type solid)
		)
		(fill yes)
		(layer "In2.Cu")
		(net "M_I_CPU1_SA_DQ<21>")
	)
	(gr_poly
		(pts
			(xy 131.614926 -238.612426) (xy 131.614926 -238.567976) (xy 131.414774 -238.567976) (xy 131.414774 -238.612426)
			(xy 131.51485 -238.712502)
		)
		(stroke
			(width 0)
			(type solid)
		)
		(fill yes)
		(layer "In2.Cu")
		(net "M_I_CPU1_SA_DQ<22>")
	)
	(gr_poly
		(pts
			(xy 131.614926 -237.39602) (xy 131.51485 -237.296198) (xy 131.414774 -237.39602) (xy 131.414774 -237.443772)
			(xy 131.614926 -237.443772)
		)
		(stroke
			(width 0)
			(type solid)
		)
		(fill yes)
		(layer "In2.Cu")
		(net "M_I_CPU1_SA_DQS_DN<7>")
	)
	(gr_poly
		(pts
			(xy 131.614926 -236.992668) (xy 131.614926 -236.944916) (xy 131.414774 -236.944916) (xy 131.414774 -236.992668)
			(xy 131.51485 -237.09249)
		)
		(stroke
			(width 0)
			(type solid)
		)
		(fill yes)
		(layer "In2.Cu")
		(net "M_I_CPU1_SA_DQS_DN<2>")
	)
	(gr_poly
		(pts
			(xy 131.614926 -235.776262) (xy 131.51485 -235.676186) (xy 131.414774 -235.776262) (xy 131.414774 -235.820712)
			(xy 131.614926 -235.820712)
		)
		(stroke
			(width 0)
			(type solid)
		)
		(fill yes)
		(layer "In2.Cu")
		(net "M_I_CPU1_SA_DQ<17>")
	)
	(gr_poly
		(pts
			(xy 131.614926 -235.372402) (xy 131.614926 -235.327952) (xy 131.414774 -235.327952) (xy 131.414774 -235.372402)
			(xy 131.51485 -235.472478)
		)
		(stroke
			(width 0)
			(type solid)
		)
		(fill yes)
		(layer "In2.Cu")
		(net "M_I_CPU1_SA_DQ<18>")
	)
	(gr_poly
		(pts
			(xy 131.614926 -234.15625) (xy 131.51485 -234.056174) (xy 131.414774 -234.15625) (xy 131.414774 -234.2007)
			(xy 131.614926 -234.2007)
		)
		(stroke
			(width 0)
			(type solid)
		)
		(fill yes)
		(layer "In2.Cu")
		(net "M_I_CPU1_SA_DQ<13>")
	)
	(gr_poly
		(pts
			(xy 131.614926 -233.75239) (xy 131.614926 -233.70794) (xy 131.414774 -233.70794) (xy 131.414774 -233.75239)
			(xy 131.51485 -233.852466)
		)
		(stroke
			(width 0)
			(type solid)
		)
		(fill yes)
		(layer "In2.Cu")
		(net "M_I_CPU1_SA_DQ<14>")
	)
	(gr_poly
		(pts
			(xy 131.614926 -232.535984) (xy 131.51485 -232.436162) (xy 131.414774 -232.535984) (xy 131.414774 -232.583736)
			(xy 131.614926 -232.583736)
		)
		(stroke
			(width 0)
			(type solid)
		)
		(fill yes)
		(layer "In2.Cu")
		(net "M_I_CPU1_SA_DQS_DN<6>")
	)
	(gr_poly
		(pts
			(xy 131.614926 -232.132632) (xy 131.614926 -232.08488) (xy 131.414774 -232.08488) (xy 131.414774 -232.132632)
			(xy 131.51485 -232.232454)
		)
		(stroke
			(width 0)
			(type solid)
		)
		(fill yes)
		(layer "In2.Cu")
		(net "M_I_CPU1_SA_DQS_DN<1>")
	)
	(gr_poly
		(pts
			(xy 131.614926 -230.916226) (xy 131.51485 -230.81615) (xy 131.414774 -230.916226) (xy 131.414774 -230.960676)
			(xy 131.614926 -230.960676)
		)
		(stroke
			(width 0)
			(type solid)
		)
		(fill yes)
		(layer "In2.Cu")
		(net "M_I_CPU1_SA_DQ<9>")
	)
	(gr_poly
		(pts
			(xy 131.614926 -230.51262) (xy 131.614926 -230.46817) (xy 131.414774 -230.46817) (xy 131.414774 -230.51262)
			(xy 131.51485 -230.612696)
		)
		(stroke
			(width 0)
			(type solid)
		)
		(fill yes)
		(layer "In2.Cu")
		(net "M_I_CPU1_SA_DQ<10>")
	)
	(gr_poly
		(pts
			(xy 131.614926 -229.296214) (xy 131.51485 -229.196138) (xy 131.414774 -229.296214) (xy 131.414774 -229.340664)
			(xy 131.614926 -229.340664)
		)
		(stroke
			(width 0)
			(type solid)
		)
		(fill yes)
		(layer "In2.Cu")
		(net "M_I_CPU1_SA_DQ<5>")
	)
	(gr_poly
		(pts
			(xy 131.614926 -228.892608) (xy 131.614926 -228.848158) (xy 131.414774 -228.848158) (xy 131.414774 -228.892608)
			(xy 131.51485 -228.992684)
		)
		(stroke
			(width 0)
			(type solid)
		)
		(fill yes)
		(layer "In2.Cu")
		(net "M_I_CPU1_SA_DQ<6>")
	)
	(gr_poly
		(pts
			(xy 131.614926 -227.676202) (xy 131.51485 -227.57638) (xy 131.414774 -227.676202) (xy 131.414774 -227.723954)
			(xy 131.614926 -227.723954)
		)
		(stroke
			(width 0)
			(type solid)
		)
		(fill yes)
		(layer "In2.Cu")
		(net "M_I_CPU1_SA_DQS_DN<5>")
	)
	(gr_poly
		(pts
			(xy 131.614926 -227.27285) (xy 131.614926 -227.225098) (xy 131.414774 -227.225098) (xy 131.414774 -227.27285)
			(xy 131.51485 -227.372672)
		)
		(stroke
			(width 0)
			(type solid)
		)
		(fill yes)
		(layer "In2.Cu")
		(net "M_I_CPU1_SA_DQS_DN<0>")
	)
	(gr_poly
		(pts
			(xy 131.614926 -226.056444) (xy 131.51485 -225.956368) (xy 131.414774 -226.056444) (xy 131.414774 -226.100894)
			(xy 131.614926 -226.100894)
		)
		(stroke
			(width 0)
			(type solid)
		)
		(fill yes)
		(layer "In2.Cu")
		(net "M_I_CPU1_SA_DQ<1>")
	)
	(gr_poly
		(pts
			(xy 131.614926 -225.652584) (xy 131.614926 -225.608134) (xy 131.414774 -225.608134) (xy 131.414774 -225.652584)
			(xy 131.51485 -225.75266)
		)
		(stroke
			(width 0)
			(type solid)
		)
		(fill yes)
		(layer "In2.Cu")
		(net "M_I_CPU1_SA_DQ<2>")
	)
	(gr_poly
		(pts
			(xy 131.9149 -293.32428) (xy 131.9149 -293.27983) (xy 131.714748 -293.27983) (xy 131.714748 -293.32428)
			(xy 131.814824 -293.424356)
		)
		(stroke
			(width 0)
			(type solid)
		)
		(fill yes)
		(layer "In2.Cu")
		(net "M_I_CPU1_SB_DQ<31>")
	)
	(gr_poly
		(pts
			(xy 131.9149 -292.108128) (xy 131.814824 -292.008052) (xy 131.714748 -292.108128) (xy 131.714748 -292.152578)
			(xy 131.9149 -292.152578)
		)
		(stroke
			(width 0)
			(type solid)
		)
		(fill yes)
		(layer "In2.Cu")
		(net "M_I_CPU1_SB_DQ<28>")
	)
	(gr_poly
		(pts
			(xy 131.9149 -291.704522) (xy 131.9149 -291.65677) (xy 131.714748 -291.65677) (xy 131.714748 -291.704522)
			(xy 131.814824 -291.804344)
		)
		(stroke
			(width 0)
			(type solid)
		)
		(fill yes)
		(layer "In2.Cu")
		(net "M_I_CPU1_SB_DQS_DP<8>")
	)
	(gr_poly
		(pts
			(xy 131.9149 -290.487862) (xy 131.814824 -290.38804) (xy 131.714748 -290.487862) (xy 131.714748 -290.535614)
			(xy 131.9149 -290.535614)
		)
		(stroke
			(width 0)
			(type solid)
		)
		(fill yes)
		(layer "In2.Cu")
		(net "M_I_CPU1_SB_DQS_DP<3>")
	)
	(gr_poly
		(pts
			(xy 131.9149 -290.084256) (xy 131.9149 -290.039806) (xy 131.714748 -290.039806) (xy 131.714748 -290.084256)
			(xy 131.814824 -290.184332)
		)
		(stroke
			(width 0)
			(type solid)
		)
		(fill yes)
		(layer "In2.Cu")
		(net "M_I_CPU1_SB_DQ<27>")
	)
	(gr_poly
		(pts
			(xy 131.9149 -288.868104) (xy 131.814824 -288.768028) (xy 131.714748 -288.868104) (xy 131.714748 -288.912554)
			(xy 131.9149 -288.912554)
		)
		(stroke
			(width 0)
			(type solid)
		)
		(fill yes)
		(layer "In2.Cu")
		(net "M_I_CPU1_SB_DQ<24>")
	)
	(gr_poly
		(pts
			(xy 131.9149 -288.464498) (xy 131.9149 -288.420048) (xy 131.714748 -288.420048) (xy 131.714748 -288.464498)
			(xy 131.814824 -288.564574)
		)
		(stroke
			(width 0)
			(type solid)
		)
		(fill yes)
		(layer "In2.Cu")
		(net "M_I_CPU1_SB_DQ<23>")
	)
	(gr_poly
		(pts
			(xy 131.9149 -287.248092) (xy 131.814824 -287.148016) (xy 131.714748 -287.248092) (xy 131.714748 -287.292542)
			(xy 131.9149 -287.292542)
		)
		(stroke
			(width 0)
			(type solid)
		)
		(fill yes)
		(layer "In2.Cu")
		(net "M_I_CPU1_SB_DQ<20>")
	)
	(gr_poly
		(pts
			(xy 131.9149 -286.844486) (xy 131.9149 -286.796734) (xy 131.714748 -286.796734) (xy 131.714748 -286.844486)
			(xy 131.814824 -286.944562)
		)
		(stroke
			(width 0)
			(type solid)
		)
		(fill yes)
		(layer "In2.Cu")
		(net "M_I_CPU1_SB_DQS_DP<7>")
	)
	(gr_poly
		(pts
			(xy 131.9149 -285.62808) (xy 131.814824 -285.528258) (xy 131.714748 -285.62808) (xy 131.714748 -285.675832)
			(xy 131.9149 -285.675832)
		)
		(stroke
			(width 0)
			(type solid)
		)
		(fill yes)
		(layer "In2.Cu")
		(net "M_I_CPU1_SB_DQS_DP<2>")
	)
	(gr_poly
		(pts
			(xy 131.9149 -285.224474) (xy 131.9149 -285.180024) (xy 131.714748 -285.180024) (xy 131.714748 -285.224474)
			(xy 131.814824 -285.32455)
		)
		(stroke
			(width 0)
			(type solid)
		)
		(fill yes)
		(layer "In2.Cu")
		(net "M_I_CPU1_SB_DQ<19>")
	)
	(gr_poly
		(pts
			(xy 131.9149 -284.008322) (xy 131.814824 -283.908246) (xy 131.714748 -284.008322) (xy 131.714748 -284.052772)
			(xy 131.9149 -284.052772)
		)
		(stroke
			(width 0)
			(type solid)
		)
		(fill yes)
		(layer "In2.Cu")
		(net "M_I_CPU1_SB_DQ<16>")
	)
	(gr_poly
		(pts
			(xy 131.9149 -283.604462) (xy 131.9149 -283.560012) (xy 131.714748 -283.560012) (xy 131.714748 -283.604462)
			(xy 131.814824 -283.704538)
		)
		(stroke
			(width 0)
			(type solid)
		)
		(fill yes)
		(layer "In2.Cu")
		(net "M_I_CPU1_SB_DQ<15>")
	)
	(gr_poly
		(pts
			(xy 131.9149 -282.38831) (xy 131.814824 -282.288234) (xy 131.714748 -282.38831) (xy 131.714748 -282.43276)
			(xy 131.9149 -282.43276)
		)
		(stroke
			(width 0)
			(type solid)
		)
		(fill yes)
		(layer "In2.Cu")
		(net "M_I_CPU1_SB_DQ<12>")
	)
	(gr_poly
		(pts
			(xy 131.9149 -281.984704) (xy 131.9149 -281.936952) (xy 131.714748 -281.936952) (xy 131.714748 -281.984704)
			(xy 131.814824 -282.084526)
		)
		(stroke
			(width 0)
			(type solid)
		)
		(fill yes)
		(layer "In2.Cu")
		(net "M_I_CPU1_SB_DQS_DP<6>")
	)
	(gr_poly
		(pts
			(xy 131.9149 -280.768044) (xy 131.814824 -280.668222) (xy 131.714748 -280.768044) (xy 131.714748 -280.815796)
			(xy 131.9149 -280.815796)
		)
		(stroke
			(width 0)
			(type solid)
		)
		(fill yes)
		(layer "In2.Cu")
		(net "M_I_CPU1_SB_DQS_DP<1>")
	)
	(gr_poly
		(pts
			(xy 131.9149 -280.364438) (xy 131.9149 -280.319988) (xy 131.714748 -280.319988) (xy 131.714748 -280.364438)
			(xy 131.814824 -280.464514)
		)
		(stroke
			(width 0)
			(type solid)
		)
		(fill yes)
		(layer "In2.Cu")
		(net "M_I_CPU1_SB_DQ<11>")
	)
	(gr_poly
		(pts
			(xy 131.9149 -279.148286) (xy 131.814824 -279.04821) (xy 131.714748 -279.148286) (xy 131.714748 -279.192736)
			(xy 131.9149 -279.192736)
		)
		(stroke
			(width 0)
			(type solid)
		)
		(fill yes)
		(layer "In2.Cu")
		(net "M_I_CPU1_SB_DQ<8>")
	)
	(gr_poly
		(pts
			(xy 131.9149 -278.744426) (xy 131.9149 -278.699976) (xy 131.714748 -278.699976) (xy 131.714748 -278.744426)
			(xy 131.814824 -278.844502)
		)
		(stroke
			(width 0)
			(type solid)
		)
		(fill yes)
		(layer "In2.Cu")
		(net "M_I_CPU1_SB_DQ<7>")
	)
	(gr_poly
		(pts
			(xy 131.9149 -277.528274) (xy 131.814824 -277.428198) (xy 131.714748 -277.528274) (xy 131.714748 -277.572724)
			(xy 131.9149 -277.572724)
		)
		(stroke
			(width 0)
			(type solid)
		)
		(fill yes)
		(layer "In2.Cu")
		(net "M_I_CPU1_SB_DQ<4>")
	)
	(gr_poly
		(pts
			(xy 131.9149 -277.124668) (xy 131.9149 -277.076916) (xy 131.714748 -277.076916) (xy 131.714748 -277.124668)
			(xy 131.814824 -277.22449)
		)
		(stroke
			(width 0)
			(type solid)
		)
		(fill yes)
		(layer "In2.Cu")
		(net "M_I_CPU1_SB_DQS_DP<5>")
	)
	(gr_poly
		(pts
			(xy 131.9149 -275.908008) (xy 131.814824 -275.808186) (xy 131.714748 -275.908008) (xy 131.714748 -275.95576)
			(xy 131.9149 -275.95576)
		)
		(stroke
			(width 0)
			(type solid)
		)
		(fill yes)
		(layer "In2.Cu")
		(net "M_I_CPU1_SB_DQS_DP<0>")
	)
	(gr_poly
		(pts
			(xy 131.9149 -275.504402) (xy 131.9149 -275.459952) (xy 131.714748 -275.459952) (xy 131.714748 -275.504402)
			(xy 131.814824 -275.604478)
		)
		(stroke
			(width 0)
			(type solid)
		)
		(fill yes)
		(layer "In2.Cu")
		(net "M_I_CPU1_SB_DQ<3>")
	)
	(gr_poly
		(pts
			(xy 131.9149 -274.28825) (xy 131.814824 -274.188174) (xy 131.714748 -274.28825) (xy 131.714748 -274.3327)
			(xy 131.9149 -274.3327)
		)
		(stroke
			(width 0)
			(type solid)
		)
		(fill yes)
		(layer "In2.Cu")
		(net "M_I_CPU1_SB_DQ<0>")
	)
	(gr_poly
		(pts
			(xy 131.9149 -273.88439) (xy 131.9149 -273.83994) (xy 131.714748 -273.83994) (xy 131.714748 -273.88439)
			(xy 131.814824 -273.984466)
		)
		(stroke
			(width 0)
			(type solid)
		)
		(fill yes)
		(layer "In2.Cu")
		(net "M_I_CPU1_SB_CB<3>")
	)
	(gr_poly
		(pts
			(xy 131.9149 -272.668238) (xy 131.814824 -272.568162) (xy 131.714748 -272.668238) (xy 131.714748 -272.712688)
			(xy 131.9149 -272.712688)
		)
		(stroke
			(width 0)
			(type solid)
		)
		(fill yes)
		(layer "In2.Cu")
		(net "M_I_CPU1_SB_CB<0>")
	)
	(gr_poly
		(pts
			(xy 131.9149 -272.264632) (xy 131.9149 -272.21688) (xy 131.714748 -272.21688) (xy 131.714748 -272.264632)
			(xy 131.814824 -272.364454)
		)
		(stroke
			(width 0)
			(type solid)
		)
		(fill yes)
		(layer "In2.Cu")
		(net "M_I_CPU1_SB_DQS_DP<4>")
	)
	(gr_poly
		(pts
			(xy 131.9149 -271.047972) (xy 131.814824 -270.94815) (xy 131.714748 -271.047972) (xy 131.714748 -271.095724)
			(xy 131.9149 -271.095724)
		)
		(stroke
			(width 0)
			(type solid)
		)
		(fill yes)
		(layer "In2.Cu")
		(net "M_I_CPU1_SB_DQS_DP<9>")
	)
	(gr_poly
		(pts
			(xy 131.9149 -270.644366) (xy 131.9149 -270.599916) (xy 131.714748 -270.599916) (xy 131.714748 -270.644366)
			(xy 131.814824 -270.744442)
		)
		(stroke
			(width 0)
			(type solid)
		)
		(fill yes)
		(layer "In2.Cu")
		(net "M_I_CPU1_SB_CB<7>")
	)
	(gr_poly
		(pts
			(xy 131.9149 -269.428214) (xy 131.814824 -269.328138) (xy 131.714748 -269.428214) (xy 131.714748 -269.472664)
			(xy 131.9149 -269.472664)
		)
		(stroke
			(width 0)
			(type solid)
		)
		(fill yes)
		(layer "In2.Cu")
		(net "M_I_CPU1_SB_CB<4>")
	)
	(gr_poly
		(pts
			(xy 131.9149 -267.404342) (xy 131.9149 -267.359892) (xy 131.714748 -267.359892) (xy 131.714748 -267.404342)
			(xy 131.814824 -267.504418)
		)
		(stroke
			(width 0)
			(type solid)
		)
		(fill yes)
		(layer "In2.Cu")
		(net "M_I_CPU1_SB_RSP<0>")
	)
	(gr_poly
		(pts
			(xy 131.9149 -265.78433) (xy 131.9149 -265.73988) (xy 131.714748 -265.73988) (xy 131.714748 -265.78433)
			(xy 131.814824 -265.884406)
		)
		(stroke
			(width 0)
			(type solid)
		)
		(fill yes)
		(layer "In2.Cu")
		(net "M_I_CPU1_SB_CS_N<0>")
	)
	(gr_poly
		(pts
			(xy 131.9149 -264.568178) (xy 131.814824 -264.468102) (xy 131.714748 -264.568178) (xy 131.714748 -264.612628)
			(xy 131.9149 -264.612628)
		)
		(stroke
			(width 0)
			(type solid)
		)
		(fill yes)
		(layer "In2.Cu")
		(net "M_I_CPU1_SB_CA<6>")
	)
	(gr_poly
		(pts
			(xy 131.9149 -264.164318) (xy 131.9149 -264.119868) (xy 131.714748 -264.119868) (xy 131.714748 -264.164318)
			(xy 131.814824 -264.264394)
		)
		(stroke
			(width 0)
			(type solid)
		)
		(fill yes)
		(layer "In2.Cu")
		(net "M_I_CPU1_SB_CA<5>")
	)
	(gr_poly
		(pts
			(xy 131.9149 -262.948166) (xy 131.814824 -262.84809) (xy 131.714748 -262.948166) (xy 131.714748 -262.992616)
			(xy 131.9149 -262.992616)
		)
		(stroke
			(width 0)
			(type solid)
		)
		(fill yes)
		(layer "In2.Cu")
		(net "M_I_CPU1_SB_CA<2>")
	)
	(gr_poly
		(pts
			(xy 131.9149 -262.544306) (xy 131.9149 -262.499856) (xy 131.714748 -262.499856) (xy 131.714748 -262.544306)
			(xy 131.814824 -262.644382)
		)
		(stroke
			(width 0)
			(type solid)
		)
		(fill yes)
		(layer "In2.Cu")
		(net "M_I_CPU1_SB_CA<1>")
	)
	(gr_poly
		(pts
			(xy 132.084826 -256.026158) (xy 131.98475 -255.926336) (xy 131.884674 -256.026158) (xy 131.884674 -256.07391)
			(xy 132.084826 -256.07391)
		)
		(stroke
			(width 0)
			(type solid)
		)
		(fill yes)
		(layer "In2.Cu")
		(net "M_I_CPU1_CLK_DP<0>")
	)
	(gr_poly
		(pts
			(xy 132.084826 -255.622552) (xy 132.084826 -255.578102) (xy 131.884674 -255.578102) (xy 131.884674 -255.622552)
			(xy 131.98475 -255.722628)
		)
		(stroke
			(width 0)
			(type solid)
		)
		(fill yes)
		(layer "In2.Cu")
		(net "M_I_CPU1_SA_PAR")
	)
	(gr_poly
		(pts
			(xy 132.084826 -254.4064) (xy 131.98475 -254.306324) (xy 131.884674 -254.4064) (xy 131.884674 -254.45085)
			(xy 132.084826 -254.45085)
		)
		(stroke
			(width 0)
			(type solid)
		)
		(fill yes)
		(layer "In2.Cu")
		(net "M_I_CPU1_SA_CA<4>")
	)
	(gr_poly
		(pts
			(xy 132.084826 -254.00254) (xy 132.084826 -253.95809) (xy 131.884674 -253.95809) (xy 131.884674 -254.00254)
			(xy 131.98475 -254.102616)
		)
		(stroke
			(width 0)
			(type solid)
		)
		(fill yes)
		(layer "In2.Cu")
		(net "M_I_CPU1_SA_CA<3>")
	)
	(gr_poly
		(pts
			(xy 132.084826 -252.786388) (xy 131.98475 -252.686312) (xy 131.884674 -252.786388) (xy 131.884674 -252.830838)
			(xy 132.084826 -252.830838)
		)
		(stroke
			(width 0)
			(type solid)
		)
		(fill yes)
		(layer "In2.Cu")
		(net "M_I_CPU1_SA_CA<0>")
	)
	(gr_poly
		(pts
			(xy 132.084826 -251.166376) (xy 131.98475 -251.0663) (xy 131.884674 -251.166376) (xy 131.884674 -251.210826)
			(xy 132.084826 -251.210826)
		)
		(stroke
			(width 0)
			(type solid)
		)
		(fill yes)
		(layer "In2.Cu")
		(net "M_I_CPU1_SA_CS_N<0>")
	)
	(gr_poly
		(pts
			(xy 132.084826 -250.762516) (xy 132.084826 -250.718066) (xy 131.884674 -250.718066) (xy 131.884674 -250.762516)
			(xy 131.98475 -250.862592)
		)
		(stroke
			(width 0)
			(type solid)
		)
		(fill yes)
		(layer "In2.Cu")
		(net "M_I_CPU1_RESET_N")
	)
	(gr_poly
		(pts
			(xy 132.084826 -249.142504) (xy 132.084826 -249.098054) (xy 131.884674 -249.098054) (xy 131.884674 -249.142504)
			(xy 131.98475 -249.24258)
		)
		(stroke
			(width 0)
			(type solid)
		)
		(fill yes)
		(layer "In2.Cu")
		(net "M_I_CPU1_SA_CB<7>")
	)
	(gr_poly
		(pts
			(xy 132.084826 -247.926352) (xy 131.98475 -247.826276) (xy 131.884674 -247.926352) (xy 131.884674 -247.970802)
			(xy 132.084826 -247.970802)
		)
		(stroke
			(width 0)
			(type solid)
		)
		(fill yes)
		(layer "In2.Cu")
		(net "M_I_CPU1_SA_CB<4>")
	)
	(gr_poly
		(pts
			(xy 132.084826 -247.522746) (xy 132.084826 -247.474994) (xy 131.884674 -247.474994) (xy 131.884674 -247.522746)
			(xy 131.98475 -247.622568)
		)
		(stroke
			(width 0)
			(type solid)
		)
		(fill yes)
		(layer "In2.Cu")
		(net "M_I_CPU1_SA_DQS_DP<9>")
	)
	(gr_poly
		(pts
			(xy 132.084826 -246.306086) (xy 131.98475 -246.206264) (xy 131.884674 -246.306086) (xy 131.884674 -246.353838)
			(xy 132.084826 -246.353838)
		)
		(stroke
			(width 0)
			(type solid)
		)
		(fill yes)
		(layer "In2.Cu")
		(net "M_I_CPU1_SA_DQS_DP<4>")
	)
	(gr_poly
		(pts
			(xy 132.084826 -245.90248) (xy 132.084826 -245.85803) (xy 131.884674 -245.85803) (xy 131.884674 -245.90248)
			(xy 131.98475 -246.002556)
		)
		(stroke
			(width 0)
			(type solid)
		)
		(fill yes)
		(layer "In2.Cu")
		(net "M_I_CPU1_SA_CB<3>")
	)
	(gr_poly
		(pts
			(xy 132.084826 -244.686328) (xy 131.98475 -244.586252) (xy 131.884674 -244.686328) (xy 131.884674 -244.730778)
			(xy 132.084826 -244.730778)
		)
		(stroke
			(width 0)
			(type solid)
		)
		(fill yes)
		(layer "In2.Cu")
		(net "M_I_CPU1_SA_CB<0>")
	)
	(gr_poly
		(pts
			(xy 132.084826 -244.282468) (xy 132.084826 -244.238018) (xy 131.884674 -244.238018) (xy 131.884674 -244.282468)
			(xy 131.98475 -244.382544)
		)
		(stroke
			(width 0)
			(type solid)
		)
		(fill yes)
		(layer "In2.Cu")
		(net "M_I_CPU1_SA_DQ<31>")
	)
	(gr_poly
		(pts
			(xy 132.084826 -243.066316) (xy 131.98475 -242.96624) (xy 131.884674 -243.066316) (xy 131.884674 -243.110766)
			(xy 132.084826 -243.110766)
		)
		(stroke
			(width 0)
			(type solid)
		)
		(fill yes)
		(layer "In2.Cu")
		(net "M_I_CPU1_SA_DQ<28>")
	)
	(gr_poly
		(pts
			(xy 132.084826 -242.66271) (xy 132.084826 -242.614958) (xy 131.884674 -242.614958) (xy 131.884674 -242.66271)
			(xy 131.98475 -242.762532)
		)
		(stroke
			(width 0)
			(type solid)
		)
		(fill yes)
		(layer "In2.Cu")
		(net "M_I_CPU1_SA_DQS_DP<8>")
	)
	(gr_poly
		(pts
			(xy 132.084826 -241.44605) (xy 131.98475 -241.346228) (xy 131.884674 -241.44605) (xy 131.884674 -241.493802)
			(xy 132.084826 -241.493802)
		)
		(stroke
			(width 0)
			(type solid)
		)
		(fill yes)
		(layer "In2.Cu")
		(net "M_I_CPU1_SA_DQS_DP<3>")
	)
	(gr_poly
		(pts
			(xy 132.084826 -241.042444) (xy 132.084826 -240.997994) (xy 131.884674 -240.997994) (xy 131.884674 -241.042444)
			(xy 131.98475 -241.14252)
		)
		(stroke
			(width 0)
			(type solid)
		)
		(fill yes)
		(layer "In2.Cu")
		(net "M_I_CPU1_SA_DQ<27>")
	)
	(gr_poly
		(pts
			(xy 132.084826 -239.826292) (xy 131.98475 -239.726216) (xy 131.884674 -239.826292) (xy 131.884674 -239.870742)
			(xy 132.084826 -239.870742)
		)
		(stroke
			(width 0)
			(type solid)
		)
		(fill yes)
		(layer "In2.Cu")
		(net "M_I_CPU1_SA_DQ<24>")
	)
	(gr_poly
		(pts
			(xy 132.084826 -239.422432) (xy 132.084826 -239.377982) (xy 131.884674 -239.377982) (xy 131.884674 -239.422432)
			(xy 131.98475 -239.522508)
		)
		(stroke
			(width 0)
			(type solid)
		)
		(fill yes)
		(layer "In2.Cu")
		(net "M_I_CPU1_SA_DQ<23>")
	)
	(gr_poly
		(pts
			(xy 132.084826 -238.20628) (xy 131.98475 -238.106204) (xy 131.884674 -238.20628) (xy 131.884674 -238.25073)
			(xy 132.084826 -238.25073)
		)
		(stroke
			(width 0)
			(type solid)
		)
		(fill yes)
		(layer "In2.Cu")
		(net "M_I_CPU1_SA_DQ<20>")
	)
	(gr_poly
		(pts
			(xy 132.084826 -237.802674) (xy 132.084826 -237.754922) (xy 131.884674 -237.754922) (xy 131.884674 -237.802674)
			(xy 131.98475 -237.902496)
		)
		(stroke
			(width 0)
			(type solid)
		)
		(fill yes)
		(layer "In2.Cu")
		(net "M_I_CPU1_SA_DQS_DP<7>")
	)
	(gr_poly
		(pts
			(xy 132.084826 -236.586014) (xy 131.98475 -236.486192) (xy 131.884674 -236.586014) (xy 131.884674 -236.633766)
			(xy 132.084826 -236.633766)
		)
		(stroke
			(width 0)
			(type solid)
		)
		(fill yes)
		(layer "In2.Cu")
		(net "M_I_CPU1_SA_DQS_DP<2>")
	)
	(gr_poly
		(pts
			(xy 132.084826 -236.182408) (xy 132.084826 -236.137958) (xy 131.884674 -236.137958) (xy 131.884674 -236.182408)
			(xy 131.98475 -236.282484)
		)
		(stroke
			(width 0)
			(type solid)
		)
		(fill yes)
		(layer "In2.Cu")
		(net "M_I_CPU1_SA_DQ<19>")
	)
	(gr_poly
		(pts
			(xy 132.084826 -234.966256) (xy 131.98475 -234.86618) (xy 131.884674 -234.966256) (xy 131.884674 -235.010706)
			(xy 132.084826 -235.010706)
		)
		(stroke
			(width 0)
			(type solid)
		)
		(fill yes)
		(layer "In2.Cu")
		(net "M_I_CPU1_SA_DQ<16>")
	)
	(gr_poly
		(pts
			(xy 132.084826 -234.562396) (xy 132.084826 -234.517946) (xy 131.884674 -234.517946) (xy 131.884674 -234.562396)
			(xy 131.98475 -234.662472)
		)
		(stroke
			(width 0)
			(type solid)
		)
		(fill yes)
		(layer "In2.Cu")
		(net "M_I_CPU1_SA_DQ<15>")
	)
	(gr_poly
		(pts
			(xy 132.084826 -233.346244) (xy 131.98475 -233.246168) (xy 131.884674 -233.346244) (xy 131.884674 -233.390694)
			(xy 132.084826 -233.390694)
		)
		(stroke
			(width 0)
			(type solid)
		)
		(fill yes)
		(layer "In2.Cu")
		(net "M_I_CPU1_SA_DQ<12>")
	)
	(gr_poly
		(pts
			(xy 132.084826 -232.942638) (xy 132.084826 -232.894886) (xy 131.884674 -232.894886) (xy 131.884674 -232.942638)
			(xy 131.98475 -233.04246)
		)
		(stroke
			(width 0)
			(type solid)
		)
		(fill yes)
		(layer "In2.Cu")
		(net "M_I_CPU1_SA_DQS_DP<6>")
	)
	(gr_poly
		(pts
			(xy 132.084826 -231.725978) (xy 131.98475 -231.626156) (xy 131.884674 -231.725978) (xy 131.884674 -231.77373)
			(xy 132.084826 -231.77373)
		)
		(stroke
			(width 0)
			(type solid)
		)
		(fill yes)
		(layer "In2.Cu")
		(net "M_I_CPU1_SA_DQS_DP<1>")
	)
	(gr_poly
		(pts
			(xy 132.084826 -231.322626) (xy 132.084826 -231.278176) (xy 131.884674 -231.278176) (xy 131.884674 -231.322626)
			(xy 131.98475 -231.422702)
		)
		(stroke
			(width 0)
			(type solid)
		)
		(fill yes)
		(layer "In2.Cu")
		(net "M_I_CPU1_SA_DQ<11>")
	)
	(gr_poly
		(pts
			(xy 132.084826 -230.10622) (xy 131.98475 -230.006144) (xy 131.884674 -230.10622) (xy 131.884674 -230.15067)
			(xy 132.084826 -230.15067)
		)
		(stroke
			(width 0)
			(type solid)
		)
		(fill yes)
		(layer "In2.Cu")
		(net "M_I_CPU1_SA_DQ<8>")
	)
	(gr_poly
		(pts
			(xy 132.084826 -229.702614) (xy 132.084826 -229.658164) (xy 131.884674 -229.658164) (xy 131.884674 -229.702614)
			(xy 131.98475 -229.80269)
		)
		(stroke
			(width 0)
			(type solid)
		)
		(fill yes)
		(layer "In2.Cu")
		(net "M_I_CPU1_SA_DQ<7>")
	)
	(gr_poly
		(pts
			(xy 132.084826 -228.486462) (xy 131.98475 -228.386386) (xy 131.884674 -228.486462) (xy 131.884674 -228.530912)
			(xy 132.084826 -228.530912)
		)
		(stroke
			(width 0)
			(type solid)
		)
		(fill yes)
		(layer "In2.Cu")
		(net "M_I_CPU1_SA_DQ<4>")
	)
	(gr_poly
		(pts
			(xy 132.084826 -228.082856) (xy 132.084826 -228.035104) (xy 131.884674 -228.035104) (xy 131.884674 -228.082856)
			(xy 131.98475 -228.182678)
		)
		(stroke
			(width 0)
			(type solid)
		)
		(fill yes)
		(layer "In2.Cu")
		(net "M_I_CPU1_SA_DQS_DP<5>")
	)
	(gr_poly
		(pts
			(xy 132.084826 -226.866196) (xy 131.98475 -226.766374) (xy 131.884674 -226.866196) (xy 131.884674 -226.913948)
			(xy 132.084826 -226.913948)
		)
		(stroke
			(width 0)
			(type solid)
		)
		(fill yes)
		(layer "In2.Cu")
		(net "M_I_CPU1_SA_DQS_DP<0>")
	)
	(gr_poly
		(pts
			(xy 132.084826 -226.46259) (xy 132.084826 -226.41814) (xy 131.884674 -226.41814) (xy 131.884674 -226.46259)
			(xy 131.98475 -226.562666)
		)
		(stroke
			(width 0)
			(type solid)
		)
		(fill yes)
		(layer "In2.Cu")
		(net "M_I_CPU1_SA_DQ<3>")
	)
	(gr_poly
		(pts
			(xy 132.084826 -225.246438) (xy 131.98475 -225.146362) (xy 131.884674 -225.246438) (xy 131.884674 -225.290888)
			(xy 132.084826 -225.290888)
		)
		(stroke
			(width 0)
			(type solid)
		)
		(fill yes)
		(layer "In2.Cu")
		(net "M_I_CPU1_SA_DQ<0>")
	)
	(gr_poly
		(pts
			(xy 132.3848 -292.918134) (xy 132.284724 -292.818058) (xy 132.184648 -292.918134) (xy 132.184648 -292.962584)
			(xy 132.3848 -292.962584)
		)
		(stroke
			(width 0)
			(type solid)
		)
		(fill yes)
		(layer "In2.Cu")
		(net "M_I_CPU1_SB_DQ<29>")
	)
	(gr_poly
		(pts
			(xy 132.3848 -292.514274) (xy 132.3848 -292.469824) (xy 132.184648 -292.469824) (xy 132.184648 -292.514274)
			(xy 132.284724 -292.61435)
		)
		(stroke
			(width 0)
			(type solid)
		)
		(fill yes)
		(layer "In2.Cu")
		(net "M_I_CPU1_SB_DQ<30>")
	)
	(gr_poly
		(pts
			(xy 132.3848 -291.297868) (xy 132.284724 -291.198046) (xy 132.184648 -291.297868) (xy 132.184648 -291.34562)
			(xy 132.3848 -291.34562)
		)
		(stroke
			(width 0)
			(type solid)
		)
		(fill yes)
		(layer "In2.Cu")
		(net "M_I_CPU1_SB_DQS_DN<8>")
	)
	(gr_poly
		(pts
			(xy 132.3848 -290.894516) (xy 132.3848 -290.846764) (xy 132.184648 -290.846764) (xy 132.184648 -290.894516)
			(xy 132.284724 -290.994338)
		)
		(stroke
			(width 0)
			(type solid)
		)
		(fill yes)
		(layer "In2.Cu")
		(net "M_I_CPU1_SB_DQS_DN<3>")
	)
	(gr_poly
		(pts
			(xy 132.3848 -289.67811) (xy 132.284724 -289.578034) (xy 132.184648 -289.67811) (xy 132.184648 -289.72256)
			(xy 132.3848 -289.72256)
		)
		(stroke
			(width 0)
			(type solid)
		)
		(fill yes)
		(layer "In2.Cu")
		(net "M_I_CPU1_SB_DQ<25>")
	)
	(gr_poly
		(pts
			(xy 132.3848 -289.27425) (xy 132.3848 -289.2298) (xy 132.184648 -289.2298) (xy 132.184648 -289.27425)
			(xy 132.284724 -289.374326)
		)
		(stroke
			(width 0)
			(type solid)
		)
		(fill yes)
		(layer "In2.Cu")
		(net "M_I_CPU1_SB_DQ<26>")
	)
	(gr_poly
		(pts
			(xy 132.3848 -288.058098) (xy 132.284724 -287.958022) (xy 132.184648 -288.058098) (xy 132.184648 -288.102548)
			(xy 132.3848 -288.102548)
		)
		(stroke
			(width 0)
			(type solid)
		)
		(fill yes)
		(layer "In2.Cu")
		(net "M_I_CPU1_SB_DQ<21>")
	)
	(gr_poly
		(pts
			(xy 132.3848 -287.654492) (xy 132.3848 -287.610042) (xy 132.184648 -287.610042) (xy 132.184648 -287.654492)
			(xy 132.284724 -287.754568)
		)
		(stroke
			(width 0)
			(type solid)
		)
		(fill yes)
		(layer "In2.Cu")
		(net "M_I_CPU1_SB_DQ<22>")
	)
	(gr_poly
		(pts
			(xy 132.3848 -286.438086) (xy 132.284724 -286.33801) (xy 132.184648 -286.438086) (xy 132.184648 -286.485838)
			(xy 132.3848 -286.485838)
		)
		(stroke
			(width 0)
			(type solid)
		)
		(fill yes)
		(layer "In2.Cu")
		(net "M_I_CPU1_SB_DQS_DN<7>")
	)
	(gr_poly
		(pts
			(xy 132.3848 -286.034734) (xy 132.3848 -285.986982) (xy 132.184648 -285.986982) (xy 132.184648 -286.034734)
			(xy 132.284724 -286.134556)
		)
		(stroke
			(width 0)
			(type solid)
		)
		(fill yes)
		(layer "In2.Cu")
		(net "M_I_CPU1_SB_DQS_DN<2>")
	)
	(gr_poly
		(pts
			(xy 132.3848 -284.818328) (xy 132.284724 -284.718252) (xy 132.184648 -284.818328) (xy 132.184648 -284.862778)
			(xy 132.3848 -284.862778)
		)
		(stroke
			(width 0)
			(type solid)
		)
		(fill yes)
		(layer "In2.Cu")
		(net "M_I_CPU1_SB_DQ<17>")
	)
	(gr_poly
		(pts
			(xy 132.3848 -284.414468) (xy 132.3848 -284.370018) (xy 132.184648 -284.370018) (xy 132.184648 -284.414468)
			(xy 132.284724 -284.514544)
		)
		(stroke
			(width 0)
			(type solid)
		)
		(fill yes)
		(layer "In2.Cu")
		(net "M_I_CPU1_SB_DQ<18>")
	)
	(gr_poly
		(pts
			(xy 132.3848 -283.198316) (xy 132.284724 -283.09824) (xy 132.184648 -283.198316) (xy 132.184648 -283.242766)
			(xy 132.3848 -283.242766)
		)
		(stroke
			(width 0)
			(type solid)
		)
		(fill yes)
		(layer "In2.Cu")
		(net "M_I_CPU1_SB_DQ<13>")
	)
	(gr_poly
		(pts
			(xy 132.3848 -282.794456) (xy 132.3848 -282.750006) (xy 132.184648 -282.750006) (xy 132.184648 -282.794456)
			(xy 132.284724 -282.894532)
		)
		(stroke
			(width 0)
			(type solid)
		)
		(fill yes)
		(layer "In2.Cu")
		(net "M_I_CPU1_SB_DQ<14>")
	)
	(gr_poly
		(pts
			(xy 132.3848 -281.57805) (xy 132.284724 -281.478228) (xy 132.184648 -281.57805) (xy 132.184648 -281.625802)
			(xy 132.3848 -281.625802)
		)
		(stroke
			(width 0)
			(type solid)
		)
		(fill yes)
		(layer "In2.Cu")
		(net "M_I_CPU1_SB_DQS_DN<6>")
	)
	(gr_poly
		(pts
			(xy 132.3848 -281.174698) (xy 132.3848 -281.126946) (xy 132.184648 -281.126946) (xy 132.184648 -281.174698)
			(xy 132.284724 -281.27452)
		)
		(stroke
			(width 0)
			(type solid)
		)
		(fill yes)
		(layer "In2.Cu")
		(net "M_I_CPU1_SB_DQS_DN<1>")
	)
	(gr_poly
		(pts
			(xy 132.3848 -279.958292) (xy 132.284724 -279.858216) (xy 132.184648 -279.958292) (xy 132.184648 -280.002742)
			(xy 132.3848 -280.002742)
		)
		(stroke
			(width 0)
			(type solid)
		)
		(fill yes)
		(layer "In2.Cu")
		(net "M_I_CPU1_SB_DQ<9>")
	)
	(gr_poly
		(pts
			(xy 132.3848 -279.554432) (xy 132.3848 -279.509982) (xy 132.184648 -279.509982) (xy 132.184648 -279.554432)
			(xy 132.284724 -279.654508)
		)
		(stroke
			(width 0)
			(type solid)
		)
		(fill yes)
		(layer "In2.Cu")
		(net "M_I_CPU1_SB_DQ<10>")
	)
	(gr_poly
		(pts
			(xy 132.3848 -278.33828) (xy 132.284724 -278.238204) (xy 132.184648 -278.33828) (xy 132.184648 -278.38273)
			(xy 132.3848 -278.38273)
		)
		(stroke
			(width 0)
			(type solid)
		)
		(fill yes)
		(layer "In2.Cu")
		(net "M_I_CPU1_SB_DQ<5>")
	)
	(gr_poly
		(pts
			(xy 132.3848 -277.93442) (xy 132.3848 -277.88997) (xy 132.184648 -277.88997) (xy 132.184648 -277.93442)
			(xy 132.284724 -278.034496)
		)
		(stroke
			(width 0)
			(type solid)
		)
		(fill yes)
		(layer "In2.Cu")
		(net "M_I_CPU1_SB_DQ<6>")
	)
	(gr_poly
		(pts
			(xy 132.3848 -276.718014) (xy 132.284724 -276.618192) (xy 132.184648 -276.718014) (xy 132.184648 -276.765766)
			(xy 132.3848 -276.765766)
		)
		(stroke
			(width 0)
			(type solid)
		)
		(fill yes)
		(layer "In2.Cu")
		(net "M_I_CPU1_SB_DQS_DN<5>")
	)
	(gr_poly
		(pts
			(xy 132.3848 -276.314662) (xy 132.3848 -276.26691) (xy 132.184648 -276.26691) (xy 132.184648 -276.314662)
			(xy 132.284724 -276.414484)
		)
		(stroke
			(width 0)
			(type solid)
		)
		(fill yes)
		(layer "In2.Cu")
		(net "M_I_CPU1_SB_DQS_DN<0>")
	)
	(gr_poly
		(pts
			(xy 132.3848 -275.098256) (xy 132.284724 -274.99818) (xy 132.184648 -275.098256) (xy 132.184648 -275.142706)
			(xy 132.3848 -275.142706)
		)
		(stroke
			(width 0)
			(type solid)
		)
		(fill yes)
		(layer "In2.Cu")
		(net "M_I_CPU1_SB_DQ<1>")
	)
	(gr_poly
		(pts
			(xy 132.3848 -274.694396) (xy 132.3848 -274.649946) (xy 132.184648 -274.649946) (xy 132.184648 -274.694396)
			(xy 132.284724 -274.794472)
		)
		(stroke
			(width 0)
			(type solid)
		)
		(fill yes)
		(layer "In2.Cu")
		(net "M_I_CPU1_SB_DQ<2>")
	)
	(gr_poly
		(pts
			(xy 132.3848 -273.478244) (xy 132.284724 -273.378168) (xy 132.184648 -273.478244) (xy 132.184648 -273.522694)
			(xy 132.3848 -273.522694)
		)
		(stroke
			(width 0)
			(type solid)
		)
		(fill yes)
		(layer "In2.Cu")
		(net "M_I_CPU1_SB_CB<1>")
	)
	(gr_poly
		(pts
			(xy 132.3848 -273.074384) (xy 132.3848 -273.029934) (xy 132.184648 -273.029934) (xy 132.184648 -273.074384)
			(xy 132.284724 -273.17446)
		)
		(stroke
			(width 0)
			(type solid)
		)
		(fill yes)
		(layer "In2.Cu")
		(net "M_I_CPU1_SB_CB<2>")
	)
	(gr_poly
		(pts
			(xy 132.3848 -271.857978) (xy 132.284724 -271.758156) (xy 132.184648 -271.857978) (xy 132.184648 -271.90573)
			(xy 132.3848 -271.90573)
		)
		(stroke
			(width 0)
			(type solid)
		)
		(fill yes)
		(layer "In2.Cu")
		(net "M_I_CPU1_SB_DQS_DN<4>")
	)
	(gr_poly
		(pts
			(xy 132.3848 -271.454626) (xy 132.3848 -271.406874) (xy 132.184648 -271.406874) (xy 132.184648 -271.454626)
			(xy 132.284724 -271.554448)
		)
		(stroke
			(width 0)
			(type solid)
		)
		(fill yes)
		(layer "In2.Cu")
		(net "M_I_CPU1_SB_DQS_DN<9>")
	)
	(gr_poly
		(pts
			(xy 132.3848 -270.23822) (xy 132.284724 -270.138144) (xy 132.184648 -270.23822) (xy 132.184648 -270.28267)
			(xy 132.3848 -270.28267)
		)
		(stroke
			(width 0)
			(type solid)
		)
		(fill yes)
		(layer "In2.Cu")
		(net "M_I_CPU1_SB_CB<5>")
	)
	(gr_poly
		(pts
			(xy 132.3848 -269.83436) (xy 132.3848 -269.78991) (xy 132.184648 -269.78991) (xy 132.184648 -269.83436)
			(xy 132.284724 -269.934436)
		)
		(stroke
			(width 0)
			(type solid)
		)
		(fill yes)
		(layer "In2.Cu")
		(net "M_I_CPU1_SB_CB<6>")
	)
	(gr_poly
		(pts
			(xy 132.3848 -266.998196) (xy 132.284724 -266.89812) (xy 132.184648 -266.998196) (xy 132.184648 -267.042646)
			(xy 132.3848 -267.042646)
		)
		(stroke
			(width 0)
			(type solid)
		)
		(fill yes)
		(layer "In2.Cu")
		(net "M_I_CPU1_SA_RSP<0>")
	)
	(gr_poly
		(pts
			(xy 132.3848 -266.594336) (xy 132.3848 -266.549886) (xy 132.184648 -266.549886) (xy 132.184648 -266.594336)
			(xy 132.284724 -266.694412)
		)
		(stroke
			(width 0)
			(type solid)
		)
		(fill yes)
		(layer "In2.Cu")
		(net "M_I_CPU1_SB_CS_N<1>")
	)
	(gr_poly
		(pts
			(xy 132.3848 -265.378184) (xy 132.284724 -265.278108) (xy 132.184648 -265.378184) (xy 132.184648 -265.422634)
			(xy 132.3848 -265.422634)
		)
		(stroke
			(width 0)
			(type solid)
		)
		(fill yes)
		(layer "In2.Cu")
		(net "M_I_CPU1_SB_PAR")
	)
	(gr_poly
		(pts
			(xy 132.3848 -263.758172) (xy 132.284724 -263.658096) (xy 132.184648 -263.758172) (xy 132.184648 -263.802622)
			(xy 132.3848 -263.802622)
		)
		(stroke
			(width 0)
			(type solid)
		)
		(fill yes)
		(layer "In2.Cu")
		(net "M_I_CPU1_SB_CA<4>")
	)
	(gr_poly
		(pts
			(xy 132.3848 -263.354312) (xy 132.3848 -263.309862) (xy 132.184648 -263.309862) (xy 132.184648 -263.354312)
			(xy 132.284724 -263.454388)
		)
		(stroke
			(width 0)
			(type solid)
		)
		(fill yes)
		(layer "In2.Cu")
		(net "M_I_CPU1_SB_CA<3>")
	)
	(gr_poly
		(pts
			(xy 132.3848 -262.13816) (xy 132.284724 -262.038084) (xy 132.184648 -262.13816) (xy 132.184648 -262.18261)
			(xy 132.3848 -262.18261)
		)
		(stroke
			(width 0)
			(type solid)
		)
		(fill yes)
		(layer "In2.Cu")
		(net "M_I_CPU1_SB_CA<0>")
	)
	(gr_poly
		(pts
			(xy 132.554726 -256.432812) (xy 132.554726 -256.38506) (xy 132.354574 -256.38506) (xy 132.354574 -256.432812)
			(xy 132.45465 -256.532634)
		)
		(stroke
			(width 0)
			(type solid)
		)
		(fill yes)
		(layer "In2.Cu")
		(net "M_I_CPU1_CLK_DN<0>")
	)
	(gr_poly
		(pts
			(xy 132.554726 -255.216406) (xy 132.45465 -255.11633) (xy 132.354574 -255.216406) (xy 132.354574 -255.260856)
			(xy 132.554726 -255.260856)
		)
		(stroke
			(width 0)
			(type solid)
		)
		(fill yes)
		(layer "In2.Cu")
		(net "M_I_CPU1_SA_CA<6>")
	)
	(gr_poly
		(pts
			(xy 132.554726 -254.812546) (xy 132.554726 -254.768096) (xy 132.354574 -254.768096) (xy 132.354574 -254.812546)
			(xy 132.45465 -254.912622)
		)
		(stroke
			(width 0)
			(type solid)
		)
		(fill yes)
		(layer "In2.Cu")
		(net "M_I_CPU1_SA_CA<5>")
	)
	(gr_poly
		(pts
			(xy 132.554726 -253.596394) (xy 132.45465 -253.496318) (xy 132.354574 -253.596394) (xy 132.354574 -253.640844)
			(xy 132.554726 -253.640844)
		)
		(stroke
			(width 0)
			(type solid)
		)
		(fill yes)
		(layer "In2.Cu")
		(net "M_I_CPU1_SA_CA<2>")
	)
	(gr_poly
		(pts
			(xy 132.554726 -253.192534) (xy 132.554726 -253.148084) (xy 132.354574 -253.148084) (xy 132.354574 -253.192534)
			(xy 132.45465 -253.29261)
		)
		(stroke
			(width 0)
			(type solid)
		)
		(fill yes)
		(layer "In2.Cu")
		(net "M_I_CPU1_SA_CA<1>")
	)
	(gr_poly
		(pts
			(xy 132.554726 -251.976382) (xy 132.45465 -251.876306) (xy 132.354574 -251.976382) (xy 132.354574 -252.020832)
			(xy 132.554726 -252.020832)
		)
		(stroke
			(width 0)
			(type solid)
		)
		(fill yes)
		(layer "In2.Cu")
		(net "M_I_CPU1_SA_CS_N<1>")
	)
	(gr_poly
		(pts
			(xy 132.554726 -250.35637) (xy 132.45465 -250.256294) (xy 132.354574 -250.35637) (xy 132.354574 -250.40082)
			(xy 132.554726 -250.40082)
		)
		(stroke
			(width 0)
			(type solid)
		)
		(fill yes)
		(layer "In2.Cu")
		(net "M_I_CPU1_ALERT_R_N")
	)
	(gr_poly
		(pts
			(xy 132.554726 -248.736358) (xy 132.45465 -248.636282) (xy 132.354574 -248.736358) (xy 132.354574 -248.780808)
			(xy 132.554726 -248.780808)
		)
		(stroke
			(width 0)
			(type solid)
		)
		(fill yes)
		(layer "In2.Cu")
		(net "M_I_CPU1_SA_CB<5>")
	)
	(gr_poly
		(pts
			(xy 132.554726 -248.332498) (xy 132.554726 -248.288048) (xy 132.354574 -248.288048) (xy 132.354574 -248.332498)
			(xy 132.45465 -248.432574)
		)
		(stroke
			(width 0)
			(type solid)
		)
		(fill yes)
		(layer "In2.Cu")
		(net "M_I_CPU1_SA_CB<6>")
	)
	(gr_poly
		(pts
			(xy 132.554726 -247.116092) (xy 132.45465 -247.01627) (xy 132.354574 -247.116092) (xy 132.354574 -247.163844)
			(xy 132.554726 -247.163844)
		)
		(stroke
			(width 0)
			(type solid)
		)
		(fill yes)
		(layer "In2.Cu")
		(net "M_I_CPU1_SA_DQS_DN<9>")
	)
	(gr_poly
		(pts
			(xy 132.554726 -246.71274) (xy 132.554726 -246.664988) (xy 132.354574 -246.664988) (xy 132.354574 -246.71274)
			(xy 132.45465 -246.812562)
		)
		(stroke
			(width 0)
			(type solid)
		)
		(fill yes)
		(layer "In2.Cu")
		(net "M_I_CPU1_SA_DQS_DN<4>")
	)
	(gr_poly
		(pts
			(xy 132.554726 -245.496334) (xy 132.45465 -245.396258) (xy 132.354574 -245.496334) (xy 132.354574 -245.540784)
			(xy 132.554726 -245.540784)
		)
		(stroke
			(width 0)
			(type solid)
		)
		(fill yes)
		(layer "In2.Cu")
		(net "M_I_CPU1_SA_CB<1>")
	)
	(gr_poly
		(pts
			(xy 132.554726 -245.092474) (xy 132.554726 -245.048024) (xy 132.354574 -245.048024) (xy 132.354574 -245.092474)
			(xy 132.45465 -245.19255)
		)
		(stroke
			(width 0)
			(type solid)
		)
		(fill yes)
		(layer "In2.Cu")
		(net "M_I_CPU1_SA_CB<2>")
	)
	(gr_poly
		(pts
			(xy 132.554726 -243.876322) (xy 132.45465 -243.776246) (xy 132.354574 -243.876322) (xy 132.354574 -243.920772)
			(xy 132.554726 -243.920772)
		)
		(stroke
			(width 0)
			(type solid)
		)
		(fill yes)
		(layer "In2.Cu")
		(net "M_I_CPU1_SA_DQ<29>")
	)
	(gr_poly
		(pts
			(xy 132.554726 -243.472462) (xy 132.554726 -243.428012) (xy 132.354574 -243.428012) (xy 132.354574 -243.472462)
			(xy 132.45465 -243.572538)
		)
		(stroke
			(width 0)
			(type solid)
		)
		(fill yes)
		(layer "In2.Cu")
		(net "M_I_CPU1_SA_DQ<30>")
	)
	(gr_poly
		(pts
			(xy 132.554726 -242.256056) (xy 132.45465 -242.156234) (xy 132.354574 -242.256056) (xy 132.354574 -242.303808)
			(xy 132.554726 -242.303808)
		)
		(stroke
			(width 0)
			(type solid)
		)
		(fill yes)
		(layer "In2.Cu")
		(net "M_I_CPU1_SA_DQS_DN<8>")
	)
	(gr_poly
		(pts
			(xy 132.554726 -241.852704) (xy 132.554726 -241.804952) (xy 132.354574 -241.804952) (xy 132.354574 -241.852704)
			(xy 132.45465 -241.952526)
		)
		(stroke
			(width 0)
			(type solid)
		)
		(fill yes)
		(layer "In2.Cu")
		(net "M_I_CPU1_SA_DQS_DN<3>")
	)
	(gr_poly
		(pts
			(xy 132.554726 -240.636298) (xy 132.45465 -240.536222) (xy 132.354574 -240.636298) (xy 132.354574 -240.680748)
			(xy 132.554726 -240.680748)
		)
		(stroke
			(width 0)
			(type solid)
		)
		(fill yes)
		(layer "In2.Cu")
		(net "M_I_CPU1_SA_DQ<25>")
	)
	(gr_poly
		(pts
			(xy 132.554726 -240.232438) (xy 132.554726 -240.187988) (xy 132.354574 -240.187988) (xy 132.354574 -240.232438)
			(xy 132.45465 -240.332514)
		)
		(stroke
			(width 0)
			(type solid)
		)
		(fill yes)
		(layer "In2.Cu")
		(net "M_I_CPU1_SA_DQ<26>")
	)
	(gr_poly
		(pts
			(xy 132.554726 -239.016286) (xy 132.45465 -238.91621) (xy 132.354574 -239.016286) (xy 132.354574 -239.060736)
			(xy 132.554726 -239.060736)
		)
		(stroke
			(width 0)
			(type solid)
		)
		(fill yes)
		(layer "In2.Cu")
		(net "M_I_CPU1_SA_DQ<21>")
	)
	(gr_poly
		(pts
			(xy 132.554726 -238.612426) (xy 132.554726 -238.567976) (xy 132.354574 -238.567976) (xy 132.354574 -238.612426)
			(xy 132.45465 -238.712502)
		)
		(stroke
			(width 0)
			(type solid)
		)
		(fill yes)
		(layer "In2.Cu")
		(net "M_I_CPU1_SA_DQ<22>")
	)
	(gr_poly
		(pts
			(xy 132.554726 -237.39602) (xy 132.45465 -237.296198) (xy 132.354574 -237.39602) (xy 132.354574 -237.443772)
			(xy 132.554726 -237.443772)
		)
		(stroke
			(width 0)
			(type solid)
		)
		(fill yes)
		(layer "In2.Cu")
		(net "M_I_CPU1_SA_DQS_DN<7>")
	)
	(gr_poly
		(pts
			(xy 132.554726 -236.992668) (xy 132.554726 -236.944916) (xy 132.354574 -236.944916) (xy 132.354574 -236.992668)
			(xy 132.45465 -237.09249)
		)
		(stroke
			(width 0)
			(type solid)
		)
		(fill yes)
		(layer "In2.Cu")
		(net "M_I_CPU1_SA_DQS_DN<2>")
	)
	(gr_poly
		(pts
			(xy 132.554726 -235.776262) (xy 132.45465 -235.676186) (xy 132.354574 -235.776262) (xy 132.354574 -235.820712)
			(xy 132.554726 -235.820712)
		)
		(stroke
			(width 0)
			(type solid)
		)
		(fill yes)
		(layer "In2.Cu")
		(net "M_I_CPU1_SA_DQ<17>")
	)
	(gr_poly
		(pts
			(xy 132.554726 -235.372402) (xy 132.554726 -235.327952) (xy 132.354574 -235.327952) (xy 132.354574 -235.372402)
			(xy 132.45465 -235.472478)
		)
		(stroke
			(width 0)
			(type solid)
		)
		(fill yes)
		(layer "In2.Cu")
		(net "M_I_CPU1_SA_DQ<18>")
	)
	(gr_poly
		(pts
			(xy 132.554726 -234.15625) (xy 132.45465 -234.056174) (xy 132.354574 -234.15625) (xy 132.354574 -234.2007)
			(xy 132.554726 -234.2007)
		)
		(stroke
			(width 0)
			(type solid)
		)
		(fill yes)
		(layer "In2.Cu")
		(net "M_I_CPU1_SA_DQ<13>")
	)
	(gr_poly
		(pts
			(xy 132.554726 -233.75239) (xy 132.554726 -233.70794) (xy 132.354574 -233.70794) (xy 132.354574 -233.75239)
			(xy 132.45465 -233.852466)
		)
		(stroke
			(width 0)
			(type solid)
		)
		(fill yes)
		(layer "In2.Cu")
		(net "M_I_CPU1_SA_DQ<14>")
	)
	(gr_poly
		(pts
			(xy 132.554726 -232.535984) (xy 132.45465 -232.436162) (xy 132.354574 -232.535984) (xy 132.354574 -232.583736)
			(xy 132.554726 -232.583736)
		)
		(stroke
			(width 0)
			(type solid)
		)
		(fill yes)
		(layer "In2.Cu")
		(net "M_I_CPU1_SA_DQS_DN<6>")
	)
	(gr_poly
		(pts
			(xy 132.554726 -232.132632) (xy 132.554726 -232.08488) (xy 132.354574 -232.08488) (xy 132.354574 -232.132632)
			(xy 132.45465 -232.232454)
		)
		(stroke
			(width 0)
			(type solid)
		)
		(fill yes)
		(layer "In2.Cu")
		(net "M_I_CPU1_SA_DQS_DN<1>")
	)
	(gr_poly
		(pts
			(xy 132.554726 -230.916226) (xy 132.45465 -230.81615) (xy 132.354574 -230.916226) (xy 132.354574 -230.960676)
			(xy 132.554726 -230.960676)
		)
		(stroke
			(width 0)
			(type solid)
		)
		(fill yes)
		(layer "In2.Cu")
		(net "M_I_CPU1_SA_DQ<9>")
	)
	(gr_poly
		(pts
			(xy 132.554726 -230.51262) (xy 132.554726 -230.46817) (xy 132.354574 -230.46817) (xy 132.354574 -230.51262)
			(xy 132.45465 -230.612696)
		)
		(stroke
			(width 0)
			(type solid)
		)
		(fill yes)
		(layer "In2.Cu")
		(net "M_I_CPU1_SA_DQ<10>")
	)
	(gr_poly
		(pts
			(xy 132.554726 -229.296214) (xy 132.45465 -229.196138) (xy 132.354574 -229.296214) (xy 132.354574 -229.340664)
			(xy 132.554726 -229.340664)
		)
		(stroke
			(width 0)
			(type solid)
		)
		(fill yes)
		(layer "In2.Cu")
		(net "M_I_CPU1_SA_DQ<5>")
	)
	(gr_poly
		(pts
			(xy 132.554726 -228.892608) (xy 132.554726 -228.848158) (xy 132.354574 -228.848158) (xy 132.354574 -228.892608)
			(xy 132.45465 -228.992684)
		)
		(stroke
			(width 0)
			(type solid)
		)
		(fill yes)
		(layer "In2.Cu")
		(net "M_I_CPU1_SA_DQ<6>")
	)
	(gr_poly
		(pts
			(xy 132.554726 -227.676202) (xy 132.45465 -227.57638) (xy 132.354574 -227.676202) (xy 132.354574 -227.723954)
			(xy 132.554726 -227.723954)
		)
		(stroke
			(width 0)
			(type solid)
		)
		(fill yes)
		(layer "In2.Cu")
		(net "M_I_CPU1_SA_DQS_DN<5>")
	)
	(gr_poly
		(pts
			(xy 132.554726 -227.27285) (xy 132.554726 -227.225098) (xy 132.354574 -227.225098) (xy 132.354574 -227.27285)
			(xy 132.45465 -227.372672)
		)
		(stroke
			(width 0)
			(type solid)
		)
		(fill yes)
		(layer "In2.Cu")
		(net "M_I_CPU1_SA_DQS_DN<0>")
	)
	(gr_poly
		(pts
			(xy 132.554726 -226.056444) (xy 132.45465 -225.956368) (xy 132.354574 -226.056444) (xy 132.354574 -226.100894)
			(xy 132.554726 -226.100894)
		)
		(stroke
			(width 0)
			(type solid)
		)
		(fill yes)
		(layer "In2.Cu")
		(net "M_I_CPU1_SA_DQ<1>")
	)
	(gr_poly
		(pts
			(xy 132.554726 -225.652584) (xy 132.554726 -225.608134) (xy 132.354574 -225.608134) (xy 132.354574 -225.652584)
			(xy 132.45465 -225.75266)
		)
		(stroke
			(width 0)
			(type solid)
		)
		(fill yes)
		(layer "In2.Cu")
		(net "M_I_CPU1_SA_DQ<2>")
	)
	(gr_poly
		(pts
			(xy 132.8547 -262.544306) (xy 132.8547 -262.499856) (xy 132.654548 -262.499856) (xy 132.654548 -262.544306)
			(xy 132.754624 -262.644382)
		)
		(stroke
			(width 0)
			(type solid)
		)
		(fill yes)
		(layer "In2.Cu")
		(net "M_I_CPU1_SB_CA<1>")
	)
	(gr_poly
		(pts
			(xy 132.854954 -293.32428) (xy 132.854954 -293.27983) (xy 132.654802 -293.27983) (xy 132.654802 -293.32428)
			(xy 132.754878 -293.424356)
		)
		(stroke
			(width 0)
			(type solid)
		)
		(fill yes)
		(layer "In2.Cu")
		(net "M_I_CPU1_SB_DQ<31>")
	)
	(gr_poly
		(pts
			(xy 132.854954 -292.108128) (xy 132.754878 -292.008052) (xy 132.654802 -292.108128) (xy 132.654802 -292.152578)
			(xy 132.854954 -292.152578)
		)
		(stroke
			(width 0)
			(type solid)
		)
		(fill yes)
		(layer "In2.Cu")
		(net "M_I_CPU1_SB_DQ<28>")
	)
	(gr_poly
		(pts
			(xy 132.854954 -291.704522) (xy 132.854954 -291.65677) (xy 132.654802 -291.65677) (xy 132.654802 -291.704522)
			(xy 132.754878 -291.804344)
		)
		(stroke
			(width 0)
			(type solid)
		)
		(fill yes)
		(layer "In2.Cu")
		(net "M_I_CPU1_SB_DQS_DP<8>")
	)
	(gr_poly
		(pts
			(xy 132.854954 -290.487862) (xy 132.754878 -290.38804) (xy 132.654802 -290.487862) (xy 132.654802 -290.535614)
			(xy 132.854954 -290.535614)
		)
		(stroke
			(width 0)
			(type solid)
		)
		(fill yes)
		(layer "In2.Cu")
		(net "M_I_CPU1_SB_DQS_DP<3>")
	)
	(gr_poly
		(pts
			(xy 132.854954 -290.084256) (xy 132.854954 -290.039806) (xy 132.654802 -290.039806) (xy 132.654802 -290.084256)
			(xy 132.754878 -290.184332)
		)
		(stroke
			(width 0)
			(type solid)
		)
		(fill yes)
		(layer "In2.Cu")
		(net "M_I_CPU1_SB_DQ<27>")
	)
	(gr_poly
		(pts
			(xy 132.854954 -288.868104) (xy 132.754878 -288.768028) (xy 132.654802 -288.868104) (xy 132.654802 -288.912554)
			(xy 132.854954 -288.912554)
		)
		(stroke
			(width 0)
			(type solid)
		)
		(fill yes)
		(layer "In2.Cu")
		(net "M_I_CPU1_SB_DQ<24>")
	)
	(gr_poly
		(pts
			(xy 132.854954 -288.464498) (xy 132.854954 -288.420048) (xy 132.654802 -288.420048) (xy 132.654802 -288.464498)
			(xy 132.754878 -288.564574)
		)
		(stroke
			(width 0)
			(type solid)
		)
		(fill yes)
		(layer "In2.Cu")
		(net "M_I_CPU1_SB_DQ<23>")
	)
	(gr_poly
		(pts
			(xy 132.854954 -287.248092) (xy 132.754878 -287.148016) (xy 132.654802 -287.248092) (xy 132.654802 -287.292542)
			(xy 132.854954 -287.292542)
		)
		(stroke
			(width 0)
			(type solid)
		)
		(fill yes)
		(layer "In2.Cu")
		(net "M_I_CPU1_SB_DQ<20>")
	)
	(gr_poly
		(pts
			(xy 132.854954 -286.844486) (xy 132.854954 -286.796734) (xy 132.654802 -286.796734) (xy 132.654802 -286.844486)
			(xy 132.754878 -286.944562)
		)
		(stroke
			(width 0)
			(type solid)
		)
		(fill yes)
		(layer "In2.Cu")
		(net "M_I_CPU1_SB_DQS_DP<7>")
	)
	(gr_poly
		(pts
			(xy 132.854954 -285.62808) (xy 132.754878 -285.528258) (xy 132.654802 -285.62808) (xy 132.654802 -285.675832)
			(xy 132.854954 -285.675832)
		)
		(stroke
			(width 0)
			(type solid)
		)
		(fill yes)
		(layer "In2.Cu")
		(net "M_I_CPU1_SB_DQS_DP<2>")
	)
	(gr_poly
		(pts
			(xy 132.854954 -285.224474) (xy 132.854954 -285.180024) (xy 132.654802 -285.180024) (xy 132.654802 -285.224474)
			(xy 132.754878 -285.32455)
		)
		(stroke
			(width 0)
			(type solid)
		)
		(fill yes)
		(layer "In2.Cu")
		(net "M_I_CPU1_SB_DQ<19>")
	)
	(gr_poly
		(pts
			(xy 132.854954 -284.008322) (xy 132.754878 -283.908246) (xy 132.654802 -284.008322) (xy 132.654802 -284.052772)
			(xy 132.854954 -284.052772)
		)
		(stroke
			(width 0)
			(type solid)
		)
		(fill yes)
		(layer "In2.Cu")
		(net "M_I_CPU1_SB_DQ<16>")
	)
	(gr_poly
		(pts
			(xy 132.854954 -283.604462) (xy 132.854954 -283.560012) (xy 132.654802 -283.560012) (xy 132.654802 -283.604462)
			(xy 132.754878 -283.704538)
		)
		(stroke
			(width 0)
			(type solid)
		)
		(fill yes)
		(layer "In2.Cu")
		(net "M_I_CPU1_SB_DQ<15>")
	)
	(gr_poly
		(pts
			(xy 132.854954 -282.38831) (xy 132.754878 -282.288234) (xy 132.654802 -282.38831) (xy 132.654802 -282.43276)
			(xy 132.854954 -282.43276)
		)
		(stroke
			(width 0)
			(type solid)
		)
		(fill yes)
		(layer "In2.Cu")
		(net "M_I_CPU1_SB_DQ<12>")
	)
	(gr_poly
		(pts
			(xy 132.854954 -281.984704) (xy 132.854954 -281.936952) (xy 132.654802 -281.936952) (xy 132.654802 -281.984704)
			(xy 132.754878 -282.084526)
		)
		(stroke
			(width 0)
			(type solid)
		)
		(fill yes)
		(layer "In2.Cu")
		(net "M_I_CPU1_SB_DQS_DP<6>")
	)
	(gr_poly
		(pts
			(xy 132.854954 -280.768044) (xy 132.754878 -280.668222) (xy 132.654802 -280.768044) (xy 132.654802 -280.815796)
			(xy 132.854954 -280.815796)
		)
		(stroke
			(width 0)
			(type solid)
		)
		(fill yes)
		(layer "In2.Cu")
		(net "M_I_CPU1_SB_DQS_DP<1>")
	)
	(gr_poly
		(pts
			(xy 132.854954 -280.364438) (xy 132.854954 -280.319988) (xy 132.654802 -280.319988) (xy 132.654802 -280.364438)
			(xy 132.754878 -280.464514)
		)
		(stroke
			(width 0)
			(type solid)
		)
		(fill yes)
		(layer "In2.Cu")
		(net "M_I_CPU1_SB_DQ<11>")
	)
	(gr_poly
		(pts
			(xy 132.854954 -279.148286) (xy 132.754878 -279.04821) (xy 132.654802 -279.148286) (xy 132.654802 -279.192736)
			(xy 132.854954 -279.192736)
		)
		(stroke
			(width 0)
			(type solid)
		)
		(fill yes)
		(layer "In2.Cu")
		(net "M_I_CPU1_SB_DQ<8>")
	)
	(gr_poly
		(pts
			(xy 132.854954 -278.744426) (xy 132.854954 -278.699976) (xy 132.654802 -278.699976) (xy 132.654802 -278.744426)
			(xy 132.754878 -278.844502)
		)
		(stroke
			(width 0)
			(type solid)
		)
		(fill yes)
		(layer "In2.Cu")
		(net "M_I_CPU1_SB_DQ<7>")
	)
	(gr_poly
		(pts
			(xy 132.854954 -277.528274) (xy 132.754878 -277.428198) (xy 132.654802 -277.528274) (xy 132.654802 -277.572724)
			(xy 132.854954 -277.572724)
		)
		(stroke
			(width 0)
			(type solid)
		)
		(fill yes)
		(layer "In2.Cu")
		(net "M_I_CPU1_SB_DQ<4>")
	)
	(gr_poly
		(pts
			(xy 132.854954 -277.124668) (xy 132.854954 -277.076916) (xy 132.654802 -277.076916) (xy 132.654802 -277.124668)
			(xy 132.754878 -277.22449)
		)
		(stroke
			(width 0)
			(type solid)
		)
		(fill yes)
		(layer "In2.Cu")
		(net "M_I_CPU1_SB_DQS_DP<5>")
	)
	(gr_poly
		(pts
			(xy 132.854954 -275.908008) (xy 132.754878 -275.808186) (xy 132.654802 -275.908008) (xy 132.654802 -275.95576)
			(xy 132.854954 -275.95576)
		)
		(stroke
			(width 0)
			(type solid)
		)
		(fill yes)
		(layer "In2.Cu")
		(net "M_I_CPU1_SB_DQS_DP<0>")
	)
	(gr_poly
		(pts
			(xy 132.854954 -275.504402) (xy 132.854954 -275.459952) (xy 132.654802 -275.459952) (xy 132.654802 -275.504402)
			(xy 132.754878 -275.604478)
		)
		(stroke
			(width 0)
			(type solid)
		)
		(fill yes)
		(layer "In2.Cu")
		(net "M_I_CPU1_SB_DQ<3>")
	)
	(gr_poly
		(pts
			(xy 132.854954 -274.28825) (xy 132.754878 -274.188174) (xy 132.654802 -274.28825) (xy 132.654802 -274.3327)
			(xy 132.854954 -274.3327)
		)
		(stroke
			(width 0)
			(type solid)
		)
		(fill yes)
		(layer "In2.Cu")
		(net "M_I_CPU1_SB_DQ<0>")
	)
	(gr_poly
		(pts
			(xy 132.854954 -273.88439) (xy 132.854954 -273.83994) (xy 132.654802 -273.83994) (xy 132.654802 -273.88439)
			(xy 132.754878 -273.984466)
		)
		(stroke
			(width 0)
			(type solid)
		)
		(fill yes)
		(layer "In2.Cu")
		(net "M_I_CPU1_SB_CB<3>")
	)
	(gr_poly
		(pts
			(xy 132.854954 -272.668238) (xy 132.754878 -272.568162) (xy 132.654802 -272.668238) (xy 132.654802 -272.712688)
			(xy 132.854954 -272.712688)
		)
		(stroke
			(width 0)
			(type solid)
		)
		(fill yes)
		(layer "In2.Cu")
		(net "M_I_CPU1_SB_CB<0>")
	)
	(gr_poly
		(pts
			(xy 132.854954 -272.264632) (xy 132.854954 -272.21688) (xy 132.654802 -272.21688) (xy 132.654802 -272.264632)
			(xy 132.754878 -272.364454)
		)
		(stroke
			(width 0)
			(type solid)
		)
		(fill yes)
		(layer "In2.Cu")
		(net "M_I_CPU1_SB_DQS_DP<4>")
	)
	(gr_poly
		(pts
			(xy 132.854954 -271.047972) (xy 132.754878 -270.94815) (xy 132.654802 -271.047972) (xy 132.654802 -271.095724)
			(xy 132.854954 -271.095724)
		)
		(stroke
			(width 0)
			(type solid)
		)
		(fill yes)
		(layer "In2.Cu")
		(net "M_I_CPU1_SB_DQS_DP<9>")
	)
	(gr_poly
		(pts
			(xy 132.854954 -270.644366) (xy 132.854954 -270.599916) (xy 132.654802 -270.599916) (xy 132.654802 -270.644366)
			(xy 132.754878 -270.744442)
		)
		(stroke
			(width 0)
			(type solid)
		)
		(fill yes)
		(layer "In2.Cu")
		(net "M_I_CPU1_SB_CB<7>")
	)
	(gr_poly
		(pts
			(xy 132.854954 -269.428214) (xy 132.754878 -269.328138) (xy 132.654802 -269.428214) (xy 132.654802 -269.472664)
			(xy 132.854954 -269.472664)
		)
		(stroke
			(width 0)
			(type solid)
		)
		(fill yes)
		(layer "In2.Cu")
		(net "M_I_CPU1_SB_CB<4>")
	)
	(gr_poly
		(pts
			(xy 132.854954 -267.404342) (xy 132.854954 -267.359892) (xy 132.654802 -267.359892) (xy 132.654802 -267.404342)
			(xy 132.754878 -267.504418)
		)
		(stroke
			(width 0)
			(type solid)
		)
		(fill yes)
		(layer "In2.Cu")
		(net "M_I_CPU1_SB_RSP<0>")
	)
	(gr_poly
		(pts
			(xy 132.854954 -265.78433) (xy 132.854954 -265.73988) (xy 132.654802 -265.73988) (xy 132.654802 -265.78433)
			(xy 132.754878 -265.884406)
		)
		(stroke
			(width 0)
			(type solid)
		)
		(fill yes)
		(layer "In2.Cu")
		(net "M_I_CPU1_SB_CS_N<0>")
	)
	(gr_poly
		(pts
			(xy 132.854954 -264.568178) (xy 132.754878 -264.468102) (xy 132.654802 -264.568178) (xy 132.654802 -264.612628)
			(xy 132.854954 -264.612628)
		)
		(stroke
			(width 0)
			(type solid)
		)
		(fill yes)
		(layer "In2.Cu")
		(net "M_I_CPU1_SB_CA<6>")
	)
	(gr_poly
		(pts
			(xy 132.854954 -264.164318) (xy 132.854954 -264.119868) (xy 132.654802 -264.119868) (xy 132.654802 -264.164318)
			(xy 132.754878 -264.264394)
		)
		(stroke
			(width 0)
			(type solid)
		)
		(fill yes)
		(layer "In2.Cu")
		(net "M_I_CPU1_SB_CA<5>")
	)
	(gr_poly
		(pts
			(xy 132.854954 -262.948166) (xy 132.754878 -262.84809) (xy 132.654802 -262.948166) (xy 132.654802 -262.992616)
			(xy 132.854954 -262.992616)
		)
		(stroke
			(width 0)
			(type solid)
		)
		(fill yes)
		(layer "In2.Cu")
		(net "M_I_CPU1_SB_CA<2>")
	)
	(gr_poly
		(pts
			(xy 133.02488 -256.026158) (xy 132.924804 -255.926336) (xy 132.824728 -256.026158) (xy 132.824728 -256.07391)
			(xy 133.02488 -256.07391)
		)
		(stroke
			(width 0)
			(type solid)
		)
		(fill yes)
		(layer "In2.Cu")
		(net "M_I_CPU1_CLK_DP<0>")
	)
	(gr_poly
		(pts
			(xy 133.02488 -255.622552) (xy 133.02488 -255.578102) (xy 132.824728 -255.578102) (xy 132.824728 -255.622552)
			(xy 132.924804 -255.722628)
		)
		(stroke
			(width 0)
			(type solid)
		)
		(fill yes)
		(layer "In2.Cu")
		(net "M_I_CPU1_SA_PAR")
	)
	(gr_poly
		(pts
			(xy 133.02488 -254.4064) (xy 132.924804 -254.306324) (xy 132.824728 -254.4064) (xy 132.824728 -254.45085)
			(xy 133.02488 -254.45085)
		)
		(stroke
			(width 0)
			(type solid)
		)
		(fill yes)
		(layer "In2.Cu")
		(net "M_I_CPU1_SA_CA<4>")
	)
	(gr_poly
		(pts
			(xy 133.02488 -254.00254) (xy 133.02488 -253.95809) (xy 132.824728 -253.95809) (xy 132.824728 -254.00254)
			(xy 132.924804 -254.102616)
		)
		(stroke
			(width 0)
			(type solid)
		)
		(fill yes)
		(layer "In2.Cu")
		(net "M_I_CPU1_SA_CA<3>")
	)
	(gr_poly
		(pts
			(xy 133.02488 -252.786388) (xy 132.924804 -252.686312) (xy 132.824728 -252.786388) (xy 132.824728 -252.830838)
			(xy 133.02488 -252.830838)
		)
		(stroke
			(width 0)
			(type solid)
		)
		(fill yes)
		(layer "In2.Cu")
		(net "M_I_CPU1_SA_CA<0>")
	)
	(gr_poly
		(pts
			(xy 133.02488 -251.166376) (xy 132.924804 -251.0663) (xy 132.824728 -251.166376) (xy 132.824728 -251.210826)
			(xy 133.02488 -251.210826)
		)
		(stroke
			(width 0)
			(type solid)
		)
		(fill yes)
		(layer "In2.Cu")
		(net "M_I_CPU1_SA_CS_N<0>")
	)
	(gr_poly
		(pts
			(xy 133.02488 -250.762516) (xy 133.02488 -250.718066) (xy 132.824728 -250.718066) (xy 132.824728 -250.762516)
			(xy 132.924804 -250.862592)
		)
		(stroke
			(width 0)
			(type solid)
		)
		(fill yes)
		(layer "In2.Cu")
		(net "M_I_CPU1_RESET_N")
	)
	(gr_poly
		(pts
			(xy 133.02488 -249.142504) (xy 133.02488 -249.098054) (xy 132.824728 -249.098054) (xy 132.824728 -249.142504)
			(xy 132.924804 -249.24258)
		)
		(stroke
			(width 0)
			(type solid)
		)
		(fill yes)
		(layer "In2.Cu")
		(net "M_I_CPU1_SA_CB<7>")
	)
	(gr_poly
		(pts
			(xy 133.02488 -247.926352) (xy 132.924804 -247.826276) (xy 132.824728 -247.926352) (xy 132.824728 -247.970802)
			(xy 133.02488 -247.970802)
		)
		(stroke
			(width 0)
			(type solid)
		)
		(fill yes)
		(layer "In2.Cu")
		(net "M_I_CPU1_SA_CB<4>")
	)
	(gr_poly
		(pts
			(xy 133.02488 -247.522746) (xy 133.02488 -247.474994) (xy 132.824728 -247.474994) (xy 132.824728 -247.522746)
			(xy 132.924804 -247.622568)
		)
		(stroke
			(width 0)
			(type solid)
		)
		(fill yes)
		(layer "In2.Cu")
		(net "M_I_CPU1_SA_DQS_DP<9>")
	)
	(gr_poly
		(pts
			(xy 133.02488 -246.306086) (xy 132.924804 -246.206264) (xy 132.824728 -246.306086) (xy 132.824728 -246.353838)
			(xy 133.02488 -246.353838)
		)
		(stroke
			(width 0)
			(type solid)
		)
		(fill yes)
		(layer "In2.Cu")
		(net "M_I_CPU1_SA_DQS_DP<4>")
	)
	(gr_poly
		(pts
			(xy 133.02488 -245.90248) (xy 133.02488 -245.85803) (xy 132.824728 -245.85803) (xy 132.824728 -245.90248)
			(xy 132.924804 -246.002556)
		)
		(stroke
			(width 0)
			(type solid)
		)
		(fill yes)
		(layer "In2.Cu")
		(net "M_I_CPU1_SA_CB<3>")
	)
	(gr_poly
		(pts
			(xy 133.02488 -244.686328) (xy 132.924804 -244.586252) (xy 132.824728 -244.686328) (xy 132.824728 -244.730778)
			(xy 133.02488 -244.730778)
		)
		(stroke
			(width 0)
			(type solid)
		)
		(fill yes)
		(layer "In2.Cu")
		(net "M_I_CPU1_SA_CB<0>")
	)
	(gr_poly
		(pts
			(xy 133.02488 -244.282468) (xy 133.02488 -244.238018) (xy 132.824728 -244.238018) (xy 132.824728 -244.282468)
			(xy 132.924804 -244.382544)
		)
		(stroke
			(width 0)
			(type solid)
		)
		(fill yes)
		(layer "In2.Cu")
		(net "M_I_CPU1_SA_DQ<31>")
	)
	(gr_poly
		(pts
			(xy 133.02488 -243.066316) (xy 132.924804 -242.96624) (xy 132.824728 -243.066316) (xy 132.824728 -243.110766)
			(xy 133.02488 -243.110766)
		)
		(stroke
			(width 0)
			(type solid)
		)
		(fill yes)
		(layer "In2.Cu")
		(net "M_I_CPU1_SA_DQ<28>")
	)
	(gr_poly
		(pts
			(xy 133.02488 -242.66271) (xy 133.02488 -242.614958) (xy 132.824728 -242.614958) (xy 132.824728 -242.66271)
			(xy 132.924804 -242.762532)
		)
		(stroke
			(width 0)
			(type solid)
		)
		(fill yes)
		(layer "In2.Cu")
		(net "M_I_CPU1_SA_DQS_DP<8>")
	)
	(gr_poly
		(pts
			(xy 133.02488 -241.44605) (xy 132.924804 -241.346228) (xy 132.824728 -241.44605) (xy 132.824728 -241.493802)
			(xy 133.02488 -241.493802)
		)
		(stroke
			(width 0)
			(type solid)
		)
		(fill yes)
		(layer "In2.Cu")
		(net "M_I_CPU1_SA_DQS_DP<3>")
	)
	(gr_poly
		(pts
			(xy 133.02488 -241.042444) (xy 133.02488 -240.997994) (xy 132.824728 -240.997994) (xy 132.824728 -241.042444)
			(xy 132.924804 -241.14252)
		)
		(stroke
			(width 0)
			(type solid)
		)
		(fill yes)
		(layer "In2.Cu")
		(net "M_I_CPU1_SA_DQ<27>")
	)
	(gr_poly
		(pts
			(xy 133.02488 -239.826292) (xy 132.924804 -239.726216) (xy 132.824728 -239.826292) (xy 132.824728 -239.870742)
			(xy 133.02488 -239.870742)
		)
		(stroke
			(width 0)
			(type solid)
		)
		(fill yes)
		(layer "In2.Cu")
		(net "M_I_CPU1_SA_DQ<24>")
	)
	(gr_poly
		(pts
			(xy 133.02488 -239.422432) (xy 133.02488 -239.377982) (xy 132.824728 -239.377982) (xy 132.824728 -239.422432)
			(xy 132.924804 -239.522508)
		)
		(stroke
			(width 0)
			(type solid)
		)
		(fill yes)
		(layer "In2.Cu")
		(net "M_I_CPU1_SA_DQ<23>")
	)
	(gr_poly
		(pts
			(xy 133.02488 -238.20628) (xy 132.924804 -238.106204) (xy 132.824728 -238.20628) (xy 132.824728 -238.25073)
			(xy 133.02488 -238.25073)
		)
		(stroke
			(width 0)
			(type solid)
		)
		(fill yes)
		(layer "In2.Cu")
		(net "M_I_CPU1_SA_DQ<20>")
	)
	(gr_poly
		(pts
			(xy 133.02488 -237.802674) (xy 133.02488 -237.754922) (xy 132.824728 -237.754922) (xy 132.824728 -237.802674)
			(xy 132.924804 -237.902496)
		)
		(stroke
			(width 0)
			(type solid)
		)
		(fill yes)
		(layer "In2.Cu")
		(net "M_I_CPU1_SA_DQS_DP<7>")
	)
	(gr_poly
		(pts
			(xy 133.02488 -236.586014) (xy 132.924804 -236.486192) (xy 132.824728 -236.586014) (xy 132.824728 -236.633766)
			(xy 133.02488 -236.633766)
		)
		(stroke
			(width 0)
			(type solid)
		)
		(fill yes)
		(layer "In2.Cu")
		(net "M_I_CPU1_SA_DQS_DP<2>")
	)
	(gr_poly
		(pts
			(xy 133.02488 -236.182408) (xy 133.02488 -236.137958) (xy 132.824728 -236.137958) (xy 132.824728 -236.182408)
			(xy 132.924804 -236.282484)
		)
		(stroke
			(width 0)
			(type solid)
		)
		(fill yes)
		(layer "In2.Cu")
		(net "M_I_CPU1_SA_DQ<19>")
	)
	(gr_poly
		(pts
			(xy 133.02488 -234.966256) (xy 132.924804 -234.86618) (xy 132.824728 -234.966256) (xy 132.824728 -235.010706)
			(xy 133.02488 -235.010706)
		)
		(stroke
			(width 0)
			(type solid)
		)
		(fill yes)
		(layer "In2.Cu")
		(net "M_I_CPU1_SA_DQ<16>")
	)
	(gr_poly
		(pts
			(xy 133.02488 -234.562396) (xy 133.02488 -234.517946) (xy 132.824728 -234.517946) (xy 132.824728 -234.562396)
			(xy 132.924804 -234.662472)
		)
		(stroke
			(width 0)
			(type solid)
		)
		(fill yes)
		(layer "In2.Cu")
		(net "M_I_CPU1_SA_DQ<15>")
	)
	(gr_poly
		(pts
			(xy 133.02488 -233.346244) (xy 132.924804 -233.246168) (xy 132.824728 -233.346244) (xy 132.824728 -233.390694)
			(xy 133.02488 -233.390694)
		)
		(stroke
			(width 0)
			(type solid)
		)
		(fill yes)
		(layer "In2.Cu")
		(net "M_I_CPU1_SA_DQ<12>")
	)
	(gr_poly
		(pts
			(xy 133.02488 -232.942638) (xy 133.02488 -232.894886) (xy 132.824728 -232.894886) (xy 132.824728 -232.942638)
			(xy 132.924804 -233.04246)
		)
		(stroke
			(width 0)
			(type solid)
		)
		(fill yes)
		(layer "In2.Cu")
		(net "M_I_CPU1_SA_DQS_DP<6>")
	)
	(gr_poly
		(pts
			(xy 133.02488 -231.725978) (xy 132.924804 -231.626156) (xy 132.824728 -231.725978) (xy 132.824728 -231.77373)
			(xy 133.02488 -231.77373)
		)
		(stroke
			(width 0)
			(type solid)
		)
		(fill yes)
		(layer "In2.Cu")
		(net "M_I_CPU1_SA_DQS_DP<1>")
	)
	(gr_poly
		(pts
			(xy 133.02488 -231.322626) (xy 133.02488 -231.278176) (xy 132.824728 -231.278176) (xy 132.824728 -231.322626)
			(xy 132.924804 -231.422702)
		)
		(stroke
			(width 0)
			(type solid)
		)
		(fill yes)
		(layer "In2.Cu")
		(net "M_I_CPU1_SA_DQ<11>")
	)
	(gr_poly
		(pts
			(xy 133.02488 -230.10622) (xy 132.924804 -230.006144) (xy 132.824728 -230.10622) (xy 132.824728 -230.15067)
			(xy 133.02488 -230.15067)
		)
		(stroke
			(width 0)
			(type solid)
		)
		(fill yes)
		(layer "In2.Cu")
		(net "M_I_CPU1_SA_DQ<8>")
	)
	(gr_poly
		(pts
			(xy 133.02488 -229.702614) (xy 133.02488 -229.658164) (xy 132.824728 -229.658164) (xy 132.824728 -229.702614)
			(xy 132.924804 -229.80269)
		)
		(stroke
			(width 0)
			(type solid)
		)
		(fill yes)
		(layer "In2.Cu")
		(net "M_I_CPU1_SA_DQ<7>")
	)
	(gr_poly
		(pts
			(xy 133.02488 -228.486462) (xy 132.924804 -228.386386) (xy 132.824728 -228.486462) (xy 132.824728 -228.530912)
			(xy 133.02488 -228.530912)
		)
		(stroke
			(width 0)
			(type solid)
		)
		(fill yes)
		(layer "In2.Cu")
		(net "M_I_CPU1_SA_DQ<4>")
	)
	(gr_poly
		(pts
			(xy 133.02488 -228.082856) (xy 133.02488 -228.035104) (xy 132.824728 -228.035104) (xy 132.824728 -228.082856)
			(xy 132.924804 -228.182678)
		)
		(stroke
			(width 0)
			(type solid)
		)
		(fill yes)
		(layer "In2.Cu")
		(net "M_I_CPU1_SA_DQS_DP<5>")
	)
	(gr_poly
		(pts
			(xy 133.02488 -226.866196) (xy 132.924804 -226.766374) (xy 132.824728 -226.866196) (xy 132.824728 -226.913948)
			(xy 133.02488 -226.913948)
		)
		(stroke
			(width 0)
			(type solid)
		)
		(fill yes)
		(layer "In2.Cu")
		(net "M_I_CPU1_SA_DQS_DP<0>")
	)
	(gr_poly
		(pts
			(xy 133.02488 -226.46259) (xy 133.02488 -226.41814) (xy 132.824728 -226.41814) (xy 132.824728 -226.46259)
			(xy 132.924804 -226.562666)
		)
		(stroke
			(width 0)
			(type solid)
		)
		(fill yes)
		(layer "In2.Cu")
		(net "M_I_CPU1_SA_DQ<3>")
	)
	(gr_poly
		(pts
			(xy 133.02488 -225.246438) (xy 132.924804 -225.146362) (xy 132.824728 -225.246438) (xy 132.824728 -225.290888)
			(xy 133.02488 -225.290888)
		)
		(stroke
			(width 0)
			(type solid)
		)
		(fill yes)
		(layer "In2.Cu")
		(net "M_I_CPU1_SA_DQ<0>")
	)
	(gr_poly
		(pts
			(xy 133.324854 -292.918134) (xy 133.224778 -292.818058) (xy 133.124702 -292.918134) (xy 133.124702 -292.962584)
			(xy 133.324854 -292.962584)
		)
		(stroke
			(width 0)
			(type solid)
		)
		(fill yes)
		(layer "In2.Cu")
		(net "M_I_CPU1_SB_DQ<29>")
	)
	(gr_poly
		(pts
			(xy 133.324854 -292.514274) (xy 133.324854 -292.469824) (xy 133.124702 -292.469824) (xy 133.124702 -292.514274)
			(xy 133.224778 -292.61435)
		)
		(stroke
			(width 0)
			(type solid)
		)
		(fill yes)
		(layer "In2.Cu")
		(net "M_I_CPU1_SB_DQ<30>")
	)
	(gr_poly
		(pts
			(xy 133.324854 -291.297868) (xy 133.224778 -291.198046) (xy 133.124702 -291.297868) (xy 133.124702 -291.34562)
			(xy 133.324854 -291.34562)
		)
		(stroke
			(width 0)
			(type solid)
		)
		(fill yes)
		(layer "In2.Cu")
		(net "M_I_CPU1_SB_DQS_DN<8>")
	)
	(gr_poly
		(pts
			(xy 133.324854 -290.894516) (xy 133.324854 -290.846764) (xy 133.124702 -290.846764) (xy 133.124702 -290.894516)
			(xy 133.224778 -290.994338)
		)
		(stroke
			(width 0)
			(type solid)
		)
		(fill yes)
		(layer "In2.Cu")
		(net "M_I_CPU1_SB_DQS_DN<3>")
	)
	(gr_poly
		(pts
			(xy 133.324854 -289.67811) (xy 133.224778 -289.578034) (xy 133.124702 -289.67811) (xy 133.124702 -289.72256)
			(xy 133.324854 -289.72256)
		)
		(stroke
			(width 0)
			(type solid)
		)
		(fill yes)
		(layer "In2.Cu")
		(net "M_I_CPU1_SB_DQ<25>")
	)
	(gr_poly
		(pts
			(xy 133.324854 -289.27425) (xy 133.324854 -289.2298) (xy 133.124702 -289.2298) (xy 133.124702 -289.27425)
			(xy 133.224778 -289.374326)
		)
		(stroke
			(width 0)
			(type solid)
		)
		(fill yes)
		(layer "In2.Cu")
		(net "M_I_CPU1_SB_DQ<26>")
	)
	(gr_poly
		(pts
			(xy 133.324854 -288.058098) (xy 133.224778 -287.958022) (xy 133.124702 -288.058098) (xy 133.124702 -288.102548)
			(xy 133.324854 -288.102548)
		)
		(stroke
			(width 0)
			(type solid)
		)
		(fill yes)
		(layer "In2.Cu")
		(net "M_I_CPU1_SB_DQ<21>")
	)
	(gr_poly
		(pts
			(xy 133.324854 -287.654492) (xy 133.324854 -287.610042) (xy 133.124702 -287.610042) (xy 133.124702 -287.654492)
			(xy 133.224778 -287.754568)
		)
		(stroke
			(width 0)
			(type solid)
		)
		(fill yes)
		(layer "In2.Cu")
		(net "M_I_CPU1_SB_DQ<22>")
	)
	(gr_poly
		(pts
			(xy 133.324854 -286.438086) (xy 133.224778 -286.33801) (xy 133.124702 -286.438086) (xy 133.124702 -286.485838)
			(xy 133.324854 -286.485838)
		)
		(stroke
			(width 0)
			(type solid)
		)
		(fill yes)
		(layer "In2.Cu")
		(net "M_I_CPU1_SB_DQS_DN<7>")
	)
	(gr_poly
		(pts
			(xy 133.324854 -286.034734) (xy 133.324854 -285.986982) (xy 133.124702 -285.986982) (xy 133.124702 -286.034734)
			(xy 133.224778 -286.134556)
		)
		(stroke
			(width 0)
			(type solid)
		)
		(fill yes)
		(layer "In2.Cu")
		(net "M_I_CPU1_SB_DQS_DN<2>")
	)
	(gr_poly
		(pts
			(xy 133.324854 -284.818328) (xy 133.224778 -284.718252) (xy 133.124702 -284.818328) (xy 133.124702 -284.862778)
			(xy 133.324854 -284.862778)
		)
		(stroke
			(width 0)
			(type solid)
		)
		(fill yes)
		(layer "In2.Cu")
		(net "M_I_CPU1_SB_DQ<17>")
	)
	(gr_poly
		(pts
			(xy 133.324854 -284.414468) (xy 133.324854 -284.370018) (xy 133.124702 -284.370018) (xy 133.124702 -284.414468)
			(xy 133.224778 -284.514544)
		)
		(stroke
			(width 0)
			(type solid)
		)
		(fill yes)
		(layer "In2.Cu")
		(net "M_I_CPU1_SB_DQ<18>")
	)
	(gr_poly
		(pts
			(xy 133.324854 -283.198316) (xy 133.224778 -283.09824) (xy 133.124702 -283.198316) (xy 133.124702 -283.242766)
			(xy 133.324854 -283.242766)
		)
		(stroke
			(width 0)
			(type solid)
		)
		(fill yes)
		(layer "In2.Cu")
		(net "M_I_CPU1_SB_DQ<13>")
	)
	(gr_poly
		(pts
			(xy 133.324854 -282.794456) (xy 133.324854 -282.750006) (xy 133.124702 -282.750006) (xy 133.124702 -282.794456)
			(xy 133.224778 -282.894532)
		)
		(stroke
			(width 0)
			(type solid)
		)
		(fill yes)
		(layer "In2.Cu")
		(net "M_I_CPU1_SB_DQ<14>")
	)
	(gr_poly
		(pts
			(xy 133.324854 -281.57805) (xy 133.224778 -281.478228) (xy 133.124702 -281.57805) (xy 133.124702 -281.625802)
			(xy 133.324854 -281.625802)
		)
		(stroke
			(width 0)
			(type solid)
		)
		(fill yes)
		(layer "In2.Cu")
		(net "M_I_CPU1_SB_DQS_DN<6>")
	)
	(gr_poly
		(pts
			(xy 133.324854 -281.174698) (xy 133.324854 -281.126946) (xy 133.124702 -281.126946) (xy 133.124702 -281.174698)
			(xy 133.224778 -281.27452)
		)
		(stroke
			(width 0)
			(type solid)
		)
		(fill yes)
		(layer "In2.Cu")
		(net "M_I_CPU1_SB_DQS_DN<1>")
	)
	(gr_poly
		(pts
			(xy 133.324854 -279.958292) (xy 133.224778 -279.858216) (xy 133.124702 -279.958292) (xy 133.124702 -280.002742)
			(xy 133.324854 -280.002742)
		)
		(stroke
			(width 0)
			(type solid)
		)
		(fill yes)
		(layer "In2.Cu")
		(net "M_I_CPU1_SB_DQ<9>")
	)
	(gr_poly
		(pts
			(xy 133.324854 -279.554432) (xy 133.324854 -279.509982) (xy 133.124702 -279.509982) (xy 133.124702 -279.554432)
			(xy 133.224778 -279.654508)
		)
		(stroke
			(width 0)
			(type solid)
		)
		(fill yes)
		(layer "In2.Cu")
		(net "M_I_CPU1_SB_DQ<10>")
	)
	(gr_poly
		(pts
			(xy 133.324854 -278.33828) (xy 133.224778 -278.238204) (xy 133.124702 -278.33828) (xy 133.124702 -278.38273)
			(xy 133.324854 -278.38273)
		)
		(stroke
			(width 0)
			(type solid)
		)
		(fill yes)
		(layer "In2.Cu")
		(net "M_I_CPU1_SB_DQ<5>")
	)
	(gr_poly
		(pts
			(xy 133.324854 -277.93442) (xy 133.324854 -277.88997) (xy 133.124702 -277.88997) (xy 133.124702 -277.93442)
			(xy 133.224778 -278.034496)
		)
		(stroke
			(width 0)
			(type solid)
		)
		(fill yes)
		(layer "In2.Cu")
		(net "M_I_CPU1_SB_DQ<6>")
	)
	(gr_poly
		(pts
			(xy 133.324854 -276.718014) (xy 133.224778 -276.618192) (xy 133.124702 -276.718014) (xy 133.124702 -276.765766)
			(xy 133.324854 -276.765766)
		)
		(stroke
			(width 0)
			(type solid)
		)
		(fill yes)
		(layer "In2.Cu")
		(net "M_I_CPU1_SB_DQS_DN<5>")
	)
	(gr_poly
		(pts
			(xy 133.324854 -276.314662) (xy 133.324854 -276.26691) (xy 133.124702 -276.26691) (xy 133.124702 -276.314662)
			(xy 133.224778 -276.414484)
		)
		(stroke
			(width 0)
			(type solid)
		)
		(fill yes)
		(layer "In2.Cu")
		(net "M_I_CPU1_SB_DQS_DN<0>")
	)
	(gr_poly
		(pts
			(xy 133.324854 -275.098256) (xy 133.224778 -274.99818) (xy 133.124702 -275.098256) (xy 133.124702 -275.142706)
			(xy 133.324854 -275.142706)
		)
		(stroke
			(width 0)
			(type solid)
		)
		(fill yes)
		(layer "In2.Cu")
		(net "M_I_CPU1_SB_DQ<1>")
	)
	(gr_poly
		(pts
			(xy 133.324854 -274.694396) (xy 133.324854 -274.649946) (xy 133.124702 -274.649946) (xy 133.124702 -274.694396)
			(xy 133.224778 -274.794472)
		)
		(stroke
			(width 0)
			(type solid)
		)
		(fill yes)
		(layer "In2.Cu")
		(net "M_I_CPU1_SB_DQ<2>")
	)
	(gr_poly
		(pts
			(xy 133.324854 -273.478244) (xy 133.224778 -273.378168) (xy 133.124702 -273.478244) (xy 133.124702 -273.522694)
			(xy 133.324854 -273.522694)
		)
		(stroke
			(width 0)
			(type solid)
		)
		(fill yes)
		(layer "In2.Cu")
		(net "M_I_CPU1_SB_CB<1>")
	)
	(gr_poly
		(pts
			(xy 133.324854 -273.074384) (xy 133.324854 -273.029934) (xy 133.124702 -273.029934) (xy 133.124702 -273.074384)
			(xy 133.224778 -273.17446)
		)
		(stroke
			(width 0)
			(type solid)
		)
		(fill yes)
		(layer "In2.Cu")
		(net "M_I_CPU1_SB_CB<2>")
	)
	(gr_poly
		(pts
			(xy 133.324854 -271.857978) (xy 133.224778 -271.758156) (xy 133.124702 -271.857978) (xy 133.124702 -271.90573)
			(xy 133.324854 -271.90573)
		)
		(stroke
			(width 0)
			(type solid)
		)
		(fill yes)
		(layer "In2.Cu")
		(net "M_I_CPU1_SB_DQS_DN<4>")
	)
	(gr_poly
		(pts
			(xy 133.324854 -271.454626) (xy 133.324854 -271.406874) (xy 133.124702 -271.406874) (xy 133.124702 -271.454626)
			(xy 133.224778 -271.554448)
		)
		(stroke
			(width 0)
			(type solid)
		)
		(fill yes)
		(layer "In2.Cu")
		(net "M_I_CPU1_SB_DQS_DN<9>")
	)
	(gr_poly
		(pts
			(xy 133.324854 -270.23822) (xy 133.224778 -270.138144) (xy 133.124702 -270.23822) (xy 133.124702 -270.28267)
			(xy 133.324854 -270.28267)
		)
		(stroke
			(width 0)
			(type solid)
		)
		(fill yes)
		(layer "In2.Cu")
		(net "M_I_CPU1_SB_CB<5>")
	)
	(gr_poly
		(pts
			(xy 133.324854 -269.83436) (xy 133.324854 -269.78991) (xy 133.124702 -269.78991) (xy 133.124702 -269.83436)
			(xy 133.224778 -269.934436)
		)
		(stroke
			(width 0)
			(type solid)
		)
		(fill yes)
		(layer "In2.Cu")
		(net "M_I_CPU1_SB_CB<6>")
	)
	(gr_poly
		(pts
			(xy 133.324854 -266.998196) (xy 133.224778 -266.89812) (xy 133.124702 -266.998196) (xy 133.124702 -267.042646)
			(xy 133.324854 -267.042646)
		)
		(stroke
			(width 0)
			(type solid)
		)
		(fill yes)
		(layer "In2.Cu")
		(net "M_I_CPU1_SA_RSP<0>")
	)
	(gr_poly
		(pts
			(xy 133.324854 -266.594336) (xy 133.324854 -266.549886) (xy 133.124702 -266.549886) (xy 133.124702 -266.594336)
			(xy 133.224778 -266.694412)
		)
		(stroke
			(width 0)
			(type solid)
		)
		(fill yes)
		(layer "In2.Cu")
		(net "M_I_CPU1_SB_CS_N<1>")
	)
	(gr_poly
		(pts
			(xy 133.324854 -265.378184) (xy 133.224778 -265.278108) (xy 133.124702 -265.378184) (xy 133.124702 -265.422634)
			(xy 133.324854 -265.422634)
		)
		(stroke
			(width 0)
			(type solid)
		)
		(fill yes)
		(layer "In2.Cu")
		(net "M_I_CPU1_SB_PAR")
	)
	(gr_poly
		(pts
			(xy 133.324854 -263.758172) (xy 133.224778 -263.658096) (xy 133.124702 -263.758172) (xy 133.124702 -263.802622)
			(xy 133.324854 -263.802622)
		)
		(stroke
			(width 0)
			(type solid)
		)
		(fill yes)
		(layer "In2.Cu")
		(net "M_I_CPU1_SB_CA<4>")
	)
	(gr_poly
		(pts
			(xy 133.324854 -263.354312) (xy 133.324854 -263.309862) (xy 133.124702 -263.309862) (xy 133.124702 -263.354312)
			(xy 133.224778 -263.454388)
		)
		(stroke
			(width 0)
			(type solid)
		)
		(fill yes)
		(layer "In2.Cu")
		(net "M_I_CPU1_SB_CA<3>")
	)
	(gr_poly
		(pts
			(xy 133.324854 -262.13816) (xy 133.224778 -262.038084) (xy 133.124702 -262.13816) (xy 133.124702 -262.18261)
			(xy 133.324854 -262.18261)
		)
		(stroke
			(width 0)
			(type solid)
		)
		(fill yes)
		(layer "In2.Cu")
		(net "M_I_CPU1_SB_CA<0>")
	)
	(gr_poly
		(pts
			(xy 133.49478 -256.432812) (xy 133.49478 -256.38506) (xy 133.294628 -256.38506) (xy 133.294628 -256.432812)
			(xy 133.394704 -256.532634)
		)
		(stroke
			(width 0)
			(type solid)
		)
		(fill yes)
		(layer "In2.Cu")
		(net "M_I_CPU1_CLK_DN<0>")
	)
	(gr_poly
		(pts
			(xy 133.49478 -255.216406) (xy 133.394704 -255.11633) (xy 133.294628 -255.216406) (xy 133.294628 -255.260856)
			(xy 133.49478 -255.260856)
		)
		(stroke
			(width 0)
			(type solid)
		)
		(fill yes)
		(layer "In2.Cu")
		(net "M_I_CPU1_SA_CA<6>")
	)
	(gr_poly
		(pts
			(xy 133.49478 -254.812546) (xy 133.49478 -254.768096) (xy 133.294628 -254.768096) (xy 133.294628 -254.812546)
			(xy 133.394704 -254.912622)
		)
		(stroke
			(width 0)
			(type solid)
		)
		(fill yes)
		(layer "In2.Cu")
		(net "M_I_CPU1_SA_CA<5>")
	)
	(gr_poly
		(pts
			(xy 133.49478 -253.596394) (xy 133.394704 -253.496318) (xy 133.294628 -253.596394) (xy 133.294628 -253.640844)
			(xy 133.49478 -253.640844)
		)
		(stroke
			(width 0)
			(type solid)
		)
		(fill yes)
		(layer "In2.Cu")
		(net "M_I_CPU1_SA_CA<2>")
	)
	(gr_poly
		(pts
			(xy 133.49478 -253.192534) (xy 133.49478 -253.148084) (xy 133.294628 -253.148084) (xy 133.294628 -253.192534)
			(xy 133.394704 -253.29261)
		)
		(stroke
			(width 0)
			(type solid)
		)
		(fill yes)
		(layer "In2.Cu")
		(net "M_I_CPU1_SA_CA<1>")
	)
	(gr_poly
		(pts
			(xy 133.49478 -251.976382) (xy 133.394704 -251.876306) (xy 133.294628 -251.976382) (xy 133.294628 -252.020832)
			(xy 133.49478 -252.020832)
		)
		(stroke
			(width 0)
			(type solid)
		)
		(fill yes)
		(layer "In2.Cu")
		(net "M_I_CPU1_SA_CS_N<1>")
	)
	(gr_poly
		(pts
			(xy 133.49478 -250.35637) (xy 133.394704 -250.256294) (xy 133.294628 -250.35637) (xy 133.294628 -250.40082)
			(xy 133.49478 -250.40082)
		)
		(stroke
			(width 0)
			(type solid)
		)
		(fill yes)
		(layer "In2.Cu")
		(net "M_I_CPU1_ALERT_R_N")
	)
	(gr_poly
		(pts
			(xy 133.49478 -248.736358) (xy 133.394704 -248.636282) (xy 133.294628 -248.736358) (xy 133.294628 -248.780808)
			(xy 133.49478 -248.780808)
		)
		(stroke
			(width 0)
			(type solid)
		)
		(fill yes)
		(layer "In2.Cu")
		(net "M_I_CPU1_SA_CB<5>")
	)
	(gr_poly
		(pts
			(xy 133.49478 -248.332498) (xy 133.49478 -248.288048) (xy 133.294628 -248.288048) (xy 133.294628 -248.332498)
			(xy 133.394704 -248.432574)
		)
		(stroke
			(width 0)
			(type solid)
		)
		(fill yes)
		(layer "In2.Cu")
		(net "M_I_CPU1_SA_CB<6>")
	)
	(gr_poly
		(pts
			(xy 133.49478 -247.116092) (xy 133.394704 -247.01627) (xy 133.294628 -247.116092) (xy 133.294628 -247.163844)
			(xy 133.49478 -247.163844)
		)
		(stroke
			(width 0)
			(type solid)
		)
		(fill yes)
		(layer "In2.Cu")
		(net "M_I_CPU1_SA_DQS_DN<9>")
	)
	(gr_poly
		(pts
			(xy 133.49478 -246.71274) (xy 133.49478 -246.664988) (xy 133.294628 -246.664988) (xy 133.294628 -246.71274)
			(xy 133.394704 -246.812562)
		)
		(stroke
			(width 0)
			(type solid)
		)
		(fill yes)
		(layer "In2.Cu")
		(net "M_I_CPU1_SA_DQS_DN<4>")
	)
	(gr_poly
		(pts
			(xy 133.49478 -245.496334) (xy 133.394704 -245.396258) (xy 133.294628 -245.496334) (xy 133.294628 -245.540784)
			(xy 133.49478 -245.540784)
		)
		(stroke
			(width 0)
			(type solid)
		)
		(fill yes)
		(layer "In2.Cu")
		(net "M_I_CPU1_SA_CB<1>")
	)
	(gr_poly
		(pts
			(xy 133.49478 -245.092474) (xy 133.49478 -245.048024) (xy 133.294628 -245.048024) (xy 133.294628 -245.092474)
			(xy 133.394704 -245.19255)
		)
		(stroke
			(width 0)
			(type solid)
		)
		(fill yes)
		(layer "In2.Cu")
		(net "M_I_CPU1_SA_CB<2>")
	)
	(gr_poly
		(pts
			(xy 133.49478 -243.876322) (xy 133.394704 -243.776246) (xy 133.294628 -243.876322) (xy 133.294628 -243.920772)
			(xy 133.49478 -243.920772)
		)
		(stroke
			(width 0)
			(type solid)
		)
		(fill yes)
		(layer "In2.Cu")
		(net "M_I_CPU1_SA_DQ<29>")
	)
	(gr_poly
		(pts
			(xy 133.49478 -243.472462) (xy 133.49478 -243.428012) (xy 133.294628 -243.428012) (xy 133.294628 -243.472462)
			(xy 133.394704 -243.572538)
		)
		(stroke
			(width 0)
			(type solid)
		)
		(fill yes)
		(layer "In2.Cu")
		(net "M_I_CPU1_SA_DQ<30>")
	)
	(gr_poly
		(pts
			(xy 133.49478 -242.256056) (xy 133.394704 -242.156234) (xy 133.294628 -242.256056) (xy 133.294628 -242.303808)
			(xy 133.49478 -242.303808)
		)
		(stroke
			(width 0)
			(type solid)
		)
		(fill yes)
		(layer "In2.Cu")
		(net "M_I_CPU1_SA_DQS_DN<8>")
	)
	(gr_poly
		(pts
			(xy 133.49478 -241.852704) (xy 133.49478 -241.804952) (xy 133.294628 -241.804952) (xy 133.294628 -241.852704)
			(xy 133.394704 -241.952526)
		)
		(stroke
			(width 0)
			(type solid)
		)
		(fill yes)
		(layer "In2.Cu")
		(net "M_I_CPU1_SA_DQS_DN<3>")
	)
	(gr_poly
		(pts
			(xy 133.49478 -240.636298) (xy 133.394704 -240.536222) (xy 133.294628 -240.636298) (xy 133.294628 -240.680748)
			(xy 133.49478 -240.680748)
		)
		(stroke
			(width 0)
			(type solid)
		)
		(fill yes)
		(layer "In2.Cu")
		(net "M_I_CPU1_SA_DQ<25>")
	)
	(gr_poly
		(pts
			(xy 133.49478 -240.232438) (xy 133.49478 -240.187988) (xy 133.294628 -240.187988) (xy 133.294628 -240.232438)
			(xy 133.394704 -240.332514)
		)
		(stroke
			(width 0)
			(type solid)
		)
		(fill yes)
		(layer "In2.Cu")
		(net "M_I_CPU1_SA_DQ<26>")
	)
	(gr_poly
		(pts
			(xy 133.49478 -239.016286) (xy 133.394704 -238.91621) (xy 133.294628 -239.016286) (xy 133.294628 -239.060736)
			(xy 133.49478 -239.060736)
		)
		(stroke
			(width 0)
			(type solid)
		)
		(fill yes)
		(layer "In2.Cu")
		(net "M_I_CPU1_SA_DQ<21>")
	)
	(gr_poly
		(pts
			(xy 133.49478 -238.612426) (xy 133.49478 -238.567976) (xy 133.294628 -238.567976) (xy 133.294628 -238.612426)
			(xy 133.394704 -238.712502)
		)
		(stroke
			(width 0)
			(type solid)
		)
		(fill yes)
		(layer "In2.Cu")
		(net "M_I_CPU1_SA_DQ<22>")
	)
	(gr_poly
		(pts
			(xy 133.49478 -237.39602) (xy 133.394704 -237.296198) (xy 133.294628 -237.39602) (xy 133.294628 -237.443772)
			(xy 133.49478 -237.443772)
		)
		(stroke
			(width 0)
			(type solid)
		)
		(fill yes)
		(layer "In2.Cu")
		(net "M_I_CPU1_SA_DQS_DN<7>")
	)
	(gr_poly
		(pts
			(xy 133.49478 -236.992668) (xy 133.49478 -236.944916) (xy 133.294628 -236.944916) (xy 133.294628 -236.992668)
			(xy 133.394704 -237.09249)
		)
		(stroke
			(width 0)
			(type solid)
		)
		(fill yes)
		(layer "In2.Cu")
		(net "M_I_CPU1_SA_DQS_DN<2>")
	)
	(gr_poly
		(pts
			(xy 133.49478 -235.776262) (xy 133.394704 -235.676186) (xy 133.294628 -235.776262) (xy 133.294628 -235.820712)
			(xy 133.49478 -235.820712)
		)
		(stroke
			(width 0)
			(type solid)
		)
		(fill yes)
		(layer "In2.Cu")
		(net "M_I_CPU1_SA_DQ<17>")
	)
	(gr_poly
		(pts
			(xy 133.49478 -235.372402) (xy 133.49478 -235.327952) (xy 133.294628 -235.327952) (xy 133.294628 -235.372402)
			(xy 133.394704 -235.472478)
		)
		(stroke
			(width 0)
			(type solid)
		)
		(fill yes)
		(layer "In2.Cu")
		(net "M_I_CPU1_SA_DQ<18>")
	)
	(gr_poly
		(pts
			(xy 133.49478 -234.15625) (xy 133.394704 -234.056174) (xy 133.294628 -234.15625) (xy 133.294628 -234.2007)
			(xy 133.49478 -234.2007)
		)
		(stroke
			(width 0)
			(type solid)
		)
		(fill yes)
		(layer "In2.Cu")
		(net "M_I_CPU1_SA_DQ<13>")
	)
	(gr_poly
		(pts
			(xy 133.49478 -233.75239) (xy 133.49478 -233.70794) (xy 133.294628 -233.70794) (xy 133.294628 -233.75239)
			(xy 133.394704 -233.852466)
		)
		(stroke
			(width 0)
			(type solid)
		)
		(fill yes)
		(layer "In2.Cu")
		(net "M_I_CPU1_SA_DQ<14>")
	)
	(gr_poly
		(pts
			(xy 133.49478 -232.535984) (xy 133.394704 -232.436162) (xy 133.294628 -232.535984) (xy 133.294628 -232.583736)
			(xy 133.49478 -232.583736)
		)
		(stroke
			(width 0)
			(type solid)
		)
		(fill yes)
		(layer "In2.Cu")
		(net "M_I_CPU1_SA_DQS_DN<6>")
	)
	(gr_poly
		(pts
			(xy 133.49478 -232.132632) (xy 133.49478 -232.08488) (xy 133.294628 -232.08488) (xy 133.294628 -232.132632)
			(xy 133.394704 -232.232454)
		)
		(stroke
			(width 0)
			(type solid)
		)
		(fill yes)
		(layer "In2.Cu")
		(net "M_I_CPU1_SA_DQS_DN<1>")
	)
	(gr_poly
		(pts
			(xy 133.49478 -230.916226) (xy 133.394704 -230.81615) (xy 133.294628 -230.916226) (xy 133.294628 -230.960676)
			(xy 133.49478 -230.960676)
		)
		(stroke
			(width 0)
			(type solid)
		)
		(fill yes)
		(layer "In2.Cu")
		(net "M_I_CPU1_SA_DQ<9>")
	)
	(gr_poly
		(pts
			(xy 133.49478 -230.51262) (xy 133.49478 -230.46817) (xy 133.294628 -230.46817) (xy 133.294628 -230.51262)
			(xy 133.394704 -230.612696)
		)
		(stroke
			(width 0)
			(type solid)
		)
		(fill yes)
		(layer "In2.Cu")
		(net "M_I_CPU1_SA_DQ<10>")
	)
	(gr_poly
		(pts
			(xy 133.49478 -229.296214) (xy 133.394704 -229.196138) (xy 133.294628 -229.296214) (xy 133.294628 -229.340664)
			(xy 133.49478 -229.340664)
		)
		(stroke
			(width 0)
			(type solid)
		)
		(fill yes)
		(layer "In2.Cu")
		(net "M_I_CPU1_SA_DQ<5>")
	)
	(gr_poly
		(pts
			(xy 133.49478 -228.892608) (xy 133.49478 -228.848158) (xy 133.294628 -228.848158) (xy 133.294628 -228.892608)
			(xy 133.394704 -228.992684)
		)
		(stroke
			(width 0)
			(type solid)
		)
		(fill yes)
		(layer "In2.Cu")
		(net "M_I_CPU1_SA_DQ<6>")
	)
	(gr_poly
		(pts
			(xy 133.49478 -227.676202) (xy 133.394704 -227.57638) (xy 133.294628 -227.676202) (xy 133.294628 -227.723954)
			(xy 133.49478 -227.723954)
		)
		(stroke
			(width 0)
			(type solid)
		)
		(fill yes)
		(layer "In2.Cu")
		(net "M_I_CPU1_SA_DQS_DN<5>")
	)
	(gr_poly
		(pts
			(xy 133.49478 -227.27285) (xy 133.49478 -227.225098) (xy 133.294628 -227.225098) (xy 133.294628 -227.27285)
			(xy 133.394704 -227.372672)
		)
		(stroke
			(width 0)
			(type solid)
		)
		(fill yes)
		(layer "In2.Cu")
		(net "M_I_CPU1_SA_DQS_DN<0>")
	)
	(gr_poly
		(pts
			(xy 133.49478 -226.056444) (xy 133.394704 -225.956368) (xy 133.294628 -226.056444) (xy 133.294628 -226.100894)
			(xy 133.49478 -226.100894)
		)
		(stroke
			(width 0)
			(type solid)
		)
		(fill yes)
		(layer "In2.Cu")
		(net "M_I_CPU1_SA_DQ<1>")
	)
	(gr_poly
		(pts
			(xy 133.49478 -225.652584) (xy 133.49478 -225.608134) (xy 133.294628 -225.608134) (xy 133.294628 -225.652584)
			(xy 133.394704 -225.75266)
		)
		(stroke
			(width 0)
			(type solid)
		)
		(fill yes)
		(layer "In2.Cu")
		(net "M_I_CPU1_SA_DQ<2>")
	)
	(gr_poly
		(pts
			(xy 133.794754 -293.32428) (xy 133.794754 -293.27983) (xy 133.594602 -293.27983) (xy 133.594602 -293.32428)
			(xy 133.694678 -293.424356)
		)
		(stroke
			(width 0)
			(type solid)
		)
		(fill yes)
		(layer "In2.Cu")
		(net "M_I_CPU1_SB_DQ<31>")
	)
	(gr_poly
		(pts
			(xy 133.794754 -292.108128) (xy 133.694678 -292.008052) (xy 133.594602 -292.108128) (xy 133.594602 -292.152578)
			(xy 133.794754 -292.152578)
		)
		(stroke
			(width 0)
			(type solid)
		)
		(fill yes)
		(layer "In2.Cu")
		(net "M_I_CPU1_SB_DQ<28>")
	)
	(gr_poly
		(pts
			(xy 133.794754 -291.704522) (xy 133.794754 -291.65677) (xy 133.594602 -291.65677) (xy 133.594602 -291.704522)
			(xy 133.694678 -291.804344)
		)
		(stroke
			(width 0)
			(type solid)
		)
		(fill yes)
		(layer "In2.Cu")
		(net "M_I_CPU1_SB_DQS_DP<8>")
	)
	(gr_poly
		(pts
			(xy 133.794754 -290.487862) (xy 133.694678 -290.38804) (xy 133.594602 -290.487862) (xy 133.594602 -290.535614)
			(xy 133.794754 -290.535614)
		)
		(stroke
			(width 0)
			(type solid)
		)
		(fill yes)
		(layer "In2.Cu")
		(net "M_I_CPU1_SB_DQS_DP<3>")
	)
	(gr_poly
		(pts
			(xy 133.794754 -290.084256) (xy 133.794754 -290.039806) (xy 133.594602 -290.039806) (xy 133.594602 -290.084256)
			(xy 133.694678 -290.184332)
		)
		(stroke
			(width 0)
			(type solid)
		)
		(fill yes)
		(layer "In2.Cu")
		(net "M_I_CPU1_SB_DQ<27>")
	)
	(gr_poly
		(pts
			(xy 133.794754 -288.868104) (xy 133.694678 -288.768028) (xy 133.594602 -288.868104) (xy 133.594602 -288.912554)
			(xy 133.794754 -288.912554)
		)
		(stroke
			(width 0)
			(type solid)
		)
		(fill yes)
		(layer "In2.Cu")
		(net "M_I_CPU1_SB_DQ<24>")
	)
	(gr_poly
		(pts
			(xy 133.794754 -288.464498) (xy 133.794754 -288.420048) (xy 133.594602 -288.420048) (xy 133.594602 -288.464498)
			(xy 133.694678 -288.564574)
		)
		(stroke
			(width 0)
			(type solid)
		)
		(fill yes)
		(layer "In2.Cu")
		(net "M_I_CPU1_SB_DQ<23>")
	)
	(gr_poly
		(pts
			(xy 133.794754 -287.248092) (xy 133.694678 -287.148016) (xy 133.594602 -287.248092) (xy 133.594602 -287.292542)
			(xy 133.794754 -287.292542)
		)
		(stroke
			(width 0)
			(type solid)
		)
		(fill yes)
		(layer "In2.Cu")
		(net "M_I_CPU1_SB_DQ<20>")
	)
	(gr_poly
		(pts
			(xy 133.794754 -286.844486) (xy 133.794754 -286.796734) (xy 133.594602 -286.796734) (xy 133.594602 -286.844486)
			(xy 133.694678 -286.944562)
		)
		(stroke
			(width 0)
			(type solid)
		)
		(fill yes)
		(layer "In2.Cu")
		(net "M_I_CPU1_SB_DQS_DP<7>")
	)
	(gr_poly
		(pts
			(xy 133.794754 -285.62808) (xy 133.694678 -285.528258) (xy 133.594602 -285.62808) (xy 133.594602 -285.675832)
			(xy 133.794754 -285.675832)
		)
		(stroke
			(width 0)
			(type solid)
		)
		(fill yes)
		(layer "In2.Cu")
		(net "M_I_CPU1_SB_DQS_DP<2>")
	)
	(gr_poly
		(pts
			(xy 133.794754 -285.224474) (xy 133.794754 -285.180024) (xy 133.594602 -285.180024) (xy 133.594602 -285.224474)
			(xy 133.694678 -285.32455)
		)
		(stroke
			(width 0)
			(type solid)
		)
		(fill yes)
		(layer "In2.Cu")
		(net "M_I_CPU1_SB_DQ<19>")
	)
	(gr_poly
		(pts
			(xy 133.794754 -284.008322) (xy 133.694678 -283.908246) (xy 133.594602 -284.008322) (xy 133.594602 -284.052772)
			(xy 133.794754 -284.052772)
		)
		(stroke
			(width 0)
			(type solid)
		)
		(fill yes)
		(layer "In2.Cu")
		(net "M_I_CPU1_SB_DQ<16>")
	)
	(gr_poly
		(pts
			(xy 133.794754 -283.604462) (xy 133.794754 -283.560012) (xy 133.594602 -283.560012) (xy 133.594602 -283.604462)
			(xy 133.694678 -283.704538)
		)
		(stroke
			(width 0)
			(type solid)
		)
		(fill yes)
		(layer "In2.Cu")
		(net "M_I_CPU1_SB_DQ<15>")
	)
	(gr_poly
		(pts
			(xy 133.794754 -282.38831) (xy 133.694678 -282.288234) (xy 133.594602 -282.38831) (xy 133.594602 -282.43276)
			(xy 133.794754 -282.43276)
		)
		(stroke
			(width 0)
			(type solid)
		)
		(fill yes)
		(layer "In2.Cu")
		(net "M_I_CPU1_SB_DQ<12>")
	)
	(gr_poly
		(pts
			(xy 133.794754 -281.984704) (xy 133.794754 -281.936952) (xy 133.594602 -281.936952) (xy 133.594602 -281.984704)
			(xy 133.694678 -282.084526)
		)
		(stroke
			(width 0)
			(type solid)
		)
		(fill yes)
		(layer "In2.Cu")
		(net "M_I_CPU1_SB_DQS_DP<6>")
	)
	(gr_poly
		(pts
			(xy 133.794754 -280.768044) (xy 133.694678 -280.668222) (xy 133.594602 -280.768044) (xy 133.594602 -280.815796)
			(xy 133.794754 -280.815796)
		)
		(stroke
			(width 0)
			(type solid)
		)
		(fill yes)
		(layer "In2.Cu")
		(net "M_I_CPU1_SB_DQS_DP<1>")
	)
	(gr_poly
		(pts
			(xy 133.794754 -280.364438) (xy 133.794754 -280.319988) (xy 133.594602 -280.319988) (xy 133.594602 -280.364438)
			(xy 133.694678 -280.464514)
		)
		(stroke
			(width 0)
			(type solid)
		)
		(fill yes)
		(layer "In2.Cu")
		(net "M_I_CPU1_SB_DQ<11>")
	)
	(gr_poly
		(pts
			(xy 133.794754 -279.148286) (xy 133.694678 -279.04821) (xy 133.594602 -279.148286) (xy 133.594602 -279.192736)
			(xy 133.794754 -279.192736)
		)
		(stroke
			(width 0)
			(type solid)
		)
		(fill yes)
		(layer "In2.Cu")
		(net "M_I_CPU1_SB_DQ<8>")
	)
	(gr_poly
		(pts
			(xy 133.794754 -278.744426) (xy 133.794754 -278.699976) (xy 133.594602 -278.699976) (xy 133.594602 -278.744426)
			(xy 133.694678 -278.844502)
		)
		(stroke
			(width 0)
			(type solid)
		)
		(fill yes)
		(layer "In2.Cu")
		(net "M_I_CPU1_SB_DQ<7>")
	)
	(gr_poly
		(pts
			(xy 133.794754 -277.528274) (xy 133.694678 -277.428198) (xy 133.594602 -277.528274) (xy 133.594602 -277.572724)
			(xy 133.794754 -277.572724)
		)
		(stroke
			(width 0)
			(type solid)
		)
		(fill yes)
		(layer "In2.Cu")
		(net "M_I_CPU1_SB_DQ<4>")
	)
	(gr_poly
		(pts
			(xy 133.794754 -277.124668) (xy 133.794754 -277.076916) (xy 133.594602 -277.076916) (xy 133.594602 -277.124668)
			(xy 133.694678 -277.22449)
		)
		(stroke
			(width 0)
			(type solid)
		)
		(fill yes)
		(layer "In2.Cu")
		(net "M_I_CPU1_SB_DQS_DP<5>")
	)
	(gr_poly
		(pts
			(xy 133.794754 -275.908008) (xy 133.694678 -275.808186) (xy 133.594602 -275.908008) (xy 133.594602 -275.95576)
			(xy 133.794754 -275.95576)
		)
		(stroke
			(width 0)
			(type solid)
		)
		(fill yes)
		(layer "In2.Cu")
		(net "M_I_CPU1_SB_DQS_DP<0>")
	)
	(gr_poly
		(pts
			(xy 133.794754 -275.504402) (xy 133.794754 -275.459952) (xy 133.594602 -275.459952) (xy 133.594602 -275.504402)
			(xy 133.694678 -275.604478)
		)
		(stroke
			(width 0)
			(type solid)
		)
		(fill yes)
		(layer "In2.Cu")
		(net "M_I_CPU1_SB_DQ<3>")
	)
	(gr_poly
		(pts
			(xy 133.794754 -274.28825) (xy 133.694678 -274.188174) (xy 133.594602 -274.28825) (xy 133.594602 -274.3327)
			(xy 133.794754 -274.3327)
		)
		(stroke
			(width 0)
			(type solid)
		)
		(fill yes)
		(layer "In2.Cu")
		(net "M_I_CPU1_SB_DQ<0>")
	)
	(gr_poly
		(pts
			(xy 133.794754 -273.88439) (xy 133.794754 -273.83994) (xy 133.594602 -273.83994) (xy 133.594602 -273.88439)
			(xy 133.694678 -273.984466)
		)
		(stroke
			(width 0)
			(type solid)
		)
		(fill yes)
		(layer "In2.Cu")
		(net "M_I_CPU1_SB_CB<3>")
	)
	(gr_poly
		(pts
			(xy 133.794754 -272.668238) (xy 133.694678 -272.568162) (xy 133.594602 -272.668238) (xy 133.594602 -272.712688)
			(xy 133.794754 -272.712688)
		)
		(stroke
			(width 0)
			(type solid)
		)
		(fill yes)
		(layer "In2.Cu")
		(net "M_I_CPU1_SB_CB<0>")
	)
	(gr_poly
		(pts
			(xy 133.794754 -272.264632) (xy 133.794754 -272.21688) (xy 133.594602 -272.21688) (xy 133.594602 -272.264632)
			(xy 133.694678 -272.364454)
		)
		(stroke
			(width 0)
			(type solid)
		)
		(fill yes)
		(layer "In2.Cu")
		(net "M_I_CPU1_SB_DQS_DP<4>")
	)
	(gr_poly
		(pts
			(xy 133.794754 -271.047972) (xy 133.694678 -270.94815) (xy 133.594602 -271.047972) (xy 133.594602 -271.095724)
			(xy 133.794754 -271.095724)
		)
		(stroke
			(width 0)
			(type solid)
		)
		(fill yes)
		(layer "In2.Cu")
		(net "M_I_CPU1_SB_DQS_DP<9>")
	)
	(gr_poly
		(pts
			(xy 133.794754 -270.644366) (xy 133.794754 -270.599916) (xy 133.594602 -270.599916) (xy 133.594602 -270.644366)
			(xy 133.694678 -270.744442)
		)
		(stroke
			(width 0)
			(type solid)
		)
		(fill yes)
		(layer "In2.Cu")
		(net "M_I_CPU1_SB_CB<7>")
	)
	(gr_poly
		(pts
			(xy 133.794754 -269.428214) (xy 133.694678 -269.328138) (xy 133.594602 -269.428214) (xy 133.594602 -269.472664)
			(xy 133.794754 -269.472664)
		)
		(stroke
			(width 0)
			(type solid)
		)
		(fill yes)
		(layer "In2.Cu")
		(net "M_I_CPU1_SB_CB<4>")
	)
	(gr_poly
		(pts
			(xy 133.794754 -267.404342) (xy 133.794754 -267.359892) (xy 133.594602 -267.359892) (xy 133.594602 -267.404342)
			(xy 133.694678 -267.504418)
		)
		(stroke
			(width 0)
			(type solid)
		)
		(fill yes)
		(layer "In2.Cu")
		(net "M_I_CPU1_SB_RSP<0>")
	)
	(gr_poly
		(pts
			(xy 133.794754 -265.78433) (xy 133.794754 -265.73988) (xy 133.594602 -265.73988) (xy 133.594602 -265.78433)
			(xy 133.694678 -265.884406)
		)
		(stroke
			(width 0)
			(type solid)
		)
		(fill yes)
		(layer "In2.Cu")
		(net "M_I_CPU1_SB_CS_N<0>")
	)
	(gr_poly
		(pts
			(xy 133.794754 -264.568178) (xy 133.694678 -264.468102) (xy 133.594602 -264.568178) (xy 133.594602 -264.612628)
			(xy 133.794754 -264.612628)
		)
		(stroke
			(width 0)
			(type solid)
		)
		(fill yes)
		(layer "In2.Cu")
		(net "M_I_CPU1_SB_CA<6>")
	)
	(gr_poly
		(pts
			(xy 133.794754 -264.164318) (xy 133.794754 -264.119868) (xy 133.594602 -264.119868) (xy 133.594602 -264.164318)
			(xy 133.694678 -264.264394)
		)
		(stroke
			(width 0)
			(type solid)
		)
		(fill yes)
		(layer "In2.Cu")
		(net "M_I_CPU1_SB_CA<5>")
	)
	(gr_poly
		(pts
			(xy 133.794754 -262.948166) (xy 133.694678 -262.84809) (xy 133.594602 -262.948166) (xy 133.594602 -262.992616)
			(xy 133.794754 -262.992616)
		)
		(stroke
			(width 0)
			(type solid)
		)
		(fill yes)
		(layer "In2.Cu")
		(net "M_I_CPU1_SB_CA<2>")
	)
	(gr_poly
		(pts
			(xy 133.794754 -262.544306) (xy 133.794754 -262.499856) (xy 133.594602 -262.499856) (xy 133.594602 -262.544306)
			(xy 133.694678 -262.644382)
		)
		(stroke
			(width 0)
			(type solid)
		)
		(fill yes)
		(layer "In2.Cu")
		(net "M_I_CPU1_SB_CA<1>")
	)
	(gr_poly
		(pts
			(xy 133.964934 -256.026158) (xy 133.864858 -255.926336) (xy 133.764782 -256.026158) (xy 133.764782 -256.07391)
			(xy 133.964934 -256.07391)
		)
		(stroke
			(width 0)
			(type solid)
		)
		(fill yes)
		(layer "In2.Cu")
		(net "M_I_CPU1_CLK_DP<0>")
	)
	(gr_poly
		(pts
			(xy 133.964934 -255.622552) (xy 133.964934 -255.578102) (xy 133.764782 -255.578102) (xy 133.764782 -255.622552)
			(xy 133.864858 -255.722628)
		)
		(stroke
			(width 0)
			(type solid)
		)
		(fill yes)
		(layer "In2.Cu")
		(net "M_I_CPU1_SA_PAR")
	)
	(gr_poly
		(pts
			(xy 133.964934 -254.4064) (xy 133.864858 -254.306324) (xy 133.764782 -254.4064) (xy 133.764782 -254.45085)
			(xy 133.964934 -254.45085)
		)
		(stroke
			(width 0)
			(type solid)
		)
		(fill yes)
		(layer "In2.Cu")
		(net "M_I_CPU1_SA_CA<4>")
	)
	(gr_poly
		(pts
			(xy 133.964934 -254.00254) (xy 133.964934 -253.95809) (xy 133.764782 -253.95809) (xy 133.764782 -254.00254)
			(xy 133.864858 -254.102616)
		)
		(stroke
			(width 0)
			(type solid)
		)
		(fill yes)
		(layer "In2.Cu")
		(net "M_I_CPU1_SA_CA<3>")
	)
	(gr_poly
		(pts
			(xy 133.964934 -252.786388) (xy 133.864858 -252.686312) (xy 133.764782 -252.786388) (xy 133.764782 -252.830838)
			(xy 133.964934 -252.830838)
		)
		(stroke
			(width 0)
			(type solid)
		)
		(fill yes)
		(layer "In2.Cu")
		(net "M_I_CPU1_SA_CA<0>")
	)
	(gr_poly
		(pts
			(xy 133.964934 -251.166376) (xy 133.864858 -251.0663) (xy 133.764782 -251.166376) (xy 133.764782 -251.210826)
			(xy 133.964934 -251.210826)
		)
		(stroke
			(width 0)
			(type solid)
		)
		(fill yes)
		(layer "In2.Cu")
		(net "M_I_CPU1_SA_CS_N<0>")
	)
	(gr_poly
		(pts
			(xy 133.964934 -250.762516) (xy 133.964934 -250.718066) (xy 133.764782 -250.718066) (xy 133.764782 -250.762516)
			(xy 133.864858 -250.862592)
		)
		(stroke
			(width 0)
			(type solid)
		)
		(fill yes)
		(layer "In2.Cu")
		(net "M_I_CPU1_RESET_N")
	)
	(gr_poly
		(pts
			(xy 133.964934 -249.142504) (xy 133.964934 -249.098054) (xy 133.764782 -249.098054) (xy 133.764782 -249.142504)
			(xy 133.864858 -249.24258)
		)
		(stroke
			(width 0)
			(type solid)
		)
		(fill yes)
		(layer "In2.Cu")
		(net "M_I_CPU1_SA_CB<7>")
	)
	(gr_poly
		(pts
			(xy 133.964934 -247.926352) (xy 133.864858 -247.826276) (xy 133.764782 -247.926352) (xy 133.764782 -247.970802)
			(xy 133.964934 -247.970802)
		)
		(stroke
			(width 0)
			(type solid)
		)
		(fill yes)
		(layer "In2.Cu")
		(net "M_I_CPU1_SA_CB<4>")
	)
	(gr_poly
		(pts
			(xy 133.964934 -247.522746) (xy 133.964934 -247.474994) (xy 133.764782 -247.474994) (xy 133.764782 -247.522746)
			(xy 133.864858 -247.622568)
		)
		(stroke
			(width 0)
			(type solid)
		)
		(fill yes)
		(layer "In2.Cu")
		(net "M_I_CPU1_SA_DQS_DP<9>")
	)
	(gr_poly
		(pts
			(xy 133.964934 -246.306086) (xy 133.864858 -246.206264) (xy 133.764782 -246.306086) (xy 133.764782 -246.353838)
			(xy 133.964934 -246.353838)
		)
		(stroke
			(width 0)
			(type solid)
		)
		(fill yes)
		(layer "In2.Cu")
		(net "M_I_CPU1_SA_DQS_DP<4>")
	)
	(gr_poly
		(pts
			(xy 133.964934 -245.90248) (xy 133.964934 -245.85803) (xy 133.764782 -245.85803) (xy 133.764782 -245.90248)
			(xy 133.864858 -246.002556)
		)
		(stroke
			(width 0)
			(type solid)
		)
		(fill yes)
		(layer "In2.Cu")
		(net "M_I_CPU1_SA_CB<3>")
	)
	(gr_poly
		(pts
			(xy 133.964934 -244.686328) (xy 133.864858 -244.586252) (xy 133.764782 -244.686328) (xy 133.764782 -244.730778)
			(xy 133.964934 -244.730778)
		)
		(stroke
			(width 0)
			(type solid)
		)
		(fill yes)
		(layer "In2.Cu")
		(net "M_I_CPU1_SA_CB<0>")
	)
	(gr_poly
		(pts
			(xy 133.964934 -244.282468) (xy 133.964934 -244.238018) (xy 133.764782 -244.238018) (xy 133.764782 -244.282468)
			(xy 133.864858 -244.382544)
		)
		(stroke
			(width 0)
			(type solid)
		)
		(fill yes)
		(layer "In2.Cu")
		(net "M_I_CPU1_SA_DQ<31>")
	)
	(gr_poly
		(pts
			(xy 133.964934 -243.066316) (xy 133.864858 -242.96624) (xy 133.764782 -243.066316) (xy 133.764782 -243.110766)
			(xy 133.964934 -243.110766)
		)
		(stroke
			(width 0)
			(type solid)
		)
		(fill yes)
		(layer "In2.Cu")
		(net "M_I_CPU1_SA_DQ<28>")
	)
	(gr_poly
		(pts
			(xy 133.964934 -242.66271) (xy 133.964934 -242.614958) (xy 133.764782 -242.614958) (xy 133.764782 -242.66271)
			(xy 133.864858 -242.762532)
		)
		(stroke
			(width 0)
			(type solid)
		)
		(fill yes)
		(layer "In2.Cu")
		(net "M_I_CPU1_SA_DQS_DP<8>")
	)
	(gr_poly
		(pts
			(xy 133.964934 -241.44605) (xy 133.864858 -241.346228) (xy 133.764782 -241.44605) (xy 133.764782 -241.493802)
			(xy 133.964934 -241.493802)
		)
		(stroke
			(width 0)
			(type solid)
		)
		(fill yes)
		(layer "In2.Cu")
		(net "M_I_CPU1_SA_DQS_DP<3>")
	)
	(gr_poly
		(pts
			(xy 133.964934 -241.042444) (xy 133.964934 -240.997994) (xy 133.764782 -240.997994) (xy 133.764782 -241.042444)
			(xy 133.864858 -241.14252)
		)
		(stroke
			(width 0)
			(type solid)
		)
		(fill yes)
		(layer "In2.Cu")
		(net "M_I_CPU1_SA_DQ<27>")
	)
	(gr_poly
		(pts
			(xy 133.964934 -239.826292) (xy 133.864858 -239.726216) (xy 133.764782 -239.826292) (xy 133.764782 -239.870742)
			(xy 133.964934 -239.870742)
		)
		(stroke
			(width 0)
			(type solid)
		)
		(fill yes)
		(layer "In2.Cu")
		(net "M_I_CPU1_SA_DQ<24>")
	)
	(gr_poly
		(pts
			(xy 133.964934 -239.422432) (xy 133.964934 -239.377982) (xy 133.764782 -239.377982) (xy 133.764782 -239.422432)
			(xy 133.864858 -239.522508)
		)
		(stroke
			(width 0)
			(type solid)
		)
		(fill yes)
		(layer "In2.Cu")
		(net "M_I_CPU1_SA_DQ<23>")
	)
	(gr_poly
		(pts
			(xy 133.964934 -238.20628) (xy 133.864858 -238.106204) (xy 133.764782 -238.20628) (xy 133.764782 -238.25073)
			(xy 133.964934 -238.25073)
		)
		(stroke
			(width 0)
			(type solid)
		)
		(fill yes)
		(layer "In2.Cu")
		(net "M_I_CPU1_SA_DQ<20>")
	)
	(gr_poly
		(pts
			(xy 133.964934 -237.802674) (xy 133.964934 -237.754922) (xy 133.764782 -237.754922) (xy 133.764782 -237.802674)
			(xy 133.864858 -237.902496)
		)
		(stroke
			(width 0)
			(type solid)
		)
		(fill yes)
		(layer "In2.Cu")
		(net "M_I_CPU1_SA_DQS_DP<7>")
	)
	(gr_poly
		(pts
			(xy 133.964934 -236.586014) (xy 133.864858 -236.486192) (xy 133.764782 -236.586014) (xy 133.764782 -236.633766)
			(xy 133.964934 -236.633766)
		)
		(stroke
			(width 0)
			(type solid)
		)
		(fill yes)
		(layer "In2.Cu")
		(net "M_I_CPU1_SA_DQS_DP<2>")
	)
	(gr_poly
		(pts
			(xy 133.964934 -236.182408) (xy 133.964934 -236.137958) (xy 133.764782 -236.137958) (xy 133.764782 -236.182408)
			(xy 133.864858 -236.282484)
		)
		(stroke
			(width 0)
			(type solid)
		)
		(fill yes)
		(layer "In2.Cu")
		(net "M_I_CPU1_SA_DQ<19>")
	)
	(gr_poly
		(pts
			(xy 133.964934 -234.966256) (xy 133.864858 -234.86618) (xy 133.764782 -234.966256) (xy 133.764782 -235.010706)
			(xy 133.964934 -235.010706)
		)
		(stroke
			(width 0)
			(type solid)
		)
		(fill yes)
		(layer "In2.Cu")
		(net "M_I_CPU1_SA_DQ<16>")
	)
	(gr_poly
		(pts
			(xy 133.964934 -234.562396) (xy 133.964934 -234.517946) (xy 133.764782 -234.517946) (xy 133.764782 -234.562396)
			(xy 133.864858 -234.662472)
		)
		(stroke
			(width 0)
			(type solid)
		)
		(fill yes)
		(layer "In2.Cu")
		(net "M_I_CPU1_SA_DQ<15>")
	)
	(gr_poly
		(pts
			(xy 133.964934 -233.346244) (xy 133.864858 -233.246168) (xy 133.764782 -233.346244) (xy 133.764782 -233.390694)
			(xy 133.964934 -233.390694)
		)
		(stroke
			(width 0)
			(type solid)
		)
		(fill yes)
		(layer "In2.Cu")
		(net "M_I_CPU1_SA_DQ<12>")
	)
	(gr_poly
		(pts
			(xy 133.964934 -232.942638) (xy 133.964934 -232.894886) (xy 133.764782 -232.894886) (xy 133.764782 -232.942638)
			(xy 133.864858 -233.04246)
		)
		(stroke
			(width 0)
			(type solid)
		)
		(fill yes)
		(layer "In2.Cu")
		(net "M_I_CPU1_SA_DQS_DP<6>")
	)
	(gr_poly
		(pts
			(xy 133.964934 -231.725978) (xy 133.864858 -231.626156) (xy 133.764782 -231.725978) (xy 133.764782 -231.77373)
			(xy 133.964934 -231.77373)
		)
		(stroke
			(width 0)
			(type solid)
		)
		(fill yes)
		(layer "In2.Cu")
		(net "M_I_CPU1_SA_DQS_DP<1>")
	)
	(gr_poly
		(pts
			(xy 133.964934 -231.322626) (xy 133.964934 -231.278176) (xy 133.764782 -231.278176) (xy 133.764782 -231.322626)
			(xy 133.864858 -231.422702)
		)
		(stroke
			(width 0)
			(type solid)
		)
		(fill yes)
		(layer "In2.Cu")
		(net "M_I_CPU1_SA_DQ<11>")
	)
	(gr_poly
		(pts
			(xy 133.964934 -230.10622) (xy 133.864858 -230.006144) (xy 133.764782 -230.10622) (xy 133.764782 -230.15067)
			(xy 133.964934 -230.15067)
		)
		(stroke
			(width 0)
			(type solid)
		)
		(fill yes)
		(layer "In2.Cu")
		(net "M_I_CPU1_SA_DQ<8>")
	)
	(gr_poly
		(pts
			(xy 133.964934 -229.702614) (xy 133.964934 -229.658164) (xy 133.764782 -229.658164) (xy 133.764782 -229.702614)
			(xy 133.864858 -229.80269)
		)
		(stroke
			(width 0)
			(type solid)
		)
		(fill yes)
		(layer "In2.Cu")
		(net "M_I_CPU1_SA_DQ<7>")
	)
	(gr_poly
		(pts
			(xy 133.964934 -228.486462) (xy 133.864858 -228.386386) (xy 133.764782 -228.486462) (xy 133.764782 -228.530912)
			(xy 133.964934 -228.530912)
		)
		(stroke
			(width 0)
			(type solid)
		)
		(fill yes)
		(layer "In2.Cu")
		(net "M_I_CPU1_SA_DQ<4>")
	)
	(gr_poly
		(pts
			(xy 133.964934 -228.082856) (xy 133.964934 -228.035104) (xy 133.764782 -228.035104) (xy 133.764782 -228.082856)
			(xy 133.864858 -228.182678)
		)
		(stroke
			(width 0)
			(type solid)
		)
		(fill yes)
		(layer "In2.Cu")
		(net "M_I_CPU1_SA_DQS_DP<5>")
	)
	(gr_poly
		(pts
			(xy 133.964934 -226.866196) (xy 133.864858 -226.766374) (xy 133.764782 -226.866196) (xy 133.764782 -226.913948)
			(xy 133.964934 -226.913948)
		)
		(stroke
			(width 0)
			(type solid)
		)
		(fill yes)
		(layer "In2.Cu")
		(net "M_I_CPU1_SA_DQS_DP<0>")
	)
	(gr_poly
		(pts
			(xy 133.964934 -226.46259) (xy 133.964934 -226.41814) (xy 133.764782 -226.41814) (xy 133.764782 -226.46259)
			(xy 133.864858 -226.562666)
		)
		(stroke
			(width 0)
			(type solid)
		)
		(fill yes)
		(layer "In2.Cu")
		(net "M_I_CPU1_SA_DQ<3>")
	)
	(gr_poly
		(pts
			(xy 133.964934 -225.246438) (xy 133.864858 -225.146362) (xy 133.764782 -225.246438) (xy 133.764782 -225.290888)
			(xy 133.964934 -225.290888)
		)
		(stroke
			(width 0)
			(type solid)
		)
		(fill yes)
		(layer "In2.Cu")
		(net "M_I_CPU1_SA_DQ<0>")
	)
	(gr_poly
		(pts
			(xy 134.264908 -292.918134) (xy 134.164832 -292.818058) (xy 134.064756 -292.918134) (xy 134.064756 -292.962584)
			(xy 134.264908 -292.962584)
		)
		(stroke
			(width 0)
			(type solid)
		)
		(fill yes)
		(layer "In2.Cu")
		(net "M_I_CPU1_SB_DQ<29>")
	)
	(gr_poly
		(pts
			(xy 134.264908 -292.514274) (xy 134.264908 -292.469824) (xy 134.064756 -292.469824) (xy 134.064756 -292.514274)
			(xy 134.164832 -292.61435)
		)
		(stroke
			(width 0)
			(type solid)
		)
		(fill yes)
		(layer "In2.Cu")
		(net "M_I_CPU1_SB_DQ<30>")
	)
	(gr_poly
		(pts
			(xy 134.264908 -291.297868) (xy 134.164832 -291.198046) (xy 134.064756 -291.297868) (xy 134.064756 -291.34562)
			(xy 134.264908 -291.34562)
		)
		(stroke
			(width 0)
			(type solid)
		)
		(fill yes)
		(layer "In2.Cu")
		(net "M_I_CPU1_SB_DQS_DN<8>")
	)
	(gr_poly
		(pts
			(xy 134.264908 -290.894516) (xy 134.264908 -290.846764) (xy 134.064756 -290.846764) (xy 134.064756 -290.894516)
			(xy 134.164832 -290.994338)
		)
		(stroke
			(width 0)
			(type solid)
		)
		(fill yes)
		(layer "In2.Cu")
		(net "M_I_CPU1_SB_DQS_DN<3>")
	)
	(gr_poly
		(pts
			(xy 134.264908 -289.67811) (xy 134.164832 -289.578034) (xy 134.064756 -289.67811) (xy 134.064756 -289.72256)
			(xy 134.264908 -289.72256)
		)
		(stroke
			(width 0)
			(type solid)
		)
		(fill yes)
		(layer "In2.Cu")
		(net "M_I_CPU1_SB_DQ<25>")
	)
	(gr_poly
		(pts
			(xy 134.264908 -289.27425) (xy 134.264908 -289.2298) (xy 134.064756 -289.2298) (xy 134.064756 -289.27425)
			(xy 134.164832 -289.374326)
		)
		(stroke
			(width 0)
			(type solid)
		)
		(fill yes)
		(layer "In2.Cu")
		(net "M_I_CPU1_SB_DQ<26>")
	)
	(gr_poly
		(pts
			(xy 134.264908 -288.058098) (xy 134.164832 -287.958022) (xy 134.064756 -288.058098) (xy 134.064756 -288.102548)
			(xy 134.264908 -288.102548)
		)
		(stroke
			(width 0)
			(type solid)
		)
		(fill yes)
		(layer "In2.Cu")
		(net "M_I_CPU1_SB_DQ<21>")
	)
	(gr_poly
		(pts
			(xy 134.264908 -287.654492) (xy 134.264908 -287.610042) (xy 134.064756 -287.610042) (xy 134.064756 -287.654492)
			(xy 134.164832 -287.754568)
		)
		(stroke
			(width 0)
			(type solid)
		)
		(fill yes)
		(layer "In2.Cu")
		(net "M_I_CPU1_SB_DQ<22>")
	)
	(gr_poly
		(pts
			(xy 134.264908 -286.438086) (xy 134.164832 -286.33801) (xy 134.064756 -286.438086) (xy 134.064756 -286.485838)
			(xy 134.264908 -286.485838)
		)
		(stroke
			(width 0)
			(type solid)
		)
		(fill yes)
		(layer "In2.Cu")
		(net "M_I_CPU1_SB_DQS_DN<7>")
	)
	(gr_poly
		(pts
			(xy 134.264908 -286.034734) (xy 134.264908 -285.986982) (xy 134.064756 -285.986982) (xy 134.064756 -286.034734)
			(xy 134.164832 -286.134556)
		)
		(stroke
			(width 0)
			(type solid)
		)
		(fill yes)
		(layer "In2.Cu")
		(net "M_I_CPU1_SB_DQS_DN<2>")
	)
	(gr_poly
		(pts
			(xy 134.264908 -284.818328) (xy 134.164832 -284.718252) (xy 134.064756 -284.818328) (xy 134.064756 -284.862778)
			(xy 134.264908 -284.862778)
		)
		(stroke
			(width 0)
			(type solid)
		)
		(fill yes)
		(layer "In2.Cu")
		(net "M_I_CPU1_SB_DQ<17>")
	)
	(gr_poly
		(pts
			(xy 134.264908 -284.414468) (xy 134.264908 -284.370018) (xy 134.064756 -284.370018) (xy 134.064756 -284.414468)
			(xy 134.164832 -284.514544)
		)
		(stroke
			(width 0)
			(type solid)
		)
		(fill yes)
		(layer "In2.Cu")
		(net "M_I_CPU1_SB_DQ<18>")
	)
	(gr_poly
		(pts
			(xy 134.264908 -283.198316) (xy 134.164832 -283.09824) (xy 134.064756 -283.198316) (xy 134.064756 -283.242766)
			(xy 134.264908 -283.242766)
		)
		(stroke
			(width 0)
			(type solid)
		)
		(fill yes)
		(layer "In2.Cu")
		(net "M_I_CPU1_SB_DQ<13>")
	)
	(gr_poly
		(pts
			(xy 134.264908 -282.794456) (xy 134.264908 -282.750006) (xy 134.064756 -282.750006) (xy 134.064756 -282.794456)
			(xy 134.164832 -282.894532)
		)
		(stroke
			(width 0)
			(type solid)
		)
		(fill yes)
		(layer "In2.Cu")
		(net "M_I_CPU1_SB_DQ<14>")
	)
	(gr_poly
		(pts
			(xy 134.264908 -281.57805) (xy 134.164832 -281.478228) (xy 134.064756 -281.57805) (xy 134.064756 -281.625802)
			(xy 134.264908 -281.625802)
		)
		(stroke
			(width 0)
			(type solid)
		)
		(fill yes)
		(layer "In2.Cu")
		(net "M_I_CPU1_SB_DQS_DN<6>")
	)
	(gr_poly
		(pts
			(xy 134.264908 -281.174698) (xy 134.264908 -281.126946) (xy 134.064756 -281.126946) (xy 134.064756 -281.174698)
			(xy 134.164832 -281.27452)
		)
		(stroke
			(width 0)
			(type solid)
		)
		(fill yes)
		(layer "In2.Cu")
		(net "M_I_CPU1_SB_DQS_DN<1>")
	)
	(gr_poly
		(pts
			(xy 134.264908 -279.958292) (xy 134.164832 -279.858216) (xy 134.064756 -279.958292) (xy 134.064756 -280.002742)
			(xy 134.264908 -280.002742)
		)
		(stroke
			(width 0)
			(type solid)
		)
		(fill yes)
		(layer "In2.Cu")
		(net "M_I_CPU1_SB_DQ<9>")
	)
	(gr_poly
		(pts
			(xy 134.264908 -279.554432) (xy 134.264908 -279.509982) (xy 134.064756 -279.509982) (xy 134.064756 -279.554432)
			(xy 134.164832 -279.654508)
		)
		(stroke
			(width 0)
			(type solid)
		)
		(fill yes)
		(layer "In2.Cu")
		(net "M_I_CPU1_SB_DQ<10>")
	)
	(gr_poly
		(pts
			(xy 134.264908 -278.33828) (xy 134.164832 -278.238204) (xy 134.064756 -278.33828) (xy 134.064756 -278.38273)
			(xy 134.264908 -278.38273)
		)
		(stroke
			(width 0)
			(type solid)
		)
		(fill yes)
		(layer "In2.Cu")
		(net "M_I_CPU1_SB_DQ<5>")
	)
	(gr_poly
		(pts
			(xy 134.264908 -277.93442) (xy 134.264908 -277.88997) (xy 134.064756 -277.88997) (xy 134.064756 -277.93442)
			(xy 134.164832 -278.034496)
		)
		(stroke
			(width 0)
			(type solid)
		)
		(fill yes)
		(layer "In2.Cu")
		(net "M_I_CPU1_SB_DQ<6>")
	)
	(gr_poly
		(pts
			(xy 134.264908 -276.718014) (xy 134.164832 -276.618192) (xy 134.064756 -276.718014) (xy 134.064756 -276.765766)
			(xy 134.264908 -276.765766)
		)
		(stroke
			(width 0)
			(type solid)
		)
		(fill yes)
		(layer "In2.Cu")
		(net "M_I_CPU1_SB_DQS_DN<5>")
	)
	(gr_poly
		(pts
			(xy 134.264908 -276.314662) (xy 134.264908 -276.26691) (xy 134.064756 -276.26691) (xy 134.064756 -276.314662)
			(xy 134.164832 -276.414484)
		)
		(stroke
			(width 0)
			(type solid)
		)
		(fill yes)
		(layer "In2.Cu")
		(net "M_I_CPU1_SB_DQS_DN<0>")
	)
	(gr_poly
		(pts
			(xy 134.264908 -275.098256) (xy 134.164832 -274.99818) (xy 134.064756 -275.098256) (xy 134.064756 -275.142706)
			(xy 134.264908 -275.142706)
		)
		(stroke
			(width 0)
			(type solid)
		)
		(fill yes)
		(layer "In2.Cu")
		(net "M_I_CPU1_SB_DQ<1>")
	)
	(gr_poly
		(pts
			(xy 134.264908 -274.694396) (xy 134.264908 -274.649946) (xy 134.064756 -274.649946) (xy 134.064756 -274.694396)
			(xy 134.164832 -274.794472)
		)
		(stroke
			(width 0)
			(type solid)
		)
		(fill yes)
		(layer "In2.Cu")
		(net "M_I_CPU1_SB_DQ<2>")
	)
	(gr_poly
		(pts
			(xy 134.264908 -273.478244) (xy 134.164832 -273.378168) (xy 134.064756 -273.478244) (xy 134.064756 -273.522694)
			(xy 134.264908 -273.522694)
		)
		(stroke
			(width 0)
			(type solid)
		)
		(fill yes)
		(layer "In2.Cu")
		(net "M_I_CPU1_SB_CB<1>")
	)
	(gr_poly
		(pts
			(xy 134.264908 -273.074384) (xy 134.264908 -273.029934) (xy 134.064756 -273.029934) (xy 134.064756 -273.074384)
			(xy 134.164832 -273.17446)
		)
		(stroke
			(width 0)
			(type solid)
		)
		(fill yes)
		(layer "In2.Cu")
		(net "M_I_CPU1_SB_CB<2>")
	)
	(gr_poly
		(pts
			(xy 134.264908 -271.857978) (xy 134.164832 -271.758156) (xy 134.064756 -271.857978) (xy 134.064756 -271.90573)
			(xy 134.264908 -271.90573)
		)
		(stroke
			(width 0)
			(type solid)
		)
		(fill yes)
		(layer "In2.Cu")
		(net "M_I_CPU1_SB_DQS_DN<4>")
	)
	(gr_poly
		(pts
			(xy 134.264908 -271.454626) (xy 134.264908 -271.406874) (xy 134.064756 -271.406874) (xy 134.064756 -271.454626)
			(xy 134.164832 -271.554448)
		)
		(stroke
			(width 0)
			(type solid)
		)
		(fill yes)
		(layer "In2.Cu")
		(net "M_I_CPU1_SB_DQS_DN<9>")
	)
	(gr_poly
		(pts
			(xy 134.264908 -270.23822) (xy 134.164832 -270.138144) (xy 134.064756 -270.23822) (xy 134.064756 -270.28267)
			(xy 134.264908 -270.28267)
		)
		(stroke
			(width 0)
			(type solid)
		)
		(fill yes)
		(layer "In2.Cu")
		(net "M_I_CPU1_SB_CB<5>")
	)
	(gr_poly
		(pts
			(xy 134.264908 -269.83436) (xy 134.264908 -269.78991) (xy 134.064756 -269.78991) (xy 134.064756 -269.83436)
			(xy 134.164832 -269.934436)
		)
		(stroke
			(width 0)
			(type solid)
		)
		(fill yes)
		(layer "In2.Cu")
		(net "M_I_CPU1_SB_CB<6>")
	)
	(gr_poly
		(pts
			(xy 134.264908 -266.998196) (xy 134.164832 -266.89812) (xy 134.064756 -266.998196) (xy 134.064756 -267.042646)
			(xy 134.264908 -267.042646)
		)
		(stroke
			(width 0)
			(type solid)
		)
		(fill yes)
		(layer "In2.Cu")
		(net "M_I_CPU1_SA_RSP<0>")
	)
	(gr_poly
		(pts
			(xy 134.264908 -266.594336) (xy 134.264908 -266.549886) (xy 134.064756 -266.549886) (xy 134.064756 -266.594336)
			(xy 134.164832 -266.694412)
		)
		(stroke
			(width 0)
			(type solid)
		)
		(fill yes)
		(layer "In2.Cu")
		(net "M_I_CPU1_SB_CS_N<1>")
	)
	(gr_poly
		(pts
			(xy 134.264908 -265.378184) (xy 134.164832 -265.278108) (xy 134.064756 -265.378184) (xy 134.064756 -265.422634)
			(xy 134.264908 -265.422634)
		)
		(stroke
			(width 0)
			(type solid)
		)
		(fill yes)
		(layer "In2.Cu")
		(net "M_I_CPU1_SB_PAR")
	)
	(gr_poly
		(pts
			(xy 134.264908 -263.758172) (xy 134.164832 -263.658096) (xy 134.064756 -263.758172) (xy 134.064756 -263.802622)
			(xy 134.264908 -263.802622)
		)
		(stroke
			(width 0)
			(type solid)
		)
		(fill yes)
		(layer "In2.Cu")
		(net "M_I_CPU1_SB_CA<4>")
	)
	(gr_poly
		(pts
			(xy 134.264908 -263.354312) (xy 134.264908 -263.309862) (xy 134.064756 -263.309862) (xy 134.064756 -263.354312)
			(xy 134.164832 -263.454388)
		)
		(stroke
			(width 0)
			(type solid)
		)
		(fill yes)
		(layer "In2.Cu")
		(net "M_I_CPU1_SB_CA<3>")
	)
	(gr_poly
		(pts
			(xy 134.264908 -262.13816) (xy 134.164832 -262.038084) (xy 134.064756 -262.13816) (xy 134.064756 -262.18261)
			(xy 134.264908 -262.18261)
		)
		(stroke
			(width 0)
			(type solid)
		)
		(fill yes)
		(layer "In2.Cu")
		(net "M_I_CPU1_SB_CA<0>")
	)
	(gr_poly
		(pts
			(xy 134.434834 -256.432812) (xy 134.434834 -256.38506) (xy 134.234682 -256.38506) (xy 134.234682 -256.432812)
			(xy 134.334758 -256.532634)
		)
		(stroke
			(width 0)
			(type solid)
		)
		(fill yes)
		(layer "In2.Cu")
		(net "M_I_CPU1_CLK_DN<0>")
	)
	(gr_poly
		(pts
			(xy 134.434834 -255.216406) (xy 134.334758 -255.11633) (xy 134.234682 -255.216406) (xy 134.234682 -255.260856)
			(xy 134.434834 -255.260856)
		)
		(stroke
			(width 0)
			(type solid)
		)
		(fill yes)
		(layer "In2.Cu")
		(net "M_I_CPU1_SA_CA<6>")
	)
	(gr_poly
		(pts
			(xy 134.434834 -254.812546) (xy 134.434834 -254.768096) (xy 134.234682 -254.768096) (xy 134.234682 -254.812546)
			(xy 134.334758 -254.912622)
		)
		(stroke
			(width 0)
			(type solid)
		)
		(fill yes)
		(layer "In2.Cu")
		(net "M_I_CPU1_SA_CA<5>")
	)
	(gr_poly
		(pts
			(xy 134.434834 -253.596394) (xy 134.334758 -253.496318) (xy 134.234682 -253.596394) (xy 134.234682 -253.640844)
			(xy 134.434834 -253.640844)
		)
		(stroke
			(width 0)
			(type solid)
		)
		(fill yes)
		(layer "In2.Cu")
		(net "M_I_CPU1_SA_CA<2>")
	)
	(gr_poly
		(pts
			(xy 134.434834 -253.192534) (xy 134.434834 -253.148084) (xy 134.234682 -253.148084) (xy 134.234682 -253.192534)
			(xy 134.334758 -253.29261)
		)
		(stroke
			(width 0)
			(type solid)
		)
		(fill yes)
		(layer "In2.Cu")
		(net "M_I_CPU1_SA_CA<1>")
	)
	(gr_poly
		(pts
			(xy 134.434834 -251.976382) (xy 134.334758 -251.876306) (xy 134.234682 -251.976382) (xy 134.234682 -252.020832)
			(xy 134.434834 -252.020832)
		)
		(stroke
			(width 0)
			(type solid)
		)
		(fill yes)
		(layer "In2.Cu")
		(net "M_I_CPU1_SA_CS_N<1>")
	)
	(gr_poly
		(pts
			(xy 134.434834 -250.35637) (xy 134.334758 -250.256294) (xy 134.234682 -250.35637) (xy 134.234682 -250.40082)
			(xy 134.434834 -250.40082)
		)
		(stroke
			(width 0)
			(type solid)
		)
		(fill yes)
		(layer "In2.Cu")
		(net "M_I_CPU1_ALERT_R_N")
	)
	(gr_poly
		(pts
			(xy 134.434834 -248.736358) (xy 134.334758 -248.636282) (xy 134.234682 -248.736358) (xy 134.234682 -248.780808)
			(xy 134.434834 -248.780808)
		)
		(stroke
			(width 0)
			(type solid)
		)
		(fill yes)
		(layer "In2.Cu")
		(net "M_I_CPU1_SA_CB<5>")
	)
	(gr_poly
		(pts
			(xy 134.434834 -248.332498) (xy 134.434834 -248.288048) (xy 134.234682 -248.288048) (xy 134.234682 -248.332498)
			(xy 134.334758 -248.432574)
		)
		(stroke
			(width 0)
			(type solid)
		)
		(fill yes)
		(layer "In2.Cu")
		(net "M_I_CPU1_SA_CB<6>")
	)
	(gr_poly
		(pts
			(xy 134.434834 -247.116092) (xy 134.334758 -247.01627) (xy 134.234682 -247.116092) (xy 134.234682 -247.163844)
			(xy 134.434834 -247.163844)
		)
		(stroke
			(width 0)
			(type solid)
		)
		(fill yes)
		(layer "In2.Cu")
		(net "M_I_CPU1_SA_DQS_DN<9>")
	)
	(gr_poly
		(pts
			(xy 134.434834 -246.71274) (xy 134.434834 -246.664988) (xy 134.234682 -246.664988) (xy 134.234682 -246.71274)
			(xy 134.334758 -246.812562)
		)
		(stroke
			(width 0)
			(type solid)
		)
		(fill yes)
		(layer "In2.Cu")
		(net "M_I_CPU1_SA_DQS_DN<4>")
	)
	(gr_poly
		(pts
			(xy 134.434834 -245.496334) (xy 134.334758 -245.396258) (xy 134.234682 -245.496334) (xy 134.234682 -245.540784)
			(xy 134.434834 -245.540784)
		)
		(stroke
			(width 0)
			(type solid)
		)
		(fill yes)
		(layer "In2.Cu")
		(net "M_I_CPU1_SA_CB<1>")
	)
	(gr_poly
		(pts
			(xy 134.434834 -245.092474) (xy 134.434834 -245.048024) (xy 134.234682 -245.048024) (xy 134.234682 -245.092474)
			(xy 134.334758 -245.19255)
		)
		(stroke
			(width 0)
			(type solid)
		)
		(fill yes)
		(layer "In2.Cu")
		(net "M_I_CPU1_SA_CB<2>")
	)
	(gr_poly
		(pts
			(xy 134.434834 -243.876322) (xy 134.334758 -243.776246) (xy 134.234682 -243.876322) (xy 134.234682 -243.920772)
			(xy 134.434834 -243.920772)
		)
		(stroke
			(width 0)
			(type solid)
		)
		(fill yes)
		(layer "In2.Cu")
		(net "M_I_CPU1_SA_DQ<29>")
	)
	(gr_poly
		(pts
			(xy 134.434834 -243.472462) (xy 134.434834 -243.428012) (xy 134.234682 -243.428012) (xy 134.234682 -243.472462)
			(xy 134.334758 -243.572538)
		)
		(stroke
			(width 0)
			(type solid)
		)
		(fill yes)
		(layer "In2.Cu")
		(net "M_I_CPU1_SA_DQ<30>")
	)
	(gr_poly
		(pts
			(xy 134.434834 -242.256056) (xy 134.334758 -242.156234) (xy 134.234682 -242.256056) (xy 134.234682 -242.303808)
			(xy 134.434834 -242.303808)
		)
		(stroke
			(width 0)
			(type solid)
		)
		(fill yes)
		(layer "In2.Cu")
		(net "M_I_CPU1_SA_DQS_DN<8>")
	)
	(gr_poly
		(pts
			(xy 134.434834 -241.852704) (xy 134.434834 -241.804952) (xy 134.234682 -241.804952) (xy 134.234682 -241.852704)
			(xy 134.334758 -241.952526)
		)
		(stroke
			(width 0)
			(type solid)
		)
		(fill yes)
		(layer "In2.Cu")
		(net "M_I_CPU1_SA_DQS_DN<3>")
	)
	(gr_poly
		(pts
			(xy 134.434834 -240.636298) (xy 134.334758 -240.536222) (xy 134.234682 -240.636298) (xy 134.234682 -240.680748)
			(xy 134.434834 -240.680748)
		)
		(stroke
			(width 0)
			(type solid)
		)
		(fill yes)
		(layer "In2.Cu")
		(net "M_I_CPU1_SA_DQ<25>")
	)
	(gr_poly
		(pts
			(xy 134.434834 -240.232438) (xy 134.434834 -240.187988) (xy 134.234682 -240.187988) (xy 134.234682 -240.232438)
			(xy 134.334758 -240.332514)
		)
		(stroke
			(width 0)
			(type solid)
		)
		(fill yes)
		(layer "In2.Cu")
		(net "M_I_CPU1_SA_DQ<26>")
	)
	(gr_poly
		(pts
			(xy 134.434834 -239.016286) (xy 134.334758 -238.91621) (xy 134.234682 -239.016286) (xy 134.234682 -239.060736)
			(xy 134.434834 -239.060736)
		)
		(stroke
			(width 0)
			(type solid)
		)
		(fill yes)
		(layer "In2.Cu")
		(net "M_I_CPU1_SA_DQ<21>")
	)
	(gr_poly
		(pts
			(xy 134.434834 -238.612426) (xy 134.434834 -238.567976) (xy 134.234682 -238.567976) (xy 134.234682 -238.612426)
			(xy 134.334758 -238.712502)
		)
		(stroke
			(width 0)
			(type solid)
		)
		(fill yes)
		(layer "In2.Cu")
		(net "M_I_CPU1_SA_DQ<22>")
	)
	(gr_poly
		(pts
			(xy 134.434834 -237.39602) (xy 134.334758 -237.296198) (xy 134.234682 -237.39602) (xy 134.234682 -237.443772)
			(xy 134.434834 -237.443772)
		)
		(stroke
			(width 0)
			(type solid)
		)
		(fill yes)
		(layer "In2.Cu")
		(net "M_I_CPU1_SA_DQS_DN<7>")
	)
	(gr_poly
		(pts
			(xy 134.434834 -236.992668) (xy 134.434834 -236.944916) (xy 134.234682 -236.944916) (xy 134.234682 -236.992668)
			(xy 134.334758 -237.09249)
		)
		(stroke
			(width 0)
			(type solid)
		)
		(fill yes)
		(layer "In2.Cu")
		(net "M_I_CPU1_SA_DQS_DN<2>")
	)
	(gr_poly
		(pts
			(xy 134.434834 -235.776262) (xy 134.334758 -235.676186) (xy 134.234682 -235.776262) (xy 134.234682 -235.820712)
			(xy 134.434834 -235.820712)
		)
		(stroke
			(width 0)
			(type solid)
		)
		(fill yes)
		(layer "In2.Cu")
		(net "M_I_CPU1_SA_DQ<17>")
	)
	(gr_poly
		(pts
			(xy 134.434834 -235.372402) (xy 134.434834 -235.327952) (xy 134.234682 -235.327952) (xy 134.234682 -235.372402)
			(xy 134.334758 -235.472478)
		)
		(stroke
			(width 0)
			(type solid)
		)
		(fill yes)
		(layer "In2.Cu")
		(net "M_I_CPU1_SA_DQ<18>")
	)
	(gr_poly
		(pts
			(xy 134.434834 -234.15625) (xy 134.334758 -234.056174) (xy 134.234682 -234.15625) (xy 134.234682 -234.2007)
			(xy 134.434834 -234.2007)
		)
		(stroke
			(width 0)
			(type solid)
		)
		(fill yes)
		(layer "In2.Cu")
		(net "M_I_CPU1_SA_DQ<13>")
	)
	(gr_poly
		(pts
			(xy 134.434834 -233.75239) (xy 134.434834 -233.70794) (xy 134.234682 -233.70794) (xy 134.234682 -233.75239)
			(xy 134.334758 -233.852466)
		)
		(stroke
			(width 0)
			(type solid)
		)
		(fill yes)
		(layer "In2.Cu")
		(net "M_I_CPU1_SA_DQ<14>")
	)
	(gr_poly
		(pts
			(xy 134.434834 -232.535984) (xy 134.334758 -232.436162) (xy 134.234682 -232.535984) (xy 134.234682 -232.583736)
			(xy 134.434834 -232.583736)
		)
		(stroke
			(width 0)
			(type solid)
		)
		(fill yes)
		(layer "In2.Cu")
		(net "M_I_CPU1_SA_DQS_DN<6>")
	)
	(gr_poly
		(pts
			(xy 134.434834 -232.132632) (xy 134.434834 -232.08488) (xy 134.234682 -232.08488) (xy 134.234682 -232.132632)
			(xy 134.334758 -232.232454)
		)
		(stroke
			(width 0)
			(type solid)
		)
		(fill yes)
		(layer "In2.Cu")
		(net "M_I_CPU1_SA_DQS_DN<1>")
	)
	(gr_poly
		(pts
			(xy 134.434834 -230.916226) (xy 134.334758 -230.81615) (xy 134.234682 -230.916226) (xy 134.234682 -230.960676)
			(xy 134.434834 -230.960676)
		)
		(stroke
			(width 0)
			(type solid)
		)
		(fill yes)
		(layer "In2.Cu")
		(net "M_I_CPU1_SA_DQ<9>")
	)
	(gr_poly
		(pts
			(xy 134.434834 -230.51262) (xy 134.434834 -230.46817) (xy 134.234682 -230.46817) (xy 134.234682 -230.51262)
			(xy 134.334758 -230.612696)
		)
		(stroke
			(width 0)
			(type solid)
		)
		(fill yes)
		(layer "In2.Cu")
		(net "M_I_CPU1_SA_DQ<10>")
	)
	(gr_poly
		(pts
			(xy 134.434834 -229.296214) (xy 134.334758 -229.196138) (xy 134.234682 -229.296214) (xy 134.234682 -229.340664)
			(xy 134.434834 -229.340664)
		)
		(stroke
			(width 0)
			(type solid)
		)
		(fill yes)
		(layer "In2.Cu")
		(net "M_I_CPU1_SA_DQ<5>")
	)
	(gr_poly
		(pts
			(xy 134.434834 -228.892608) (xy 134.434834 -228.848158) (xy 134.234682 -228.848158) (xy 134.234682 -228.892608)
			(xy 134.334758 -228.992684)
		)
		(stroke
			(width 0)
			(type solid)
		)
		(fill yes)
		(layer "In2.Cu")
		(net "M_I_CPU1_SA_DQ<6>")
	)
	(gr_poly
		(pts
			(xy 134.434834 -227.676202) (xy 134.334758 -227.57638) (xy 134.234682 -227.676202) (xy 134.234682 -227.723954)
			(xy 134.434834 -227.723954)
		)
		(stroke
			(width 0)
			(type solid)
		)
		(fill yes)
		(layer "In2.Cu")
		(net "M_I_CPU1_SA_DQS_DN<5>")
	)
	(gr_poly
		(pts
			(xy 134.434834 -227.27285) (xy 134.434834 -227.225098) (xy 134.234682 -227.225098) (xy 134.234682 -227.27285)
			(xy 134.334758 -227.372672)
		)
		(stroke
			(width 0)
			(type solid)
		)
		(fill yes)
		(layer "In2.Cu")
		(net "M_I_CPU1_SA_DQS_DN<0>")
	)
	(gr_poly
		(pts
			(xy 134.434834 -226.056444) (xy 134.334758 -225.956368) (xy 134.234682 -226.056444) (xy 134.234682 -226.100894)
			(xy 134.434834 -226.100894)
		)
		(stroke
			(width 0)
			(type solid)
		)
		(fill yes)
		(layer "In2.Cu")
		(net "M_I_CPU1_SA_DQ<1>")
	)
	(gr_poly
		(pts
			(xy 134.434834 -225.652584) (xy 134.434834 -225.608134) (xy 134.234682 -225.608134) (xy 134.234682 -225.652584)
			(xy 134.334758 -225.75266)
		)
		(stroke
			(width 0)
			(type solid)
		)
		(fill yes)
		(layer "In2.Cu")
		(net "M_I_CPU1_SA_DQ<2>")
	)
	(gr_poly
		(pts
			(xy 134.734808 -293.32428) (xy 134.734808 -293.27983) (xy 134.534656 -293.27983) (xy 134.534656 -293.32428)
			(xy 134.634732 -293.424356)
		)
		(stroke
			(width 0)
			(type solid)
		)
		(fill yes)
		(layer "In2.Cu")
		(net "M_I_CPU1_SB_DQ<31>")
	)
	(gr_poly
		(pts
			(xy 134.734808 -292.108128) (xy 134.634732 -292.008052) (xy 134.534656 -292.108128) (xy 134.534656 -292.152578)
			(xy 134.734808 -292.152578)
		)
		(stroke
			(width 0)
			(type solid)
		)
		(fill yes)
		(layer "In2.Cu")
		(net "M_I_CPU1_SB_DQ<28>")
	)
	(gr_poly
		(pts
			(xy 134.734808 -291.704522) (xy 134.734808 -291.65677) (xy 134.534656 -291.65677) (xy 134.534656 -291.704522)
			(xy 134.634732 -291.804344)
		)
		(stroke
			(width 0)
			(type solid)
		)
		(fill yes)
		(layer "In2.Cu")
		(net "M_I_CPU1_SB_DQS_DP<8>")
	)
	(gr_poly
		(pts
			(xy 134.734808 -290.487862) (xy 134.634732 -290.38804) (xy 134.534656 -290.487862) (xy 134.534656 -290.535614)
			(xy 134.734808 -290.535614)
		)
		(stroke
			(width 0)
			(type solid)
		)
		(fill yes)
		(layer "In2.Cu")
		(net "M_I_CPU1_SB_DQS_DP<3>")
	)
	(gr_poly
		(pts
			(xy 134.734808 -290.084256) (xy 134.734808 -290.039806) (xy 134.534656 -290.039806) (xy 134.534656 -290.084256)
			(xy 134.634732 -290.184332)
		)
		(stroke
			(width 0)
			(type solid)
		)
		(fill yes)
		(layer "In2.Cu")
		(net "M_I_CPU1_SB_DQ<27>")
	)
	(gr_poly
		(pts
			(xy 134.734808 -288.868104) (xy 134.634732 -288.768028) (xy 134.534656 -288.868104) (xy 134.534656 -288.912554)
			(xy 134.734808 -288.912554)
		)
		(stroke
			(width 0)
			(type solid)
		)
		(fill yes)
		(layer "In2.Cu")
		(net "M_I_CPU1_SB_DQ<24>")
	)
	(gr_poly
		(pts
			(xy 134.734808 -288.464498) (xy 134.734808 -288.420048) (xy 134.534656 -288.420048) (xy 134.534656 -288.464498)
			(xy 134.634732 -288.564574)
		)
		(stroke
			(width 0)
			(type solid)
		)
		(fill yes)
		(layer "In2.Cu")
		(net "M_I_CPU1_SB_DQ<23>")
	)
	(gr_poly
		(pts
			(xy 134.734808 -287.248092) (xy 134.634732 -287.148016) (xy 134.534656 -287.248092) (xy 134.534656 -287.292542)
			(xy 134.734808 -287.292542)
		)
		(stroke
			(width 0)
			(type solid)
		)
		(fill yes)
		(layer "In2.Cu")
		(net "M_I_CPU1_SB_DQ<20>")
	)
	(gr_poly
		(pts
			(xy 134.734808 -286.844486) (xy 134.734808 -286.796734) (xy 134.534656 -286.796734) (xy 134.534656 -286.844486)
			(xy 134.634732 -286.944562)
		)
		(stroke
			(width 0)
			(type solid)
		)
		(fill yes)
		(layer "In2.Cu")
		(net "M_I_CPU1_SB_DQS_DP<7>")
	)
	(gr_poly
		(pts
			(xy 134.734808 -285.62808) (xy 134.634732 -285.528258) (xy 134.534656 -285.62808) (xy 134.534656 -285.675832)
			(xy 134.734808 -285.675832)
		)
		(stroke
			(width 0)
			(type solid)
		)
		(fill yes)
		(layer "In2.Cu")
		(net "M_I_CPU1_SB_DQS_DP<2>")
	)
	(gr_poly
		(pts
			(xy 134.734808 -285.224474) (xy 134.734808 -285.180024) (xy 134.534656 -285.180024) (xy 134.534656 -285.224474)
			(xy 134.634732 -285.32455)
		)
		(stroke
			(width 0)
			(type solid)
		)
		(fill yes)
		(layer "In2.Cu")
		(net "M_I_CPU1_SB_DQ<19>")
	)
	(gr_poly
		(pts
			(xy 134.734808 -284.008322) (xy 134.634732 -283.908246) (xy 134.534656 -284.008322) (xy 134.534656 -284.052772)
			(xy 134.734808 -284.052772)
		)
		(stroke
			(width 0)
			(type solid)
		)
		(fill yes)
		(layer "In2.Cu")
		(net "M_I_CPU1_SB_DQ<16>")
	)
	(gr_poly
		(pts
			(xy 134.734808 -283.604462) (xy 134.734808 -283.560012) (xy 134.534656 -283.560012) (xy 134.534656 -283.604462)
			(xy 134.634732 -283.704538)
		)
		(stroke
			(width 0)
			(type solid)
		)
		(fill yes)
		(layer "In2.Cu")
		(net "M_I_CPU1_SB_DQ<15>")
	)
	(gr_poly
		(pts
			(xy 134.734808 -282.38831) (xy 134.634732 -282.288234) (xy 134.534656 -282.38831) (xy 134.534656 -282.43276)
			(xy 134.734808 -282.43276)
		)
		(stroke
			(width 0)
			(type solid)
		)
		(fill yes)
		(layer "In2.Cu")
		(net "M_I_CPU1_SB_DQ<12>")
	)
	(gr_poly
		(pts
			(xy 134.734808 -281.984704) (xy 134.734808 -281.936952) (xy 134.534656 -281.936952) (xy 134.534656 -281.984704)
			(xy 134.634732 -282.084526)
		)
		(stroke
			(width 0)
			(type solid)
		)
		(fill yes)
		(layer "In2.Cu")
		(net "M_I_CPU1_SB_DQS_DP<6>")
	)
	(gr_poly
		(pts
			(xy 134.734808 -280.768044) (xy 134.634732 -280.668222) (xy 134.534656 -280.768044) (xy 134.534656 -280.815796)
			(xy 134.734808 -280.815796)
		)
		(stroke
			(width 0)
			(type solid)
		)
		(fill yes)
		(layer "In2.Cu")
		(net "M_I_CPU1_SB_DQS_DP<1>")
	)
	(gr_poly
		(pts
			(xy 134.734808 -280.364438) (xy 134.734808 -280.319988) (xy 134.534656 -280.319988) (xy 134.534656 -280.364438)
			(xy 134.634732 -280.464514)
		)
		(stroke
			(width 0)
			(type solid)
		)
		(fill yes)
		(layer "In2.Cu")
		(net "M_I_CPU1_SB_DQ<11>")
	)
	(gr_poly
		(pts
			(xy 134.734808 -279.148286) (xy 134.634732 -279.04821) (xy 134.534656 -279.148286) (xy 134.534656 -279.192736)
			(xy 134.734808 -279.192736)
		)
		(stroke
			(width 0)
			(type solid)
		)
		(fill yes)
		(layer "In2.Cu")
		(net "M_I_CPU1_SB_DQ<8>")
	)
	(gr_poly
		(pts
			(xy 134.734808 -278.744426) (xy 134.734808 -278.699976) (xy 134.534656 -278.699976) (xy 134.534656 -278.744426)
			(xy 134.634732 -278.844502)
		)
		(stroke
			(width 0)
			(type solid)
		)
		(fill yes)
		(layer "In2.Cu")
		(net "M_I_CPU1_SB_DQ<7>")
	)
	(gr_poly
		(pts
			(xy 134.734808 -277.528274) (xy 134.634732 -277.428198) (xy 134.534656 -277.528274) (xy 134.534656 -277.572724)
			(xy 134.734808 -277.572724)
		)
		(stroke
			(width 0)
			(type solid)
		)
		(fill yes)
		(layer "In2.Cu")
		(net "M_I_CPU1_SB_DQ<4>")
	)
	(gr_poly
		(pts
			(xy 134.734808 -277.124668) (xy 134.734808 -277.076916) (xy 134.534656 -277.076916) (xy 134.534656 -277.124668)
			(xy 134.634732 -277.22449)
		)
		(stroke
			(width 0)
			(type solid)
		)
		(fill yes)
		(layer "In2.Cu")
		(net "M_I_CPU1_SB_DQS_DP<5>")
	)
	(gr_poly
		(pts
			(xy 134.734808 -275.908008) (xy 134.634732 -275.808186) (xy 134.534656 -275.908008) (xy 134.534656 -275.95576)
			(xy 134.734808 -275.95576)
		)
		(stroke
			(width 0)
			(type solid)
		)
		(fill yes)
		(layer "In2.Cu")
		(net "M_I_CPU1_SB_DQS_DP<0>")
	)
	(gr_poly
		(pts
			(xy 134.734808 -275.504402) (xy 134.734808 -275.459952) (xy 134.534656 -275.459952) (xy 134.534656 -275.504402)
			(xy 134.634732 -275.604478)
		)
		(stroke
			(width 0)
			(type solid)
		)
		(fill yes)
		(layer "In2.Cu")
		(net "M_I_CPU1_SB_DQ<3>")
	)
	(gr_poly
		(pts
			(xy 134.734808 -274.28825) (xy 134.634732 -274.188174) (xy 134.534656 -274.28825) (xy 134.534656 -274.3327)
			(xy 134.734808 -274.3327)
		)
		(stroke
			(width 0)
			(type solid)
		)
		(fill yes)
		(layer "In2.Cu")
		(net "M_I_CPU1_SB_DQ<0>")
	)
	(gr_poly
		(pts
			(xy 134.734808 -273.88439) (xy 134.734808 -273.83994) (xy 134.534656 -273.83994) (xy 134.534656 -273.88439)
			(xy 134.634732 -273.984466)
		)
		(stroke
			(width 0)
			(type solid)
		)
		(fill yes)
		(layer "In2.Cu")
		(net "M_I_CPU1_SB_CB<3>")
	)
	(gr_poly
		(pts
			(xy 134.734808 -272.668238) (xy 134.634732 -272.568162) (xy 134.534656 -272.668238) (xy 134.534656 -272.712688)
			(xy 134.734808 -272.712688)
		)
		(stroke
			(width 0)
			(type solid)
		)
		(fill yes)
		(layer "In2.Cu")
		(net "M_I_CPU1_SB_CB<0>")
	)
	(gr_poly
		(pts
			(xy 134.734808 -272.264632) (xy 134.734808 -272.21688) (xy 134.534656 -272.21688) (xy 134.534656 -272.264632)
			(xy 134.634732 -272.364454)
		)
		(stroke
			(width 0)
			(type solid)
		)
		(fill yes)
		(layer "In2.Cu")
		(net "M_I_CPU1_SB_DQS_DP<4>")
	)
	(gr_poly
		(pts
			(xy 134.734808 -271.047972) (xy 134.634732 -270.94815) (xy 134.534656 -271.047972) (xy 134.534656 -271.095724)
			(xy 134.734808 -271.095724)
		)
		(stroke
			(width 0)
			(type solid)
		)
		(fill yes)
		(layer "In2.Cu")
		(net "M_I_CPU1_SB_DQS_DP<9>")
	)
	(gr_poly
		(pts
			(xy 134.734808 -270.644366) (xy 134.734808 -270.599916) (xy 134.534656 -270.599916) (xy 134.534656 -270.644366)
			(xy 134.634732 -270.744442)
		)
		(stroke
			(width 0)
			(type solid)
		)
		(fill yes)
		(layer "In2.Cu")
		(net "M_I_CPU1_SB_CB<7>")
	)
	(gr_poly
		(pts
			(xy 134.734808 -269.428214) (xy 134.634732 -269.328138) (xy 134.534656 -269.428214) (xy 134.534656 -269.472664)
			(xy 134.734808 -269.472664)
		)
		(stroke
			(width 0)
			(type solid)
		)
		(fill yes)
		(layer "In2.Cu")
		(net "M_I_CPU1_SB_CB<4>")
	)
	(gr_poly
		(pts
			(xy 134.734808 -267.404342) (xy 134.734808 -267.359892) (xy 134.534656 -267.359892) (xy 134.534656 -267.404342)
			(xy 134.634732 -267.504418)
		)
		(stroke
			(width 0)
			(type solid)
		)
		(fill yes)
		(layer "In2.Cu")
		(net "M_I_CPU1_SB_RSP<0>")
	)
	(gr_poly
		(pts
			(xy 134.734808 -265.78433) (xy 134.734808 -265.73988) (xy 134.534656 -265.73988) (xy 134.534656 -265.78433)
			(xy 134.634732 -265.884406)
		)
		(stroke
			(width 0)
			(type solid)
		)
		(fill yes)
		(layer "In2.Cu")
		(net "M_I_CPU1_SB_CS_N<0>")
	)
	(gr_poly
		(pts
			(xy 134.734808 -264.568178) (xy 134.634732 -264.468102) (xy 134.534656 -264.568178) (xy 134.534656 -264.612628)
			(xy 134.734808 -264.612628)
		)
		(stroke
			(width 0)
			(type solid)
		)
		(fill yes)
		(layer "In2.Cu")
		(net "M_I_CPU1_SB_CA<6>")
	)
	(gr_poly
		(pts
			(xy 134.734808 -264.164318) (xy 134.734808 -264.119868) (xy 134.534656 -264.119868) (xy 134.534656 -264.164318)
			(xy 134.634732 -264.264394)
		)
		(stroke
			(width 0)
			(type solid)
		)
		(fill yes)
		(layer "In2.Cu")
		(net "M_I_CPU1_SB_CA<5>")
	)
	(gr_poly
		(pts
			(xy 134.734808 -262.948166) (xy 134.634732 -262.84809) (xy 134.534656 -262.948166) (xy 134.534656 -262.992616)
			(xy 134.734808 -262.992616)
		)
		(stroke
			(width 0)
			(type solid)
		)
		(fill yes)
		(layer "In2.Cu")
		(net "M_I_CPU1_SB_CA<2>")
	)
	(gr_poly
		(pts
			(xy 134.734808 -262.544306) (xy 134.734808 -262.499856) (xy 134.534656 -262.499856) (xy 134.534656 -262.544306)
			(xy 134.634732 -262.644382)
		)
		(stroke
			(width 0)
			(type solid)
		)
		(fill yes)
		(layer "In2.Cu")
		(net "M_I_CPU1_SB_CA<1>")
	)
	(gr_poly
		(pts
			(xy 134.904734 -256.026158) (xy 134.804658 -255.926336) (xy 134.704582 -256.026158) (xy 134.704582 -256.07391)
			(xy 134.904734 -256.07391)
		)
		(stroke
			(width 0)
			(type solid)
		)
		(fill yes)
		(layer "In2.Cu")
		(net "M_I_CPU1_CLK_DP<0>")
	)
	(gr_poly
		(pts
			(xy 134.904734 -255.622552) (xy 134.904734 -255.578102) (xy 134.704582 -255.578102) (xy 134.704582 -255.622552)
			(xy 134.804658 -255.722628)
		)
		(stroke
			(width 0)
			(type solid)
		)
		(fill yes)
		(layer "In2.Cu")
		(net "M_I_CPU1_SA_PAR")
	)
	(gr_poly
		(pts
			(xy 134.904734 -254.4064) (xy 134.804658 -254.306324) (xy 134.704582 -254.4064) (xy 134.704582 -254.45085)
			(xy 134.904734 -254.45085)
		)
		(stroke
			(width 0)
			(type solid)
		)
		(fill yes)
		(layer "In2.Cu")
		(net "M_I_CPU1_SA_CA<4>")
	)
	(gr_poly
		(pts
			(xy 134.904734 -254.00254) (xy 134.904734 -253.95809) (xy 134.704582 -253.95809) (xy 134.704582 -254.00254)
			(xy 134.804658 -254.102616)
		)
		(stroke
			(width 0)
			(type solid)
		)
		(fill yes)
		(layer "In2.Cu")
		(net "M_I_CPU1_SA_CA<3>")
	)
	(gr_poly
		(pts
			(xy 134.904734 -252.786388) (xy 134.804658 -252.686312) (xy 134.704582 -252.786388) (xy 134.704582 -252.830838)
			(xy 134.904734 -252.830838)
		)
		(stroke
			(width 0)
			(type solid)
		)
		(fill yes)
		(layer "In2.Cu")
		(net "M_I_CPU1_SA_CA<0>")
	)
	(gr_poly
		(pts
			(xy 134.904734 -251.166376) (xy 134.804658 -251.0663) (xy 134.704582 -251.166376) (xy 134.704582 -251.210826)
			(xy 134.904734 -251.210826)
		)
		(stroke
			(width 0)
			(type solid)
		)
		(fill yes)
		(layer "In2.Cu")
		(net "M_I_CPU1_SA_CS_N<0>")
	)
	(gr_poly
		(pts
			(xy 134.904734 -250.762516) (xy 134.904734 -250.718066) (xy 134.704582 -250.718066) (xy 134.704582 -250.762516)
			(xy 134.804658 -250.862592)
		)
		(stroke
			(width 0)
			(type solid)
		)
		(fill yes)
		(layer "In2.Cu")
		(net "M_I_CPU1_RESET_N")
	)
	(gr_poly
		(pts
			(xy 134.904734 -249.142504) (xy 134.904734 -249.098054) (xy 134.704582 -249.098054) (xy 134.704582 -249.142504)
			(xy 134.804658 -249.24258)
		)
		(stroke
			(width 0)
			(type solid)
		)
		(fill yes)
		(layer "In2.Cu")
		(net "M_I_CPU1_SA_CB<7>")
	)
	(gr_poly
		(pts
			(xy 134.904734 -247.926352) (xy 134.804658 -247.826276) (xy 134.704582 -247.926352) (xy 134.704582 -247.970802)
			(xy 134.904734 -247.970802)
		)
		(stroke
			(width 0)
			(type solid)
		)
		(fill yes)
		(layer "In2.Cu")
		(net "M_I_CPU1_SA_CB<4>")
	)
	(gr_poly
		(pts
			(xy 134.904734 -247.522746) (xy 134.904734 -247.474994) (xy 134.704582 -247.474994) (xy 134.704582 -247.522746)
			(xy 134.804658 -247.622568)
		)
		(stroke
			(width 0)
			(type solid)
		)
		(fill yes)
		(layer "In2.Cu")
		(net "M_I_CPU1_SA_DQS_DP<9>")
	)
	(gr_poly
		(pts
			(xy 134.904734 -246.306086) (xy 134.804658 -246.206264) (xy 134.704582 -246.306086) (xy 134.704582 -246.353838)
			(xy 134.904734 -246.353838)
		)
		(stroke
			(width 0)
			(type solid)
		)
		(fill yes)
		(layer "In2.Cu")
		(net "M_I_CPU1_SA_DQS_DP<4>")
	)
	(gr_poly
		(pts
			(xy 134.904734 -245.90248) (xy 134.904734 -245.85803) (xy 134.704582 -245.85803) (xy 134.704582 -245.90248)
			(xy 134.804658 -246.002556)
		)
		(stroke
			(width 0)
			(type solid)
		)
		(fill yes)
		(layer "In2.Cu")
		(net "M_I_CPU1_SA_CB<3>")
	)
	(gr_poly
		(pts
			(xy 134.904734 -244.686328) (xy 134.804658 -244.586252) (xy 134.704582 -244.686328) (xy 134.704582 -244.730778)
			(xy 134.904734 -244.730778)
		)
		(stroke
			(width 0)
			(type solid)
		)
		(fill yes)
		(layer "In2.Cu")
		(net "M_I_CPU1_SA_CB<0>")
	)
	(gr_poly
		(pts
			(xy 134.904734 -244.282468) (xy 134.904734 -244.238018) (xy 134.704582 -244.238018) (xy 134.704582 -244.282468)
			(xy 134.804658 -244.382544)
		)
		(stroke
			(width 0)
			(type solid)
		)
		(fill yes)
		(layer "In2.Cu")
		(net "M_I_CPU1_SA_DQ<31>")
	)
	(gr_poly
		(pts
			(xy 134.904734 -243.066316) (xy 134.804658 -242.96624) (xy 134.704582 -243.066316) (xy 134.704582 -243.110766)
			(xy 134.904734 -243.110766)
		)
		(stroke
			(width 0)
			(type solid)
		)
		(fill yes)
		(layer "In2.Cu")
		(net "M_I_CPU1_SA_DQ<28>")
	)
	(gr_poly
		(pts
			(xy 134.904734 -242.66271) (xy 134.904734 -242.614958) (xy 134.704582 -242.614958) (xy 134.704582 -242.66271)
			(xy 134.804658 -242.762532)
		)
		(stroke
			(width 0)
			(type solid)
		)
		(fill yes)
		(layer "In2.Cu")
		(net "M_I_CPU1_SA_DQS_DP<8>")
	)
	(gr_poly
		(pts
			(xy 134.904734 -241.44605) (xy 134.804658 -241.346228) (xy 134.704582 -241.44605) (xy 134.704582 -241.493802)
			(xy 134.904734 -241.493802)
		)
		(stroke
			(width 0)
			(type solid)
		)
		(fill yes)
		(layer "In2.Cu")
		(net "M_I_CPU1_SA_DQS_DP<3>")
	)
	(gr_poly
		(pts
			(xy 134.904734 -241.042444) (xy 134.904734 -240.997994) (xy 134.704582 -240.997994) (xy 134.704582 -241.042444)
			(xy 134.804658 -241.14252)
		)
		(stroke
			(width 0)
			(type solid)
		)
		(fill yes)
		(layer "In2.Cu")
		(net "M_I_CPU1_SA_DQ<27>")
	)
	(gr_poly
		(pts
			(xy 134.904734 -239.826292) (xy 134.804658 -239.726216) (xy 134.704582 -239.826292) (xy 134.704582 -239.870742)
			(xy 134.904734 -239.870742)
		)
		(stroke
			(width 0)
			(type solid)
		)
		(fill yes)
		(layer "In2.Cu")
		(net "M_I_CPU1_SA_DQ<24>")
	)
	(gr_poly
		(pts
			(xy 134.904734 -239.422432) (xy 134.904734 -239.377982) (xy 134.704582 -239.377982) (xy 134.704582 -239.422432)
			(xy 134.804658 -239.522508)
		)
		(stroke
			(width 0)
			(type solid)
		)
		(fill yes)
		(layer "In2.Cu")
		(net "M_I_CPU1_SA_DQ<23>")
	)
	(gr_poly
		(pts
			(xy 134.904734 -238.20628) (xy 134.804658 -238.106204) (xy 134.704582 -238.20628) (xy 134.704582 -238.25073)
			(xy 134.904734 -238.25073)
		)
		(stroke
			(width 0)
			(type solid)
		)
		(fill yes)
		(layer "In2.Cu")
		(net "M_I_CPU1_SA_DQ<20>")
	)
	(gr_poly
		(pts
			(xy 134.904734 -237.802674) (xy 134.904734 -237.754922) (xy 134.704582 -237.754922) (xy 134.704582 -237.802674)
			(xy 134.804658 -237.902496)
		)
		(stroke
			(width 0)
			(type solid)
		)
		(fill yes)
		(layer "In2.Cu")
		(net "M_I_CPU1_SA_DQS_DP<7>")
	)
	(gr_poly
		(pts
			(xy 134.904734 -236.586014) (xy 134.804658 -236.486192) (xy 134.704582 -236.586014) (xy 134.704582 -236.633766)
			(xy 134.904734 -236.633766)
		)
		(stroke
			(width 0)
			(type solid)
		)
		(fill yes)
		(layer "In2.Cu")
		(net "M_I_CPU1_SA_DQS_DP<2>")
	)
	(gr_poly
		(pts
			(xy 134.904734 -236.182408) (xy 134.904734 -236.137958) (xy 134.704582 -236.137958) (xy 134.704582 -236.182408)
			(xy 134.804658 -236.282484)
		)
		(stroke
			(width 0)
			(type solid)
		)
		(fill yes)
		(layer "In2.Cu")
		(net "M_I_CPU1_SA_DQ<19>")
	)
	(gr_poly
		(pts
			(xy 134.904734 -234.966256) (xy 134.804658 -234.86618) (xy 134.704582 -234.966256) (xy 134.704582 -235.010706)
			(xy 134.904734 -235.010706)
		)
		(stroke
			(width 0)
			(type solid)
		)
		(fill yes)
		(layer "In2.Cu")
		(net "M_I_CPU1_SA_DQ<16>")
	)
	(gr_poly
		(pts
			(xy 134.904734 -234.562396) (xy 134.904734 -234.517946) (xy 134.704582 -234.517946) (xy 134.704582 -234.562396)
			(xy 134.804658 -234.662472)
		)
		(stroke
			(width 0)
			(type solid)
		)
		(fill yes)
		(layer "In2.Cu")
		(net "M_I_CPU1_SA_DQ<15>")
	)
	(gr_poly
		(pts
			(xy 134.904734 -233.346244) (xy 134.804658 -233.246168) (xy 134.704582 -233.346244) (xy 134.704582 -233.390694)
			(xy 134.904734 -233.390694)
		)
		(stroke
			(width 0)
			(type solid)
		)
		(fill yes)
		(layer "In2.Cu")
		(net "M_I_CPU1_SA_DQ<12>")
	)
	(gr_poly
		(pts
			(xy 134.904734 -232.942638) (xy 134.904734 -232.894886) (xy 134.704582 -232.894886) (xy 134.704582 -232.942638)
			(xy 134.804658 -233.04246)
		)
		(stroke
			(width 0)
			(type solid)
		)
		(fill yes)
		(layer "In2.Cu")
		(net "M_I_CPU1_SA_DQS_DP<6>")
	)
	(gr_poly
		(pts
			(xy 134.904734 -231.725978) (xy 134.804658 -231.626156) (xy 134.704582 -231.725978) (xy 134.704582 -231.77373)
			(xy 134.904734 -231.77373)
		)
		(stroke
			(width 0)
			(type solid)
		)
		(fill yes)
		(layer "In2.Cu")
		(net "M_I_CPU1_SA_DQS_DP<1>")
	)
	(gr_poly
		(pts
			(xy 134.904734 -231.322626) (xy 134.904734 -231.278176) (xy 134.704582 -231.278176) (xy 134.704582 -231.322626)
			(xy 134.804658 -231.422702)
		)
		(stroke
			(width 0)
			(type solid)
		)
		(fill yes)
		(layer "In2.Cu")
		(net "M_I_CPU1_SA_DQ<11>")
	)
	(gr_poly
		(pts
			(xy 134.904734 -230.10622) (xy 134.804658 -230.006144) (xy 134.704582 -230.10622) (xy 134.704582 -230.15067)
			(xy 134.904734 -230.15067)
		)
		(stroke
			(width 0)
			(type solid)
		)
		(fill yes)
		(layer "In2.Cu")
		(net "M_I_CPU1_SA_DQ<8>")
	)
	(gr_poly
		(pts
			(xy 134.904734 -229.702614) (xy 134.904734 -229.658164) (xy 134.704582 -229.658164) (xy 134.704582 -229.702614)
			(xy 134.804658 -229.80269)
		)
		(stroke
			(width 0)
			(type solid)
		)
		(fill yes)
		(layer "In2.Cu")
		(net "M_I_CPU1_SA_DQ<7>")
	)
	(gr_poly
		(pts
			(xy 134.904734 -228.486462) (xy 134.804658 -228.386386) (xy 134.704582 -228.486462) (xy 134.704582 -228.530912)
			(xy 134.904734 -228.530912)
		)
		(stroke
			(width 0)
			(type solid)
		)
		(fill yes)
		(layer "In2.Cu")
		(net "M_I_CPU1_SA_DQ<4>")
	)
	(gr_poly
		(pts
			(xy 134.904734 -228.082856) (xy 134.904734 -228.035104) (xy 134.704582 -228.035104) (xy 134.704582 -228.082856)
			(xy 134.804658 -228.182678)
		)
		(stroke
			(width 0)
			(type solid)
		)
		(fill yes)
		(layer "In2.Cu")
		(net "M_I_CPU1_SA_DQS_DP<5>")
	)
	(gr_poly
		(pts
			(xy 134.904734 -226.866196) (xy 134.804658 -226.766374) (xy 134.704582 -226.866196) (xy 134.704582 -226.913948)
			(xy 134.904734 -226.913948)
		)
		(stroke
			(width 0)
			(type solid)
		)
		(fill yes)
		(layer "In2.Cu")
		(net "M_I_CPU1_SA_DQS_DP<0>")
	)
	(gr_poly
		(pts
			(xy 134.904734 -226.46259) (xy 134.904734 -226.41814) (xy 134.704582 -226.41814) (xy 134.704582 -226.46259)
			(xy 134.804658 -226.562666)
		)
		(stroke
			(width 0)
			(type solid)
		)
		(fill yes)
		(layer "In2.Cu")
		(net "M_I_CPU1_SA_DQ<3>")
	)
	(gr_poly
		(pts
			(xy 134.904734 -225.246438) (xy 134.804658 -225.146362) (xy 134.704582 -225.246438) (xy 134.704582 -225.290888)
			(xy 134.904734 -225.290888)
		)
		(stroke
			(width 0)
			(type solid)
		)
		(fill yes)
		(layer "In2.Cu")
		(net "M_I_CPU1_SA_DQ<0>")
	)
	(gr_poly
		(pts
			(xy 135.204708 -292.918134) (xy 135.104632 -292.818058) (xy 135.004556 -292.918134) (xy 135.004556 -292.962584)
			(xy 135.204708 -292.962584)
		)
		(stroke
			(width 0)
			(type solid)
		)
		(fill yes)
		(layer "In2.Cu")
		(net "M_I_CPU1_SB_DQ<29>")
	)
	(gr_poly
		(pts
			(xy 135.204708 -292.514274) (xy 135.204708 -292.469824) (xy 135.004556 -292.469824) (xy 135.004556 -292.514274)
			(xy 135.104632 -292.61435)
		)
		(stroke
			(width 0)
			(type solid)
		)
		(fill yes)
		(layer "In2.Cu")
		(net "M_I_CPU1_SB_DQ<30>")
	)
	(gr_poly
		(pts
			(xy 135.204708 -291.297868) (xy 135.104632 -291.198046) (xy 135.004556 -291.297868) (xy 135.004556 -291.34562)
			(xy 135.204708 -291.34562)
		)
		(stroke
			(width 0)
			(type solid)
		)
		(fill yes)
		(layer "In2.Cu")
		(net "M_I_CPU1_SB_DQS_DN<8>")
	)
	(gr_poly
		(pts
			(xy 135.204708 -290.894516) (xy 135.204708 -290.846764) (xy 135.004556 -290.846764) (xy 135.004556 -290.894516)
			(xy 135.104632 -290.994338)
		)
		(stroke
			(width 0)
			(type solid)
		)
		(fill yes)
		(layer "In2.Cu")
		(net "M_I_CPU1_SB_DQS_DN<3>")
	)
	(gr_poly
		(pts
			(xy 135.204708 -289.67811) (xy 135.104632 -289.578034) (xy 135.004556 -289.67811) (xy 135.004556 -289.72256)
			(xy 135.204708 -289.72256)
		)
		(stroke
			(width 0)
			(type solid)
		)
		(fill yes)
		(layer "In2.Cu")
		(net "M_I_CPU1_SB_DQ<25>")
	)
	(gr_poly
		(pts
			(xy 135.204708 -289.27425) (xy 135.204708 -289.2298) (xy 135.004556 -289.2298) (xy 135.004556 -289.27425)
			(xy 135.104632 -289.374326)
		)
		(stroke
			(width 0)
			(type solid)
		)
		(fill yes)
		(layer "In2.Cu")
		(net "M_I_CPU1_SB_DQ<26>")
	)
	(gr_poly
		(pts
			(xy 135.204708 -288.058098) (xy 135.104632 -287.958022) (xy 135.004556 -288.058098) (xy 135.004556 -288.102548)
			(xy 135.204708 -288.102548)
		)
		(stroke
			(width 0)
			(type solid)
		)
		(fill yes)
		(layer "In2.Cu")
		(net "M_I_CPU1_SB_DQ<21>")
	)
	(gr_poly
		(pts
			(xy 135.204708 -287.654492) (xy 135.204708 -287.610042) (xy 135.004556 -287.610042) (xy 135.004556 -287.654492)
			(xy 135.104632 -287.754568)
		)
		(stroke
			(width 0)
			(type solid)
		)
		(fill yes)
		(layer "In2.Cu")
		(net "M_I_CPU1_SB_DQ<22>")
	)
	(gr_poly
		(pts
			(xy 135.204708 -286.438086) (xy 135.104632 -286.33801) (xy 135.004556 -286.438086) (xy 135.004556 -286.485838)
			(xy 135.204708 -286.485838)
		)
		(stroke
			(width 0)
			(type solid)
		)
		(fill yes)
		(layer "In2.Cu")
		(net "M_I_CPU1_SB_DQS_DN<7>")
	)
	(gr_poly
		(pts
			(xy 135.204708 -286.034734) (xy 135.204708 -285.986982) (xy 135.004556 -285.986982) (xy 135.004556 -286.034734)
			(xy 135.104632 -286.134556)
		)
		(stroke
			(width 0)
			(type solid)
		)
		(fill yes)
		(layer "In2.Cu")
		(net "M_I_CPU1_SB_DQS_DN<2>")
	)
	(gr_poly
		(pts
			(xy 135.204708 -284.818328) (xy 135.104632 -284.718252) (xy 135.004556 -284.818328) (xy 135.004556 -284.862778)
			(xy 135.204708 -284.862778)
		)
		(stroke
			(width 0)
			(type solid)
		)
		(fill yes)
		(layer "In2.Cu")
		(net "M_I_CPU1_SB_DQ<17>")
	)
	(gr_poly
		(pts
			(xy 135.204708 -284.414468) (xy 135.204708 -284.370018) (xy 135.004556 -284.370018) (xy 135.004556 -284.414468)
			(xy 135.104632 -284.514544)
		)
		(stroke
			(width 0)
			(type solid)
		)
		(fill yes)
		(layer "In2.Cu")
		(net "M_I_CPU1_SB_DQ<18>")
	)
	(gr_poly
		(pts
			(xy 135.204708 -283.198316) (xy 135.104632 -283.09824) (xy 135.004556 -283.198316) (xy 135.004556 -283.242766)
			(xy 135.204708 -283.242766)
		)
		(stroke
			(width 0)
			(type solid)
		)
		(fill yes)
		(layer "In2.Cu")
		(net "M_I_CPU1_SB_DQ<13>")
	)
	(gr_poly
		(pts
			(xy 135.204708 -282.794456) (xy 135.204708 -282.750006) (xy 135.004556 -282.750006) (xy 135.004556 -282.794456)
			(xy 135.104632 -282.894532)
		)
		(stroke
			(width 0)
			(type solid)
		)
		(fill yes)
		(layer "In2.Cu")
		(net "M_I_CPU1_SB_DQ<14>")
	)
	(gr_poly
		(pts
			(xy 135.204708 -281.57805) (xy 135.104632 -281.478228) (xy 135.004556 -281.57805) (xy 135.004556 -281.625802)
			(xy 135.204708 -281.625802)
		)
		(stroke
			(width 0)
			(type solid)
		)
		(fill yes)
		(layer "In2.Cu")
		(net "M_I_CPU1_SB_DQS_DN<6>")
	)
	(gr_poly
		(pts
			(xy 135.204708 -281.174698) (xy 135.204708 -281.126946) (xy 135.004556 -281.126946) (xy 135.004556 -281.174698)
			(xy 135.104632 -281.27452)
		)
		(stroke
			(width 0)
			(type solid)
		)
		(fill yes)
		(layer "In2.Cu")
		(net "M_I_CPU1_SB_DQS_DN<1>")
	)
	(gr_poly
		(pts
			(xy 135.204708 -279.958292) (xy 135.104632 -279.858216) (xy 135.004556 -279.958292) (xy 135.004556 -280.002742)
			(xy 135.204708 -280.002742)
		)
		(stroke
			(width 0)
			(type solid)
		)
		(fill yes)
		(layer "In2.Cu")
		(net "M_I_CPU1_SB_DQ<9>")
	)
	(gr_poly
		(pts
			(xy 135.204708 -279.554432) (xy 135.204708 -279.509982) (xy 135.004556 -279.509982) (xy 135.004556 -279.554432)
			(xy 135.104632 -279.654508)
		)
		(stroke
			(width 0)
			(type solid)
		)
		(fill yes)
		(layer "In2.Cu")
		(net "M_I_CPU1_SB_DQ<10>")
	)
	(gr_poly
		(pts
			(xy 135.204708 -278.33828) (xy 135.104632 -278.238204) (xy 135.004556 -278.33828) (xy 135.004556 -278.38273)
			(xy 135.204708 -278.38273)
		)
		(stroke
			(width 0)
			(type solid)
		)
		(fill yes)
		(layer "In2.Cu")
		(net "M_I_CPU1_SB_DQ<5>")
	)
	(gr_poly
		(pts
			(xy 135.204708 -277.93442) (xy 135.204708 -277.88997) (xy 135.004556 -277.88997) (xy 135.004556 -277.93442)
			(xy 135.104632 -278.034496)
		)
		(stroke
			(width 0)
			(type solid)
		)
		(fill yes)
		(layer "In2.Cu")
		(net "M_I_CPU1_SB_DQ<6>")
	)
	(gr_poly
		(pts
			(xy 135.204708 -276.718014) (xy 135.104632 -276.618192) (xy 135.004556 -276.718014) (xy 135.004556 -276.765766)
			(xy 135.204708 -276.765766)
		)
		(stroke
			(width 0)
			(type solid)
		)
		(fill yes)
		(layer "In2.Cu")
		(net "M_I_CPU1_SB_DQS_DN<5>")
	)
	(gr_poly
		(pts
			(xy 135.204708 -276.314662) (xy 135.204708 -276.26691) (xy 135.004556 -276.26691) (xy 135.004556 -276.314662)
			(xy 135.104632 -276.414484)
		)
		(stroke
			(width 0)
			(type solid)
		)
		(fill yes)
		(layer "In2.Cu")
		(net "M_I_CPU1_SB_DQS_DN<0>")
	)
	(gr_poly
		(pts
			(xy 135.204708 -275.098256) (xy 135.104632 -274.99818) (xy 135.004556 -275.098256) (xy 135.004556 -275.142706)
			(xy 135.204708 -275.142706)
		)
		(stroke
			(width 0)
			(type solid)
		)
		(fill yes)
		(layer "In2.Cu")
		(net "M_I_CPU1_SB_DQ<1>")
	)
	(gr_poly
		(pts
			(xy 135.204708 -274.694396) (xy 135.204708 -274.649946) (xy 135.004556 -274.649946) (xy 135.004556 -274.694396)
			(xy 135.104632 -274.794472)
		)
		(stroke
			(width 0)
			(type solid)
		)
		(fill yes)
		(layer "In2.Cu")
		(net "M_I_CPU1_SB_DQ<2>")
	)
	(gr_poly
		(pts
			(xy 135.204708 -273.478244) (xy 135.104632 -273.378168) (xy 135.004556 -273.478244) (xy 135.004556 -273.522694)
			(xy 135.204708 -273.522694)
		)
		(stroke
			(width 0)
			(type solid)
		)
		(fill yes)
		(layer "In2.Cu")
		(net "M_I_CPU1_SB_CB<1>")
	)
	(gr_poly
		(pts
			(xy 135.204708 -273.074384) (xy 135.204708 -273.029934) (xy 135.004556 -273.029934) (xy 135.004556 -273.074384)
			(xy 135.104632 -273.17446)
		)
		(stroke
			(width 0)
			(type solid)
		)
		(fill yes)
		(layer "In2.Cu")
		(net "M_I_CPU1_SB_CB<2>")
	)
	(gr_poly
		(pts
			(xy 135.204708 -271.857978) (xy 135.104632 -271.758156) (xy 135.004556 -271.857978) (xy 135.004556 -271.90573)
			(xy 135.204708 -271.90573)
		)
		(stroke
			(width 0)
			(type solid)
		)
		(fill yes)
		(layer "In2.Cu")
		(net "M_I_CPU1_SB_DQS_DN<4>")
	)
	(gr_poly
		(pts
			(xy 135.204708 -271.454626) (xy 135.204708 -271.406874) (xy 135.004556 -271.406874) (xy 135.004556 -271.454626)
			(xy 135.104632 -271.554448)
		)
		(stroke
			(width 0)
			(type solid)
		)
		(fill yes)
		(layer "In2.Cu")
		(net "M_I_CPU1_SB_DQS_DN<9>")
	)
	(gr_poly
		(pts
			(xy 135.204708 -270.23822) (xy 135.104632 -270.138144) (xy 135.004556 -270.23822) (xy 135.004556 -270.28267)
			(xy 135.204708 -270.28267)
		)
		(stroke
			(width 0)
			(type solid)
		)
		(fill yes)
		(layer "In2.Cu")
		(net "M_I_CPU1_SB_CB<5>")
	)
	(gr_poly
		(pts
			(xy 135.204708 -269.83436) (xy 135.204708 -269.78991) (xy 135.004556 -269.78991) (xy 135.004556 -269.83436)
			(xy 135.104632 -269.934436)
		)
		(stroke
			(width 0)
			(type solid)
		)
		(fill yes)
		(layer "In2.Cu")
		(net "M_I_CPU1_SB_CB<6>")
	)
	(gr_poly
		(pts
			(xy 135.204708 -266.998196) (xy 135.104632 -266.89812) (xy 135.004556 -266.998196) (xy 135.004556 -267.042646)
			(xy 135.204708 -267.042646)
		)
		(stroke
			(width 0)
			(type solid)
		)
		(fill yes)
		(layer "In2.Cu")
		(net "M_I_CPU1_SA_RSP<0>")
	)
	(gr_poly
		(pts
			(xy 135.204708 -266.594336) (xy 135.204708 -266.549886) (xy 135.004556 -266.549886) (xy 135.004556 -266.594336)
			(xy 135.104632 -266.694412)
		)
		(stroke
			(width 0)
			(type solid)
		)
		(fill yes)
		(layer "In2.Cu")
		(net "M_I_CPU1_SB_CS_N<1>")
	)
	(gr_poly
		(pts
			(xy 135.204708 -265.378184) (xy 135.104632 -265.278108) (xy 135.004556 -265.378184) (xy 135.004556 -265.422634)
			(xy 135.204708 -265.422634)
		)
		(stroke
			(width 0)
			(type solid)
		)
		(fill yes)
		(layer "In2.Cu")
		(net "M_I_CPU1_SB_PAR")
	)
	(gr_poly
		(pts
			(xy 135.204708 -263.758172) (xy 135.104632 -263.658096) (xy 135.004556 -263.758172) (xy 135.004556 -263.802622)
			(xy 135.204708 -263.802622)
		)
		(stroke
			(width 0)
			(type solid)
		)
		(fill yes)
		(layer "In2.Cu")
		(net "M_I_CPU1_SB_CA<4>")
	)
	(gr_poly
		(pts
			(xy 135.204708 -263.354312) (xy 135.204708 -263.309862) (xy 135.004556 -263.309862) (xy 135.004556 -263.354312)
			(xy 135.104632 -263.454388)
		)
		(stroke
			(width 0)
			(type solid)
		)
		(fill yes)
		(layer "In2.Cu")
		(net "M_I_CPU1_SB_CA<3>")
	)
	(gr_poly
		(pts
			(xy 135.204708 -262.13816) (xy 135.104632 -262.038084) (xy 135.004556 -262.13816) (xy 135.004556 -262.18261)
			(xy 135.204708 -262.18261)
		)
		(stroke
			(width 0)
			(type solid)
		)
		(fill yes)
		(layer "In2.Cu")
		(net "M_I_CPU1_SB_CA<0>")
	)
	(gr_poly
		(pts
			(xy 135.374888 -256.432812) (xy 135.374888 -256.38506) (xy 135.174736 -256.38506) (xy 135.174736 -256.432812)
			(xy 135.274812 -256.532634)
		)
		(stroke
			(width 0)
			(type solid)
		)
		(fill yes)
		(layer "In2.Cu")
		(net "M_I_CPU1_CLK_DN<0>")
	)
	(gr_poly
		(pts
			(xy 135.374888 -255.216406) (xy 135.274812 -255.11633) (xy 135.174736 -255.216406) (xy 135.174736 -255.260856)
			(xy 135.374888 -255.260856)
		)
		(stroke
			(width 0)
			(type solid)
		)
		(fill yes)
		(layer "In2.Cu")
		(net "M_I_CPU1_SA_CA<6>")
	)
	(gr_poly
		(pts
			(xy 135.374888 -254.812546) (xy 135.374888 -254.768096) (xy 135.174736 -254.768096) (xy 135.174736 -254.812546)
			(xy 135.274812 -254.912622)
		)
		(stroke
			(width 0)
			(type solid)
		)
		(fill yes)
		(layer "In2.Cu")
		(net "M_I_CPU1_SA_CA<5>")
	)
	(gr_poly
		(pts
			(xy 135.374888 -253.596394) (xy 135.274812 -253.496318) (xy 135.174736 -253.596394) (xy 135.174736 -253.640844)
			(xy 135.374888 -253.640844)
		)
		(stroke
			(width 0)
			(type solid)
		)
		(fill yes)
		(layer "In2.Cu")
		(net "M_I_CPU1_SA_CA<2>")
	)
	(gr_poly
		(pts
			(xy 135.374888 -253.192534) (xy 135.374888 -253.148084) (xy 135.174736 -253.148084) (xy 135.174736 -253.192534)
			(xy 135.274812 -253.29261)
		)
		(stroke
			(width 0)
			(type solid)
		)
		(fill yes)
		(layer "In2.Cu")
		(net "M_I_CPU1_SA_CA<1>")
	)
	(gr_poly
		(pts
			(xy 135.374888 -251.976382) (xy 135.274812 -251.876306) (xy 135.174736 -251.976382) (xy 135.174736 -252.020832)
			(xy 135.374888 -252.020832)
		)
		(stroke
			(width 0)
			(type solid)
		)
		(fill yes)
		(layer "In2.Cu")
		(net "M_I_CPU1_SA_CS_N<1>")
	)
	(gr_poly
		(pts
			(xy 135.374888 -250.35637) (xy 135.274812 -250.256294) (xy 135.174736 -250.35637) (xy 135.174736 -250.40082)
			(xy 135.374888 -250.40082)
		)
		(stroke
			(width 0)
			(type solid)
		)
		(fill yes)
		(layer "In2.Cu")
		(net "M_I_CPU1_ALERT_R_N")
	)
	(gr_poly
		(pts
			(xy 135.374888 -248.736358) (xy 135.274812 -248.636282) (xy 135.174736 -248.736358) (xy 135.174736 -248.780808)
			(xy 135.374888 -248.780808)
		)
		(stroke
			(width 0)
			(type solid)
		)
		(fill yes)
		(layer "In2.Cu")
		(net "M_I_CPU1_SA_CB<5>")
	)
	(gr_poly
		(pts
			(xy 135.374888 -248.332498) (xy 135.374888 -248.288048) (xy 135.174736 -248.288048) (xy 135.174736 -248.332498)
			(xy 135.274812 -248.432574)
		)
		(stroke
			(width 0)
			(type solid)
		)
		(fill yes)
		(layer "In2.Cu")
		(net "M_I_CPU1_SA_CB<6>")
	)
	(gr_poly
		(pts
			(xy 135.374888 -247.116092) (xy 135.274812 -247.01627) (xy 135.174736 -247.116092) (xy 135.174736 -247.163844)
			(xy 135.374888 -247.163844)
		)
		(stroke
			(width 0)
			(type solid)
		)
		(fill yes)
		(layer "In2.Cu")
		(net "M_I_CPU1_SA_DQS_DN<9>")
	)
	(gr_poly
		(pts
			(xy 135.374888 -246.71274) (xy 135.374888 -246.664988) (xy 135.174736 -246.664988) (xy 135.174736 -246.71274)
			(xy 135.274812 -246.812562)
		)
		(stroke
			(width 0)
			(type solid)
		)
		(fill yes)
		(layer "In2.Cu")
		(net "M_I_CPU1_SA_DQS_DN<4>")
	)
	(gr_poly
		(pts
			(xy 135.374888 -245.496334) (xy 135.274812 -245.396258) (xy 135.174736 -245.496334) (xy 135.174736 -245.540784)
			(xy 135.374888 -245.540784)
		)
		(stroke
			(width 0)
			(type solid)
		)
		(fill yes)
		(layer "In2.Cu")
		(net "M_I_CPU1_SA_CB<1>")
	)
	(gr_poly
		(pts
			(xy 135.374888 -245.092474) (xy 135.374888 -245.048024) (xy 135.174736 -245.048024) (xy 135.174736 -245.092474)
			(xy 135.274812 -245.19255)
		)
		(stroke
			(width 0)
			(type solid)
		)
		(fill yes)
		(layer "In2.Cu")
		(net "M_I_CPU1_SA_CB<2>")
	)
	(gr_poly
		(pts
			(xy 135.374888 -243.876322) (xy 135.274812 -243.776246) (xy 135.174736 -243.876322) (xy 135.174736 -243.920772)
			(xy 135.374888 -243.920772)
		)
		(stroke
			(width 0)
			(type solid)
		)
		(fill yes)
		(layer "In2.Cu")
		(net "M_I_CPU1_SA_DQ<29>")
	)
	(gr_poly
		(pts
			(xy 135.374888 -243.472462) (xy 135.374888 -243.428012) (xy 135.174736 -243.428012) (xy 135.174736 -243.472462)
			(xy 135.274812 -243.572538)
		)
		(stroke
			(width 0)
			(type solid)
		)
		(fill yes)
		(layer "In2.Cu")
		(net "M_I_CPU1_SA_DQ<30>")
	)
	(gr_poly
		(pts
			(xy 135.374888 -242.256056) (xy 135.274812 -242.156234) (xy 135.174736 -242.256056) (xy 135.174736 -242.303808)
			(xy 135.374888 -242.303808)
		)
		(stroke
			(width 0)
			(type solid)
		)
		(fill yes)
		(layer "In2.Cu")
		(net "M_I_CPU1_SA_DQS_DN<8>")
	)
	(gr_poly
		(pts
			(xy 135.374888 -241.852704) (xy 135.374888 -241.804952) (xy 135.174736 -241.804952) (xy 135.174736 -241.852704)
			(xy 135.274812 -241.952526)
		)
		(stroke
			(width 0)
			(type solid)
		)
		(fill yes)
		(layer "In2.Cu")
		(net "M_I_CPU1_SA_DQS_DN<3>")
	)
	(gr_poly
		(pts
			(xy 135.374888 -240.636298) (xy 135.274812 -240.536222) (xy 135.174736 -240.636298) (xy 135.174736 -240.680748)
			(xy 135.374888 -240.680748)
		)
		(stroke
			(width 0)
			(type solid)
		)
		(fill yes)
		(layer "In2.Cu")
		(net "M_I_CPU1_SA_DQ<25>")
	)
	(gr_poly
		(pts
			(xy 135.374888 -240.232438) (xy 135.374888 -240.187988) (xy 135.174736 -240.187988) (xy 135.174736 -240.232438)
			(xy 135.274812 -240.332514)
		)
		(stroke
			(width 0)
			(type solid)
		)
		(fill yes)
		(layer "In2.Cu")
		(net "M_I_CPU1_SA_DQ<26>")
	)
	(gr_poly
		(pts
			(xy 135.374888 -239.016286) (xy 135.274812 -238.91621) (xy 135.174736 -239.016286) (xy 135.174736 -239.060736)
			(xy 135.374888 -239.060736)
		)
		(stroke
			(width 0)
			(type solid)
		)
		(fill yes)
		(layer "In2.Cu")
		(net "M_I_CPU1_SA_DQ<21>")
	)
	(gr_poly
		(pts
			(xy 135.374888 -238.612426) (xy 135.374888 -238.567976) (xy 135.174736 -238.567976) (xy 135.174736 -238.612426)
			(xy 135.274812 -238.712502)
		)
		(stroke
			(width 0)
			(type solid)
		)
		(fill yes)
		(layer "In2.Cu")
		(net "M_I_CPU1_SA_DQ<22>")
	)
	(gr_poly
		(pts
			(xy 135.374888 -237.39602) (xy 135.274812 -237.296198) (xy 135.174736 -237.39602) (xy 135.174736 -237.443772)
			(xy 135.374888 -237.443772)
		)
		(stroke
			(width 0)
			(type solid)
		)
		(fill yes)
		(layer "In2.Cu")
		(net "M_I_CPU1_SA_DQS_DN<7>")
	)
	(gr_poly
		(pts
			(xy 135.374888 -236.992668) (xy 135.374888 -236.944916) (xy 135.174736 -236.944916) (xy 135.174736 -236.992668)
			(xy 135.274812 -237.09249)
		)
		(stroke
			(width 0)
			(type solid)
		)
		(fill yes)
		(layer "In2.Cu")
		(net "M_I_CPU1_SA_DQS_DN<2>")
	)
	(gr_poly
		(pts
			(xy 135.374888 -235.776262) (xy 135.274812 -235.676186) (xy 135.174736 -235.776262) (xy 135.174736 -235.820712)
			(xy 135.374888 -235.820712)
		)
		(stroke
			(width 0)
			(type solid)
		)
		(fill yes)
		(layer "In2.Cu")
		(net "M_I_CPU1_SA_DQ<17>")
	)
	(gr_poly
		(pts
			(xy 135.374888 -235.372402) (xy 135.374888 -235.327952) (xy 135.174736 -235.327952) (xy 135.174736 -235.372402)
			(xy 135.274812 -235.472478)
		)
		(stroke
			(width 0)
			(type solid)
		)
		(fill yes)
		(layer "In2.Cu")
		(net "M_I_CPU1_SA_DQ<18>")
	)
	(gr_poly
		(pts
			(xy 135.374888 -234.15625) (xy 135.274812 -234.056174) (xy 135.174736 -234.15625) (xy 135.174736 -234.2007)
			(xy 135.374888 -234.2007)
		)
		(stroke
			(width 0)
			(type solid)
		)
		(fill yes)
		(layer "In2.Cu")
		(net "M_I_CPU1_SA_DQ<13>")
	)
	(gr_poly
		(pts
			(xy 135.374888 -233.75239) (xy 135.374888 -233.70794) (xy 135.174736 -233.70794) (xy 135.174736 -233.75239)
			(xy 135.274812 -233.852466)
		)
		(stroke
			(width 0)
			(type solid)
		)
		(fill yes)
		(layer "In2.Cu")
		(net "M_I_CPU1_SA_DQ<14>")
	)
	(gr_poly
		(pts
			(xy 135.374888 -232.535984) (xy 135.274812 -232.436162) (xy 135.174736 -232.535984) (xy 135.174736 -232.583736)
			(xy 135.374888 -232.583736)
		)
		(stroke
			(width 0)
			(type solid)
		)
		(fill yes)
		(layer "In2.Cu")
		(net "M_I_CPU1_SA_DQS_DN<6>")
	)
	(gr_poly
		(pts
			(xy 135.374888 -232.132632) (xy 135.374888 -232.08488) (xy 135.174736 -232.08488) (xy 135.174736 -232.132632)
			(xy 135.274812 -232.232454)
		)
		(stroke
			(width 0)
			(type solid)
		)
		(fill yes)
		(layer "In2.Cu")
		(net "M_I_CPU1_SA_DQS_DN<1>")
	)
	(gr_poly
		(pts
			(xy 135.374888 -230.916226) (xy 135.274812 -230.81615) (xy 135.174736 -230.916226) (xy 135.174736 -230.960676)
			(xy 135.374888 -230.960676)
		)
		(stroke
			(width 0)
			(type solid)
		)
		(fill yes)
		(layer "In2.Cu")
		(net "M_I_CPU1_SA_DQ<9>")
	)
	(gr_poly
		(pts
			(xy 135.374888 -230.51262) (xy 135.374888 -230.46817) (xy 135.174736 -230.46817) (xy 135.174736 -230.51262)
			(xy 135.274812 -230.612696)
		)
		(stroke
			(width 0)
			(type solid)
		)
		(fill yes)
		(layer "In2.Cu")
		(net "M_I_CPU1_SA_DQ<10>")
	)
	(gr_poly
		(pts
			(xy 135.374888 -229.296214) (xy 135.274812 -229.196138) (xy 135.174736 -229.296214) (xy 135.174736 -229.340664)
			(xy 135.374888 -229.340664)
		)
		(stroke
			(width 0)
			(type solid)
		)
		(fill yes)
		(layer "In2.Cu")
		(net "M_I_CPU1_SA_DQ<5>")
	)
	(gr_poly
		(pts
			(xy 135.374888 -228.892608) (xy 135.374888 -228.848158) (xy 135.174736 -228.848158) (xy 135.174736 -228.892608)
			(xy 135.274812 -228.992684)
		)
		(stroke
			(width 0)
			(type solid)
		)
		(fill yes)
		(layer "In2.Cu")
		(net "M_I_CPU1_SA_DQ<6>")
	)
	(gr_poly
		(pts
			(xy 135.374888 -227.676202) (xy 135.274812 -227.57638) (xy 135.174736 -227.676202) (xy 135.174736 -227.723954)
			(xy 135.374888 -227.723954)
		)
		(stroke
			(width 0)
			(type solid)
		)
		(fill yes)
		(layer "In2.Cu")
		(net "M_I_CPU1_SA_DQS_DN<5>")
	)
	(gr_poly
		(pts
			(xy 135.374888 -227.27285) (xy 135.374888 -227.225098) (xy 135.174736 -227.225098) (xy 135.174736 -227.27285)
			(xy 135.274812 -227.372672)
		)
		(stroke
			(width 0)
			(type solid)
		)
		(fill yes)
		(layer "In2.Cu")
		(net "M_I_CPU1_SA_DQS_DN<0>")
	)
	(gr_poly
		(pts
			(xy 135.374888 -226.056444) (xy 135.274812 -225.956368) (xy 135.174736 -226.056444) (xy 135.174736 -226.100894)
			(xy 135.374888 -226.100894)
		)
		(stroke
			(width 0)
			(type solid)
		)
		(fill yes)
		(layer "In2.Cu")
		(net "M_I_CPU1_SA_DQ<1>")
	)
	(gr_poly
		(pts
			(xy 135.374888 -225.652584) (xy 135.374888 -225.608134) (xy 135.174736 -225.608134) (xy 135.174736 -225.652584)
			(xy 135.274812 -225.75266)
		)
		(stroke
			(width 0)
			(type solid)
		)
		(fill yes)
		(layer "In2.Cu")
		(net "M_I_CPU1_SA_DQ<2>")
	)
	(gr_poly
		(pts
			(xy 135.674862 -293.32428) (xy 135.674862 -293.27983) (xy 135.47471 -293.27983) (xy 135.47471 -293.32428)
			(xy 135.574786 -293.424356)
		)
		(stroke
			(width 0)
			(type solid)
		)
		(fill yes)
		(layer "In2.Cu")
		(net "M_I_CPU1_SB_DQ<31>")
	)
	(gr_poly
		(pts
			(xy 135.674862 -292.108128) (xy 135.574786 -292.008052) (xy 135.47471 -292.108128) (xy 135.47471 -292.152578)
			(xy 135.674862 -292.152578)
		)
		(stroke
			(width 0)
			(type solid)
		)
		(fill yes)
		(layer "In2.Cu")
		(net "M_I_CPU1_SB_DQ<28>")
	)
	(gr_poly
		(pts
			(xy 135.674862 -291.704522) (xy 135.674862 -291.65677) (xy 135.47471 -291.65677) (xy 135.47471 -291.704522)
			(xy 135.574786 -291.804344)
		)
		(stroke
			(width 0)
			(type solid)
		)
		(fill yes)
		(layer "In2.Cu")
		(net "M_I_CPU1_SB_DQS_DP<8>")
	)
	(gr_poly
		(pts
			(xy 135.674862 -290.487862) (xy 135.574786 -290.38804) (xy 135.47471 -290.487862) (xy 135.47471 -290.535614)
			(xy 135.674862 -290.535614)
		)
		(stroke
			(width 0)
			(type solid)
		)
		(fill yes)
		(layer "In2.Cu")
		(net "M_I_CPU1_SB_DQS_DP<3>")
	)
	(gr_poly
		(pts
			(xy 135.674862 -290.084256) (xy 135.674862 -290.039806) (xy 135.47471 -290.039806) (xy 135.47471 -290.084256)
			(xy 135.574786 -290.184332)
		)
		(stroke
			(width 0)
			(type solid)
		)
		(fill yes)
		(layer "In2.Cu")
		(net "M_I_CPU1_SB_DQ<27>")
	)
	(gr_poly
		(pts
			(xy 135.674862 -288.868104) (xy 135.574786 -288.768028) (xy 135.47471 -288.868104) (xy 135.47471 -288.912554)
			(xy 135.674862 -288.912554)
		)
		(stroke
			(width 0)
			(type solid)
		)
		(fill yes)
		(layer "In2.Cu")
		(net "M_I_CPU1_SB_DQ<24>")
	)
	(gr_poly
		(pts
			(xy 135.674862 -288.464498) (xy 135.674862 -288.420048) (xy 135.47471 -288.420048) (xy 135.47471 -288.464498)
			(xy 135.574786 -288.564574)
		)
		(stroke
			(width 0)
			(type solid)
		)
		(fill yes)
		(layer "In2.Cu")
		(net "M_I_CPU1_SB_DQ<23>")
	)
	(gr_poly
		(pts
			(xy 135.674862 -287.248092) (xy 135.574786 -287.148016) (xy 135.47471 -287.248092) (xy 135.47471 -287.292542)
			(xy 135.674862 -287.292542)
		)
		(stroke
			(width 0)
			(type solid)
		)
		(fill yes)
		(layer "In2.Cu")
		(net "M_I_CPU1_SB_DQ<20>")
	)
	(gr_poly
		(pts
			(xy 135.674862 -286.844486) (xy 135.674862 -286.796734) (xy 135.47471 -286.796734) (xy 135.47471 -286.844486)
			(xy 135.574786 -286.944562)
		)
		(stroke
			(width 0)
			(type solid)
		)
		(fill yes)
		(layer "In2.Cu")
		(net "M_I_CPU1_SB_DQS_DP<7>")
	)
	(gr_poly
		(pts
			(xy 135.674862 -285.62808) (xy 135.574786 -285.528258) (xy 135.47471 -285.62808) (xy 135.47471 -285.675832)
			(xy 135.674862 -285.675832)
		)
		(stroke
			(width 0)
			(type solid)
		)
		(fill yes)
		(layer "In2.Cu")
		(net "M_I_CPU1_SB_DQS_DP<2>")
	)
	(gr_poly
		(pts
			(xy 135.674862 -285.224474) (xy 135.674862 -285.180024) (xy 135.47471 -285.180024) (xy 135.47471 -285.224474)
			(xy 135.574786 -285.32455)
		)
		(stroke
			(width 0)
			(type solid)
		)
		(fill yes)
		(layer "In2.Cu")
		(net "M_I_CPU1_SB_DQ<19>")
	)
	(gr_poly
		(pts
			(xy 135.674862 -284.008322) (xy 135.574786 -283.908246) (xy 135.47471 -284.008322) (xy 135.47471 -284.052772)
			(xy 135.674862 -284.052772)
		)
		(stroke
			(width 0)
			(type solid)
		)
		(fill yes)
		(layer "In2.Cu")
		(net "M_I_CPU1_SB_DQ<16>")
	)
	(gr_poly
		(pts
			(xy 135.674862 -283.604462) (xy 135.674862 -283.560012) (xy 135.47471 -283.560012) (xy 135.47471 -283.604462)
			(xy 135.574786 -283.704538)
		)
		(stroke
			(width 0)
			(type solid)
		)
		(fill yes)
		(layer "In2.Cu")
		(net "M_I_CPU1_SB_DQ<15>")
	)
	(gr_poly
		(pts
			(xy 135.674862 -282.38831) (xy 135.574786 -282.288234) (xy 135.47471 -282.38831) (xy 135.47471 -282.43276)
			(xy 135.674862 -282.43276)
		)
		(stroke
			(width 0)
			(type solid)
		)
		(fill yes)
		(layer "In2.Cu")
		(net "M_I_CPU1_SB_DQ<12>")
	)
	(gr_poly
		(pts
			(xy 135.674862 -281.984704) (xy 135.674862 -281.936952) (xy 135.47471 -281.936952) (xy 135.47471 -281.984704)
			(xy 135.574786 -282.084526)
		)
		(stroke
			(width 0)
			(type solid)
		)
		(fill yes)
		(layer "In2.Cu")
		(net "M_I_CPU1_SB_DQS_DP<6>")
	)
	(gr_poly
		(pts
			(xy 135.674862 -280.768044) (xy 135.574786 -280.668222) (xy 135.47471 -280.768044) (xy 135.47471 -280.815796)
			(xy 135.674862 -280.815796)
		)
		(stroke
			(width 0)
			(type solid)
		)
		(fill yes)
		(layer "In2.Cu")
		(net "M_I_CPU1_SB_DQS_DP<1>")
	)
	(gr_poly
		(pts
			(xy 135.674862 -280.364438) (xy 135.674862 -280.319988) (xy 135.47471 -280.319988) (xy 135.47471 -280.364438)
			(xy 135.574786 -280.464514)
		)
		(stroke
			(width 0)
			(type solid)
		)
		(fill yes)
		(layer "In2.Cu")
		(net "M_I_CPU1_SB_DQ<11>")
	)
	(gr_poly
		(pts
			(xy 135.674862 -279.148286) (xy 135.574786 -279.04821) (xy 135.47471 -279.148286) (xy 135.47471 -279.192736)
			(xy 135.674862 -279.192736)
		)
		(stroke
			(width 0)
			(type solid)
		)
		(fill yes)
		(layer "In2.Cu")
		(net "M_I_CPU1_SB_DQ<8>")
	)
	(gr_poly
		(pts
			(xy 135.674862 -278.744426) (xy 135.674862 -278.699976) (xy 135.47471 -278.699976) (xy 135.47471 -278.744426)
			(xy 135.574786 -278.844502)
		)
		(stroke
			(width 0)
			(type solid)
		)
		(fill yes)
		(layer "In2.Cu")
		(net "M_I_CPU1_SB_DQ<7>")
	)
	(gr_poly
		(pts
			(xy 135.674862 -277.528274) (xy 135.574786 -277.428198) (xy 135.47471 -277.528274) (xy 135.47471 -277.572724)
			(xy 135.674862 -277.572724)
		)
		(stroke
			(width 0)
			(type solid)
		)
		(fill yes)
		(layer "In2.Cu")
		(net "M_I_CPU1_SB_DQ<4>")
	)
	(gr_poly
		(pts
			(xy 135.674862 -277.124668) (xy 135.674862 -277.076916) (xy 135.47471 -277.076916) (xy 135.47471 -277.124668)
			(xy 135.574786 -277.22449)
		)
		(stroke
			(width 0)
			(type solid)
		)
		(fill yes)
		(layer "In2.Cu")
		(net "M_I_CPU1_SB_DQS_DP<5>")
	)
	(gr_poly
		(pts
			(xy 135.674862 -275.908008) (xy 135.574786 -275.808186) (xy 135.47471 -275.908008) (xy 135.47471 -275.95576)
			(xy 135.674862 -275.95576)
		)
		(stroke
			(width 0)
			(type solid)
		)
		(fill yes)
		(layer "In2.Cu")
		(net "M_I_CPU1_SB_DQS_DP<0>")
	)
	(gr_poly
		(pts
			(xy 135.674862 -275.504402) (xy 135.674862 -275.459952) (xy 135.47471 -275.459952) (xy 135.47471 -275.504402)
			(xy 135.574786 -275.604478)
		)
		(stroke
			(width 0)
			(type solid)
		)
		(fill yes)
		(layer "In2.Cu")
		(net "M_I_CPU1_SB_DQ<3>")
	)
	(gr_poly
		(pts
			(xy 135.674862 -274.28825) (xy 135.574786 -274.188174) (xy 135.47471 -274.28825) (xy 135.47471 -274.3327)
			(xy 135.674862 -274.3327)
		)
		(stroke
			(width 0)
			(type solid)
		)
		(fill yes)
		(layer "In2.Cu")
		(net "M_I_CPU1_SB_DQ<0>")
	)
	(gr_poly
		(pts
			(xy 135.674862 -273.88439) (xy 135.674862 -273.83994) (xy 135.47471 -273.83994) (xy 135.47471 -273.88439)
			(xy 135.574786 -273.984466)
		)
		(stroke
			(width 0)
			(type solid)
		)
		(fill yes)
		(layer "In2.Cu")
		(net "M_I_CPU1_SB_CB<3>")
	)
	(gr_poly
		(pts
			(xy 135.674862 -272.668238) (xy 135.574786 -272.568162) (xy 135.47471 -272.668238) (xy 135.47471 -272.712688)
			(xy 135.674862 -272.712688)
		)
		(stroke
			(width 0)
			(type solid)
		)
		(fill yes)
		(layer "In2.Cu")
		(net "M_I_CPU1_SB_CB<0>")
	)
	(gr_poly
		(pts
			(xy 135.674862 -272.264632) (xy 135.674862 -272.21688) (xy 135.47471 -272.21688) (xy 135.47471 -272.264632)
			(xy 135.574786 -272.364454)
		)
		(stroke
			(width 0)
			(type solid)
		)
		(fill yes)
		(layer "In2.Cu")
		(net "M_I_CPU1_SB_DQS_DP<4>")
	)
	(gr_poly
		(pts
			(xy 135.674862 -271.047972) (xy 135.574786 -270.94815) (xy 135.47471 -271.047972) (xy 135.47471 -271.095724)
			(xy 135.674862 -271.095724)
		)
		(stroke
			(width 0)
			(type solid)
		)
		(fill yes)
		(layer "In2.Cu")
		(net "M_I_CPU1_SB_DQS_DP<9>")
	)
	(gr_poly
		(pts
			(xy 135.674862 -270.644366) (xy 135.674862 -270.599916) (xy 135.47471 -270.599916) (xy 135.47471 -270.644366)
			(xy 135.574786 -270.744442)
		)
		(stroke
			(width 0)
			(type solid)
		)
		(fill yes)
		(layer "In2.Cu")
		(net "M_I_CPU1_SB_CB<7>")
	)
	(gr_poly
		(pts
			(xy 135.674862 -269.428214) (xy 135.574786 -269.328138) (xy 135.47471 -269.428214) (xy 135.47471 -269.472664)
			(xy 135.674862 -269.472664)
		)
		(stroke
			(width 0)
			(type solid)
		)
		(fill yes)
		(layer "In2.Cu")
		(net "M_I_CPU1_SB_CB<4>")
	)
	(gr_poly
		(pts
			(xy 135.674862 -267.404342) (xy 135.674862 -267.359892) (xy 135.47471 -267.359892) (xy 135.47471 -267.404342)
			(xy 135.574786 -267.504418)
		)
		(stroke
			(width 0)
			(type solid)
		)
		(fill yes)
		(layer "In2.Cu")
		(net "M_I_CPU1_SB_RSP<0>")
	)
	(gr_poly
		(pts
			(xy 135.674862 -265.78433) (xy 135.674862 -265.73988) (xy 135.47471 -265.73988) (xy 135.47471 -265.78433)
			(xy 135.574786 -265.884406)
		)
		(stroke
			(width 0)
			(type solid)
		)
		(fill yes)
		(layer "In2.Cu")
		(net "M_I_CPU1_SB_CS_N<0>")
	)
	(gr_poly
		(pts
			(xy 135.674862 -264.568178) (xy 135.574786 -264.468102) (xy 135.47471 -264.568178) (xy 135.47471 -264.612628)
			(xy 135.674862 -264.612628)
		)
		(stroke
			(width 0)
			(type solid)
		)
		(fill yes)
		(layer "In2.Cu")
		(net "M_I_CPU1_SB_CA<6>")
	)
	(gr_poly
		(pts
			(xy 135.674862 -264.164318) (xy 135.674862 -264.119868) (xy 135.47471 -264.119868) (xy 135.47471 -264.164318)
			(xy 135.574786 -264.264394)
		)
		(stroke
			(width 0)
			(type solid)
		)
		(fill yes)
		(layer "In2.Cu")
		(net "M_I_CPU1_SB_CA<5>")
	)
	(gr_poly
		(pts
			(xy 135.674862 -262.948166) (xy 135.574786 -262.84809) (xy 135.47471 -262.948166) (xy 135.47471 -262.992616)
			(xy 135.674862 -262.992616)
		)
		(stroke
			(width 0)
			(type solid)
		)
		(fill yes)
		(layer "In2.Cu")
		(net "M_I_CPU1_SB_CA<2>")
	)
	(gr_poly
		(pts
			(xy 135.674862 -262.544306) (xy 135.674862 -262.499856) (xy 135.47471 -262.499856) (xy 135.47471 -262.544306)
			(xy 135.574786 -262.644382)
		)
		(stroke
			(width 0)
			(type solid)
		)
		(fill yes)
		(layer "In2.Cu")
		(net "M_I_CPU1_SB_CA<1>")
	)
	(gr_poly
		(pts
			(xy 135.844788 -256.026158) (xy 135.744712 -255.926336) (xy 135.644636 -256.026158) (xy 135.644636 -256.07391)
			(xy 135.844788 -256.07391)
		)
		(stroke
			(width 0)
			(type solid)
		)
		(fill yes)
		(layer "In2.Cu")
		(net "M_I_CPU1_CLK_DP<0>")
	)
	(gr_poly
		(pts
			(xy 135.844788 -255.622552) (xy 135.844788 -255.578102) (xy 135.644636 -255.578102) (xy 135.644636 -255.622552)
			(xy 135.744712 -255.722628)
		)
		(stroke
			(width 0)
			(type solid)
		)
		(fill yes)
		(layer "In2.Cu")
		(net "M_I_CPU1_SA_PAR")
	)
	(gr_poly
		(pts
			(xy 135.844788 -254.4064) (xy 135.744712 -254.306324) (xy 135.644636 -254.4064) (xy 135.644636 -254.45085)
			(xy 135.844788 -254.45085)
		)
		(stroke
			(width 0)
			(type solid)
		)
		(fill yes)
		(layer "In2.Cu")
		(net "M_I_CPU1_SA_CA<4>")
	)
	(gr_poly
		(pts
			(xy 135.844788 -254.00254) (xy 135.844788 -253.95809) (xy 135.644636 -253.95809) (xy 135.644636 -254.00254)
			(xy 135.744712 -254.102616)
		)
		(stroke
			(width 0)
			(type solid)
		)
		(fill yes)
		(layer "In2.Cu")
		(net "M_I_CPU1_SA_CA<3>")
	)
	(gr_poly
		(pts
			(xy 135.844788 -252.786388) (xy 135.744712 -252.686312) (xy 135.644636 -252.786388) (xy 135.644636 -252.830838)
			(xy 135.844788 -252.830838)
		)
		(stroke
			(width 0)
			(type solid)
		)
		(fill yes)
		(layer "In2.Cu")
		(net "M_I_CPU1_SA_CA<0>")
	)
	(gr_poly
		(pts
			(xy 135.844788 -251.166376) (xy 135.744712 -251.0663) (xy 135.644636 -251.166376) (xy 135.644636 -251.210826)
			(xy 135.844788 -251.210826)
		)
		(stroke
			(width 0)
			(type solid)
		)
		(fill yes)
		(layer "In2.Cu")
		(net "M_I_CPU1_SA_CS_N<0>")
	)
	(gr_poly
		(pts
			(xy 135.844788 -250.762516) (xy 135.844788 -250.718066) (xy 135.644636 -250.718066) (xy 135.644636 -250.762516)
			(xy 135.744712 -250.862592)
		)
		(stroke
			(width 0)
			(type solid)
		)
		(fill yes)
		(layer "In2.Cu")
		(net "M_I_CPU1_RESET_N")
	)
	(gr_poly
		(pts
			(xy 135.844788 -249.142504) (xy 135.844788 -249.098054) (xy 135.644636 -249.098054) (xy 135.644636 -249.142504)
			(xy 135.744712 -249.24258)
		)
		(stroke
			(width 0)
			(type solid)
		)
		(fill yes)
		(layer "In2.Cu")
		(net "M_I_CPU1_SA_CB<7>")
	)
	(gr_poly
		(pts
			(xy 135.844788 -247.926352) (xy 135.744712 -247.826276) (xy 135.644636 -247.926352) (xy 135.644636 -247.970802)
			(xy 135.844788 -247.970802)
		)
		(stroke
			(width 0)
			(type solid)
		)
		(fill yes)
		(layer "In2.Cu")
		(net "M_I_CPU1_SA_CB<4>")
	)
	(gr_poly
		(pts
			(xy 135.844788 -247.522746) (xy 135.844788 -247.474994) (xy 135.644636 -247.474994) (xy 135.644636 -247.522746)
			(xy 135.744712 -247.622568)
		)
		(stroke
			(width 0)
			(type solid)
		)
		(fill yes)
		(layer "In2.Cu")
		(net "M_I_CPU1_SA_DQS_DP<9>")
	)
	(gr_poly
		(pts
			(xy 135.844788 -246.306086) (xy 135.744712 -246.206264) (xy 135.644636 -246.306086) (xy 135.644636 -246.353838)
			(xy 135.844788 -246.353838)
		)
		(stroke
			(width 0)
			(type solid)
		)
		(fill yes)
		(layer "In2.Cu")
		(net "M_I_CPU1_SA_DQS_DP<4>")
	)
	(gr_poly
		(pts
			(xy 135.844788 -245.90248) (xy 135.844788 -245.85803) (xy 135.644636 -245.85803) (xy 135.644636 -245.90248)
			(xy 135.744712 -246.002556)
		)
		(stroke
			(width 0)
			(type solid)
		)
		(fill yes)
		(layer "In2.Cu")
		(net "M_I_CPU1_SA_CB<3>")
	)
	(gr_poly
		(pts
			(xy 135.844788 -244.686328) (xy 135.744712 -244.586252) (xy 135.644636 -244.686328) (xy 135.644636 -244.730778)
			(xy 135.844788 -244.730778)
		)
		(stroke
			(width 0)
			(type solid)
		)
		(fill yes)
		(layer "In2.Cu")
		(net "M_I_CPU1_SA_CB<0>")
	)
	(gr_poly
		(pts
			(xy 135.844788 -244.282468) (xy 135.844788 -244.238018) (xy 135.644636 -244.238018) (xy 135.644636 -244.282468)
			(xy 135.744712 -244.382544)
		)
		(stroke
			(width 0)
			(type solid)
		)
		(fill yes)
		(layer "In2.Cu")
		(net "M_I_CPU1_SA_DQ<31>")
	)
	(gr_poly
		(pts
			(xy 135.844788 -243.066316) (xy 135.744712 -242.96624) (xy 135.644636 -243.066316) (xy 135.644636 -243.110766)
			(xy 135.844788 -243.110766)
		)
		(stroke
			(width 0)
			(type solid)
		)
		(fill yes)
		(layer "In2.Cu")
		(net "M_I_CPU1_SA_DQ<28>")
	)
	(gr_poly
		(pts
			(xy 135.844788 -242.66271) (xy 135.844788 -242.614958) (xy 135.644636 -242.614958) (xy 135.644636 -242.66271)
			(xy 135.744712 -242.762532)
		)
		(stroke
			(width 0)
			(type solid)
		)
		(fill yes)
		(layer "In2.Cu")
		(net "M_I_CPU1_SA_DQS_DP<8>")
	)
	(gr_poly
		(pts
			(xy 135.844788 -241.44605) (xy 135.744712 -241.346228) (xy 135.644636 -241.44605) (xy 135.644636 -241.493802)
			(xy 135.844788 -241.493802)
		)
		(stroke
			(width 0)
			(type solid)
		)
		(fill yes)
		(layer "In2.Cu")
		(net "M_I_CPU1_SA_DQS_DP<3>")
	)
	(gr_poly
		(pts
			(xy 135.844788 -241.042444) (xy 135.844788 -240.997994) (xy 135.644636 -240.997994) (xy 135.644636 -241.042444)
			(xy 135.744712 -241.14252)
		)
		(stroke
			(width 0)
			(type solid)
		)
		(fill yes)
		(layer "In2.Cu")
		(net "M_I_CPU1_SA_DQ<27>")
	)
	(gr_poly
		(pts
			(xy 135.844788 -239.826292) (xy 135.744712 -239.726216) (xy 135.644636 -239.826292) (xy 135.644636 -239.870742)
			(xy 135.844788 -239.870742)
		)
		(stroke
			(width 0)
			(type solid)
		)
		(fill yes)
		(layer "In2.Cu")
		(net "M_I_CPU1_SA_DQ<24>")
	)
	(gr_poly
		(pts
			(xy 135.844788 -239.422432) (xy 135.844788 -239.377982) (xy 135.644636 -239.377982) (xy 135.644636 -239.422432)
			(xy 135.744712 -239.522508)
		)
		(stroke
			(width 0)
			(type solid)
		)
		(fill yes)
		(layer "In2.Cu")
		(net "M_I_CPU1_SA_DQ<23>")
	)
	(gr_poly
		(pts
			(xy 135.844788 -238.20628) (xy 135.744712 -238.106204) (xy 135.644636 -238.20628) (xy 135.644636 -238.25073)
			(xy 135.844788 -238.25073)
		)
		(stroke
			(width 0)
			(type solid)
		)
		(fill yes)
		(layer "In2.Cu")
		(net "M_I_CPU1_SA_DQ<20>")
	)
	(gr_poly
		(pts
			(xy 135.844788 -237.802674) (xy 135.844788 -237.754922) (xy 135.644636 -237.754922) (xy 135.644636 -237.802674)
			(xy 135.744712 -237.902496)
		)
		(stroke
			(width 0)
			(type solid)
		)
		(fill yes)
		(layer "In2.Cu")
		(net "M_I_CPU1_SA_DQS_DP<7>")
	)
	(gr_poly
		(pts
			(xy 135.844788 -236.586014) (xy 135.744712 -236.486192) (xy 135.644636 -236.586014) (xy 135.644636 -236.633766)
			(xy 135.844788 -236.633766)
		)
		(stroke
			(width 0)
			(type solid)
		)
		(fill yes)
		(layer "In2.Cu")
		(net "M_I_CPU1_SA_DQS_DP<2>")
	)
	(gr_poly
		(pts
			(xy 135.844788 -236.182408) (xy 135.844788 -236.137958) (xy 135.644636 -236.137958) (xy 135.644636 -236.182408)
			(xy 135.744712 -236.282484)
		)
		(stroke
			(width 0)
			(type solid)
		)
		(fill yes)
		(layer "In2.Cu")
		(net "M_I_CPU1_SA_DQ<19>")
	)
	(gr_poly
		(pts
			(xy 135.844788 -234.966256) (xy 135.744712 -234.86618) (xy 135.644636 -234.966256) (xy 135.644636 -235.010706)
			(xy 135.844788 -235.010706)
		)
		(stroke
			(width 0)
			(type solid)
		)
		(fill yes)
		(layer "In2.Cu")
		(net "M_I_CPU1_SA_DQ<16>")
	)
	(gr_poly
		(pts
			(xy 135.844788 -234.562396) (xy 135.844788 -234.517946) (xy 135.644636 -234.517946) (xy 135.644636 -234.562396)
			(xy 135.744712 -234.662472)
		)
		(stroke
			(width 0)
			(type solid)
		)
		(fill yes)
		(layer "In2.Cu")
		(net "M_I_CPU1_SA_DQ<15>")
	)
	(gr_poly
		(pts
			(xy 135.844788 -233.346244) (xy 135.744712 -233.246168) (xy 135.644636 -233.346244) (xy 135.644636 -233.390694)
			(xy 135.844788 -233.390694)
		)
		(stroke
			(width 0)
			(type solid)
		)
		(fill yes)
		(layer "In2.Cu")
		(net "M_I_CPU1_SA_DQ<12>")
	)
	(gr_poly
		(pts
			(xy 135.844788 -232.942638) (xy 135.844788 -232.894886) (xy 135.644636 -232.894886) (xy 135.644636 -232.942638)
			(xy 135.744712 -233.04246)
		)
		(stroke
			(width 0)
			(type solid)
		)
		(fill yes)
		(layer "In2.Cu")
		(net "M_I_CPU1_SA_DQS_DP<6>")
	)
	(gr_poly
		(pts
			(xy 135.844788 -231.725978) (xy 135.744712 -231.626156) (xy 135.644636 -231.725978) (xy 135.644636 -231.77373)
			(xy 135.844788 -231.77373)
		)
		(stroke
			(width 0)
			(type solid)
		)
		(fill yes)
		(layer "In2.Cu")
		(net "M_I_CPU1_SA_DQS_DP<1>")
	)
	(gr_poly
		(pts
			(xy 135.844788 -231.322626) (xy 135.844788 -231.278176) (xy 135.644636 -231.278176) (xy 135.644636 -231.322626)
			(xy 135.744712 -231.422702)
		)
		(stroke
			(width 0)
			(type solid)
		)
		(fill yes)
		(layer "In2.Cu")
		(net "M_I_CPU1_SA_DQ<11>")
	)
	(gr_poly
		(pts
			(xy 135.844788 -230.10622) (xy 135.744712 -230.006144) (xy 135.644636 -230.10622) (xy 135.644636 -230.15067)
			(xy 135.844788 -230.15067)
		)
		(stroke
			(width 0)
			(type solid)
		)
		(fill yes)
		(layer "In2.Cu")
		(net "M_I_CPU1_SA_DQ<8>")
	)
	(gr_poly
		(pts
			(xy 135.844788 -229.702614) (xy 135.844788 -229.658164) (xy 135.644636 -229.658164) (xy 135.644636 -229.702614)
			(xy 135.744712 -229.80269)
		)
		(stroke
			(width 0)
			(type solid)
		)
		(fill yes)
		(layer "In2.Cu")
		(net "M_I_CPU1_SA_DQ<7>")
	)
	(gr_poly
		(pts
			(xy 135.844788 -228.486462) (xy 135.744712 -228.386386) (xy 135.644636 -228.486462) (xy 135.644636 -228.530912)
			(xy 135.844788 -228.530912)
		)
		(stroke
			(width 0)
			(type solid)
		)
		(fill yes)
		(layer "In2.Cu")
		(net "M_I_CPU1_SA_DQ<4>")
	)
	(gr_poly
		(pts
			(xy 135.844788 -228.082856) (xy 135.844788 -228.035104) (xy 135.644636 -228.035104) (xy 135.644636 -228.082856)
			(xy 135.744712 -228.182678)
		)
		(stroke
			(width 0)
			(type solid)
		)
		(fill yes)
		(layer "In2.Cu")
		(net "M_I_CPU1_SA_DQS_DP<5>")
	)
	(gr_poly
		(pts
			(xy 135.844788 -226.866196) (xy 135.744712 -226.766374) (xy 135.644636 -226.866196) (xy 135.644636 -226.913948)
			(xy 135.844788 -226.913948)
		)
		(stroke
			(width 0)
			(type solid)
		)
		(fill yes)
		(layer "In2.Cu")
		(net "M_I_CPU1_SA_DQS_DP<0>")
	)
	(gr_poly
		(pts
			(xy 135.844788 -226.46259) (xy 135.844788 -226.41814) (xy 135.644636 -226.41814) (xy 135.644636 -226.46259)
			(xy 135.744712 -226.562666)
		)
		(stroke
			(width 0)
			(type solid)
		)
		(fill yes)
		(layer "In2.Cu")
		(net "M_I_CPU1_SA_DQ<3>")
	)
	(gr_poly
		(pts
			(xy 135.844788 -225.246438) (xy 135.744712 -225.146362) (xy 135.644636 -225.246438) (xy 135.644636 -225.290888)
			(xy 135.844788 -225.290888)
		)
		(stroke
			(width 0)
			(type solid)
		)
		(fill yes)
		(layer "In2.Cu")
		(net "M_I_CPU1_SA_DQ<0>")
	)
	(gr_poly
		(pts
			(xy 136.144762 -292.918134) (xy 136.044686 -292.818058) (xy 135.94461 -292.918134) (xy 135.94461 -292.962584)
			(xy 136.144762 -292.962584)
		)
		(stroke
			(width 0)
			(type solid)
		)
		(fill yes)
		(layer "In2.Cu")
		(net "M_I_CPU1_SB_DQ<29>")
	)
	(gr_poly
		(pts
			(xy 136.144762 -292.514274) (xy 136.144762 -292.469824) (xy 135.94461 -292.469824) (xy 135.94461 -292.514274)
			(xy 136.044686 -292.61435)
		)
		(stroke
			(width 0)
			(type solid)
		)
		(fill yes)
		(layer "In2.Cu")
		(net "M_I_CPU1_SB_DQ<30>")
	)
	(gr_poly
		(pts
			(xy 136.144762 -291.297868) (xy 136.044686 -291.198046) (xy 135.94461 -291.297868) (xy 135.94461 -291.34562)
			(xy 136.144762 -291.34562)
		)
		(stroke
			(width 0)
			(type solid)
		)
		(fill yes)
		(layer "In2.Cu")
		(net "M_I_CPU1_SB_DQS_DN<8>")
	)
	(gr_poly
		(pts
			(xy 136.144762 -290.894516) (xy 136.144762 -290.846764) (xy 135.94461 -290.846764) (xy 135.94461 -290.894516)
			(xy 136.044686 -290.994338)
		)
		(stroke
			(width 0)
			(type solid)
		)
		(fill yes)
		(layer "In2.Cu")
		(net "M_I_CPU1_SB_DQS_DN<3>")
	)
	(gr_poly
		(pts
			(xy 136.144762 -289.67811) (xy 136.044686 -289.578034) (xy 135.94461 -289.67811) (xy 135.94461 -289.72256)
			(xy 136.144762 -289.72256)
		)
		(stroke
			(width 0)
			(type solid)
		)
		(fill yes)
		(layer "In2.Cu")
		(net "M_I_CPU1_SB_DQ<25>")
	)
	(gr_poly
		(pts
			(xy 136.144762 -289.27425) (xy 136.144762 -289.2298) (xy 135.94461 -289.2298) (xy 135.94461 -289.27425)
			(xy 136.044686 -289.374326)
		)
		(stroke
			(width 0)
			(type solid)
		)
		(fill yes)
		(layer "In2.Cu")
		(net "M_I_CPU1_SB_DQ<26>")
	)
	(gr_poly
		(pts
			(xy 136.144762 -288.058098) (xy 136.044686 -287.958022) (xy 135.94461 -288.058098) (xy 135.94461 -288.102548)
			(xy 136.144762 -288.102548)
		)
		(stroke
			(width 0)
			(type solid)
		)
		(fill yes)
		(layer "In2.Cu")
		(net "M_I_CPU1_SB_DQ<21>")
	)
	(gr_poly
		(pts
			(xy 136.144762 -287.654492) (xy 136.144762 -287.610042) (xy 135.94461 -287.610042) (xy 135.94461 -287.654492)
			(xy 136.044686 -287.754568)
		)
		(stroke
			(width 0)
			(type solid)
		)
		(fill yes)
		(layer "In2.Cu")
		(net "M_I_CPU1_SB_DQ<22>")
	)
	(gr_poly
		(pts
			(xy 136.144762 -286.438086) (xy 136.044686 -286.33801) (xy 135.94461 -286.438086) (xy 135.94461 -286.485838)
			(xy 136.144762 -286.485838)
		)
		(stroke
			(width 0)
			(type solid)
		)
		(fill yes)
		(layer "In2.Cu")
		(net "M_I_CPU1_SB_DQS_DN<7>")
	)
	(gr_poly
		(pts
			(xy 136.144762 -286.034734) (xy 136.144762 -285.986982) (xy 135.94461 -285.986982) (xy 135.94461 -286.034734)
			(xy 136.044686 -286.134556)
		)
		(stroke
			(width 0)
			(type solid)
		)
		(fill yes)
		(layer "In2.Cu")
		(net "M_I_CPU1_SB_DQS_DN<2>")
	)
	(gr_poly
		(pts
			(xy 136.144762 -284.818328) (xy 136.044686 -284.718252) (xy 135.94461 -284.818328) (xy 135.94461 -284.862778)
			(xy 136.144762 -284.862778)
		)
		(stroke
			(width 0)
			(type solid)
		)
		(fill yes)
		(layer "In2.Cu")
		(net "M_I_CPU1_SB_DQ<17>")
	)
	(gr_poly
		(pts
			(xy 136.144762 -284.414468) (xy 136.144762 -284.370018) (xy 135.94461 -284.370018) (xy 135.94461 -284.414468)
			(xy 136.044686 -284.514544)
		)
		(stroke
			(width 0)
			(type solid)
		)
		(fill yes)
		(layer "In2.Cu")
		(net "M_I_CPU1_SB_DQ<18>")
	)
	(gr_poly
		(pts
			(xy 136.144762 -283.198316) (xy 136.044686 -283.09824) (xy 135.94461 -283.198316) (xy 135.94461 -283.242766)
			(xy 136.144762 -283.242766)
		)
		(stroke
			(width 0)
			(type solid)
		)
		(fill yes)
		(layer "In2.Cu")
		(net "M_I_CPU1_SB_DQ<13>")
	)
	(gr_poly
		(pts
			(xy 136.144762 -282.794456) (xy 136.144762 -282.750006) (xy 135.94461 -282.750006) (xy 135.94461 -282.794456)
			(xy 136.044686 -282.894532)
		)
		(stroke
			(width 0)
			(type solid)
		)
		(fill yes)
		(layer "In2.Cu")
		(net "M_I_CPU1_SB_DQ<14>")
	)
	(gr_poly
		(pts
			(xy 136.144762 -281.57805) (xy 136.044686 -281.478228) (xy 135.94461 -281.57805) (xy 135.94461 -281.625802)
			(xy 136.144762 -281.625802)
		)
		(stroke
			(width 0)
			(type solid)
		)
		(fill yes)
		(layer "In2.Cu")
		(net "M_I_CPU1_SB_DQS_DN<6>")
	)
	(gr_poly
		(pts
			(xy 136.144762 -281.174698) (xy 136.144762 -281.126946) (xy 135.94461 -281.126946) (xy 135.94461 -281.174698)
			(xy 136.044686 -281.27452)
		)
		(stroke
			(width 0)
			(type solid)
		)
		(fill yes)
		(layer "In2.Cu")
		(net "M_I_CPU1_SB_DQS_DN<1>")
	)
	(gr_poly
		(pts
			(xy 136.144762 -279.958292) (xy 136.044686 -279.858216) (xy 135.94461 -279.958292) (xy 135.94461 -280.002742)
			(xy 136.144762 -280.002742)
		)
		(stroke
			(width 0)
			(type solid)
		)
		(fill yes)
		(layer "In2.Cu")
		(net "M_I_CPU1_SB_DQ<9>")
	)
	(gr_poly
		(pts
			(xy 136.144762 -279.554432) (xy 136.144762 -279.509982) (xy 135.94461 -279.509982) (xy 135.94461 -279.554432)
			(xy 136.044686 -279.654508)
		)
		(stroke
			(width 0)
			(type solid)
		)
		(fill yes)
		(layer "In2.Cu")
		(net "M_I_CPU1_SB_DQ<10>")
	)
	(gr_poly
		(pts
			(xy 136.144762 -278.33828) (xy 136.044686 -278.238204) (xy 135.94461 -278.33828) (xy 135.94461 -278.38273)
			(xy 136.144762 -278.38273)
		)
		(stroke
			(width 0)
			(type solid)
		)
		(fill yes)
		(layer "In2.Cu")
		(net "M_I_CPU1_SB_DQ<5>")
	)
	(gr_poly
		(pts
			(xy 136.144762 -277.93442) (xy 136.144762 -277.88997) (xy 135.94461 -277.88997) (xy 135.94461 -277.93442)
			(xy 136.044686 -278.034496)
		)
		(stroke
			(width 0)
			(type solid)
		)
		(fill yes)
		(layer "In2.Cu")
		(net "M_I_CPU1_SB_DQ<6>")
	)
	(gr_poly
		(pts
			(xy 136.144762 -276.718014) (xy 136.044686 -276.618192) (xy 135.94461 -276.718014) (xy 135.94461 -276.765766)
			(xy 136.144762 -276.765766)
		)
		(stroke
			(width 0)
			(type solid)
		)
		(fill yes)
		(layer "In2.Cu")
		(net "M_I_CPU1_SB_DQS_DN<5>")
	)
	(gr_poly
		(pts
			(xy 136.144762 -276.314662) (xy 136.144762 -276.26691) (xy 135.94461 -276.26691) (xy 135.94461 -276.314662)
			(xy 136.044686 -276.414484)
		)
		(stroke
			(width 0)
			(type solid)
		)
		(fill yes)
		(layer "In2.Cu")
		(net "M_I_CPU1_SB_DQS_DN<0>")
	)
	(gr_poly
		(pts
			(xy 136.144762 -275.098256) (xy 136.044686 -274.99818) (xy 135.94461 -275.098256) (xy 135.94461 -275.142706)
			(xy 136.144762 -275.142706)
		)
		(stroke
			(width 0)
			(type solid)
		)
		(fill yes)
		(layer "In2.Cu")
		(net "M_I_CPU1_SB_DQ<1>")
	)
	(gr_poly
		(pts
			(xy 136.144762 -274.694396) (xy 136.144762 -274.649946) (xy 135.94461 -274.649946) (xy 135.94461 -274.694396)
			(xy 136.044686 -274.794472)
		)
		(stroke
			(width 0)
			(type solid)
		)
		(fill yes)
		(layer "In2.Cu")
		(net "M_I_CPU1_SB_DQ<2>")
	)
	(gr_poly
		(pts
			(xy 136.144762 -273.478244) (xy 136.044686 -273.378168) (xy 135.94461 -273.478244) (xy 135.94461 -273.522694)
			(xy 136.144762 -273.522694)
		)
		(stroke
			(width 0)
			(type solid)
		)
		(fill yes)
		(layer "In2.Cu")
		(net "M_I_CPU1_SB_CB<1>")
	)
	(gr_poly
		(pts
			(xy 136.144762 -273.074384) (xy 136.144762 -273.029934) (xy 135.94461 -273.029934) (xy 135.94461 -273.074384)
			(xy 136.044686 -273.17446)
		)
		(stroke
			(width 0)
			(type solid)
		)
		(fill yes)
		(layer "In2.Cu")
		(net "M_I_CPU1_SB_CB<2>")
	)
	(gr_poly
		(pts
			(xy 136.144762 -271.857978) (xy 136.044686 -271.758156) (xy 135.94461 -271.857978) (xy 135.94461 -271.90573)
			(xy 136.144762 -271.90573)
		)
		(stroke
			(width 0)
			(type solid)
		)
		(fill yes)
		(layer "In2.Cu")
		(net "M_I_CPU1_SB_DQS_DN<4>")
	)
	(gr_poly
		(pts
			(xy 136.144762 -271.454626) (xy 136.144762 -271.406874) (xy 135.94461 -271.406874) (xy 135.94461 -271.454626)
			(xy 136.044686 -271.554448)
		)
		(stroke
			(width 0)
			(type solid)
		)
		(fill yes)
		(layer "In2.Cu")
		(net "M_I_CPU1_SB_DQS_DN<9>")
	)
	(gr_poly
		(pts
			(xy 136.144762 -270.23822) (xy 136.044686 -270.138144) (xy 135.94461 -270.23822) (xy 135.94461 -270.28267)
			(xy 136.144762 -270.28267)
		)
		(stroke
			(width 0)
			(type solid)
		)
		(fill yes)
		(layer "In2.Cu")
		(net "M_I_CPU1_SB_CB<5>")
	)
	(gr_poly
		(pts
			(xy 136.144762 -269.83436) (xy 136.144762 -269.78991) (xy 135.94461 -269.78991) (xy 135.94461 -269.83436)
			(xy 136.044686 -269.934436)
		)
		(stroke
			(width 0)
			(type solid)
		)
		(fill yes)
		(layer "In2.Cu")
		(net "M_I_CPU1_SB_CB<6>")
	)
	(gr_poly
		(pts
			(xy 136.144762 -266.998196) (xy 136.044686 -266.89812) (xy 135.94461 -266.998196) (xy 135.94461 -267.042646)
			(xy 136.144762 -267.042646)
		)
		(stroke
			(width 0)
			(type solid)
		)
		(fill yes)
		(layer "In2.Cu")
		(net "M_I_CPU1_SA_RSP<0>")
	)
	(gr_poly
		(pts
			(xy 136.144762 -266.594336) (xy 136.144762 -266.549886) (xy 135.94461 -266.549886) (xy 135.94461 -266.594336)
			(xy 136.044686 -266.694412)
		)
		(stroke
			(width 0)
			(type solid)
		)
		(fill yes)
		(layer "In2.Cu")
		(net "M_I_CPU1_SB_CS_N<1>")
	)
	(gr_poly
		(pts
			(xy 136.144762 -265.378184) (xy 136.044686 -265.278108) (xy 135.94461 -265.378184) (xy 135.94461 -265.422634)
			(xy 136.144762 -265.422634)
		)
		(stroke
			(width 0)
			(type solid)
		)
		(fill yes)
		(layer "In2.Cu")
		(net "M_I_CPU1_SB_PAR")
	)
	(gr_poly
		(pts
			(xy 136.144762 -263.758172) (xy 136.044686 -263.658096) (xy 135.94461 -263.758172) (xy 135.94461 -263.802622)
			(xy 136.144762 -263.802622)
		)
		(stroke
			(width 0)
			(type solid)
		)
		(fill yes)
		(layer "In2.Cu")
		(net "M_I_CPU1_SB_CA<4>")
	)
	(gr_poly
		(pts
			(xy 136.144762 -263.354312) (xy 136.144762 -263.309862) (xy 135.94461 -263.309862) (xy 135.94461 -263.354312)
			(xy 136.044686 -263.454388)
		)
		(stroke
			(width 0)
			(type solid)
		)
		(fill yes)
		(layer "In2.Cu")
		(net "M_I_CPU1_SB_CA<3>")
	)
	(gr_poly
		(pts
			(xy 136.144762 -262.13816) (xy 136.044686 -262.038084) (xy 135.94461 -262.13816) (xy 135.94461 -262.18261)
			(xy 136.144762 -262.18261)
		)
		(stroke
			(width 0)
			(type solid)
		)
		(fill yes)
		(layer "In2.Cu")
		(net "M_I_CPU1_SB_CA<0>")
	)
	(gr_poly
		(pts
			(xy 136.314942 -256.432812) (xy 136.314942 -256.38506) (xy 136.11479 -256.38506) (xy 136.11479 -256.432812)
			(xy 136.214866 -256.532634)
		)
		(stroke
			(width 0)
			(type solid)
		)
		(fill yes)
		(layer "In2.Cu")
		(net "M_I_CPU1_CLK_DN<0>")
	)
	(gr_poly
		(pts
			(xy 136.314942 -255.216406) (xy 136.214866 -255.11633) (xy 136.11479 -255.216406) (xy 136.11479 -255.260856)
			(xy 136.314942 -255.260856)
		)
		(stroke
			(width 0)
			(type solid)
		)
		(fill yes)
		(layer "In2.Cu")
		(net "M_I_CPU1_SA_CA<6>")
	)
	(gr_poly
		(pts
			(xy 136.314942 -254.812546) (xy 136.314942 -254.768096) (xy 136.11479 -254.768096) (xy 136.11479 -254.812546)
			(xy 136.214866 -254.912622)
		)
		(stroke
			(width 0)
			(type solid)
		)
		(fill yes)
		(layer "In2.Cu")
		(net "M_I_CPU1_SA_CA<5>")
	)
	(gr_poly
		(pts
			(xy 136.314942 -253.596394) (xy 136.214866 -253.496318) (xy 136.11479 -253.596394) (xy 136.11479 -253.640844)
			(xy 136.314942 -253.640844)
		)
		(stroke
			(width 0)
			(type solid)
		)
		(fill yes)
		(layer "In2.Cu")
		(net "M_I_CPU1_SA_CA<2>")
	)
	(gr_poly
		(pts
			(xy 136.314942 -253.192534) (xy 136.314942 -253.148084) (xy 136.11479 -253.148084) (xy 136.11479 -253.192534)
			(xy 136.214866 -253.29261)
		)
		(stroke
			(width 0)
			(type solid)
		)
		(fill yes)
		(layer "In2.Cu")
		(net "M_I_CPU1_SA_CA<1>")
	)
	(gr_poly
		(pts
			(xy 136.314942 -251.976382) (xy 136.214866 -251.876306) (xy 136.11479 -251.976382) (xy 136.11479 -252.020832)
			(xy 136.314942 -252.020832)
		)
		(stroke
			(width 0)
			(type solid)
		)
		(fill yes)
		(layer "In2.Cu")
		(net "M_I_CPU1_SA_CS_N<1>")
	)
	(gr_poly
		(pts
			(xy 136.314942 -250.35637) (xy 136.214866 -250.256294) (xy 136.11479 -250.35637) (xy 136.11479 -250.40082)
			(xy 136.314942 -250.40082)
		)
		(stroke
			(width 0)
			(type solid)
		)
		(fill yes)
		(layer "In2.Cu")
		(net "M_I_CPU1_ALERT_R_N")
	)
	(gr_poly
		(pts
			(xy 136.314942 -248.736358) (xy 136.214866 -248.636282) (xy 136.11479 -248.736358) (xy 136.11479 -248.780808)
			(xy 136.314942 -248.780808)
		)
		(stroke
			(width 0)
			(type solid)
		)
		(fill yes)
		(layer "In2.Cu")
		(net "M_I_CPU1_SA_CB<5>")
	)
	(gr_poly
		(pts
			(xy 136.314942 -248.332498) (xy 136.314942 -248.288048) (xy 136.11479 -248.288048) (xy 136.11479 -248.332498)
			(xy 136.214866 -248.432574)
		)
		(stroke
			(width 0)
			(type solid)
		)
		(fill yes)
		(layer "In2.Cu")
		(net "M_I_CPU1_SA_CB<6>")
	)
	(gr_poly
		(pts
			(xy 136.314942 -247.116092) (xy 136.214866 -247.01627) (xy 136.11479 -247.116092) (xy 136.11479 -247.163844)
			(xy 136.314942 -247.163844)
		)
		(stroke
			(width 0)
			(type solid)
		)
		(fill yes)
		(layer "In2.Cu")
		(net "M_I_CPU1_SA_DQS_DN<9>")
	)
	(gr_poly
		(pts
			(xy 136.314942 -246.71274) (xy 136.314942 -246.664988) (xy 136.11479 -246.664988) (xy 136.11479 -246.71274)
			(xy 136.214866 -246.812562)
		)
		(stroke
			(width 0)
			(type solid)
		)
		(fill yes)
		(layer "In2.Cu")
		(net "M_I_CPU1_SA_DQS_DN<4>")
	)
	(gr_poly
		(pts
			(xy 136.314942 -245.496334) (xy 136.214866 -245.396258) (xy 136.11479 -245.496334) (xy 136.11479 -245.540784)
			(xy 136.314942 -245.540784)
		)
		(stroke
			(width 0)
			(type solid)
		)
		(fill yes)
		(layer "In2.Cu")
		(net "M_I_CPU1_SA_CB<1>")
	)
	(gr_poly
		(pts
			(xy 136.314942 -245.092474) (xy 136.314942 -245.048024) (xy 136.11479 -245.048024) (xy 136.11479 -245.092474)
			(xy 136.214866 -245.19255)
		)
		(stroke
			(width 0)
			(type solid)
		)
		(fill yes)
		(layer "In2.Cu")
		(net "M_I_CPU1_SA_CB<2>")
	)
	(gr_poly
		(pts
			(xy 136.314942 -243.876322) (xy 136.214866 -243.776246) (xy 136.11479 -243.876322) (xy 136.11479 -243.920772)
			(xy 136.314942 -243.920772)
		)
		(stroke
			(width 0)
			(type solid)
		)
		(fill yes)
		(layer "In2.Cu")
		(net "M_I_CPU1_SA_DQ<29>")
	)
	(gr_poly
		(pts
			(xy 136.314942 -243.472462) (xy 136.314942 -243.428012) (xy 136.11479 -243.428012) (xy 136.11479 -243.472462)
			(xy 136.214866 -243.572538)
		)
		(stroke
			(width 0)
			(type solid)
		)
		(fill yes)
		(layer "In2.Cu")
		(net "M_I_CPU1_SA_DQ<30>")
	)
	(gr_poly
		(pts
			(xy 136.314942 -242.256056) (xy 136.214866 -242.156234) (xy 136.11479 -242.256056) (xy 136.11479 -242.303808)
			(xy 136.314942 -242.303808)
		)
		(stroke
			(width 0)
			(type solid)
		)
		(fill yes)
		(layer "In2.Cu")
		(net "M_I_CPU1_SA_DQS_DN<8>")
	)
	(gr_poly
		(pts
			(xy 136.314942 -241.852704) (xy 136.314942 -241.804952) (xy 136.11479 -241.804952) (xy 136.11479 -241.852704)
			(xy 136.214866 -241.952526)
		)
		(stroke
			(width 0)
			(type solid)
		)
		(fill yes)
		(layer "In2.Cu")
		(net "M_I_CPU1_SA_DQS_DN<3>")
	)
	(gr_poly
		(pts
			(xy 136.314942 -240.636298) (xy 136.214866 -240.536222) (xy 136.11479 -240.636298) (xy 136.11479 -240.680748)
			(xy 136.314942 -240.680748)
		)
		(stroke
			(width 0)
			(type solid)
		)
		(fill yes)
		(layer "In2.Cu")
		(net "M_I_CPU1_SA_DQ<25>")
	)
	(gr_poly
		(pts
			(xy 136.314942 -240.232438) (xy 136.314942 -240.187988) (xy 136.11479 -240.187988) (xy 136.11479 -240.232438)
			(xy 136.214866 -240.332514)
		)
		(stroke
			(width 0)
			(type solid)
		)
		(fill yes)
		(layer "In2.Cu")
		(net "M_I_CPU1_SA_DQ<26>")
	)
	(gr_poly
		(pts
			(xy 136.314942 -239.016286) (xy 136.214866 -238.91621) (xy 136.11479 -239.016286) (xy 136.11479 -239.060736)
			(xy 136.314942 -239.060736)
		)
		(stroke
			(width 0)
			(type solid)
		)
		(fill yes)
		(layer "In2.Cu")
		(net "M_I_CPU1_SA_DQ<21>")
	)
	(gr_poly
		(pts
			(xy 136.314942 -238.612426) (xy 136.314942 -238.567976) (xy 136.11479 -238.567976) (xy 136.11479 -238.612426)
			(xy 136.214866 -238.712502)
		)
		(stroke
			(width 0)
			(type solid)
		)
		(fill yes)
		(layer "In2.Cu")
		(net "M_I_CPU1_SA_DQ<22>")
	)
	(gr_poly
		(pts
			(xy 136.314942 -237.39602) (xy 136.214866 -237.296198) (xy 136.11479 -237.39602) (xy 136.11479 -237.443772)
			(xy 136.314942 -237.443772)
		)
		(stroke
			(width 0)
			(type solid)
		)
		(fill yes)
		(layer "In2.Cu")
		(net "M_I_CPU1_SA_DQS_DN<7>")
	)
	(gr_poly
		(pts
			(xy 136.314942 -236.992668) (xy 136.314942 -236.944916) (xy 136.11479 -236.944916) (xy 136.11479 -236.992668)
			(xy 136.214866 -237.09249)
		)
		(stroke
			(width 0)
			(type solid)
		)
		(fill yes)
		(layer "In2.Cu")
		(net "M_I_CPU1_SA_DQS_DN<2>")
	)
	(gr_poly
		(pts
			(xy 136.314942 -235.776262) (xy 136.214866 -235.676186) (xy 136.11479 -235.776262) (xy 136.11479 -235.820712)
			(xy 136.314942 -235.820712)
		)
		(stroke
			(width 0)
			(type solid)
		)
		(fill yes)
		(layer "In2.Cu")
		(net "M_I_CPU1_SA_DQ<17>")
	)
	(gr_poly
		(pts
			(xy 136.314942 -235.372402) (xy 136.314942 -235.327952) (xy 136.11479 -235.327952) (xy 136.11479 -235.372402)
			(xy 136.214866 -235.472478)
		)
		(stroke
			(width 0)
			(type solid)
		)
		(fill yes)
		(layer "In2.Cu")
		(net "M_I_CPU1_SA_DQ<18>")
	)
	(gr_poly
		(pts
			(xy 136.314942 -234.15625) (xy 136.214866 -234.056174) (xy 136.11479 -234.15625) (xy 136.11479 -234.2007)
			(xy 136.314942 -234.2007)
		)
		(stroke
			(width 0)
			(type solid)
		)
		(fill yes)
		(layer "In2.Cu")
		(net "M_I_CPU1_SA_DQ<13>")
	)
	(gr_poly
		(pts
			(xy 136.314942 -233.75239) (xy 136.314942 -233.70794) (xy 136.11479 -233.70794) (xy 136.11479 -233.75239)
			(xy 136.214866 -233.852466)
		)
		(stroke
			(width 0)
			(type solid)
		)
		(fill yes)
		(layer "In2.Cu")
		(net "M_I_CPU1_SA_DQ<14>")
	)
	(gr_poly
		(pts
			(xy 136.314942 -232.535984) (xy 136.214866 -232.436162) (xy 136.11479 -232.535984) (xy 136.11479 -232.583736)
			(xy 136.314942 -232.583736)
		)
		(stroke
			(width 0)
			(type solid)
		)
		(fill yes)
		(layer "In2.Cu")
		(net "M_I_CPU1_SA_DQS_DN<6>")
	)
	(gr_poly
		(pts
			(xy 136.314942 -232.132632) (xy 136.314942 -232.08488) (xy 136.11479 -232.08488) (xy 136.11479 -232.132632)
			(xy 136.214866 -232.232454)
		)
		(stroke
			(width 0)
			(type solid)
		)
		(fill yes)
		(layer "In2.Cu")
		(net "M_I_CPU1_SA_DQS_DN<1>")
	)
	(gr_poly
		(pts
			(xy 136.314942 -230.916226) (xy 136.214866 -230.81615) (xy 136.11479 -230.916226) (xy 136.11479 -230.960676)
			(xy 136.314942 -230.960676)
		)
		(stroke
			(width 0)
			(type solid)
		)
		(fill yes)
		(layer "In2.Cu")
		(net "M_I_CPU1_SA_DQ<9>")
	)
	(gr_poly
		(pts
			(xy 136.314942 -230.51262) (xy 136.314942 -230.46817) (xy 136.11479 -230.46817) (xy 136.11479 -230.51262)
			(xy 136.214866 -230.612696)
		)
		(stroke
			(width 0)
			(type solid)
		)
		(fill yes)
		(layer "In2.Cu")
		(net "M_I_CPU1_SA_DQ<10>")
	)
	(gr_poly
		(pts
			(xy 136.314942 -229.296214) (xy 136.214866 -229.196138) (xy 136.11479 -229.296214) (xy 136.11479 -229.340664)
			(xy 136.314942 -229.340664)
		)
		(stroke
			(width 0)
			(type solid)
		)
		(fill yes)
		(layer "In2.Cu")
		(net "M_I_CPU1_SA_DQ<5>")
	)
	(gr_poly
		(pts
			(xy 136.314942 -228.892608) (xy 136.314942 -228.848158) (xy 136.11479 -228.848158) (xy 136.11479 -228.892608)
			(xy 136.214866 -228.992684)
		)
		(stroke
			(width 0)
			(type solid)
		)
		(fill yes)
		(layer "In2.Cu")
		(net "M_I_CPU1_SA_DQ<6>")
	)
	(gr_poly
		(pts
			(xy 136.314942 -227.676202) (xy 136.214866 -227.57638) (xy 136.11479 -227.676202) (xy 136.11479 -227.723954)
			(xy 136.314942 -227.723954)
		)
		(stroke
			(width 0)
			(type solid)
		)
		(fill yes)
		(layer "In2.Cu")
		(net "M_I_CPU1_SA_DQS_DN<5>")
	)
	(gr_poly
		(pts
			(xy 136.314942 -227.27285) (xy 136.314942 -227.225098) (xy 136.11479 -227.225098) (xy 136.11479 -227.27285)
			(xy 136.214866 -227.372672)
		)
		(stroke
			(width 0)
			(type solid)
		)
		(fill yes)
		(layer "In2.Cu")
		(net "M_I_CPU1_SA_DQS_DN<0>")
	)
	(gr_poly
		(pts
			(xy 136.314942 -226.056444) (xy 136.214866 -225.956368) (xy 136.11479 -226.056444) (xy 136.11479 -226.100894)
			(xy 136.314942 -226.100894)
		)
		(stroke
			(width 0)
			(type solid)
		)
		(fill yes)
		(layer "In2.Cu")
		(net "M_I_CPU1_SA_DQ<1>")
	)
	(gr_poly
		(pts
			(xy 136.314942 -225.652584) (xy 136.314942 -225.608134) (xy 136.11479 -225.608134) (xy 136.11479 -225.652584)
			(xy 136.214866 -225.75266)
		)
		(stroke
			(width 0)
			(type solid)
		)
		(fill yes)
		(layer "In2.Cu")
		(net "M_I_CPU1_SA_DQ<2>")
	)
	(gr_poly
		(pts
			(xy 136.614916 -293.32428) (xy 136.614916 -293.27983) (xy 136.414764 -293.27983) (xy 136.414764 -293.32428)
			(xy 136.51484 -293.424356)
		)
		(stroke
			(width 0)
			(type solid)
		)
		(fill yes)
		(layer "In2.Cu")
		(net "M_I_CPU1_SB_DQ<31>")
	)
	(gr_poly
		(pts
			(xy 136.614916 -292.108128) (xy 136.51484 -292.008052) (xy 136.414764 -292.108128) (xy 136.414764 -292.152578)
			(xy 136.614916 -292.152578)
		)
		(stroke
			(width 0)
			(type solid)
		)
		(fill yes)
		(layer "In2.Cu")
		(net "M_I_CPU1_SB_DQ<28>")
	)
	(gr_poly
		(pts
			(xy 136.614916 -291.704522) (xy 136.614916 -291.65677) (xy 136.414764 -291.65677) (xy 136.414764 -291.704522)
			(xy 136.51484 -291.804344)
		)
		(stroke
			(width 0)
			(type solid)
		)
		(fill yes)
		(layer "In2.Cu")
		(net "M_I_CPU1_SB_DQS_DP<8>")
	)
	(gr_poly
		(pts
			(xy 136.614916 -290.487862) (xy 136.51484 -290.38804) (xy 136.414764 -290.487862) (xy 136.414764 -290.535614)
			(xy 136.614916 -290.535614)
		)
		(stroke
			(width 0)
			(type solid)
		)
		(fill yes)
		(layer "In2.Cu")
		(net "M_I_CPU1_SB_DQS_DP<3>")
	)
	(gr_poly
		(pts
			(xy 136.614916 -290.084256) (xy 136.614916 -290.039806) (xy 136.414764 -290.039806) (xy 136.414764 -290.084256)
			(xy 136.51484 -290.184332)
		)
		(stroke
			(width 0)
			(type solid)
		)
		(fill yes)
		(layer "In2.Cu")
		(net "M_I_CPU1_SB_DQ<27>")
	)
	(gr_poly
		(pts
			(xy 136.614916 -288.868104) (xy 136.51484 -288.768028) (xy 136.414764 -288.868104) (xy 136.414764 -288.912554)
			(xy 136.614916 -288.912554)
		)
		(stroke
			(width 0)
			(type solid)
		)
		(fill yes)
		(layer "In2.Cu")
		(net "M_I_CPU1_SB_DQ<24>")
	)
	(gr_poly
		(pts
			(xy 136.614916 -288.464498) (xy 136.614916 -288.420048) (xy 136.414764 -288.420048) (xy 136.414764 -288.464498)
			(xy 136.51484 -288.564574)
		)
		(stroke
			(width 0)
			(type solid)
		)
		(fill yes)
		(layer "In2.Cu")
		(net "M_I_CPU1_SB_DQ<23>")
	)
	(gr_poly
		(pts
			(xy 136.614916 -287.248092) (xy 136.51484 -287.148016) (xy 136.414764 -287.248092) (xy 136.414764 -287.292542)
			(xy 136.614916 -287.292542)
		)
		(stroke
			(width 0)
			(type solid)
		)
		(fill yes)
		(layer "In2.Cu")
		(net "M_I_CPU1_SB_DQ<20>")
	)
	(gr_poly
		(pts
			(xy 136.614916 -286.844486) (xy 136.614916 -286.796734) (xy 136.414764 -286.796734) (xy 136.414764 -286.844486)
			(xy 136.51484 -286.944562)
		)
		(stroke
			(width 0)
			(type solid)
		)
		(fill yes)
		(layer "In2.Cu")
		(net "M_I_CPU1_SB_DQS_DP<7>")
	)
	(gr_poly
		(pts
			(xy 136.614916 -285.62808) (xy 136.51484 -285.528258) (xy 136.414764 -285.62808) (xy 136.414764 -285.675832)
			(xy 136.614916 -285.675832)
		)
		(stroke
			(width 0)
			(type solid)
		)
		(fill yes)
		(layer "In2.Cu")
		(net "M_I_CPU1_SB_DQS_DP<2>")
	)
	(gr_poly
		(pts
			(xy 136.614916 -285.224474) (xy 136.614916 -285.180024) (xy 136.414764 -285.180024) (xy 136.414764 -285.224474)
			(xy 136.51484 -285.32455)
		)
		(stroke
			(width 0)
			(type solid)
		)
		(fill yes)
		(layer "In2.Cu")
		(net "M_I_CPU1_SB_DQ<19>")
	)
	(gr_poly
		(pts
			(xy 136.614916 -284.008322) (xy 136.51484 -283.908246) (xy 136.414764 -284.008322) (xy 136.414764 -284.052772)
			(xy 136.614916 -284.052772)
		)
		(stroke
			(width 0)
			(type solid)
		)
		(fill yes)
		(layer "In2.Cu")
		(net "M_I_CPU1_SB_DQ<16>")
	)
	(gr_poly
		(pts
			(xy 136.614916 -283.604462) (xy 136.614916 -283.560012) (xy 136.414764 -283.560012) (xy 136.414764 -283.604462)
			(xy 136.51484 -283.704538)
		)
		(stroke
			(width 0)
			(type solid)
		)
		(fill yes)
		(layer "In2.Cu")
		(net "M_I_CPU1_SB_DQ<15>")
	)
	(gr_poly
		(pts
			(xy 136.614916 -282.38831) (xy 136.51484 -282.288234) (xy 136.414764 -282.38831) (xy 136.414764 -282.43276)
			(xy 136.614916 -282.43276)
		)
		(stroke
			(width 0)
			(type solid)
		)
		(fill yes)
		(layer "In2.Cu")
		(net "M_I_CPU1_SB_DQ<12>")
	)
	(gr_poly
		(pts
			(xy 136.614916 -281.984704) (xy 136.614916 -281.936952) (xy 136.414764 -281.936952) (xy 136.414764 -281.984704)
			(xy 136.51484 -282.084526)
		)
		(stroke
			(width 0)
			(type solid)
		)
		(fill yes)
		(layer "In2.Cu")
		(net "M_I_CPU1_SB_DQS_DP<6>")
	)
	(gr_poly
		(pts
			(xy 136.614916 -280.768044) (xy 136.51484 -280.668222) (xy 136.414764 -280.768044) (xy 136.414764 -280.815796)
			(xy 136.614916 -280.815796)
		)
		(stroke
			(width 0)
			(type solid)
		)
		(fill yes)
		(layer "In2.Cu")
		(net "M_I_CPU1_SB_DQS_DP<1>")
	)
	(gr_poly
		(pts
			(xy 136.614916 -280.364438) (xy 136.614916 -280.319988) (xy 136.414764 -280.319988) (xy 136.414764 -280.364438)
			(xy 136.51484 -280.464514)
		)
		(stroke
			(width 0)
			(type solid)
		)
		(fill yes)
		(layer "In2.Cu")
		(net "M_I_CPU1_SB_DQ<11>")
	)
	(gr_poly
		(pts
			(xy 136.614916 -279.148286) (xy 136.51484 -279.04821) (xy 136.414764 -279.148286) (xy 136.414764 -279.192736)
			(xy 136.614916 -279.192736)
		)
		(stroke
			(width 0)
			(type solid)
		)
		(fill yes)
		(layer "In2.Cu")
		(net "M_I_CPU1_SB_DQ<8>")
	)
	(gr_poly
		(pts
			(xy 136.614916 -278.744426) (xy 136.614916 -278.699976) (xy 136.414764 -278.699976) (xy 136.414764 -278.744426)
			(xy 136.51484 -278.844502)
		)
		(stroke
			(width 0)
			(type solid)
		)
		(fill yes)
		(layer "In2.Cu")
		(net "M_I_CPU1_SB_DQ<7>")
	)
	(gr_poly
		(pts
			(xy 136.614916 -277.528274) (xy 136.51484 -277.428198) (xy 136.414764 -277.528274) (xy 136.414764 -277.572724)
			(xy 136.614916 -277.572724)
		)
		(stroke
			(width 0)
			(type solid)
		)
		(fill yes)
		(layer "In2.Cu")
		(net "M_I_CPU1_SB_DQ<4>")
	)
	(gr_poly
		(pts
			(xy 136.614916 -277.124668) (xy 136.614916 -277.076916) (xy 136.414764 -277.076916) (xy 136.414764 -277.124668)
			(xy 136.51484 -277.22449)
		)
		(stroke
			(width 0)
			(type solid)
		)
		(fill yes)
		(layer "In2.Cu")
		(net "M_I_CPU1_SB_DQS_DP<5>")
	)
	(gr_poly
		(pts
			(xy 136.614916 -275.908008) (xy 136.51484 -275.808186) (xy 136.414764 -275.908008) (xy 136.414764 -275.95576)
			(xy 136.614916 -275.95576)
		)
		(stroke
			(width 0)
			(type solid)
		)
		(fill yes)
		(layer "In2.Cu")
		(net "M_I_CPU1_SB_DQS_DP<0>")
	)
	(gr_poly
		(pts
			(xy 136.614916 -275.504402) (xy 136.614916 -275.459952) (xy 136.414764 -275.459952) (xy 136.414764 -275.504402)
			(xy 136.51484 -275.604478)
		)
		(stroke
			(width 0)
			(type solid)
		)
		(fill yes)
		(layer "In2.Cu")
		(net "M_I_CPU1_SB_DQ<3>")
	)
	(gr_poly
		(pts
			(xy 136.614916 -274.28825) (xy 136.51484 -274.188174) (xy 136.414764 -274.28825) (xy 136.414764 -274.3327)
			(xy 136.614916 -274.3327)
		)
		(stroke
			(width 0)
			(type solid)
		)
		(fill yes)
		(layer "In2.Cu")
		(net "M_I_CPU1_SB_DQ<0>")
	)
	(gr_poly
		(pts
			(xy 136.614916 -273.88439) (xy 136.614916 -273.83994) (xy 136.414764 -273.83994) (xy 136.414764 -273.88439)
			(xy 136.51484 -273.984466)
		)
		(stroke
			(width 0)
			(type solid)
		)
		(fill yes)
		(layer "In2.Cu")
		(net "M_I_CPU1_SB_CB<3>")
	)
	(gr_poly
		(pts
			(xy 136.614916 -272.668238) (xy 136.51484 -272.568162) (xy 136.414764 -272.668238) (xy 136.414764 -272.712688)
			(xy 136.614916 -272.712688)
		)
		(stroke
			(width 0)
			(type solid)
		)
		(fill yes)
		(layer "In2.Cu")
		(net "M_I_CPU1_SB_CB<0>")
	)
	(gr_poly
		(pts
			(xy 136.614916 -272.264632) (xy 136.614916 -272.21688) (xy 136.414764 -272.21688) (xy 136.414764 -272.264632)
			(xy 136.51484 -272.364454)
		)
		(stroke
			(width 0)
			(type solid)
		)
		(fill yes)
		(layer "In2.Cu")
		(net "M_I_CPU1_SB_DQS_DP<4>")
	)
	(gr_poly
		(pts
			(xy 136.614916 -271.047972) (xy 136.51484 -270.94815) (xy 136.414764 -271.047972) (xy 136.414764 -271.095724)
			(xy 136.614916 -271.095724)
		)
		(stroke
			(width 0)
			(type solid)
		)
		(fill yes)
		(layer "In2.Cu")
		(net "M_I_CPU1_SB_DQS_DP<9>")
	)
	(gr_poly
		(pts
			(xy 136.614916 -270.644366) (xy 136.614916 -270.599916) (xy 136.414764 -270.599916) (xy 136.414764 -270.644366)
			(xy 136.51484 -270.744442)
		)
		(stroke
			(width 0)
			(type solid)
		)
		(fill yes)
		(layer "In2.Cu")
		(net "M_I_CPU1_SB_CB<7>")
	)
	(gr_poly
		(pts
			(xy 136.614916 -269.428214) (xy 136.51484 -269.328138) (xy 136.414764 -269.428214) (xy 136.414764 -269.472664)
			(xy 136.614916 -269.472664)
		)
		(stroke
			(width 0)
			(type solid)
		)
		(fill yes)
		(layer "In2.Cu")
		(net "M_I_CPU1_SB_CB<4>")
	)
	(gr_poly
		(pts
			(xy 136.614916 -267.404342) (xy 136.614916 -267.359892) (xy 136.414764 -267.359892) (xy 136.414764 -267.404342)
			(xy 136.51484 -267.504418)
		)
		(stroke
			(width 0)
			(type solid)
		)
		(fill yes)
		(layer "In2.Cu")
		(net "M_I_CPU1_SB_RSP<0>")
	)
	(gr_poly
		(pts
			(xy 136.614916 -265.78433) (xy 136.614916 -265.73988) (xy 136.414764 -265.73988) (xy 136.414764 -265.78433)
			(xy 136.51484 -265.884406)
		)
		(stroke
			(width 0)
			(type solid)
		)
		(fill yes)
		(layer "In2.Cu")
		(net "M_I_CPU1_SB_CS_N<0>")
	)
	(gr_poly
		(pts
			(xy 136.614916 -264.568178) (xy 136.51484 -264.468102) (xy 136.414764 -264.568178) (xy 136.414764 -264.612628)
			(xy 136.614916 -264.612628)
		)
		(stroke
			(width 0)
			(type solid)
		)
		(fill yes)
		(layer "In2.Cu")
		(net "M_I_CPU1_SB_CA<6>")
	)
	(gr_poly
		(pts
			(xy 136.614916 -264.164318) (xy 136.614916 -264.119868) (xy 136.414764 -264.119868) (xy 136.414764 -264.164318)
			(xy 136.51484 -264.264394)
		)
		(stroke
			(width 0)
			(type solid)
		)
		(fill yes)
		(layer "In2.Cu")
		(net "M_I_CPU1_SB_CA<5>")
	)
	(gr_poly
		(pts
			(xy 136.614916 -262.948166) (xy 136.51484 -262.84809) (xy 136.414764 -262.948166) (xy 136.414764 -262.992616)
			(xy 136.614916 -262.992616)
		)
		(stroke
			(width 0)
			(type solid)
		)
		(fill yes)
		(layer "In2.Cu")
		(net "M_I_CPU1_SB_CA<2>")
	)
	(gr_poly
		(pts
			(xy 136.614916 -262.544306) (xy 136.614916 -262.499856) (xy 136.414764 -262.499856) (xy 136.414764 -262.544306)
			(xy 136.51484 -262.644382)
		)
		(stroke
			(width 0)
			(type solid)
		)
		(fill yes)
		(layer "In2.Cu")
		(net "M_I_CPU1_SB_CA<1>")
	)
	(gr_poly
		(pts
			(xy 136.784842 -256.026158) (xy 136.684766 -255.926336) (xy 136.58469 -256.026158) (xy 136.58469 -256.07391)
			(xy 136.784842 -256.07391)
		)
		(stroke
			(width 0)
			(type solid)
		)
		(fill yes)
		(layer "In2.Cu")
		(net "M_I_CPU1_CLK_DP<0>")
	)
	(gr_poly
		(pts
			(xy 136.784842 -255.622552) (xy 136.784842 -255.578102) (xy 136.58469 -255.578102) (xy 136.58469 -255.622552)
			(xy 136.684766 -255.722628)
		)
		(stroke
			(width 0)
			(type solid)
		)
		(fill yes)
		(layer "In2.Cu")
		(net "M_I_CPU1_SA_PAR")
	)
	(gr_poly
		(pts
			(xy 136.784842 -254.4064) (xy 136.684766 -254.306324) (xy 136.58469 -254.4064) (xy 136.58469 -254.45085)
			(xy 136.784842 -254.45085)
		)
		(stroke
			(width 0)
			(type solid)
		)
		(fill yes)
		(layer "In2.Cu")
		(net "M_I_CPU1_SA_CA<4>")
	)
	(gr_poly
		(pts
			(xy 136.784842 -254.00254) (xy 136.784842 -253.95809) (xy 136.58469 -253.95809) (xy 136.58469 -254.00254)
			(xy 136.684766 -254.102616)
		)
		(stroke
			(width 0)
			(type solid)
		)
		(fill yes)
		(layer "In2.Cu")
		(net "M_I_CPU1_SA_CA<3>")
	)
	(gr_poly
		(pts
			(xy 136.784842 -252.786388) (xy 136.684766 -252.686312) (xy 136.58469 -252.786388) (xy 136.58469 -252.830838)
			(xy 136.784842 -252.830838)
		)
		(stroke
			(width 0)
			(type solid)
		)
		(fill yes)
		(layer "In2.Cu")
		(net "M_I_CPU1_SA_CA<0>")
	)
	(gr_poly
		(pts
			(xy 136.784842 -251.166376) (xy 136.684766 -251.0663) (xy 136.58469 -251.166376) (xy 136.58469 -251.210826)
			(xy 136.784842 -251.210826)
		)
		(stroke
			(width 0)
			(type solid)
		)
		(fill yes)
		(layer "In2.Cu")
		(net "M_I_CPU1_SA_CS_N<0>")
	)
	(gr_poly
		(pts
			(xy 136.784842 -250.762516) (xy 136.784842 -250.718066) (xy 136.58469 -250.718066) (xy 136.58469 -250.762516)
			(xy 136.684766 -250.862592)
		)
		(stroke
			(width 0)
			(type solid)
		)
		(fill yes)
		(layer "In2.Cu")
		(net "M_I_CPU1_RESET_N")
	)
	(gr_poly
		(pts
			(xy 136.784842 -249.142504) (xy 136.784842 -249.098054) (xy 136.58469 -249.098054) (xy 136.58469 -249.142504)
			(xy 136.684766 -249.24258)
		)
		(stroke
			(width 0)
			(type solid)
		)
		(fill yes)
		(layer "In2.Cu")
		(net "M_I_CPU1_SA_CB<7>")
	)
	(gr_poly
		(pts
			(xy 136.784842 -247.926352) (xy 136.684766 -247.826276) (xy 136.58469 -247.926352) (xy 136.58469 -247.970802)
			(xy 136.784842 -247.970802)
		)
		(stroke
			(width 0)
			(type solid)
		)
		(fill yes)
		(layer "In2.Cu")
		(net "M_I_CPU1_SA_CB<4>")
	)
	(gr_poly
		(pts
			(xy 136.784842 -247.522746) (xy 136.784842 -247.474994) (xy 136.58469 -247.474994) (xy 136.58469 -247.522746)
			(xy 136.684766 -247.622568)
		)
		(stroke
			(width 0)
			(type solid)
		)
		(fill yes)
		(layer "In2.Cu")
		(net "M_I_CPU1_SA_DQS_DP<9>")
	)
	(gr_poly
		(pts
			(xy 136.784842 -246.306086) (xy 136.684766 -246.206264) (xy 136.58469 -246.306086) (xy 136.58469 -246.353838)
			(xy 136.784842 -246.353838)
		)
		(stroke
			(width 0)
			(type solid)
		)
		(fill yes)
		(layer "In2.Cu")
		(net "M_I_CPU1_SA_DQS_DP<4>")
	)
	(gr_poly
		(pts
			(xy 136.784842 -245.90248) (xy 136.784842 -245.85803) (xy 136.58469 -245.85803) (xy 136.58469 -245.90248)
			(xy 136.684766 -246.002556)
		)
		(stroke
			(width 0)
			(type solid)
		)
		(fill yes)
		(layer "In2.Cu")
		(net "M_I_CPU1_SA_CB<3>")
	)
	(gr_poly
		(pts
			(xy 136.784842 -244.686328) (xy 136.684766 -244.586252) (xy 136.58469 -244.686328) (xy 136.58469 -244.730778)
			(xy 136.784842 -244.730778)
		)
		(stroke
			(width 0)
			(type solid)
		)
		(fill yes)
		(layer "In2.Cu")
		(net "M_I_CPU1_SA_CB<0>")
	)
	(gr_poly
		(pts
			(xy 136.784842 -244.282468) (xy 136.784842 -244.238018) (xy 136.58469 -244.238018) (xy 136.58469 -244.282468)
			(xy 136.684766 -244.382544)
		)
		(stroke
			(width 0)
			(type solid)
		)
		(fill yes)
		(layer "In2.Cu")
		(net "M_I_CPU1_SA_DQ<31>")
	)
	(gr_poly
		(pts
			(xy 136.784842 -243.066316) (xy 136.684766 -242.96624) (xy 136.58469 -243.066316) (xy 136.58469 -243.110766)
			(xy 136.784842 -243.110766)
		)
		(stroke
			(width 0)
			(type solid)
		)
		(fill yes)
		(layer "In2.Cu")
		(net "M_I_CPU1_SA_DQ<28>")
	)
	(gr_poly
		(pts
			(xy 136.784842 -242.66271) (xy 136.784842 -242.614958) (xy 136.58469 -242.614958) (xy 136.58469 -242.66271)
			(xy 136.684766 -242.762532)
		)
		(stroke
			(width 0)
			(type solid)
		)
		(fill yes)
		(layer "In2.Cu")
		(net "M_I_CPU1_SA_DQS_DP<8>")
	)
	(gr_poly
		(pts
			(xy 136.784842 -241.44605) (xy 136.684766 -241.346228) (xy 136.58469 -241.44605) (xy 136.58469 -241.493802)
			(xy 136.784842 -241.493802)
		)
		(stroke
			(width 0)
			(type solid)
		)
		(fill yes)
		(layer "In2.Cu")
		(net "M_I_CPU1_SA_DQS_DP<3>")
	)
	(gr_poly
		(pts
			(xy 136.784842 -241.042444) (xy 136.784842 -240.997994) (xy 136.58469 -240.997994) (xy 136.58469 -241.042444)
			(xy 136.684766 -241.14252)
		)
		(stroke
			(width 0)
			(type solid)
		)
		(fill yes)
		(layer "In2.Cu")
		(net "M_I_CPU1_SA_DQ<27>")
	)
	(gr_poly
		(pts
			(xy 136.784842 -239.826292) (xy 136.684766 -239.726216) (xy 136.58469 -239.826292) (xy 136.58469 -239.870742)
			(xy 136.784842 -239.870742)
		)
		(stroke
			(width 0)
			(type solid)
		)
		(fill yes)
		(layer "In2.Cu")
		(net "M_I_CPU1_SA_DQ<24>")
	)
	(gr_poly
		(pts
			(xy 136.784842 -239.422432) (xy 136.784842 -239.377982) (xy 136.58469 -239.377982) (xy 136.58469 -239.422432)
			(xy 136.684766 -239.522508)
		)
		(stroke
			(width 0)
			(type solid)
		)
		(fill yes)
		(layer "In2.Cu")
		(net "M_I_CPU1_SA_DQ<23>")
	)
	(gr_poly
		(pts
			(xy 136.784842 -238.20628) (xy 136.684766 -238.106204) (xy 136.58469 -238.20628) (xy 136.58469 -238.25073)
			(xy 136.784842 -238.25073)
		)
		(stroke
			(width 0)
			(type solid)
		)
		(fill yes)
		(layer "In2.Cu")
		(net "M_I_CPU1_SA_DQ<20>")
	)
	(gr_poly
		(pts
			(xy 136.784842 -237.802674) (xy 136.784842 -237.754922) (xy 136.58469 -237.754922) (xy 136.58469 -237.802674)
			(xy 136.684766 -237.902496)
		)
		(stroke
			(width 0)
			(type solid)
		)
		(fill yes)
		(layer "In2.Cu")
		(net "M_I_CPU1_SA_DQS_DP<7>")
	)
	(gr_poly
		(pts
			(xy 136.784842 -236.586014) (xy 136.684766 -236.486192) (xy 136.58469 -236.586014) (xy 136.58469 -236.633766)
			(xy 136.784842 -236.633766)
		)
		(stroke
			(width 0)
			(type solid)
		)
		(fill yes)
		(layer "In2.Cu")
		(net "M_I_CPU1_SA_DQS_DP<2>")
	)
	(gr_poly
		(pts
			(xy 136.784842 -236.182408) (xy 136.784842 -236.137958) (xy 136.58469 -236.137958) (xy 136.58469 -236.182408)
			(xy 136.684766 -236.282484)
		)
		(stroke
			(width 0)
			(type solid)
		)
		(fill yes)
		(layer "In2.Cu")
		(net "M_I_CPU1_SA_DQ<19>")
	)
	(gr_poly
		(pts
			(xy 136.784842 -234.966256) (xy 136.684766 -234.86618) (xy 136.58469 -234.966256) (xy 136.58469 -235.010706)
			(xy 136.784842 -235.010706)
		)
		(stroke
			(width 0)
			(type solid)
		)
		(fill yes)
		(layer "In2.Cu")
		(net "M_I_CPU1_SA_DQ<16>")
	)
	(gr_poly
		(pts
			(xy 136.784842 -234.562396) (xy 136.784842 -234.517946) (xy 136.58469 -234.517946) (xy 136.58469 -234.562396)
			(xy 136.684766 -234.662472)
		)
		(stroke
			(width 0)
			(type solid)
		)
		(fill yes)
		(layer "In2.Cu")
		(net "M_I_CPU1_SA_DQ<15>")
	)
	(gr_poly
		(pts
			(xy 136.784842 -233.346244) (xy 136.684766 -233.246168) (xy 136.58469 -233.346244) (xy 136.58469 -233.390694)
			(xy 136.784842 -233.390694)
		)
		(stroke
			(width 0)
			(type solid)
		)
		(fill yes)
		(layer "In2.Cu")
		(net "M_I_CPU1_SA_DQ<12>")
	)
	(gr_poly
		(pts
			(xy 136.784842 -232.942638) (xy 136.784842 -232.894886) (xy 136.58469 -232.894886) (xy 136.58469 -232.942638)
			(xy 136.684766 -233.04246)
		)
		(stroke
			(width 0)
			(type solid)
		)
		(fill yes)
		(layer "In2.Cu")
		(net "M_I_CPU1_SA_DQS_DP<6>")
	)
	(gr_poly
		(pts
			(xy 136.784842 -231.725978) (xy 136.684766 -231.626156) (xy 136.58469 -231.725978) (xy 136.58469 -231.77373)
			(xy 136.784842 -231.77373)
		)
		(stroke
			(width 0)
			(type solid)
		)
		(fill yes)
		(layer "In2.Cu")
		(net "M_I_CPU1_SA_DQS_DP<1>")
	)
	(gr_poly
		(pts
			(xy 136.784842 -231.322626) (xy 136.784842 -231.278176) (xy 136.58469 -231.278176) (xy 136.58469 -231.322626)
			(xy 136.684766 -231.422702)
		)
		(stroke
			(width 0)
			(type solid)
		)
		(fill yes)
		(layer "In2.Cu")
		(net "M_I_CPU1_SA_DQ<11>")
	)
	(gr_poly
		(pts
			(xy 136.784842 -230.10622) (xy 136.684766 -230.006144) (xy 136.58469 -230.10622) (xy 136.58469 -230.15067)
			(xy 136.784842 -230.15067)
		)
		(stroke
			(width 0)
			(type solid)
		)
		(fill yes)
		(layer "In2.Cu")
		(net "M_I_CPU1_SA_DQ<8>")
	)
	(gr_poly
		(pts
			(xy 136.784842 -229.702614) (xy 136.784842 -229.658164) (xy 136.58469 -229.658164) (xy 136.58469 -229.702614)
			(xy 136.684766 -229.80269)
		)
		(stroke
			(width 0)
			(type solid)
		)
		(fill yes)
		(layer "In2.Cu")
		(net "M_I_CPU1_SA_DQ<7>")
	)
	(gr_poly
		(pts
			(xy 136.784842 -228.486462) (xy 136.684766 -228.386386) (xy 136.58469 -228.486462) (xy 136.58469 -228.530912)
			(xy 136.784842 -228.530912)
		)
		(stroke
			(width 0)
			(type solid)
		)
		(fill yes)
		(layer "In2.Cu")
		(net "M_I_CPU1_SA_DQ<4>")
	)
	(gr_poly
		(pts
			(xy 136.784842 -228.082856) (xy 136.784842 -228.035104) (xy 136.58469 -228.035104) (xy 136.58469 -228.082856)
			(xy 136.684766 -228.182678)
		)
		(stroke
			(width 0)
			(type solid)
		)
		(fill yes)
		(layer "In2.Cu")
		(net "M_I_CPU1_SA_DQS_DP<5>")
	)
	(gr_poly
		(pts
			(xy 136.784842 -226.866196) (xy 136.684766 -226.766374) (xy 136.58469 -226.866196) (xy 136.58469 -226.913948)
			(xy 136.784842 -226.913948)
		)
		(stroke
			(width 0)
			(type solid)
		)
		(fill yes)
		(layer "In2.Cu")
		(net "M_I_CPU1_SA_DQS_DP<0>")
	)
	(gr_poly
		(pts
			(xy 136.784842 -226.46259) (xy 136.784842 -226.41814) (xy 136.58469 -226.41814) (xy 136.58469 -226.46259)
			(xy 136.684766 -226.562666)
		)
		(stroke
			(width 0)
			(type solid)
		)
		(fill yes)
		(layer "In2.Cu")
		(net "M_I_CPU1_SA_DQ<3>")
	)
	(gr_poly
		(pts
			(xy 136.784842 -225.246438) (xy 136.684766 -225.146362) (xy 136.58469 -225.246438) (xy 136.58469 -225.290888)
			(xy 136.784842 -225.290888)
		)
		(stroke
			(width 0)
			(type solid)
		)
		(fill yes)
		(layer "In2.Cu")
		(net "M_I_CPU1_SA_DQ<0>")
	)
	(gr_poly
		(pts
			(xy 137.084816 -292.918134) (xy 136.98474 -292.818058) (xy 136.884664 -292.918134) (xy 136.884664 -292.962584)
			(xy 137.084816 -292.962584)
		)
		(stroke
			(width 0)
			(type solid)
		)
		(fill yes)
		(layer "In2.Cu")
		(net "M_I_CPU1_SB_DQ<29>")
	)
	(gr_poly
		(pts
			(xy 137.084816 -292.514274) (xy 137.084816 -292.469824) (xy 136.884664 -292.469824) (xy 136.884664 -292.514274)
			(xy 136.98474 -292.61435)
		)
		(stroke
			(width 0)
			(type solid)
		)
		(fill yes)
		(layer "In2.Cu")
		(net "M_I_CPU1_SB_DQ<30>")
	)
	(gr_poly
		(pts
			(xy 137.084816 -291.297868) (xy 136.98474 -291.198046) (xy 136.884664 -291.297868) (xy 136.884664 -291.34562)
			(xy 137.084816 -291.34562)
		)
		(stroke
			(width 0)
			(type solid)
		)
		(fill yes)
		(layer "In2.Cu")
		(net "M_I_CPU1_SB_DQS_DN<8>")
	)
	(gr_poly
		(pts
			(xy 137.084816 -290.894516) (xy 137.084816 -290.846764) (xy 136.884664 -290.846764) (xy 136.884664 -290.894516)
			(xy 136.98474 -290.994338)
		)
		(stroke
			(width 0)
			(type solid)
		)
		(fill yes)
		(layer "In2.Cu")
		(net "M_I_CPU1_SB_DQS_DN<3>")
	)
	(gr_poly
		(pts
			(xy 137.084816 -289.67811) (xy 136.98474 -289.578034) (xy 136.884664 -289.67811) (xy 136.884664 -289.72256)
			(xy 137.084816 -289.72256)
		)
		(stroke
			(width 0)
			(type solid)
		)
		(fill yes)
		(layer "In2.Cu")
		(net "M_I_CPU1_SB_DQ<25>")
	)
	(gr_poly
		(pts
			(xy 137.084816 -289.27425) (xy 137.084816 -289.2298) (xy 136.884664 -289.2298) (xy 136.884664 -289.27425)
			(xy 136.98474 -289.374326)
		)
		(stroke
			(width 0)
			(type solid)
		)
		(fill yes)
		(layer "In2.Cu")
		(net "M_I_CPU1_SB_DQ<26>")
	)
	(gr_poly
		(pts
			(xy 137.084816 -288.058098) (xy 136.98474 -287.958022) (xy 136.884664 -288.058098) (xy 136.884664 -288.102548)
			(xy 137.084816 -288.102548)
		)
		(stroke
			(width 0)
			(type solid)
		)
		(fill yes)
		(layer "In2.Cu")
		(net "M_I_CPU1_SB_DQ<21>")
	)
	(gr_poly
		(pts
			(xy 137.084816 -287.654492) (xy 137.084816 -287.610042) (xy 136.884664 -287.610042) (xy 136.884664 -287.654492)
			(xy 136.98474 -287.754568)
		)
		(stroke
			(width 0)
			(type solid)
		)
		(fill yes)
		(layer "In2.Cu")
		(net "M_I_CPU1_SB_DQ<22>")
	)
	(gr_poly
		(pts
			(xy 137.084816 -286.438086) (xy 136.98474 -286.33801) (xy 136.884664 -286.438086) (xy 136.884664 -286.485838)
			(xy 137.084816 -286.485838)
		)
		(stroke
			(width 0)
			(type solid)
		)
		(fill yes)
		(layer "In2.Cu")
		(net "M_I_CPU1_SB_DQS_DN<7>")
	)
	(gr_poly
		(pts
			(xy 137.084816 -286.034734) (xy 137.084816 -285.986982) (xy 136.884664 -285.986982) (xy 136.884664 -286.034734)
			(xy 136.98474 -286.134556)
		)
		(stroke
			(width 0)
			(type solid)
		)
		(fill yes)
		(layer "In2.Cu")
		(net "M_I_CPU1_SB_DQS_DN<2>")
	)
	(gr_poly
		(pts
			(xy 137.084816 -284.818328) (xy 136.98474 -284.718252) (xy 136.884664 -284.818328) (xy 136.884664 -284.862778)
			(xy 137.084816 -284.862778)
		)
		(stroke
			(width 0)
			(type solid)
		)
		(fill yes)
		(layer "In2.Cu")
		(net "M_I_CPU1_SB_DQ<17>")
	)
	(gr_poly
		(pts
			(xy 137.084816 -284.414468) (xy 137.084816 -284.370018) (xy 136.884664 -284.370018) (xy 136.884664 -284.414468)
			(xy 136.98474 -284.514544)
		)
		(stroke
			(width 0)
			(type solid)
		)
		(fill yes)
		(layer "In2.Cu")
		(net "M_I_CPU1_SB_DQ<18>")
	)
	(gr_poly
		(pts
			(xy 137.084816 -283.198316) (xy 136.98474 -283.09824) (xy 136.884664 -283.198316) (xy 136.884664 -283.242766)
			(xy 137.084816 -283.242766)
		)
		(stroke
			(width 0)
			(type solid)
		)
		(fill yes)
		(layer "In2.Cu")
		(net "M_I_CPU1_SB_DQ<13>")
	)
	(gr_poly
		(pts
			(xy 137.084816 -282.794456) (xy 137.084816 -282.750006) (xy 136.884664 -282.750006) (xy 136.884664 -282.794456)
			(xy 136.98474 -282.894532)
		)
		(stroke
			(width 0)
			(type solid)
		)
		(fill yes)
		(layer "In2.Cu")
		(net "M_I_CPU1_SB_DQ<14>")
	)
	(gr_poly
		(pts
			(xy 137.084816 -281.57805) (xy 136.98474 -281.478228) (xy 136.884664 -281.57805) (xy 136.884664 -281.625802)
			(xy 137.084816 -281.625802)
		)
		(stroke
			(width 0)
			(type solid)
		)
		(fill yes)
		(layer "In2.Cu")
		(net "M_I_CPU1_SB_DQS_DN<6>")
	)
	(gr_poly
		(pts
			(xy 137.084816 -281.174698) (xy 137.084816 -281.126946) (xy 136.884664 -281.126946) (xy 136.884664 -281.174698)
			(xy 136.98474 -281.27452)
		)
		(stroke
			(width 0)
			(type solid)
		)
		(fill yes)
		(layer "In2.Cu")
		(net "M_I_CPU1_SB_DQS_DN<1>")
	)
	(gr_poly
		(pts
			(xy 137.084816 -279.958292) (xy 136.98474 -279.858216) (xy 136.884664 -279.958292) (xy 136.884664 -280.002742)
			(xy 137.084816 -280.002742)
		)
		(stroke
			(width 0)
			(type solid)
		)
		(fill yes)
		(layer "In2.Cu")
		(net "M_I_CPU1_SB_DQ<9>")
	)
	(gr_poly
		(pts
			(xy 137.084816 -279.554432) (xy 137.084816 -279.509982) (xy 136.884664 -279.509982) (xy 136.884664 -279.554432)
			(xy 136.98474 -279.654508)
		)
		(stroke
			(width 0)
			(type solid)
		)
		(fill yes)
		(layer "In2.Cu")
		(net "M_I_CPU1_SB_DQ<10>")
	)
	(gr_poly
		(pts
			(xy 137.084816 -278.33828) (xy 136.98474 -278.238204) (xy 136.884664 -278.33828) (xy 136.884664 -278.38273)
			(xy 137.084816 -278.38273)
		)
		(stroke
			(width 0)
			(type solid)
		)
		(fill yes)
		(layer "In2.Cu")
		(net "M_I_CPU1_SB_DQ<5>")
	)
	(gr_poly
		(pts
			(xy 137.084816 -277.93442) (xy 137.084816 -277.88997) (xy 136.884664 -277.88997) (xy 136.884664 -277.93442)
			(xy 136.98474 -278.034496)
		)
		(stroke
			(width 0)
			(type solid)
		)
		(fill yes)
		(layer "In2.Cu")
		(net "M_I_CPU1_SB_DQ<6>")
	)
	(gr_poly
		(pts
			(xy 137.084816 -276.718014) (xy 136.98474 -276.618192) (xy 136.884664 -276.718014) (xy 136.884664 -276.765766)
			(xy 137.084816 -276.765766)
		)
		(stroke
			(width 0)
			(type solid)
		)
		(fill yes)
		(layer "In2.Cu")
		(net "M_I_CPU1_SB_DQS_DN<5>")
	)
	(gr_poly
		(pts
			(xy 137.084816 -276.314662) (xy 137.084816 -276.26691) (xy 136.884664 -276.26691) (xy 136.884664 -276.314662)
			(xy 136.98474 -276.414484)
		)
		(stroke
			(width 0)
			(type solid)
		)
		(fill yes)
		(layer "In2.Cu")
		(net "M_I_CPU1_SB_DQS_DN<0>")
	)
	(gr_poly
		(pts
			(xy 137.084816 -275.098256) (xy 136.98474 -274.99818) (xy 136.884664 -275.098256) (xy 136.884664 -275.142706)
			(xy 137.084816 -275.142706)
		)
		(stroke
			(width 0)
			(type solid)
		)
		(fill yes)
		(layer "In2.Cu")
		(net "M_I_CPU1_SB_DQ<1>")
	)
	(gr_poly
		(pts
			(xy 137.084816 -274.694396) (xy 137.084816 -274.649946) (xy 136.884664 -274.649946) (xy 136.884664 -274.694396)
			(xy 136.98474 -274.794472)
		)
		(stroke
			(width 0)
			(type solid)
		)
		(fill yes)
		(layer "In2.Cu")
		(net "M_I_CPU1_SB_DQ<2>")
	)
	(gr_poly
		(pts
			(xy 137.084816 -273.478244) (xy 136.98474 -273.378168) (xy 136.884664 -273.478244) (xy 136.884664 -273.522694)
			(xy 137.084816 -273.522694)
		)
		(stroke
			(width 0)
			(type solid)
		)
		(fill yes)
		(layer "In2.Cu")
		(net "M_I_CPU1_SB_CB<1>")
	)
	(gr_poly
		(pts
			(xy 137.084816 -273.074384) (xy 137.084816 -273.029934) (xy 136.884664 -273.029934) (xy 136.884664 -273.074384)
			(xy 136.98474 -273.17446)
		)
		(stroke
			(width 0)
			(type solid)
		)
		(fill yes)
		(layer "In2.Cu")
		(net "M_I_CPU1_SB_CB<2>")
	)
	(gr_poly
		(pts
			(xy 137.084816 -271.857978) (xy 136.98474 -271.758156) (xy 136.884664 -271.857978) (xy 136.884664 -271.90573)
			(xy 137.084816 -271.90573)
		)
		(stroke
			(width 0)
			(type solid)
		)
		(fill yes)
		(layer "In2.Cu")
		(net "M_I_CPU1_SB_DQS_DN<4>")
	)
	(gr_poly
		(pts
			(xy 137.084816 -271.454626) (xy 137.084816 -271.406874) (xy 136.884664 -271.406874) (xy 136.884664 -271.454626)
			(xy 136.98474 -271.554448)
		)
		(stroke
			(width 0)
			(type solid)
		)
		(fill yes)
		(layer "In2.Cu")
		(net "M_I_CPU1_SB_DQS_DN<9>")
	)
	(gr_poly
		(pts
			(xy 137.084816 -270.23822) (xy 136.98474 -270.138144) (xy 136.884664 -270.23822) (xy 136.884664 -270.28267)
			(xy 137.084816 -270.28267)
		)
		(stroke
			(width 0)
			(type solid)
		)
		(fill yes)
		(layer "In2.Cu")
		(net "M_I_CPU1_SB_CB<5>")
	)
	(gr_poly
		(pts
			(xy 137.084816 -269.83436) (xy 137.084816 -269.78991) (xy 136.884664 -269.78991) (xy 136.884664 -269.83436)
			(xy 136.98474 -269.934436)
		)
		(stroke
			(width 0)
			(type solid)
		)
		(fill yes)
		(layer "In2.Cu")
		(net "M_I_CPU1_SB_CB<6>")
	)
	(gr_poly
		(pts
			(xy 137.084816 -266.998196) (xy 136.98474 -266.89812) (xy 136.884664 -266.998196) (xy 136.884664 -267.042646)
			(xy 137.084816 -267.042646)
		)
		(stroke
			(width 0)
			(type solid)
		)
		(fill yes)
		(layer "In2.Cu")
		(net "M_I_CPU1_SA_RSP<0>")
	)
	(gr_poly
		(pts
			(xy 137.084816 -266.594336) (xy 137.084816 -266.549886) (xy 136.884664 -266.549886) (xy 136.884664 -266.594336)
			(xy 136.98474 -266.694412)
		)
		(stroke
			(width 0)
			(type solid)
		)
		(fill yes)
		(layer "In2.Cu")
		(net "M_I_CPU1_SB_CS_N<1>")
	)
	(gr_poly
		(pts
			(xy 137.084816 -265.378184) (xy 136.98474 -265.278108) (xy 136.884664 -265.378184) (xy 136.884664 -265.422634)
			(xy 137.084816 -265.422634)
		)
		(stroke
			(width 0)
			(type solid)
		)
		(fill yes)
		(layer "In2.Cu")
		(net "M_I_CPU1_SB_PAR")
	)
	(gr_poly
		(pts
			(xy 137.084816 -263.758172) (xy 136.98474 -263.658096) (xy 136.884664 -263.758172) (xy 136.884664 -263.802622)
			(xy 137.084816 -263.802622)
		)
		(stroke
			(width 0)
			(type solid)
		)
		(fill yes)
		(layer "In2.Cu")
		(net "M_I_CPU1_SB_CA<4>")
	)
	(gr_poly
		(pts
			(xy 137.084816 -263.354312) (xy 137.084816 -263.309862) (xy 136.884664 -263.309862) (xy 136.884664 -263.354312)
			(xy 136.98474 -263.454388)
		)
		(stroke
			(width 0)
			(type solid)
		)
		(fill yes)
		(layer "In2.Cu")
		(net "M_I_CPU1_SB_CA<3>")
	)
	(gr_poly
		(pts
			(xy 137.084816 -262.13816) (xy 136.98474 -262.038084) (xy 136.884664 -262.13816) (xy 136.884664 -262.18261)
			(xy 137.084816 -262.18261)
		)
		(stroke
			(width 0)
			(type solid)
		)
		(fill yes)
		(layer "In2.Cu")
		(net "M_I_CPU1_SB_CA<0>")
	)
	(gr_poly
		(pts
			(xy 137.254742 -256.432812) (xy 137.254742 -256.38506) (xy 137.05459 -256.38506) (xy 137.05459 -256.432812)
			(xy 137.154666 -256.532634)
		)
		(stroke
			(width 0)
			(type solid)
		)
		(fill yes)
		(layer "In2.Cu")
		(net "M_I_CPU1_CLK_DN<0>")
	)
	(gr_poly
		(pts
			(xy 137.254742 -255.216406) (xy 137.154666 -255.11633) (xy 137.05459 -255.216406) (xy 137.05459 -255.260856)
			(xy 137.254742 -255.260856)
		)
		(stroke
			(width 0)
			(type solid)
		)
		(fill yes)
		(layer "In2.Cu")
		(net "M_I_CPU1_SA_CA<6>")
	)
	(gr_poly
		(pts
			(xy 137.254742 -254.812546) (xy 137.254742 -254.768096) (xy 137.05459 -254.768096) (xy 137.05459 -254.812546)
			(xy 137.154666 -254.912622)
		)
		(stroke
			(width 0)
			(type solid)
		)
		(fill yes)
		(layer "In2.Cu")
		(net "M_I_CPU1_SA_CA<5>")
	)
	(gr_poly
		(pts
			(xy 137.254742 -253.596394) (xy 137.154666 -253.496318) (xy 137.05459 -253.596394) (xy 137.05459 -253.640844)
			(xy 137.254742 -253.640844)
		)
		(stroke
			(width 0)
			(type solid)
		)
		(fill yes)
		(layer "In2.Cu")
		(net "M_I_CPU1_SA_CA<2>")
	)
	(gr_poly
		(pts
			(xy 137.254742 -253.192534) (xy 137.254742 -253.148084) (xy 137.05459 -253.148084) (xy 137.05459 -253.192534)
			(xy 137.154666 -253.29261)
		)
		(stroke
			(width 0)
			(type solid)
		)
		(fill yes)
		(layer "In2.Cu")
		(net "M_I_CPU1_SA_CA<1>")
	)
	(gr_poly
		(pts
			(xy 137.254742 -251.976382) (xy 137.154666 -251.876306) (xy 137.05459 -251.976382) (xy 137.05459 -252.020832)
			(xy 137.254742 -252.020832)
		)
		(stroke
			(width 0)
			(type solid)
		)
		(fill yes)
		(layer "In2.Cu")
		(net "M_I_CPU1_SA_CS_N<1>")
	)
	(gr_poly
		(pts
			(xy 137.254742 -250.35637) (xy 137.154666 -250.256294) (xy 137.05459 -250.35637) (xy 137.05459 -250.40082)
			(xy 137.254742 -250.40082)
		)
		(stroke
			(width 0)
			(type solid)
		)
		(fill yes)
		(layer "In2.Cu")
		(net "M_I_CPU1_ALERT_R_N")
	)
	(gr_poly
		(pts
			(xy 137.254742 -248.736358) (xy 137.154666 -248.636282) (xy 137.05459 -248.736358) (xy 137.05459 -248.780808)
			(xy 137.254742 -248.780808)
		)
		(stroke
			(width 0)
			(type solid)
		)
		(fill yes)
		(layer "In2.Cu")
		(net "M_I_CPU1_SA_CB<5>")
	)
	(gr_poly
		(pts
			(xy 137.254742 -248.332498) (xy 137.254742 -248.288048) (xy 137.05459 -248.288048) (xy 137.05459 -248.332498)
			(xy 137.154666 -248.432574)
		)
		(stroke
			(width 0)
			(type solid)
		)
		(fill yes)
		(layer "In2.Cu")
		(net "M_I_CPU1_SA_CB<6>")
	)
	(gr_poly
		(pts
			(xy 137.254742 -247.116092) (xy 137.154666 -247.01627) (xy 137.05459 -247.116092) (xy 137.05459 -247.163844)
			(xy 137.254742 -247.163844)
		)
		(stroke
			(width 0)
			(type solid)
		)
		(fill yes)
		(layer "In2.Cu")
		(net "M_I_CPU1_SA_DQS_DN<9>")
	)
	(gr_poly
		(pts
			(xy 137.254742 -246.71274) (xy 137.254742 -246.664988) (xy 137.05459 -246.664988) (xy 137.05459 -246.71274)
			(xy 137.154666 -246.812562)
		)
		(stroke
			(width 0)
			(type solid)
		)
		(fill yes)
		(layer "In2.Cu")
		(net "M_I_CPU1_SA_DQS_DN<4>")
	)
	(gr_poly
		(pts
			(xy 137.254742 -245.496334) (xy 137.154666 -245.396258) (xy 137.05459 -245.496334) (xy 137.05459 -245.540784)
			(xy 137.254742 -245.540784)
		)
		(stroke
			(width 0)
			(type solid)
		)
		(fill yes)
		(layer "In2.Cu")
		(net "M_I_CPU1_SA_CB<1>")
	)
	(gr_poly
		(pts
			(xy 137.254742 -245.092474) (xy 137.254742 -245.048024) (xy 137.05459 -245.048024) (xy 137.05459 -245.092474)
			(xy 137.154666 -245.19255)
		)
		(stroke
			(width 0)
			(type solid)
		)
		(fill yes)
		(layer "In2.Cu")
		(net "M_I_CPU1_SA_CB<2>")
	)
	(gr_poly
		(pts
			(xy 137.254742 -243.876322) (xy 137.154666 -243.776246) (xy 137.05459 -243.876322) (xy 137.05459 -243.920772)
			(xy 137.254742 -243.920772)
		)
		(stroke
			(width 0)
			(type solid)
		)
		(fill yes)
		(layer "In2.Cu")
		(net "M_I_CPU1_SA_DQ<29>")
	)
	(gr_poly
		(pts
			(xy 137.254742 -243.472462) (xy 137.254742 -243.428012) (xy 137.05459 -243.428012) (xy 137.05459 -243.472462)
			(xy 137.154666 -243.572538)
		)
		(stroke
			(width 0)
			(type solid)
		)
		(fill yes)
		(layer "In2.Cu")
		(net "M_I_CPU1_SA_DQ<30>")
	)
	(gr_poly
		(pts
			(xy 137.254742 -242.256056) (xy 137.154666 -242.156234) (xy 137.05459 -242.256056) (xy 137.05459 -242.303808)
			(xy 137.254742 -242.303808)
		)
		(stroke
			(width 0)
			(type solid)
		)
		(fill yes)
		(layer "In2.Cu")
		(net "M_I_CPU1_SA_DQS_DN<8>")
	)
	(gr_poly
		(pts
			(xy 137.254742 -241.852704) (xy 137.254742 -241.804952) (xy 137.05459 -241.804952) (xy 137.05459 -241.852704)
			(xy 137.154666 -241.952526)
		)
		(stroke
			(width 0)
			(type solid)
		)
		(fill yes)
		(layer "In2.Cu")
		(net "M_I_CPU1_SA_DQS_DN<3>")
	)
	(gr_poly
		(pts
			(xy 137.254742 -240.636298) (xy 137.154666 -240.536222) (xy 137.05459 -240.636298) (xy 137.05459 -240.680748)
			(xy 137.254742 -240.680748)
		)
		(stroke
			(width 0)
			(type solid)
		)
		(fill yes)
		(layer "In2.Cu")
		(net "M_I_CPU1_SA_DQ<25>")
	)
	(gr_poly
		(pts
			(xy 137.254742 -240.232438) (xy 137.254742 -240.187988) (xy 137.05459 -240.187988) (xy 137.05459 -240.232438)
			(xy 137.154666 -240.332514)
		)
		(stroke
			(width 0)
			(type solid)
		)
		(fill yes)
		(layer "In2.Cu")
		(net "M_I_CPU1_SA_DQ<26>")
	)
	(gr_poly
		(pts
			(xy 137.254742 -239.016286) (xy 137.154666 -238.91621) (xy 137.05459 -239.016286) (xy 137.05459 -239.060736)
			(xy 137.254742 -239.060736)
		)
		(stroke
			(width 0)
			(type solid)
		)
		(fill yes)
		(layer "In2.Cu")
		(net "M_I_CPU1_SA_DQ<21>")
	)
	(gr_poly
		(pts
			(xy 137.254742 -238.612426) (xy 137.254742 -238.567976) (xy 137.05459 -238.567976) (xy 137.05459 -238.612426)
			(xy 137.154666 -238.712502)
		)
		(stroke
			(width 0)
			(type solid)
		)
		(fill yes)
		(layer "In2.Cu")
		(net "M_I_CPU1_SA_DQ<22>")
	)
	(gr_poly
		(pts
			(xy 137.254742 -237.39602) (xy 137.154666 -237.296198) (xy 137.05459 -237.39602) (xy 137.05459 -237.443772)
			(xy 137.254742 -237.443772)
		)
		(stroke
			(width 0)
			(type solid)
		)
		(fill yes)
		(layer "In2.Cu")
		(net "M_I_CPU1_SA_DQS_DN<7>")
	)
	(gr_poly
		(pts
			(xy 137.254742 -236.992668) (xy 137.254742 -236.944916) (xy 137.05459 -236.944916) (xy 137.05459 -236.992668)
			(xy 137.154666 -237.09249)
		)
		(stroke
			(width 0)
			(type solid)
		)
		(fill yes)
		(layer "In2.Cu")
		(net "M_I_CPU1_SA_DQS_DN<2>")
	)
	(gr_poly
		(pts
			(xy 137.254742 -235.776262) (xy 137.154666 -235.676186) (xy 137.05459 -235.776262) (xy 137.05459 -235.820712)
			(xy 137.254742 -235.820712)
		)
		(stroke
			(width 0)
			(type solid)
		)
		(fill yes)
		(layer "In2.Cu")
		(net "M_I_CPU1_SA_DQ<17>")
	)
	(gr_poly
		(pts
			(xy 137.254742 -235.372402) (xy 137.254742 -235.327952) (xy 137.05459 -235.327952) (xy 137.05459 -235.372402)
			(xy 137.154666 -235.472478)
		)
		(stroke
			(width 0)
			(type solid)
		)
		(fill yes)
		(layer "In2.Cu")
		(net "M_I_CPU1_SA_DQ<18>")
	)
	(gr_poly
		(pts
			(xy 137.254742 -234.15625) (xy 137.154666 -234.056174) (xy 137.05459 -234.15625) (xy 137.05459 -234.2007)
			(xy 137.254742 -234.2007)
		)
		(stroke
			(width 0)
			(type solid)
		)
		(fill yes)
		(layer "In2.Cu")
		(net "M_I_CPU1_SA_DQ<13>")
	)
	(gr_poly
		(pts
			(xy 137.254742 -233.75239) (xy 137.254742 -233.70794) (xy 137.05459 -233.70794) (xy 137.05459 -233.75239)
			(xy 137.154666 -233.852466)
		)
		(stroke
			(width 0)
			(type solid)
		)
		(fill yes)
		(layer "In2.Cu")
		(net "M_I_CPU1_SA_DQ<14>")
	)
	(gr_poly
		(pts
			(xy 137.254742 -232.535984) (xy 137.154666 -232.436162) (xy 137.05459 -232.535984) (xy 137.05459 -232.583736)
			(xy 137.254742 -232.583736)
		)
		(stroke
			(width 0)
			(type solid)
		)
		(fill yes)
		(layer "In2.Cu")
		(net "M_I_CPU1_SA_DQS_DN<6>")
	)
	(gr_poly
		(pts
			(xy 137.254742 -232.132632) (xy 137.254742 -232.08488) (xy 137.05459 -232.08488) (xy 137.05459 -232.132632)
			(xy 137.154666 -232.232454)
		)
		(stroke
			(width 0)
			(type solid)
		)
		(fill yes)
		(layer "In2.Cu")
		(net "M_I_CPU1_SA_DQS_DN<1>")
	)
	(gr_poly
		(pts
			(xy 137.254742 -230.916226) (xy 137.154666 -230.81615) (xy 137.05459 -230.916226) (xy 137.05459 -230.960676)
			(xy 137.254742 -230.960676)
		)
		(stroke
			(width 0)
			(type solid)
		)
		(fill yes)
		(layer "In2.Cu")
		(net "M_I_CPU1_SA_DQ<9>")
	)
	(gr_poly
		(pts
			(xy 137.254742 -230.51262) (xy 137.254742 -230.46817) (xy 137.05459 -230.46817) (xy 137.05459 -230.51262)
			(xy 137.154666 -230.612696)
		)
		(stroke
			(width 0)
			(type solid)
		)
		(fill yes)
		(layer "In2.Cu")
		(net "M_I_CPU1_SA_DQ<10>")
	)
	(gr_poly
		(pts
			(xy 137.254742 -229.296214) (xy 137.154666 -229.196138) (xy 137.05459 -229.296214) (xy 137.05459 -229.340664)
			(xy 137.254742 -229.340664)
		)
		(stroke
			(width 0)
			(type solid)
		)
		(fill yes)
		(layer "In2.Cu")
		(net "M_I_CPU1_SA_DQ<5>")
	)
	(gr_poly
		(pts
			(xy 137.254742 -228.892608) (xy 137.254742 -228.848158) (xy 137.05459 -228.848158) (xy 137.05459 -228.892608)
			(xy 137.154666 -228.992684)
		)
		(stroke
			(width 0)
			(type solid)
		)
		(fill yes)
		(layer "In2.Cu")
		(net "M_I_CPU1_SA_DQ<6>")
	)
	(gr_poly
		(pts
			(xy 137.254742 -227.676202) (xy 137.154666 -227.57638) (xy 137.05459 -227.676202) (xy 137.05459 -227.723954)
			(xy 137.254742 -227.723954)
		)
		(stroke
			(width 0)
			(type solid)
		)
		(fill yes)
		(layer "In2.Cu")
		(net "M_I_CPU1_SA_DQS_DN<5>")
	)
	(gr_poly
		(pts
			(xy 137.254742 -227.27285) (xy 137.254742 -227.225098) (xy 137.05459 -227.225098) (xy 137.05459 -227.27285)
			(xy 137.154666 -227.372672)
		)
		(stroke
			(width 0)
			(type solid)
		)
		(fill yes)
		(layer "In2.Cu")
		(net "M_I_CPU1_SA_DQS_DN<0>")
	)
	(gr_poly
		(pts
			(xy 137.254742 -226.056444) (xy 137.154666 -225.956368) (xy 137.05459 -226.056444) (xy 137.05459 -226.100894)
			(xy 137.254742 -226.100894)
		)
		(stroke
			(width 0)
			(type solid)
		)
		(fill yes)
		(layer "In2.Cu")
		(net "M_I_CPU1_SA_DQ<1>")
	)
	(gr_poly
		(pts
			(xy 137.254742 -225.652584) (xy 137.254742 -225.608134) (xy 137.05459 -225.608134) (xy 137.05459 -225.652584)
			(xy 137.154666 -225.75266)
		)
		(stroke
			(width 0)
			(type solid)
		)
		(fill yes)
		(layer "In2.Cu")
		(net "M_I_CPU1_SA_DQ<2>")
	)
	(gr_poly
		(pts
			(xy 137.554716 -293.32428) (xy 137.554716 -293.27983) (xy 137.354564 -293.27983) (xy 137.354564 -293.32428)
			(xy 137.45464 -293.424356)
		)
		(stroke
			(width 0)
			(type solid)
		)
		(fill yes)
		(layer "In2.Cu")
		(net "M_I_CPU1_SB_DQ<31>")
	)
	(gr_poly
		(pts
			(xy 137.554716 -292.108128) (xy 137.45464 -292.008052) (xy 137.354564 -292.108128) (xy 137.354564 -292.152578)
			(xy 137.554716 -292.152578)
		)
		(stroke
			(width 0)
			(type solid)
		)
		(fill yes)
		(layer "In2.Cu")
		(net "M_I_CPU1_SB_DQ<28>")
	)
	(gr_poly
		(pts
			(xy 137.554716 -291.704522) (xy 137.554716 -291.65677) (xy 137.354564 -291.65677) (xy 137.354564 -291.704522)
			(xy 137.45464 -291.804344)
		)
		(stroke
			(width 0)
			(type solid)
		)
		(fill yes)
		(layer "In2.Cu")
		(net "M_I_CPU1_SB_DQS_DP<8>")
	)
	(gr_poly
		(pts
			(xy 137.554716 -290.487862) (xy 137.45464 -290.38804) (xy 137.354564 -290.487862) (xy 137.354564 -290.535614)
			(xy 137.554716 -290.535614)
		)
		(stroke
			(width 0)
			(type solid)
		)
		(fill yes)
		(layer "In2.Cu")
		(net "M_I_CPU1_SB_DQS_DP<3>")
	)
	(gr_poly
		(pts
			(xy 137.554716 -290.084256) (xy 137.554716 -290.039806) (xy 137.354564 -290.039806) (xy 137.354564 -290.084256)
			(xy 137.45464 -290.184332)
		)
		(stroke
			(width 0)
			(type solid)
		)
		(fill yes)
		(layer "In2.Cu")
		(net "M_I_CPU1_SB_DQ<27>")
	)
	(gr_poly
		(pts
			(xy 137.554716 -288.868104) (xy 137.45464 -288.768028) (xy 137.354564 -288.868104) (xy 137.354564 -288.912554)
			(xy 137.554716 -288.912554)
		)
		(stroke
			(width 0)
			(type solid)
		)
		(fill yes)
		(layer "In2.Cu")
		(net "M_I_CPU1_SB_DQ<24>")
	)
	(gr_poly
		(pts
			(xy 137.554716 -288.464498) (xy 137.554716 -288.420048) (xy 137.354564 -288.420048) (xy 137.354564 -288.464498)
			(xy 137.45464 -288.564574)
		)
		(stroke
			(width 0)
			(type solid)
		)
		(fill yes)
		(layer "In2.Cu")
		(net "M_I_CPU1_SB_DQ<23>")
	)
	(gr_poly
		(pts
			(xy 137.554716 -287.248092) (xy 137.45464 -287.148016) (xy 137.354564 -287.248092) (xy 137.354564 -287.292542)
			(xy 137.554716 -287.292542)
		)
		(stroke
			(width 0)
			(type solid)
		)
		(fill yes)
		(layer "In2.Cu")
		(net "M_I_CPU1_SB_DQ<20>")
	)
	(gr_poly
		(pts
			(xy 137.554716 -286.844486) (xy 137.554716 -286.796734) (xy 137.354564 -286.796734) (xy 137.354564 -286.844486)
			(xy 137.45464 -286.944562)
		)
		(stroke
			(width 0)
			(type solid)
		)
		(fill yes)
		(layer "In2.Cu")
		(net "M_I_CPU1_SB_DQS_DP<7>")
	)
	(gr_poly
		(pts
			(xy 137.554716 -285.62808) (xy 137.45464 -285.528258) (xy 137.354564 -285.62808) (xy 137.354564 -285.675832)
			(xy 137.554716 -285.675832)
		)
		(stroke
			(width 0)
			(type solid)
		)
		(fill yes)
		(layer "In2.Cu")
		(net "M_I_CPU1_SB_DQS_DP<2>")
	)
	(gr_poly
		(pts
			(xy 137.554716 -285.224474) (xy 137.554716 -285.180024) (xy 137.354564 -285.180024) (xy 137.354564 -285.224474)
			(xy 137.45464 -285.32455)
		)
		(stroke
			(width 0)
			(type solid)
		)
		(fill yes)
		(layer "In2.Cu")
		(net "M_I_CPU1_SB_DQ<19>")
	)
	(gr_poly
		(pts
			(xy 137.554716 -284.008322) (xy 137.45464 -283.908246) (xy 137.354564 -284.008322) (xy 137.354564 -284.052772)
			(xy 137.554716 -284.052772)
		)
		(stroke
			(width 0)
			(type solid)
		)
		(fill yes)
		(layer "In2.Cu")
		(net "M_I_CPU1_SB_DQ<16>")
	)
	(gr_poly
		(pts
			(xy 137.554716 -283.604462) (xy 137.554716 -283.560012) (xy 137.354564 -283.560012) (xy 137.354564 -283.604462)
			(xy 137.45464 -283.704538)
		)
		(stroke
			(width 0)
			(type solid)
		)
		(fill yes)
		(layer "In2.Cu")
		(net "M_I_CPU1_SB_DQ<15>")
	)
	(gr_poly
		(pts
			(xy 137.554716 -282.38831) (xy 137.45464 -282.288234) (xy 137.354564 -282.38831) (xy 137.354564 -282.43276)
			(xy 137.554716 -282.43276)
		)
		(stroke
			(width 0)
			(type solid)
		)
		(fill yes)
		(layer "In2.Cu")
		(net "M_I_CPU1_SB_DQ<12>")
	)
	(gr_poly
		(pts
			(xy 137.554716 -281.984704) (xy 137.554716 -281.936952) (xy 137.354564 -281.936952) (xy 137.354564 -281.984704)
			(xy 137.45464 -282.084526)
		)
		(stroke
			(width 0)
			(type solid)
		)
		(fill yes)
		(layer "In2.Cu")
		(net "M_I_CPU1_SB_DQS_DP<6>")
	)
	(gr_poly
		(pts
			(xy 137.554716 -280.768044) (xy 137.45464 -280.668222) (xy 137.354564 -280.768044) (xy 137.354564 -280.815796)
			(xy 137.554716 -280.815796)
		)
		(stroke
			(width 0)
			(type solid)
		)
		(fill yes)
		(layer "In2.Cu")
		(net "M_I_CPU1_SB_DQS_DP<1>")
	)
	(gr_poly
		(pts
			(xy 137.554716 -280.364438) (xy 137.554716 -280.319988) (xy 137.354564 -280.319988) (xy 137.354564 -280.364438)
			(xy 137.45464 -280.464514)
		)
		(stroke
			(width 0)
			(type solid)
		)
		(fill yes)
		(layer "In2.Cu")
		(net "M_I_CPU1_SB_DQ<11>")
	)
	(gr_poly
		(pts
			(xy 137.554716 -279.148286) (xy 137.45464 -279.04821) (xy 137.354564 -279.148286) (xy 137.354564 -279.192736)
			(xy 137.554716 -279.192736)
		)
		(stroke
			(width 0)
			(type solid)
		)
		(fill yes)
		(layer "In2.Cu")
		(net "M_I_CPU1_SB_DQ<8>")
	)
	(gr_poly
		(pts
			(xy 137.554716 -278.744426) (xy 137.554716 -278.699976) (xy 137.354564 -278.699976) (xy 137.354564 -278.744426)
			(xy 137.45464 -278.844502)
		)
		(stroke
			(width 0)
			(type solid)
		)
		(fill yes)
		(layer "In2.Cu")
		(net "M_I_CPU1_SB_DQ<7>")
	)
	(gr_poly
		(pts
			(xy 137.554716 -277.528274) (xy 137.45464 -277.428198) (xy 137.354564 -277.528274) (xy 137.354564 -277.572724)
			(xy 137.554716 -277.572724)
		)
		(stroke
			(width 0)
			(type solid)
		)
		(fill yes)
		(layer "In2.Cu")
		(net "M_I_CPU1_SB_DQ<4>")
	)
	(gr_poly
		(pts
			(xy 137.554716 -277.124668) (xy 137.554716 -277.076916) (xy 137.354564 -277.076916) (xy 137.354564 -277.124668)
			(xy 137.45464 -277.22449)
		)
		(stroke
			(width 0)
			(type solid)
		)
		(fill yes)
		(layer "In2.Cu")
		(net "M_I_CPU1_SB_DQS_DP<5>")
	)
	(gr_poly
		(pts
			(xy 137.554716 -275.908008) (xy 137.45464 -275.808186) (xy 137.354564 -275.908008) (xy 137.354564 -275.95576)
			(xy 137.554716 -275.95576)
		)
		(stroke
			(width 0)
			(type solid)
		)
		(fill yes)
		(layer "In2.Cu")
		(net "M_I_CPU1_SB_DQS_DP<0>")
	)
	(gr_poly
		(pts
			(xy 137.554716 -275.504402) (xy 137.554716 -275.459952) (xy 137.354564 -275.459952) (xy 137.354564 -275.504402)
			(xy 137.45464 -275.604478)
		)
		(stroke
			(width 0)
			(type solid)
		)
		(fill yes)
		(layer "In2.Cu")
		(net "M_I_CPU1_SB_DQ<3>")
	)
	(gr_poly
		(pts
			(xy 137.554716 -274.28825) (xy 137.45464 -274.188174) (xy 137.354564 -274.28825) (xy 137.354564 -274.3327)
			(xy 137.554716 -274.3327)
		)
		(stroke
			(width 0)
			(type solid)
		)
		(fill yes)
		(layer "In2.Cu")
		(net "M_I_CPU1_SB_DQ<0>")
	)
	(gr_poly
		(pts
			(xy 137.554716 -273.88439) (xy 137.554716 -273.83994) (xy 137.354564 -273.83994) (xy 137.354564 -273.88439)
			(xy 137.45464 -273.984466)
		)
		(stroke
			(width 0)
			(type solid)
		)
		(fill yes)
		(layer "In2.Cu")
		(net "M_I_CPU1_SB_CB<3>")
	)
	(gr_poly
		(pts
			(xy 137.554716 -272.668238) (xy 137.45464 -272.568162) (xy 137.354564 -272.668238) (xy 137.354564 -272.712688)
			(xy 137.554716 -272.712688)
		)
		(stroke
			(width 0)
			(type solid)
		)
		(fill yes)
		(layer "In2.Cu")
		(net "M_I_CPU1_SB_CB<0>")
	)
	(gr_poly
		(pts
			(xy 137.554716 -272.264632) (xy 137.554716 -272.21688) (xy 137.354564 -272.21688) (xy 137.354564 -272.264632)
			(xy 137.45464 -272.364454)
		)
		(stroke
			(width 0)
			(type solid)
		)
		(fill yes)
		(layer "In2.Cu")
		(net "M_I_CPU1_SB_DQS_DP<4>")
	)
	(gr_poly
		(pts
			(xy 137.554716 -271.047972) (xy 137.45464 -270.94815) (xy 137.354564 -271.047972) (xy 137.354564 -271.095724)
			(xy 137.554716 -271.095724)
		)
		(stroke
			(width 0)
			(type solid)
		)
		(fill yes)
		(layer "In2.Cu")
		(net "M_I_CPU1_SB_DQS_DP<9>")
	)
	(gr_poly
		(pts
			(xy 137.554716 -270.644366) (xy 137.554716 -270.599916) (xy 137.354564 -270.599916) (xy 137.354564 -270.644366)
			(xy 137.45464 -270.744442)
		)
		(stroke
			(width 0)
			(type solid)
		)
		(fill yes)
		(layer "In2.Cu")
		(net "M_I_CPU1_SB_CB<7>")
	)
	(gr_poly
		(pts
			(xy 137.554716 -269.428214) (xy 137.45464 -269.328138) (xy 137.354564 -269.428214) (xy 137.354564 -269.472664)
			(xy 137.554716 -269.472664)
		)
		(stroke
			(width 0)
			(type solid)
		)
		(fill yes)
		(layer "In2.Cu")
		(net "M_I_CPU1_SB_CB<4>")
	)
	(gr_poly
		(pts
			(xy 137.554716 -267.404342) (xy 137.554716 -267.359892) (xy 137.354564 -267.359892) (xy 137.354564 -267.404342)
			(xy 137.45464 -267.504418)
		)
		(stroke
			(width 0)
			(type solid)
		)
		(fill yes)
		(layer "In2.Cu")
		(net "M_I_CPU1_SB_RSP<0>")
	)
	(gr_poly
		(pts
			(xy 137.554716 -265.78433) (xy 137.554716 -265.73988) (xy 137.354564 -265.73988) (xy 137.354564 -265.78433)
			(xy 137.45464 -265.884406)
		)
		(stroke
			(width 0)
			(type solid)
		)
		(fill yes)
		(layer "In2.Cu")
		(net "M_I_CPU1_SB_CS_N<0>")
	)
	(gr_poly
		(pts
			(xy 137.554716 -264.568178) (xy 137.45464 -264.468102) (xy 137.354564 -264.568178) (xy 137.354564 -264.612628)
			(xy 137.554716 -264.612628)
		)
		(stroke
			(width 0)
			(type solid)
		)
		(fill yes)
		(layer "In2.Cu")
		(net "M_I_CPU1_SB_CA<6>")
	)
	(gr_poly
		(pts
			(xy 137.554716 -264.164318) (xy 137.554716 -264.119868) (xy 137.354564 -264.119868) (xy 137.354564 -264.164318)
			(xy 137.45464 -264.264394)
		)
		(stroke
			(width 0)
			(type solid)
		)
		(fill yes)
		(layer "In2.Cu")
		(net "M_I_CPU1_SB_CA<5>")
	)
	(gr_poly
		(pts
			(xy 137.554716 -262.948166) (xy 137.45464 -262.84809) (xy 137.354564 -262.948166) (xy 137.354564 -262.992616)
			(xy 137.554716 -262.992616)
		)
		(stroke
			(width 0)
			(type solid)
		)
		(fill yes)
		(layer "In2.Cu")
		(net "M_I_CPU1_SB_CA<2>")
	)
	(gr_poly
		(pts
			(xy 137.554716 -262.544306) (xy 137.554716 -262.499856) (xy 137.354564 -262.499856) (xy 137.354564 -262.544306)
			(xy 137.45464 -262.644382)
		)
		(stroke
			(width 0)
			(type solid)
		)
		(fill yes)
		(layer "In2.Cu")
		(net "M_I_CPU1_SB_CA<1>")
	)
	(gr_poly
		(pts
			(xy 137.724896 -256.026158) (xy 137.62482 -255.926336) (xy 137.524744 -256.026158) (xy 137.524744 -256.07391)
			(xy 137.724896 -256.07391)
		)
		(stroke
			(width 0)
			(type solid)
		)
		(fill yes)
		(layer "In2.Cu")
		(net "M_I_CPU1_CLK_DP<0>")
	)
	(gr_poly
		(pts
			(xy 137.724896 -255.622552) (xy 137.724896 -255.578102) (xy 137.524744 -255.578102) (xy 137.524744 -255.622552)
			(xy 137.62482 -255.722628)
		)
		(stroke
			(width 0)
			(type solid)
		)
		(fill yes)
		(layer "In2.Cu")
		(net "M_I_CPU1_SA_PAR")
	)
	(gr_poly
		(pts
			(xy 137.724896 -254.4064) (xy 137.62482 -254.306324) (xy 137.524744 -254.4064) (xy 137.524744 -254.45085)
			(xy 137.724896 -254.45085)
		)
		(stroke
			(width 0)
			(type solid)
		)
		(fill yes)
		(layer "In2.Cu")
		(net "M_I_CPU1_SA_CA<4>")
	)
	(gr_poly
		(pts
			(xy 137.724896 -254.00254) (xy 137.724896 -253.95809) (xy 137.524744 -253.95809) (xy 137.524744 -254.00254)
			(xy 137.62482 -254.102616)
		)
		(stroke
			(width 0)
			(type solid)
		)
		(fill yes)
		(layer "In2.Cu")
		(net "M_I_CPU1_SA_CA<3>")
	)
	(gr_poly
		(pts
			(xy 137.724896 -252.786388) (xy 137.62482 -252.686312) (xy 137.524744 -252.786388) (xy 137.524744 -252.830838)
			(xy 137.724896 -252.830838)
		)
		(stroke
			(width 0)
			(type solid)
		)
		(fill yes)
		(layer "In2.Cu")
		(net "M_I_CPU1_SA_CA<0>")
	)
	(gr_poly
		(pts
			(xy 137.724896 -251.166376) (xy 137.62482 -251.0663) (xy 137.524744 -251.166376) (xy 137.524744 -251.210826)
			(xy 137.724896 -251.210826)
		)
		(stroke
			(width 0)
			(type solid)
		)
		(fill yes)
		(layer "In2.Cu")
		(net "M_I_CPU1_SA_CS_N<0>")
	)
	(gr_poly
		(pts
			(xy 137.724896 -250.762516) (xy 137.724896 -250.718066) (xy 137.524744 -250.718066) (xy 137.524744 -250.762516)
			(xy 137.62482 -250.862592)
		)
		(stroke
			(width 0)
			(type solid)
		)
		(fill yes)
		(layer "In2.Cu")
		(net "M_I_CPU1_RESET_N")
	)
	(gr_poly
		(pts
			(xy 137.724896 -249.142504) (xy 137.724896 -249.098054) (xy 137.524744 -249.098054) (xy 137.524744 -249.142504)
			(xy 137.62482 -249.24258)
		)
		(stroke
			(width 0)
			(type solid)
		)
		(fill yes)
		(layer "In2.Cu")
		(net "M_I_CPU1_SA_CB<7>")
	)
	(gr_poly
		(pts
			(xy 137.724896 -247.926352) (xy 137.62482 -247.826276) (xy 137.524744 -247.926352) (xy 137.524744 -247.970802)
			(xy 137.724896 -247.970802)
		)
		(stroke
			(width 0)
			(type solid)
		)
		(fill yes)
		(layer "In2.Cu")
		(net "M_I_CPU1_SA_CB<4>")
	)
	(gr_poly
		(pts
			(xy 137.724896 -247.522746) (xy 137.724896 -247.474994) (xy 137.524744 -247.474994) (xy 137.524744 -247.522746)
			(xy 137.62482 -247.622568)
		)
		(stroke
			(width 0)
			(type solid)
		)
		(fill yes)
		(layer "In2.Cu")
		(net "M_I_CPU1_SA_DQS_DP<9>")
	)
	(gr_poly
		(pts
			(xy 137.724896 -246.306086) (xy 137.62482 -246.206264) (xy 137.524744 -246.306086) (xy 137.524744 -246.353838)
			(xy 137.724896 -246.353838)
		)
		(stroke
			(width 0)
			(type solid)
		)
		(fill yes)
		(layer "In2.Cu")
		(net "M_I_CPU1_SA_DQS_DP<4>")
	)
	(gr_poly
		(pts
			(xy 137.724896 -245.90248) (xy 137.724896 -245.85803) (xy 137.524744 -245.85803) (xy 137.524744 -245.90248)
			(xy 137.62482 -246.002556)
		)
		(stroke
			(width 0)
			(type solid)
		)
		(fill yes)
		(layer "In2.Cu")
		(net "M_I_CPU1_SA_CB<3>")
	)
	(gr_poly
		(pts
			(xy 137.724896 -244.686328) (xy 137.62482 -244.586252) (xy 137.524744 -244.686328) (xy 137.524744 -244.730778)
			(xy 137.724896 -244.730778)
		)
		(stroke
			(width 0)
			(type solid)
		)
		(fill yes)
		(layer "In2.Cu")
		(net "M_I_CPU1_SA_CB<0>")
	)
	(gr_poly
		(pts
			(xy 137.724896 -244.282468) (xy 137.724896 -244.238018) (xy 137.524744 -244.238018) (xy 137.524744 -244.282468)
			(xy 137.62482 -244.382544)
		)
		(stroke
			(width 0)
			(type solid)
		)
		(fill yes)
		(layer "In2.Cu")
		(net "M_I_CPU1_SA_DQ<31>")
	)
	(gr_poly
		(pts
			(xy 137.724896 -243.066316) (xy 137.62482 -242.96624) (xy 137.524744 -243.066316) (xy 137.524744 -243.110766)
			(xy 137.724896 -243.110766)
		)
		(stroke
			(width 0)
			(type solid)
		)
		(fill yes)
		(layer "In2.Cu")
		(net "M_I_CPU1_SA_DQ<28>")
	)
	(gr_poly
		(pts
			(xy 137.724896 -242.66271) (xy 137.724896 -242.614958) (xy 137.524744 -242.614958) (xy 137.524744 -242.66271)
			(xy 137.62482 -242.762532)
		)
		(stroke
			(width 0)
			(type solid)
		)
		(fill yes)
		(layer "In2.Cu")
		(net "M_I_CPU1_SA_DQS_DP<8>")
	)
	(gr_poly
		(pts
			(xy 137.724896 -241.44605) (xy 137.62482 -241.346228) (xy 137.524744 -241.44605) (xy 137.524744 -241.493802)
			(xy 137.724896 -241.493802)
		)
		(stroke
			(width 0)
			(type solid)
		)
		(fill yes)
		(layer "In2.Cu")
		(net "M_I_CPU1_SA_DQS_DP<3>")
	)
	(gr_poly
		(pts
			(xy 137.724896 -241.042444) (xy 137.724896 -240.997994) (xy 137.524744 -240.997994) (xy 137.524744 -241.042444)
			(xy 137.62482 -241.14252)
		)
		(stroke
			(width 0)
			(type solid)
		)
		(fill yes)
		(layer "In2.Cu")
		(net "M_I_CPU1_SA_DQ<27>")
	)
	(gr_poly
		(pts
			(xy 137.724896 -239.826292) (xy 137.62482 -239.726216) (xy 137.524744 -239.826292) (xy 137.524744 -239.870742)
			(xy 137.724896 -239.870742)
		)
		(stroke
			(width 0)
			(type solid)
		)
		(fill yes)
		(layer "In2.Cu")
		(net "M_I_CPU1_SA_DQ<24>")
	)
	(gr_poly
		(pts
			(xy 137.724896 -239.422432) (xy 137.724896 -239.377982) (xy 137.524744 -239.377982) (xy 137.524744 -239.422432)
			(xy 137.62482 -239.522508)
		)
		(stroke
			(width 0)
			(type solid)
		)
		(fill yes)
		(layer "In2.Cu")
		(net "M_I_CPU1_SA_DQ<23>")
	)
	(gr_poly
		(pts
			(xy 137.724896 -238.20628) (xy 137.62482 -238.106204) (xy 137.524744 -238.20628) (xy 137.524744 -238.25073)
			(xy 137.724896 -238.25073)
		)
		(stroke
			(width 0)
			(type solid)
		)
		(fill yes)
		(layer "In2.Cu")
		(net "M_I_CPU1_SA_DQ<20>")
	)
	(gr_poly
		(pts
			(xy 137.724896 -237.802674) (xy 137.724896 -237.754922) (xy 137.524744 -237.754922) (xy 137.524744 -237.802674)
			(xy 137.62482 -237.902496)
		)
		(stroke
			(width 0)
			(type solid)
		)
		(fill yes)
		(layer "In2.Cu")
		(net "M_I_CPU1_SA_DQS_DP<7>")
	)
	(gr_poly
		(pts
			(xy 137.724896 -236.586014) (xy 137.62482 -236.486192) (xy 137.524744 -236.586014) (xy 137.524744 -236.633766)
			(xy 137.724896 -236.633766)
		)
		(stroke
			(width 0)
			(type solid)
		)
		(fill yes)
		(layer "In2.Cu")
		(net "M_I_CPU1_SA_DQS_DP<2>")
	)
	(gr_poly
		(pts
			(xy 137.724896 -236.182408) (xy 137.724896 -236.137958) (xy 137.524744 -236.137958) (xy 137.524744 -236.182408)
			(xy 137.62482 -236.282484)
		)
		(stroke
			(width 0)
			(type solid)
		)
		(fill yes)
		(layer "In2.Cu")
		(net "M_I_CPU1_SA_DQ<19>")
	)
	(gr_poly
		(pts
			(xy 137.724896 -234.966256) (xy 137.62482 -234.86618) (xy 137.524744 -234.966256) (xy 137.524744 -235.010706)
			(xy 137.724896 -235.010706)
		)
		(stroke
			(width 0)
			(type solid)
		)
		(fill yes)
		(layer "In2.Cu")
		(net "M_I_CPU1_SA_DQ<16>")
	)
	(gr_poly
		(pts
			(xy 137.724896 -234.562396) (xy 137.724896 -234.517946) (xy 137.524744 -234.517946) (xy 137.524744 -234.562396)
			(xy 137.62482 -234.662472)
		)
		(stroke
			(width 0)
			(type solid)
		)
		(fill yes)
		(layer "In2.Cu")
		(net "M_I_CPU1_SA_DQ<15>")
	)
	(gr_poly
		(pts
			(xy 137.724896 -233.346244) (xy 137.62482 -233.246168) (xy 137.524744 -233.346244) (xy 137.524744 -233.390694)
			(xy 137.724896 -233.390694)
		)
		(stroke
			(width 0)
			(type solid)
		)
		(fill yes)
		(layer "In2.Cu")
		(net "M_I_CPU1_SA_DQ<12>")
	)
	(gr_poly
		(pts
			(xy 137.724896 -232.942638) (xy 137.724896 -232.894886) (xy 137.524744 -232.894886) (xy 137.524744 -232.942638)
			(xy 137.62482 -233.04246)
		)
		(stroke
			(width 0)
			(type solid)
		)
		(fill yes)
		(layer "In2.Cu")
		(net "M_I_CPU1_SA_DQS_DP<6>")
	)
	(gr_poly
		(pts
			(xy 137.724896 -231.725978) (xy 137.62482 -231.626156) (xy 137.524744 -231.725978) (xy 137.524744 -231.77373)
			(xy 137.724896 -231.77373)
		)
		(stroke
			(width 0)
			(type solid)
		)
		(fill yes)
		(layer "In2.Cu")
		(net "M_I_CPU1_SA_DQS_DP<1>")
	)
	(gr_poly
		(pts
			(xy 137.724896 -231.322626) (xy 137.724896 -231.278176) (xy 137.524744 -231.278176) (xy 137.524744 -231.322626)
			(xy 137.62482 -231.422702)
		)
		(stroke
			(width 0)
			(type solid)
		)
		(fill yes)
		(layer "In2.Cu")
		(net "M_I_CPU1_SA_DQ<11>")
	)
	(gr_poly
		(pts
			(xy 137.724896 -230.10622) (xy 137.62482 -230.006144) (xy 137.524744 -230.10622) (xy 137.524744 -230.15067)
			(xy 137.724896 -230.15067)
		)
		(stroke
			(width 0)
			(type solid)
		)
		(fill yes)
		(layer "In2.Cu")
		(net "M_I_CPU1_SA_DQ<8>")
	)
	(gr_poly
		(pts
			(xy 137.724896 -229.702614) (xy 137.724896 -229.658164) (xy 137.524744 -229.658164) (xy 137.524744 -229.702614)
			(xy 137.62482 -229.80269)
		)
		(stroke
			(width 0)
			(type solid)
		)
		(fill yes)
		(layer "In2.Cu")
		(net "M_I_CPU1_SA_DQ<7>")
	)
	(gr_poly
		(pts
			(xy 137.724896 -228.486462) (xy 137.62482 -228.386386) (xy 137.524744 -228.486462) (xy 137.524744 -228.530912)
			(xy 137.724896 -228.530912)
		)
		(stroke
			(width 0)
			(type solid)
		)
		(fill yes)
		(layer "In2.Cu")
		(net "M_I_CPU1_SA_DQ<4>")
	)
	(gr_poly
		(pts
			(xy 137.724896 -228.082856) (xy 137.724896 -228.035104) (xy 137.524744 -228.035104) (xy 137.524744 -228.082856)
			(xy 137.62482 -228.182678)
		)
		(stroke
			(width 0)
			(type solid)
		)
		(fill yes)
		(layer "In2.Cu")
		(net "M_I_CPU1_SA_DQS_DP<5>")
	)
	(gr_poly
		(pts
			(xy 137.724896 -226.866196) (xy 137.62482 -226.766374) (xy 137.524744 -226.866196) (xy 137.524744 -226.913948)
			(xy 137.724896 -226.913948)
		)
		(stroke
			(width 0)
			(type solid)
		)
		(fill yes)
		(layer "In2.Cu")
		(net "M_I_CPU1_SA_DQS_DP<0>")
	)
	(gr_poly
		(pts
			(xy 137.724896 -226.46259) (xy 137.724896 -226.41814) (xy 137.524744 -226.41814) (xy 137.524744 -226.46259)
			(xy 137.62482 -226.562666)
		)
		(stroke
			(width 0)
			(type solid)
		)
		(fill yes)
		(layer "In2.Cu")
		(net "M_I_CPU1_SA_DQ<3>")
	)
	(gr_poly
		(pts
			(xy 137.724896 -225.246438) (xy 137.62482 -225.146362) (xy 137.524744 -225.246438) (xy 137.524744 -225.290888)
			(xy 137.724896 -225.290888)
		)
		(stroke
			(width 0)
			(type solid)
		)
		(fill yes)
		(layer "In2.Cu")
		(net "M_I_CPU1_SA_DQ<0>")
	)
	(gr_poly
		(pts
			(xy 138.02487 -292.918134) (xy 137.924794 -292.818058) (xy 137.824718 -292.918134) (xy 137.824718 -292.962584)
			(xy 138.02487 -292.962584)
		)
		(stroke
			(width 0)
			(type solid)
		)
		(fill yes)
		(layer "In2.Cu")
		(net "M_I_CPU1_SB_DQ<29>")
	)
	(gr_poly
		(pts
			(xy 138.02487 -292.514274) (xy 138.02487 -292.469824) (xy 137.824718 -292.469824) (xy 137.824718 -292.514274)
			(xy 137.924794 -292.61435)
		)
		(stroke
			(width 0)
			(type solid)
		)
		(fill yes)
		(layer "In2.Cu")
		(net "M_I_CPU1_SB_DQ<30>")
	)
	(gr_poly
		(pts
			(xy 138.02487 -291.297868) (xy 137.924794 -291.198046) (xy 137.824718 -291.297868) (xy 137.824718 -291.34562)
			(xy 138.02487 -291.34562)
		)
		(stroke
			(width 0)
			(type solid)
		)
		(fill yes)
		(layer "In2.Cu")
		(net "M_I_CPU1_SB_DQS_DN<8>")
	)
	(gr_poly
		(pts
			(xy 138.02487 -290.894516) (xy 138.02487 -290.846764) (xy 137.824718 -290.846764) (xy 137.824718 -290.894516)
			(xy 137.924794 -290.994338)
		)
		(stroke
			(width 0)
			(type solid)
		)
		(fill yes)
		(layer "In2.Cu")
		(net "M_I_CPU1_SB_DQS_DN<3>")
	)
	(gr_poly
		(pts
			(xy 138.02487 -289.67811) (xy 137.924794 -289.578034) (xy 137.824718 -289.67811) (xy 137.824718 -289.72256)
			(xy 138.02487 -289.72256)
		)
		(stroke
			(width 0)
			(type solid)
		)
		(fill yes)
		(layer "In2.Cu")
		(net "M_I_CPU1_SB_DQ<25>")
	)
	(gr_poly
		(pts
			(xy 138.02487 -289.27425) (xy 138.02487 -289.2298) (xy 137.824718 -289.2298) (xy 137.824718 -289.27425)
			(xy 137.924794 -289.374326)
		)
		(stroke
			(width 0)
			(type solid)
		)
		(fill yes)
		(layer "In2.Cu")
		(net "M_I_CPU1_SB_DQ<26>")
	)
	(gr_poly
		(pts
			(xy 138.02487 -288.058098) (xy 137.924794 -287.958022) (xy 137.824718 -288.058098) (xy 137.824718 -288.102548)
			(xy 138.02487 -288.102548)
		)
		(stroke
			(width 0)
			(type solid)
		)
		(fill yes)
		(layer "In2.Cu")
		(net "M_I_CPU1_SB_DQ<21>")
	)
	(gr_poly
		(pts
			(xy 138.02487 -287.654492) (xy 138.02487 -287.610042) (xy 137.824718 -287.610042) (xy 137.824718 -287.654492)
			(xy 137.924794 -287.754568)
		)
		(stroke
			(width 0)
			(type solid)
		)
		(fill yes)
		(layer "In2.Cu")
		(net "M_I_CPU1_SB_DQ<22>")
	)
	(gr_poly
		(pts
			(xy 138.02487 -286.438086) (xy 137.924794 -286.33801) (xy 137.824718 -286.438086) (xy 137.824718 -286.485838)
			(xy 138.02487 -286.485838)
		)
		(stroke
			(width 0)
			(type solid)
		)
		(fill yes)
		(layer "In2.Cu")
		(net "M_I_CPU1_SB_DQS_DN<7>")
	)
	(gr_poly
		(pts
			(xy 138.02487 -286.034734) (xy 138.02487 -285.986982) (xy 137.824718 -285.986982) (xy 137.824718 -286.034734)
			(xy 137.924794 -286.134556)
		)
		(stroke
			(width 0)
			(type solid)
		)
		(fill yes)
		(layer "In2.Cu")
		(net "M_I_CPU1_SB_DQS_DN<2>")
	)
	(gr_poly
		(pts
			(xy 138.02487 -284.818328) (xy 137.924794 -284.718252) (xy 137.824718 -284.818328) (xy 137.824718 -284.862778)
			(xy 138.02487 -284.862778)
		)
		(stroke
			(width 0)
			(type solid)
		)
		(fill yes)
		(layer "In2.Cu")
		(net "M_I_CPU1_SB_DQ<17>")
	)
	(gr_poly
		(pts
			(xy 138.02487 -284.414468) (xy 138.02487 -284.370018) (xy 137.824718 -284.370018) (xy 137.824718 -284.414468)
			(xy 137.924794 -284.514544)
		)
		(stroke
			(width 0)
			(type solid)
		)
		(fill yes)
		(layer "In2.Cu")
		(net "M_I_CPU1_SB_DQ<18>")
	)
	(gr_poly
		(pts
			(xy 138.02487 -283.198316) (xy 137.924794 -283.09824) (xy 137.824718 -283.198316) (xy 137.824718 -283.242766)
			(xy 138.02487 -283.242766)
		)
		(stroke
			(width 0)
			(type solid)
		)
		(fill yes)
		(layer "In2.Cu")
		(net "M_I_CPU1_SB_DQ<13>")
	)
	(gr_poly
		(pts
			(xy 138.02487 -282.794456) (xy 138.02487 -282.750006) (xy 137.824718 -282.750006) (xy 137.824718 -282.794456)
			(xy 137.924794 -282.894532)
		)
		(stroke
			(width 0)
			(type solid)
		)
		(fill yes)
		(layer "In2.Cu")
		(net "M_I_CPU1_SB_DQ<14>")
	)
	(gr_poly
		(pts
			(xy 138.02487 -281.57805) (xy 137.924794 -281.478228) (xy 137.824718 -281.57805) (xy 137.824718 -281.625802)
			(xy 138.02487 -281.625802)
		)
		(stroke
			(width 0)
			(type solid)
		)
		(fill yes)
		(layer "In2.Cu")
		(net "M_I_CPU1_SB_DQS_DN<6>")
	)
	(gr_poly
		(pts
			(xy 138.02487 -281.174698) (xy 138.02487 -281.126946) (xy 137.824718 -281.126946) (xy 137.824718 -281.174698)
			(xy 137.924794 -281.27452)
		)
		(stroke
			(width 0)
			(type solid)
		)
		(fill yes)
		(layer "In2.Cu")
		(net "M_I_CPU1_SB_DQS_DN<1>")
	)
	(gr_poly
		(pts
			(xy 138.02487 -279.958292) (xy 137.924794 -279.858216) (xy 137.824718 -279.958292) (xy 137.824718 -280.002742)
			(xy 138.02487 -280.002742)
		)
		(stroke
			(width 0)
			(type solid)
		)
		(fill yes)
		(layer "In2.Cu")
		(net "M_I_CPU1_SB_DQ<9>")
	)
	(gr_poly
		(pts
			(xy 138.02487 -279.554432) (xy 138.02487 -279.509982) (xy 137.824718 -279.509982) (xy 137.824718 -279.554432)
			(xy 137.924794 -279.654508)
		)
		(stroke
			(width 0)
			(type solid)
		)
		(fill yes)
		(layer "In2.Cu")
		(net "M_I_CPU1_SB_DQ<10>")
	)
	(gr_poly
		(pts
			(xy 138.02487 -278.33828) (xy 137.924794 -278.238204) (xy 137.824718 -278.33828) (xy 137.824718 -278.38273)
			(xy 138.02487 -278.38273)
		)
		(stroke
			(width 0)
			(type solid)
		)
		(fill yes)
		(layer "In2.Cu")
		(net "M_I_CPU1_SB_DQ<5>")
	)
	(gr_poly
		(pts
			(xy 138.02487 -277.93442) (xy 138.02487 -277.88997) (xy 137.824718 -277.88997) (xy 137.824718 -277.93442)
			(xy 137.924794 -278.034496)
		)
		(stroke
			(width 0)
			(type solid)
		)
		(fill yes)
		(layer "In2.Cu")
		(net "M_I_CPU1_SB_DQ<6>")
	)
	(gr_poly
		(pts
			(xy 138.02487 -276.718014) (xy 137.924794 -276.618192) (xy 137.824718 -276.718014) (xy 137.824718 -276.765766)
			(xy 138.02487 -276.765766)
		)
		(stroke
			(width 0)
			(type solid)
		)
		(fill yes)
		(layer "In2.Cu")
		(net "M_I_CPU1_SB_DQS_DN<5>")
	)
	(gr_poly
		(pts
			(xy 138.02487 -276.314662) (xy 138.02487 -276.26691) (xy 137.824718 -276.26691) (xy 137.824718 -276.314662)
			(xy 137.924794 -276.414484)
		)
		(stroke
			(width 0)
			(type solid)
		)
		(fill yes)
		(layer "In2.Cu")
		(net "M_I_CPU1_SB_DQS_DN<0>")
	)
	(gr_poly
		(pts
			(xy 138.02487 -275.098256) (xy 137.924794 -274.99818) (xy 137.824718 -275.098256) (xy 137.824718 -275.142706)
			(xy 138.02487 -275.142706)
		)
		(stroke
			(width 0)
			(type solid)
		)
		(fill yes)
		(layer "In2.Cu")
		(net "M_I_CPU1_SB_DQ<1>")
	)
	(gr_poly
		(pts
			(xy 138.02487 -274.694396) (xy 138.02487 -274.649946) (xy 137.824718 -274.649946) (xy 137.824718 -274.694396)
			(xy 137.924794 -274.794472)
		)
		(stroke
			(width 0)
			(type solid)
		)
		(fill yes)
		(layer "In2.Cu")
		(net "M_I_CPU1_SB_DQ<2>")
	)
	(gr_poly
		(pts
			(xy 138.02487 -273.478244) (xy 137.924794 -273.378168) (xy 137.824718 -273.478244) (xy 137.824718 -273.522694)
			(xy 138.02487 -273.522694)
		)
		(stroke
			(width 0)
			(type solid)
		)
		(fill yes)
		(layer "In2.Cu")
		(net "M_I_CPU1_SB_CB<1>")
	)
	(gr_poly
		(pts
			(xy 138.02487 -273.074384) (xy 138.02487 -273.029934) (xy 137.824718 -273.029934) (xy 137.824718 -273.074384)
			(xy 137.924794 -273.17446)
		)
		(stroke
			(width 0)
			(type solid)
		)
		(fill yes)
		(layer "In2.Cu")
		(net "M_I_CPU1_SB_CB<2>")
	)
	(gr_poly
		(pts
			(xy 138.02487 -271.857978) (xy 137.924794 -271.758156) (xy 137.824718 -271.857978) (xy 137.824718 -271.90573)
			(xy 138.02487 -271.90573)
		)
		(stroke
			(width 0)
			(type solid)
		)
		(fill yes)
		(layer "In2.Cu")
		(net "M_I_CPU1_SB_DQS_DN<4>")
	)
	(gr_poly
		(pts
			(xy 138.02487 -271.454626) (xy 138.02487 -271.406874) (xy 137.824718 -271.406874) (xy 137.824718 -271.454626)
			(xy 137.924794 -271.554448)
		)
		(stroke
			(width 0)
			(type solid)
		)
		(fill yes)
		(layer "In2.Cu")
		(net "M_I_CPU1_SB_DQS_DN<9>")
	)
	(gr_poly
		(pts
			(xy 138.02487 -270.23822) (xy 137.924794 -270.138144) (xy 137.824718 -270.23822) (xy 137.824718 -270.28267)
			(xy 138.02487 -270.28267)
		)
		(stroke
			(width 0)
			(type solid)
		)
		(fill yes)
		(layer "In2.Cu")
		(net "M_I_CPU1_SB_CB<5>")
	)
	(gr_poly
		(pts
			(xy 138.02487 -269.83436) (xy 138.02487 -269.78991) (xy 137.824718 -269.78991) (xy 137.824718 -269.83436)
			(xy 137.924794 -269.934436)
		)
		(stroke
			(width 0)
			(type solid)
		)
		(fill yes)
		(layer "In2.Cu")
		(net "M_I_CPU1_SB_CB<6>")
	)
	(gr_poly
		(pts
			(xy 138.02487 -266.998196) (xy 137.924794 -266.89812) (xy 137.824718 -266.998196) (xy 137.824718 -267.042646)
			(xy 138.02487 -267.042646)
		)
		(stroke
			(width 0)
			(type solid)
		)
		(fill yes)
		(layer "In2.Cu")
		(net "M_I_CPU1_SA_RSP<0>")
	)
	(gr_poly
		(pts
			(xy 138.02487 -266.594336) (xy 138.02487 -266.549886) (xy 137.824718 -266.549886) (xy 137.824718 -266.594336)
			(xy 137.924794 -266.694412)
		)
		(stroke
			(width 0)
			(type solid)
		)
		(fill yes)
		(layer "In2.Cu")
		(net "M_I_CPU1_SB_CS_N<1>")
	)
	(gr_poly
		(pts
			(xy 138.02487 -265.378184) (xy 137.924794 -265.278108) (xy 137.824718 -265.378184) (xy 137.824718 -265.422634)
			(xy 138.02487 -265.422634)
		)
		(stroke
			(width 0)
			(type solid)
		)
		(fill yes)
		(layer "In2.Cu")
		(net "M_I_CPU1_SB_PAR")
	)
	(gr_poly
		(pts
			(xy 138.02487 -263.758172) (xy 137.924794 -263.658096) (xy 137.824718 -263.758172) (xy 137.824718 -263.802622)
			(xy 138.02487 -263.802622)
		)
		(stroke
			(width 0)
			(type solid)
		)
		(fill yes)
		(layer "In2.Cu")
		(net "M_I_CPU1_SB_CA<4>")
	)
	(gr_poly
		(pts
			(xy 138.02487 -263.354312) (xy 138.02487 -263.309862) (xy 137.824718 -263.309862) (xy 137.824718 -263.354312)
			(xy 137.924794 -263.454388)
		)
		(stroke
			(width 0)
			(type solid)
		)
		(fill yes)
		(layer "In2.Cu")
		(net "M_I_CPU1_SB_CA<3>")
	)
	(gr_poly
		(pts
			(xy 138.02487 -262.13816) (xy 137.924794 -262.038084) (xy 137.824718 -262.13816) (xy 137.824718 -262.18261)
			(xy 138.02487 -262.18261)
		)
		(stroke
			(width 0)
			(type solid)
		)
		(fill yes)
		(layer "In2.Cu")
		(net "M_I_CPU1_SB_CA<0>")
	)
	(gr_poly
		(pts
			(xy 138.194796 -256.432812) (xy 138.194796 -256.38506) (xy 137.994644 -256.38506) (xy 137.994644 -256.432812)
			(xy 138.09472 -256.532634)
		)
		(stroke
			(width 0)
			(type solid)
		)
		(fill yes)
		(layer "In2.Cu")
		(net "M_I_CPU1_CLK_DN<0>")
	)
	(gr_poly
		(pts
			(xy 138.194796 -255.216406) (xy 138.09472 -255.11633) (xy 137.994644 -255.216406) (xy 137.994644 -255.260856)
			(xy 138.194796 -255.260856)
		)
		(stroke
			(width 0)
			(type solid)
		)
		(fill yes)
		(layer "In2.Cu")
		(net "M_I_CPU1_SA_CA<6>")
	)
	(gr_poly
		(pts
			(xy 138.194796 -254.812546) (xy 138.194796 -254.768096) (xy 137.994644 -254.768096) (xy 137.994644 -254.812546)
			(xy 138.09472 -254.912622)
		)
		(stroke
			(width 0)
			(type solid)
		)
		(fill yes)
		(layer "In2.Cu")
		(net "M_I_CPU1_SA_CA<5>")
	)
	(gr_poly
		(pts
			(xy 138.194796 -253.596394) (xy 138.09472 -253.496318) (xy 137.994644 -253.596394) (xy 137.994644 -253.640844)
			(xy 138.194796 -253.640844)
		)
		(stroke
			(width 0)
			(type solid)
		)
		(fill yes)
		(layer "In2.Cu")
		(net "M_I_CPU1_SA_CA<2>")
	)
	(gr_poly
		(pts
			(xy 138.194796 -253.192534) (xy 138.194796 -253.148084) (xy 137.994644 -253.148084) (xy 137.994644 -253.192534)
			(xy 138.09472 -253.29261)
		)
		(stroke
			(width 0)
			(type solid)
		)
		(fill yes)
		(layer "In2.Cu")
		(net "M_I_CPU1_SA_CA<1>")
	)
	(gr_poly
		(pts
			(xy 138.194796 -251.976382) (xy 138.09472 -251.876306) (xy 137.994644 -251.976382) (xy 137.994644 -252.020832)
			(xy 138.194796 -252.020832)
		)
		(stroke
			(width 0)
			(type solid)
		)
		(fill yes)
		(layer "In2.Cu")
		(net "M_I_CPU1_SA_CS_N<1>")
	)
	(gr_poly
		(pts
			(xy 138.194796 -250.35637) (xy 138.09472 -250.256294) (xy 137.994644 -250.35637) (xy 137.994644 -250.40082)
			(xy 138.194796 -250.40082)
		)
		(stroke
			(width 0)
			(type solid)
		)
		(fill yes)
		(layer "In2.Cu")
		(net "M_I_CPU1_ALERT_R_N")
	)
	(gr_poly
		(pts
			(xy 138.194796 -248.736358) (xy 138.09472 -248.636282) (xy 137.994644 -248.736358) (xy 137.994644 -248.780808)
			(xy 138.194796 -248.780808)
		)
		(stroke
			(width 0)
			(type solid)
		)
		(fill yes)
		(layer "In2.Cu")
		(net "M_I_CPU1_SA_CB<5>")
	)
	(gr_poly
		(pts
			(xy 138.194796 -248.332498) (xy 138.194796 -248.288048) (xy 137.994644 -248.288048) (xy 137.994644 -248.332498)
			(xy 138.09472 -248.432574)
		)
		(stroke
			(width 0)
			(type solid)
		)
		(fill yes)
		(layer "In2.Cu")
		(net "M_I_CPU1_SA_CB<6>")
	)
	(gr_poly
		(pts
			(xy 138.194796 -247.116092) (xy 138.09472 -247.01627) (xy 137.994644 -247.116092) (xy 137.994644 -247.163844)
			(xy 138.194796 -247.163844)
		)
		(stroke
			(width 0)
			(type solid)
		)
		(fill yes)
		(layer "In2.Cu")
		(net "M_I_CPU1_SA_DQS_DN<9>")
	)
	(gr_poly
		(pts
			(xy 138.194796 -246.71274) (xy 138.194796 -246.664988) (xy 137.994644 -246.664988) (xy 137.994644 -246.71274)
			(xy 138.09472 -246.812562)
		)
		(stroke
			(width 0)
			(type solid)
		)
		(fill yes)
		(layer "In2.Cu")
		(net "M_I_CPU1_SA_DQS_DN<4>")
	)
	(gr_poly
		(pts
			(xy 138.194796 -245.496334) (xy 138.09472 -245.396258) (xy 137.994644 -245.496334) (xy 137.994644 -245.540784)
			(xy 138.194796 -245.540784)
		)
		(stroke
			(width 0)
			(type solid)
		)
		(fill yes)
		(layer "In2.Cu")
		(net "M_I_CPU1_SA_CB<1>")
	)
	(gr_poly
		(pts
			(xy 138.194796 -245.092474) (xy 138.194796 -245.048024) (xy 137.994644 -245.048024) (xy 137.994644 -245.092474)
			(xy 138.09472 -245.19255)
		)
		(stroke
			(width 0)
			(type solid)
		)
		(fill yes)
		(layer "In2.Cu")
		(net "M_I_CPU1_SA_CB<2>")
	)
	(gr_poly
		(pts
			(xy 138.194796 -243.876322) (xy 138.09472 -243.776246) (xy 137.994644 -243.876322) (xy 137.994644 -243.920772)
			(xy 138.194796 -243.920772)
		)
		(stroke
			(width 0)
			(type solid)
		)
		(fill yes)
		(layer "In2.Cu")
		(net "M_I_CPU1_SA_DQ<29>")
	)
	(gr_poly
		(pts
			(xy 138.194796 -243.472462) (xy 138.194796 -243.428012) (xy 137.994644 -243.428012) (xy 137.994644 -243.472462)
			(xy 138.09472 -243.572538)
		)
		(stroke
			(width 0)
			(type solid)
		)
		(fill yes)
		(layer "In2.Cu")
		(net "M_I_CPU1_SA_DQ<30>")
	)
	(gr_poly
		(pts
			(xy 138.194796 -242.256056) (xy 138.09472 -242.156234) (xy 137.994644 -242.256056) (xy 137.994644 -242.303808)
			(xy 138.194796 -242.303808)
		)
		(stroke
			(width 0)
			(type solid)
		)
		(fill yes)
		(layer "In2.Cu")
		(net "M_I_CPU1_SA_DQS_DN<8>")
	)
	(gr_poly
		(pts
			(xy 138.194796 -241.852704) (xy 138.194796 -241.804952) (xy 137.994644 -241.804952) (xy 137.994644 -241.852704)
			(xy 138.09472 -241.952526)
		)
		(stroke
			(width 0)
			(type solid)
		)
		(fill yes)
		(layer "In2.Cu")
		(net "M_I_CPU1_SA_DQS_DN<3>")
	)
	(gr_poly
		(pts
			(xy 138.194796 -240.636298) (xy 138.09472 -240.536222) (xy 137.994644 -240.636298) (xy 137.994644 -240.680748)
			(xy 138.194796 -240.680748)
		)
		(stroke
			(width 0)
			(type solid)
		)
		(fill yes)
		(layer "In2.Cu")
		(net "M_I_CPU1_SA_DQ<25>")
	)
	(gr_poly
		(pts
			(xy 138.194796 -240.232438) (xy 138.194796 -240.187988) (xy 137.994644 -240.187988) (xy 137.994644 -240.232438)
			(xy 138.09472 -240.332514)
		)
		(stroke
			(width 0)
			(type solid)
		)
		(fill yes)
		(layer "In2.Cu")
		(net "M_I_CPU1_SA_DQ<26>")
	)
	(gr_poly
		(pts
			(xy 138.194796 -239.016286) (xy 138.09472 -238.91621) (xy 137.994644 -239.016286) (xy 137.994644 -239.060736)
			(xy 138.194796 -239.060736)
		)
		(stroke
			(width 0)
			(type solid)
		)
		(fill yes)
		(layer "In2.Cu")
		(net "M_I_CPU1_SA_DQ<21>")
	)
	(gr_poly
		(pts
			(xy 138.194796 -238.612426) (xy 138.194796 -238.567976) (xy 137.994644 -238.567976) (xy 137.994644 -238.612426)
			(xy 138.09472 -238.712502)
		)
		(stroke
			(width 0)
			(type solid)
		)
		(fill yes)
		(layer "In2.Cu")
		(net "M_I_CPU1_SA_DQ<22>")
	)
	(gr_poly
		(pts
			(xy 138.194796 -237.39602) (xy 138.09472 -237.296198) (xy 137.994644 -237.39602) (xy 137.994644 -237.443772)
			(xy 138.194796 -237.443772)
		)
		(stroke
			(width 0)
			(type solid)
		)
		(fill yes)
		(layer "In2.Cu")
		(net "M_I_CPU1_SA_DQS_DN<7>")
	)
	(gr_poly
		(pts
			(xy 138.194796 -236.992668) (xy 138.194796 -236.944916) (xy 137.994644 -236.944916) (xy 137.994644 -236.992668)
			(xy 138.09472 -237.09249)
		)
		(stroke
			(width 0)
			(type solid)
		)
		(fill yes)
		(layer "In2.Cu")
		(net "M_I_CPU1_SA_DQS_DN<2>")
	)
	(gr_poly
		(pts
			(xy 138.194796 -235.776262) (xy 138.09472 -235.676186) (xy 137.994644 -235.776262) (xy 137.994644 -235.820712)
			(xy 138.194796 -235.820712)
		)
		(stroke
			(width 0)
			(type solid)
		)
		(fill yes)
		(layer "In2.Cu")
		(net "M_I_CPU1_SA_DQ<17>")
	)
	(gr_poly
		(pts
			(xy 138.194796 -235.372402) (xy 138.194796 -235.327952) (xy 137.994644 -235.327952) (xy 137.994644 -235.372402)
			(xy 138.09472 -235.472478)
		)
		(stroke
			(width 0)
			(type solid)
		)
		(fill yes)
		(layer "In2.Cu")
		(net "M_I_CPU1_SA_DQ<18>")
	)
	(gr_poly
		(pts
			(xy 138.194796 -234.15625) (xy 138.09472 -234.056174) (xy 137.994644 -234.15625) (xy 137.994644 -234.2007)
			(xy 138.194796 -234.2007)
		)
		(stroke
			(width 0)
			(type solid)
		)
		(fill yes)
		(layer "In2.Cu")
		(net "M_I_CPU1_SA_DQ<13>")
	)
	(gr_poly
		(pts
			(xy 138.194796 -233.75239) (xy 138.194796 -233.70794) (xy 137.994644 -233.70794) (xy 137.994644 -233.75239)
			(xy 138.09472 -233.852466)
		)
		(stroke
			(width 0)
			(type solid)
		)
		(fill yes)
		(layer "In2.Cu")
		(net "M_I_CPU1_SA_DQ<14>")
	)
	(gr_poly
		(pts
			(xy 138.194796 -232.535984) (xy 138.09472 -232.436162) (xy 137.994644 -232.535984) (xy 137.994644 -232.583736)
			(xy 138.194796 -232.583736)
		)
		(stroke
			(width 0)
			(type solid)
		)
		(fill yes)
		(layer "In2.Cu")
		(net "M_I_CPU1_SA_DQS_DN<6>")
	)
	(gr_poly
		(pts
			(xy 138.194796 -232.132632) (xy 138.194796 -232.08488) (xy 137.994644 -232.08488) (xy 137.994644 -232.132632)
			(xy 138.09472 -232.232454)
		)
		(stroke
			(width 0)
			(type solid)
		)
		(fill yes)
		(layer "In2.Cu")
		(net "M_I_CPU1_SA_DQS_DN<1>")
	)
	(gr_poly
		(pts
			(xy 138.194796 -230.916226) (xy 138.09472 -230.81615) (xy 137.994644 -230.916226) (xy 137.994644 -230.960676)
			(xy 138.194796 -230.960676)
		)
		(stroke
			(width 0)
			(type solid)
		)
		(fill yes)
		(layer "In2.Cu")
		(net "M_I_CPU1_SA_DQ<9>")
	)
	(gr_poly
		(pts
			(xy 138.194796 -230.51262) (xy 138.194796 -230.46817) (xy 137.994644 -230.46817) (xy 137.994644 -230.51262)
			(xy 138.09472 -230.612696)
		)
		(stroke
			(width 0)
			(type solid)
		)
		(fill yes)
		(layer "In2.Cu")
		(net "M_I_CPU1_SA_DQ<10>")
	)
	(gr_poly
		(pts
			(xy 138.194796 -229.296214) (xy 138.09472 -229.196138) (xy 137.994644 -229.296214) (xy 137.994644 -229.340664)
			(xy 138.194796 -229.340664)
		)
		(stroke
			(width 0)
			(type solid)
		)
		(fill yes)
		(layer "In2.Cu")
		(net "M_I_CPU1_SA_DQ<5>")
	)
	(gr_poly
		(pts
			(xy 138.194796 -228.892608) (xy 138.194796 -228.848158) (xy 137.994644 -228.848158) (xy 137.994644 -228.892608)
			(xy 138.09472 -228.992684)
		)
		(stroke
			(width 0)
			(type solid)
		)
		(fill yes)
		(layer "In2.Cu")
		(net "M_I_CPU1_SA_DQ<6>")
	)
	(gr_poly
		(pts
			(xy 138.194796 -227.676202) (xy 138.09472 -227.57638) (xy 137.994644 -227.676202) (xy 137.994644 -227.723954)
			(xy 138.194796 -227.723954)
		)
		(stroke
			(width 0)
			(type solid)
		)
		(fill yes)
		(layer "In2.Cu")
		(net "M_I_CPU1_SA_DQS_DN<5>")
	)
	(gr_poly
		(pts
			(xy 138.194796 -227.27285) (xy 138.194796 -227.225098) (xy 137.994644 -227.225098) (xy 137.994644 -227.27285)
			(xy 138.09472 -227.372672)
		)
		(stroke
			(width 0)
			(type solid)
		)
		(fill yes)
		(layer "In2.Cu")
		(net "M_I_CPU1_SA_DQS_DN<0>")
	)
	(gr_poly
		(pts
			(xy 138.194796 -226.056444) (xy 138.09472 -225.956368) (xy 137.994644 -226.056444) (xy 137.994644 -226.100894)
			(xy 138.194796 -226.100894)
		)
		(stroke
			(width 0)
			(type solid)
		)
		(fill yes)
		(layer "In2.Cu")
		(net "M_I_CPU1_SA_DQ<1>")
	)
	(gr_poly
		(pts
			(xy 138.194796 -225.652584) (xy 138.194796 -225.608134) (xy 137.994644 -225.608134) (xy 137.994644 -225.652584)
			(xy 138.09472 -225.75266)
		)
		(stroke
			(width 0)
			(type solid)
		)
		(fill yes)
		(layer "In2.Cu")
		(net "M_I_CPU1_SA_DQ<2>")
	)
	(gr_poly
		(pts
			(xy 138.49477 -293.32428) (xy 138.49477 -293.27983) (xy 138.294618 -293.27983) (xy 138.294618 -293.32428)
			(xy 138.394694 -293.424356)
		)
		(stroke
			(width 0)
			(type solid)
		)
		(fill yes)
		(layer "In2.Cu")
		(net "M_I_CPU1_SB_DQ<31>")
	)
	(gr_poly
		(pts
			(xy 138.49477 -292.108128) (xy 138.394694 -292.008052) (xy 138.294618 -292.108128) (xy 138.294618 -292.152578)
			(xy 138.49477 -292.152578)
		)
		(stroke
			(width 0)
			(type solid)
		)
		(fill yes)
		(layer "In2.Cu")
		(net "M_I_CPU1_SB_DQ<28>")
	)
	(gr_poly
		(pts
			(xy 138.49477 -291.704522) (xy 138.49477 -291.65677) (xy 138.294618 -291.65677) (xy 138.294618 -291.704522)
			(xy 138.394694 -291.804344)
		)
		(stroke
			(width 0)
			(type solid)
		)
		(fill yes)
		(layer "In2.Cu")
		(net "M_I_CPU1_SB_DQS_DP<8>")
	)
	(gr_poly
		(pts
			(xy 138.49477 -290.487862) (xy 138.394694 -290.38804) (xy 138.294618 -290.487862) (xy 138.294618 -290.535614)
			(xy 138.49477 -290.535614)
		)
		(stroke
			(width 0)
			(type solid)
		)
		(fill yes)
		(layer "In2.Cu")
		(net "M_I_CPU1_SB_DQS_DP<3>")
	)
	(gr_poly
		(pts
			(xy 138.49477 -290.084256) (xy 138.49477 -290.039806) (xy 138.294618 -290.039806) (xy 138.294618 -290.084256)
			(xy 138.394694 -290.184332)
		)
		(stroke
			(width 0)
			(type solid)
		)
		(fill yes)
		(layer "In2.Cu")
		(net "M_I_CPU1_SB_DQ<27>")
	)
	(gr_poly
		(pts
			(xy 138.49477 -288.868104) (xy 138.394694 -288.768028) (xy 138.294618 -288.868104) (xy 138.294618 -288.912554)
			(xy 138.49477 -288.912554)
		)
		(stroke
			(width 0)
			(type solid)
		)
		(fill yes)
		(layer "In2.Cu")
		(net "M_I_CPU1_SB_DQ<24>")
	)
	(gr_poly
		(pts
			(xy 138.49477 -288.464498) (xy 138.49477 -288.420048) (xy 138.294618 -288.420048) (xy 138.294618 -288.464498)
			(xy 138.394694 -288.564574)
		)
		(stroke
			(width 0)
			(type solid)
		)
		(fill yes)
		(layer "In2.Cu")
		(net "M_I_CPU1_SB_DQ<23>")
	)
	(gr_poly
		(pts
			(xy 138.49477 -287.248092) (xy 138.394694 -287.148016) (xy 138.294618 -287.248092) (xy 138.294618 -287.292542)
			(xy 138.49477 -287.292542)
		)
		(stroke
			(width 0)
			(type solid)
		)
		(fill yes)
		(layer "In2.Cu")
		(net "M_I_CPU1_SB_DQ<20>")
	)
	(gr_poly
		(pts
			(xy 138.49477 -286.844486) (xy 138.49477 -286.796734) (xy 138.294618 -286.796734) (xy 138.294618 -286.844486)
			(xy 138.394694 -286.944562)
		)
		(stroke
			(width 0)
			(type solid)
		)
		(fill yes)
		(layer "In2.Cu")
		(net "M_I_CPU1_SB_DQS_DP<7>")
	)
	(gr_poly
		(pts
			(xy 138.49477 -285.62808) (xy 138.394694 -285.528258) (xy 138.294618 -285.62808) (xy 138.294618 -285.675832)
			(xy 138.49477 -285.675832)
		)
		(stroke
			(width 0)
			(type solid)
		)
		(fill yes)
		(layer "In2.Cu")
		(net "M_I_CPU1_SB_DQS_DP<2>")
	)
	(gr_poly
		(pts
			(xy 138.49477 -285.224474) (xy 138.49477 -285.180024) (xy 138.294618 -285.180024) (xy 138.294618 -285.224474)
			(xy 138.394694 -285.32455)
		)
		(stroke
			(width 0)
			(type solid)
		)
		(fill yes)
		(layer "In2.Cu")
		(net "M_I_CPU1_SB_DQ<19>")
	)
	(gr_poly
		(pts
			(xy 138.49477 -284.008322) (xy 138.394694 -283.908246) (xy 138.294618 -284.008322) (xy 138.294618 -284.052772)
			(xy 138.49477 -284.052772)
		)
		(stroke
			(width 0)
			(type solid)
		)
		(fill yes)
		(layer "In2.Cu")
		(net "M_I_CPU1_SB_DQ<16>")
	)
	(gr_poly
		(pts
			(xy 138.49477 -283.604462) (xy 138.49477 -283.560012) (xy 138.294618 -283.560012) (xy 138.294618 -283.604462)
			(xy 138.394694 -283.704538)
		)
		(stroke
			(width 0)
			(type solid)
		)
		(fill yes)
		(layer "In2.Cu")
		(net "M_I_CPU1_SB_DQ<15>")
	)
	(gr_poly
		(pts
			(xy 138.49477 -282.38831) (xy 138.394694 -282.288234) (xy 138.294618 -282.38831) (xy 138.294618 -282.43276)
			(xy 138.49477 -282.43276)
		)
		(stroke
			(width 0)
			(type solid)
		)
		(fill yes)
		(layer "In2.Cu")
		(net "M_I_CPU1_SB_DQ<12>")
	)
	(gr_poly
		(pts
			(xy 138.49477 -281.984704) (xy 138.49477 -281.936952) (xy 138.294618 -281.936952) (xy 138.294618 -281.984704)
			(xy 138.394694 -282.084526)
		)
		(stroke
			(width 0)
			(type solid)
		)
		(fill yes)
		(layer "In2.Cu")
		(net "M_I_CPU1_SB_DQS_DP<6>")
	)
	(gr_poly
		(pts
			(xy 138.49477 -280.768044) (xy 138.394694 -280.668222) (xy 138.294618 -280.768044) (xy 138.294618 -280.815796)
			(xy 138.49477 -280.815796)
		)
		(stroke
			(width 0)
			(type solid)
		)
		(fill yes)
		(layer "In2.Cu")
		(net "M_I_CPU1_SB_DQS_DP<1>")
	)
	(gr_poly
		(pts
			(xy 138.49477 -280.364438) (xy 138.49477 -280.319988) (xy 138.294618 -280.319988) (xy 138.294618 -280.364438)
			(xy 138.394694 -280.464514)
		)
		(stroke
			(width 0)
			(type solid)
		)
		(fill yes)
		(layer "In2.Cu")
		(net "M_I_CPU1_SB_DQ<11>")
	)
	(gr_poly
		(pts
			(xy 138.49477 -279.148286) (xy 138.394694 -279.04821) (xy 138.294618 -279.148286) (xy 138.294618 -279.192736)
			(xy 138.49477 -279.192736)
		)
		(stroke
			(width 0)
			(type solid)
		)
		(fill yes)
		(layer "In2.Cu")
		(net "M_I_CPU1_SB_DQ<8>")
	)
	(gr_poly
		(pts
			(xy 138.49477 -278.744426) (xy 138.49477 -278.699976) (xy 138.294618 -278.699976) (xy 138.294618 -278.744426)
			(xy 138.394694 -278.844502)
		)
		(stroke
			(width 0)
			(type solid)
		)
		(fill yes)
		(layer "In2.Cu")
		(net "M_I_CPU1_SB_DQ<7>")
	)
	(gr_poly
		(pts
			(xy 138.49477 -277.528274) (xy 138.394694 -277.428198) (xy 138.294618 -277.528274) (xy 138.294618 -277.572724)
			(xy 138.49477 -277.572724)
		)
		(stroke
			(width 0)
			(type solid)
		)
		(fill yes)
		(layer "In2.Cu")
		(net "M_I_CPU1_SB_DQ<4>")
	)
	(gr_poly
		(pts
			(xy 138.49477 -277.124668) (xy 138.49477 -277.076916) (xy 138.294618 -277.076916) (xy 138.294618 -277.124668)
			(xy 138.394694 -277.22449)
		)
		(stroke
			(width 0)
			(type solid)
		)
		(fill yes)
		(layer "In2.Cu")
		(net "M_I_CPU1_SB_DQS_DP<5>")
	)
	(gr_poly
		(pts
			(xy 138.49477 -275.908008) (xy 138.394694 -275.808186) (xy 138.294618 -275.908008) (xy 138.294618 -275.95576)
			(xy 138.49477 -275.95576)
		)
		(stroke
			(width 0)
			(type solid)
		)
		(fill yes)
		(layer "In2.Cu")
		(net "M_I_CPU1_SB_DQS_DP<0>")
	)
	(gr_poly
		(pts
			(xy 138.49477 -275.504402) (xy 138.49477 -275.459952) (xy 138.294618 -275.459952) (xy 138.294618 -275.504402)
			(xy 138.394694 -275.604478)
		)
		(stroke
			(width 0)
			(type solid)
		)
		(fill yes)
		(layer "In2.Cu")
		(net "M_I_CPU1_SB_DQ<3>")
	)
	(gr_poly
		(pts
			(xy 138.49477 -274.28825) (xy 138.394694 -274.188174) (xy 138.294618 -274.28825) (xy 138.294618 -274.3327)
			(xy 138.49477 -274.3327)
		)
		(stroke
			(width 0)
			(type solid)
		)
		(fill yes)
		(layer "In2.Cu")
		(net "M_I_CPU1_SB_DQ<0>")
	)
	(gr_poly
		(pts
			(xy 138.49477 -273.88439) (xy 138.49477 -273.83994) (xy 138.294618 -273.83994) (xy 138.294618 -273.88439)
			(xy 138.394694 -273.984466)
		)
		(stroke
			(width 0)
			(type solid)
		)
		(fill yes)
		(layer "In2.Cu")
		(net "M_I_CPU1_SB_CB<3>")
	)
	(gr_poly
		(pts
			(xy 138.49477 -272.668238) (xy 138.394694 -272.568162) (xy 138.294618 -272.668238) (xy 138.294618 -272.712688)
			(xy 138.49477 -272.712688)
		)
		(stroke
			(width 0)
			(type solid)
		)
		(fill yes)
		(layer "In2.Cu")
		(net "M_I_CPU1_SB_CB<0>")
	)
	(gr_poly
		(pts
			(xy 138.49477 -272.264632) (xy 138.49477 -272.21688) (xy 138.294618 -272.21688) (xy 138.294618 -272.264632)
			(xy 138.394694 -272.364454)
		)
		(stroke
			(width 0)
			(type solid)
		)
		(fill yes)
		(layer "In2.Cu")
		(net "M_I_CPU1_SB_DQS_DP<4>")
	)
	(gr_poly
		(pts
			(xy 138.49477 -271.047972) (xy 138.394694 -270.94815) (xy 138.294618 -271.047972) (xy 138.294618 -271.095724)
			(xy 138.49477 -271.095724)
		)
		(stroke
			(width 0)
			(type solid)
		)
		(fill yes)
		(layer "In2.Cu")
		(net "M_I_CPU1_SB_DQS_DP<9>")
	)
	(gr_poly
		(pts
			(xy 138.49477 -270.644366) (xy 138.49477 -270.599916) (xy 138.294618 -270.599916) (xy 138.294618 -270.644366)
			(xy 138.394694 -270.744442)
		)
		(stroke
			(width 0)
			(type solid)
		)
		(fill yes)
		(layer "In2.Cu")
		(net "M_I_CPU1_SB_CB<7>")
	)
	(gr_poly
		(pts
			(xy 138.49477 -269.428214) (xy 138.394694 -269.328138) (xy 138.294618 -269.428214) (xy 138.294618 -269.472664)
			(xy 138.49477 -269.472664)
		)
		(stroke
			(width 0)
			(type solid)
		)
		(fill yes)
		(layer "In2.Cu")
		(net "M_I_CPU1_SB_CB<4>")
	)
	(gr_poly
		(pts
			(xy 138.49477 -267.404342) (xy 138.49477 -267.359892) (xy 138.294618 -267.359892) (xy 138.294618 -267.404342)
			(xy 138.394694 -267.504418)
		)
		(stroke
			(width 0)
			(type solid)
		)
		(fill yes)
		(layer "In2.Cu")
		(net "M_I_CPU1_SB_RSP<0>")
	)
	(gr_poly
		(pts
			(xy 138.49477 -265.78433) (xy 138.49477 -265.73988) (xy 138.294618 -265.73988) (xy 138.294618 -265.78433)
			(xy 138.394694 -265.884406)
		)
		(stroke
			(width 0)
			(type solid)
		)
		(fill yes)
		(layer "In2.Cu")
		(net "M_I_CPU1_SB_CS_N<0>")
	)
	(gr_poly
		(pts
			(xy 138.49477 -264.568178) (xy 138.394694 -264.468102) (xy 138.294618 -264.568178) (xy 138.294618 -264.612628)
			(xy 138.49477 -264.612628)
		)
		(stroke
			(width 0)
			(type solid)
		)
		(fill yes)
		(layer "In2.Cu")
		(net "M_I_CPU1_SB_CA<6>")
	)
	(gr_poly
		(pts
			(xy 138.49477 -264.164318) (xy 138.49477 -264.119868) (xy 138.294618 -264.119868) (xy 138.294618 -264.164318)
			(xy 138.394694 -264.264394)
		)
		(stroke
			(width 0)
			(type solid)
		)
		(fill yes)
		(layer "In2.Cu")
		(net "M_I_CPU1_SB_CA<5>")
	)
	(gr_poly
		(pts
			(xy 138.49477 -262.948166) (xy 138.394694 -262.84809) (xy 138.294618 -262.948166) (xy 138.294618 -262.992616)
			(xy 138.49477 -262.992616)
		)
		(stroke
			(width 0)
			(type solid)
		)
		(fill yes)
		(layer "In2.Cu")
		(net "M_I_CPU1_SB_CA<2>")
	)
	(gr_poly
		(pts
			(xy 138.49477 -262.544306) (xy 138.49477 -262.499856) (xy 138.294618 -262.499856) (xy 138.294618 -262.544306)
			(xy 138.394694 -262.644382)
		)
		(stroke
			(width 0)
			(type solid)
		)
		(fill yes)
		(layer "In2.Cu")
		(net "M_I_CPU1_SB_CA<1>")
	)
	(gr_poly
		(pts
			(xy 138.66495 -256.026158) (xy 138.564874 -255.926336) (xy 138.464798 -256.026158) (xy 138.464798 -256.07391)
			(xy 138.66495 -256.07391)
		)
		(stroke
			(width 0)
			(type solid)
		)
		(fill yes)
		(layer "In2.Cu")
		(net "M_I_CPU1_CLK_DP<0>")
	)
	(gr_poly
		(pts
			(xy 138.66495 -255.622552) (xy 138.66495 -255.578102) (xy 138.464798 -255.578102) (xy 138.464798 -255.622552)
			(xy 138.564874 -255.722628)
		)
		(stroke
			(width 0)
			(type solid)
		)
		(fill yes)
		(layer "In2.Cu")
		(net "M_I_CPU1_SA_PAR")
	)
	(gr_poly
		(pts
			(xy 138.66495 -254.4064) (xy 138.564874 -254.306324) (xy 138.464798 -254.4064) (xy 138.464798 -254.45085)
			(xy 138.66495 -254.45085)
		)
		(stroke
			(width 0)
			(type solid)
		)
		(fill yes)
		(layer "In2.Cu")
		(net "M_I_CPU1_SA_CA<4>")
	)
	(gr_poly
		(pts
			(xy 138.66495 -254.00254) (xy 138.66495 -253.95809) (xy 138.464798 -253.95809) (xy 138.464798 -254.00254)
			(xy 138.564874 -254.102616)
		)
		(stroke
			(width 0)
			(type solid)
		)
		(fill yes)
		(layer "In2.Cu")
		(net "M_I_CPU1_SA_CA<3>")
	)
	(gr_poly
		(pts
			(xy 138.66495 -252.786388) (xy 138.564874 -252.686312) (xy 138.464798 -252.786388) (xy 138.464798 -252.830838)
			(xy 138.66495 -252.830838)
		)
		(stroke
			(width 0)
			(type solid)
		)
		(fill yes)
		(layer "In2.Cu")
		(net "M_I_CPU1_SA_CA<0>")
	)
	(gr_poly
		(pts
			(xy 138.66495 -251.166376) (xy 138.564874 -251.0663) (xy 138.464798 -251.166376) (xy 138.464798 -251.210826)
			(xy 138.66495 -251.210826)
		)
		(stroke
			(width 0)
			(type solid)
		)
		(fill yes)
		(layer "In2.Cu")
		(net "M_I_CPU1_SA_CS_N<0>")
	)
	(gr_poly
		(pts
			(xy 138.66495 -250.762516) (xy 138.66495 -250.718066) (xy 138.464798 -250.718066) (xy 138.464798 -250.762516)
			(xy 138.564874 -250.862592)
		)
		(stroke
			(width 0)
			(type solid)
		)
		(fill yes)
		(layer "In2.Cu")
		(net "M_I_CPU1_RESET_N")
	)
	(gr_poly
		(pts
			(xy 138.66495 -249.142504) (xy 138.66495 -249.098054) (xy 138.464798 -249.098054) (xy 138.464798 -249.142504)
			(xy 138.564874 -249.24258)
		)
		(stroke
			(width 0)
			(type solid)
		)
		(fill yes)
		(layer "In2.Cu")
		(net "M_I_CPU1_SA_CB<7>")
	)
	(gr_poly
		(pts
			(xy 138.66495 -247.926352) (xy 138.564874 -247.826276) (xy 138.464798 -247.926352) (xy 138.464798 -247.970802)
			(xy 138.66495 -247.970802)
		)
		(stroke
			(width 0)
			(type solid)
		)
		(fill yes)
		(layer "In2.Cu")
		(net "M_I_CPU1_SA_CB<4>")
	)
	(gr_poly
		(pts
			(xy 138.66495 -247.522746) (xy 138.66495 -247.474994) (xy 138.464798 -247.474994) (xy 138.464798 -247.522746)
			(xy 138.564874 -247.622568)
		)
		(stroke
			(width 0)
			(type solid)
		)
		(fill yes)
		(layer "In2.Cu")
		(net "M_I_CPU1_SA_DQS_DP<9>")
	)
	(gr_poly
		(pts
			(xy 138.66495 -246.306086) (xy 138.564874 -246.206264) (xy 138.464798 -246.306086) (xy 138.464798 -246.353838)
			(xy 138.66495 -246.353838)
		)
		(stroke
			(width 0)
			(type solid)
		)
		(fill yes)
		(layer "In2.Cu")
		(net "M_I_CPU1_SA_DQS_DP<4>")
	)
	(gr_poly
		(pts
			(xy 138.66495 -245.90248) (xy 138.66495 -245.85803) (xy 138.464798 -245.85803) (xy 138.464798 -245.90248)
			(xy 138.564874 -246.002556)
		)
		(stroke
			(width 0)
			(type solid)
		)
		(fill yes)
		(layer "In2.Cu")
		(net "M_I_CPU1_SA_CB<3>")
	)
	(gr_poly
		(pts
			(xy 138.66495 -244.686328) (xy 138.564874 -244.586252) (xy 138.464798 -244.686328) (xy 138.464798 -244.730778)
			(xy 138.66495 -244.730778)
		)
		(stroke
			(width 0)
			(type solid)
		)
		(fill yes)
		(layer "In2.Cu")
		(net "M_I_CPU1_SA_CB<0>")
	)
	(gr_poly
		(pts
			(xy 138.66495 -244.282468) (xy 138.66495 -244.238018) (xy 138.464798 -244.238018) (xy 138.464798 -244.282468)
			(xy 138.564874 -244.382544)
		)
		(stroke
			(width 0)
			(type solid)
		)
		(fill yes)
		(layer "In2.Cu")
		(net "M_I_CPU1_SA_DQ<31>")
	)
	(gr_poly
		(pts
			(xy 138.66495 -243.066316) (xy 138.564874 -242.96624) (xy 138.464798 -243.066316) (xy 138.464798 -243.110766)
			(xy 138.66495 -243.110766)
		)
		(stroke
			(width 0)
			(type solid)
		)
		(fill yes)
		(layer "In2.Cu")
		(net "M_I_CPU1_SA_DQ<28>")
	)
	(gr_poly
		(pts
			(xy 138.66495 -242.66271) (xy 138.66495 -242.614958) (xy 138.464798 -242.614958) (xy 138.464798 -242.66271)
			(xy 138.564874 -242.762532)
		)
		(stroke
			(width 0)
			(type solid)
		)
		(fill yes)
		(layer "In2.Cu")
		(net "M_I_CPU1_SA_DQS_DP<8>")
	)
	(gr_poly
		(pts
			(xy 138.66495 -241.44605) (xy 138.564874 -241.346228) (xy 138.464798 -241.44605) (xy 138.464798 -241.493802)
			(xy 138.66495 -241.493802)
		)
		(stroke
			(width 0)
			(type solid)
		)
		(fill yes)
		(layer "In2.Cu")
		(net "M_I_CPU1_SA_DQS_DP<3>")
	)
	(gr_poly
		(pts
			(xy 138.66495 -241.042444) (xy 138.66495 -240.997994) (xy 138.464798 -240.997994) (xy 138.464798 -241.042444)
			(xy 138.564874 -241.14252)
		)
		(stroke
			(width 0)
			(type solid)
		)
		(fill yes)
		(layer "In2.Cu")
		(net "M_I_CPU1_SA_DQ<27>")
	)
	(gr_poly
		(pts
			(xy 138.66495 -239.826292) (xy 138.564874 -239.726216) (xy 138.464798 -239.826292) (xy 138.464798 -239.870742)
			(xy 138.66495 -239.870742)
		)
		(stroke
			(width 0)
			(type solid)
		)
		(fill yes)
		(layer "In2.Cu")
		(net "M_I_CPU1_SA_DQ<24>")
	)
	(gr_poly
		(pts
			(xy 138.66495 -239.422432) (xy 138.66495 -239.377982) (xy 138.464798 -239.377982) (xy 138.464798 -239.422432)
			(xy 138.564874 -239.522508)
		)
		(stroke
			(width 0)
			(type solid)
		)
		(fill yes)
		(layer "In2.Cu")
		(net "M_I_CPU1_SA_DQ<23>")
	)
	(gr_poly
		(pts
			(xy 138.66495 -238.20628) (xy 138.564874 -238.106204) (xy 138.464798 -238.20628) (xy 138.464798 -238.25073)
			(xy 138.66495 -238.25073)
		)
		(stroke
			(width 0)
			(type solid)
		)
		(fill yes)
		(layer "In2.Cu")
		(net "M_I_CPU1_SA_DQ<20>")
	)
	(gr_poly
		(pts
			(xy 138.66495 -237.802674) (xy 138.66495 -237.754922) (xy 138.464798 -237.754922) (xy 138.464798 -237.802674)
			(xy 138.564874 -237.902496)
		)
		(stroke
			(width 0)
			(type solid)
		)
		(fill yes)
		(layer "In2.Cu")
		(net "M_I_CPU1_SA_DQS_DP<7>")
	)
	(gr_poly
		(pts
			(xy 138.66495 -236.586014) (xy 138.564874 -236.486192) (xy 138.464798 -236.586014) (xy 138.464798 -236.633766)
			(xy 138.66495 -236.633766)
		)
		(stroke
			(width 0)
			(type solid)
		)
		(fill yes)
		(layer "In2.Cu")
		(net "M_I_CPU1_SA_DQS_DP<2>")
	)
	(gr_poly
		(pts
			(xy 138.66495 -236.182408) (xy 138.66495 -236.137958) (xy 138.464798 -236.137958) (xy 138.464798 -236.182408)
			(xy 138.564874 -236.282484)
		)
		(stroke
			(width 0)
			(type solid)
		)
		(fill yes)
		(layer "In2.Cu")
		(net "M_I_CPU1_SA_DQ<19>")
	)
	(gr_poly
		(pts
			(xy 138.66495 -234.966256) (xy 138.564874 -234.86618) (xy 138.464798 -234.966256) (xy 138.464798 -235.010706)
			(xy 138.66495 -235.010706)
		)
		(stroke
			(width 0)
			(type solid)
		)
		(fill yes)
		(layer "In2.Cu")
		(net "M_I_CPU1_SA_DQ<16>")
	)
	(gr_poly
		(pts
			(xy 138.66495 -234.562396) (xy 138.66495 -234.517946) (xy 138.464798 -234.517946) (xy 138.464798 -234.562396)
			(xy 138.564874 -234.662472)
		)
		(stroke
			(width 0)
			(type solid)
		)
		(fill yes)
		(layer "In2.Cu")
		(net "M_I_CPU1_SA_DQ<15>")
	)
	(gr_poly
		(pts
			(xy 138.66495 -233.346244) (xy 138.564874 -233.246168) (xy 138.464798 -233.346244) (xy 138.464798 -233.390694)
			(xy 138.66495 -233.390694)
		)
		(stroke
			(width 0)
			(type solid)
		)
		(fill yes)
		(layer "In2.Cu")
		(net "M_I_CPU1_SA_DQ<12>")
	)
	(gr_poly
		(pts
			(xy 138.66495 -232.942638) (xy 138.66495 -232.894886) (xy 138.464798 -232.894886) (xy 138.464798 -232.942638)
			(xy 138.564874 -233.04246)
		)
		(stroke
			(width 0)
			(type solid)
		)
		(fill yes)
		(layer "In2.Cu")
		(net "M_I_CPU1_SA_DQS_DP<6>")
	)
	(gr_poly
		(pts
			(xy 138.66495 -231.725978) (xy 138.564874 -231.626156) (xy 138.464798 -231.725978) (xy 138.464798 -231.77373)
			(xy 138.66495 -231.77373)
		)
		(stroke
			(width 0)
			(type solid)
		)
		(fill yes)
		(layer "In2.Cu")
		(net "M_I_CPU1_SA_DQS_DP<1>")
	)
	(gr_poly
		(pts
			(xy 138.66495 -231.322626) (xy 138.66495 -231.278176) (xy 138.464798 -231.278176) (xy 138.464798 -231.322626)
			(xy 138.564874 -231.422702)
		)
		(stroke
			(width 0)
			(type solid)
		)
		(fill yes)
		(layer "In2.Cu")
		(net "M_I_CPU1_SA_DQ<11>")
	)
	(gr_poly
		(pts
			(xy 138.66495 -230.10622) (xy 138.564874 -230.006144) (xy 138.464798 -230.10622) (xy 138.464798 -230.15067)
			(xy 138.66495 -230.15067)
		)
		(stroke
			(width 0)
			(type solid)
		)
		(fill yes)
		(layer "In2.Cu")
		(net "M_I_CPU1_SA_DQ<8>")
	)
	(gr_poly
		(pts
			(xy 138.66495 -229.702614) (xy 138.66495 -229.658164) (xy 138.464798 -229.658164) (xy 138.464798 -229.702614)
			(xy 138.564874 -229.80269)
		)
		(stroke
			(width 0)
			(type solid)
		)
		(fill yes)
		(layer "In2.Cu")
		(net "M_I_CPU1_SA_DQ<7>")
	)
	(gr_poly
		(pts
			(xy 138.66495 -228.486462) (xy 138.564874 -228.386386) (xy 138.464798 -228.486462) (xy 138.464798 -228.530912)
			(xy 138.66495 -228.530912)
		)
		(stroke
			(width 0)
			(type solid)
		)
		(fill yes)
		(layer "In2.Cu")
		(net "M_I_CPU1_SA_DQ<4>")
	)
	(gr_poly
		(pts
			(xy 138.66495 -228.082856) (xy 138.66495 -228.035104) (xy 138.464798 -228.035104) (xy 138.464798 -228.082856)
			(xy 138.564874 -228.182678)
		)
		(stroke
			(width 0)
			(type solid)
		)
		(fill yes)
		(layer "In2.Cu")
		(net "M_I_CPU1_SA_DQS_DP<5>")
	)
	(gr_poly
		(pts
			(xy 138.66495 -226.866196) (xy 138.564874 -226.766374) (xy 138.464798 -226.866196) (xy 138.464798 -226.913948)
			(xy 138.66495 -226.913948)
		)
		(stroke
			(width 0)
			(type solid)
		)
		(fill yes)
		(layer "In2.Cu")
		(net "M_I_CPU1_SA_DQS_DP<0>")
	)
	(gr_poly
		(pts
			(xy 138.66495 -226.46259) (xy 138.66495 -226.41814) (xy 138.464798 -226.41814) (xy 138.464798 -226.46259)
			(xy 138.564874 -226.562666)
		)
		(stroke
			(width 0)
			(type solid)
		)
		(fill yes)
		(layer "In2.Cu")
		(net "M_I_CPU1_SA_DQ<3>")
	)
	(gr_poly
		(pts
			(xy 138.66495 -225.246438) (xy 138.564874 -225.146362) (xy 138.464798 -225.246438) (xy 138.464798 -225.290888)
			(xy 138.66495 -225.290888)
		)
		(stroke
			(width 0)
			(type solid)
		)
		(fill yes)
		(layer "In2.Cu")
		(net "M_I_CPU1_SA_DQ<0>")
	)
	(gr_poly
		(pts
			(xy 138.964924 -292.918134) (xy 138.864848 -292.818058) (xy 138.764772 -292.918134) (xy 138.764772 -292.962584)
			(xy 138.964924 -292.962584)
		)
		(stroke
			(width 0)
			(type solid)
		)
		(fill yes)
		(layer "In2.Cu")
		(net "M_I_CPU1_SB_DQ<29>")
	)
	(gr_poly
		(pts
			(xy 138.964924 -292.514274) (xy 138.964924 -292.469824) (xy 138.764772 -292.469824) (xy 138.764772 -292.514274)
			(xy 138.864848 -292.61435)
		)
		(stroke
			(width 0)
			(type solid)
		)
		(fill yes)
		(layer "In2.Cu")
		(net "M_I_CPU1_SB_DQ<30>")
	)
	(gr_poly
		(pts
			(xy 138.964924 -291.297868) (xy 138.864848 -291.198046) (xy 138.764772 -291.297868) (xy 138.764772 -291.34562)
			(xy 138.964924 -291.34562)
		)
		(stroke
			(width 0)
			(type solid)
		)
		(fill yes)
		(layer "In2.Cu")
		(net "M_I_CPU1_SB_DQS_DN<8>")
	)
	(gr_poly
		(pts
			(xy 138.964924 -290.894516) (xy 138.964924 -290.846764) (xy 138.764772 -290.846764) (xy 138.764772 -290.894516)
			(xy 138.864848 -290.994338)
		)
		(stroke
			(width 0)
			(type solid)
		)
		(fill yes)
		(layer "In2.Cu")
		(net "M_I_CPU1_SB_DQS_DN<3>")
	)
	(gr_poly
		(pts
			(xy 138.964924 -289.67811) (xy 138.864848 -289.578034) (xy 138.764772 -289.67811) (xy 138.764772 -289.72256)
			(xy 138.964924 -289.72256)
		)
		(stroke
			(width 0)
			(type solid)
		)
		(fill yes)
		(layer "In2.Cu")
		(net "M_I_CPU1_SB_DQ<25>")
	)
	(gr_poly
		(pts
			(xy 138.964924 -289.27425) (xy 138.964924 -289.2298) (xy 138.764772 -289.2298) (xy 138.764772 -289.27425)
			(xy 138.864848 -289.374326)
		)
		(stroke
			(width 0)
			(type solid)
		)
		(fill yes)
		(layer "In2.Cu")
		(net "M_I_CPU1_SB_DQ<26>")
	)
	(gr_poly
		(pts
			(xy 138.964924 -288.058098) (xy 138.864848 -287.958022) (xy 138.764772 -288.058098) (xy 138.764772 -288.102548)
			(xy 138.964924 -288.102548)
		)
		(stroke
			(width 0)
			(type solid)
		)
		(fill yes)
		(layer "In2.Cu")
		(net "M_I_CPU1_SB_DQ<21>")
	)
	(gr_poly
		(pts
			(xy 138.964924 -287.654492) (xy 138.964924 -287.610042) (xy 138.764772 -287.610042) (xy 138.764772 -287.654492)
			(xy 138.864848 -287.754568)
		)
		(stroke
			(width 0)
			(type solid)
		)
		(fill yes)
		(layer "In2.Cu")
		(net "M_I_CPU1_SB_DQ<22>")
	)
	(gr_poly
		(pts
			(xy 138.964924 -286.438086) (xy 138.864848 -286.33801) (xy 138.764772 -286.438086) (xy 138.764772 -286.485838)
			(xy 138.964924 -286.485838)
		)
		(stroke
			(width 0)
			(type solid)
		)
		(fill yes)
		(layer "In2.Cu")
		(net "M_I_CPU1_SB_DQS_DN<7>")
	)
	(gr_poly
		(pts
			(xy 138.964924 -286.034734) (xy 138.964924 -285.986982) (xy 138.764772 -285.986982) (xy 138.764772 -286.034734)
			(xy 138.864848 -286.134556)
		)
		(stroke
			(width 0)
			(type solid)
		)
		(fill yes)
		(layer "In2.Cu")
		(net "M_I_CPU1_SB_DQS_DN<2>")
	)
	(gr_poly
		(pts
			(xy 138.964924 -284.818328) (xy 138.864848 -284.718252) (xy 138.764772 -284.818328) (xy 138.764772 -284.862778)
			(xy 138.964924 -284.862778)
		)
		(stroke
			(width 0)
			(type solid)
		)
		(fill yes)
		(layer "In2.Cu")
		(net "M_I_CPU1_SB_DQ<17>")
	)
	(gr_poly
		(pts
			(xy 138.964924 -284.414468) (xy 138.964924 -284.370018) (xy 138.764772 -284.370018) (xy 138.764772 -284.414468)
			(xy 138.864848 -284.514544)
		)
		(stroke
			(width 0)
			(type solid)
		)
		(fill yes)
		(layer "In2.Cu")
		(net "M_I_CPU1_SB_DQ<18>")
	)
	(gr_poly
		(pts
			(xy 138.964924 -283.198316) (xy 138.864848 -283.09824) (xy 138.764772 -283.198316) (xy 138.764772 -283.242766)
			(xy 138.964924 -283.242766)
		)
		(stroke
			(width 0)
			(type solid)
		)
		(fill yes)
		(layer "In2.Cu")
		(net "M_I_CPU1_SB_DQ<13>")
	)
	(gr_poly
		(pts
			(xy 138.964924 -282.794456) (xy 138.964924 -282.750006) (xy 138.764772 -282.750006) (xy 138.764772 -282.794456)
			(xy 138.864848 -282.894532)
		)
		(stroke
			(width 0)
			(type solid)
		)
		(fill yes)
		(layer "In2.Cu")
		(net "M_I_CPU1_SB_DQ<14>")
	)
	(gr_poly
		(pts
			(xy 138.964924 -281.57805) (xy 138.864848 -281.478228) (xy 138.764772 -281.57805) (xy 138.764772 -281.625802)
			(xy 138.964924 -281.625802)
		)
		(stroke
			(width 0)
			(type solid)
		)
		(fill yes)
		(layer "In2.Cu")
		(net "M_I_CPU1_SB_DQS_DN<6>")
	)
	(gr_poly
		(pts
			(xy 138.964924 -281.174698) (xy 138.964924 -281.126946) (xy 138.764772 -281.126946) (xy 138.764772 -281.174698)
			(xy 138.864848 -281.27452)
		)
		(stroke
			(width 0)
			(type solid)
		)
		(fill yes)
		(layer "In2.Cu")
		(net "M_I_CPU1_SB_DQS_DN<1>")
	)
	(gr_poly
		(pts
			(xy 138.964924 -279.958292) (xy 138.864848 -279.858216) (xy 138.764772 -279.958292) (xy 138.764772 -280.002742)
			(xy 138.964924 -280.002742)
		)
		(stroke
			(width 0)
			(type solid)
		)
		(fill yes)
		(layer "In2.Cu")
		(net "M_I_CPU1_SB_DQ<9>")
	)
	(gr_poly
		(pts
			(xy 138.964924 -279.554432) (xy 138.964924 -279.509982) (xy 138.764772 -279.509982) (xy 138.764772 -279.554432)
			(xy 138.864848 -279.654508)
		)
		(stroke
			(width 0)
			(type solid)
		)
		(fill yes)
		(layer "In2.Cu")
		(net "M_I_CPU1_SB_DQ<10>")
	)
	(gr_poly
		(pts
			(xy 138.964924 -278.33828) (xy 138.864848 -278.238204) (xy 138.764772 -278.33828) (xy 138.764772 -278.38273)
			(xy 138.964924 -278.38273)
		)
		(stroke
			(width 0)
			(type solid)
		)
		(fill yes)
		(layer "In2.Cu")
		(net "M_I_CPU1_SB_DQ<5>")
	)
	(gr_poly
		(pts
			(xy 138.964924 -277.93442) (xy 138.964924 -277.88997) (xy 138.764772 -277.88997) (xy 138.764772 -277.93442)
			(xy 138.864848 -278.034496)
		)
		(stroke
			(width 0)
			(type solid)
		)
		(fill yes)
		(layer "In2.Cu")
		(net "M_I_CPU1_SB_DQ<6>")
	)
	(gr_poly
		(pts
			(xy 138.964924 -276.718014) (xy 138.864848 -276.618192) (xy 138.764772 -276.718014) (xy 138.764772 -276.765766)
			(xy 138.964924 -276.765766)
		)
		(stroke
			(width 0)
			(type solid)
		)
		(fill yes)
		(layer "In2.Cu")
		(net "M_I_CPU1_SB_DQS_DN<5>")
	)
	(gr_poly
		(pts
			(xy 138.964924 -276.314662) (xy 138.964924 -276.26691) (xy 138.764772 -276.26691) (xy 138.764772 -276.314662)
			(xy 138.864848 -276.414484)
		)
		(stroke
			(width 0)
			(type solid)
		)
		(fill yes)
		(layer "In2.Cu")
		(net "M_I_CPU1_SB_DQS_DN<0>")
	)
	(gr_poly
		(pts
			(xy 138.964924 -275.098256) (xy 138.864848 -274.99818) (xy 138.764772 -275.098256) (xy 138.764772 -275.142706)
			(xy 138.964924 -275.142706)
		)
		(stroke
			(width 0)
			(type solid)
		)
		(fill yes)
		(layer "In2.Cu")
		(net "M_I_CPU1_SB_DQ<1>")
	)
	(gr_poly
		(pts
			(xy 138.964924 -274.694396) (xy 138.964924 -274.649946) (xy 138.764772 -274.649946) (xy 138.764772 -274.694396)
			(xy 138.864848 -274.794472)
		)
		(stroke
			(width 0)
			(type solid)
		)
		(fill yes)
		(layer "In2.Cu")
		(net "M_I_CPU1_SB_DQ<2>")
	)
	(gr_poly
		(pts
			(xy 138.964924 -273.478244) (xy 138.864848 -273.378168) (xy 138.764772 -273.478244) (xy 138.764772 -273.522694)
			(xy 138.964924 -273.522694)
		)
		(stroke
			(width 0)
			(type solid)
		)
		(fill yes)
		(layer "In2.Cu")
		(net "M_I_CPU1_SB_CB<1>")
	)
	(gr_poly
		(pts
			(xy 138.964924 -273.074384) (xy 138.964924 -273.029934) (xy 138.764772 -273.029934) (xy 138.764772 -273.074384)
			(xy 138.864848 -273.17446)
		)
		(stroke
			(width 0)
			(type solid)
		)
		(fill yes)
		(layer "In2.Cu")
		(net "M_I_CPU1_SB_CB<2>")
	)
	(gr_poly
		(pts
			(xy 138.964924 -271.857978) (xy 138.864848 -271.758156) (xy 138.764772 -271.857978) (xy 138.764772 -271.90573)
			(xy 138.964924 -271.90573)
		)
		(stroke
			(width 0)
			(type solid)
		)
		(fill yes)
		(layer "In2.Cu")
		(net "M_I_CPU1_SB_DQS_DN<4>")
	)
	(gr_poly
		(pts
			(xy 138.964924 -271.454626) (xy 138.964924 -271.406874) (xy 138.764772 -271.406874) (xy 138.764772 -271.454626)
			(xy 138.864848 -271.554448)
		)
		(stroke
			(width 0)
			(type solid)
		)
		(fill yes)
		(layer "In2.Cu")
		(net "M_I_CPU1_SB_DQS_DN<9>")
	)
	(gr_poly
		(pts
			(xy 138.964924 -270.23822) (xy 138.864848 -270.138144) (xy 138.764772 -270.23822) (xy 138.764772 -270.28267)
			(xy 138.964924 -270.28267)
		)
		(stroke
			(width 0)
			(type solid)
		)
		(fill yes)
		(layer "In2.Cu")
		(net "M_I_CPU1_SB_CB<5>")
	)
	(gr_poly
		(pts
			(xy 138.964924 -269.83436) (xy 138.964924 -269.78991) (xy 138.764772 -269.78991) (xy 138.764772 -269.83436)
			(xy 138.864848 -269.934436)
		)
		(stroke
			(width 0)
			(type solid)
		)
		(fill yes)
		(layer "In2.Cu")
		(net "M_I_CPU1_SB_CB<6>")
	)
	(gr_poly
		(pts
			(xy 138.964924 -266.998196) (xy 138.864848 -266.89812) (xy 138.764772 -266.998196) (xy 138.764772 -267.042646)
			(xy 138.964924 -267.042646)
		)
		(stroke
			(width 0)
			(type solid)
		)
		(fill yes)
		(layer "In2.Cu")
		(net "M_I_CPU1_SA_RSP<0>")
	)
	(gr_poly
		(pts
			(xy 138.964924 -266.594336) (xy 138.964924 -266.549886) (xy 138.764772 -266.549886) (xy 138.764772 -266.594336)
			(xy 138.864848 -266.694412)
		)
		(stroke
			(width 0)
			(type solid)
		)
		(fill yes)
		(layer "In2.Cu")
		(net "M_I_CPU1_SB_CS_N<1>")
	)
	(gr_poly
		(pts
			(xy 138.964924 -265.378184) (xy 138.864848 -265.278108) (xy 138.764772 -265.378184) (xy 138.764772 -265.422634)
			(xy 138.964924 -265.422634)
		)
		(stroke
			(width 0)
			(type solid)
		)
		(fill yes)
		(layer "In2.Cu")
		(net "M_I_CPU1_SB_PAR")
	)
	(gr_poly
		(pts
			(xy 138.964924 -263.758172) (xy 138.864848 -263.658096) (xy 138.764772 -263.758172) (xy 138.764772 -263.802622)
			(xy 138.964924 -263.802622)
		)
		(stroke
			(width 0)
			(type solid)
		)
		(fill yes)
		(layer "In2.Cu")
		(net "M_I_CPU1_SB_CA<4>")
	)
	(gr_poly
		(pts
			(xy 138.964924 -263.354312) (xy 138.964924 -263.309862) (xy 138.764772 -263.309862) (xy 138.764772 -263.354312)
			(xy 138.864848 -263.454388)
		)
		(stroke
			(width 0)
			(type solid)
		)
		(fill yes)
		(layer "In2.Cu")
		(net "M_I_CPU1_SB_CA<3>")
	)
	(gr_poly
		(pts
			(xy 138.964924 -262.13816) (xy 138.864848 -262.038084) (xy 138.764772 -262.13816) (xy 138.764772 -262.18261)
			(xy 138.964924 -262.18261)
		)
		(stroke
			(width 0)
			(type solid)
		)
		(fill yes)
		(layer "In2.Cu")
		(net "M_I_CPU1_SB_CA<0>")
	)
	(gr_poly
		(pts
			(xy 139.13485 -256.432812) (xy 139.13485 -256.38506) (xy 138.934698 -256.38506) (xy 138.934698 -256.432812)
			(xy 139.034774 -256.532634)
		)
		(stroke
			(width 0)
			(type solid)
		)
		(fill yes)
		(layer "In2.Cu")
		(net "M_I_CPU1_CLK_DN<0>")
	)
	(gr_poly
		(pts
			(xy 139.13485 -255.216406) (xy 139.034774 -255.11633) (xy 138.934698 -255.216406) (xy 138.934698 -255.260856)
			(xy 139.13485 -255.260856)
		)
		(stroke
			(width 0)
			(type solid)
		)
		(fill yes)
		(layer "In2.Cu")
		(net "M_I_CPU1_SA_CA<6>")
	)
	(gr_poly
		(pts
			(xy 139.13485 -254.812546) (xy 139.13485 -254.768096) (xy 138.934698 -254.768096) (xy 138.934698 -254.812546)
			(xy 139.034774 -254.912622)
		)
		(stroke
			(width 0)
			(type solid)
		)
		(fill yes)
		(layer "In2.Cu")
		(net "M_I_CPU1_SA_CA<5>")
	)
	(gr_poly
		(pts
			(xy 139.13485 -253.596394) (xy 139.034774 -253.496318) (xy 138.934698 -253.596394) (xy 138.934698 -253.640844)
			(xy 139.13485 -253.640844)
		)
		(stroke
			(width 0)
			(type solid)
		)
		(fill yes)
		(layer "In2.Cu")
		(net "M_I_CPU1_SA_CA<2>")
	)
	(gr_poly
		(pts
			(xy 139.13485 -253.192534) (xy 139.13485 -253.148084) (xy 138.934698 -253.148084) (xy 138.934698 -253.192534)
			(xy 139.034774 -253.29261)
		)
		(stroke
			(width 0)
			(type solid)
		)
		(fill yes)
		(layer "In2.Cu")
		(net "M_I_CPU1_SA_CA<1>")
	)
	(gr_poly
		(pts
			(xy 139.13485 -251.976382) (xy 139.034774 -251.876306) (xy 138.934698 -251.976382) (xy 138.934698 -252.020832)
			(xy 139.13485 -252.020832)
		)
		(stroke
			(width 0)
			(type solid)
		)
		(fill yes)
		(layer "In2.Cu")
		(net "M_I_CPU1_SA_CS_N<1>")
	)
	(gr_poly
		(pts
			(xy 139.13485 -250.35637) (xy 139.034774 -250.256294) (xy 138.934698 -250.35637) (xy 138.934698 -250.40082)
			(xy 139.13485 -250.40082)
		)
		(stroke
			(width 0)
			(type solid)
		)
		(fill yes)
		(layer "In2.Cu")
		(net "M_I_CPU1_ALERT_R_N")
	)
	(gr_poly
		(pts
			(xy 139.13485 -248.736358) (xy 139.034774 -248.636282) (xy 138.934698 -248.736358) (xy 138.934698 -248.780808)
			(xy 139.13485 -248.780808)
		)
		(stroke
			(width 0)
			(type solid)
		)
		(fill yes)
		(layer "In2.Cu")
		(net "M_I_CPU1_SA_CB<5>")
	)
	(gr_poly
		(pts
			(xy 139.13485 -248.332498) (xy 139.13485 -248.288048) (xy 138.934698 -248.288048) (xy 138.934698 -248.332498)
			(xy 139.034774 -248.432574)
		)
		(stroke
			(width 0)
			(type solid)
		)
		(fill yes)
		(layer "In2.Cu")
		(net "M_I_CPU1_SA_CB<6>")
	)
	(gr_poly
		(pts
			(xy 139.13485 -247.116092) (xy 139.034774 -247.01627) (xy 138.934698 -247.116092) (xy 138.934698 -247.163844)
			(xy 139.13485 -247.163844)
		)
		(stroke
			(width 0)
			(type solid)
		)
		(fill yes)
		(layer "In2.Cu")
		(net "M_I_CPU1_SA_DQS_DN<9>")
	)
	(gr_poly
		(pts
			(xy 139.13485 -246.71274) (xy 139.13485 -246.664988) (xy 138.934698 -246.664988) (xy 138.934698 -246.71274)
			(xy 139.034774 -246.812562)
		)
		(stroke
			(width 0)
			(type solid)
		)
		(fill yes)
		(layer "In2.Cu")
		(net "M_I_CPU1_SA_DQS_DN<4>")
	)
	(gr_poly
		(pts
			(xy 139.13485 -245.496334) (xy 139.034774 -245.396258) (xy 138.934698 -245.496334) (xy 138.934698 -245.540784)
			(xy 139.13485 -245.540784)
		)
		(stroke
			(width 0)
			(type solid)
		)
		(fill yes)
		(layer "In2.Cu")
		(net "M_I_CPU1_SA_CB<1>")
	)
	(gr_poly
		(pts
			(xy 139.13485 -245.092474) (xy 139.13485 -245.048024) (xy 138.934698 -245.048024) (xy 138.934698 -245.092474)
			(xy 139.034774 -245.19255)
		)
		(stroke
			(width 0)
			(type solid)
		)
		(fill yes)
		(layer "In2.Cu")
		(net "M_I_CPU1_SA_CB<2>")
	)
	(gr_poly
		(pts
			(xy 139.13485 -243.876322) (xy 139.034774 -243.776246) (xy 138.934698 -243.876322) (xy 138.934698 -243.920772)
			(xy 139.13485 -243.920772)
		)
		(stroke
			(width 0)
			(type solid)
		)
		(fill yes)
		(layer "In2.Cu")
		(net "M_I_CPU1_SA_DQ<29>")
	)
	(gr_poly
		(pts
			(xy 139.13485 -243.472462) (xy 139.13485 -243.428012) (xy 138.934698 -243.428012) (xy 138.934698 -243.472462)
			(xy 139.034774 -243.572538)
		)
		(stroke
			(width 0)
			(type solid)
		)
		(fill yes)
		(layer "In2.Cu")
		(net "M_I_CPU1_SA_DQ<30>")
	)
	(gr_poly
		(pts
			(xy 139.13485 -242.256056) (xy 139.034774 -242.156234) (xy 138.934698 -242.256056) (xy 138.934698 -242.303808)
			(xy 139.13485 -242.303808)
		)
		(stroke
			(width 0)
			(type solid)
		)
		(fill yes)
		(layer "In2.Cu")
		(net "M_I_CPU1_SA_DQS_DN<8>")
	)
	(gr_poly
		(pts
			(xy 139.13485 -241.852704) (xy 139.13485 -241.804952) (xy 138.934698 -241.804952) (xy 138.934698 -241.852704)
			(xy 139.034774 -241.952526)
		)
		(stroke
			(width 0)
			(type solid)
		)
		(fill yes)
		(layer "In2.Cu")
		(net "M_I_CPU1_SA_DQS_DN<3>")
	)
	(gr_poly
		(pts
			(xy 139.13485 -240.636298) (xy 139.034774 -240.536222) (xy 138.934698 -240.636298) (xy 138.934698 -240.680748)
			(xy 139.13485 -240.680748)
		)
		(stroke
			(width 0)
			(type solid)
		)
		(fill yes)
		(layer "In2.Cu")
		(net "M_I_CPU1_SA_DQ<25>")
	)
	(gr_poly
		(pts
			(xy 139.13485 -240.232438) (xy 139.13485 -240.187988) (xy 138.934698 -240.187988) (xy 138.934698 -240.232438)
			(xy 139.034774 -240.332514)
		)
		(stroke
			(width 0)
			(type solid)
		)
		(fill yes)
		(layer "In2.Cu")
		(net "M_I_CPU1_SA_DQ<26>")
	)
	(gr_poly
		(pts
			(xy 139.13485 -239.016286) (xy 139.034774 -238.91621) (xy 138.934698 -239.016286) (xy 138.934698 -239.060736)
			(xy 139.13485 -239.060736)
		)
		(stroke
			(width 0)
			(type solid)
		)
		(fill yes)
		(layer "In2.Cu")
		(net "M_I_CPU1_SA_DQ<21>")
	)
	(gr_poly
		(pts
			(xy 139.13485 -238.612426) (xy 139.13485 -238.567976) (xy 138.934698 -238.567976) (xy 138.934698 -238.612426)
			(xy 139.034774 -238.712502)
		)
		(stroke
			(width 0)
			(type solid)
		)
		(fill yes)
		(layer "In2.Cu")
		(net "M_I_CPU1_SA_DQ<22>")
	)
	(gr_poly
		(pts
			(xy 139.13485 -237.39602) (xy 139.034774 -237.296198) (xy 138.934698 -237.39602) (xy 138.934698 -237.443772)
			(xy 139.13485 -237.443772)
		)
		(stroke
			(width 0)
			(type solid)
		)
		(fill yes)
		(layer "In2.Cu")
		(net "M_I_CPU1_SA_DQS_DN<7>")
	)
	(gr_poly
		(pts
			(xy 139.13485 -236.992668) (xy 139.13485 -236.944916) (xy 138.934698 -236.944916) (xy 138.934698 -236.992668)
			(xy 139.034774 -237.09249)
		)
		(stroke
			(width 0)
			(type solid)
		)
		(fill yes)
		(layer "In2.Cu")
		(net "M_I_CPU1_SA_DQS_DN<2>")
	)
	(gr_poly
		(pts
			(xy 139.13485 -235.776262) (xy 139.034774 -235.676186) (xy 138.934698 -235.776262) (xy 138.934698 -235.820712)
			(xy 139.13485 -235.820712)
		)
		(stroke
			(width 0)
			(type solid)
		)
		(fill yes)
		(layer "In2.Cu")
		(net "M_I_CPU1_SA_DQ<17>")
	)
	(gr_poly
		(pts
			(xy 139.13485 -235.372402) (xy 139.13485 -235.327952) (xy 138.934698 -235.327952) (xy 138.934698 -235.372402)
			(xy 139.034774 -235.472478)
		)
		(stroke
			(width 0)
			(type solid)
		)
		(fill yes)
		(layer "In2.Cu")
		(net "M_I_CPU1_SA_DQ<18>")
	)
	(gr_poly
		(pts
			(xy 139.13485 -234.15625) (xy 139.034774 -234.056174) (xy 138.934698 -234.15625) (xy 138.934698 -234.2007)
			(xy 139.13485 -234.2007)
		)
		(stroke
			(width 0)
			(type solid)
		)
		(fill yes)
		(layer "In2.Cu")
		(net "M_I_CPU1_SA_DQ<13>")
	)
	(gr_poly
		(pts
			(xy 139.13485 -233.75239) (xy 139.13485 -233.70794) (xy 138.934698 -233.70794) (xy 138.934698 -233.75239)
			(xy 139.034774 -233.852466)
		)
		(stroke
			(width 0)
			(type solid)
		)
		(fill yes)
		(layer "In2.Cu")
		(net "M_I_CPU1_SA_DQ<14>")
	)
	(gr_poly
		(pts
			(xy 139.13485 -232.535984) (xy 139.034774 -232.436162) (xy 138.934698 -232.535984) (xy 138.934698 -232.583736)
			(xy 139.13485 -232.583736)
		)
		(stroke
			(width 0)
			(type solid)
		)
		(fill yes)
		(layer "In2.Cu")
		(net "M_I_CPU1_SA_DQS_DN<6>")
	)
	(gr_poly
		(pts
			(xy 139.13485 -232.132632) (xy 139.13485 -232.08488) (xy 138.934698 -232.08488) (xy 138.934698 -232.132632)
			(xy 139.034774 -232.232454)
		)
		(stroke
			(width 0)
			(type solid)
		)
		(fill yes)
		(layer "In2.Cu")
		(net "M_I_CPU1_SA_DQS_DN<1>")
	)
	(gr_poly
		(pts
			(xy 139.13485 -230.916226) (xy 139.034774 -230.81615) (xy 138.934698 -230.916226) (xy 138.934698 -230.960676)
			(xy 139.13485 -230.960676)
		)
		(stroke
			(width 0)
			(type solid)
		)
		(fill yes)
		(layer "In2.Cu")
		(net "M_I_CPU1_SA_DQ<9>")
	)
	(gr_poly
		(pts
			(xy 139.13485 -230.51262) (xy 139.13485 -230.46817) (xy 138.934698 -230.46817) (xy 138.934698 -230.51262)
			(xy 139.034774 -230.612696)
		)
		(stroke
			(width 0)
			(type solid)
		)
		(fill yes)
		(layer "In2.Cu")
		(net "M_I_CPU1_SA_DQ<10>")
	)
	(gr_poly
		(pts
			(xy 139.13485 -229.296214) (xy 139.034774 -229.196138) (xy 138.934698 -229.296214) (xy 138.934698 -229.340664)
			(xy 139.13485 -229.340664)
		)
		(stroke
			(width 0)
			(type solid)
		)
		(fill yes)
		(layer "In2.Cu")
		(net "M_I_CPU1_SA_DQ<5>")
	)
	(gr_poly
		(pts
			(xy 139.13485 -228.892608) (xy 139.13485 -228.848158) (xy 138.934698 -228.848158) (xy 138.934698 -228.892608)
			(xy 139.034774 -228.992684)
		)
		(stroke
			(width 0)
			(type solid)
		)
		(fill yes)
		(layer "In2.Cu")
		(net "M_I_CPU1_SA_DQ<6>")
	)
	(gr_poly
		(pts
			(xy 139.13485 -227.676202) (xy 139.034774 -227.57638) (xy 138.934698 -227.676202) (xy 138.934698 -227.723954)
			(xy 139.13485 -227.723954)
		)
		(stroke
			(width 0)
			(type solid)
		)
		(fill yes)
		(layer "In2.Cu")
		(net "M_I_CPU1_SA_DQS_DN<5>")
	)
	(gr_poly
		(pts
			(xy 139.13485 -227.27285) (xy 139.13485 -227.225098) (xy 138.934698 -227.225098) (xy 138.934698 -227.27285)
			(xy 139.034774 -227.372672)
		)
		(stroke
			(width 0)
			(type solid)
		)
		(fill yes)
		(layer "In2.Cu")
		(net "M_I_CPU1_SA_DQS_DN<0>")
	)
	(gr_poly
		(pts
			(xy 139.13485 -226.056444) (xy 139.034774 -225.956368) (xy 138.934698 -226.056444) (xy 138.934698 -226.100894)
			(xy 139.13485 -226.100894)
		)
		(stroke
			(width 0)
			(type solid)
		)
		(fill yes)
		(layer "In2.Cu")
		(net "M_I_CPU1_SA_DQ<1>")
	)
	(gr_poly
		(pts
			(xy 139.13485 -225.652584) (xy 139.13485 -225.608134) (xy 138.934698 -225.608134) (xy 138.934698 -225.652584)
			(xy 139.034774 -225.75266)
		)
		(stroke
			(width 0)
			(type solid)
		)
		(fill yes)
		(layer "In2.Cu")
		(net "M_I_CPU1_SA_DQ<2>")
	)
	(gr_poly
		(pts
			(xy 139.434824 -293.32428) (xy 139.434824 -293.27983) (xy 139.234672 -293.27983) (xy 139.234672 -293.32428)
			(xy 139.334748 -293.424356)
		)
		(stroke
			(width 0)
			(type solid)
		)
		(fill yes)
		(layer "In2.Cu")
		(net "M_I_CPU1_SB_DQ<31>")
	)
	(gr_poly
		(pts
			(xy 139.434824 -292.108128) (xy 139.334748 -292.008052) (xy 139.234672 -292.108128) (xy 139.234672 -292.152578)
			(xy 139.434824 -292.152578)
		)
		(stroke
			(width 0)
			(type solid)
		)
		(fill yes)
		(layer "In2.Cu")
		(net "M_I_CPU1_SB_DQ<28>")
	)
	(gr_poly
		(pts
			(xy 139.434824 -291.704522) (xy 139.434824 -291.65677) (xy 139.234672 -291.65677) (xy 139.234672 -291.704522)
			(xy 139.334748 -291.804344)
		)
		(stroke
			(width 0)
			(type solid)
		)
		(fill yes)
		(layer "In2.Cu")
		(net "M_I_CPU1_SB_DQS_DP<8>")
	)
	(gr_poly
		(pts
			(xy 139.434824 -290.487862) (xy 139.334748 -290.38804) (xy 139.234672 -290.487862) (xy 139.234672 -290.535614)
			(xy 139.434824 -290.535614)
		)
		(stroke
			(width 0)
			(type solid)
		)
		(fill yes)
		(layer "In2.Cu")
		(net "M_I_CPU1_SB_DQS_DP<3>")
	)
	(gr_poly
		(pts
			(xy 139.434824 -290.084256) (xy 139.434824 -290.039806) (xy 139.234672 -290.039806) (xy 139.234672 -290.084256)
			(xy 139.334748 -290.184332)
		)
		(stroke
			(width 0)
			(type solid)
		)
		(fill yes)
		(layer "In2.Cu")
		(net "M_I_CPU1_SB_DQ<27>")
	)
	(gr_poly
		(pts
			(xy 139.434824 -288.868104) (xy 139.334748 -288.768028) (xy 139.234672 -288.868104) (xy 139.234672 -288.912554)
			(xy 139.434824 -288.912554)
		)
		(stroke
			(width 0)
			(type solid)
		)
		(fill yes)
		(layer "In2.Cu")
		(net "M_I_CPU1_SB_DQ<24>")
	)
	(gr_poly
		(pts
			(xy 139.434824 -288.464498) (xy 139.434824 -288.420048) (xy 139.234672 -288.420048) (xy 139.234672 -288.464498)
			(xy 139.334748 -288.564574)
		)
		(stroke
			(width 0)
			(type solid)
		)
		(fill yes)
		(layer "In2.Cu")
		(net "M_I_CPU1_SB_DQ<23>")
	)
	(gr_poly
		(pts
			(xy 139.434824 -287.248092) (xy 139.334748 -287.148016) (xy 139.234672 -287.248092) (xy 139.234672 -287.292542)
			(xy 139.434824 -287.292542)
		)
		(stroke
			(width 0)
			(type solid)
		)
		(fill yes)
		(layer "In2.Cu")
		(net "M_I_CPU1_SB_DQ<20>")
	)
	(gr_poly
		(pts
			(xy 139.434824 -286.844486) (xy 139.434824 -286.796734) (xy 139.234672 -286.796734) (xy 139.234672 -286.844486)
			(xy 139.334748 -286.944562)
		)
		(stroke
			(width 0)
			(type solid)
		)
		(fill yes)
		(layer "In2.Cu")
		(net "M_I_CPU1_SB_DQS_DP<7>")
	)
	(gr_poly
		(pts
			(xy 139.434824 -285.62808) (xy 139.334748 -285.528258) (xy 139.234672 -285.62808) (xy 139.234672 -285.675832)
			(xy 139.434824 -285.675832)
		)
		(stroke
			(width 0)
			(type solid)
		)
		(fill yes)
		(layer "In2.Cu")
		(net "M_I_CPU1_SB_DQS_DP<2>")
	)
	(gr_poly
		(pts
			(xy 139.434824 -285.224474) (xy 139.434824 -285.180024) (xy 139.234672 -285.180024) (xy 139.234672 -285.224474)
			(xy 139.334748 -285.32455)
		)
		(stroke
			(width 0)
			(type solid)
		)
		(fill yes)
		(layer "In2.Cu")
		(net "M_I_CPU1_SB_DQ<19>")
	)
	(gr_poly
		(pts
			(xy 139.434824 -284.008322) (xy 139.334748 -283.908246) (xy 139.234672 -284.008322) (xy 139.234672 -284.052772)
			(xy 139.434824 -284.052772)
		)
		(stroke
			(width 0)
			(type solid)
		)
		(fill yes)
		(layer "In2.Cu")
		(net "M_I_CPU1_SB_DQ<16>")
	)
	(gr_poly
		(pts
			(xy 139.434824 -283.604462) (xy 139.434824 -283.560012) (xy 139.234672 -283.560012) (xy 139.234672 -283.604462)
			(xy 139.334748 -283.704538)
		)
		(stroke
			(width 0)
			(type solid)
		)
		(fill yes)
		(layer "In2.Cu")
		(net "M_I_CPU1_SB_DQ<15>")
	)
	(gr_poly
		(pts
			(xy 139.434824 -282.38831) (xy 139.334748 -282.288234) (xy 139.234672 -282.38831) (xy 139.234672 -282.43276)
			(xy 139.434824 -282.43276)
		)
		(stroke
			(width 0)
			(type solid)
		)
		(fill yes)
		(layer "In2.Cu")
		(net "M_I_CPU1_SB_DQ<12>")
	)
	(gr_poly
		(pts
			(xy 139.434824 -281.984704) (xy 139.434824 -281.936952) (xy 139.234672 -281.936952) (xy 139.234672 -281.984704)
			(xy 139.334748 -282.084526)
		)
		(stroke
			(width 0)
			(type solid)
		)
		(fill yes)
		(layer "In2.Cu")
		(net "M_I_CPU1_SB_DQS_DP<6>")
	)
	(gr_poly
		(pts
			(xy 139.434824 -280.768044) (xy 139.334748 -280.668222) (xy 139.234672 -280.768044) (xy 139.234672 -280.815796)
			(xy 139.434824 -280.815796)
		)
		(stroke
			(width 0)
			(type solid)
		)
		(fill yes)
		(layer "In2.Cu")
		(net "M_I_CPU1_SB_DQS_DP<1>")
	)
	(gr_poly
		(pts
			(xy 139.434824 -280.364438) (xy 139.434824 -280.319988) (xy 139.234672 -280.319988) (xy 139.234672 -280.364438)
			(xy 139.334748 -280.464514)
		)
		(stroke
			(width 0)
			(type solid)
		)
		(fill yes)
		(layer "In2.Cu")
		(net "M_I_CPU1_SB_DQ<11>")
	)
	(gr_poly
		(pts
			(xy 139.434824 -279.148286) (xy 139.334748 -279.04821) (xy 139.234672 -279.148286) (xy 139.234672 -279.192736)
			(xy 139.434824 -279.192736)
		)
		(stroke
			(width 0)
			(type solid)
		)
		(fill yes)
		(layer "In2.Cu")
		(net "M_I_CPU1_SB_DQ<8>")
	)
	(gr_poly
		(pts
			(xy 139.434824 -278.744426) (xy 139.434824 -278.699976) (xy 139.234672 -278.699976) (xy 139.234672 -278.744426)
			(xy 139.334748 -278.844502)
		)
		(stroke
			(width 0)
			(type solid)
		)
		(fill yes)
		(layer "In2.Cu")
		(net "M_I_CPU1_SB_DQ<7>")
	)
	(gr_poly
		(pts
			(xy 139.434824 -277.528274) (xy 139.334748 -277.428198) (xy 139.234672 -277.528274) (xy 139.234672 -277.572724)
			(xy 139.434824 -277.572724)
		)
		(stroke
			(width 0)
			(type solid)
		)
		(fill yes)
		(layer "In2.Cu")
		(net "M_I_CPU1_SB_DQ<4>")
	)
	(gr_poly
		(pts
			(xy 139.434824 -277.124668) (xy 139.434824 -277.076916) (xy 139.234672 -277.076916) (xy 139.234672 -277.124668)
			(xy 139.334748 -277.22449)
		)
		(stroke
			(width 0)
			(type solid)
		)
		(fill yes)
		(layer "In2.Cu")
		(net "M_I_CPU1_SB_DQS_DP<5>")
	)
	(gr_poly
		(pts
			(xy 139.434824 -275.908008) (xy 139.334748 -275.808186) (xy 139.234672 -275.908008) (xy 139.234672 -275.95576)
			(xy 139.434824 -275.95576)
		)
		(stroke
			(width 0)
			(type solid)
		)
		(fill yes)
		(layer "In2.Cu")
		(net "M_I_CPU1_SB_DQS_DP<0>")
	)
	(gr_poly
		(pts
			(xy 139.434824 -275.504402) (xy 139.434824 -275.459952) (xy 139.234672 -275.459952) (xy 139.234672 -275.504402)
			(xy 139.334748 -275.604478)
		)
		(stroke
			(width 0)
			(type solid)
		)
		(fill yes)
		(layer "In2.Cu")
		(net "M_I_CPU1_SB_DQ<3>")
	)
	(gr_poly
		(pts
			(xy 139.434824 -274.28825) (xy 139.334748 -274.188174) (xy 139.234672 -274.28825) (xy 139.234672 -274.3327)
			(xy 139.434824 -274.3327)
		)
		(stroke
			(width 0)
			(type solid)
		)
		(fill yes)
		(layer "In2.Cu")
		(net "M_I_CPU1_SB_DQ<0>")
	)
	(gr_poly
		(pts
			(xy 139.434824 -273.88439) (xy 139.434824 -273.83994) (xy 139.234672 -273.83994) (xy 139.234672 -273.88439)
			(xy 139.334748 -273.984466)
		)
		(stroke
			(width 0)
			(type solid)
		)
		(fill yes)
		(layer "In2.Cu")
		(net "M_I_CPU1_SB_CB<3>")
	)
	(gr_poly
		(pts
			(xy 139.434824 -272.668238) (xy 139.334748 -272.568162) (xy 139.234672 -272.668238) (xy 139.234672 -272.712688)
			(xy 139.434824 -272.712688)
		)
		(stroke
			(width 0)
			(type solid)
		)
		(fill yes)
		(layer "In2.Cu")
		(net "M_I_CPU1_SB_CB<0>")
	)
	(gr_poly
		(pts
			(xy 139.434824 -272.264632) (xy 139.434824 -272.21688) (xy 139.234672 -272.21688) (xy 139.234672 -272.264632)
			(xy 139.334748 -272.364454)
		)
		(stroke
			(width 0)
			(type solid)
		)
		(fill yes)
		(layer "In2.Cu")
		(net "M_I_CPU1_SB_DQS_DP<4>")
	)
	(gr_poly
		(pts
			(xy 139.434824 -271.047972) (xy 139.334748 -270.94815) (xy 139.234672 -271.047972) (xy 139.234672 -271.095724)
			(xy 139.434824 -271.095724)
		)
		(stroke
			(width 0)
			(type solid)
		)
		(fill yes)
		(layer "In2.Cu")
		(net "M_I_CPU1_SB_DQS_DP<9>")
	)
	(gr_poly
		(pts
			(xy 139.434824 -270.644366) (xy 139.434824 -270.599916) (xy 139.234672 -270.599916) (xy 139.234672 -270.644366)
			(xy 139.334748 -270.744442)
		)
		(stroke
			(width 0)
			(type solid)
		)
		(fill yes)
		(layer "In2.Cu")
		(net "M_I_CPU1_SB_CB<7>")
	)
	(gr_poly
		(pts
			(xy 139.434824 -269.428214) (xy 139.334748 -269.328138) (xy 139.234672 -269.428214) (xy 139.234672 -269.472664)
			(xy 139.434824 -269.472664)
		)
		(stroke
			(width 0)
			(type solid)
		)
		(fill yes)
		(layer "In2.Cu")
		(net "M_I_CPU1_SB_CB<4>")
	)
	(gr_poly
		(pts
			(xy 139.434824 -267.404342) (xy 139.434824 -267.359892) (xy 139.234672 -267.359892) (xy 139.234672 -267.404342)
			(xy 139.334748 -267.504418)
		)
		(stroke
			(width 0)
			(type solid)
		)
		(fill yes)
		(layer "In2.Cu")
		(net "M_I_CPU1_SB_RSP<0>")
	)
	(gr_poly
		(pts
			(xy 139.434824 -265.78433) (xy 139.434824 -265.73988) (xy 139.234672 -265.73988) (xy 139.234672 -265.78433)
			(xy 139.334748 -265.884406)
		)
		(stroke
			(width 0)
			(type solid)
		)
		(fill yes)
		(layer "In2.Cu")
		(net "M_I_CPU1_SB_CS_N<0>")
	)
	(gr_poly
		(pts
			(xy 139.434824 -264.568178) (xy 139.334748 -264.468102) (xy 139.234672 -264.568178) (xy 139.234672 -264.612628)
			(xy 139.434824 -264.612628)
		)
		(stroke
			(width 0)
			(type solid)
		)
		(fill yes)
		(layer "In2.Cu")
		(net "M_I_CPU1_SB_CA<6>")
	)
	(gr_poly
		(pts
			(xy 139.434824 -264.164318) (xy 139.434824 -264.119868) (xy 139.234672 -264.119868) (xy 139.234672 -264.164318)
			(xy 139.334748 -264.264394)
		)
		(stroke
			(width 0)
			(type solid)
		)
		(fill yes)
		(layer "In2.Cu")
		(net "M_I_CPU1_SB_CA<5>")
	)
	(gr_poly
		(pts
			(xy 139.434824 -262.948166) (xy 139.334748 -262.84809) (xy 139.234672 -262.948166) (xy 139.234672 -262.992616)
			(xy 139.434824 -262.992616)
		)
		(stroke
			(width 0)
			(type solid)
		)
		(fill yes)
		(layer "In2.Cu")
		(net "M_I_CPU1_SB_CA<2>")
	)
	(gr_poly
		(pts
			(xy 139.434824 -262.544306) (xy 139.434824 -262.499856) (xy 139.234672 -262.499856) (xy 139.234672 -262.544306)
			(xy 139.334748 -262.644382)
		)
		(stroke
			(width 0)
			(type solid)
		)
		(fill yes)
		(layer "In2.Cu")
		(net "M_I_CPU1_SB_CA<1>")
	)
	(gr_poly
		(pts
			(xy 139.523978 -224.695766) (xy 139.48537 -224.673414) (xy 139.348718 -224.70999) (xy 139.385548 -224.846642)
			(xy 139.423902 -224.868994)
		)
		(stroke
			(width 0)
			(type solid)
		)
		(fill yes)
		(layer "In2.Cu")
		(net "M_I_CPU1_SA_DQ<0>")
	)
	(gr_poly
		(pts
			(xy 139.60475 -256.026158) (xy 139.504674 -255.926336) (xy 139.404598 -256.026158) (xy 139.404598 -256.07391)
			(xy 139.60475 -256.07391)
		)
		(stroke
			(width 0)
			(type solid)
		)
		(fill yes)
		(layer "In2.Cu")
		(net "M_I_CPU1_CLK_DP<0>")
	)
	(gr_poly
		(pts
			(xy 139.60475 -255.622552) (xy 139.60475 -255.578102) (xy 139.404598 -255.578102) (xy 139.404598 -255.622552)
			(xy 139.504674 -255.722628)
		)
		(stroke
			(width 0)
			(type solid)
		)
		(fill yes)
		(layer "In2.Cu")
		(net "M_I_CPU1_SA_PAR")
	)
	(gr_poly
		(pts
			(xy 139.60475 -254.4064) (xy 139.504674 -254.306324) (xy 139.404598 -254.4064) (xy 139.404598 -254.45085)
			(xy 139.60475 -254.45085)
		)
		(stroke
			(width 0)
			(type solid)
		)
		(fill yes)
		(layer "In2.Cu")
		(net "M_I_CPU1_SA_CA<4>")
	)
	(gr_poly
		(pts
			(xy 139.60475 -254.00254) (xy 139.60475 -253.95809) (xy 139.404598 -253.95809) (xy 139.404598 -254.00254)
			(xy 139.504674 -254.102616)
		)
		(stroke
			(width 0)
			(type solid)
		)
		(fill yes)
		(layer "In2.Cu")
		(net "M_I_CPU1_SA_CA<3>")
	)
	(gr_poly
		(pts
			(xy 139.60475 -252.786388) (xy 139.504674 -252.686312) (xy 139.404598 -252.786388) (xy 139.404598 -252.830838)
			(xy 139.60475 -252.830838)
		)
		(stroke
			(width 0)
			(type solid)
		)
		(fill yes)
		(layer "In2.Cu")
		(net "M_I_CPU1_SA_CA<0>")
	)
	(gr_poly
		(pts
			(xy 139.60475 -251.166376) (xy 139.504674 -251.0663) (xy 139.404598 -251.166376) (xy 139.404598 -251.210826)
			(xy 139.60475 -251.210826)
		)
		(stroke
			(width 0)
			(type solid)
		)
		(fill yes)
		(layer "In2.Cu")
		(net "M_I_CPU1_SA_CS_N<0>")
	)
	(gr_poly
		(pts
			(xy 139.60475 -250.762516) (xy 139.60475 -250.718066) (xy 139.404598 -250.718066) (xy 139.404598 -250.762516)
			(xy 139.504674 -250.862592)
		)
		(stroke
			(width 0)
			(type solid)
		)
		(fill yes)
		(layer "In2.Cu")
		(net "M_I_CPU1_RESET_N")
	)
	(gr_poly
		(pts
			(xy 139.60475 -249.142504) (xy 139.60475 -249.098054) (xy 139.404598 -249.098054) (xy 139.404598 -249.142504)
			(xy 139.504674 -249.24258)
		)
		(stroke
			(width 0)
			(type solid)
		)
		(fill yes)
		(layer "In2.Cu")
		(net "M_I_CPU1_SA_CB<7>")
	)
	(gr_poly
		(pts
			(xy 139.60475 -247.926352) (xy 139.504674 -247.826276) (xy 139.404598 -247.926352) (xy 139.404598 -247.970802)
			(xy 139.60475 -247.970802)
		)
		(stroke
			(width 0)
			(type solid)
		)
		(fill yes)
		(layer "In2.Cu")
		(net "M_I_CPU1_SA_CB<4>")
	)
	(gr_poly
		(pts
			(xy 139.60475 -247.522746) (xy 139.60475 -247.474994) (xy 139.404598 -247.474994) (xy 139.404598 -247.522746)
			(xy 139.504674 -247.622568)
		)
		(stroke
			(width 0)
			(type solid)
		)
		(fill yes)
		(layer "In2.Cu")
		(net "M_I_CPU1_SA_DQS_DP<9>")
	)
	(gr_poly
		(pts
			(xy 139.60475 -246.306086) (xy 139.504674 -246.206264) (xy 139.404598 -246.306086) (xy 139.404598 -246.353838)
			(xy 139.60475 -246.353838)
		)
		(stroke
			(width 0)
			(type solid)
		)
		(fill yes)
		(layer "In2.Cu")
		(net "M_I_CPU1_SA_DQS_DP<4>")
	)
	(gr_poly
		(pts
			(xy 139.60475 -245.90248) (xy 139.60475 -245.85803) (xy 139.404598 -245.85803) (xy 139.404598 -245.90248)
			(xy 139.504674 -246.002556)
		)
		(stroke
			(width 0)
			(type solid)
		)
		(fill yes)
		(layer "In2.Cu")
		(net "M_I_CPU1_SA_CB<3>")
	)
	(gr_poly
		(pts
			(xy 139.60475 -244.686328) (xy 139.504674 -244.586252) (xy 139.404598 -244.686328) (xy 139.404598 -244.730778)
			(xy 139.60475 -244.730778)
		)
		(stroke
			(width 0)
			(type solid)
		)
		(fill yes)
		(layer "In2.Cu")
		(net "M_I_CPU1_SA_CB<0>")
	)
	(gr_poly
		(pts
			(xy 139.60475 -244.282468) (xy 139.60475 -244.238018) (xy 139.404598 -244.238018) (xy 139.404598 -244.282468)
			(xy 139.504674 -244.382544)
		)
		(stroke
			(width 0)
			(type solid)
		)
		(fill yes)
		(layer "In2.Cu")
		(net "M_I_CPU1_SA_DQ<31>")
	)
	(gr_poly
		(pts
			(xy 139.60475 -243.066316) (xy 139.504674 -242.96624) (xy 139.404598 -243.066316) (xy 139.404598 -243.110766)
			(xy 139.60475 -243.110766)
		)
		(stroke
			(width 0)
			(type solid)
		)
		(fill yes)
		(layer "In2.Cu")
		(net "M_I_CPU1_SA_DQ<28>")
	)
	(gr_poly
		(pts
			(xy 139.60475 -242.66271) (xy 139.60475 -242.614958) (xy 139.404598 -242.614958) (xy 139.404598 -242.66271)
			(xy 139.504674 -242.762532)
		)
		(stroke
			(width 0)
			(type solid)
		)
		(fill yes)
		(layer "In2.Cu")
		(net "M_I_CPU1_SA_DQS_DP<8>")
	)
	(gr_poly
		(pts
			(xy 139.60475 -241.44605) (xy 139.504674 -241.346228) (xy 139.404598 -241.44605) (xy 139.404598 -241.493802)
			(xy 139.60475 -241.493802)
		)
		(stroke
			(width 0)
			(type solid)
		)
		(fill yes)
		(layer "In2.Cu")
		(net "M_I_CPU1_SA_DQS_DP<3>")
	)
	(gr_poly
		(pts
			(xy 139.60475 -241.042444) (xy 139.60475 -240.997994) (xy 139.404598 -240.997994) (xy 139.404598 -241.042444)
			(xy 139.504674 -241.14252)
		)
		(stroke
			(width 0)
			(type solid)
		)
		(fill yes)
		(layer "In2.Cu")
		(net "M_I_CPU1_SA_DQ<27>")
	)
	(gr_poly
		(pts
			(xy 139.60475 -239.826292) (xy 139.504674 -239.726216) (xy 139.404598 -239.826292) (xy 139.404598 -239.870742)
			(xy 139.60475 -239.870742)
		)
		(stroke
			(width 0)
			(type solid)
		)
		(fill yes)
		(layer "In2.Cu")
		(net "M_I_CPU1_SA_DQ<24>")
	)
	(gr_poly
		(pts
			(xy 139.60475 -239.422432) (xy 139.60475 -239.377982) (xy 139.404598 -239.377982) (xy 139.404598 -239.422432)
			(xy 139.504674 -239.522508)
		)
		(stroke
			(width 0)
			(type solid)
		)
		(fill yes)
		(layer "In2.Cu")
		(net "M_I_CPU1_SA_DQ<23>")
	)
	(gr_poly
		(pts
			(xy 139.60475 -238.20628) (xy 139.504674 -238.106204) (xy 139.404598 -238.20628) (xy 139.404598 -238.25073)
			(xy 139.60475 -238.25073)
		)
		(stroke
			(width 0)
			(type solid)
		)
		(fill yes)
		(layer "In2.Cu")
		(net "M_I_CPU1_SA_DQ<20>")
	)
	(gr_poly
		(pts
			(xy 139.60475 -237.802674) (xy 139.60475 -237.754922) (xy 139.404598 -237.754922) (xy 139.404598 -237.802674)
			(xy 139.504674 -237.902496)
		)
		(stroke
			(width 0)
			(type solid)
		)
		(fill yes)
		(layer "In2.Cu")
		(net "M_I_CPU1_SA_DQS_DP<7>")
	)
	(gr_poly
		(pts
			(xy 139.60475 -236.586014) (xy 139.504674 -236.486192) (xy 139.404598 -236.586014) (xy 139.404598 -236.633766)
			(xy 139.60475 -236.633766)
		)
		(stroke
			(width 0)
			(type solid)
		)
		(fill yes)
		(layer "In2.Cu")
		(net "M_I_CPU1_SA_DQS_DP<2>")
	)
	(gr_poly
		(pts
			(xy 139.60475 -236.182408) (xy 139.60475 -236.137958) (xy 139.404598 -236.137958) (xy 139.404598 -236.182408)
			(xy 139.504674 -236.282484)
		)
		(stroke
			(width 0)
			(type solid)
		)
		(fill yes)
		(layer "In2.Cu")
		(net "M_I_CPU1_SA_DQ<19>")
	)
	(gr_poly
		(pts
			(xy 139.60475 -234.966256) (xy 139.504674 -234.86618) (xy 139.404598 -234.966256) (xy 139.404598 -235.010706)
			(xy 139.60475 -235.010706)
		)
		(stroke
			(width 0)
			(type solid)
		)
		(fill yes)
		(layer "In2.Cu")
		(net "M_I_CPU1_SA_DQ<16>")
	)
	(gr_poly
		(pts
			(xy 139.60475 -234.562396) (xy 139.60475 -234.517946) (xy 139.404598 -234.517946) (xy 139.404598 -234.562396)
			(xy 139.504674 -234.662472)
		)
		(stroke
			(width 0)
			(type solid)
		)
		(fill yes)
		(layer "In2.Cu")
		(net "M_I_CPU1_SA_DQ<15>")
	)
	(gr_poly
		(pts
			(xy 139.60475 -233.346244) (xy 139.504674 -233.246168) (xy 139.404598 -233.346244) (xy 139.404598 -233.390694)
			(xy 139.60475 -233.390694)
		)
		(stroke
			(width 0)
			(type solid)
		)
		(fill yes)
		(layer "In2.Cu")
		(net "M_I_CPU1_SA_DQ<12>")
	)
	(gr_poly
		(pts
			(xy 139.60475 -232.942638) (xy 139.60475 -232.894886) (xy 139.404598 -232.894886) (xy 139.404598 -232.942638)
			(xy 139.504674 -233.04246)
		)
		(stroke
			(width 0)
			(type solid)
		)
		(fill yes)
		(layer "In2.Cu")
		(net "M_I_CPU1_SA_DQS_DP<6>")
	)
	(gr_poly
		(pts
			(xy 139.60475 -231.725978) (xy 139.504674 -231.626156) (xy 139.404598 -231.725978) (xy 139.404598 -231.77373)
			(xy 139.60475 -231.77373)
		)
		(stroke
			(width 0)
			(type solid)
		)
		(fill yes)
		(layer "In2.Cu")
		(net "M_I_CPU1_SA_DQS_DP<1>")
	)
	(gr_poly
		(pts
			(xy 139.60475 -231.322626) (xy 139.60475 -231.278176) (xy 139.404598 -231.278176) (xy 139.404598 -231.322626)
			(xy 139.504674 -231.422702)
		)
		(stroke
			(width 0)
			(type solid)
		)
		(fill yes)
		(layer "In2.Cu")
		(net "M_I_CPU1_SA_DQ<11>")
	)
	(gr_poly
		(pts
			(xy 139.60475 -230.10622) (xy 139.504674 -230.006144) (xy 139.404598 -230.10622) (xy 139.404598 -230.15067)
			(xy 139.60475 -230.15067)
		)
		(stroke
			(width 0)
			(type solid)
		)
		(fill yes)
		(layer "In2.Cu")
		(net "M_I_CPU1_SA_DQ<8>")
	)
	(gr_poly
		(pts
			(xy 139.60475 -229.702614) (xy 139.60475 -229.658164) (xy 139.404598 -229.658164) (xy 139.404598 -229.702614)
			(xy 139.504674 -229.80269)
		)
		(stroke
			(width 0)
			(type solid)
		)
		(fill yes)
		(layer "In2.Cu")
		(net "M_I_CPU1_SA_DQ<7>")
	)
	(gr_poly
		(pts
			(xy 139.60475 -228.486462) (xy 139.504674 -228.386386) (xy 139.404598 -228.486462) (xy 139.404598 -228.530912)
			(xy 139.60475 -228.530912)
		)
		(stroke
			(width 0)
			(type solid)
		)
		(fill yes)
		(layer "In2.Cu")
		(net "M_I_CPU1_SA_DQ<4>")
	)
	(gr_poly
		(pts
			(xy 139.60475 -228.082856) (xy 139.60475 -228.035104) (xy 139.404598 -228.035104) (xy 139.404598 -228.082856)
			(xy 139.504674 -228.182678)
		)
		(stroke
			(width 0)
			(type solid)
		)
		(fill yes)
		(layer "In2.Cu")
		(net "M_I_CPU1_SA_DQS_DP<5>")
	)
	(gr_poly
		(pts
			(xy 139.60475 -226.866196) (xy 139.504674 -226.766374) (xy 139.404598 -226.866196) (xy 139.404598 -226.913948)
			(xy 139.60475 -226.913948)
		)
		(stroke
			(width 0)
			(type solid)
		)
		(fill yes)
		(layer "In2.Cu")
		(net "M_I_CPU1_SA_DQS_DP<0>")
	)
	(gr_poly
		(pts
			(xy 139.60475 -226.46259) (xy 139.60475 -226.41814) (xy 139.404598 -226.41814) (xy 139.404598 -226.46259)
			(xy 139.504674 -226.562666)
		)
		(stroke
			(width 0)
			(type solid)
		)
		(fill yes)
		(layer "In2.Cu")
		(net "M_I_CPU1_SA_DQ<3>")
	)
	(gr_poly
		(pts
			(xy 139.66063 -225.379026) (xy 139.624054 -225.242374) (xy 139.5857 -225.220022) (xy 139.485624 -225.39325)
			(xy 139.524232 -225.415602)
		)
		(stroke
			(width 0)
			(type solid)
		)
		(fill yes)
		(layer "In2.Cu")
		(net "M_I_CPU1_SA_DQ<2>")
	)
	(gr_poly
		(pts
			(xy 139.904724 -292.918134) (xy 139.804648 -292.818058) (xy 139.704572 -292.918134) (xy 139.704572 -292.962584)
			(xy 139.904724 -292.962584)
		)
		(stroke
			(width 0)
			(type solid)
		)
		(fill yes)
		(layer "In2.Cu")
		(net "M_I_CPU1_SB_DQ<29>")
	)
	(gr_poly
		(pts
			(xy 139.904724 -292.514274) (xy 139.904724 -292.469824) (xy 139.704572 -292.469824) (xy 139.704572 -292.514274)
			(xy 139.804648 -292.61435)
		)
		(stroke
			(width 0)
			(type solid)
		)
		(fill yes)
		(layer "In2.Cu")
		(net "M_I_CPU1_SB_DQ<30>")
	)
	(gr_poly
		(pts
			(xy 139.904724 -291.297868) (xy 139.804648 -291.198046) (xy 139.704572 -291.297868) (xy 139.704572 -291.34562)
			(xy 139.904724 -291.34562)
		)
		(stroke
			(width 0)
			(type solid)
		)
		(fill yes)
		(layer "In2.Cu")
		(net "M_I_CPU1_SB_DQS_DN<8>")
	)
	(gr_poly
		(pts
			(xy 139.904724 -290.894516) (xy 139.904724 -290.846764) (xy 139.704572 -290.846764) (xy 139.704572 -290.894516)
			(xy 139.804648 -290.994338)
		)
		(stroke
			(width 0)
			(type solid)
		)
		(fill yes)
		(layer "In2.Cu")
		(net "M_I_CPU1_SB_DQS_DN<3>")
	)
	(gr_poly
		(pts
			(xy 139.904724 -289.67811) (xy 139.804648 -289.578034) (xy 139.704572 -289.67811) (xy 139.704572 -289.72256)
			(xy 139.904724 -289.72256)
		)
		(stroke
			(width 0)
			(type solid)
		)
		(fill yes)
		(layer "In2.Cu")
		(net "M_I_CPU1_SB_DQ<25>")
	)
	(gr_poly
		(pts
			(xy 139.904724 -289.27425) (xy 139.904724 -289.2298) (xy 139.704572 -289.2298) (xy 139.704572 -289.27425)
			(xy 139.804648 -289.374326)
		)
		(stroke
			(width 0)
			(type solid)
		)
		(fill yes)
		(layer "In2.Cu")
		(net "M_I_CPU1_SB_DQ<26>")
	)
	(gr_poly
		(pts
			(xy 139.904724 -288.058098) (xy 139.804648 -287.958022) (xy 139.704572 -288.058098) (xy 139.704572 -288.102548)
			(xy 139.904724 -288.102548)
		)
		(stroke
			(width 0)
			(type solid)
		)
		(fill yes)
		(layer "In2.Cu")
		(net "M_I_CPU1_SB_DQ<21>")
	)
	(gr_poly
		(pts
			(xy 139.904724 -287.654492) (xy 139.904724 -287.610042) (xy 139.704572 -287.610042) (xy 139.704572 -287.654492)
			(xy 139.804648 -287.754568)
		)
		(stroke
			(width 0)
			(type solid)
		)
		(fill yes)
		(layer "In2.Cu")
		(net "M_I_CPU1_SB_DQ<22>")
	)
	(gr_poly
		(pts
			(xy 139.904724 -286.438086) (xy 139.804648 -286.33801) (xy 139.704572 -286.438086) (xy 139.704572 -286.485838)
			(xy 139.904724 -286.485838)
		)
		(stroke
			(width 0)
			(type solid)
		)
		(fill yes)
		(layer "In2.Cu")
		(net "M_I_CPU1_SB_DQS_DN<7>")
	)
	(gr_poly
		(pts
			(xy 139.904724 -286.034734) (xy 139.904724 -285.986982) (xy 139.704572 -285.986982) (xy 139.704572 -286.034734)
			(xy 139.804648 -286.134556)
		)
		(stroke
			(width 0)
			(type solid)
		)
		(fill yes)
		(layer "In2.Cu")
		(net "M_I_CPU1_SB_DQS_DN<2>")
	)
	(gr_poly
		(pts
			(xy 139.904724 -284.818328) (xy 139.804648 -284.718252) (xy 139.704572 -284.818328) (xy 139.704572 -284.862778)
			(xy 139.904724 -284.862778)
		)
		(stroke
			(width 0)
			(type solid)
		)
		(fill yes)
		(layer "In2.Cu")
		(net "M_I_CPU1_SB_DQ<17>")
	)
	(gr_poly
		(pts
			(xy 139.904724 -284.414468) (xy 139.904724 -284.370018) (xy 139.704572 -284.370018) (xy 139.704572 -284.414468)
			(xy 139.804648 -284.514544)
		)
		(stroke
			(width 0)
			(type solid)
		)
		(fill yes)
		(layer "In2.Cu")
		(net "M_I_CPU1_SB_DQ<18>")
	)
	(gr_poly
		(pts
			(xy 139.904724 -283.198316) (xy 139.804648 -283.09824) (xy 139.704572 -283.198316) (xy 139.704572 -283.242766)
			(xy 139.904724 -283.242766)
		)
		(stroke
			(width 0)
			(type solid)
		)
		(fill yes)
		(layer "In2.Cu")
		(net "M_I_CPU1_SB_DQ<13>")
	)
	(gr_poly
		(pts
			(xy 139.904724 -282.794456) (xy 139.904724 -282.750006) (xy 139.704572 -282.750006) (xy 139.704572 -282.794456)
			(xy 139.804648 -282.894532)
		)
		(stroke
			(width 0)
			(type solid)
		)
		(fill yes)
		(layer "In2.Cu")
		(net "M_I_CPU1_SB_DQ<14>")
	)
	(gr_poly
		(pts
			(xy 139.904724 -281.57805) (xy 139.804648 -281.478228) (xy 139.704572 -281.57805) (xy 139.704572 -281.625802)
			(xy 139.904724 -281.625802)
		)
		(stroke
			(width 0)
			(type solid)
		)
		(fill yes)
		(layer "In2.Cu")
		(net "M_I_CPU1_SB_DQS_DN<6>")
	)
	(gr_poly
		(pts
			(xy 139.904724 -281.174698) (xy 139.904724 -281.126946) (xy 139.704572 -281.126946) (xy 139.704572 -281.174698)
			(xy 139.804648 -281.27452)
		)
		(stroke
			(width 0)
			(type solid)
		)
		(fill yes)
		(layer "In2.Cu")
		(net "M_I_CPU1_SB_DQS_DN<1>")
	)
	(gr_poly
		(pts
			(xy 139.904724 -279.958292) (xy 139.804648 -279.858216) (xy 139.704572 -279.958292) (xy 139.704572 -280.002742)
			(xy 139.904724 -280.002742)
		)
		(stroke
			(width 0)
			(type solid)
		)
		(fill yes)
		(layer "In2.Cu")
		(net "M_I_CPU1_SB_DQ<9>")
	)
	(gr_poly
		(pts
			(xy 139.904724 -279.554432) (xy 139.904724 -279.509982) (xy 139.704572 -279.509982) (xy 139.704572 -279.554432)
			(xy 139.804648 -279.654508)
		)
		(stroke
			(width 0)
			(type solid)
		)
		(fill yes)
		(layer "In2.Cu")
		(net "M_I_CPU1_SB_DQ<10>")
	)
	(gr_poly
		(pts
			(xy 139.904724 -278.33828) (xy 139.804648 -278.238204) (xy 139.704572 -278.33828) (xy 139.704572 -278.38273)
			(xy 139.904724 -278.38273)
		)
		(stroke
			(width 0)
			(type solid)
		)
		(fill yes)
		(layer "In2.Cu")
		(net "M_I_CPU1_SB_DQ<5>")
	)
	(gr_poly
		(pts
			(xy 139.904724 -277.93442) (xy 139.904724 -277.88997) (xy 139.704572 -277.88997) (xy 139.704572 -277.93442)
			(xy 139.804648 -278.034496)
		)
		(stroke
			(width 0)
			(type solid)
		)
		(fill yes)
		(layer "In2.Cu")
		(net "M_I_CPU1_SB_DQ<6>")
	)
	(gr_poly
		(pts
			(xy 139.904724 -276.718014) (xy 139.804648 -276.618192) (xy 139.704572 -276.718014) (xy 139.704572 -276.765766)
			(xy 139.904724 -276.765766)
		)
		(stroke
			(width 0)
			(type solid)
		)
		(fill yes)
		(layer "In2.Cu")
		(net "M_I_CPU1_SB_DQS_DN<5>")
	)
	(gr_poly
		(pts
			(xy 139.904724 -276.314662) (xy 139.904724 -276.26691) (xy 139.704572 -276.26691) (xy 139.704572 -276.314662)
			(xy 139.804648 -276.414484)
		)
		(stroke
			(width 0)
			(type solid)
		)
		(fill yes)
		(layer "In2.Cu")
		(net "M_I_CPU1_SB_DQS_DN<0>")
	)
	(gr_poly
		(pts
			(xy 139.904724 -275.098256) (xy 139.804648 -274.99818) (xy 139.704572 -275.098256) (xy 139.704572 -275.142706)
			(xy 139.904724 -275.142706)
		)
		(stroke
			(width 0)
			(type solid)
		)
		(fill yes)
		(layer "In2.Cu")
		(net "M_I_CPU1_SB_DQ<1>")
	)
	(gr_poly
		(pts
			(xy 139.904724 -274.694396) (xy 139.904724 -274.649946) (xy 139.704572 -274.649946) (xy 139.704572 -274.694396)
			(xy 139.804648 -274.794472)
		)
		(stroke
			(width 0)
			(type solid)
		)
		(fill yes)
		(layer "In2.Cu")
		(net "M_I_CPU1_SB_DQ<2>")
	)
	(gr_poly
		(pts
			(xy 139.904724 -273.478244) (xy 139.804648 -273.378168) (xy 139.704572 -273.478244) (xy 139.704572 -273.522694)
			(xy 139.904724 -273.522694)
		)
		(stroke
			(width 0)
			(type solid)
		)
		(fill yes)
		(layer "In2.Cu")
		(net "M_I_CPU1_SB_CB<1>")
	)
	(gr_poly
		(pts
			(xy 139.904724 -273.074384) (xy 139.904724 -273.029934) (xy 139.704572 -273.029934) (xy 139.704572 -273.074384)
			(xy 139.804648 -273.17446)
		)
		(stroke
			(width 0)
			(type solid)
		)
		(fill yes)
		(layer "In2.Cu")
		(net "M_I_CPU1_SB_CB<2>")
	)
	(gr_poly
		(pts
			(xy 139.904724 -271.857978) (xy 139.804648 -271.758156) (xy 139.704572 -271.857978) (xy 139.704572 -271.90573)
			(xy 139.904724 -271.90573)
		)
		(stroke
			(width 0)
			(type solid)
		)
		(fill yes)
		(layer "In2.Cu")
		(net "M_I_CPU1_SB_DQS_DN<4>")
	)
	(gr_poly
		(pts
			(xy 139.904724 -271.454626) (xy 139.904724 -271.406874) (xy 139.704572 -271.406874) (xy 139.704572 -271.454626)
			(xy 139.804648 -271.554448)
		)
		(stroke
			(width 0)
			(type solid)
		)
		(fill yes)
		(layer "In2.Cu")
		(net "M_I_CPU1_SB_DQS_DN<9>")
	)
	(gr_poly
		(pts
			(xy 139.904724 -270.23822) (xy 139.804648 -270.138144) (xy 139.704572 -270.23822) (xy 139.704572 -270.28267)
			(xy 139.904724 -270.28267)
		)
		(stroke
			(width 0)
			(type solid)
		)
		(fill yes)
		(layer "In2.Cu")
		(net "M_I_CPU1_SB_CB<5>")
	)
	(gr_poly
		(pts
			(xy 139.904724 -269.83436) (xy 139.904724 -269.78991) (xy 139.704572 -269.78991) (xy 139.704572 -269.83436)
			(xy 139.804648 -269.934436)
		)
		(stroke
			(width 0)
			(type solid)
		)
		(fill yes)
		(layer "In2.Cu")
		(net "M_I_CPU1_SB_CB<6>")
	)
	(gr_poly
		(pts
			(xy 139.904724 -266.998196) (xy 139.804648 -266.89812) (xy 139.704572 -266.998196) (xy 139.704572 -267.042646)
			(xy 139.904724 -267.042646)
		)
		(stroke
			(width 0)
			(type solid)
		)
		(fill yes)
		(layer "In2.Cu")
		(net "M_I_CPU1_SA_RSP<0>")
	)
	(gr_poly
		(pts
			(xy 139.904724 -266.594336) (xy 139.904724 -266.549886) (xy 139.704572 -266.549886) (xy 139.704572 -266.594336)
			(xy 139.804648 -266.694412)
		)
		(stroke
			(width 0)
			(type solid)
		)
		(fill yes)
		(layer "In2.Cu")
		(net "M_I_CPU1_SB_CS_N<1>")
	)
	(gr_poly
		(pts
			(xy 139.904724 -265.378184) (xy 139.804648 -265.278108) (xy 139.704572 -265.378184) (xy 139.704572 -265.422634)
			(xy 139.904724 -265.422634)
		)
		(stroke
			(width 0)
			(type solid)
		)
		(fill yes)
		(layer "In2.Cu")
		(net "M_I_CPU1_SB_PAR")
	)
	(gr_poly
		(pts
			(xy 139.904724 -263.758172) (xy 139.804648 -263.658096) (xy 139.704572 -263.758172) (xy 139.704572 -263.802622)
			(xy 139.904724 -263.802622)
		)
		(stroke
			(width 0)
			(type solid)
		)
		(fill yes)
		(layer "In2.Cu")
		(net "M_I_CPU1_SB_CA<4>")
	)
	(gr_poly
		(pts
			(xy 139.904724 -263.354312) (xy 139.904724 -263.309862) (xy 139.704572 -263.309862) (xy 139.704572 -263.354312)
			(xy 139.804648 -263.454388)
		)
		(stroke
			(width 0)
			(type solid)
		)
		(fill yes)
		(layer "In2.Cu")
		(net "M_I_CPU1_SB_CA<3>")
	)
	(gr_poly
		(pts
			(xy 139.904724 -262.13816) (xy 139.804648 -262.038084) (xy 139.704572 -262.13816) (xy 139.704572 -262.18261)
			(xy 139.904724 -262.18261)
		)
		(stroke
			(width 0)
			(type solid)
		)
		(fill yes)
		(layer "In2.Cu")
		(net "M_I_CPU1_SB_CA<0>")
	)
	(gr_poly
		(pts
			(xy 139.993878 -225.505772) (xy 139.95527 -225.48342) (xy 139.818618 -225.519996) (xy 139.855448 -225.656648)
			(xy 139.893802 -225.679)
		)
		(stroke
			(width 0)
			(type solid)
		)
		(fill yes)
		(layer "In2.Cu")
		(net "M_I_CPU1_SA_DQ<1>")
	)
	(gr_poly
		(pts
			(xy 139.994132 -223.884998) (xy 139.955778 -223.862646) (xy 139.819126 -223.899222) (xy 139.855702 -224.035874)
			(xy 139.89431 -224.058226)
		)
		(stroke
			(width 0)
			(type solid)
		)
		(fill yes)
		(layer "In2.Cu")
		(net "M_I_CPU1_SA_DQ<0>")
	)
	(gr_poly
		(pts
			(xy 140.074904 -256.432812) (xy 140.074904 -256.38506) (xy 139.874752 -256.38506) (xy 139.874752 -256.432812)
			(xy 139.974828 -256.532634)
		)
		(stroke
			(width 0)
			(type solid)
		)
		(fill yes)
		(layer "In2.Cu")
		(net "M_I_CPU1_CLK_DN<0>")
	)
	(gr_poly
		(pts
			(xy 140.074904 -255.216406) (xy 139.974828 -255.11633) (xy 139.874752 -255.216406) (xy 139.874752 -255.260856)
			(xy 140.074904 -255.260856)
		)
		(stroke
			(width 0)
			(type solid)
		)
		(fill yes)
		(layer "In2.Cu")
		(net "M_I_CPU1_SA_CA<6>")
	)
	(gr_poly
		(pts
			(xy 140.074904 -254.812546) (xy 140.074904 -254.768096) (xy 139.874752 -254.768096) (xy 139.874752 -254.812546)
			(xy 139.974828 -254.912622)
		)
		(stroke
			(width 0)
			(type solid)
		)
		(fill yes)
		(layer "In2.Cu")
		(net "M_I_CPU1_SA_CA<5>")
	)
	(gr_poly
		(pts
			(xy 140.074904 -253.596394) (xy 139.974828 -253.496318) (xy 139.874752 -253.596394) (xy 139.874752 -253.640844)
			(xy 140.074904 -253.640844)
		)
		(stroke
			(width 0)
			(type solid)
		)
		(fill yes)
		(layer "In2.Cu")
		(net "M_I_CPU1_SA_CA<2>")
	)
	(gr_poly
		(pts
			(xy 140.074904 -253.192534) (xy 140.074904 -253.148084) (xy 139.874752 -253.148084) (xy 139.874752 -253.192534)
			(xy 139.974828 -253.29261)
		)
		(stroke
			(width 0)
			(type solid)
		)
		(fill yes)
		(layer "In2.Cu")
		(net "M_I_CPU1_SA_CA<1>")
	)
	(gr_poly
		(pts
			(xy 140.074904 -251.976382) (xy 139.974828 -251.876306) (xy 139.874752 -251.976382) (xy 139.874752 -252.020832)
			(xy 140.074904 -252.020832)
		)
		(stroke
			(width 0)
			(type solid)
		)
		(fill yes)
		(layer "In2.Cu")
		(net "M_I_CPU1_SA_CS_N<1>")
	)
	(gr_poly
		(pts
			(xy 140.074904 -250.35637) (xy 139.974828 -250.256294) (xy 139.874752 -250.35637) (xy 139.874752 -250.40082)
			(xy 140.074904 -250.40082)
		)
		(stroke
			(width 0)
			(type solid)
		)
		(fill yes)
		(layer "In2.Cu")
		(net "M_I_CPU1_ALERT_R_N")
	)
	(gr_poly
		(pts
			(xy 140.074904 -248.736358) (xy 139.974828 -248.636282) (xy 139.874752 -248.736358) (xy 139.874752 -248.780808)
			(xy 140.074904 -248.780808)
		)
		(stroke
			(width 0)
			(type solid)
		)
		(fill yes)
		(layer "In2.Cu")
		(net "M_I_CPU1_SA_CB<5>")
	)
	(gr_poly
		(pts
			(xy 140.074904 -248.332498) (xy 140.074904 -248.288048) (xy 139.874752 -248.288048) (xy 139.874752 -248.332498)
			(xy 139.974828 -248.432574)
		)
		(stroke
			(width 0)
			(type solid)
		)
		(fill yes)
		(layer "In2.Cu")
		(net "M_I_CPU1_SA_CB<6>")
	)
	(gr_poly
		(pts
			(xy 140.074904 -247.116092) (xy 139.974828 -247.01627) (xy 139.874752 -247.116092) (xy 139.874752 -247.163844)
			(xy 140.074904 -247.163844)
		)
		(stroke
			(width 0)
			(type solid)
		)
		(fill yes)
		(layer "In2.Cu")
		(net "M_I_CPU1_SA_DQS_DN<9>")
	)
	(gr_poly
		(pts
			(xy 140.074904 -246.71274) (xy 140.074904 -246.664988) (xy 139.874752 -246.664988) (xy 139.874752 -246.71274)
			(xy 139.974828 -246.812562)
		)
		(stroke
			(width 0)
			(type solid)
		)
		(fill yes)
		(layer "In2.Cu")
		(net "M_I_CPU1_SA_DQS_DN<4>")
	)
	(gr_poly
		(pts
			(xy 140.074904 -245.496334) (xy 139.974828 -245.396258) (xy 139.874752 -245.496334) (xy 139.874752 -245.540784)
			(xy 140.074904 -245.540784)
		)
		(stroke
			(width 0)
			(type solid)
		)
		(fill yes)
		(layer "In2.Cu")
		(net "M_I_CPU1_SA_CB<1>")
	)
	(gr_poly
		(pts
			(xy 140.074904 -245.092474) (xy 140.074904 -245.048024) (xy 139.874752 -245.048024) (xy 139.874752 -245.092474)
			(xy 139.974828 -245.19255)
		)
		(stroke
			(width 0)
			(type solid)
		)
		(fill yes)
		(layer "In2.Cu")
		(net "M_I_CPU1_SA_CB<2>")
	)
	(gr_poly
		(pts
			(xy 140.074904 -243.876322) (xy 139.974828 -243.776246) (xy 139.874752 -243.876322) (xy 139.874752 -243.920772)
			(xy 140.074904 -243.920772)
		)
		(stroke
			(width 0)
			(type solid)
		)
		(fill yes)
		(layer "In2.Cu")
		(net "M_I_CPU1_SA_DQ<29>")
	)
	(gr_poly
		(pts
			(xy 140.074904 -243.472462) (xy 140.074904 -243.428012) (xy 139.874752 -243.428012) (xy 139.874752 -243.472462)
			(xy 139.974828 -243.572538)
		)
		(stroke
			(width 0)
			(type solid)
		)
		(fill yes)
		(layer "In2.Cu")
		(net "M_I_CPU1_SA_DQ<30>")
	)
	(gr_poly
		(pts
			(xy 140.074904 -242.256056) (xy 139.974828 -242.156234) (xy 139.874752 -242.256056) (xy 139.874752 -242.303808)
			(xy 140.074904 -242.303808)
		)
		(stroke
			(width 0)
			(type solid)
		)
		(fill yes)
		(layer "In2.Cu")
		(net "M_I_CPU1_SA_DQS_DN<8>")
	)
	(gr_poly
		(pts
			(xy 140.074904 -241.852704) (xy 140.074904 -241.804952) (xy 139.874752 -241.804952) (xy 139.874752 -241.852704)
			(xy 139.974828 -241.952526)
		)
		(stroke
			(width 0)
			(type solid)
		)
		(fill yes)
		(layer "In2.Cu")
		(net "M_I_CPU1_SA_DQS_DN<3>")
	)
	(gr_poly
		(pts
			(xy 140.074904 -240.636298) (xy 139.974828 -240.536222) (xy 139.874752 -240.636298) (xy 139.874752 -240.680748)
			(xy 140.074904 -240.680748)
		)
		(stroke
			(width 0)
			(type solid)
		)
		(fill yes)
		(layer "In2.Cu")
		(net "M_I_CPU1_SA_DQ<25>")
	)
	(gr_poly
		(pts
			(xy 140.074904 -240.232438) (xy 140.074904 -240.187988) (xy 139.874752 -240.187988) (xy 139.874752 -240.232438)
			(xy 139.974828 -240.332514)
		)
		(stroke
			(width 0)
			(type solid)
		)
		(fill yes)
		(layer "In2.Cu")
		(net "M_I_CPU1_SA_DQ<26>")
	)
	(gr_poly
		(pts
			(xy 140.074904 -239.016286) (xy 139.974828 -238.91621) (xy 139.874752 -239.016286) (xy 139.874752 -239.060736)
			(xy 140.074904 -239.060736)
		)
		(stroke
			(width 0)
			(type solid)
		)
		(fill yes)
		(layer "In2.Cu")
		(net "M_I_CPU1_SA_DQ<21>")
	)
	(gr_poly
		(pts
			(xy 140.074904 -238.612426) (xy 140.074904 -238.567976) (xy 139.874752 -238.567976) (xy 139.874752 -238.612426)
			(xy 139.974828 -238.712502)
		)
		(stroke
			(width 0)
			(type solid)
		)
		(fill yes)
		(layer "In2.Cu")
		(net "M_I_CPU1_SA_DQ<22>")
	)
	(gr_poly
		(pts
			(xy 140.074904 -237.39602) (xy 139.974828 -237.296198) (xy 139.874752 -237.39602) (xy 139.874752 -237.443772)
			(xy 140.074904 -237.443772)
		)
		(stroke
			(width 0)
			(type solid)
		)
		(fill yes)
		(layer "In2.Cu")
		(net "M_I_CPU1_SA_DQS_DN<7>")
	)
	(gr_poly
		(pts
			(xy 140.074904 -236.992668) (xy 140.074904 -236.944916) (xy 139.874752 -236.944916) (xy 139.874752 -236.992668)
			(xy 139.974828 -237.09249)
		)
		(stroke
			(width 0)
			(type solid)
		)
		(fill yes)
		(layer "In2.Cu")
		(net "M_I_CPU1_SA_DQS_DN<2>")
	)
	(gr_poly
		(pts
			(xy 140.074904 -235.776262) (xy 139.974828 -235.676186) (xy 139.874752 -235.776262) (xy 139.874752 -235.820712)
			(xy 140.074904 -235.820712)
		)
		(stroke
			(width 0)
			(type solid)
		)
		(fill yes)
		(layer "In2.Cu")
		(net "M_I_CPU1_SA_DQ<17>")
	)
	(gr_poly
		(pts
			(xy 140.074904 -235.372402) (xy 140.074904 -235.327952) (xy 139.874752 -235.327952) (xy 139.874752 -235.372402)
			(xy 139.974828 -235.472478)
		)
		(stroke
			(width 0)
			(type solid)
		)
		(fill yes)
		(layer "In2.Cu")
		(net "M_I_CPU1_SA_DQ<18>")
	)
	(gr_poly
		(pts
			(xy 140.074904 -234.15625) (xy 139.974828 -234.056174) (xy 139.874752 -234.15625) (xy 139.874752 -234.2007)
			(xy 140.074904 -234.2007)
		)
		(stroke
			(width 0)
			(type solid)
		)
		(fill yes)
		(layer "In2.Cu")
		(net "M_I_CPU1_SA_DQ<13>")
	)
	(gr_poly
		(pts
			(xy 140.074904 -233.75239) (xy 140.074904 -233.70794) (xy 139.874752 -233.70794) (xy 139.874752 -233.75239)
			(xy 139.974828 -233.852466)
		)
		(stroke
			(width 0)
			(type solid)
		)
		(fill yes)
		(layer "In2.Cu")
		(net "M_I_CPU1_SA_DQ<14>")
	)
	(gr_poly
		(pts
			(xy 140.074904 -232.535984) (xy 139.974828 -232.436162) (xy 139.874752 -232.535984) (xy 139.874752 -232.583736)
			(xy 140.074904 -232.583736)
		)
		(stroke
			(width 0)
			(type solid)
		)
		(fill yes)
		(layer "In2.Cu")
		(net "M_I_CPU1_SA_DQS_DN<6>")
	)
	(gr_poly
		(pts
			(xy 140.074904 -232.132632) (xy 140.074904 -232.08488) (xy 139.874752 -232.08488) (xy 139.874752 -232.132632)
			(xy 139.974828 -232.232454)
		)
		(stroke
			(width 0)
			(type solid)
		)
		(fill yes)
		(layer "In2.Cu")
		(net "M_I_CPU1_SA_DQS_DN<1>")
	)
	(gr_poly
		(pts
			(xy 140.074904 -230.916226) (xy 139.974828 -230.81615) (xy 139.874752 -230.916226) (xy 139.874752 -230.960676)
			(xy 140.074904 -230.960676)
		)
		(stroke
			(width 0)
			(type solid)
		)
		(fill yes)
		(layer "In2.Cu")
		(net "M_I_CPU1_SA_DQ<9>")
	)
	(gr_poly
		(pts
			(xy 140.074904 -230.51262) (xy 140.074904 -230.46817) (xy 139.874752 -230.46817) (xy 139.874752 -230.51262)
			(xy 139.974828 -230.612696)
		)
		(stroke
			(width 0)
			(type solid)
		)
		(fill yes)
		(layer "In2.Cu")
		(net "M_I_CPU1_SA_DQ<10>")
	)
	(gr_poly
		(pts
			(xy 140.074904 -229.296214) (xy 139.974828 -229.196138) (xy 139.874752 -229.296214) (xy 139.874752 -229.340664)
			(xy 140.074904 -229.340664)
		)
		(stroke
			(width 0)
			(type solid)
		)
		(fill yes)
		(layer "In2.Cu")
		(net "M_I_CPU1_SA_DQ<5>")
	)
	(gr_poly
		(pts
			(xy 140.074904 -228.892608) (xy 140.074904 -228.848158) (xy 139.874752 -228.848158) (xy 139.874752 -228.892608)
			(xy 139.974828 -228.992684)
		)
		(stroke
			(width 0)
			(type solid)
		)
		(fill yes)
		(layer "In2.Cu")
		(net "M_I_CPU1_SA_DQ<6>")
	)
	(gr_poly
		(pts
			(xy 140.074904 -227.676202) (xy 139.974828 -227.57638) (xy 139.874752 -227.676202) (xy 139.874752 -227.723954)
			(xy 140.074904 -227.723954)
		)
		(stroke
			(width 0)
			(type solid)
		)
		(fill yes)
		(layer "In2.Cu")
		(net "M_I_CPU1_SA_DQS_DN<5>")
	)
	(gr_poly
		(pts
			(xy 140.074904 -227.27285) (xy 140.074904 -227.225098) (xy 139.874752 -227.225098) (xy 139.874752 -227.27285)
			(xy 139.974828 -227.372672)
		)
		(stroke
			(width 0)
			(type solid)
		)
		(fill yes)
		(layer "In2.Cu")
		(net "M_I_CPU1_SA_DQS_DN<0>")
	)
	(gr_poly
		(pts
			(xy 140.129768 -224.57029) (xy 140.093192 -224.433638) (xy 140.054584 -224.41154) (xy 139.954508 -224.584768)
			(xy 139.993116 -224.606866)
		)
		(stroke
			(width 0)
			(type solid)
		)
		(fill yes)
		(layer "In2.Cu")
		(net "M_I_CPU1_SA_DQ<2>")
	)
	(gr_poly
		(pts
			(xy 140.13053 -226.189032) (xy 140.093954 -226.05238) (xy 140.0556 -226.030028) (xy 139.955524 -226.203256)
			(xy 139.994132 -226.225608)
		)
		(stroke
			(width 0)
			(type solid)
		)
		(fill yes)
		(layer "In2.Cu")
		(net "M_I_CPU1_SA_DQ<3>")
	)
	(gr_poly
		(pts
			(xy 140.374878 -293.32428) (xy 140.374878 -293.27983) (xy 140.174726 -293.27983) (xy 140.174726 -293.32428)
			(xy 140.274802 -293.424356)
		)
		(stroke
			(width 0)
			(type solid)
		)
		(fill yes)
		(layer "In2.Cu")
		(net "M_I_CPU1_SB_DQ<31>")
	)
	(gr_poly
		(pts
			(xy 140.374878 -292.108128) (xy 140.274802 -292.008052) (xy 140.174726 -292.108128) (xy 140.174726 -292.152578)
			(xy 140.374878 -292.152578)
		)
		(stroke
			(width 0)
			(type solid)
		)
		(fill yes)
		(layer "In2.Cu")
		(net "M_I_CPU1_SB_DQ<28>")
	)
	(gr_poly
		(pts
			(xy 140.374878 -291.704522) (xy 140.374878 -291.65677) (xy 140.174726 -291.65677) (xy 140.174726 -291.704522)
			(xy 140.274802 -291.804344)
		)
		(stroke
			(width 0)
			(type solid)
		)
		(fill yes)
		(layer "In2.Cu")
		(net "M_I_CPU1_SB_DQS_DP<8>")
	)
	(gr_poly
		(pts
			(xy 140.374878 -290.487862) (xy 140.274802 -290.38804) (xy 140.174726 -290.487862) (xy 140.174726 -290.535614)
			(xy 140.374878 -290.535614)
		)
		(stroke
			(width 0)
			(type solid)
		)
		(fill yes)
		(layer "In2.Cu")
		(net "M_I_CPU1_SB_DQS_DP<3>")
	)
	(gr_poly
		(pts
			(xy 140.374878 -290.084256) (xy 140.374878 -290.039806) (xy 140.174726 -290.039806) (xy 140.174726 -290.084256)
			(xy 140.274802 -290.184332)
		)
		(stroke
			(width 0)
			(type solid)
		)
		(fill yes)
		(layer "In2.Cu")
		(net "M_I_CPU1_SB_DQ<27>")
	)
	(gr_poly
		(pts
			(xy 140.374878 -288.868104) (xy 140.274802 -288.768028) (xy 140.174726 -288.868104) (xy 140.174726 -288.912554)
			(xy 140.374878 -288.912554)
		)
		(stroke
			(width 0)
			(type solid)
		)
		(fill yes)
		(layer "In2.Cu")
		(net "M_I_CPU1_SB_DQ<24>")
	)
	(gr_poly
		(pts
			(xy 140.374878 -288.464498) (xy 140.374878 -288.420048) (xy 140.174726 -288.420048) (xy 140.174726 -288.464498)
			(xy 140.274802 -288.564574)
		)
		(stroke
			(width 0)
			(type solid)
		)
		(fill yes)
		(layer "In2.Cu")
		(net "M_I_CPU1_SB_DQ<23>")
	)
	(gr_poly
		(pts
			(xy 140.374878 -287.248092) (xy 140.274802 -287.148016) (xy 140.174726 -287.248092) (xy 140.174726 -287.292542)
			(xy 140.374878 -287.292542)
		)
		(stroke
			(width 0)
			(type solid)
		)
		(fill yes)
		(layer "In2.Cu")
		(net "M_I_CPU1_SB_DQ<20>")
	)
	(gr_poly
		(pts
			(xy 140.374878 -286.844486) (xy 140.374878 -286.796734) (xy 140.174726 -286.796734) (xy 140.174726 -286.844486)
			(xy 140.274802 -286.944562)
		)
		(stroke
			(width 0)
			(type solid)
		)
		(fill yes)
		(layer "In2.Cu")
		(net "M_I_CPU1_SB_DQS_DP<7>")
	)
	(gr_poly
		(pts
			(xy 140.374878 -285.62808) (xy 140.274802 -285.528258) (xy 140.174726 -285.62808) (xy 140.174726 -285.675832)
			(xy 140.374878 -285.675832)
		)
		(stroke
			(width 0)
			(type solid)
		)
		(fill yes)
		(layer "In2.Cu")
		(net "M_I_CPU1_SB_DQS_DP<2>")
	)
	(gr_poly
		(pts
			(xy 140.374878 -285.224474) (xy 140.374878 -285.180024) (xy 140.174726 -285.180024) (xy 140.174726 -285.224474)
			(xy 140.274802 -285.32455)
		)
		(stroke
			(width 0)
			(type solid)
		)
		(fill yes)
		(layer "In2.Cu")
		(net "M_I_CPU1_SB_DQ<19>")
	)
	(gr_poly
		(pts
			(xy 140.374878 -284.008322) (xy 140.274802 -283.908246) (xy 140.174726 -284.008322) (xy 140.174726 -284.052772)
			(xy 140.374878 -284.052772)
		)
		(stroke
			(width 0)
			(type solid)
		)
		(fill yes)
		(layer "In2.Cu")
		(net "M_I_CPU1_SB_DQ<16>")
	)
	(gr_poly
		(pts
			(xy 140.374878 -283.604462) (xy 140.374878 -283.560012) (xy 140.174726 -283.560012) (xy 140.174726 -283.604462)
			(xy 140.274802 -283.704538)
		)
		(stroke
			(width 0)
			(type solid)
		)
		(fill yes)
		(layer "In2.Cu")
		(net "M_I_CPU1_SB_DQ<15>")
	)
	(gr_poly
		(pts
			(xy 140.374878 -282.38831) (xy 140.274802 -282.288234) (xy 140.174726 -282.38831) (xy 140.174726 -282.43276)
			(xy 140.374878 -282.43276)
		)
		(stroke
			(width 0)
			(type solid)
		)
		(fill yes)
		(layer "In2.Cu")
		(net "M_I_CPU1_SB_DQ<12>")
	)
	(gr_poly
		(pts
			(xy 140.374878 -281.984704) (xy 140.374878 -281.936952) (xy 140.174726 -281.936952) (xy 140.174726 -281.984704)
			(xy 140.274802 -282.084526)
		)
		(stroke
			(width 0)
			(type solid)
		)
		(fill yes)
		(layer "In2.Cu")
		(net "M_I_CPU1_SB_DQS_DP<6>")
	)
	(gr_poly
		(pts
			(xy 140.374878 -280.768044) (xy 140.274802 -280.668222) (xy 140.174726 -280.768044) (xy 140.174726 -280.815796)
			(xy 140.374878 -280.815796)
		)
		(stroke
			(width 0)
			(type solid)
		)
		(fill yes)
		(layer "In2.Cu")
		(net "M_I_CPU1_SB_DQS_DP<1>")
	)
	(gr_poly
		(pts
			(xy 140.374878 -280.364438) (xy 140.374878 -280.319988) (xy 140.174726 -280.319988) (xy 140.174726 -280.364438)
			(xy 140.274802 -280.464514)
		)
		(stroke
			(width 0)
			(type solid)
		)
		(fill yes)
		(layer "In2.Cu")
		(net "M_I_CPU1_SB_DQ<11>")
	)
	(gr_poly
		(pts
			(xy 140.374878 -279.148286) (xy 140.274802 -279.04821) (xy 140.174726 -279.148286) (xy 140.174726 -279.192736)
			(xy 140.374878 -279.192736)
		)
		(stroke
			(width 0)
			(type solid)
		)
		(fill yes)
		(layer "In2.Cu")
		(net "M_I_CPU1_SB_DQ<8>")
	)
	(gr_poly
		(pts
			(xy 140.374878 -278.744426) (xy 140.374878 -278.699976) (xy 140.174726 -278.699976) (xy 140.174726 -278.744426)
			(xy 140.274802 -278.844502)
		)
		(stroke
			(width 0)
			(type solid)
		)
		(fill yes)
		(layer "In2.Cu")
		(net "M_I_CPU1_SB_DQ<7>")
	)
	(gr_poly
		(pts
			(xy 140.374878 -277.528274) (xy 140.274802 -277.428198) (xy 140.174726 -277.528274) (xy 140.174726 -277.572724)
			(xy 140.374878 -277.572724)
		)
		(stroke
			(width 0)
			(type solid)
		)
		(fill yes)
		(layer "In2.Cu")
		(net "M_I_CPU1_SB_DQ<4>")
	)
	(gr_poly
		(pts
			(xy 140.374878 -277.124668) (xy 140.374878 -277.076916) (xy 140.174726 -277.076916) (xy 140.174726 -277.124668)
			(xy 140.274802 -277.22449)
		)
		(stroke
			(width 0)
			(type solid)
		)
		(fill yes)
		(layer "In2.Cu")
		(net "M_I_CPU1_SB_DQS_DP<5>")
	)
	(gr_poly
		(pts
			(xy 140.374878 -275.908008) (xy 140.274802 -275.808186) (xy 140.174726 -275.908008) (xy 140.174726 -275.95576)
			(xy 140.374878 -275.95576)
		)
		(stroke
			(width 0)
			(type solid)
		)
		(fill yes)
		(layer "In2.Cu")
		(net "M_I_CPU1_SB_DQS_DP<0>")
	)
	(gr_poly
		(pts
			(xy 140.374878 -275.504402) (xy 140.374878 -275.459952) (xy 140.174726 -275.459952) (xy 140.174726 -275.504402)
			(xy 140.274802 -275.604478)
		)
		(stroke
			(width 0)
			(type solid)
		)
		(fill yes)
		(layer "In2.Cu")
		(net "M_I_CPU1_SB_DQ<3>")
	)
	(gr_poly
		(pts
			(xy 140.374878 -274.28825) (xy 140.274802 -274.188174) (xy 140.174726 -274.28825) (xy 140.174726 -274.3327)
			(xy 140.374878 -274.3327)
		)
		(stroke
			(width 0)
			(type solid)
		)
		(fill yes)
		(layer "In2.Cu")
		(net "M_I_CPU1_SB_DQ<0>")
	)
	(gr_poly
		(pts
			(xy 140.374878 -273.88439) (xy 140.374878 -273.83994) (xy 140.174726 -273.83994) (xy 140.174726 -273.88439)
			(xy 140.274802 -273.984466)
		)
		(stroke
			(width 0)
			(type solid)
		)
		(fill yes)
		(layer "In2.Cu")
		(net "M_I_CPU1_SB_CB<3>")
	)
	(gr_poly
		(pts
			(xy 140.374878 -272.668238) (xy 140.274802 -272.568162) (xy 140.174726 -272.668238) (xy 140.174726 -272.712688)
			(xy 140.374878 -272.712688)
		)
		(stroke
			(width 0)
			(type solid)
		)
		(fill yes)
		(layer "In2.Cu")
		(net "M_I_CPU1_SB_CB<0>")
	)
	(gr_poly
		(pts
			(xy 140.374878 -272.264632) (xy 140.374878 -272.21688) (xy 140.174726 -272.21688) (xy 140.174726 -272.264632)
			(xy 140.274802 -272.364454)
		)
		(stroke
			(width 0)
			(type solid)
		)
		(fill yes)
		(layer "In2.Cu")
		(net "M_I_CPU1_SB_DQS_DP<4>")
	)
	(gr_poly
		(pts
			(xy 140.374878 -271.047972) (xy 140.274802 -270.94815) (xy 140.174726 -271.047972) (xy 140.174726 -271.095724)
			(xy 140.374878 -271.095724)
		)
		(stroke
			(width 0)
			(type solid)
		)
		(fill yes)
		(layer "In2.Cu")
		(net "M_I_CPU1_SB_DQS_DP<9>")
	)
	(gr_poly
		(pts
			(xy 140.374878 -270.644366) (xy 140.374878 -270.599916) (xy 140.174726 -270.599916) (xy 140.174726 -270.644366)
			(xy 140.274802 -270.744442)
		)
		(stroke
			(width 0)
			(type solid)
		)
		(fill yes)
		(layer "In2.Cu")
		(net "M_I_CPU1_SB_CB<7>")
	)
	(gr_poly
		(pts
			(xy 140.374878 -269.428214) (xy 140.274802 -269.328138) (xy 140.174726 -269.428214) (xy 140.174726 -269.472664)
			(xy 140.374878 -269.472664)
		)
		(stroke
			(width 0)
			(type solid)
		)
		(fill yes)
		(layer "In2.Cu")
		(net "M_I_CPU1_SB_CB<4>")
	)
	(gr_poly
		(pts
			(xy 140.374878 -267.404342) (xy 140.374878 -267.359892) (xy 140.174726 -267.359892) (xy 140.174726 -267.404342)
			(xy 140.274802 -267.504418)
		)
		(stroke
			(width 0)
			(type solid)
		)
		(fill yes)
		(layer "In2.Cu")
		(net "M_I_CPU1_SB_RSP<0>")
	)
	(gr_poly
		(pts
			(xy 140.374878 -265.78433) (xy 140.374878 -265.73988) (xy 140.174726 -265.73988) (xy 140.174726 -265.78433)
			(xy 140.274802 -265.884406)
		)
		(stroke
			(width 0)
			(type solid)
		)
		(fill yes)
		(layer "In2.Cu")
		(net "M_I_CPU1_SB_CS_N<0>")
	)
	(gr_poly
		(pts
			(xy 140.374878 -264.568178) (xy 140.274802 -264.468102) (xy 140.174726 -264.568178) (xy 140.174726 -264.612628)
			(xy 140.374878 -264.612628)
		)
		(stroke
			(width 0)
			(type solid)
		)
		(fill yes)
		(layer "In2.Cu")
		(net "M_I_CPU1_SB_CA<6>")
	)
	(gr_poly
		(pts
			(xy 140.374878 -264.164318) (xy 140.374878 -264.119868) (xy 140.174726 -264.119868) (xy 140.174726 -264.164318)
			(xy 140.274802 -264.264394)
		)
		(stroke
			(width 0)
			(type solid)
		)
		(fill yes)
		(layer "In2.Cu")
		(net "M_I_CPU1_SB_CA<5>")
	)
	(gr_poly
		(pts
			(xy 140.374878 -262.948166) (xy 140.274802 -262.84809) (xy 140.174726 -262.948166) (xy 140.174726 -262.992616)
			(xy 140.374878 -262.992616)
		)
		(stroke
			(width 0)
			(type solid)
		)
		(fill yes)
		(layer "In2.Cu")
		(net "M_I_CPU1_SB_CA<2>")
	)
	(gr_poly
		(pts
			(xy 140.374878 -262.544306) (xy 140.374878 -262.499856) (xy 140.174726 -262.499856) (xy 140.174726 -262.544306)
			(xy 140.274802 -262.644382)
		)
		(stroke
			(width 0)
			(type solid)
		)
		(fill yes)
		(layer "In2.Cu")
		(net "M_I_CPU1_SB_CA<1>")
	)
	(gr_poly
		(pts
			(xy 140.463778 -224.696274) (xy 140.42517 -224.674176) (xy 140.288518 -224.710752) (xy 140.325348 -224.847404)
			(xy 140.363702 -224.869502)
		)
		(stroke
			(width 0)
			(type solid)
		)
		(fill yes)
		(layer "In2.Cu")
		(net "M_I_CPU1_SA_DQ<1>")
	)
	(gr_poly
		(pts
			(xy 140.464032 -223.074992) (xy 140.425678 -223.05264) (xy 140.289026 -223.089216) (xy 140.325602 -223.225868)
			(xy 140.36421 -223.24822)
		)
		(stroke
			(width 0)
			(type solid)
		)
		(fill yes)
		(layer "In2.Cu")
		(net "M_I_CPU1_SA_DQ<0>")
	)
	(gr_poly
		(pts
			(xy 140.466826 -226.31654) (xy 140.425678 -226.292664) (xy 140.289026 -226.329494) (xy 140.325602 -226.465892)
			(xy 140.367004 -226.489768)
		)
		(stroke
			(width 0)
			(type solid)
		)
		(fill yes)
		(layer "In2.Cu")
		(net "M_I_CPU1_SA_DQS_DP<0>")
	)
	(gr_poly
		(pts
			(xy 140.544804 -256.026158) (xy 140.444728 -255.926336) (xy 140.344652 -256.026158) (xy 140.344652 -256.07391)
			(xy 140.544804 -256.07391)
		)
		(stroke
			(width 0)
			(type solid)
		)
		(fill yes)
		(layer "In2.Cu")
		(net "M_I_CPU1_CLK_DP<0>")
	)
	(gr_poly
		(pts
			(xy 140.544804 -255.622552) (xy 140.544804 -255.578102) (xy 140.344652 -255.578102) (xy 140.344652 -255.622552)
			(xy 140.444728 -255.722628)
		)
		(stroke
			(width 0)
			(type solid)
		)
		(fill yes)
		(layer "In2.Cu")
		(net "M_I_CPU1_SA_PAR")
	)
	(gr_poly
		(pts
			(xy 140.544804 -254.4064) (xy 140.444728 -254.306324) (xy 140.344652 -254.4064) (xy 140.344652 -254.45085)
			(xy 140.544804 -254.45085)
		)
		(stroke
			(width 0)
			(type solid)
		)
		(fill yes)
		(layer "In2.Cu")
		(net "M_I_CPU1_SA_CA<4>")
	)
	(gr_poly
		(pts
			(xy 140.544804 -254.00254) (xy 140.544804 -253.95809) (xy 140.344652 -253.95809) (xy 140.344652 -254.00254)
			(xy 140.444728 -254.102616)
		)
		(stroke
			(width 0)
			(type solid)
		)
		(fill yes)
		(layer "In2.Cu")
		(net "M_I_CPU1_SA_CA<3>")
	)
	(gr_poly
		(pts
			(xy 140.544804 -252.786388) (xy 140.444728 -252.686312) (xy 140.344652 -252.786388) (xy 140.344652 -252.830838)
			(xy 140.544804 -252.830838)
		)
		(stroke
			(width 0)
			(type solid)
		)
		(fill yes)
		(layer "In2.Cu")
		(net "M_I_CPU1_SA_CA<0>")
	)
	(gr_poly
		(pts
			(xy 140.544804 -251.166376) (xy 140.444728 -251.0663) (xy 140.344652 -251.166376) (xy 140.344652 -251.210826)
			(xy 140.544804 -251.210826)
		)
		(stroke
			(width 0)
			(type solid)
		)
		(fill yes)
		(layer "In2.Cu")
		(net "M_I_CPU1_SA_CS_N<0>")
	)
	(gr_poly
		(pts
			(xy 140.544804 -250.762516) (xy 140.544804 -250.718066) (xy 140.344652 -250.718066) (xy 140.344652 -250.762516)
			(xy 140.444728 -250.862592)
		)
		(stroke
			(width 0)
			(type solid)
		)
		(fill yes)
		(layer "In2.Cu")
		(net "M_I_CPU1_RESET_N")
	)
	(gr_poly
		(pts
			(xy 140.544804 -249.142504) (xy 140.544804 -249.098054) (xy 140.344652 -249.098054) (xy 140.344652 -249.142504)
			(xy 140.444728 -249.24258)
		)
		(stroke
			(width 0)
			(type solid)
		)
		(fill yes)
		(layer "In2.Cu")
		(net "M_I_CPU1_SA_CB<7>")
	)
	(gr_poly
		(pts
			(xy 140.544804 -247.926352) (xy 140.444728 -247.826276) (xy 140.344652 -247.926352) (xy 140.344652 -247.970802)
			(xy 140.544804 -247.970802)
		)
		(stroke
			(width 0)
			(type solid)
		)
		(fill yes)
		(layer "In2.Cu")
		(net "M_I_CPU1_SA_CB<4>")
	)
	(gr_poly
		(pts
			(xy 140.544804 -247.522746) (xy 140.544804 -247.474994) (xy 140.344652 -247.474994) (xy 140.344652 -247.522746)
			(xy 140.444728 -247.622568)
		)
		(stroke
			(width 0)
			(type solid)
		)
		(fill yes)
		(layer "In2.Cu")
		(net "M_I_CPU1_SA_DQS_DP<9>")
	)
	(gr_poly
		(pts
			(xy 140.544804 -246.306086) (xy 140.444728 -246.206264) (xy 140.344652 -246.306086) (xy 140.344652 -246.353838)
			(xy 140.544804 -246.353838)
		)
		(stroke
			(width 0)
			(type solid)
		)
		(fill yes)
		(layer "In2.Cu")
		(net "M_I_CPU1_SA_DQS_DP<4>")
	)
	(gr_poly
		(pts
			(xy 140.544804 -245.90248) (xy 140.544804 -245.85803) (xy 140.344652 -245.85803) (xy 140.344652 -245.90248)
			(xy 140.444728 -246.002556)
		)
		(stroke
			(width 0)
			(type solid)
		)
		(fill yes)
		(layer "In2.Cu")
		(net "M_I_CPU1_SA_CB<3>")
	)
	(gr_poly
		(pts
			(xy 140.544804 -244.686328) (xy 140.444728 -244.586252) (xy 140.344652 -244.686328) (xy 140.344652 -244.730778)
			(xy 140.544804 -244.730778)
		)
		(stroke
			(width 0)
			(type solid)
		)
		(fill yes)
		(layer "In2.Cu")
		(net "M_I_CPU1_SA_CB<0>")
	)
	(gr_poly
		(pts
			(xy 140.544804 -244.282468) (xy 140.544804 -244.238018) (xy 140.344652 -244.238018) (xy 140.344652 -244.282468)
			(xy 140.444728 -244.382544)
		)
		(stroke
			(width 0)
			(type solid)
		)
		(fill yes)
		(layer "In2.Cu")
		(net "M_I_CPU1_SA_DQ<31>")
	)
	(gr_poly
		(pts
			(xy 140.544804 -243.066316) (xy 140.444728 -242.96624) (xy 140.344652 -243.066316) (xy 140.344652 -243.110766)
			(xy 140.544804 -243.110766)
		)
		(stroke
			(width 0)
			(type solid)
		)
		(fill yes)
		(layer "In2.Cu")
		(net "M_I_CPU1_SA_DQ<28>")
	)
	(gr_poly
		(pts
			(xy 140.544804 -242.66271) (xy 140.544804 -242.614958) (xy 140.344652 -242.614958) (xy 140.344652 -242.66271)
			(xy 140.444728 -242.762532)
		)
		(stroke
			(width 0)
			(type solid)
		)
		(fill yes)
		(layer "In2.Cu")
		(net "M_I_CPU1_SA_DQS_DP<8>")
	)
	(gr_poly
		(pts
			(xy 140.544804 -241.44605) (xy 140.444728 -241.346228) (xy 140.344652 -241.44605) (xy 140.344652 -241.493802)
			(xy 140.544804 -241.493802)
		)
		(stroke
			(width 0)
			(type solid)
		)
		(fill yes)
		(layer "In2.Cu")
		(net "M_I_CPU1_SA_DQS_DP<3>")
	)
	(gr_poly
		(pts
			(xy 140.544804 -241.042444) (xy 140.544804 -240.997994) (xy 140.344652 -240.997994) (xy 140.344652 -241.042444)
			(xy 140.444728 -241.14252)
		)
		(stroke
			(width 0)
			(type solid)
		)
		(fill yes)
		(layer "In2.Cu")
		(net "M_I_CPU1_SA_DQ<27>")
	)
	(gr_poly
		(pts
			(xy 140.544804 -239.826292) (xy 140.444728 -239.726216) (xy 140.344652 -239.826292) (xy 140.344652 -239.870742)
			(xy 140.544804 -239.870742)
		)
		(stroke
			(width 0)
			(type solid)
		)
		(fill yes)
		(layer "In2.Cu")
		(net "M_I_CPU1_SA_DQ<24>")
	)
	(gr_poly
		(pts
			(xy 140.544804 -239.422432) (xy 140.544804 -239.377982) (xy 140.344652 -239.377982) (xy 140.344652 -239.422432)
			(xy 140.444728 -239.522508)
		)
		(stroke
			(width 0)
			(type solid)
		)
		(fill yes)
		(layer "In2.Cu")
		(net "M_I_CPU1_SA_DQ<23>")
	)
	(gr_poly
		(pts
			(xy 140.544804 -238.20628) (xy 140.444728 -238.106204) (xy 140.344652 -238.20628) (xy 140.344652 -238.25073)
			(xy 140.544804 -238.25073)
		)
		(stroke
			(width 0)
			(type solid)
		)
		(fill yes)
		(layer "In2.Cu")
		(net "M_I_CPU1_SA_DQ<20>")
	)
	(gr_poly
		(pts
			(xy 140.544804 -237.802674) (xy 140.544804 -237.754922) (xy 140.344652 -237.754922) (xy 140.344652 -237.802674)
			(xy 140.444728 -237.902496)
		)
		(stroke
			(width 0)
			(type solid)
		)
		(fill yes)
		(layer "In2.Cu")
		(net "M_I_CPU1_SA_DQS_DP<7>")
	)
	(gr_poly
		(pts
			(xy 140.544804 -236.586014) (xy 140.444728 -236.486192) (xy 140.344652 -236.586014) (xy 140.344652 -236.633766)
			(xy 140.544804 -236.633766)
		)
		(stroke
			(width 0)
			(type solid)
		)
		(fill yes)
		(layer "In2.Cu")
		(net "M_I_CPU1_SA_DQS_DP<2>")
	)
	(gr_poly
		(pts
			(xy 140.544804 -236.182408) (xy 140.544804 -236.137958) (xy 140.344652 -236.137958) (xy 140.344652 -236.182408)
			(xy 140.444728 -236.282484)
		)
		(stroke
			(width 0)
			(type solid)
		)
		(fill yes)
		(layer "In2.Cu")
		(net "M_I_CPU1_SA_DQ<19>")
	)
	(gr_poly
		(pts
			(xy 140.544804 -234.966256) (xy 140.444728 -234.86618) (xy 140.344652 -234.966256) (xy 140.344652 -235.010706)
			(xy 140.544804 -235.010706)
		)
		(stroke
			(width 0)
			(type solid)
		)
		(fill yes)
		(layer "In2.Cu")
		(net "M_I_CPU1_SA_DQ<16>")
	)
	(gr_poly
		(pts
			(xy 140.544804 -234.562396) (xy 140.544804 -234.517946) (xy 140.344652 -234.517946) (xy 140.344652 -234.562396)
			(xy 140.444728 -234.662472)
		)
		(stroke
			(width 0)
			(type solid)
		)
		(fill yes)
		(layer "In2.Cu")
		(net "M_I_CPU1_SA_DQ<15>")
	)
	(gr_poly
		(pts
			(xy 140.544804 -233.346244) (xy 140.444728 -233.246168) (xy 140.344652 -233.346244) (xy 140.344652 -233.390694)
			(xy 140.544804 -233.390694)
		)
		(stroke
			(width 0)
			(type solid)
		)
		(fill yes)
		(layer "In2.Cu")
		(net "M_I_CPU1_SA_DQ<12>")
	)
	(gr_poly
		(pts
			(xy 140.544804 -232.942638) (xy 140.544804 -232.894886) (xy 140.344652 -232.894886) (xy 140.344652 -232.942638)
			(xy 140.444728 -233.04246)
		)
		(stroke
			(width 0)
			(type solid)
		)
		(fill yes)
		(layer "In2.Cu")
		(net "M_I_CPU1_SA_DQS_DP<6>")
	)
	(gr_poly
		(pts
			(xy 140.544804 -231.725978) (xy 140.444728 -231.626156) (xy 140.344652 -231.725978) (xy 140.344652 -231.77373)
			(xy 140.544804 -231.77373)
		)
		(stroke
			(width 0)
			(type solid)
		)
		(fill yes)
		(layer "In2.Cu")
		(net "M_I_CPU1_SA_DQS_DP<1>")
	)
	(gr_poly
		(pts
			(xy 140.544804 -231.322626) (xy 140.544804 -231.278176) (xy 140.344652 -231.278176) (xy 140.344652 -231.322626)
			(xy 140.444728 -231.422702)
		)
		(stroke
			(width 0)
			(type solid)
		)
		(fill yes)
		(layer "In2.Cu")
		(net "M_I_CPU1_SA_DQ<11>")
	)
	(gr_poly
		(pts
			(xy 140.544804 -230.10622) (xy 140.444728 -230.006144) (xy 140.344652 -230.10622) (xy 140.344652 -230.15067)
			(xy 140.544804 -230.15067)
		)
		(stroke
			(width 0)
			(type solid)
		)
		(fill yes)
		(layer "In2.Cu")
		(net "M_I_CPU1_SA_DQ<8>")
	)
	(gr_poly
		(pts
			(xy 140.544804 -229.702614) (xy 140.544804 -229.658164) (xy 140.344652 -229.658164) (xy 140.344652 -229.702614)
			(xy 140.444728 -229.80269)
		)
		(stroke
			(width 0)
			(type solid)
		)
		(fill yes)
		(layer "In2.Cu")
		(net "M_I_CPU1_SA_DQ<7>")
	)
	(gr_poly
		(pts
			(xy 140.544804 -228.486462) (xy 140.444728 -228.386386) (xy 140.344652 -228.486462) (xy 140.344652 -228.530912)
			(xy 140.544804 -228.530912)
		)
		(stroke
			(width 0)
			(type solid)
		)
		(fill yes)
		(layer "In2.Cu")
		(net "M_I_CPU1_SA_DQ<4>")
	)
	(gr_poly
		(pts
			(xy 140.544804 -228.082856) (xy 140.544804 -228.035104) (xy 140.344652 -228.035104) (xy 140.344652 -228.082856)
			(xy 140.444728 -228.182678)
		)
		(stroke
			(width 0)
			(type solid)
		)
		(fill yes)
		(layer "In2.Cu")
		(net "M_I_CPU1_SA_DQS_DP<5>")
	)
	(gr_poly
		(pts
			(xy 140.600176 -223.759776) (xy 140.5636 -223.623124) (xy 140.525246 -223.600772) (xy 140.42517 -223.774)
			(xy 140.463524 -223.796352)
		)
		(stroke
			(width 0)
			(type solid)
		)
		(fill yes)
		(layer "In2.Cu")
		(net "M_I_CPU1_SA_DQ<2>")
	)
	(gr_poly
		(pts
			(xy 140.600684 -226.999546) (xy 140.564108 -226.863148) (xy 140.522706 -226.839272) (xy 140.422884 -227.0125)
			(xy 140.464032 -227.036376)
		)
		(stroke
			(width 0)
			(type solid)
		)
		(fill yes)
		(layer "In2.Cu")
		(net "M_I_CPU1_SA_DQS_DN<0>")
	)
	(gr_poly
		(pts
			(xy 140.600938 -225.379026) (xy 140.564108 -225.242374) (xy 140.525754 -225.220022) (xy 140.425678 -225.39325)
			(xy 140.464286 -225.415602)
		)
		(stroke
			(width 0)
			(type solid)
		)
		(fill yes)
		(layer "In2.Cu")
		(net "M_I_CPU1_SA_DQ<3>")
	)
	(gr_poly
		(pts
			(xy 140.844778 -292.918134) (xy 140.744702 -292.818058) (xy 140.644626 -292.918134) (xy 140.644626 -292.962584)
			(xy 140.844778 -292.962584)
		)
		(stroke
			(width 0)
			(type solid)
		)
		(fill yes)
		(layer "In2.Cu")
		(net "M_I_CPU1_SB_DQ<29>")
	)
	(gr_poly
		(pts
			(xy 140.844778 -292.514274) (xy 140.844778 -292.469824) (xy 140.644626 -292.469824) (xy 140.644626 -292.514274)
			(xy 140.744702 -292.61435)
		)
		(stroke
			(width 0)
			(type solid)
		)
		(fill yes)
		(layer "In2.Cu")
		(net "M_I_CPU1_SB_DQ<30>")
	)
	(gr_poly
		(pts
			(xy 140.844778 -291.297868) (xy 140.744702 -291.198046) (xy 140.644626 -291.297868) (xy 140.644626 -291.34562)
			(xy 140.844778 -291.34562)
		)
		(stroke
			(width 0)
			(type solid)
		)
		(fill yes)
		(layer "In2.Cu")
		(net "M_I_CPU1_SB_DQS_DN<8>")
	)
	(gr_poly
		(pts
			(xy 140.844778 -290.894516) (xy 140.844778 -290.846764) (xy 140.644626 -290.846764) (xy 140.644626 -290.894516)
			(xy 140.744702 -290.994338)
		)
		(stroke
			(width 0)
			(type solid)
		)
		(fill yes)
		(layer "In2.Cu")
		(net "M_I_CPU1_SB_DQS_DN<3>")
	)
	(gr_poly
		(pts
			(xy 140.844778 -289.67811) (xy 140.744702 -289.578034) (xy 140.644626 -289.67811) (xy 140.644626 -289.72256)
			(xy 140.844778 -289.72256)
		)
		(stroke
			(width 0)
			(type solid)
		)
		(fill yes)
		(layer "In2.Cu")
		(net "M_I_CPU1_SB_DQ<25>")
	)
	(gr_poly
		(pts
			(xy 140.844778 -289.27425) (xy 140.844778 -289.2298) (xy 140.644626 -289.2298) (xy 140.644626 -289.27425)
			(xy 140.744702 -289.374326)
		)
		(stroke
			(width 0)
			(type solid)
		)
		(fill yes)
		(layer "In2.Cu")
		(net "M_I_CPU1_SB_DQ<26>")
	)
	(gr_poly
		(pts
			(xy 140.844778 -288.058098) (xy 140.744702 -287.958022) (xy 140.644626 -288.058098) (xy 140.644626 -288.102548)
			(xy 140.844778 -288.102548)
		)
		(stroke
			(width 0)
			(type solid)
		)
		(fill yes)
		(layer "In2.Cu")
		(net "M_I_CPU1_SB_DQ<21>")
	)
	(gr_poly
		(pts
			(xy 140.844778 -287.654492) (xy 140.844778 -287.610042) (xy 140.644626 -287.610042) (xy 140.644626 -287.654492)
			(xy 140.744702 -287.754568)
		)
		(stroke
			(width 0)
			(type solid)
		)
		(fill yes)
		(layer "In2.Cu")
		(net "M_I_CPU1_SB_DQ<22>")
	)
	(gr_poly
		(pts
			(xy 140.844778 -286.438086) (xy 140.744702 -286.33801) (xy 140.644626 -286.438086) (xy 140.644626 -286.485838)
			(xy 140.844778 -286.485838)
		)
		(stroke
			(width 0)
			(type solid)
		)
		(fill yes)
		(layer "In2.Cu")
		(net "M_I_CPU1_SB_DQS_DN<7>")
	)
	(gr_poly
		(pts
			(xy 140.844778 -286.034734) (xy 140.844778 -285.986982) (xy 140.644626 -285.986982) (xy 140.644626 -286.034734)
			(xy 140.744702 -286.134556)
		)
		(stroke
			(width 0)
			(type solid)
		)
		(fill yes)
		(layer "In2.Cu")
		(net "M_I_CPU1_SB_DQS_DN<2>")
	)
	(gr_poly
		(pts
			(xy 140.844778 -284.818328) (xy 140.744702 -284.718252) (xy 140.644626 -284.818328) (xy 140.644626 -284.862778)
			(xy 140.844778 -284.862778)
		)
		(stroke
			(width 0)
			(type solid)
		)
		(fill yes)
		(layer "In2.Cu")
		(net "M_I_CPU1_SB_DQ<17>")
	)
	(gr_poly
		(pts
			(xy 140.844778 -284.414468) (xy 140.844778 -284.370018) (xy 140.644626 -284.370018) (xy 140.644626 -284.414468)
			(xy 140.744702 -284.514544)
		)
		(stroke
			(width 0)
			(type solid)
		)
		(fill yes)
		(layer "In2.Cu")
		(net "M_I_CPU1_SB_DQ<18>")
	)
	(gr_poly
		(pts
			(xy 140.844778 -283.198316) (xy 140.744702 -283.09824) (xy 140.644626 -283.198316) (xy 140.644626 -283.242766)
			(xy 140.844778 -283.242766)
		)
		(stroke
			(width 0)
			(type solid)
		)
		(fill yes)
		(layer "In2.Cu")
		(net "M_I_CPU1_SB_DQ<13>")
	)
	(gr_poly
		(pts
			(xy 140.844778 -282.794456) (xy 140.844778 -282.750006) (xy 140.644626 -282.750006) (xy 140.644626 -282.794456)
			(xy 140.744702 -282.894532)
		)
		(stroke
			(width 0)
			(type solid)
		)
		(fill yes)
		(layer "In2.Cu")
		(net "M_I_CPU1_SB_DQ<14>")
	)
	(gr_poly
		(pts
			(xy 140.844778 -281.57805) (xy 140.744702 -281.478228) (xy 140.644626 -281.57805) (xy 140.644626 -281.625802)
			(xy 140.844778 -281.625802)
		)
		(stroke
			(width 0)
			(type solid)
		)
		(fill yes)
		(layer "In2.Cu")
		(net "M_I_CPU1_SB_DQS_DN<6>")
	)
	(gr_poly
		(pts
			(xy 140.844778 -281.174698) (xy 140.844778 -281.126946) (xy 140.644626 -281.126946) (xy 140.644626 -281.174698)
			(xy 140.744702 -281.27452)
		)
		(stroke
			(width 0)
			(type solid)
		)
		(fill yes)
		(layer "In2.Cu")
		(net "M_I_CPU1_SB_DQS_DN<1>")
	)
	(gr_poly
		(pts
			(xy 140.844778 -279.958292) (xy 140.744702 -279.858216) (xy 140.644626 -279.958292) (xy 140.644626 -280.002742)
			(xy 140.844778 -280.002742)
		)
		(stroke
			(width 0)
			(type solid)
		)
		(fill yes)
		(layer "In2.Cu")
		(net "M_I_CPU1_SB_DQ<9>")
	)
	(gr_poly
		(pts
			(xy 140.844778 -279.554432) (xy 140.844778 -279.509982) (xy 140.644626 -279.509982) (xy 140.644626 -279.554432)
			(xy 140.744702 -279.654508)
		)
		(stroke
			(width 0)
			(type solid)
		)
		(fill yes)
		(layer "In2.Cu")
		(net "M_I_CPU1_SB_DQ<10>")
	)
	(gr_poly
		(pts
			(xy 140.844778 -278.33828) (xy 140.744702 -278.238204) (xy 140.644626 -278.33828) (xy 140.644626 -278.38273)
			(xy 140.844778 -278.38273)
		)
		(stroke
			(width 0)
			(type solid)
		)
		(fill yes)
		(layer "In2.Cu")
		(net "M_I_CPU1_SB_DQ<5>")
	)
	(gr_poly
		(pts
			(xy 140.844778 -277.93442) (xy 140.844778 -277.88997) (xy 140.644626 -277.88997) (xy 140.644626 -277.93442)
			(xy 140.744702 -278.034496)
		)
		(stroke
			(width 0)
			(type solid)
		)
		(fill yes)
		(layer "In2.Cu")
		(net "M_I_CPU1_SB_DQ<6>")
	)
	(gr_poly
		(pts
			(xy 140.844778 -276.718014) (xy 140.744702 -276.618192) (xy 140.644626 -276.718014) (xy 140.644626 -276.765766)
			(xy 140.844778 -276.765766)
		)
		(stroke
			(width 0)
			(type solid)
		)
		(fill yes)
		(layer "In2.Cu")
		(net "M_I_CPU1_SB_DQS_DN<5>")
	)
	(gr_poly
		(pts
			(xy 140.844778 -276.314662) (xy 140.844778 -276.26691) (xy 140.644626 -276.26691) (xy 140.644626 -276.314662)
			(xy 140.744702 -276.414484)
		)
		(stroke
			(width 0)
			(type solid)
		)
		(fill yes)
		(layer "In2.Cu")
		(net "M_I_CPU1_SB_DQS_DN<0>")
	)
	(gr_poly
		(pts
			(xy 140.844778 -275.098256) (xy 140.744702 -274.99818) (xy 140.644626 -275.098256) (xy 140.644626 -275.142706)
			(xy 140.844778 -275.142706)
		)
		(stroke
			(width 0)
			(type solid)
		)
		(fill yes)
		(layer "In2.Cu")
		(net "M_I_CPU1_SB_DQ<1>")
	)
	(gr_poly
		(pts
			(xy 140.844778 -274.694396) (xy 140.844778 -274.649946) (xy 140.644626 -274.649946) (xy 140.644626 -274.694396)
			(xy 140.744702 -274.794472)
		)
		(stroke
			(width 0)
			(type solid)
		)
		(fill yes)
		(layer "In2.Cu")
		(net "M_I_CPU1_SB_DQ<2>")
	)
	(gr_poly
		(pts
			(xy 140.844778 -273.478244) (xy 140.744702 -273.378168) (xy 140.644626 -273.478244) (xy 140.644626 -273.522694)
			(xy 140.844778 -273.522694)
		)
		(stroke
			(width 0)
			(type solid)
		)
		(fill yes)
		(layer "In2.Cu")
		(net "M_I_CPU1_SB_CB<1>")
	)
	(gr_poly
		(pts
			(xy 140.844778 -273.074384) (xy 140.844778 -273.029934) (xy 140.644626 -273.029934) (xy 140.644626 -273.074384)
			(xy 140.744702 -273.17446)
		)
		(stroke
			(width 0)
			(type solid)
		)
		(fill yes)
		(layer "In2.Cu")
		(net "M_I_CPU1_SB_CB<2>")
	)
	(gr_poly
		(pts
			(xy 140.844778 -271.857978) (xy 140.744702 -271.758156) (xy 140.644626 -271.857978) (xy 140.644626 -271.90573)
			(xy 140.844778 -271.90573)
		)
		(stroke
			(width 0)
			(type solid)
		)
		(fill yes)
		(layer "In2.Cu")
		(net "M_I_CPU1_SB_DQS_DN<4>")
	)
	(gr_poly
		(pts
			(xy 140.844778 -271.454626) (xy 140.844778 -271.406874) (xy 140.644626 -271.406874) (xy 140.644626 -271.454626)
			(xy 140.744702 -271.554448)
		)
		(stroke
			(width 0)
			(type solid)
		)
		(fill yes)
		(layer "In2.Cu")
		(net "M_I_CPU1_SB_DQS_DN<9>")
	)
	(gr_poly
		(pts
			(xy 140.844778 -270.23822) (xy 140.744702 -270.138144) (xy 140.644626 -270.23822) (xy 140.644626 -270.28267)
			(xy 140.844778 -270.28267)
		)
		(stroke
			(width 0)
			(type solid)
		)
		(fill yes)
		(layer "In2.Cu")
		(net "M_I_CPU1_SB_CB<5>")
	)
	(gr_poly
		(pts
			(xy 140.844778 -269.83436) (xy 140.844778 -269.78991) (xy 140.644626 -269.78991) (xy 140.644626 -269.83436)
			(xy 140.744702 -269.934436)
		)
		(stroke
			(width 0)
			(type solid)
		)
		(fill yes)
		(layer "In2.Cu")
		(net "M_I_CPU1_SB_CB<6>")
	)
	(gr_poly
		(pts
			(xy 140.844778 -266.998196) (xy 140.744702 -266.89812) (xy 140.644626 -266.998196) (xy 140.644626 -267.042646)
			(xy 140.844778 -267.042646)
		)
		(stroke
			(width 0)
			(type solid)
		)
		(fill yes)
		(layer "In2.Cu")
		(net "M_I_CPU1_SA_RSP<0>")
	)
	(gr_poly
		(pts
			(xy 140.844778 -266.594336) (xy 140.844778 -266.549886) (xy 140.644626 -266.549886) (xy 140.644626 -266.594336)
			(xy 140.744702 -266.694412)
		)
		(stroke
			(width 0)
			(type solid)
		)
		(fill yes)
		(layer "In2.Cu")
		(net "M_I_CPU1_SB_CS_N<1>")
	)
	(gr_poly
		(pts
			(xy 140.844778 -265.378184) (xy 140.744702 -265.278108) (xy 140.644626 -265.378184) (xy 140.644626 -265.422634)
			(xy 140.844778 -265.422634)
		)
		(stroke
			(width 0)
			(type solid)
		)
		(fill yes)
		(layer "In2.Cu")
		(net "M_I_CPU1_SB_PAR")
	)
	(gr_poly
		(pts
			(xy 140.844778 -263.758172) (xy 140.744702 -263.658096) (xy 140.644626 -263.758172) (xy 140.644626 -263.802622)
			(xy 140.844778 -263.802622)
		)
		(stroke
			(width 0)
			(type solid)
		)
		(fill yes)
		(layer "In2.Cu")
		(net "M_I_CPU1_SB_CA<4>")
	)
	(gr_poly
		(pts
			(xy 140.844778 -263.354312) (xy 140.844778 -263.309862) (xy 140.644626 -263.309862) (xy 140.644626 -263.354312)
			(xy 140.744702 -263.454388)
		)
		(stroke
			(width 0)
			(type solid)
		)
		(fill yes)
		(layer "In2.Cu")
		(net "M_I_CPU1_SB_CA<3>")
	)
	(gr_poly
		(pts
			(xy 140.844778 -262.13816) (xy 140.744702 -262.038084) (xy 140.644626 -262.13816) (xy 140.644626 -262.18261)
			(xy 140.844778 -262.18261)
		)
		(stroke
			(width 0)
			(type solid)
		)
		(fill yes)
		(layer "In2.Cu")
		(net "M_I_CPU1_SB_CA<0>")
	)
	(gr_poly
		(pts
			(xy 140.934186 -222.264986) (xy 140.895832 -222.242634) (xy 140.75918 -222.27921) (xy 140.795756 -222.415862)
			(xy 140.834364 -222.438214)
		)
		(stroke
			(width 0)
			(type solid)
		)
		(fill yes)
		(layer "In2.Cu")
		(net "M_I_CPU1_SA_DQ<0>")
	)
	(gr_poly
		(pts
			(xy 140.93444 -223.884998) (xy 140.896086 -223.862646) (xy 140.759434 -223.899222) (xy 140.79601 -224.035874)
			(xy 140.834618 -224.058226)
		)
		(stroke
			(width 0)
			(type solid)
		)
		(fill yes)
		(layer "In2.Cu")
		(net "M_I_CPU1_SA_DQ<1>")
	)
	(gr_poly
		(pts
			(xy 140.936726 -227.126546) (xy 140.895578 -227.10267) (xy 140.758926 -227.1395) (xy 140.795502 -227.275898)
			(xy 140.836904 -227.299774)
		)
		(stroke
			(width 0)
			(type solid)
		)
		(fill yes)
		(layer "In2.Cu")
		(net "M_I_CPU1_SA_DQS_DN<5>")
	)
	(gr_poly
		(pts
			(xy 140.936726 -225.506534) (xy 140.895578 -225.482912) (xy 140.758926 -225.519488) (xy 140.795502 -225.655886)
			(xy 140.836904 -225.679762)
		)
		(stroke
			(width 0)
			(type solid)
		)
		(fill yes)
		(layer "In2.Cu")
		(net "M_I_CPU1_SA_DQS_DP<0>")
	)
	(gr_poly
		(pts
			(xy 141.014958 -256.432812) (xy 141.014958 -256.38506) (xy 140.814806 -256.38506) (xy 140.814806 -256.432812)
			(xy 140.914882 -256.532634)
		)
		(stroke
			(width 0)
			(type solid)
		)
		(fill yes)
		(layer "In2.Cu")
		(net "M_I_CPU1_CLK_DN<0>")
	)
	(gr_poly
		(pts
			(xy 141.014958 -255.216406) (xy 140.914882 -255.11633) (xy 140.814806 -255.216406) (xy 140.814806 -255.260856)
			(xy 141.014958 -255.260856)
		)
		(stroke
			(width 0)
			(type solid)
		)
		(fill yes)
		(layer "In2.Cu")
		(net "M_I_CPU1_SA_CA<6>")
	)
	(gr_poly
		(pts
			(xy 141.014958 -254.812546) (xy 141.014958 -254.768096) (xy 140.814806 -254.768096) (xy 140.814806 -254.812546)
			(xy 140.914882 -254.912622)
		)
		(stroke
			(width 0)
			(type solid)
		)
		(fill yes)
		(layer "In2.Cu")
		(net "M_I_CPU1_SA_CA<5>")
	)
	(gr_poly
		(pts
			(xy 141.014958 -253.596394) (xy 140.914882 -253.496318) (xy 140.814806 -253.596394) (xy 140.814806 -253.640844)
			(xy 141.014958 -253.640844)
		)
		(stroke
			(width 0)
			(type solid)
		)
		(fill yes)
		(layer "In2.Cu")
		(net "M_I_CPU1_SA_CA<2>")
	)
	(gr_poly
		(pts
			(xy 141.014958 -253.192534) (xy 141.014958 -253.148084) (xy 140.814806 -253.148084) (xy 140.814806 -253.192534)
			(xy 140.914882 -253.29261)
		)
		(stroke
			(width 0)
			(type solid)
		)
		(fill yes)
		(layer "In2.Cu")
		(net "M_I_CPU1_SA_CA<1>")
	)
	(gr_poly
		(pts
			(xy 141.014958 -251.976382) (xy 140.914882 -251.876306) (xy 140.814806 -251.976382) (xy 140.814806 -252.020832)
			(xy 141.014958 -252.020832)
		)
		(stroke
			(width 0)
			(type solid)
		)
		(fill yes)
		(layer "In2.Cu")
		(net "M_I_CPU1_SA_CS_N<1>")
	)
	(gr_poly
		(pts
			(xy 141.014958 -250.35637) (xy 140.914882 -250.256294) (xy 140.814806 -250.35637) (xy 140.814806 -250.40082)
			(xy 141.014958 -250.40082)
		)
		(stroke
			(width 0)
			(type solid)
		)
		(fill yes)
		(layer "In2.Cu")
		(net "M_I_CPU1_ALERT_R_N")
	)
	(gr_poly
		(pts
			(xy 141.014958 -248.736358) (xy 140.914882 -248.636282) (xy 140.814806 -248.736358) (xy 140.814806 -248.780808)
			(xy 141.014958 -248.780808)
		)
		(stroke
			(width 0)
			(type solid)
		)
		(fill yes)
		(layer "In2.Cu")
		(net "M_I_CPU1_SA_CB<5>")
	)
	(gr_poly
		(pts
			(xy 141.014958 -248.332498) (xy 141.014958 -248.288048) (xy 140.814806 -248.288048) (xy 140.814806 -248.332498)
			(xy 140.914882 -248.432574)
		)
		(stroke
			(width 0)
			(type solid)
		)
		(fill yes)
		(layer "In2.Cu")
		(net "M_I_CPU1_SA_CB<6>")
	)
	(gr_poly
		(pts
			(xy 141.014958 -247.116092) (xy 140.914882 -247.01627) (xy 140.814806 -247.116092) (xy 140.814806 -247.163844)
			(xy 141.014958 -247.163844)
		)
		(stroke
			(width 0)
			(type solid)
		)
		(fill yes)
		(layer "In2.Cu")
		(net "M_I_CPU1_SA_DQS_DN<9>")
	)
	(gr_poly
		(pts
			(xy 141.014958 -246.71274) (xy 141.014958 -246.664988) (xy 140.814806 -246.664988) (xy 140.814806 -246.71274)
			(xy 140.914882 -246.812562)
		)
		(stroke
			(width 0)
			(type solid)
		)
		(fill yes)
		(layer "In2.Cu")
		(net "M_I_CPU1_SA_DQS_DN<4>")
	)
	(gr_poly
		(pts
			(xy 141.014958 -245.496334) (xy 140.914882 -245.396258) (xy 140.814806 -245.496334) (xy 140.814806 -245.540784)
			(xy 141.014958 -245.540784)
		)
		(stroke
			(width 0)
			(type solid)
		)
		(fill yes)
		(layer "In2.Cu")
		(net "M_I_CPU1_SA_CB<1>")
	)
	(gr_poly
		(pts
			(xy 141.014958 -245.092474) (xy 141.014958 -245.048024) (xy 140.814806 -245.048024) (xy 140.814806 -245.092474)
			(xy 140.914882 -245.19255)
		)
		(stroke
			(width 0)
			(type solid)
		)
		(fill yes)
		(layer "In2.Cu")
		(net "M_I_CPU1_SA_CB<2>")
	)
	(gr_poly
		(pts
			(xy 141.014958 -243.876322) (xy 140.914882 -243.776246) (xy 140.814806 -243.876322) (xy 140.814806 -243.920772)
			(xy 141.014958 -243.920772)
		)
		(stroke
			(width 0)
			(type solid)
		)
		(fill yes)
		(layer "In2.Cu")
		(net "M_I_CPU1_SA_DQ<29>")
	)
	(gr_poly
		(pts
			(xy 141.014958 -243.472462) (xy 141.014958 -243.428012) (xy 140.814806 -243.428012) (xy 140.814806 -243.472462)
			(xy 140.914882 -243.572538)
		)
		(stroke
			(width 0)
			(type solid)
		)
		(fill yes)
		(layer "In2.Cu")
		(net "M_I_CPU1_SA_DQ<30>")
	)
	(gr_poly
		(pts
			(xy 141.014958 -242.256056) (xy 140.914882 -242.156234) (xy 140.814806 -242.256056) (xy 140.814806 -242.303808)
			(xy 141.014958 -242.303808)
		)
		(stroke
			(width 0)
			(type solid)
		)
		(fill yes)
		(layer "In2.Cu")
		(net "M_I_CPU1_SA_DQS_DN<8>")
	)
	(gr_poly
		(pts
			(xy 141.014958 -241.852704) (xy 141.014958 -241.804952) (xy 140.814806 -241.804952) (xy 140.814806 -241.852704)
			(xy 140.914882 -241.952526)
		)
		(stroke
			(width 0)
			(type solid)
		)
		(fill yes)
		(layer "In2.Cu")
		(net "M_I_CPU1_SA_DQS_DN<3>")
	)
	(gr_poly
		(pts
			(xy 141.014958 -240.636298) (xy 140.914882 -240.536222) (xy 140.814806 -240.636298) (xy 140.814806 -240.680748)
			(xy 141.014958 -240.680748)
		)
		(stroke
			(width 0)
			(type solid)
		)
		(fill yes)
		(layer "In2.Cu")
		(net "M_I_CPU1_SA_DQ<25>")
	)
	(gr_poly
		(pts
			(xy 141.014958 -240.232438) (xy 141.014958 -240.187988) (xy 140.814806 -240.187988) (xy 140.814806 -240.232438)
			(xy 140.914882 -240.332514)
		)
		(stroke
			(width 0)
			(type solid)
		)
		(fill yes)
		(layer "In2.Cu")
		(net "M_I_CPU1_SA_DQ<26>")
	)
	(gr_poly
		(pts
			(xy 141.014958 -239.016286) (xy 140.914882 -238.91621) (xy 140.814806 -239.016286) (xy 140.814806 -239.060736)
			(xy 141.014958 -239.060736)
		)
		(stroke
			(width 0)
			(type solid)
		)
		(fill yes)
		(layer "In2.Cu")
		(net "M_I_CPU1_SA_DQ<21>")
	)
	(gr_poly
		(pts
			(xy 141.014958 -238.612426) (xy 141.014958 -238.567976) (xy 140.814806 -238.567976) (xy 140.814806 -238.612426)
			(xy 140.914882 -238.712502)
		)
		(stroke
			(width 0)
			(type solid)
		)
		(fill yes)
		(layer "In2.Cu")
		(net "M_I_CPU1_SA_DQ<22>")
	)
	(gr_poly
		(pts
			(xy 141.014958 -237.39602) (xy 140.914882 -237.296198) (xy 140.814806 -237.39602) (xy 140.814806 -237.443772)
			(xy 141.014958 -237.443772)
		)
		(stroke
			(width 0)
			(type solid)
		)
		(fill yes)
		(layer "In2.Cu")
		(net "M_I_CPU1_SA_DQS_DN<7>")
	)
	(gr_poly
		(pts
			(xy 141.014958 -236.992668) (xy 141.014958 -236.944916) (xy 140.814806 -236.944916) (xy 140.814806 -236.992668)
			(xy 140.914882 -237.09249)
		)
		(stroke
			(width 0)
			(type solid)
		)
		(fill yes)
		(layer "In2.Cu")
		(net "M_I_CPU1_SA_DQS_DN<2>")
	)
	(gr_poly
		(pts
			(xy 141.014958 -235.776262) (xy 140.914882 -235.676186) (xy 140.814806 -235.776262) (xy 140.814806 -235.820712)
			(xy 141.014958 -235.820712)
		)
		(stroke
			(width 0)
			(type solid)
		)
		(fill yes)
		(layer "In2.Cu")
		(net "M_I_CPU1_SA_DQ<17>")
	)
	(gr_poly
		(pts
			(xy 141.014958 -235.372402) (xy 141.014958 -235.327952) (xy 140.814806 -235.327952) (xy 140.814806 -235.372402)
			(xy 140.914882 -235.472478)
		)
		(stroke
			(width 0)
			(type solid)
		)
		(fill yes)
		(layer "In2.Cu")
		(net "M_I_CPU1_SA_DQ<18>")
	)
	(gr_poly
		(pts
			(xy 141.014958 -234.15625) (xy 140.914882 -234.056174) (xy 140.814806 -234.15625) (xy 140.814806 -234.2007)
			(xy 141.014958 -234.2007)
		)
		(stroke
			(width 0)
			(type solid)
		)
		(fill yes)
		(layer "In2.Cu")
		(net "M_I_CPU1_SA_DQ<13>")
	)
	(gr_poly
		(pts
			(xy 141.014958 -233.75239) (xy 141.014958 -233.70794) (xy 140.814806 -233.70794) (xy 140.814806 -233.75239)
			(xy 140.914882 -233.852466)
		)
		(stroke
			(width 0)
			(type solid)
		)
		(fill yes)
		(layer "In2.Cu")
		(net "M_I_CPU1_SA_DQ<14>")
	)
	(gr_poly
		(pts
			(xy 141.014958 -232.535984) (xy 140.914882 -232.436162) (xy 140.814806 -232.535984) (xy 140.814806 -232.583736)
			(xy 141.014958 -232.583736)
		)
		(stroke
			(width 0)
			(type solid)
		)
		(fill yes)
		(layer "In2.Cu")
		(net "M_I_CPU1_SA_DQS_DN<6>")
	)
	(gr_poly
		(pts
			(xy 141.014958 -232.132632) (xy 141.014958 -232.08488) (xy 140.814806 -232.08488) (xy 140.814806 -232.132632)
			(xy 140.914882 -232.232454)
		)
		(stroke
			(width 0)
			(type solid)
		)
		(fill yes)
		(layer "In2.Cu")
		(net "M_I_CPU1_SA_DQS_DN<1>")
	)
	(gr_poly
		(pts
			(xy 141.014958 -230.916226) (xy 140.914882 -230.81615) (xy 140.814806 -230.916226) (xy 140.814806 -230.960676)
			(xy 141.014958 -230.960676)
		)
		(stroke
			(width 0)
			(type solid)
		)
		(fill yes)
		(layer "In2.Cu")
		(net "M_I_CPU1_SA_DQ<9>")
	)
	(gr_poly
		(pts
			(xy 141.014958 -230.51262) (xy 141.014958 -230.46817) (xy 140.814806 -230.46817) (xy 140.814806 -230.51262)
			(xy 140.914882 -230.612696)
		)
		(stroke
			(width 0)
			(type solid)
		)
		(fill yes)
		(layer "In2.Cu")
		(net "M_I_CPU1_SA_DQ<10>")
	)
	(gr_poly
		(pts
			(xy 141.014958 -229.296214) (xy 140.914882 -229.196138) (xy 140.814806 -229.296214) (xy 140.814806 -229.340664)
			(xy 141.014958 -229.340664)
		)
		(stroke
			(width 0)
			(type solid)
		)
		(fill yes)
		(layer "In2.Cu")
		(net "M_I_CPU1_SA_DQ<5>")
	)
	(gr_poly
		(pts
			(xy 141.014958 -228.892608) (xy 141.014958 -228.848158) (xy 140.814806 -228.848158) (xy 140.814806 -228.892608)
			(xy 140.914882 -228.992684)
		)
		(stroke
			(width 0)
			(type solid)
		)
		(fill yes)
		(layer "In2.Cu")
		(net "M_I_CPU1_SA_DQ<6>")
	)
	(gr_poly
		(pts
			(xy 141.070584 -227.809552) (xy 141.034008 -227.673154) (xy 140.992606 -227.649278) (xy 140.892784 -227.822506)
			(xy 140.933932 -227.846128)
		)
		(stroke
			(width 0)
			(type solid)
		)
		(fill yes)
		(layer "In2.Cu")
		(net "M_I_CPU1_SA_DQS_DP<5>")
	)
	(gr_poly
		(pts
			(xy 141.070584 -226.18954) (xy 141.034008 -226.053142) (xy 140.992606 -226.029266) (xy 140.892784 -226.202494)
			(xy 140.933932 -226.22637)
		)
		(stroke
			(width 0)
			(type solid)
		)
		(fill yes)
		(layer "In2.Cu")
		(net "M_I_CPU1_SA_DQS_DN<0>")
	)
	(gr_poly
		(pts
			(xy 141.070584 -224.569782) (xy 141.034008 -224.43313) (xy 140.9954 -224.410778) (xy 140.895578 -224.584006)
			(xy 140.933932 -224.606358)
		)
		(stroke
			(width 0)
			(type solid)
		)
		(fill yes)
		(layer "In2.Cu")
		(net "M_I_CPU1_SA_DQ<3>")
	)
	(gr_poly
		(pts
			(xy 141.070838 -222.948246) (xy 141.034262 -222.811848) (xy 140.995908 -222.789496) (xy 140.895832 -222.962724)
			(xy 140.93444 -222.985076)
		)
		(stroke
			(width 0)
			(type solid)
		)
		(fill yes)
		(layer "In2.Cu")
		(net "M_I_CPU1_SA_DQ<2>")
	)
	(gr_poly
		(pts
			(xy 141.314932 -293.32428) (xy 141.314932 -293.27983) (xy 141.11478 -293.27983) (xy 141.11478 -293.32428)
			(xy 141.214856 -293.424356)
		)
		(stroke
			(width 0)
			(type solid)
		)
		(fill yes)
		(layer "In2.Cu")
		(net "M_I_CPU1_SB_DQ<31>")
	)
	(gr_poly
		(pts
			(xy 141.314932 -292.108128) (xy 141.214856 -292.008052) (xy 141.11478 -292.108128) (xy 141.11478 -292.152578)
			(xy 141.314932 -292.152578)
		)
		(stroke
			(width 0)
			(type solid)
		)
		(fill yes)
		(layer "In2.Cu")
		(net "M_I_CPU1_SB_DQ<28>")
	)
	(gr_poly
		(pts
			(xy 141.314932 -291.704522) (xy 141.314932 -291.65677) (xy 141.11478 -291.65677) (xy 141.11478 -291.704522)
			(xy 141.214856 -291.804344)
		)
		(stroke
			(width 0)
			(type solid)
		)
		(fill yes)
		(layer "In2.Cu")
		(net "M_I_CPU1_SB_DQS_DP<8>")
	)
	(gr_poly
		(pts
			(xy 141.314932 -290.487862) (xy 141.214856 -290.38804) (xy 141.11478 -290.487862) (xy 141.11478 -290.535614)
			(xy 141.314932 -290.535614)
		)
		(stroke
			(width 0)
			(type solid)
		)
		(fill yes)
		(layer "In2.Cu")
		(net "M_I_CPU1_SB_DQS_DP<3>")
	)
	(gr_poly
		(pts
			(xy 141.314932 -290.084256) (xy 141.314932 -290.039806) (xy 141.11478 -290.039806) (xy 141.11478 -290.084256)
			(xy 141.214856 -290.184332)
		)
		(stroke
			(width 0)
			(type solid)
		)
		(fill yes)
		(layer "In2.Cu")
		(net "M_I_CPU1_SB_DQ<27>")
	)
	(gr_poly
		(pts
			(xy 141.314932 -288.868104) (xy 141.214856 -288.768028) (xy 141.11478 -288.868104) (xy 141.11478 -288.912554)
			(xy 141.314932 -288.912554)
		)
		(stroke
			(width 0)
			(type solid)
		)
		(fill yes)
		(layer "In2.Cu")
		(net "M_I_CPU1_SB_DQ<24>")
	)
	(gr_poly
		(pts
			(xy 141.314932 -288.464498) (xy 141.314932 -288.420048) (xy 141.11478 -288.420048) (xy 141.11478 -288.464498)
			(xy 141.214856 -288.564574)
		)
		(stroke
			(width 0)
			(type solid)
		)
		(fill yes)
		(layer "In2.Cu")
		(net "M_I_CPU1_SB_DQ<23>")
	)
	(gr_poly
		(pts
			(xy 141.314932 -287.248092) (xy 141.214856 -287.148016) (xy 141.11478 -287.248092) (xy 141.11478 -287.292542)
			(xy 141.314932 -287.292542)
		)
		(stroke
			(width 0)
			(type solid)
		)
		(fill yes)
		(layer "In2.Cu")
		(net "M_I_CPU1_SB_DQ<20>")
	)
	(gr_poly
		(pts
			(xy 141.314932 -286.844486) (xy 141.314932 -286.796734) (xy 141.11478 -286.796734) (xy 141.11478 -286.844486)
			(xy 141.214856 -286.944562)
		)
		(stroke
			(width 0)
			(type solid)
		)
		(fill yes)
		(layer "In2.Cu")
		(net "M_I_CPU1_SB_DQS_DP<7>")
	)
	(gr_poly
		(pts
			(xy 141.314932 -285.62808) (xy 141.214856 -285.528258) (xy 141.11478 -285.62808) (xy 141.11478 -285.675832)
			(xy 141.314932 -285.675832)
		)
		(stroke
			(width 0)
			(type solid)
		)
		(fill yes)
		(layer "In2.Cu")
		(net "M_I_CPU1_SB_DQS_DP<2>")
	)
	(gr_poly
		(pts
			(xy 141.314932 -285.224474) (xy 141.314932 -285.180024) (xy 141.11478 -285.180024) (xy 141.11478 -285.224474)
			(xy 141.214856 -285.32455)
		)
		(stroke
			(width 0)
			(type solid)
		)
		(fill yes)
		(layer "In2.Cu")
		(net "M_I_CPU1_SB_DQ<19>")
	)
	(gr_poly
		(pts
			(xy 141.314932 -284.008322) (xy 141.214856 -283.908246) (xy 141.11478 -284.008322) (xy 141.11478 -284.052772)
			(xy 141.314932 -284.052772)
		)
		(stroke
			(width 0)
			(type solid)
		)
		(fill yes)
		(layer "In2.Cu")
		(net "M_I_CPU1_SB_DQ<16>")
	)
	(gr_poly
		(pts
			(xy 141.314932 -283.604462) (xy 141.314932 -283.560012) (xy 141.11478 -283.560012) (xy 141.11478 -283.604462)
			(xy 141.214856 -283.704538)
		)
		(stroke
			(width 0)
			(type solid)
		)
		(fill yes)
		(layer "In2.Cu")
		(net "M_I_CPU1_SB_DQ<15>")
	)
	(gr_poly
		(pts
			(xy 141.314932 -282.38831) (xy 141.214856 -282.288234) (xy 141.11478 -282.38831) (xy 141.11478 -282.43276)
			(xy 141.314932 -282.43276)
		)
		(stroke
			(width 0)
			(type solid)
		)
		(fill yes)
		(layer "In2.Cu")
		(net "M_I_CPU1_SB_DQ<12>")
	)
	(gr_poly
		(pts
			(xy 141.314932 -281.984704) (xy 141.314932 -281.936952) (xy 141.11478 -281.936952) (xy 141.11478 -281.984704)
			(xy 141.214856 -282.084526)
		)
		(stroke
			(width 0)
			(type solid)
		)
		(fill yes)
		(layer "In2.Cu")
		(net "M_I_CPU1_SB_DQS_DP<6>")
	)
	(gr_poly
		(pts
			(xy 141.314932 -280.768044) (xy 141.214856 -280.668222) (xy 141.11478 -280.768044) (xy 141.11478 -280.815796)
			(xy 141.314932 -280.815796)
		)
		(stroke
			(width 0)
			(type solid)
		)
		(fill yes)
		(layer "In2.Cu")
		(net "M_I_CPU1_SB_DQS_DP<1>")
	)
	(gr_poly
		(pts
			(xy 141.314932 -280.364438) (xy 141.314932 -280.319988) (xy 141.11478 -280.319988) (xy 141.11478 -280.364438)
			(xy 141.214856 -280.464514)
		)
		(stroke
			(width 0)
			(type solid)
		)
		(fill yes)
		(layer "In2.Cu")
		(net "M_I_CPU1_SB_DQ<11>")
	)
	(gr_poly
		(pts
			(xy 141.314932 -279.148286) (xy 141.214856 -279.04821) (xy 141.11478 -279.148286) (xy 141.11478 -279.192736)
			(xy 141.314932 -279.192736)
		)
		(stroke
			(width 0)
			(type solid)
		)
		(fill yes)
		(layer "In2.Cu")
		(net "M_I_CPU1_SB_DQ<8>")
	)
	(gr_poly
		(pts
			(xy 141.314932 -278.744426) (xy 141.314932 -278.699976) (xy 141.11478 -278.699976) (xy 141.11478 -278.744426)
			(xy 141.214856 -278.844502)
		)
		(stroke
			(width 0)
			(type solid)
		)
		(fill yes)
		(layer "In2.Cu")
		(net "M_I_CPU1_SB_DQ<7>")
	)
	(gr_poly
		(pts
			(xy 141.314932 -277.528274) (xy 141.214856 -277.428198) (xy 141.11478 -277.528274) (xy 141.11478 -277.572724)
			(xy 141.314932 -277.572724)
		)
		(stroke
			(width 0)
			(type solid)
		)
		(fill yes)
		(layer "In2.Cu")
		(net "M_I_CPU1_SB_DQ<4>")
	)
	(gr_poly
		(pts
			(xy 141.314932 -277.124668) (xy 141.314932 -277.076916) (xy 141.11478 -277.076916) (xy 141.11478 -277.124668)
			(xy 141.214856 -277.22449)
		)
		(stroke
			(width 0)
			(type solid)
		)
		(fill yes)
		(layer "In2.Cu")
		(net "M_I_CPU1_SB_DQS_DP<5>")
	)
	(gr_poly
		(pts
			(xy 141.314932 -275.908008) (xy 141.214856 -275.808186) (xy 141.11478 -275.908008) (xy 141.11478 -275.95576)
			(xy 141.314932 -275.95576)
		)
		(stroke
			(width 0)
			(type solid)
		)
		(fill yes)
		(layer "In2.Cu")
		(net "M_I_CPU1_SB_DQS_DP<0>")
	)
	(gr_poly
		(pts
			(xy 141.314932 -275.504402) (xy 141.314932 -275.459952) (xy 141.11478 -275.459952) (xy 141.11478 -275.504402)
			(xy 141.214856 -275.604478)
		)
		(stroke
			(width 0)
			(type solid)
		)
		(fill yes)
		(layer "In2.Cu")
		(net "M_I_CPU1_SB_DQ<3>")
	)
	(gr_poly
		(pts
			(xy 141.314932 -274.28825) (xy 141.214856 -274.188174) (xy 141.11478 -274.28825) (xy 141.11478 -274.3327)
			(xy 141.314932 -274.3327)
		)
		(stroke
			(width 0)
			(type solid)
		)
		(fill yes)
		(layer "In2.Cu")
		(net "M_I_CPU1_SB_DQ<0>")
	)
	(gr_poly
		(pts
			(xy 141.314932 -273.88439) (xy 141.314932 -273.83994) (xy 141.11478 -273.83994) (xy 141.11478 -273.88439)
			(xy 141.214856 -273.984466)
		)
		(stroke
			(width 0)
			(type solid)
		)
		(fill yes)
		(layer "In2.Cu")
		(net "M_I_CPU1_SB_CB<3>")
	)
	(gr_poly
		(pts
			(xy 141.314932 -272.668238) (xy 141.214856 -272.568162) (xy 141.11478 -272.668238) (xy 141.11478 -272.712688)
			(xy 141.314932 -272.712688)
		)
		(stroke
			(width 0)
			(type solid)
		)
		(fill yes)
		(layer "In2.Cu")
		(net "M_I_CPU1_SB_CB<0>")
	)
	(gr_poly
		(pts
			(xy 141.314932 -272.264632) (xy 141.314932 -272.21688) (xy 141.11478 -272.21688) (xy 141.11478 -272.264632)
			(xy 141.214856 -272.364454)
		)
		(stroke
			(width 0)
			(type solid)
		)
		(fill yes)
		(layer "In2.Cu")
		(net "M_I_CPU1_SB_DQS_DP<4>")
	)
	(gr_poly
		(pts
			(xy 141.314932 -271.047972) (xy 141.214856 -270.94815) (xy 141.11478 -271.047972) (xy 141.11478 -271.095724)
			(xy 141.314932 -271.095724)
		)
		(stroke
			(width 0)
			(type solid)
		)
		(fill yes)
		(layer "In2.Cu")
		(net "M_I_CPU1_SB_DQS_DP<9>")
	)
	(gr_poly
		(pts
			(xy 141.314932 -270.644366) (xy 141.314932 -270.599916) (xy 141.11478 -270.599916) (xy 141.11478 -270.644366)
			(xy 141.214856 -270.744442)
		)
		(stroke
			(width 0)
			(type solid)
		)
		(fill yes)
		(layer "In2.Cu")
		(net "M_I_CPU1_SB_CB<7>")
	)
	(gr_poly
		(pts
			(xy 141.314932 -269.428214) (xy 141.214856 -269.328138) (xy 141.11478 -269.428214) (xy 141.11478 -269.472664)
			(xy 141.314932 -269.472664)
		)
		(stroke
			(width 0)
			(type solid)
		)
		(fill yes)
		(layer "In2.Cu")
		(net "M_I_CPU1_SB_CB<4>")
	)
	(gr_poly
		(pts
			(xy 141.314932 -267.404342) (xy 141.314932 -267.359892) (xy 141.11478 -267.359892) (xy 141.11478 -267.404342)
			(xy 141.214856 -267.504418)
		)
		(stroke
			(width 0)
			(type solid)
		)
		(fill yes)
		(layer "In2.Cu")
		(net "M_I_CPU1_SB_RSP<0>")
	)
	(gr_poly
		(pts
			(xy 141.314932 -265.78433) (xy 141.314932 -265.73988) (xy 141.11478 -265.73988) (xy 141.11478 -265.78433)
			(xy 141.214856 -265.884406)
		)
		(stroke
			(width 0)
			(type solid)
		)
		(fill yes)
		(layer "In2.Cu")
		(net "M_I_CPU1_SB_CS_N<0>")
	)
	(gr_poly
		(pts
			(xy 141.314932 -264.568178) (xy 141.214856 -264.468102) (xy 141.11478 -264.568178) (xy 141.11478 -264.612628)
			(xy 141.314932 -264.612628)
		)
		(stroke
			(width 0)
			(type solid)
		)
		(fill yes)
		(layer "In2.Cu")
		(net "M_I_CPU1_SB_CA<6>")
	)
	(gr_poly
		(pts
			(xy 141.314932 -264.164318) (xy 141.314932 -264.119868) (xy 141.11478 -264.119868) (xy 141.11478 -264.164318)
			(xy 141.214856 -264.264394)
		)
		(stroke
			(width 0)
			(type solid)
		)
		(fill yes)
		(layer "In2.Cu")
		(net "M_I_CPU1_SB_CA<5>")
	)
	(gr_poly
		(pts
			(xy 141.314932 -262.948166) (xy 141.214856 -262.84809) (xy 141.11478 -262.948166) (xy 141.11478 -262.992616)
			(xy 141.314932 -262.992616)
		)
		(stroke
			(width 0)
			(type solid)
		)
		(fill yes)
		(layer "In2.Cu")
		(net "M_I_CPU1_SB_CA<2>")
	)
	(gr_poly
		(pts
			(xy 141.314932 -262.544306) (xy 141.314932 -262.499856) (xy 141.11478 -262.499856) (xy 141.11478 -262.544306)
			(xy 141.214856 -262.644382)
		)
		(stroke
			(width 0)
			(type solid)
		)
		(fill yes)
		(layer "In2.Cu")
		(net "M_I_CPU1_SB_CA<1>")
	)
	(gr_poly
		(pts
			(xy 141.404848 -227.934266) (xy 141.36624 -227.912168) (xy 141.229588 -227.948744) (xy 141.266164 -228.085396)
			(xy 141.304772 -228.107494)
		)
		(stroke
			(width 0)
			(type solid)
		)
		(fill yes)
		(layer "In2.Cu")
		(net "M_I_CPU1_SA_DQ<4>")
	)
	(gr_poly
		(pts
			(xy 141.404848 -223.074992) (xy 141.366494 -223.05264) (xy 141.229842 -223.089216) (xy 141.266418 -223.225868)
			(xy 141.305026 -223.24822)
		)
		(stroke
			(width 0)
			(type solid)
		)
		(fill yes)
		(layer "In2.Cu")
		(net "M_I_CPU1_SA_DQ<1>")
	)
	(gr_poly
		(pts
			(xy 141.407896 -226.31527) (xy 141.366494 -226.291394) (xy 141.229842 -226.32797) (xy 141.266672 -226.464622)
			(xy 141.30782 -226.488498)
		)
		(stroke
			(width 0)
			(type solid)
		)
		(fill yes)
		(layer "In2.Cu")
		(net "M_I_CPU1_SA_DQS_DN<5>")
	)
	(gr_poly
		(pts
			(xy 141.407896 -224.695258) (xy 141.366494 -224.671382) (xy 141.229842 -224.708212) (xy 141.266672 -224.84461)
			(xy 141.30782 -224.868486)
		)
		(stroke
			(width 0)
			(type solid)
		)
		(fill yes)
		(layer "In2.Cu")
		(net "M_I_CPU1_SA_DQS_DP<0>")
	)
	(gr_poly
		(pts
			(xy 141.484858 -256.026158) (xy 141.384782 -255.926336) (xy 141.284706 -256.026158) (xy 141.284706 -256.07391)
			(xy 141.484858 -256.07391)
		)
		(stroke
			(width 0)
			(type solid)
		)
		(fill yes)
		(layer "In2.Cu")
		(net "M_I_CPU1_CLK_DP<0>")
	)
	(gr_poly
		(pts
			(xy 141.484858 -255.622552) (xy 141.484858 -255.578102) (xy 141.284706 -255.578102) (xy 141.284706 -255.622552)
			(xy 141.384782 -255.722628)
		)
		(stroke
			(width 0)
			(type solid)
		)
		(fill yes)
		(layer "In2.Cu")
		(net "M_I_CPU1_SA_PAR")
	)
	(gr_poly
		(pts
			(xy 141.484858 -254.4064) (xy 141.384782 -254.306324) (xy 141.284706 -254.4064) (xy 141.284706 -254.45085)
			(xy 141.484858 -254.45085)
		)
		(stroke
			(width 0)
			(type solid)
		)
		(fill yes)
		(layer "In2.Cu")
		(net "M_I_CPU1_SA_CA<4>")
	)
	(gr_poly
		(pts
			(xy 141.484858 -254.00254) (xy 141.484858 -253.95809) (xy 141.284706 -253.95809) (xy 141.284706 -254.00254)
			(xy 141.384782 -254.102616)
		)
		(stroke
			(width 0)
			(type solid)
		)
		(fill yes)
		(layer "In2.Cu")
		(net "M_I_CPU1_SA_CA<3>")
	)
	(gr_poly
		(pts
			(xy 141.484858 -252.786388) (xy 141.384782 -252.686312) (xy 141.284706 -252.786388) (xy 141.284706 -252.830838)
			(xy 141.484858 -252.830838)
		)
		(stroke
			(width 0)
			(type solid)
		)
		(fill yes)
		(layer "In2.Cu")
		(net "M_I_CPU1_SA_CA<0>")
	)
	(gr_poly
		(pts
			(xy 141.484858 -251.166376) (xy 141.384782 -251.0663) (xy 141.284706 -251.166376) (xy 141.284706 -251.210826)
			(xy 141.484858 -251.210826)
		)
		(stroke
			(width 0)
			(type solid)
		)
		(fill yes)
		(layer "In2.Cu")
		(net "M_I_CPU1_SA_CS_N<0>")
	)
	(gr_poly
		(pts
			(xy 141.484858 -250.762516) (xy 141.484858 -250.718066) (xy 141.284706 -250.718066) (xy 141.284706 -250.762516)
			(xy 141.384782 -250.862592)
		)
		(stroke
			(width 0)
			(type solid)
		)
		(fill yes)
		(layer "In2.Cu")
		(net "M_I_CPU1_RESET_N")
	)
	(gr_poly
		(pts
			(xy 141.484858 -249.142504) (xy 141.484858 -249.098054) (xy 141.284706 -249.098054) (xy 141.284706 -249.142504)
			(xy 141.384782 -249.24258)
		)
		(stroke
			(width 0)
			(type solid)
		)
		(fill yes)
		(layer "In2.Cu")
		(net "M_I_CPU1_SA_CB<7>")
	)
	(gr_poly
		(pts
			(xy 141.484858 -247.926352) (xy 141.384782 -247.826276) (xy 141.284706 -247.926352) (xy 141.284706 -247.970802)
			(xy 141.484858 -247.970802)
		)
		(stroke
			(width 0)
			(type solid)
		)
		(fill yes)
		(layer "In2.Cu")
		(net "M_I_CPU1_SA_CB<4>")
	)
	(gr_poly
		(pts
			(xy 141.484858 -247.522746) (xy 141.484858 -247.474994) (xy 141.284706 -247.474994) (xy 141.284706 -247.522746)
			(xy 141.384782 -247.622568)
		)
		(stroke
			(width 0)
			(type solid)
		)
		(fill yes)
		(layer "In2.Cu")
		(net "M_I_CPU1_SA_DQS_DP<9>")
	)
	(gr_poly
		(pts
			(xy 141.484858 -246.306086) (xy 141.384782 -246.206264) (xy 141.284706 -246.306086) (xy 141.284706 -246.353838)
			(xy 141.484858 -246.353838)
		)
		(stroke
			(width 0)
			(type solid)
		)
		(fill yes)
		(layer "In2.Cu")
		(net "M_I_CPU1_SA_DQS_DP<4>")
	)
	(gr_poly
		(pts
			(xy 141.484858 -245.90248) (xy 141.484858 -245.85803) (xy 141.284706 -245.85803) (xy 141.284706 -245.90248)
			(xy 141.384782 -246.002556)
		)
		(stroke
			(width 0)
			(type solid)
		)
		(fill yes)
		(layer "In2.Cu")
		(net "M_I_CPU1_SA_CB<3>")
	)
	(gr_poly
		(pts
			(xy 141.484858 -244.686328) (xy 141.384782 -244.586252) (xy 141.284706 -244.686328) (xy 141.284706 -244.730778)
			(xy 141.484858 -244.730778)
		)
		(stroke
			(width 0)
			(type solid)
		)
		(fill yes)
		(layer "In2.Cu")
		(net "M_I_CPU1_SA_CB<0>")
	)
	(gr_poly
		(pts
			(xy 141.484858 -244.282468) (xy 141.484858 -244.238018) (xy 141.284706 -244.238018) (xy 141.284706 -244.282468)
			(xy 141.384782 -244.382544)
		)
		(stroke
			(width 0)
			(type solid)
		)
		(fill yes)
		(layer "In2.Cu")
		(net "M_I_CPU1_SA_DQ<31>")
	)
	(gr_poly
		(pts
			(xy 141.484858 -243.066316) (xy 141.384782 -242.96624) (xy 141.284706 -243.066316) (xy 141.284706 -243.110766)
			(xy 141.484858 -243.110766)
		)
		(stroke
			(width 0)
			(type solid)
		)
		(fill yes)
		(layer "In2.Cu")
		(net "M_I_CPU1_SA_DQ<28>")
	)
	(gr_poly
		(pts
			(xy 141.484858 -242.66271) (xy 141.484858 -242.614958) (xy 141.284706 -242.614958) (xy 141.284706 -242.66271)
			(xy 141.384782 -242.762532)
		)
		(stroke
			(width 0)
			(type solid)
		)
		(fill yes)
		(layer "In2.Cu")
		(net "M_I_CPU1_SA_DQS_DP<8>")
	)
	(gr_poly
		(pts
			(xy 141.484858 -241.44605) (xy 141.384782 -241.346228) (xy 141.284706 -241.44605) (xy 141.284706 -241.493802)
			(xy 141.484858 -241.493802)
		)
		(stroke
			(width 0)
			(type solid)
		)
		(fill yes)
		(layer "In2.Cu")
		(net "M_I_CPU1_SA_DQS_DP<3>")
	)
	(gr_poly
		(pts
			(xy 141.484858 -241.042444) (xy 141.484858 -240.997994) (xy 141.284706 -240.997994) (xy 141.284706 -241.042444)
			(xy 141.384782 -241.14252)
		)
		(stroke
			(width 0)
			(type solid)
		)
		(fill yes)
		(layer "In2.Cu")
		(net "M_I_CPU1_SA_DQ<27>")
	)
	(gr_poly
		(pts
			(xy 141.484858 -239.826292) (xy 141.384782 -239.726216) (xy 141.284706 -239.826292) (xy 141.284706 -239.870742)
			(xy 141.484858 -239.870742)
		)
		(stroke
			(width 0)
			(type solid)
		)
		(fill yes)
		(layer "In2.Cu")
		(net "M_I_CPU1_SA_DQ<24>")
	)
	(gr_poly
		(pts
			(xy 141.484858 -239.422432) (xy 141.484858 -239.377982) (xy 141.284706 -239.377982) (xy 141.284706 -239.422432)
			(xy 141.384782 -239.522508)
		)
		(stroke
			(width 0)
			(type solid)
		)
		(fill yes)
		(layer "In2.Cu")
		(net "M_I_CPU1_SA_DQ<23>")
	)
	(gr_poly
		(pts
			(xy 141.484858 -238.20628) (xy 141.384782 -238.106204) (xy 141.284706 -238.20628) (xy 141.284706 -238.25073)
			(xy 141.484858 -238.25073)
		)
		(stroke
			(width 0)
			(type solid)
		)
		(fill yes)
		(layer "In2.Cu")
		(net "M_I_CPU1_SA_DQ<20>")
	)
	(gr_poly
		(pts
			(xy 141.484858 -237.802674) (xy 141.484858 -237.754922) (xy 141.284706 -237.754922) (xy 141.284706 -237.802674)
			(xy 141.384782 -237.902496)
		)
		(stroke
			(width 0)
			(type solid)
		)
		(fill yes)
		(layer "In2.Cu")
		(net "M_I_CPU1_SA_DQS_DP<7>")
	)
	(gr_poly
		(pts
			(xy 141.484858 -236.586014) (xy 141.384782 -236.486192) (xy 141.284706 -236.586014) (xy 141.284706 -236.633766)
			(xy 141.484858 -236.633766)
		)
		(stroke
			(width 0)
			(type solid)
		)
		(fill yes)
		(layer "In2.Cu")
		(net "M_I_CPU1_SA_DQS_DP<2>")
	)
	(gr_poly
		(pts
			(xy 141.484858 -236.182408) (xy 141.484858 -236.137958) (xy 141.284706 -236.137958) (xy 141.284706 -236.182408)
			(xy 141.384782 -236.282484)
		)
		(stroke
			(width 0)
			(type solid)
		)
		(fill yes)
		(layer "In2.Cu")
		(net "M_I_CPU1_SA_DQ<19>")
	)
	(gr_poly
		(pts
			(xy 141.484858 -234.966256) (xy 141.384782 -234.86618) (xy 141.284706 -234.966256) (xy 141.284706 -235.010706)
			(xy 141.484858 -235.010706)
		)
		(stroke
			(width 0)
			(type solid)
		)
		(fill yes)
		(layer "In2.Cu")
		(net "M_I_CPU1_SA_DQ<16>")
	)
	(gr_poly
		(pts
			(xy 141.484858 -234.562396) (xy 141.484858 -234.517946) (xy 141.284706 -234.517946) (xy 141.284706 -234.562396)
			(xy 141.384782 -234.662472)
		)
		(stroke
			(width 0)
			(type solid)
		)
		(fill yes)
		(layer "In2.Cu")
		(net "M_I_CPU1_SA_DQ<15>")
	)
	(gr_poly
		(pts
			(xy 141.484858 -233.346244) (xy 141.384782 -233.246168) (xy 141.284706 -233.346244) (xy 141.284706 -233.390694)
			(xy 141.484858 -233.390694)
		)
		(stroke
			(width 0)
			(type solid)
		)
		(fill yes)
		(layer "In2.Cu")
		(net "M_I_CPU1_SA_DQ<12>")
	)
	(gr_poly
		(pts
			(xy 141.484858 -232.942638) (xy 141.484858 -232.894886) (xy 141.284706 -232.894886) (xy 141.284706 -232.942638)
			(xy 141.384782 -233.04246)
		)
		(stroke
			(width 0)
			(type solid)
		)
		(fill yes)
		(layer "In2.Cu")
		(net "M_I_CPU1_SA_DQS_DP<6>")
	)
	(gr_poly
		(pts
			(xy 141.484858 -231.725978) (xy 141.384782 -231.626156) (xy 141.284706 -231.725978) (xy 141.284706 -231.77373)
			(xy 141.484858 -231.77373)
		)
		(stroke
			(width 0)
			(type solid)
		)
		(fill yes)
		(layer "In2.Cu")
		(net "M_I_CPU1_SA_DQS_DP<1>")
	)
	(gr_poly
		(pts
			(xy 141.484858 -231.322626) (xy 141.484858 -231.278176) (xy 141.284706 -231.278176) (xy 141.284706 -231.322626)
			(xy 141.384782 -231.422702)
		)
		(stroke
			(width 0)
			(type solid)
		)
		(fill yes)
		(layer "In2.Cu")
		(net "M_I_CPU1_SA_DQ<11>")
	)
	(gr_poly
		(pts
			(xy 141.484858 -230.10622) (xy 141.384782 -230.006144) (xy 141.284706 -230.10622) (xy 141.284706 -230.15067)
			(xy 141.484858 -230.15067)
		)
		(stroke
			(width 0)
			(type solid)
		)
		(fill yes)
		(layer "In2.Cu")
		(net "M_I_CPU1_SA_DQ<8>")
	)
	(gr_poly
		(pts
			(xy 141.484858 -229.702614) (xy 141.484858 -229.658164) (xy 141.284706 -229.658164) (xy 141.284706 -229.702614)
			(xy 141.384782 -229.80269)
		)
		(stroke
			(width 0)
			(type solid)
		)
		(fill yes)
		(layer "In2.Cu")
		(net "M_I_CPU1_SA_DQ<7>")
	)
	(gr_poly
		(pts
			(xy 141.53896 -222.141034) (xy 141.502384 -222.004382) (xy 141.46403 -221.98203) (xy 141.363954 -222.155258)
			(xy 141.402562 -222.17761)
		)
		(stroke
			(width 0)
			(type solid)
		)
		(fill yes)
		(layer "In2.Cu")
		(net "M_I_CPU1_SA_DQ<2>")
	)
	(gr_poly
		(pts
			(xy 141.539722 -227.00107) (xy 141.502892 -226.864418) (xy 141.461744 -226.840542) (xy 141.361668 -227.01377)
			(xy 141.40307 -227.037646)
		)
		(stroke
			(width 0)
			(type solid)
		)
		(fill yes)
		(layer "In2.Cu")
		(net "M_I_CPU1_SA_DQS_DP<5>")
	)
	(gr_poly
		(pts
			(xy 141.539722 -225.380804) (xy 141.502892 -225.244406) (xy 141.461744 -225.22053) (xy 141.361668 -225.393758)
			(xy 141.40307 -225.417634)
		)
		(stroke
			(width 0)
			(type solid)
		)
		(fill yes)
		(layer "In2.Cu")
		(net "M_I_CPU1_SA_DQS_DN<0>")
	)
	(gr_poly
		(pts
			(xy 141.539976 -228.62032) (xy 141.5034 -228.483668) (xy 141.464792 -228.46157) (xy 141.364716 -228.634798)
			(xy 141.403324 -228.656896)
		)
		(stroke
			(width 0)
			(type solid)
		)
		(fill yes)
		(layer "In2.Cu")
		(net "M_I_CPU1_SA_DQ<6>")
	)
	(gr_poly
		(pts
			(xy 141.541754 -223.758252) (xy 141.504924 -223.6216) (xy 141.46657 -223.599502) (xy 141.366494 -223.77273)
			(xy 141.405102 -223.794828)
		)
		(stroke
			(width 0)
			(type solid)
		)
		(fill yes)
		(layer "In2.Cu")
		(net "M_I_CPU1_SA_DQ<3>")
	)
	(gr_poly
		(pts
			(xy 141.784832 -292.918134) (xy 141.684756 -292.818058) (xy 141.58468 -292.918134) (xy 141.58468 -292.962584)
			(xy 141.784832 -292.962584)
		)
		(stroke
			(width 0)
			(type solid)
		)
		(fill yes)
		(layer "In2.Cu")
		(net "M_I_CPU1_SB_DQ<29>")
	)
	(gr_poly
		(pts
			(xy 141.784832 -292.514274) (xy 141.784832 -292.469824) (xy 141.58468 -292.469824) (xy 141.58468 -292.514274)
			(xy 141.684756 -292.61435)
		)
		(stroke
			(width 0)
			(type solid)
		)
		(fill yes)
		(layer "In2.Cu")
		(net "M_I_CPU1_SB_DQ<30>")
	)
	(gr_poly
		(pts
			(xy 141.784832 -291.297868) (xy 141.684756 -291.198046) (xy 141.58468 -291.297868) (xy 141.58468 -291.34562)
			(xy 141.784832 -291.34562)
		)
		(stroke
			(width 0)
			(type solid)
		)
		(fill yes)
		(layer "In2.Cu")
		(net "M_I_CPU1_SB_DQS_DN<8>")
	)
	(gr_poly
		(pts
			(xy 141.784832 -290.894516) (xy 141.784832 -290.846764) (xy 141.58468 -290.846764) (xy 141.58468 -290.894516)
			(xy 141.684756 -290.994338)
		)
		(stroke
			(width 0)
			(type solid)
		)
		(fill yes)
		(layer "In2.Cu")
		(net "M_I_CPU1_SB_DQS_DN<3>")
	)
	(gr_poly
		(pts
			(xy 141.784832 -289.67811) (xy 141.684756 -289.578034) (xy 141.58468 -289.67811) (xy 141.58468 -289.72256)
			(xy 141.784832 -289.72256)
		)
		(stroke
			(width 0)
			(type solid)
		)
		(fill yes)
		(layer "In2.Cu")
		(net "M_I_CPU1_SB_DQ<25>")
	)
	(gr_poly
		(pts
			(xy 141.784832 -289.27425) (xy 141.784832 -289.2298) (xy 141.58468 -289.2298) (xy 141.58468 -289.27425)
			(xy 141.684756 -289.374326)
		)
		(stroke
			(width 0)
			(type solid)
		)
		(fill yes)
		(layer "In2.Cu")
		(net "M_I_CPU1_SB_DQ<26>")
	)
	(gr_poly
		(pts
			(xy 141.784832 -288.058098) (xy 141.684756 -287.958022) (xy 141.58468 -288.058098) (xy 141.58468 -288.102548)
			(xy 141.784832 -288.102548)
		)
		(stroke
			(width 0)
			(type solid)
		)
		(fill yes)
		(layer "In2.Cu")
		(net "M_I_CPU1_SB_DQ<21>")
	)
	(gr_poly
		(pts
			(xy 141.784832 -287.654492) (xy 141.784832 -287.610042) (xy 141.58468 -287.610042) (xy 141.58468 -287.654492)
			(xy 141.684756 -287.754568)
		)
		(stroke
			(width 0)
			(type solid)
		)
		(fill yes)
		(layer "In2.Cu")
		(net "M_I_CPU1_SB_DQ<22>")
	)
	(gr_poly
		(pts
			(xy 141.784832 -286.438086) (xy 141.684756 -286.33801) (xy 141.58468 -286.438086) (xy 141.58468 -286.485838)
			(xy 141.784832 -286.485838)
		)
		(stroke
			(width 0)
			(type solid)
		)
		(fill yes)
		(layer "In2.Cu")
		(net "M_I_CPU1_SB_DQS_DN<7>")
	)
	(gr_poly
		(pts
			(xy 141.784832 -286.034734) (xy 141.784832 -285.986982) (xy 141.58468 -285.986982) (xy 141.58468 -286.034734)
			(xy 141.684756 -286.134556)
		)
		(stroke
			(width 0)
			(type solid)
		)
		(fill yes)
		(layer "In2.Cu")
		(net "M_I_CPU1_SB_DQS_DN<2>")
	)
	(gr_poly
		(pts
			(xy 141.784832 -284.818328) (xy 141.684756 -284.718252) (xy 141.58468 -284.818328) (xy 141.58468 -284.862778)
			(xy 141.784832 -284.862778)
		)
		(stroke
			(width 0)
			(type solid)
		)
		(fill yes)
		(layer "In2.Cu")
		(net "M_I_CPU1_SB_DQ<17>")
	)
	(gr_poly
		(pts
			(xy 141.784832 -284.414468) (xy 141.784832 -284.370018) (xy 141.58468 -284.370018) (xy 141.58468 -284.414468)
			(xy 141.684756 -284.514544)
		)
		(stroke
			(width 0)
			(type solid)
		)
		(fill yes)
		(layer "In2.Cu")
		(net "M_I_CPU1_SB_DQ<18>")
	)
	(gr_poly
		(pts
			(xy 141.784832 -283.198316) (xy 141.684756 -283.09824) (xy 141.58468 -283.198316) (xy 141.58468 -283.242766)
			(xy 141.784832 -283.242766)
		)
		(stroke
			(width 0)
			(type solid)
		)
		(fill yes)
		(layer "In2.Cu")
		(net "M_I_CPU1_SB_DQ<13>")
	)
	(gr_poly
		(pts
			(xy 141.784832 -282.794456) (xy 141.784832 -282.750006) (xy 141.58468 -282.750006) (xy 141.58468 -282.794456)
			(xy 141.684756 -282.894532)
		)
		(stroke
			(width 0)
			(type solid)
		)
		(fill yes)
		(layer "In2.Cu")
		(net "M_I_CPU1_SB_DQ<14>")
	)
	(gr_poly
		(pts
			(xy 141.784832 -281.57805) (xy 141.684756 -281.478228) (xy 141.58468 -281.57805) (xy 141.58468 -281.625802)
			(xy 141.784832 -281.625802)
		)
		(stroke
			(width 0)
			(type solid)
		)
		(fill yes)
		(layer "In2.Cu")
		(net "M_I_CPU1_SB_DQS_DN<6>")
	)
	(gr_poly
		(pts
			(xy 141.784832 -281.174698) (xy 141.784832 -281.126946) (xy 141.58468 -281.126946) (xy 141.58468 -281.174698)
			(xy 141.684756 -281.27452)
		)
		(stroke
			(width 0)
			(type solid)
		)
		(fill yes)
		(layer "In2.Cu")
		(net "M_I_CPU1_SB_DQS_DN<1>")
	)
	(gr_poly
		(pts
			(xy 141.784832 -279.958292) (xy 141.684756 -279.858216) (xy 141.58468 -279.958292) (xy 141.58468 -280.002742)
			(xy 141.784832 -280.002742)
		)
		(stroke
			(width 0)
			(type solid)
		)
		(fill yes)
		(layer "In2.Cu")
		(net "M_I_CPU1_SB_DQ<9>")
	)
	(gr_poly
		(pts
			(xy 141.784832 -279.554432) (xy 141.784832 -279.509982) (xy 141.58468 -279.509982) (xy 141.58468 -279.554432)
			(xy 141.684756 -279.654508)
		)
		(stroke
			(width 0)
			(type solid)
		)
		(fill yes)
		(layer "In2.Cu")
		(net "M_I_CPU1_SB_DQ<10>")
	)
	(gr_poly
		(pts
			(xy 141.784832 -278.33828) (xy 141.684756 -278.238204) (xy 141.58468 -278.33828) (xy 141.58468 -278.38273)
			(xy 141.784832 -278.38273)
		)
		(stroke
			(width 0)
			(type solid)
		)
		(fill yes)
		(layer "In2.Cu")
		(net "M_I_CPU1_SB_DQ<5>")
	)
	(gr_poly
		(pts
			(xy 141.784832 -277.93442) (xy 141.784832 -277.88997) (xy 141.58468 -277.88997) (xy 141.58468 -277.93442)
			(xy 141.684756 -278.034496)
		)
		(stroke
			(width 0)
			(type solid)
		)
		(fill yes)
		(layer "In2.Cu")
		(net "M_I_CPU1_SB_DQ<6>")
	)
	(gr_poly
		(pts
			(xy 141.784832 -276.718014) (xy 141.684756 -276.618192) (xy 141.58468 -276.718014) (xy 141.58468 -276.765766)
			(xy 141.784832 -276.765766)
		)
		(stroke
			(width 0)
			(type solid)
		)
		(fill yes)
		(layer "In2.Cu")
		(net "M_I_CPU1_SB_DQS_DN<5>")
	)
	(gr_poly
		(pts
			(xy 141.784832 -276.314662) (xy 141.784832 -276.26691) (xy 141.58468 -276.26691) (xy 141.58468 -276.314662)
			(xy 141.684756 -276.414484)
		)
		(stroke
			(width 0)
			(type solid)
		)
		(fill yes)
		(layer "In2.Cu")
		(net "M_I_CPU1_SB_DQS_DN<0>")
	)
	(gr_poly
		(pts
			(xy 141.784832 -275.098256) (xy 141.684756 -274.99818) (xy 141.58468 -275.098256) (xy 141.58468 -275.142706)
			(xy 141.784832 -275.142706)
		)
		(stroke
			(width 0)
			(type solid)
		)
		(fill yes)
		(layer "In2.Cu")
		(net "M_I_CPU1_SB_DQ<1>")
	)
	(gr_poly
		(pts
			(xy 141.784832 -274.694396) (xy 141.784832 -274.649946) (xy 141.58468 -274.649946) (xy 141.58468 -274.694396)
			(xy 141.684756 -274.794472)
		)
		(stroke
			(width 0)
			(type solid)
		)
		(fill yes)
		(layer "In2.Cu")
		(net "M_I_CPU1_SB_DQ<2>")
	)
	(gr_poly
		(pts
			(xy 141.784832 -273.478244) (xy 141.684756 -273.378168) (xy 141.58468 -273.478244) (xy 141.58468 -273.522694)
			(xy 141.784832 -273.522694)
		)
		(stroke
			(width 0)
			(type solid)
		)
		(fill yes)
		(layer "In2.Cu")
		(net "M_I_CPU1_SB_CB<1>")
	)
	(gr_poly
		(pts
			(xy 141.784832 -273.074384) (xy 141.784832 -273.029934) (xy 141.58468 -273.029934) (xy 141.58468 -273.074384)
			(xy 141.684756 -273.17446)
		)
		(stroke
			(width 0)
			(type solid)
		)
		(fill yes)
		(layer "In2.Cu")
		(net "M_I_CPU1_SB_CB<2>")
	)
	(gr_poly
		(pts
			(xy 141.784832 -271.857978) (xy 141.684756 -271.758156) (xy 141.58468 -271.857978) (xy 141.58468 -271.90573)
			(xy 141.784832 -271.90573)
		)
		(stroke
			(width 0)
			(type solid)
		)
		(fill yes)
		(layer "In2.Cu")
		(net "M_I_CPU1_SB_DQS_DN<4>")
	)
	(gr_poly
		(pts
			(xy 141.784832 -271.454626) (xy 141.784832 -271.406874) (xy 141.58468 -271.406874) (xy 141.58468 -271.454626)
			(xy 141.684756 -271.554448)
		)
		(stroke
			(width 0)
			(type solid)
		)
		(fill yes)
		(layer "In2.Cu")
		(net "M_I_CPU1_SB_DQS_DN<9>")
	)
	(gr_poly
		(pts
			(xy 141.784832 -270.23822) (xy 141.684756 -270.138144) (xy 141.58468 -270.23822) (xy 141.58468 -270.28267)
			(xy 141.784832 -270.28267)
		)
		(stroke
			(width 0)
			(type solid)
		)
		(fill yes)
		(layer "In2.Cu")
		(net "M_I_CPU1_SB_CB<5>")
	)
	(gr_poly
		(pts
			(xy 141.784832 -269.83436) (xy 141.784832 -269.78991) (xy 141.58468 -269.78991) (xy 141.58468 -269.83436)
			(xy 141.684756 -269.934436)
		)
		(stroke
			(width 0)
			(type solid)
		)
		(fill yes)
		(layer "In2.Cu")
		(net "M_I_CPU1_SB_CB<6>")
	)
	(gr_poly
		(pts
			(xy 141.784832 -266.998196) (xy 141.684756 -266.89812) (xy 141.58468 -266.998196) (xy 141.58468 -267.042646)
			(xy 141.784832 -267.042646)
		)
		(stroke
			(width 0)
			(type solid)
		)
		(fill yes)
		(layer "In2.Cu")
		(net "M_I_CPU1_SA_RSP<0>")
	)
	(gr_poly
		(pts
			(xy 141.784832 -266.594336) (xy 141.784832 -266.549886) (xy 141.58468 -266.549886) (xy 141.58468 -266.594336)
			(xy 141.684756 -266.694412)
		)
		(stroke
			(width 0)
			(type solid)
		)
		(fill yes)
		(layer "In2.Cu")
		(net "M_I_CPU1_SB_CS_N<1>")
	)
	(gr_poly
		(pts
			(xy 141.784832 -265.378184) (xy 141.684756 -265.278108) (xy 141.58468 -265.378184) (xy 141.58468 -265.422634)
			(xy 141.784832 -265.422634)
		)
		(stroke
			(width 0)
			(type solid)
		)
		(fill yes)
		(layer "In2.Cu")
		(net "M_I_CPU1_SB_PAR")
	)
	(gr_poly
		(pts
			(xy 141.784832 -263.758172) (xy 141.684756 -263.658096) (xy 141.58468 -263.758172) (xy 141.58468 -263.802622)
			(xy 141.784832 -263.802622)
		)
		(stroke
			(width 0)
			(type solid)
		)
		(fill yes)
		(layer "In2.Cu")
		(net "M_I_CPU1_SB_CA<4>")
	)
	(gr_poly
		(pts
			(xy 141.784832 -263.354312) (xy 141.784832 -263.309862) (xy 141.58468 -263.309862) (xy 141.58468 -263.354312)
			(xy 141.684756 -263.454388)
		)
		(stroke
			(width 0)
			(type solid)
		)
		(fill yes)
		(layer "In2.Cu")
		(net "M_I_CPU1_SB_CA<3>")
	)
	(gr_poly
		(pts
			(xy 141.784832 -262.13816) (xy 141.684756 -262.038084) (xy 141.58468 -262.13816) (xy 141.58468 -262.18261)
			(xy 141.784832 -262.18261)
		)
		(stroke
			(width 0)
			(type solid)
		)
		(fill yes)
		(layer "In2.Cu")
		(net "M_I_CPU1_SB_CA<0>")
	)
	(gr_poly
		(pts
			(xy 141.873986 -228.745796) (xy 141.835378 -228.723444) (xy 141.698726 -228.76002) (xy 141.735556 -228.896672)
			(xy 141.77391 -228.919024)
		)
		(stroke
			(width 0)
			(type solid)
		)
		(fill yes)
		(layer "In2.Cu")
		(net "M_I_CPU1_SA_DQ<5>")
	)
	(gr_poly
		(pts
			(xy 141.873986 -227.125784) (xy 141.835378 -227.103432) (xy 141.698726 -227.140008) (xy 141.735556 -227.27666)
			(xy 141.77391 -227.299012)
		)
		(stroke
			(width 0)
			(type solid)
		)
		(fill yes)
		(layer "In2.Cu")
		(net "M_I_CPU1_SA_DQ<4>")
	)
	(gr_poly
		(pts
			(xy 141.87678 -225.506534) (xy 141.835632 -225.482912) (xy 141.69898 -225.519488) (xy 141.735556 -225.655886)
			(xy 141.776958 -225.679762)
		)
		(stroke
			(width 0)
			(type solid)
		)
		(fill yes)
		(layer "In2.Cu")
		(net "M_I_CPU1_SA_DQS_DN<5>")
	)
	(gr_poly
		(pts
			(xy 141.87678 -223.886522) (xy 141.835632 -223.8629) (xy 141.69898 -223.899476) (xy 141.735556 -224.035874)
			(xy 141.776958 -224.05975)
		)
		(stroke
			(width 0)
			(type solid)
		)
		(fill yes)
		(layer "In2.Cu")
		(net "M_I_CPU1_SA_DQS_DP<0>")
	)
	(gr_poly
		(pts
			(xy 141.954758 -256.432812) (xy 141.954758 -256.38506) (xy 141.754606 -256.38506) (xy 141.754606 -256.432812)
			(xy 141.854682 -256.532634)
		)
		(stroke
			(width 0)
			(type solid)
		)
		(fill yes)
		(layer "In2.Cu")
		(net "M_I_CPU1_CLK_DN<0>")
	)
	(gr_poly
		(pts
			(xy 141.954758 -255.216406) (xy 141.854682 -255.11633) (xy 141.754606 -255.216406) (xy 141.754606 -255.260856)
			(xy 141.954758 -255.260856)
		)
		(stroke
			(width 0)
			(type solid)
		)
		(fill yes)
		(layer "In2.Cu")
		(net "M_I_CPU1_SA_CA<6>")
	)
	(gr_poly
		(pts
			(xy 141.954758 -254.812546) (xy 141.954758 -254.768096) (xy 141.754606 -254.768096) (xy 141.754606 -254.812546)
			(xy 141.854682 -254.912622)
		)
		(stroke
			(width 0)
			(type solid)
		)
		(fill yes)
		(layer "In2.Cu")
		(net "M_I_CPU1_SA_CA<5>")
	)
	(gr_poly
		(pts
			(xy 141.954758 -253.596394) (xy 141.854682 -253.496318) (xy 141.754606 -253.596394) (xy 141.754606 -253.640844)
			(xy 141.954758 -253.640844)
		)
		(stroke
			(width 0)
			(type solid)
		)
		(fill yes)
		(layer "In2.Cu")
		(net "M_I_CPU1_SA_CA<2>")
	)
	(gr_poly
		(pts
			(xy 141.954758 -253.192534) (xy 141.954758 -253.148084) (xy 141.754606 -253.148084) (xy 141.754606 -253.192534)
			(xy 141.854682 -253.29261)
		)
		(stroke
			(width 0)
			(type solid)
		)
		(fill yes)
		(layer "In2.Cu")
		(net "M_I_CPU1_SA_CA<1>")
	)
	(gr_poly
		(pts
			(xy 141.954758 -251.976382) (xy 141.854682 -251.876306) (xy 141.754606 -251.976382) (xy 141.754606 -252.020832)
			(xy 141.954758 -252.020832)
		)
		(stroke
			(width 0)
			(type solid)
		)
		(fill yes)
		(layer "In2.Cu")
		(net "M_I_CPU1_SA_CS_N<1>")
	)
	(gr_poly
		(pts
			(xy 141.954758 -250.35637) (xy 141.854682 -250.256294) (xy 141.754606 -250.35637) (xy 141.754606 -250.40082)
			(xy 141.954758 -250.40082)
		)
		(stroke
			(width 0)
			(type solid)
		)
		(fill yes)
		(layer "In2.Cu")
		(net "M_I_CPU1_ALERT_R_N")
	)
	(gr_poly
		(pts
			(xy 141.954758 -248.736358) (xy 141.854682 -248.636282) (xy 141.754606 -248.736358) (xy 141.754606 -248.780808)
			(xy 141.954758 -248.780808)
		)
		(stroke
			(width 0)
			(type solid)
		)
		(fill yes)
		(layer "In2.Cu")
		(net "M_I_CPU1_SA_CB<5>")
	)
	(gr_poly
		(pts
			(xy 141.954758 -248.332498) (xy 141.954758 -248.288048) (xy 141.754606 -248.288048) (xy 141.754606 -248.332498)
			(xy 141.854682 -248.432574)
		)
		(stroke
			(width 0)
			(type solid)
		)
		(fill yes)
		(layer "In2.Cu")
		(net "M_I_CPU1_SA_CB<6>")
	)
	(gr_poly
		(pts
			(xy 141.954758 -247.116092) (xy 141.854682 -247.01627) (xy 141.754606 -247.116092) (xy 141.754606 -247.163844)
			(xy 141.954758 -247.163844)
		)
		(stroke
			(width 0)
			(type solid)
		)
		(fill yes)
		(layer "In2.Cu")
		(net "M_I_CPU1_SA_DQS_DN<9>")
	)
	(gr_poly
		(pts
			(xy 141.954758 -246.71274) (xy 141.954758 -246.664988) (xy 141.754606 -246.664988) (xy 141.754606 -246.71274)
			(xy 141.854682 -246.812562)
		)
		(stroke
			(width 0)
			(type solid)
		)
		(fill yes)
		(layer "In2.Cu")
		(net "M_I_CPU1_SA_DQS_DN<4>")
	)
	(gr_poly
		(pts
			(xy 141.954758 -245.496334) (xy 141.854682 -245.396258) (xy 141.754606 -245.496334) (xy 141.754606 -245.540784)
			(xy 141.954758 -245.540784)
		)
		(stroke
			(width 0)
			(type solid)
		)
		(fill yes)
		(layer "In2.Cu")
		(net "M_I_CPU1_SA_CB<1>")
	)
	(gr_poly
		(pts
			(xy 141.954758 -245.092474) (xy 141.954758 -245.048024) (xy 141.754606 -245.048024) (xy 141.754606 -245.092474)
			(xy 141.854682 -245.19255)
		)
		(stroke
			(width 0)
			(type solid)
		)
		(fill yes)
		(layer "In2.Cu")
		(net "M_I_CPU1_SA_CB<2>")
	)
	(gr_poly
		(pts
			(xy 141.954758 -243.876322) (xy 141.854682 -243.776246) (xy 141.754606 -243.876322) (xy 141.754606 -243.920772)
			(xy 141.954758 -243.920772)
		)
		(stroke
			(width 0)
			(type solid)
		)
		(fill yes)
		(layer "In2.Cu")
		(net "M_I_CPU1_SA_DQ<29>")
	)
	(gr_poly
		(pts
			(xy 141.954758 -243.472462) (xy 141.954758 -243.428012) (xy 141.754606 -243.428012) (xy 141.754606 -243.472462)
			(xy 141.854682 -243.572538)
		)
		(stroke
			(width 0)
			(type solid)
		)
		(fill yes)
		(layer "In2.Cu")
		(net "M_I_CPU1_SA_DQ<30>")
	)
	(gr_poly
		(pts
			(xy 141.954758 -242.256056) (xy 141.854682 -242.156234) (xy 141.754606 -242.256056) (xy 141.754606 -242.303808)
			(xy 141.954758 -242.303808)
		)
		(stroke
			(width 0)
			(type solid)
		)
		(fill yes)
		(layer "In2.Cu")
		(net "M_I_CPU1_SA_DQS_DN<8>")
	)
	(gr_poly
		(pts
			(xy 141.954758 -241.852704) (xy 141.954758 -241.804952) (xy 141.754606 -241.804952) (xy 141.754606 -241.852704)
			(xy 141.854682 -241.952526)
		)
		(stroke
			(width 0)
			(type solid)
		)
		(fill yes)
		(layer "In2.Cu")
		(net "M_I_CPU1_SA_DQS_DN<3>")
	)
	(gr_poly
		(pts
			(xy 141.954758 -240.636298) (xy 141.854682 -240.536222) (xy 141.754606 -240.636298) (xy 141.754606 -240.680748)
			(xy 141.954758 -240.680748)
		)
		(stroke
			(width 0)
			(type solid)
		)
		(fill yes)
		(layer "In2.Cu")
		(net "M_I_CPU1_SA_DQ<25>")
	)
	(gr_poly
		(pts
			(xy 141.954758 -240.232438) (xy 141.954758 -240.187988) (xy 141.754606 -240.187988) (xy 141.754606 -240.232438)
			(xy 141.854682 -240.332514)
		)
		(stroke
			(width 0)
			(type solid)
		)
		(fill yes)
		(layer "In2.Cu")
		(net "M_I_CPU1_SA_DQ<26>")
	)
	(gr_poly
		(pts
			(xy 141.954758 -239.016286) (xy 141.854682 -238.91621) (xy 141.754606 -239.016286) (xy 141.754606 -239.060736)
			(xy 141.954758 -239.060736)
		)
		(stroke
			(width 0)
			(type solid)
		)
		(fill yes)
		(layer "In2.Cu")
		(net "M_I_CPU1_SA_DQ<21>")
	)
	(gr_poly
		(pts
			(xy 141.954758 -238.612426) (xy 141.954758 -238.567976) (xy 141.754606 -238.567976) (xy 141.754606 -238.612426)
			(xy 141.854682 -238.712502)
		)
		(stroke
			(width 0)
			(type solid)
		)
		(fill yes)
		(layer "In2.Cu")
		(net "M_I_CPU1_SA_DQ<22>")
	)
	(gr_poly
		(pts
			(xy 141.954758 -237.39602) (xy 141.854682 -237.296198) (xy 141.754606 -237.39602) (xy 141.754606 -237.443772)
			(xy 141.954758 -237.443772)
		)
		(stroke
			(width 0)
			(type solid)
		)
		(fill yes)
		(layer "In2.Cu")
		(net "M_I_CPU1_SA_DQS_DN<7>")
	)
	(gr_poly
		(pts
			(xy 141.954758 -236.992668) (xy 141.954758 -236.944916) (xy 141.754606 -236.944916) (xy 141.754606 -236.992668)
			(xy 141.854682 -237.09249)
		)
		(stroke
			(width 0)
			(type solid)
		)
		(fill yes)
		(layer "In2.Cu")
		(net "M_I_CPU1_SA_DQS_DN<2>")
	)
	(gr_poly
		(pts
			(xy 141.954758 -235.776262) (xy 141.854682 -235.676186) (xy 141.754606 -235.776262) (xy 141.754606 -235.820712)
			(xy 141.954758 -235.820712)
		)
		(stroke
			(width 0)
			(type solid)
		)
		(fill yes)
		(layer "In2.Cu")
		(net "M_I_CPU1_SA_DQ<17>")
	)
	(gr_poly
		(pts
			(xy 141.954758 -235.372402) (xy 141.954758 -235.327952) (xy 141.754606 -235.327952) (xy 141.754606 -235.372402)
			(xy 141.854682 -235.472478)
		)
		(stroke
			(width 0)
			(type solid)
		)
		(fill yes)
		(layer "In2.Cu")
		(net "M_I_CPU1_SA_DQ<18>")
	)
	(gr_poly
		(pts
			(xy 141.954758 -234.15625) (xy 141.854682 -234.056174) (xy 141.754606 -234.15625) (xy 141.754606 -234.2007)
			(xy 141.954758 -234.2007)
		)
		(stroke
			(width 0)
			(type solid)
		)
		(fill yes)
		(layer "In2.Cu")
		(net "M_I_CPU1_SA_DQ<13>")
	)
	(gr_poly
		(pts
			(xy 141.954758 -233.75239) (xy 141.954758 -233.70794) (xy 141.754606 -233.70794) (xy 141.754606 -233.75239)
			(xy 141.854682 -233.852466)
		)
		(stroke
			(width 0)
			(type solid)
		)
		(fill yes)
		(layer "In2.Cu")
		(net "M_I_CPU1_SA_DQ<14>")
	)
	(gr_poly
		(pts
			(xy 141.954758 -232.535984) (xy 141.854682 -232.436162) (xy 141.754606 -232.535984) (xy 141.754606 -232.583736)
			(xy 141.954758 -232.583736)
		)
		(stroke
			(width 0)
			(type solid)
		)
		(fill yes)
		(layer "In2.Cu")
		(net "M_I_CPU1_SA_DQS_DN<6>")
	)
	(gr_poly
		(pts
			(xy 141.954758 -232.132632) (xy 141.954758 -232.08488) (xy 141.754606 -232.08488) (xy 141.754606 -232.132632)
			(xy 141.854682 -232.232454)
		)
		(stroke
			(width 0)
			(type solid)
		)
		(fill yes)
		(layer "In2.Cu")
		(net "M_I_CPU1_SA_DQS_DN<1>")
	)
	(gr_poly
		(pts
			(xy 141.954758 -230.916226) (xy 141.854682 -230.81615) (xy 141.754606 -230.916226) (xy 141.754606 -230.960676)
			(xy 141.954758 -230.960676)
		)
		(stroke
			(width 0)
			(type solid)
		)
		(fill yes)
		(layer "In2.Cu")
		(net "M_I_CPU1_SA_DQ<9>")
	)
	(gr_poly
		(pts
			(xy 141.954758 -230.51262) (xy 141.954758 -230.46817) (xy 141.754606 -230.46817) (xy 141.754606 -230.51262)
			(xy 141.854682 -230.612696)
		)
		(stroke
			(width 0)
			(type solid)
		)
		(fill yes)
		(layer "In2.Cu")
		(net "M_I_CPU1_SA_DQ<10>")
	)
	(gr_poly
		(pts
			(xy 142.010638 -229.429056) (xy 141.974062 -229.292404) (xy 141.935708 -229.270052) (xy 141.835632 -229.44328)
			(xy 141.87424 -229.465632)
		)
		(stroke
			(width 0)
			(type solid)
		)
		(fill yes)
		(layer "In2.Cu")
		(net "M_I_CPU1_SA_DQ<7>")
	)
	(gr_poly
		(pts
			(xy 142.010638 -227.809044) (xy 141.974062 -227.672392) (xy 141.935708 -227.65004) (xy 141.835632 -227.823268)
			(xy 141.87424 -227.84562)
		)
		(stroke
			(width 0)
			(type solid)
		)
		(fill yes)
		(layer "In2.Cu")
		(net "M_I_CPU1_SA_DQ<6>")
	)
	(gr_poly
		(pts
			(xy 142.010638 -226.18954) (xy 141.974062 -226.053142) (xy 141.93266 -226.029266) (xy 141.832838 -226.202494)
			(xy 141.873986 -226.22637)
		)
		(stroke
			(width 0)
			(type solid)
		)
		(fill yes)
		(layer "In2.Cu")
		(net "M_I_CPU1_SA_DQS_DP<5>")
	)
	(gr_poly
		(pts
			(xy 142.010638 -224.569528) (xy 141.974062 -224.43313) (xy 141.93266 -224.409254) (xy 141.832838 -224.582482)
			(xy 141.873986 -224.606104)
		)
		(stroke
			(width 0)
			(type solid)
		)
		(fill yes)
		(layer "In2.Cu")
		(net "M_I_CPU1_SA_DQS_DN<0>")
	)
	(gr_poly
		(pts
			(xy 142.0114 -222.948246) (xy 141.974824 -222.811594) (xy 141.936216 -222.789496) (xy 141.836394 -222.962724)
			(xy 141.874748 -222.984822)
		)
		(stroke
			(width 0)
			(type solid)
		)
		(fill yes)
		(layer "In2.Cu")
		(net "M_I_CPU1_SA_DQ<3>")
	)
	(gr_poly
		(pts
			(xy 142.17396 -293.874952) (xy 142.073884 -293.701724) (xy 142.03553 -293.724076) (xy 141.998954 -293.860728)
			(xy 142.135352 -293.897304)
		)
		(stroke
			(width 0)
			(type solid)
		)
		(fill yes)
		(layer "In2.Cu")
		(net "M_I_CPU1_SB_DQ<31>")
	)
	(gr_poly
		(pts
			(xy 142.254732 -292.108128) (xy 142.154656 -292.008052) (xy 142.05458 -292.108128) (xy 142.05458 -292.152578)
			(xy 142.254732 -292.152578)
		)
		(stroke
			(width 0)
			(type solid)
		)
		(fill yes)
		(layer "In2.Cu")
		(net "M_I_CPU1_SB_DQ<28>")
	)
	(gr_poly
		(pts
			(xy 142.254732 -291.704522) (xy 142.254732 -291.65677) (xy 142.05458 -291.65677) (xy 142.05458 -291.704522)
			(xy 142.154656 -291.804344)
		)
		(stroke
			(width 0)
			(type solid)
		)
		(fill yes)
		(layer "In2.Cu")
		(net "M_I_CPU1_SB_DQS_DP<8>")
	)
	(gr_poly
		(pts
			(xy 142.254732 -290.487862) (xy 142.154656 -290.38804) (xy 142.05458 -290.487862) (xy 142.05458 -290.535614)
			(xy 142.254732 -290.535614)
		)
		(stroke
			(width 0)
			(type solid)
		)
		(fill yes)
		(layer "In2.Cu")
		(net "M_I_CPU1_SB_DQS_DP<3>")
	)
	(gr_poly
		(pts
			(xy 142.254732 -290.084256) (xy 142.254732 -290.039806) (xy 142.05458 -290.039806) (xy 142.05458 -290.084256)
			(xy 142.154656 -290.184332)
		)
		(stroke
			(width 0)
			(type solid)
		)
		(fill yes)
		(layer "In2.Cu")
		(net "M_I_CPU1_SB_DQ<27>")
	)
	(gr_poly
		(pts
			(xy 142.254732 -288.868104) (xy 142.154656 -288.768028) (xy 142.05458 -288.868104) (xy 142.05458 -288.912554)
			(xy 142.254732 -288.912554)
		)
		(stroke
			(width 0)
			(type solid)
		)
		(fill yes)
		(layer "In2.Cu")
		(net "M_I_CPU1_SB_DQ<24>")
	)
	(gr_poly
		(pts
			(xy 142.254732 -288.464498) (xy 142.254732 -288.420048) (xy 142.05458 -288.420048) (xy 142.05458 -288.464498)
			(xy 142.154656 -288.564574)
		)
		(stroke
			(width 0)
			(type solid)
		)
		(fill yes)
		(layer "In2.Cu")
		(net "M_I_CPU1_SB_DQ<23>")
	)
	(gr_poly
		(pts
			(xy 142.254732 -287.248092) (xy 142.154656 -287.148016) (xy 142.05458 -287.248092) (xy 142.05458 -287.292542)
			(xy 142.254732 -287.292542)
		)
		(stroke
			(width 0)
			(type solid)
		)
		(fill yes)
		(layer "In2.Cu")
		(net "M_I_CPU1_SB_DQ<20>")
	)
	(gr_poly
		(pts
			(xy 142.254732 -286.844486) (xy 142.254732 -286.796734) (xy 142.05458 -286.796734) (xy 142.05458 -286.844486)
			(xy 142.154656 -286.944562)
		)
		(stroke
			(width 0)
			(type solid)
		)
		(fill yes)
		(layer "In2.Cu")
		(net "M_I_CPU1_SB_DQS_DP<7>")
	)
	(gr_poly
		(pts
			(xy 142.254732 -285.62808) (xy 142.154656 -285.528258) (xy 142.05458 -285.62808) (xy 142.05458 -285.675832)
			(xy 142.254732 -285.675832)
		)
		(stroke
			(width 0)
			(type solid)
		)
		(fill yes)
		(layer "In2.Cu")
		(net "M_I_CPU1_SB_DQS_DP<2>")
	)
	(gr_poly
		(pts
			(xy 142.254732 -285.224474) (xy 142.254732 -285.180024) (xy 142.05458 -285.180024) (xy 142.05458 -285.224474)
			(xy 142.154656 -285.32455)
		)
		(stroke
			(width 0)
			(type solid)
		)
		(fill yes)
		(layer "In2.Cu")
		(net "M_I_CPU1_SB_DQ<19>")
	)
	(gr_poly
		(pts
			(xy 142.254732 -284.008322) (xy 142.154656 -283.908246) (xy 142.05458 -284.008322) (xy 142.05458 -284.052772)
			(xy 142.254732 -284.052772)
		)
		(stroke
			(width 0)
			(type solid)
		)
		(fill yes)
		(layer "In2.Cu")
		(net "M_I_CPU1_SB_DQ<16>")
	)
	(gr_poly
		(pts
			(xy 142.254732 -283.604462) (xy 142.254732 -283.560012) (xy 142.05458 -283.560012) (xy 142.05458 -283.604462)
			(xy 142.154656 -283.704538)
		)
		(stroke
			(width 0)
			(type solid)
		)
		(fill yes)
		(layer "In2.Cu")
		(net "M_I_CPU1_SB_DQ<15>")
	)
	(gr_poly
		(pts
			(xy 142.254732 -282.38831) (xy 142.154656 -282.288234) (xy 142.05458 -282.38831) (xy 142.05458 -282.43276)
			(xy 142.254732 -282.43276)
		)
		(stroke
			(width 0)
			(type solid)
		)
		(fill yes)
		(layer "In2.Cu")
		(net "M_I_CPU1_SB_DQ<12>")
	)
	(gr_poly
		(pts
			(xy 142.254732 -281.984704) (xy 142.254732 -281.936952) (xy 142.05458 -281.936952) (xy 142.05458 -281.984704)
			(xy 142.154656 -282.084526)
		)
		(stroke
			(width 0)
			(type solid)
		)
		(fill yes)
		(layer "In2.Cu")
		(net "M_I_CPU1_SB_DQS_DP<6>")
	)
	(gr_poly
		(pts
			(xy 142.254732 -280.768044) (xy 142.154656 -280.668222) (xy 142.05458 -280.768044) (xy 142.05458 -280.815796)
			(xy 142.254732 -280.815796)
		)
		(stroke
			(width 0)
			(type solid)
		)
		(fill yes)
		(layer "In2.Cu")
		(net "M_I_CPU1_SB_DQS_DP<1>")
	)
	(gr_poly
		(pts
			(xy 142.254732 -280.364438) (xy 142.254732 -280.319988) (xy 142.05458 -280.319988) (xy 142.05458 -280.364438)
			(xy 142.154656 -280.464514)
		)
		(stroke
			(width 0)
			(type solid)
		)
		(fill yes)
		(layer "In2.Cu")
		(net "M_I_CPU1_SB_DQ<11>")
	)
	(gr_poly
		(pts
			(xy 142.254732 -279.148286) (xy 142.154656 -279.04821) (xy 142.05458 -279.148286) (xy 142.05458 -279.192736)
			(xy 142.254732 -279.192736)
		)
		(stroke
			(width 0)
			(type solid)
		)
		(fill yes)
		(layer "In2.Cu")
		(net "M_I_CPU1_SB_DQ<8>")
	)
	(gr_poly
		(pts
			(xy 142.254732 -278.744426) (xy 142.254732 -278.699976) (xy 142.05458 -278.699976) (xy 142.05458 -278.744426)
			(xy 142.154656 -278.844502)
		)
		(stroke
			(width 0)
			(type solid)
		)
		(fill yes)
		(layer "In2.Cu")
		(net "M_I_CPU1_SB_DQ<7>")
	)
	(gr_poly
		(pts
			(xy 142.254732 -277.528274) (xy 142.154656 -277.428198) (xy 142.05458 -277.528274) (xy 142.05458 -277.572724)
			(xy 142.254732 -277.572724)
		)
		(stroke
			(width 0)
			(type solid)
		)
		(fill yes)
		(layer "In2.Cu")
		(net "M_I_CPU1_SB_DQ<4>")
	)
	(gr_poly
		(pts
			(xy 142.254732 -277.124668) (xy 142.254732 -277.076916) (xy 142.05458 -277.076916) (xy 142.05458 -277.124668)
			(xy 142.154656 -277.22449)
		)
		(stroke
			(width 0)
			(type solid)
		)
		(fill yes)
		(layer "In2.Cu")
		(net "M_I_CPU1_SB_DQS_DP<5>")
	)
	(gr_poly
		(pts
			(xy 142.254732 -275.908008) (xy 142.154656 -275.808186) (xy 142.05458 -275.908008) (xy 142.05458 -275.95576)
			(xy 142.254732 -275.95576)
		)
		(stroke
			(width 0)
			(type solid)
		)
		(fill yes)
		(layer "In2.Cu")
		(net "M_I_CPU1_SB_DQS_DP<0>")
	)
	(gr_poly
		(pts
			(xy 142.254732 -275.504402) (xy 142.254732 -275.459952) (xy 142.05458 -275.459952) (xy 142.05458 -275.504402)
			(xy 142.154656 -275.604478)
		)
		(stroke
			(width 0)
			(type solid)
		)
		(fill yes)
		(layer "In2.Cu")
		(net "M_I_CPU1_SB_DQ<3>")
	)
	(gr_poly
		(pts
			(xy 142.254732 -274.28825) (xy 142.154656 -274.188174) (xy 142.05458 -274.28825) (xy 142.05458 -274.3327)
			(xy 142.254732 -274.3327)
		)
		(stroke
			(width 0)
			(type solid)
		)
		(fill yes)
		(layer "In2.Cu")
		(net "M_I_CPU1_SB_DQ<0>")
	)
	(gr_poly
		(pts
			(xy 142.254732 -273.88439) (xy 142.254732 -273.83994) (xy 142.05458 -273.83994) (xy 142.05458 -273.88439)
			(xy 142.154656 -273.984466)
		)
		(stroke
			(width 0)
			(type solid)
		)
		(fill yes)
		(layer "In2.Cu")
		(net "M_I_CPU1_SB_CB<3>")
	)
	(gr_poly
		(pts
			(xy 142.254732 -272.668238) (xy 142.154656 -272.568162) (xy 142.05458 -272.668238) (xy 142.05458 -272.712688)
			(xy 142.254732 -272.712688)
		)
		(stroke
			(width 0)
			(type solid)
		)
		(fill yes)
		(layer "In2.Cu")
		(net "M_I_CPU1_SB_CB<0>")
	)
	(gr_poly
		(pts
			(xy 142.254732 -272.264632) (xy 142.254732 -272.21688) (xy 142.05458 -272.21688) (xy 142.05458 -272.264632)
			(xy 142.154656 -272.364454)
		)
		(stroke
			(width 0)
			(type solid)
		)
		(fill yes)
		(layer "In2.Cu")
		(net "M_I_CPU1_SB_DQS_DP<4>")
	)
	(gr_poly
		(pts
			(xy 142.254732 -271.047972) (xy 142.154656 -270.94815) (xy 142.05458 -271.047972) (xy 142.05458 -271.095724)
			(xy 142.254732 -271.095724)
		)
		(stroke
			(width 0)
			(type solid)
		)
		(fill yes)
		(layer "In2.Cu")
		(net "M_I_CPU1_SB_DQS_DP<9>")
	)
	(gr_poly
		(pts
			(xy 142.254732 -270.644366) (xy 142.254732 -270.599916) (xy 142.05458 -270.599916) (xy 142.05458 -270.644366)
			(xy 142.154656 -270.744442)
		)
		(stroke
			(width 0)
			(type solid)
		)
		(fill yes)
		(layer "In2.Cu")
		(net "M_I_CPU1_SB_CB<7>")
	)
	(gr_poly
		(pts
			(xy 142.254732 -269.428214) (xy 142.154656 -269.328138) (xy 142.05458 -269.428214) (xy 142.05458 -269.472664)
			(xy 142.254732 -269.472664)
		)
		(stroke
			(width 0)
			(type solid)
		)
		(fill yes)
		(layer "In2.Cu")
		(net "M_I_CPU1_SB_CB<4>")
	)
	(gr_poly
		(pts
			(xy 142.254732 -267.404342) (xy 142.254732 -267.359892) (xy 142.05458 -267.359892) (xy 142.05458 -267.404342)
			(xy 142.154656 -267.504418)
		)
		(stroke
			(width 0)
			(type solid)
		)
		(fill yes)
		(layer "In2.Cu")
		(net "M_I_CPU1_SB_RSP<0>")
	)
	(gr_poly
		(pts
			(xy 142.254732 -265.78433) (xy 142.254732 -265.73988) (xy 142.05458 -265.73988) (xy 142.05458 -265.78433)
			(xy 142.154656 -265.884406)
		)
		(stroke
			(width 0)
			(type solid)
		)
		(fill yes)
		(layer "In2.Cu")
		(net "M_I_CPU1_SB_CS_N<0>")
	)
	(gr_poly
		(pts
			(xy 142.254732 -264.568178) (xy 142.154656 -264.468102) (xy 142.05458 -264.568178) (xy 142.05458 -264.612628)
			(xy 142.254732 -264.612628)
		)
		(stroke
			(width 0)
			(type solid)
		)
		(fill yes)
		(layer "In2.Cu")
		(net "M_I_CPU1_SB_CA<6>")
	)
	(gr_poly
		(pts
			(xy 142.254732 -264.164318) (xy 142.254732 -264.119868) (xy 142.05458 -264.119868) (xy 142.05458 -264.164318)
			(xy 142.154656 -264.264394)
		)
		(stroke
			(width 0)
			(type solid)
		)
		(fill yes)
		(layer "In2.Cu")
		(net "M_I_CPU1_SB_CA<5>")
	)
	(gr_poly
		(pts
			(xy 142.254732 -262.948166) (xy 142.154656 -262.84809) (xy 142.05458 -262.948166) (xy 142.05458 -262.992616)
			(xy 142.254732 -262.992616)
		)
		(stroke
			(width 0)
			(type solid)
		)
		(fill yes)
		(layer "In2.Cu")
		(net "M_I_CPU1_SB_CA<2>")
	)
	(gr_poly
		(pts
			(xy 142.254732 -262.544306) (xy 142.254732 -262.499856) (xy 142.05458 -262.499856) (xy 142.05458 -262.544306)
			(xy 142.154656 -262.644382)
		)
		(stroke
			(width 0)
			(type solid)
		)
		(fill yes)
		(layer "In2.Cu")
		(net "M_I_CPU1_SB_CA<1>")
	)
	(gr_poly
		(pts
			(xy 142.274036 -293.328344) (xy 142.310866 -293.191692) (xy 142.174214 -293.155116) (xy 142.135606 -293.177468)
			(xy 142.235682 -293.350696)
		)
		(stroke
			(width 0)
			(type solid)
		)
		(fill yes)
		(layer "In2.Cu")
		(net "M_I_CPU1_SB_DQ<29>")
	)
	(gr_poly
		(pts
			(xy 142.343886 -229.555548) (xy 142.305278 -229.533196) (xy 142.168626 -229.569772) (xy 142.205456 -229.706424)
			(xy 142.24381 -229.728776)
		)
		(stroke
			(width 0)
			(type solid)
		)
		(fill yes)
		(layer "In2.Cu")
		(net "M_I_CPU1_SA_DQ<8>")
	)
	(gr_poly
		(pts
			(xy 142.343886 -227.93579) (xy 142.305278 -227.913438) (xy 142.168626 -227.950014) (xy 142.205456 -228.086666)
			(xy 142.24381 -228.109018)
		)
		(stroke
			(width 0)
			(type solid)
		)
		(fill yes)
		(layer "In2.Cu")
		(net "M_I_CPU1_SA_DQ<5>")
	)
	(gr_poly
		(pts
			(xy 142.343886 -226.315778) (xy 142.305278 -226.293426) (xy 142.168626 -226.330002) (xy 142.205456 -226.466654)
			(xy 142.24381 -226.489006)
		)
		(stroke
			(width 0)
			(type solid)
		)
		(fill yes)
		(layer "In2.Cu")
		(net "M_I_CPU1_SA_DQ<4>")
	)
	(gr_poly
		(pts
			(xy 142.34668 -224.696528) (xy 142.305532 -224.672652) (xy 142.16888 -224.709482) (xy 142.205456 -224.84588)
			(xy 142.246858 -224.869756)
		)
		(stroke
			(width 0)
			(type solid)
		)
		(fill yes)
		(layer "In2.Cu")
		(net "M_I_CPU1_SA_DQS_DN<5>")
	)
	(gr_poly
		(pts
			(xy 142.34668 -223.076516) (xy 142.305532 -223.05264) (xy 142.16888 -223.08947) (xy 142.205456 -223.225868)
			(xy 142.246858 -223.249744)
		)
		(stroke
			(width 0)
			(type solid)
		)
		(fill yes)
		(layer "In2.Cu")
		(net "M_I_CPU1_SA_DQS_DP<0>")
	)
	(gr_poly
		(pts
			(xy 142.424912 -256.026158) (xy 142.324836 -255.926336) (xy 142.22476 -256.026158) (xy 142.22476 -256.07391)
			(xy 142.424912 -256.07391)
		)
		(stroke
			(width 0)
			(type solid)
		)
		(fill yes)
		(layer "In2.Cu")
		(net "M_I_CPU1_CLK_DP<0>")
	)
	(gr_poly
		(pts
			(xy 142.424912 -255.622552) (xy 142.424912 -255.578102) (xy 142.22476 -255.578102) (xy 142.22476 -255.622552)
			(xy 142.324836 -255.722628)
		)
		(stroke
			(width 0)
			(type solid)
		)
		(fill yes)
		(layer "In2.Cu")
		(net "M_I_CPU1_SA_PAR")
	)
	(gr_poly
		(pts
			(xy 142.424912 -254.4064) (xy 142.324836 -254.306324) (xy 142.22476 -254.4064) (xy 142.22476 -254.45085)
			(xy 142.424912 -254.45085)
		)
		(stroke
			(width 0)
			(type solid)
		)
		(fill yes)
		(layer "In2.Cu")
		(net "M_I_CPU1_SA_CA<4>")
	)
	(gr_poly
		(pts
			(xy 142.424912 -254.00254) (xy 142.424912 -253.95809) (xy 142.22476 -253.95809) (xy 142.22476 -254.00254)
			(xy 142.324836 -254.102616)
		)
		(stroke
			(width 0)
			(type solid)
		)
		(fill yes)
		(layer "In2.Cu")
		(net "M_I_CPU1_SA_CA<3>")
	)
	(gr_poly
		(pts
			(xy 142.424912 -252.786388) (xy 142.324836 -252.686312) (xy 142.22476 -252.786388) (xy 142.22476 -252.830838)
			(xy 142.424912 -252.830838)
		)
		(stroke
			(width 0)
			(type solid)
		)
		(fill yes)
		(layer "In2.Cu")
		(net "M_I_CPU1_SA_CA<0>")
	)
	(gr_poly
		(pts
			(xy 142.424912 -251.166376) (xy 142.324836 -251.0663) (xy 142.22476 -251.166376) (xy 142.22476 -251.210826)
			(xy 142.424912 -251.210826)
		)
		(stroke
			(width 0)
			(type solid)
		)
		(fill yes)
		(layer "In2.Cu")
		(net "M_I_CPU1_SA_CS_N<0>")
	)
	(gr_poly
		(pts
			(xy 142.424912 -250.762516) (xy 142.424912 -250.718066) (xy 142.22476 -250.718066) (xy 142.22476 -250.762516)
			(xy 142.324836 -250.862592)
		)
		(stroke
			(width 0)
			(type solid)
		)
		(fill yes)
		(layer "In2.Cu")
		(net "M_I_CPU1_RESET_N")
	)
	(gr_poly
		(pts
			(xy 142.424912 -249.142504) (xy 142.424912 -249.098054) (xy 142.22476 -249.098054) (xy 142.22476 -249.142504)
			(xy 142.324836 -249.24258)
		)
		(stroke
			(width 0)
			(type solid)
		)
		(fill yes)
		(layer "In2.Cu")
		(net "M_I_CPU1_SA_CB<7>")
	)
	(gr_poly
		(pts
			(xy 142.424912 -247.926352) (xy 142.324836 -247.826276) (xy 142.22476 -247.926352) (xy 142.22476 -247.970802)
			(xy 142.424912 -247.970802)
		)
		(stroke
			(width 0)
			(type solid)
		)
		(fill yes)
		(layer "In2.Cu")
		(net "M_I_CPU1_SA_CB<4>")
	)
	(gr_poly
		(pts
			(xy 142.424912 -247.522746) (xy 142.424912 -247.474994) (xy 142.22476 -247.474994) (xy 142.22476 -247.522746)
			(xy 142.324836 -247.622568)
		)
		(stroke
			(width 0)
			(type solid)
		)
		(fill yes)
		(layer "In2.Cu")
		(net "M_I_CPU1_SA_DQS_DP<9>")
	)
	(gr_poly
		(pts
			(xy 142.424912 -246.306086) (xy 142.324836 -246.206264) (xy 142.22476 -246.306086) (xy 142.22476 -246.353838)
			(xy 142.424912 -246.353838)
		)
		(stroke
			(width 0)
			(type solid)
		)
		(fill yes)
		(layer "In2.Cu")
		(net "M_I_CPU1_SA_DQS_DP<4>")
	)
	(gr_poly
		(pts
			(xy 142.424912 -245.90248) (xy 142.424912 -245.85803) (xy 142.22476 -245.85803) (xy 142.22476 -245.90248)
			(xy 142.324836 -246.002556)
		)
		(stroke
			(width 0)
			(type solid)
		)
		(fill yes)
		(layer "In2.Cu")
		(net "M_I_CPU1_SA_CB<3>")
	)
	(gr_poly
		(pts
			(xy 142.424912 -244.686328) (xy 142.324836 -244.586252) (xy 142.22476 -244.686328) (xy 142.22476 -244.730778)
			(xy 142.424912 -244.730778)
		)
		(stroke
			(width 0)
			(type solid)
		)
		(fill yes)
		(layer "In2.Cu")
		(net "M_I_CPU1_SA_CB<0>")
	)
	(gr_poly
		(pts
			(xy 142.424912 -244.282468) (xy 142.424912 -244.238018) (xy 142.22476 -244.238018) (xy 142.22476 -244.282468)
			(xy 142.324836 -244.382544)
		)
		(stroke
			(width 0)
			(type solid)
		)
		(fill yes)
		(layer "In2.Cu")
		(net "M_I_CPU1_SA_DQ<31>")
	)
	(gr_poly
		(pts
			(xy 142.424912 -243.066316) (xy 142.324836 -242.96624) (xy 142.22476 -243.066316) (xy 142.22476 -243.110766)
			(xy 142.424912 -243.110766)
		)
		(stroke
			(width 0)
			(type solid)
		)
		(fill yes)
		(layer "In2.Cu")
		(net "M_I_CPU1_SA_DQ<28>")
	)
	(gr_poly
		(pts
			(xy 142.424912 -242.66271) (xy 142.424912 -242.614958) (xy 142.22476 -242.614958) (xy 142.22476 -242.66271)
			(xy 142.324836 -242.762532)
		)
		(stroke
			(width 0)
			(type solid)
		)
		(fill yes)
		(layer "In2.Cu")
		(net "M_I_CPU1_SA_DQS_DP<8>")
	)
	(gr_poly
		(pts
			(xy 142.424912 -241.44605) (xy 142.324836 -241.346228) (xy 142.22476 -241.44605) (xy 142.22476 -241.493802)
			(xy 142.424912 -241.493802)
		)
		(stroke
			(width 0)
			(type solid)
		)
		(fill yes)
		(layer "In2.Cu")
		(net "M_I_CPU1_SA_DQS_DP<3>")
	)
	(gr_poly
		(pts
			(xy 142.424912 -241.042444) (xy 142.424912 -240.997994) (xy 142.22476 -240.997994) (xy 142.22476 -241.042444)
			(xy 142.324836 -241.14252)
		)
		(stroke
			(width 0)
			(type solid)
		)
		(fill yes)
		(layer "In2.Cu")
		(net "M_I_CPU1_SA_DQ<27>")
	)
	(gr_poly
		(pts
			(xy 142.424912 -239.826292) (xy 142.324836 -239.726216) (xy 142.22476 -239.826292) (xy 142.22476 -239.870742)
			(xy 142.424912 -239.870742)
		)
		(stroke
			(width 0)
			(type solid)
		)
		(fill yes)
		(layer "In2.Cu")
		(net "M_I_CPU1_SA_DQ<24>")
	)
	(gr_poly
		(pts
			(xy 142.424912 -239.422432) (xy 142.424912 -239.377982) (xy 142.22476 -239.377982) (xy 142.22476 -239.422432)
			(xy 142.324836 -239.522508)
		)
		(stroke
			(width 0)
			(type solid)
		)
		(fill yes)
		(layer "In2.Cu")
		(net "M_I_CPU1_SA_DQ<23>")
	)
	(gr_poly
		(pts
			(xy 142.424912 -238.20628) (xy 142.324836 -238.106204) (xy 142.22476 -238.20628) (xy 142.22476 -238.25073)
			(xy 142.424912 -238.25073)
		)
		(stroke
			(width 0)
			(type solid)
		)
		(fill yes)
		(layer "In2.Cu")
		(net "M_I_CPU1_SA_DQ<20>")
	)
	(gr_poly
		(pts
			(xy 142.424912 -237.802674) (xy 142.424912 -237.754922) (xy 142.22476 -237.754922) (xy 142.22476 -237.802674)
			(xy 142.324836 -237.902496)
		)
		(stroke
			(width 0)
			(type solid)
		)
		(fill yes)
		(layer "In2.Cu")
		(net "M_I_CPU1_SA_DQS_DP<7>")
	)
	(gr_poly
		(pts
			(xy 142.424912 -236.586014) (xy 142.324836 -236.486192) (xy 142.22476 -236.586014) (xy 142.22476 -236.633766)
			(xy 142.424912 -236.633766)
		)
		(stroke
			(width 0)
			(type solid)
		)
		(fill yes)
		(layer "In2.Cu")
		(net "M_I_CPU1_SA_DQS_DP<2>")
	)
	(gr_poly
		(pts
			(xy 142.424912 -236.182408) (xy 142.424912 -236.137958) (xy 142.22476 -236.137958) (xy 142.22476 -236.182408)
			(xy 142.324836 -236.282484)
		)
		(stroke
			(width 0)
			(type solid)
		)
		(fill yes)
		(layer "In2.Cu")
		(net "M_I_CPU1_SA_DQ<19>")
	)
	(gr_poly
		(pts
			(xy 142.424912 -234.966256) (xy 142.324836 -234.86618) (xy 142.22476 -234.966256) (xy 142.22476 -235.010706)
			(xy 142.424912 -235.010706)
		)
		(stroke
			(width 0)
			(type solid)
		)
		(fill yes)
		(layer "In2.Cu")
		(net "M_I_CPU1_SA_DQ<16>")
	)
	(gr_poly
		(pts
			(xy 142.424912 -234.562396) (xy 142.424912 -234.517946) (xy 142.22476 -234.517946) (xy 142.22476 -234.562396)
			(xy 142.324836 -234.662472)
		)
		(stroke
			(width 0)
			(type solid)
		)
		(fill yes)
		(layer "In2.Cu")
		(net "M_I_CPU1_SA_DQ<15>")
	)
	(gr_poly
		(pts
			(xy 142.424912 -233.346244) (xy 142.324836 -233.246168) (xy 142.22476 -233.346244) (xy 142.22476 -233.390694)
			(xy 142.424912 -233.390694)
		)
		(stroke
			(width 0)
			(type solid)
		)
		(fill yes)
		(layer "In2.Cu")
		(net "M_I_CPU1_SA_DQ<12>")
	)
	(gr_poly
		(pts
			(xy 142.424912 -232.942638) (xy 142.424912 -232.894886) (xy 142.22476 -232.894886) (xy 142.22476 -232.942638)
			(xy 142.324836 -233.04246)
		)
		(stroke
			(width 0)
			(type solid)
		)
		(fill yes)
		(layer "In2.Cu")
		(net "M_I_CPU1_SA_DQS_DP<6>")
	)
	(gr_poly
		(pts
			(xy 142.424912 -231.725978) (xy 142.324836 -231.626156) (xy 142.22476 -231.725978) (xy 142.22476 -231.77373)
			(xy 142.424912 -231.77373)
		)
		(stroke
			(width 0)
			(type solid)
		)
		(fill yes)
		(layer "In2.Cu")
		(net "M_I_CPU1_SA_DQS_DP<1>")
	)
	(gr_poly
		(pts
			(xy 142.424912 -231.322626) (xy 142.424912 -231.278176) (xy 142.22476 -231.278176) (xy 142.22476 -231.322626)
			(xy 142.324836 -231.422702)
		)
		(stroke
			(width 0)
			(type solid)
		)
		(fill yes)
		(layer "In2.Cu")
		(net "M_I_CPU1_SA_DQ<11>")
	)
	(gr_poly
		(pts
			(xy 142.48003 -230.240078) (xy 142.443454 -230.103426) (xy 142.404846 -230.081328) (xy 142.30477 -230.254556)
			(xy 142.343378 -230.276654)
		)
		(stroke
			(width 0)
			(type solid)
		)
		(fill yes)
		(layer "In2.Cu")
		(net "M_I_CPU1_SA_DQ<10>")
	)
	(gr_poly
		(pts
			(xy 142.480538 -228.61905) (xy 142.443962 -228.482398) (xy 142.405608 -228.460046) (xy 142.305532 -228.633274)
			(xy 142.34414 -228.655626)
		)
		(stroke
			(width 0)
			(type solid)
		)
		(fill yes)
		(layer "In2.Cu")
		(net "M_I_CPU1_SA_DQ<7>")
	)
	(gr_poly
		(pts
			(xy 142.480538 -226.999038) (xy 142.443962 -226.862386) (xy 142.405608 -226.840034) (xy 142.305532 -227.013262)
			(xy 142.34414 -227.035614)
		)
		(stroke
			(width 0)
			(type solid)
		)
		(fill yes)
		(layer "In2.Cu")
		(net "M_I_CPU1_SA_DQ<6>")
	)
	(gr_poly
		(pts
			(xy 142.480538 -225.379534) (xy 142.443962 -225.243136) (xy 142.40256 -225.21926) (xy 142.302738 -225.392488)
			(xy 142.343886 -225.416364)
		)
		(stroke
			(width 0)
			(type solid)
		)
		(fill yes)
		(layer "In2.Cu")
		(net "M_I_CPU1_SA_DQS_DP<5>")
	)
	(gr_poly
		(pts
			(xy 142.480538 -223.759522) (xy 142.443962 -223.623124) (xy 142.40256 -223.599248) (xy 142.302738 -223.772476)
			(xy 142.343886 -223.796352)
		)
		(stroke
			(width 0)
			(type solid)
		)
		(fill yes)
		(layer "In2.Cu")
		(net "M_I_CPU1_SA_DQS_DN<0>")
	)
	(gr_poly
		(pts
			(xy 142.64386 -294.684958) (xy 142.543784 -294.51173) (xy 142.50543 -294.534082) (xy 142.468854 -294.670734)
			(xy 142.605252 -294.70731)
		)
		(stroke
			(width 0)
			(type solid)
		)
		(fill yes)
		(layer "In2.Cu")
		(net "M_I_CPU1_SB_DQ<31>")
	)
	(gr_poly
		(pts
			(xy 142.64386 -293.064946) (xy 142.543784 -292.891718) (xy 142.50543 -292.91407) (xy 142.468854 -293.050722)
			(xy 142.605252 -293.087298)
		)
		(stroke
			(width 0)
			(type solid)
		)
		(fill yes)
		(layer "In2.Cu")
		(net "M_I_CPU1_SB_DQ<30>")
	)
	(gr_poly
		(pts
			(xy 142.724886 -291.297868) (xy 142.62481 -291.198046) (xy 142.524734 -291.297868) (xy 142.524734 -291.34562)
			(xy 142.724886 -291.34562)
		)
		(stroke
			(width 0)
			(type solid)
		)
		(fill yes)
		(layer "In2.Cu")
		(net "M_I_CPU1_SB_DQS_DN<8>")
	)
	(gr_poly
		(pts
			(xy 142.724886 -290.894516) (xy 142.724886 -290.846764) (xy 142.524734 -290.846764) (xy 142.524734 -290.894516)
			(xy 142.62481 -290.994338)
		)
		(stroke
			(width 0)
			(type solid)
		)
		(fill yes)
		(layer "In2.Cu")
		(net "M_I_CPU1_SB_DQS_DN<3>")
	)
	(gr_poly
		(pts
			(xy 142.724886 -289.67811) (xy 142.62481 -289.578034) (xy 142.524734 -289.67811) (xy 142.524734 -289.72256)
			(xy 142.724886 -289.72256)
		)
		(stroke
			(width 0)
			(type solid)
		)
		(fill yes)
		(layer "In2.Cu")
		(net "M_I_CPU1_SB_DQ<25>")
	)
	(gr_poly
		(pts
			(xy 142.724886 -289.27425) (xy 142.724886 -289.2298) (xy 142.524734 -289.2298) (xy 142.524734 -289.27425)
			(xy 142.62481 -289.374326)
		)
		(stroke
			(width 0)
			(type solid)
		)
		(fill yes)
		(layer "In2.Cu")
		(net "M_I_CPU1_SB_DQ<26>")
	)
	(gr_poly
		(pts
			(xy 142.724886 -288.058098) (xy 142.62481 -287.958022) (xy 142.524734 -288.058098) (xy 142.524734 -288.102548)
			(xy 142.724886 -288.102548)
		)
		(stroke
			(width 0)
			(type solid)
		)
		(fill yes)
		(layer "In2.Cu")
		(net "M_I_CPU1_SB_DQ<21>")
	)
	(gr_poly
		(pts
			(xy 142.724886 -287.654492) (xy 142.724886 -287.610042) (xy 142.524734 -287.610042) (xy 142.524734 -287.654492)
			(xy 142.62481 -287.754568)
		)
		(stroke
			(width 0)
			(type solid)
		)
		(fill yes)
		(layer "In2.Cu")
		(net "M_I_CPU1_SB_DQ<22>")
	)
	(gr_poly
		(pts
			(xy 142.724886 -286.438086) (xy 142.62481 -286.33801) (xy 142.524734 -286.438086) (xy 142.524734 -286.485838)
			(xy 142.724886 -286.485838)
		)
		(stroke
			(width 0)
			(type solid)
		)
		(fill yes)
		(layer "In2.Cu")
		(net "M_I_CPU1_SB_DQS_DN<7>")
	)
	(gr_poly
		(pts
			(xy 142.724886 -286.034734) (xy 142.724886 -285.986982) (xy 142.524734 -285.986982) (xy 142.524734 -286.034734)
			(xy 142.62481 -286.134556)
		)
		(stroke
			(width 0)
			(type solid)
		)
		(fill yes)
		(layer "In2.Cu")
		(net "M_I_CPU1_SB_DQS_DN<2>")
	)
	(gr_poly
		(pts
			(xy 142.724886 -284.818328) (xy 142.62481 -284.718252) (xy 142.524734 -284.818328) (xy 142.524734 -284.862778)
			(xy 142.724886 -284.862778)
		)
		(stroke
			(width 0)
			(type solid)
		)
		(fill yes)
		(layer "In2.Cu")
		(net "M_I_CPU1_SB_DQ<17>")
	)
	(gr_poly
		(pts
			(xy 142.724886 -284.414468) (xy 142.724886 -284.370018) (xy 142.524734 -284.370018) (xy 142.524734 -284.414468)
			(xy 142.62481 -284.514544)
		)
		(stroke
			(width 0)
			(type solid)
		)
		(fill yes)
		(layer "In2.Cu")
		(net "M_I_CPU1_SB_DQ<18>")
	)
	(gr_poly
		(pts
			(xy 142.724886 -283.198316) (xy 142.62481 -283.09824) (xy 142.524734 -283.198316) (xy 142.524734 -283.242766)
			(xy 142.724886 -283.242766)
		)
		(stroke
			(width 0)
			(type solid)
		)
		(fill yes)
		(layer "In2.Cu")
		(net "M_I_CPU1_SB_DQ<13>")
	)
	(gr_poly
		(pts
			(xy 142.724886 -282.794456) (xy 142.724886 -282.750006) (xy 142.524734 -282.750006) (xy 142.524734 -282.794456)
			(xy 142.62481 -282.894532)
		)
		(stroke
			(width 0)
			(type solid)
		)
		(fill yes)
		(layer "In2.Cu")
		(net "M_I_CPU1_SB_DQ<14>")
	)
	(gr_poly
		(pts
			(xy 142.724886 -281.57805) (xy 142.62481 -281.478228) (xy 142.524734 -281.57805) (xy 142.524734 -281.625802)
			(xy 142.724886 -281.625802)
		)
		(stroke
			(width 0)
			(type solid)
		)
		(fill yes)
		(layer "In2.Cu")
		(net "M_I_CPU1_SB_DQS_DN<6>")
	)
	(gr_poly
		(pts
			(xy 142.724886 -281.174698) (xy 142.724886 -281.126946) (xy 142.524734 -281.126946) (xy 142.524734 -281.174698)
			(xy 142.62481 -281.27452)
		)
		(stroke
			(width 0)
			(type solid)
		)
		(fill yes)
		(layer "In2.Cu")
		(net "M_I_CPU1_SB_DQS_DN<1>")
	)
	(gr_poly
		(pts
			(xy 142.724886 -279.958292) (xy 142.62481 -279.858216) (xy 142.524734 -279.958292) (xy 142.524734 -280.002742)
			(xy 142.724886 -280.002742)
		)
		(stroke
			(width 0)
			(type solid)
		)
		(fill yes)
		(layer "In2.Cu")
		(net "M_I_CPU1_SB_DQ<9>")
	)
	(gr_poly
		(pts
			(xy 142.724886 -279.554432) (xy 142.724886 -279.509982) (xy 142.524734 -279.509982) (xy 142.524734 -279.554432)
			(xy 142.62481 -279.654508)
		)
		(stroke
			(width 0)
			(type solid)
		)
		(fill yes)
		(layer "In2.Cu")
		(net "M_I_CPU1_SB_DQ<10>")
	)
	(gr_poly
		(pts
			(xy 142.724886 -278.33828) (xy 142.62481 -278.238204) (xy 142.524734 -278.33828) (xy 142.524734 -278.38273)
			(xy 142.724886 -278.38273)
		)
		(stroke
			(width 0)
			(type solid)
		)
		(fill yes)
		(layer "In2.Cu")
		(net "M_I_CPU1_SB_DQ<5>")
	)
	(gr_poly
		(pts
			(xy 142.724886 -277.93442) (xy 142.724886 -277.88997) (xy 142.524734 -277.88997) (xy 142.524734 -277.93442)
			(xy 142.62481 -278.034496)
		)
		(stroke
			(width 0)
			(type solid)
		)
		(fill yes)
		(layer "In2.Cu")
		(net "M_I_CPU1_SB_DQ<6>")
	)
	(gr_poly
		(pts
			(xy 142.724886 -276.718014) (xy 142.62481 -276.618192) (xy 142.524734 -276.718014) (xy 142.524734 -276.765766)
			(xy 142.724886 -276.765766)
		)
		(stroke
			(width 0)
			(type solid)
		)
		(fill yes)
		(layer "In2.Cu")
		(net "M_I_CPU1_SB_DQS_DN<5>")
	)
	(gr_poly
		(pts
			(xy 142.724886 -276.314662) (xy 142.724886 -276.26691) (xy 142.524734 -276.26691) (xy 142.524734 -276.314662)
			(xy 142.62481 -276.414484)
		)
		(stroke
			(width 0)
			(type solid)
		)
		(fill yes)
		(layer "In2.Cu")
		(net "M_I_CPU1_SB_DQS_DN<0>")
	)
	(gr_poly
		(pts
			(xy 142.724886 -275.098256) (xy 142.62481 -274.99818) (xy 142.524734 -275.098256) (xy 142.524734 -275.142706)
			(xy 142.724886 -275.142706)
		)
		(stroke
			(width 0)
			(type solid)
		)
		(fill yes)
		(layer "In2.Cu")
		(net "M_I_CPU1_SB_DQ<1>")
	)
	(gr_poly
		(pts
			(xy 142.724886 -274.694396) (xy 142.724886 -274.649946) (xy 142.524734 -274.649946) (xy 142.524734 -274.694396)
			(xy 142.62481 -274.794472)
		)
		(stroke
			(width 0)
			(type solid)
		)
		(fill yes)
		(layer "In2.Cu")
		(net "M_I_CPU1_SB_DQ<2>")
	)
	(gr_poly
		(pts
			(xy 142.724886 -273.478244) (xy 142.62481 -273.378168) (xy 142.524734 -273.478244) (xy 142.524734 -273.522694)
			(xy 142.724886 -273.522694)
		)
		(stroke
			(width 0)
			(type solid)
		)
		(fill yes)
		(layer "In2.Cu")
		(net "M_I_CPU1_SB_CB<1>")
	)
	(gr_poly
		(pts
			(xy 142.724886 -273.074384) (xy 142.724886 -273.029934) (xy 142.524734 -273.029934) (xy 142.524734 -273.074384)
			(xy 142.62481 -273.17446)
		)
		(stroke
			(width 0)
			(type solid)
		)
		(fill yes)
		(layer "In2.Cu")
		(net "M_I_CPU1_SB_CB<2>")
	)
	(gr_poly
		(pts
			(xy 142.724886 -271.857978) (xy 142.62481 -271.758156) (xy 142.524734 -271.857978) (xy 142.524734 -271.90573)
			(xy 142.724886 -271.90573)
		)
		(stroke
			(width 0)
			(type solid)
		)
		(fill yes)
		(layer "In2.Cu")
		(net "M_I_CPU1_SB_DQS_DN<4>")
	)
	(gr_poly
		(pts
			(xy 142.724886 -271.454626) (xy 142.724886 -271.406874) (xy 142.524734 -271.406874) (xy 142.524734 -271.454626)
			(xy 142.62481 -271.554448)
		)
		(stroke
			(width 0)
			(type solid)
		)
		(fill yes)
		(layer "In2.Cu")
		(net "M_I_CPU1_SB_DQS_DN<9>")
	)
	(gr_poly
		(pts
			(xy 142.724886 -270.23822) (xy 142.62481 -270.138144) (xy 142.524734 -270.23822) (xy 142.524734 -270.28267)
			(xy 142.724886 -270.28267)
		)
		(stroke
			(width 0)
			(type solid)
		)
		(fill yes)
		(layer "In2.Cu")
		(net "M_I_CPU1_SB_CB<5>")
	)
	(gr_poly
		(pts
			(xy 142.724886 -269.83436) (xy 142.724886 -269.78991) (xy 142.524734 -269.78991) (xy 142.524734 -269.83436)
			(xy 142.62481 -269.934436)
		)
		(stroke
			(width 0)
			(type solid)
		)
		(fill yes)
		(layer "In2.Cu")
		(net "M_I_CPU1_SB_CB<6>")
	)
	(gr_poly
		(pts
			(xy 142.724886 -266.998196) (xy 142.62481 -266.89812) (xy 142.524734 -266.998196) (xy 142.524734 -267.042646)
			(xy 142.724886 -267.042646)
		)
		(stroke
			(width 0)
			(type solid)
		)
		(fill yes)
		(layer "In2.Cu")
		(net "M_I_CPU1_SA_RSP<0>")
	)
	(gr_poly
		(pts
			(xy 142.724886 -266.594336) (xy 142.724886 -266.549886) (xy 142.524734 -266.549886) (xy 142.524734 -266.594336)
			(xy 142.62481 -266.694412)
		)
		(stroke
			(width 0)
			(type solid)
		)
		(fill yes)
		(layer "In2.Cu")
		(net "M_I_CPU1_SB_CS_N<1>")
	)
	(gr_poly
		(pts
			(xy 142.724886 -265.378184) (xy 142.62481 -265.278108) (xy 142.524734 -265.378184) (xy 142.524734 -265.422634)
			(xy 142.724886 -265.422634)
		)
		(stroke
			(width 0)
			(type solid)
		)
		(fill yes)
		(layer "In2.Cu")
		(net "M_I_CPU1_SB_PAR")
	)
	(gr_poly
		(pts
			(xy 142.724886 -263.758172) (xy 142.62481 -263.658096) (xy 142.524734 -263.758172) (xy 142.524734 -263.802622)
			(xy 142.724886 -263.802622)
		)
		(stroke
			(width 0)
			(type solid)
		)
		(fill yes)
		(layer "In2.Cu")
		(net "M_I_CPU1_SB_CA<4>")
	)
	(gr_poly
		(pts
			(xy 142.724886 -263.354312) (xy 142.724886 -263.309862) (xy 142.524734 -263.309862) (xy 142.524734 -263.354312)
			(xy 142.62481 -263.454388)
		)
		(stroke
			(width 0)
			(type solid)
		)
		(fill yes)
		(layer "In2.Cu")
		(net "M_I_CPU1_SB_CA<3>")
	)
	(gr_poly
		(pts
			(xy 142.724886 -262.13816) (xy 142.62481 -262.038084) (xy 142.524734 -262.13816) (xy 142.524734 -262.18261)
			(xy 142.724886 -262.18261)
		)
		(stroke
			(width 0)
			(type solid)
		)
		(fill yes)
		(layer "In2.Cu")
		(net "M_I_CPU1_SB_CA<0>")
	)
	(gr_poly
		(pts
			(xy 142.743936 -294.13835) (xy 142.780766 -294.001698) (xy 142.644114 -293.965122) (xy 142.605506 -293.987474)
			(xy 142.705582 -294.160702)
		)
		(stroke
			(width 0)
			(type solid)
		)
		(fill yes)
		(layer "In2.Cu")
		(net "M_I_CPU1_SB_DQ<29>")
	)
	(gr_poly
		(pts
			(xy 142.743936 -292.518338) (xy 142.780766 -292.381686) (xy 142.644114 -292.34511) (xy 142.605506 -292.367462)
			(xy 142.705582 -292.54069)
		)
		(stroke
			(width 0)
			(type solid)
		)
		(fill yes)
		(layer "In2.Cu")
		(net "M_I_CPU1_SB_DQ<28>")
	)
	(gr_poly
		(pts
			(xy 142.814802 -228.744272) (xy 142.776194 -228.722174) (xy 142.639542 -228.75875) (xy 142.676118 -228.895402)
			(xy 142.714726 -228.9175)
		)
		(stroke
			(width 0)
			(type solid)
		)
		(fill yes)
		(layer "In2.Cu")
		(net "M_I_CPU1_SA_DQ<8>")
	)
	(gr_poly
		(pts
			(xy 142.814802 -227.12426) (xy 142.776194 -227.102162) (xy 142.639542 -227.138738) (xy 142.676118 -227.27539)
			(xy 142.714726 -227.297488)
		)
		(stroke
			(width 0)
			(type solid)
		)
		(fill yes)
		(layer "In2.Cu")
		(net "M_I_CPU1_SA_DQ<5>")
	)
	(gr_poly
		(pts
			(xy 142.814802 -225.504248) (xy 142.776194 -225.48215) (xy 142.639542 -225.518726) (xy 142.676118 -225.655378)
			(xy 142.714726 -225.677476)
		)
		(stroke
			(width 0)
			(type solid)
		)
		(fill yes)
		(layer "In2.Cu")
		(net "M_I_CPU1_SA_DQ<4>")
	)
	(gr_poly
		(pts
			(xy 142.815564 -230.363014) (xy 142.776956 -230.340662) (xy 142.640304 -230.377238) (xy 142.677134 -230.51389)
			(xy 142.715488 -230.536242)
		)
		(stroke
			(width 0)
			(type solid)
		)
		(fill yes)
		(layer "In2.Cu")
		(net "M_I_CPU1_SA_DQ<9>")
	)
	(gr_poly
		(pts
			(xy 142.81658 -222.26651) (xy 142.775432 -222.242634) (xy 142.63878 -222.279464) (xy 142.675356 -222.415862)
			(xy 142.716758 -222.439738)
		)
		(stroke
			(width 0)
			(type solid)
		)
		(fill yes)
		(layer "In2.Cu")
		(net "M_I_CPU1_SA_DQS_DP<0>")
	)
	(gr_poly
		(pts
			(xy 142.894812 -256.432812) (xy 142.894812 -256.38506) (xy 142.69466 -256.38506) (xy 142.69466 -256.432812)
			(xy 142.794736 -256.532634)
		)
		(stroke
			(width 0)
			(type solid)
		)
		(fill yes)
		(layer "In2.Cu")
		(net "M_I_CPU1_CLK_DN<0>")
	)
	(gr_poly
		(pts
			(xy 142.894812 -255.216406) (xy 142.794736 -255.11633) (xy 142.69466 -255.216406) (xy 142.69466 -255.260856)
			(xy 142.894812 -255.260856)
		)
		(stroke
			(width 0)
			(type solid)
		)
		(fill yes)
		(layer "In2.Cu")
		(net "M_I_CPU1_SA_CA<6>")
	)
	(gr_poly
		(pts
			(xy 142.894812 -254.812546) (xy 142.894812 -254.768096) (xy 142.69466 -254.768096) (xy 142.69466 -254.812546)
			(xy 142.794736 -254.912622)
		)
		(stroke
			(width 0)
			(type solid)
		)
		(fill yes)
		(layer "In2.Cu")
		(net "M_I_CPU1_SA_CA<5>")
	)
	(gr_poly
		(pts
			(xy 142.894812 -253.596394) (xy 142.794736 -253.496318) (xy 142.69466 -253.596394) (xy 142.69466 -253.640844)
			(xy 142.894812 -253.640844)
		)
		(stroke
			(width 0)
			(type solid)
		)
		(fill yes)
		(layer "In2.Cu")
		(net "M_I_CPU1_SA_CA<2>")
	)
	(gr_poly
		(pts
			(xy 142.894812 -253.192534) (xy 142.894812 -253.148084) (xy 142.69466 -253.148084) (xy 142.69466 -253.192534)
			(xy 142.794736 -253.29261)
		)
		(stroke
			(width 0)
			(type solid)
		)
		(fill yes)
		(layer "In2.Cu")
		(net "M_I_CPU1_SA_CA<1>")
	)
	(gr_poly
		(pts
			(xy 142.894812 -251.976382) (xy 142.794736 -251.876306) (xy 142.69466 -251.976382) (xy 142.69466 -252.020832)
			(xy 142.894812 -252.020832)
		)
		(stroke
			(width 0)
			(type solid)
		)
		(fill yes)
		(layer "In2.Cu")
		(net "M_I_CPU1_SA_CS_N<1>")
	)
	(gr_poly
		(pts
			(xy 142.894812 -250.35637) (xy 142.794736 -250.256294) (xy 142.69466 -250.35637) (xy 142.69466 -250.40082)
			(xy 142.894812 -250.40082)
		)
		(stroke
			(width 0)
			(type solid)
		)
		(fill yes)
		(layer "In2.Cu")
		(net "M_I_CPU1_ALERT_R_N")
	)
	(gr_poly
		(pts
			(xy 142.894812 -248.736358) (xy 142.794736 -248.636282) (xy 142.69466 -248.736358) (xy 142.69466 -248.780808)
			(xy 142.894812 -248.780808)
		)
		(stroke
			(width 0)
			(type solid)
		)
		(fill yes)
		(layer "In2.Cu")
		(net "M_I_CPU1_SA_CB<5>")
	)
	(gr_poly
		(pts
			(xy 142.894812 -248.332498) (xy 142.894812 -248.288048) (xy 142.69466 -248.288048) (xy 142.69466 -248.332498)
			(xy 142.794736 -248.432574)
		)
		(stroke
			(width 0)
			(type solid)
		)
		(fill yes)
		(layer "In2.Cu")
		(net "M_I_CPU1_SA_CB<6>")
	)
	(gr_poly
		(pts
			(xy 142.894812 -247.116092) (xy 142.794736 -247.01627) (xy 142.69466 -247.116092) (xy 142.69466 -247.163844)
			(xy 142.894812 -247.163844)
		)
		(stroke
			(width 0)
			(type solid)
		)
		(fill yes)
		(layer "In2.Cu")
		(net "M_I_CPU1_SA_DQS_DN<9>")
	)
	(gr_poly
		(pts
			(xy 142.894812 -246.71274) (xy 142.894812 -246.664988) (xy 142.69466 -246.664988) (xy 142.69466 -246.71274)
			(xy 142.794736 -246.812562)
		)
		(stroke
			(width 0)
			(type solid)
		)
		(fill yes)
		(layer "In2.Cu")
		(net "M_I_CPU1_SA_DQS_DN<4>")
	)
	(gr_poly
		(pts
			(xy 142.894812 -245.496334) (xy 142.794736 -245.396258) (xy 142.69466 -245.496334) (xy 142.69466 -245.540784)
			(xy 142.894812 -245.540784)
		)
		(stroke
			(width 0)
			(type solid)
		)
		(fill yes)
		(layer "In2.Cu")
		(net "M_I_CPU1_SA_CB<1>")
	)
	(gr_poly
		(pts
			(xy 142.894812 -245.092474) (xy 142.894812 -245.048024) (xy 142.69466 -245.048024) (xy 142.69466 -245.092474)
			(xy 142.794736 -245.19255)
		)
		(stroke
			(width 0)
			(type solid)
		)
		(fill yes)
		(layer "In2.Cu")
		(net "M_I_CPU1_SA_CB<2>")
	)
	(gr_poly
		(pts
			(xy 142.894812 -243.876322) (xy 142.794736 -243.776246) (xy 142.69466 -243.876322) (xy 142.69466 -243.920772)
			(xy 142.894812 -243.920772)
		)
		(stroke
			(width 0)
			(type solid)
		)
		(fill yes)
		(layer "In2.Cu")
		(net "M_I_CPU1_SA_DQ<29>")
	)
	(gr_poly
		(pts
			(xy 142.894812 -243.472462) (xy 142.894812 -243.428012) (xy 142.69466 -243.428012) (xy 142.69466 -243.472462)
			(xy 142.794736 -243.572538)
		)
		(stroke
			(width 0)
			(type solid)
		)
		(fill yes)
		(layer "In2.Cu")
		(net "M_I_CPU1_SA_DQ<30>")
	)
	(gr_poly
		(pts
			(xy 142.894812 -242.256056) (xy 142.794736 -242.156234) (xy 142.69466 -242.256056) (xy 142.69466 -242.303808)
			(xy 142.894812 -242.303808)
		)
		(stroke
			(width 0)
			(type solid)
		)
		(fill yes)
		(layer "In2.Cu")
		(net "M_I_CPU1_SA_DQS_DN<8>")
	)
	(gr_poly
		(pts
			(xy 142.894812 -241.852704) (xy 142.894812 -241.804952) (xy 142.69466 -241.804952) (xy 142.69466 -241.852704)
			(xy 142.794736 -241.952526)
		)
		(stroke
			(width 0)
			(type solid)
		)
		(fill yes)
		(layer "In2.Cu")
		(net "M_I_CPU1_SA_DQS_DN<3>")
	)
	(gr_poly
		(pts
			(xy 142.894812 -240.636298) (xy 142.794736 -240.536222) (xy 142.69466 -240.636298) (xy 142.69466 -240.680748)
			(xy 142.894812 -240.680748)
		)
		(stroke
			(width 0)
			(type solid)
		)
		(fill yes)
		(layer "In2.Cu")
		(net "M_I_CPU1_SA_DQ<25>")
	)
	(gr_poly
		(pts
			(xy 142.894812 -240.232438) (xy 142.894812 -240.187988) (xy 142.69466 -240.187988) (xy 142.69466 -240.232438)
			(xy 142.794736 -240.332514)
		)
		(stroke
			(width 0)
			(type solid)
		)
		(fill yes)
		(layer "In2.Cu")
		(net "M_I_CPU1_SA_DQ<26>")
	)
	(gr_poly
		(pts
			(xy 142.894812 -239.016286) (xy 142.794736 -238.91621) (xy 142.69466 -239.016286) (xy 142.69466 -239.060736)
			(xy 142.894812 -239.060736)
		)
		(stroke
			(width 0)
			(type solid)
		)
		(fill yes)
		(layer "In2.Cu")
		(net "M_I_CPU1_SA_DQ<21>")
	)
	(gr_poly
		(pts
			(xy 142.894812 -238.612426) (xy 142.894812 -238.567976) (xy 142.69466 -238.567976) (xy 142.69466 -238.612426)
			(xy 142.794736 -238.712502)
		)
		(stroke
			(width 0)
			(type solid)
		)
		(fill yes)
		(layer "In2.Cu")
		(net "M_I_CPU1_SA_DQ<22>")
	)
	(gr_poly
		(pts
			(xy 142.894812 -237.39602) (xy 142.794736 -237.296198) (xy 142.69466 -237.39602) (xy 142.69466 -237.443772)
			(xy 142.894812 -237.443772)
		)
		(stroke
			(width 0)
			(type solid)
		)
		(fill yes)
		(layer "In2.Cu")
		(net "M_I_CPU1_SA_DQS_DN<7>")
	)
	(gr_poly
		(pts
			(xy 142.894812 -236.992668) (xy 142.894812 -236.944916) (xy 142.69466 -236.944916) (xy 142.69466 -236.992668)
			(xy 142.794736 -237.09249)
		)
		(stroke
			(width 0)
			(type solid)
		)
		(fill yes)
		(layer "In2.Cu")
		(net "M_I_CPU1_SA_DQS_DN<2>")
	)
	(gr_poly
		(pts
			(xy 142.894812 -235.776262) (xy 142.794736 -235.676186) (xy 142.69466 -235.776262) (xy 142.69466 -235.820712)
			(xy 142.894812 -235.820712)
		)
		(stroke
			(width 0)
			(type solid)
		)
		(fill yes)
		(layer "In2.Cu")
		(net "M_I_CPU1_SA_DQ<17>")
	)
	(gr_poly
		(pts
			(xy 142.894812 -235.372402) (xy 142.894812 -235.327952) (xy 142.69466 -235.327952) (xy 142.69466 -235.372402)
			(xy 142.794736 -235.472478)
		)
		(stroke
			(width 0)
			(type solid)
		)
		(fill yes)
		(layer "In2.Cu")
		(net "M_I_CPU1_SA_DQ<18>")
	)
	(gr_poly
		(pts
			(xy 142.894812 -234.15625) (xy 142.794736 -234.056174) (xy 142.69466 -234.15625) (xy 142.69466 -234.2007)
			(xy 142.894812 -234.2007)
		)
		(stroke
			(width 0)
			(type solid)
		)
		(fill yes)
		(layer "In2.Cu")
		(net "M_I_CPU1_SA_DQ<13>")
	)
	(gr_poly
		(pts
			(xy 142.894812 -233.75239) (xy 142.894812 -233.70794) (xy 142.69466 -233.70794) (xy 142.69466 -233.75239)
			(xy 142.794736 -233.852466)
		)
		(stroke
			(width 0)
			(type solid)
		)
		(fill yes)
		(layer "In2.Cu")
		(net "M_I_CPU1_SA_DQ<14>")
	)
	(gr_poly
		(pts
			(xy 142.894812 -232.535984) (xy 142.794736 -232.436162) (xy 142.69466 -232.535984) (xy 142.69466 -232.583736)
			(xy 142.894812 -232.583736)
		)
		(stroke
			(width 0)
			(type solid)
		)
		(fill yes)
		(layer "In2.Cu")
		(net "M_I_CPU1_SA_DQS_DN<6>")
	)
	(gr_poly
		(pts
			(xy 142.894812 -232.132632) (xy 142.894812 -232.08488) (xy 142.69466 -232.08488) (xy 142.69466 -232.132632)
			(xy 142.794736 -232.232454)
		)
		(stroke
			(width 0)
			(type solid)
		)
		(fill yes)
		(layer "In2.Cu")
		(net "M_I_CPU1_SA_DQS_DN<1>")
	)
	(gr_poly
		(pts
			(xy 142.94993 -231.050338) (xy 142.913354 -230.913686) (xy 142.874746 -230.891588) (xy 142.77467 -231.064816)
			(xy 142.813278 -231.086914)
		)
		(stroke
			(width 0)
			(type solid)
		)
		(fill yes)
		(layer "In2.Cu")
		(net "M_I_CPU1_SA_DQ<11>")
	)
	(gr_poly
		(pts
			(xy 142.94993 -229.430326) (xy 142.913354 -229.293674) (xy 142.874746 -229.271576) (xy 142.77467 -229.444804)
			(xy 142.813278 -229.466902)
		)
		(stroke
			(width 0)
			(type solid)
		)
		(fill yes)
		(layer "In2.Cu")
		(net "M_I_CPU1_SA_DQ<10>")
	)
	(gr_poly
		(pts
			(xy 142.94993 -227.810314) (xy 142.913354 -227.673662) (xy 142.874746 -227.651564) (xy 142.77467 -227.824792)
			(xy 142.813278 -227.84689)
		)
		(stroke
			(width 0)
			(type solid)
		)
		(fill yes)
		(layer "In2.Cu")
		(net "M_I_CPU1_SA_DQ<7>")
	)
	(gr_poly
		(pts
			(xy 142.94993 -226.190302) (xy 142.913354 -226.05365) (xy 142.874746 -226.031552) (xy 142.77467 -226.20478)
			(xy 142.813278 -226.226878)
		)
		(stroke
			(width 0)
			(type solid)
		)
		(fill yes)
		(layer "In2.Cu")
		(net "M_I_CPU1_SA_DQ<6>")
	)
	(gr_poly
		(pts
			(xy 142.950438 -222.949516) (xy 142.913862 -222.813118) (xy 142.87246 -222.789242) (xy 142.772638 -222.96247)
			(xy 142.813786 -222.986092)
		)
		(stroke
			(width 0)
			(type solid)
		)
		(fill yes)
		(layer "In2.Cu")
		(net "M_I_CPU1_SA_DQS_DN<0>")
	)
	(gr_poly
		(pts
			(xy 143.114776 -295.496488) (xy 143.0147 -295.32326) (xy 142.976092 -295.345358) (xy 142.939516 -295.48201)
			(xy 143.076168 -295.518586)
		)
		(stroke
			(width 0)
			(type solid)
		)
		(fill yes)
		(layer "In2.Cu")
		(net "M_I_CPU1_SB_DQ<31>")
	)
	(gr_poly
		(pts
			(xy 143.114776 -293.876476) (xy 143.0147 -293.703248) (xy 142.976092 -293.725346) (xy 142.939516 -293.861998)
			(xy 143.076168 -293.898574)
		)
		(stroke
			(width 0)
			(type solid)
		)
		(fill yes)
		(layer "In2.Cu")
		(net "M_I_CPU1_SB_DQ<30>")
	)
	(gr_poly
		(pts
			(xy 143.117824 -292.255448) (xy 143.017748 -292.08222) (xy 142.9766 -292.106096) (xy 142.93977 -292.242748)
			(xy 143.076422 -292.279324)
		)
		(stroke
			(width 0)
			(type solid)
		)
		(fill yes)
		(layer "In2.Cu")
		(net "M_I_CPU1_SB_DQS_DP<8>")
	)
	(gr_poly
		(pts
			(xy 143.194786 -290.487862) (xy 143.09471 -290.38804) (xy 142.994634 -290.487862) (xy 142.994634 -290.535614)
			(xy 143.194786 -290.535614)
		)
		(stroke
			(width 0)
			(type solid)
		)
		(fill yes)
		(layer "In2.Cu")
		(net "M_I_CPU1_SB_DQS_DP<3>")
	)
	(gr_poly
		(pts
			(xy 143.194786 -290.084256) (xy 143.194786 -290.039806) (xy 142.994634 -290.039806) (xy 142.994634 -290.084256)
			(xy 143.09471 -290.184332)
		)
		(stroke
			(width 0)
			(type solid)
		)
		(fill yes)
		(layer "In2.Cu")
		(net "M_I_CPU1_SB_DQ<27>")
	)
	(gr_poly
		(pts
			(xy 143.194786 -288.868104) (xy 143.09471 -288.768028) (xy 142.994634 -288.868104) (xy 142.994634 -288.912554)
			(xy 143.194786 -288.912554)
		)
		(stroke
			(width 0)
			(type solid)
		)
		(fill yes)
		(layer "In2.Cu")
		(net "M_I_CPU1_SB_DQ<24>")
	)
	(gr_poly
		(pts
			(xy 143.194786 -288.464498) (xy 143.194786 -288.420048) (xy 142.994634 -288.420048) (xy 142.994634 -288.464498)
			(xy 143.09471 -288.564574)
		)
		(stroke
			(width 0)
			(type solid)
		)
		(fill yes)
		(layer "In2.Cu")
		(net "M_I_CPU1_SB_DQ<23>")
	)
	(gr_poly
		(pts
			(xy 143.194786 -287.248092) (xy 143.09471 -287.148016) (xy 142.994634 -287.248092) (xy 142.994634 -287.292542)
			(xy 143.194786 -287.292542)
		)
		(stroke
			(width 0)
			(type solid)
		)
		(fill yes)
		(layer "In2.Cu")
		(net "M_I_CPU1_SB_DQ<20>")
	)
	(gr_poly
		(pts
			(xy 143.194786 -286.844486) (xy 143.194786 -286.796734) (xy 142.994634 -286.796734) (xy 142.994634 -286.844486)
			(xy 143.09471 -286.944562)
		)
		(stroke
			(width 0)
			(type solid)
		)
		(fill yes)
		(layer "In2.Cu")
		(net "M_I_CPU1_SB_DQS_DP<7>")
	)
	(gr_poly
		(pts
			(xy 143.194786 -285.62808) (xy 143.09471 -285.528258) (xy 142.994634 -285.62808) (xy 142.994634 -285.675832)
			(xy 143.194786 -285.675832)
		)
		(stroke
			(width 0)
			(type solid)
		)
		(fill yes)
		(layer "In2.Cu")
		(net "M_I_CPU1_SB_DQS_DP<2>")
	)
	(gr_poly
		(pts
			(xy 143.194786 -285.224474) (xy 143.194786 -285.180024) (xy 142.994634 -285.180024) (xy 142.994634 -285.224474)
			(xy 143.09471 -285.32455)
		)
		(stroke
			(width 0)
			(type solid)
		)
		(fill yes)
		(layer "In2.Cu")
		(net "M_I_CPU1_SB_DQ<19>")
	)
	(gr_poly
		(pts
			(xy 143.194786 -284.008322) (xy 143.09471 -283.908246) (xy 142.994634 -284.008322) (xy 142.994634 -284.052772)
			(xy 143.194786 -284.052772)
		)
		(stroke
			(width 0)
			(type solid)
		)
		(fill yes)
		(layer "In2.Cu")
		(net "M_I_CPU1_SB_DQ<16>")
	)
	(gr_poly
		(pts
			(xy 143.194786 -283.604462) (xy 143.194786 -283.560012) (xy 142.994634 -283.560012) (xy 142.994634 -283.604462)
			(xy 143.09471 -283.704538)
		)
		(stroke
			(width 0)
			(type solid)
		)
		(fill yes)
		(layer "In2.Cu")
		(net "M_I_CPU1_SB_DQ<15>")
	)
	(gr_poly
		(pts
			(xy 143.194786 -282.38831) (xy 143.09471 -282.288234) (xy 142.994634 -282.38831) (xy 142.994634 -282.43276)
			(xy 143.194786 -282.43276)
		)
		(stroke
			(width 0)
			(type solid)
		)
		(fill yes)
		(layer "In2.Cu")
		(net "M_I_CPU1_SB_DQ<12>")
	)
	(gr_poly
		(pts
			(xy 143.194786 -281.984704) (xy 143.194786 -281.936952) (xy 142.994634 -281.936952) (xy 142.994634 -281.984704)
			(xy 143.09471 -282.084526)
		)
		(stroke
			(width 0)
			(type solid)
		)
		(fill yes)
		(layer "In2.Cu")
		(net "M_I_CPU1_SB_DQS_DP<6>")
	)
	(gr_poly
		(pts
			(xy 143.194786 -280.768044) (xy 143.09471 -280.668222) (xy 142.994634 -280.768044) (xy 142.994634 -280.815796)
			(xy 143.194786 -280.815796)
		)
		(stroke
			(width 0)
			(type solid)
		)
		(fill yes)
		(layer "In2.Cu")
		(net "M_I_CPU1_SB_DQS_DP<1>")
	)
	(gr_poly
		(pts
			(xy 143.194786 -280.364438) (xy 143.194786 -280.319988) (xy 142.994634 -280.319988) (xy 142.994634 -280.364438)
			(xy 143.09471 -280.464514)
		)
		(stroke
			(width 0)
			(type solid)
		)
		(fill yes)
		(layer "In2.Cu")
		(net "M_I_CPU1_SB_DQ<11>")
	)
	(gr_poly
		(pts
			(xy 143.194786 -279.148286) (xy 143.09471 -279.04821) (xy 142.994634 -279.148286) (xy 142.994634 -279.192736)
			(xy 143.194786 -279.192736)
		)
		(stroke
			(width 0)
			(type solid)
		)
		(fill yes)
		(layer "In2.Cu")
		(net "M_I_CPU1_SB_DQ<8>")
	)
	(gr_poly
		(pts
			(xy 143.194786 -278.744426) (xy 143.194786 -278.699976) (xy 142.994634 -278.699976) (xy 142.994634 -278.744426)
			(xy 143.09471 -278.844502)
		)
		(stroke
			(width 0)
			(type solid)
		)
		(fill yes)
		(layer "In2.Cu")
		(net "M_I_CPU1_SB_DQ<7>")
	)
	(gr_poly
		(pts
			(xy 143.194786 -277.528274) (xy 143.09471 -277.428198) (xy 142.994634 -277.528274) (xy 142.994634 -277.572724)
			(xy 143.194786 -277.572724)
		)
		(stroke
			(width 0)
			(type solid)
		)
		(fill yes)
		(layer "In2.Cu")
		(net "M_I_CPU1_SB_DQ<4>")
	)
	(gr_poly
		(pts
			(xy 143.194786 -277.124668) (xy 143.194786 -277.076916) (xy 142.994634 -277.076916) (xy 142.994634 -277.124668)
			(xy 143.09471 -277.22449)
		)
		(stroke
			(width 0)
			(type solid)
		)
		(fill yes)
		(layer "In2.Cu")
		(net "M_I_CPU1_SB_DQS_DP<5>")
	)
	(gr_poly
		(pts
			(xy 143.194786 -275.908008) (xy 143.09471 -275.808186) (xy 142.994634 -275.908008) (xy 142.994634 -275.95576)
			(xy 143.194786 -275.95576)
		)
		(stroke
			(width 0)
			(type solid)
		)
		(fill yes)
		(layer "In2.Cu")
		(net "M_I_CPU1_SB_DQS_DP<0>")
	)
	(gr_poly
		(pts
			(xy 143.194786 -275.504402) (xy 143.194786 -275.459952) (xy 142.994634 -275.459952) (xy 142.994634 -275.504402)
			(xy 143.09471 -275.604478)
		)
		(stroke
			(width 0)
			(type solid)
		)
		(fill yes)
		(layer "In2.Cu")
		(net "M_I_CPU1_SB_DQ<3>")
	)
	(gr_poly
		(pts
			(xy 143.194786 -274.28825) (xy 143.09471 -274.188174) (xy 142.994634 -274.28825) (xy 142.994634 -274.3327)
			(xy 143.194786 -274.3327)
		)
		(stroke
			(width 0)
			(type solid)
		)
		(fill yes)
		(layer "In2.Cu")
		(net "M_I_CPU1_SB_DQ<0>")
	)
	(gr_poly
		(pts
			(xy 143.194786 -273.88439) (xy 143.194786 -273.83994) (xy 142.994634 -273.83994) (xy 142.994634 -273.88439)
			(xy 143.09471 -273.984466)
		)
		(stroke
			(width 0)
			(type solid)
		)
		(fill yes)
		(layer "In2.Cu")
		(net "M_I_CPU1_SB_CB<3>")
	)
	(gr_poly
		(pts
			(xy 143.194786 -272.668238) (xy 143.09471 -272.568162) (xy 142.994634 -272.668238) (xy 142.994634 -272.712688)
			(xy 143.194786 -272.712688)
		)
		(stroke
			(width 0)
			(type solid)
		)
		(fill yes)
		(layer "In2.Cu")
		(net "M_I_CPU1_SB_CB<0>")
	)
	(gr_poly
		(pts
			(xy 143.194786 -272.264632) (xy 143.194786 -272.21688) (xy 142.994634 -272.21688) (xy 142.994634 -272.264632)
			(xy 143.09471 -272.364454)
		)
		(stroke
			(width 0)
			(type solid)
		)
		(fill yes)
		(layer "In2.Cu")
		(net "M_I_CPU1_SB_DQS_DP<4>")
	)
	(gr_poly
		(pts
			(xy 143.194786 -271.047972) (xy 143.09471 -270.94815) (xy 142.994634 -271.047972) (xy 142.994634 -271.095724)
			(xy 143.194786 -271.095724)
		)
		(stroke
			(width 0)
			(type solid)
		)
		(fill yes)
		(layer "In2.Cu")
		(net "M_I_CPU1_SB_DQS_DP<9>")
	)
	(gr_poly
		(pts
			(xy 143.194786 -270.644366) (xy 143.194786 -270.599916) (xy 142.994634 -270.599916) (xy 142.994634 -270.644366)
			(xy 143.09471 -270.744442)
		)
		(stroke
			(width 0)
			(type solid)
		)
		(fill yes)
		(layer "In2.Cu")
		(net "M_I_CPU1_SB_CB<7>")
	)
	(gr_poly
		(pts
			(xy 143.194786 -269.428214) (xy 143.09471 -269.328138) (xy 142.994634 -269.428214) (xy 142.994634 -269.472664)
			(xy 143.194786 -269.472664)
		)
		(stroke
			(width 0)
			(type solid)
		)
		(fill yes)
		(layer "In2.Cu")
		(net "M_I_CPU1_SB_CB<4>")
	)
	(gr_poly
		(pts
			(xy 143.194786 -267.404342) (xy 143.194786 -267.359892) (xy 142.994634 -267.359892) (xy 142.994634 -267.404342)
			(xy 143.09471 -267.504418)
		)
		(stroke
			(width 0)
			(type solid)
		)
		(fill yes)
		(layer "In2.Cu")
		(net "M_I_CPU1_SB_RSP<0>")
	)
	(gr_poly
		(pts
			(xy 143.194786 -265.78433) (xy 143.194786 -265.73988) (xy 142.994634 -265.73988) (xy 142.994634 -265.78433)
			(xy 143.09471 -265.884406)
		)
		(stroke
			(width 0)
			(type solid)
		)
		(fill yes)
		(layer "In2.Cu")
		(net "M_I_CPU1_SB_CS_N<0>")
	)
	(gr_poly
		(pts
			(xy 143.194786 -264.568178) (xy 143.09471 -264.468102) (xy 142.994634 -264.568178) (xy 142.994634 -264.612628)
			(xy 143.194786 -264.612628)
		)
		(stroke
			(width 0)
			(type solid)
		)
		(fill yes)
		(layer "In2.Cu")
		(net "M_I_CPU1_SB_CA<6>")
	)
	(gr_poly
		(pts
			(xy 143.194786 -264.164318) (xy 143.194786 -264.119868) (xy 142.994634 -264.119868) (xy 142.994634 -264.164318)
			(xy 143.09471 -264.264394)
		)
		(stroke
			(width 0)
			(type solid)
		)
		(fill yes)
		(layer "In2.Cu")
		(net "M_I_CPU1_SB_CA<5>")
	)
	(gr_poly
		(pts
			(xy 143.194786 -262.948166) (xy 143.09471 -262.84809) (xy 142.994634 -262.948166) (xy 142.994634 -262.992616)
			(xy 143.194786 -262.992616)
		)
		(stroke
			(width 0)
			(type solid)
		)
		(fill yes)
		(layer "In2.Cu")
		(net "M_I_CPU1_SB_CA<2>")
	)
	(gr_poly
		(pts
			(xy 143.194786 -262.544306) (xy 143.194786 -262.499856) (xy 142.994634 -262.499856) (xy 142.994634 -262.544306)
			(xy 143.09471 -262.644382)
		)
		(stroke
			(width 0)
			(type solid)
		)
		(fill yes)
		(layer "In2.Cu")
		(net "M_I_CPU1_SB_CA<1>")
	)
	(gr_poly
		(pts
			(xy 143.21282 -291.7063) (xy 143.24965 -291.569648) (xy 143.112998 -291.533072) (xy 143.071596 -291.556948)
			(xy 143.171672 -291.730176)
		)
		(stroke
			(width 0)
			(type solid)
		)
		(fill yes)
		(layer "In2.Cu")
		(net "M_I_CPU1_SB_DQS_DN<8>")
	)
	(gr_poly
		(pts
			(xy 143.213328 -294.947086) (xy 143.249904 -294.810434) (xy 143.113252 -294.773858) (xy 143.074644 -294.795956)
			(xy 143.17472 -294.969184)
		)
		(stroke
			(width 0)
			(type solid)
		)
		(fill yes)
		(layer "In2.Cu")
		(net "M_I_CPU1_SB_DQ<29>")
	)
	(gr_poly
		(pts
			(xy 143.213328 -293.327074) (xy 143.249904 -293.190422) (xy 143.113252 -293.153846) (xy 143.074644 -293.175944)
			(xy 143.17472 -293.349172)
		)
		(stroke
			(width 0)
			(type solid)
		)
		(fill yes)
		(layer "In2.Cu")
		(net "M_I_CPU1_SB_DQ<28>")
	)
	(gr_poly
		(pts
			(xy 143.28394 -229.555548) (xy 143.245332 -229.533196) (xy 143.108934 -229.569772) (xy 143.14551 -229.706424)
			(xy 143.183864 -229.728776)
		)
		(stroke
			(width 0)
			(type solid)
		)
		(fill yes)
		(layer "In2.Cu")
		(net "M_I_CPU1_SA_DQ<9>")
	)
	(gr_poly
		(pts
			(xy 143.28394 -227.93579) (xy 143.245332 -227.913438) (xy 143.108934 -227.950014) (xy 143.14551 -228.086666)
			(xy 143.183864 -228.109018)
		)
		(stroke
			(width 0)
			(type solid)
		)
		(fill yes)
		(layer "In2.Cu")
		(net "M_I_CPU1_SA_DQ<8>")
	)
	(gr_poly
		(pts
			(xy 143.28394 -226.315778) (xy 143.245332 -226.293426) (xy 143.108934 -226.330002) (xy 143.14551 -226.466654)
			(xy 143.183864 -226.489006)
		)
		(stroke
			(width 0)
			(type solid)
		)
		(fill yes)
		(layer "In2.Cu")
		(net "M_I_CPU1_SA_DQ<5>")
	)
	(gr_poly
		(pts
			(xy 143.28394 -224.695766) (xy 143.245332 -224.673414) (xy 143.108934 -224.70999) (xy 143.14551 -224.846642)
			(xy 143.183864 -224.868994)
		)
		(stroke
			(width 0)
			(type solid)
		)
		(fill yes)
		(layer "In2.Cu")
		(net "M_I_CPU1_SA_DQ<4>")
	)
	(gr_poly
		(pts
			(xy 143.286226 -231.177592) (xy 143.245078 -231.15397) (xy 143.108426 -231.190546) (xy 143.145002 -231.327198)
			(xy 143.18615 -231.35082)
		)
		(stroke
			(width 0)
			(type solid)
		)
		(fill yes)
		(layer "In2.Cu")
		(net "M_I_CPU1_SA_DQS_DP<1>")
	)
	(gr_poly
		(pts
			(xy 143.286734 -223.076516) (xy 143.245586 -223.05264) (xy 143.108934 -223.08947) (xy 143.14551 -223.225868)
			(xy 143.186912 -223.249744)
		)
		(stroke
			(width 0)
			(type solid)
		)
		(fill yes)
		(layer "In2.Cu")
		(net "M_I_CPU1_SA_DQS_DN<5>")
	)
	(gr_poly
		(pts
			(xy 143.364712 -256.026158) (xy 143.264636 -255.926336) (xy 143.16456 -256.026158) (xy 143.16456 -256.07391)
			(xy 143.364712 -256.07391)
		)
		(stroke
			(width 0)
			(type solid)
		)
		(fill yes)
		(layer "In2.Cu")
		(net "M_I_CPU1_CLK_DP<0>")
	)
	(gr_poly
		(pts
			(xy 143.364712 -255.622552) (xy 143.364712 -255.578102) (xy 143.16456 -255.578102) (xy 143.16456 -255.622552)
			(xy 143.264636 -255.722628)
		)
		(stroke
			(width 0)
			(type solid)
		)
		(fill yes)
		(layer "In2.Cu")
		(net "M_I_CPU1_SA_PAR")
	)
	(gr_poly
		(pts
			(xy 143.364712 -254.4064) (xy 143.264636 -254.306324) (xy 143.16456 -254.4064) (xy 143.16456 -254.45085)
			(xy 143.364712 -254.45085)
		)
		(stroke
			(width 0)
			(type solid)
		)
		(fill yes)
		(layer "In2.Cu")
		(net "M_I_CPU1_SA_CA<4>")
	)
	(gr_poly
		(pts
			(xy 143.364712 -254.00254) (xy 143.364712 -253.95809) (xy 143.16456 -253.95809) (xy 143.16456 -254.00254)
			(xy 143.264636 -254.102616)
		)
		(stroke
			(width 0)
			(type solid)
		)
		(fill yes)
		(layer "In2.Cu")
		(net "M_I_CPU1_SA_CA<3>")
	)
	(gr_poly
		(pts
			(xy 143.364712 -252.786388) (xy 143.264636 -252.686312) (xy 143.16456 -252.786388) (xy 143.16456 -252.830838)
			(xy 143.364712 -252.830838)
		)
		(stroke
			(width 0)
			(type solid)
		)
		(fill yes)
		(layer "In2.Cu")
		(net "M_I_CPU1_SA_CA<0>")
	)
	(gr_poly
		(pts
			(xy 143.364712 -251.166376) (xy 143.264636 -251.0663) (xy 143.16456 -251.166376) (xy 143.16456 -251.210826)
			(xy 143.364712 -251.210826)
		)
		(stroke
			(width 0)
			(type solid)
		)
		(fill yes)
		(layer "In2.Cu")
		(net "M_I_CPU1_SA_CS_N<0>")
	)
	(gr_poly
		(pts
			(xy 143.364712 -250.762516) (xy 143.364712 -250.718066) (xy 143.16456 -250.718066) (xy 143.16456 -250.762516)
			(xy 143.264636 -250.862592)
		)
		(stroke
			(width 0)
			(type solid)
		)
		(fill yes)
		(layer "In2.Cu")
		(net "M_I_CPU1_RESET_N")
	)
	(gr_poly
		(pts
			(xy 143.364712 -249.142504) (xy 143.364712 -249.098054) (xy 143.16456 -249.098054) (xy 143.16456 -249.142504)
			(xy 143.264636 -249.24258)
		)
		(stroke
			(width 0)
			(type solid)
		)
		(fill yes)
		(layer "In2.Cu")
		(net "M_I_CPU1_SA_CB<7>")
	)
	(gr_poly
		(pts
			(xy 143.364712 -247.926352) (xy 143.264636 -247.826276) (xy 143.16456 -247.926352) (xy 143.16456 -247.970802)
			(xy 143.364712 -247.970802)
		)
		(stroke
			(width 0)
			(type solid)
		)
		(fill yes)
		(layer "In2.Cu")
		(net "M_I_CPU1_SA_CB<4>")
	)
	(gr_poly
		(pts
			(xy 143.364712 -247.522746) (xy 143.364712 -247.474994) (xy 143.16456 -247.474994) (xy 143.16456 -247.522746)
			(xy 143.264636 -247.622568)
		)
		(stroke
			(width 0)
			(type solid)
		)
		(fill yes)
		(layer "In2.Cu")
		(net "M_I_CPU1_SA_DQS_DP<9>")
	)
	(gr_poly
		(pts
			(xy 143.364712 -246.306086) (xy 143.264636 -246.206264) (xy 143.16456 -246.306086) (xy 143.16456 -246.353838)
			(xy 143.364712 -246.353838)
		)
		(stroke
			(width 0)
			(type solid)
		)
		(fill yes)
		(layer "In2.Cu")
		(net "M_I_CPU1_SA_DQS_DP<4>")
	)
	(gr_poly
		(pts
			(xy 143.364712 -245.90248) (xy 143.364712 -245.85803) (xy 143.16456 -245.85803) (xy 143.16456 -245.90248)
			(xy 143.264636 -246.002556)
		)
		(stroke
			(width 0)
			(type solid)
		)
		(fill yes)
		(layer "In2.Cu")
		(net "M_I_CPU1_SA_CB<3>")
	)
	(gr_poly
		(pts
			(xy 143.364712 -244.686328) (xy 143.264636 -244.586252) (xy 143.16456 -244.686328) (xy 143.16456 -244.730778)
			(xy 143.364712 -244.730778)
		)
		(stroke
			(width 0)
			(type solid)
		)
		(fill yes)
		(layer "In2.Cu")
		(net "M_I_CPU1_SA_CB<0>")
	)
	(gr_poly
		(pts
			(xy 143.364712 -244.282468) (xy 143.364712 -244.238018) (xy 143.16456 -244.238018) (xy 143.16456 -244.282468)
			(xy 143.264636 -244.382544)
		)
		(stroke
			(width 0)
			(type solid)
		)
		(fill yes)
		(layer "In2.Cu")
		(net "M_I_CPU1_SA_DQ<31>")
	)
	(gr_poly
		(pts
			(xy 143.364712 -243.066316) (xy 143.264636 -242.96624) (xy 143.16456 -243.066316) (xy 143.16456 -243.110766)
			(xy 143.364712 -243.110766)
		)
		(stroke
			(width 0)
			(type solid)
		)
		(fill yes)
		(layer "In2.Cu")
		(net "M_I_CPU1_SA_DQ<28>")
	)
	(gr_poly
		(pts
			(xy 143.364712 -242.66271) (xy 143.364712 -242.614958) (xy 143.16456 -242.614958) (xy 143.16456 -242.66271)
			(xy 143.264636 -242.762532)
		)
		(stroke
			(width 0)
			(type solid)
		)
		(fill yes)
		(layer "In2.Cu")
		(net "M_I_CPU1_SA_DQS_DP<8>")
	)
	(gr_poly
		(pts
			(xy 143.364712 -241.44605) (xy 143.264636 -241.346228) (xy 143.16456 -241.44605) (xy 143.16456 -241.493802)
			(xy 143.364712 -241.493802)
		)
		(stroke
			(width 0)
			(type solid)
		)
		(fill yes)
		(layer "In2.Cu")
		(net "M_I_CPU1_SA_DQS_DP<3>")
	)
	(gr_poly
		(pts
			(xy 143.364712 -241.042444) (xy 143.364712 -240.997994) (xy 143.16456 -240.997994) (xy 143.16456 -241.042444)
			(xy 143.264636 -241.14252)
		)
		(stroke
			(width 0)
			(type solid)
		)
		(fill yes)
		(layer "In2.Cu")
		(net "M_I_CPU1_SA_DQ<27>")
	)
	(gr_poly
		(pts
			(xy 143.364712 -239.826292) (xy 143.264636 -239.726216) (xy 143.16456 -239.826292) (xy 143.16456 -239.870742)
			(xy 143.364712 -239.870742)
		)
		(stroke
			(width 0)
			(type solid)
		)
		(fill yes)
		(layer "In2.Cu")
		(net "M_I_CPU1_SA_DQ<24>")
	)
	(gr_poly
		(pts
			(xy 143.364712 -239.422432) (xy 143.364712 -239.377982) (xy 143.16456 -239.377982) (xy 143.16456 -239.422432)
			(xy 143.264636 -239.522508)
		)
		(stroke
			(width 0)
			(type solid)
		)
		(fill yes)
		(layer "In2.Cu")
		(net "M_I_CPU1_SA_DQ<23>")
	)
	(gr_poly
		(pts
			(xy 143.364712 -238.20628) (xy 143.264636 -238.106204) (xy 143.16456 -238.20628) (xy 143.16456 -238.25073)
			(xy 143.364712 -238.25073)
		)
		(stroke
			(width 0)
			(type solid)
		)
		(fill yes)
		(layer "In2.Cu")
		(net "M_I_CPU1_SA_DQ<20>")
	)
	(gr_poly
		(pts
			(xy 143.364712 -236.586014) (xy 143.264636 -236.486192) (xy 143.16456 -236.586014) (xy 143.16456 -236.633766)
			(xy 143.364712 -236.633766)
		)
		(stroke
			(width 0)
			(type solid)
		)
		(fill yes)
		(layer "In2.Cu")
		(net "M_I_CPU1_SA_DQS_DP<2>")
	)
	(gr_poly
		(pts
			(xy 143.364712 -236.182408) (xy 143.364712 -236.137958) (xy 143.16456 -236.137958) (xy 143.16456 -236.182408)
			(xy 143.264636 -236.282484)
		)
		(stroke
			(width 0)
			(type solid)
		)
		(fill yes)
		(layer "In2.Cu")
		(net "M_I_CPU1_SA_DQ<19>")
	)
	(gr_poly
		(pts
			(xy 143.364712 -234.966256) (xy 143.264636 -234.86618) (xy 143.16456 -234.966256) (xy 143.16456 -235.010706)
			(xy 143.364712 -235.010706)
		)
		(stroke
			(width 0)
			(type solid)
		)
		(fill yes)
		(layer "In2.Cu")
		(net "M_I_CPU1_SA_DQ<16>")
	)
	(gr_poly
		(pts
			(xy 143.364712 -234.562396) (xy 143.364712 -234.517946) (xy 143.16456 -234.517946) (xy 143.16456 -234.562396)
			(xy 143.264636 -234.662472)
		)
		(stroke
			(width 0)
			(type solid)
		)
		(fill yes)
		(layer "In2.Cu")
		(net "M_I_CPU1_SA_DQ<15>")
	)
	(gr_poly
		(pts
			(xy 143.364712 -233.346244) (xy 143.264636 -233.246168) (xy 143.16456 -233.346244) (xy 143.16456 -233.390694)
			(xy 143.364712 -233.390694)
		)
		(stroke
			(width 0)
			(type solid)
		)
		(fill yes)
		(layer "In2.Cu")
		(net "M_I_CPU1_SA_DQ<12>")
	)
	(gr_poly
		(pts
			(xy 143.364712 -232.942638) (xy 143.364712 -232.894886) (xy 143.16456 -232.894886) (xy 143.16456 -232.942638)
			(xy 143.264636 -233.04246)
		)
		(stroke
			(width 0)
			(type solid)
		)
		(fill yes)
		(layer "In2.Cu")
		(net "M_I_CPU1_SA_DQS_DP<6>")
	)
	(gr_poly
		(pts
			(xy 143.370808 -237.802166) (xy 143.370808 -237.754668) (xy 143.17091 -237.754668) (xy 143.17091 -237.802166)
			(xy 143.270732 -237.902242)
		)
		(stroke
			(width 0)
			(type solid)
		)
		(fill yes)
		(layer "In2.Cu")
		(net "M_I_CPU1_SA_DQS_DP<7>")
	)
	(gr_poly
		(pts
			(xy 143.420084 -230.240078) (xy 143.383508 -230.103426) (xy 143.3449 -230.081328) (xy 143.244824 -230.254556)
			(xy 143.283432 -230.276654)
		)
		(stroke
			(width 0)
			(type solid)
		)
		(fill yes)
		(layer "In2.Cu")
		(net "M_I_CPU1_SA_DQ<11>")
	)
	(gr_poly
		(pts
			(xy 143.420338 -222.139002) (xy 143.383762 -222.00235) (xy 143.342614 -221.978728) (xy 143.242538 -222.151956)
			(xy 143.283686 -222.175578)
		)
		(stroke
			(width 0)
			(type solid)
		)
		(fill yes)
		(layer "In2.Cu")
		(net "M_I_CPU1_SA_DQS_DN<0>")
	)
	(gr_poly
		(pts
			(xy 143.420592 -231.859328) (xy 143.384016 -231.72293) (xy 143.342614 -231.699054) (xy 143.242792 -231.872282)
			(xy 143.28394 -231.895904)
		)
		(stroke
			(width 0)
			(type solid)
		)
		(fill yes)
		(layer "In2.Cu")
		(net "M_I_CPU1_SA_DQS_DN<1>")
	)
	(gr_poly
		(pts
			(xy 143.420592 -223.759522) (xy 143.384016 -223.623124) (xy 143.342614 -223.599248) (xy 143.242792 -223.772476)
			(xy 143.28394 -223.796352)
		)
		(stroke
			(width 0)
			(type solid)
		)
		(fill yes)
		(layer "In2.Cu")
		(net "M_I_CPU1_SA_DQS_DP<5>")
	)
	(gr_poly
		(pts
			(xy 143.420846 -228.61905) (xy 143.384016 -228.482398) (xy 143.345662 -228.460046) (xy 143.245586 -228.633274)
			(xy 143.284194 -228.655626)
		)
		(stroke
			(width 0)
			(type solid)
		)
		(fill yes)
		(layer "In2.Cu")
		(net "M_I_CPU1_SA_DQ<10>")
	)
	(gr_poly
		(pts
			(xy 143.420846 -226.999038) (xy 143.384016 -226.862386) (xy 143.345662 -226.840034) (xy 143.245586 -227.013262)
			(xy 143.284194 -227.035614)
		)
		(stroke
			(width 0)
			(type solid)
		)
		(fill yes)
		(layer "In2.Cu")
		(net "M_I_CPU1_SA_DQ<7>")
	)
	(gr_poly
		(pts
			(xy 143.420846 -225.379026) (xy 143.384016 -225.242374) (xy 143.345662 -225.220022) (xy 143.245586 -225.39325)
			(xy 143.284194 -225.415602)
		)
		(stroke
			(width 0)
			(type solid)
		)
		(fill yes)
		(layer "In2.Cu")
		(net "M_I_CPU1_SA_DQ<6>")
	)
	(gr_poly
		(pts
			(xy 143.584676 -294.686482) (xy 143.4846 -294.513254) (xy 143.445992 -294.535352) (xy 143.409416 -294.672004)
			(xy 143.546068 -294.70858)
		)
		(stroke
			(width 0)
			(type solid)
		)
		(fill yes)
		(layer "In2.Cu")
		(net "M_I_CPU1_SB_DQ<30>")
	)
	(gr_poly
		(pts
			(xy 143.586708 -293.064184) (xy 143.486886 -292.890956) (xy 143.445484 -292.914832) (xy 143.408908 -293.05123)
			(xy 143.54556 -293.08806)
		)
		(stroke
			(width 0)
			(type solid)
		)
		(fill yes)
		(layer "In2.Cu")
		(net "M_I_CPU1_SB_DQS_DP<8>")
	)
	(gr_poly
		(pts
			(xy 143.586708 -291.444172) (xy 143.486886 -291.270944) (xy 143.445484 -291.29482) (xy 143.408908 -291.431218)
			(xy 143.54556 -291.468048)
		)
		(stroke
			(width 0)
			(type solid)
		)
		(fill yes)
		(layer "In2.Cu")
		(net "M_I_CPU1_SB_DQS_DN<3>")
	)
	(gr_poly
		(pts
			(xy 143.664686 -289.67811) (xy 143.56461 -289.578034) (xy 143.464534 -289.67811) (xy 143.464534 -289.72256)
			(xy 143.664686 -289.72256)
		)
		(stroke
			(width 0)
			(type solid)
		)
		(fill yes)
		(layer "In2.Cu")
		(net "M_I_CPU1_SB_DQ<25>")
	)
	(gr_poly
		(pts
			(xy 143.664686 -289.27425) (xy 143.664686 -289.2298) (xy 143.464534 -289.2298) (xy 143.464534 -289.27425)
			(xy 143.56461 -289.374326)
		)
		(stroke
			(width 0)
			(type solid)
		)
		(fill yes)
		(layer "In2.Cu")
		(net "M_I_CPU1_SB_DQ<26>")
	)
	(gr_poly
		(pts
			(xy 143.664686 -288.058098) (xy 143.56461 -287.958022) (xy 143.464534 -288.058098) (xy 143.464534 -288.102548)
			(xy 143.664686 -288.102548)
		)
		(stroke
			(width 0)
			(type solid)
		)
		(fill yes)
		(layer "In2.Cu")
		(net "M_I_CPU1_SB_DQ<21>")
	)
	(gr_poly
		(pts
			(xy 143.664686 -287.654492) (xy 143.664686 -287.610042) (xy 143.464534 -287.610042) (xy 143.464534 -287.654492)
			(xy 143.56461 -287.754568)
		)
		(stroke
			(width 0)
			(type solid)
		)
		(fill yes)
		(layer "In2.Cu")
		(net "M_I_CPU1_SB_DQ<22>")
	)
	(gr_poly
		(pts
			(xy 143.664686 -286.438086) (xy 143.56461 -286.33801) (xy 143.464534 -286.438086) (xy 143.464534 -286.485838)
			(xy 143.664686 -286.485838)
		)
		(stroke
			(width 0)
			(type solid)
		)
		(fill yes)
		(layer "In2.Cu")
		(net "M_I_CPU1_SB_DQS_DN<7>")
	)
	(gr_poly
		(pts
			(xy 143.664686 -286.034734) (xy 143.664686 -285.986982) (xy 143.464534 -285.986982) (xy 143.464534 -286.034734)
			(xy 143.56461 -286.134556)
		)
		(stroke
			(width 0)
			(type solid)
		)
		(fill yes)
		(layer "In2.Cu")
		(net "M_I_CPU1_SB_DQS_DN<2>")
	)
	(gr_poly
		(pts
			(xy 143.664686 -284.818328) (xy 143.56461 -284.718252) (xy 143.464534 -284.818328) (xy 143.464534 -284.862778)
			(xy 143.664686 -284.862778)
		)
		(stroke
			(width 0)
			(type solid)
		)
		(fill yes)
		(layer "In2.Cu")
		(net "M_I_CPU1_SB_DQ<17>")
	)
	(gr_poly
		(pts
			(xy 143.664686 -284.414468) (xy 143.664686 -284.370018) (xy 143.464534 -284.370018) (xy 143.464534 -284.414468)
			(xy 143.56461 -284.514544)
		)
		(stroke
			(width 0)
			(type solid)
		)
		(fill yes)
		(layer "In2.Cu")
		(net "M_I_CPU1_SB_DQ<18>")
	)
	(gr_poly
		(pts
			(xy 143.664686 -283.198316) (xy 143.56461 -283.09824) (xy 143.464534 -283.198316) (xy 143.464534 -283.242766)
			(xy 143.664686 -283.242766)
		)
		(stroke
			(width 0)
			(type solid)
		)
		(fill yes)
		(layer "In2.Cu")
		(net "M_I_CPU1_SB_DQ<13>")
	)
	(gr_poly
		(pts
			(xy 143.664686 -282.794456) (xy 143.664686 -282.750006) (xy 143.464534 -282.750006) (xy 143.464534 -282.794456)
			(xy 143.56461 -282.894532)
		)
		(stroke
			(width 0)
			(type solid)
		)
		(fill yes)
		(layer "In2.Cu")
		(net "M_I_CPU1_SB_DQ<14>")
	)
	(gr_poly
		(pts
			(xy 143.664686 -281.57805) (xy 143.56461 -281.478228) (xy 143.464534 -281.57805) (xy 143.464534 -281.625802)
			(xy 143.664686 -281.625802)
		)
		(stroke
			(width 0)
			(type solid)
		)
		(fill yes)
		(layer "In2.Cu")
		(net "M_I_CPU1_SB_DQS_DN<6>")
	)
	(gr_poly
		(pts
			(xy 143.664686 -281.174698) (xy 143.664686 -281.126946) (xy 143.464534 -281.126946) (xy 143.464534 -281.174698)
			(xy 143.56461 -281.27452)
		)
		(stroke
			(width 0)
			(type solid)
		)
		(fill yes)
		(layer "In2.Cu")
		(net "M_I_CPU1_SB_DQS_DN<1>")
	)
	(gr_poly
		(pts
			(xy 143.664686 -279.958292) (xy 143.56461 -279.858216) (xy 143.464534 -279.958292) (xy 143.464534 -280.002742)
			(xy 143.664686 -280.002742)
		)
		(stroke
			(width 0)
			(type solid)
		)
		(fill yes)
		(layer "In2.Cu")
		(net "M_I_CPU1_SB_DQ<9>")
	)
	(gr_poly
		(pts
			(xy 143.664686 -279.554432) (xy 143.664686 -279.509982) (xy 143.464534 -279.509982) (xy 143.464534 -279.554432)
			(xy 143.56461 -279.654508)
		)
		(stroke
			(width 0)
			(type solid)
		)
		(fill yes)
		(layer "In2.Cu")
		(net "M_I_CPU1_SB_DQ<10>")
	)
	(gr_poly
		(pts
			(xy 143.664686 -278.33828) (xy 143.56461 -278.238204) (xy 143.464534 -278.33828) (xy 143.464534 -278.38273)
			(xy 143.664686 -278.38273)
		)
		(stroke
			(width 0)
			(type solid)
		)
		(fill yes)
		(layer "In2.Cu")
		(net "M_I_CPU1_SB_DQ<5>")
	)
	(gr_poly
		(pts
			(xy 143.664686 -277.93442) (xy 143.664686 -277.88997) (xy 143.464534 -277.88997) (xy 143.464534 -277.93442)
			(xy 143.56461 -278.034496)
		)
		(stroke
			(width 0)
			(type solid)
		)
		(fill yes)
		(layer "In2.Cu")
		(net "M_I_CPU1_SB_DQ<6>")
	)
	(gr_poly
		(pts
			(xy 143.664686 -276.718014) (xy 143.56461 -276.618192) (xy 143.464534 -276.718014) (xy 143.464534 -276.765766)
			(xy 143.664686 -276.765766)
		)
		(stroke
			(width 0)
			(type solid)
		)
		(fill yes)
		(layer "In2.Cu")
		(net "M_I_CPU1_SB_DQS_DN<5>")
	)
	(gr_poly
		(pts
			(xy 143.664686 -276.314662) (xy 143.664686 -276.26691) (xy 143.464534 -276.26691) (xy 143.464534 -276.314662)
			(xy 143.56461 -276.414484)
		)
		(stroke
			(width 0)
			(type solid)
		)
		(fill yes)
		(layer "In2.Cu")
		(net "M_I_CPU1_SB_DQS_DN<0>")
	)
	(gr_poly
		(pts
			(xy 143.664686 -275.098256) (xy 143.56461 -274.99818) (xy 143.464534 -275.098256) (xy 143.464534 -275.142706)
			(xy 143.664686 -275.142706)
		)
		(stroke
			(width 0)
			(type solid)
		)
		(fill yes)
		(layer "In2.Cu")
		(net "M_I_CPU1_SB_DQ<1>")
	)
	(gr_poly
		(pts
			(xy 143.664686 -274.694396) (xy 143.664686 -274.649946) (xy 143.464534 -274.649946) (xy 143.464534 -274.694396)
			(xy 143.56461 -274.794472)
		)
		(stroke
			(width 0)
			(type solid)
		)
		(fill yes)
		(layer "In2.Cu")
		(net "M_I_CPU1_SB_DQ<2>")
	)
	(gr_poly
		(pts
			(xy 143.664686 -273.478244) (xy 143.56461 -273.378168) (xy 143.464534 -273.478244) (xy 143.464534 -273.522694)
			(xy 143.664686 -273.522694)
		)
		(stroke
			(width 0)
			(type solid)
		)
		(fill yes)
		(layer "In2.Cu")
		(net "M_I_CPU1_SB_CB<1>")
	)
	(gr_poly
		(pts
			(xy 143.664686 -273.074384) (xy 143.664686 -273.029934) (xy 143.464534 -273.029934) (xy 143.464534 -273.074384)
			(xy 143.56461 -273.17446)
		)
		(stroke
			(width 0)
			(type solid)
		)
		(fill yes)
		(layer "In2.Cu")
		(net "M_I_CPU1_SB_CB<2>")
	)
	(gr_poly
		(pts
			(xy 143.664686 -271.857978) (xy 143.56461 -271.758156) (xy 143.464534 -271.857978) (xy 143.464534 -271.90573)
			(xy 143.664686 -271.90573)
		)
		(stroke
			(width 0)
			(type solid)
		)
		(fill yes)
		(layer "In2.Cu")
		(net "M_I_CPU1_SB_DQS_DN<4>")
	)
	(gr_poly
		(pts
			(xy 143.664686 -271.454626) (xy 143.664686 -271.406874) (xy 143.464534 -271.406874) (xy 143.464534 -271.454626)
			(xy 143.56461 -271.554448)
		)
		(stroke
			(width 0)
			(type solid)
		)
		(fill yes)
		(layer "In2.Cu")
		(net "M_I_CPU1_SB_DQS_DN<9>")
	)
	(gr_poly
		(pts
			(xy 143.664686 -270.23822) (xy 143.56461 -270.138144) (xy 143.464534 -270.23822) (xy 143.464534 -270.28267)
			(xy 143.664686 -270.28267)
		)
		(stroke
			(width 0)
			(type solid)
		)
		(fill yes)
		(layer "In2.Cu")
		(net "M_I_CPU1_SB_CB<5>")
	)
	(gr_poly
		(pts
			(xy 143.664686 -269.83436) (xy 143.664686 -269.78991) (xy 143.464534 -269.78991) (xy 143.464534 -269.83436)
			(xy 143.56461 -269.934436)
		)
		(stroke
			(width 0)
			(type solid)
		)
		(fill yes)
		(layer "In2.Cu")
		(net "M_I_CPU1_SB_CB<6>")
	)
	(gr_poly
		(pts
			(xy 143.664686 -266.998196) (xy 143.56461 -266.89812) (xy 143.464534 -266.998196) (xy 143.464534 -267.042646)
			(xy 143.664686 -267.042646)
		)
		(stroke
			(width 0)
			(type solid)
		)
		(fill yes)
		(layer "In2.Cu")
		(net "M_I_CPU1_SA_RSP<0>")
	)
	(gr_poly
		(pts
			(xy 143.664686 -266.594336) (xy 143.664686 -266.549886) (xy 143.464534 -266.549886) (xy 143.464534 -266.594336)
			(xy 143.56461 -266.694412)
		)
		(stroke
			(width 0)
			(type solid)
		)
		(fill yes)
		(layer "In2.Cu")
		(net "M_I_CPU1_SB_CS_N<1>")
	)
	(gr_poly
		(pts
			(xy 143.664686 -265.378184) (xy 143.56461 -265.278108) (xy 143.464534 -265.378184) (xy 143.464534 -265.422634)
			(xy 143.664686 -265.422634)
		)
		(stroke
			(width 0)
			(type solid)
		)
		(fill yes)
		(layer "In2.Cu")
		(net "M_I_CPU1_SB_PAR")
	)
	(gr_poly
		(pts
			(xy 143.664686 -263.758172) (xy 143.56461 -263.658096) (xy 143.464534 -263.758172) (xy 143.464534 -263.802622)
			(xy 143.664686 -263.802622)
		)
		(stroke
			(width 0)
			(type solid)
		)
		(fill yes)
		(layer "In2.Cu")
		(net "M_I_CPU1_SB_CA<4>")
	)
	(gr_poly
		(pts
			(xy 143.664686 -263.354312) (xy 143.664686 -263.309862) (xy 143.464534 -263.309862) (xy 143.464534 -263.354312)
			(xy 143.56461 -263.454388)
		)
		(stroke
			(width 0)
			(type solid)
		)
		(fill yes)
		(layer "In2.Cu")
		(net "M_I_CPU1_SB_CA<3>")
	)
	(gr_poly
		(pts
			(xy 143.664686 -262.13816) (xy 143.56461 -262.038084) (xy 143.464534 -262.13816) (xy 143.464534 -262.18261)
			(xy 143.664686 -262.18261)
		)
		(stroke
			(width 0)
			(type solid)
		)
		(fill yes)
		(layer "In2.Cu")
		(net "M_I_CPU1_SB_CA<0>")
	)
	(gr_poly
		(pts
			(xy 143.683228 -295.757092) (xy 143.719804 -295.62044) (xy 143.583152 -295.583864) (xy 143.544544 -295.605962)
			(xy 143.64462 -295.77919)
		)
		(stroke
			(width 0)
			(type solid)
		)
		(fill yes)
		(layer "In2.Cu")
		(net "M_I_CPU1_SB_DQ<29>")
	)
	(gr_poly
		(pts
			(xy 143.683228 -294.13708) (xy 143.719804 -294.000428) (xy 143.583152 -293.963852) (xy 143.544544 -293.98595)
			(xy 143.64462 -294.159178)
		)
		(stroke
			(width 0)
			(type solid)
		)
		(fill yes)
		(layer "In2.Cu")
		(net "M_I_CPU1_SB_DQ<28>")
	)
	(gr_poly
		(pts
			(xy 143.68399 -292.517576) (xy 143.720566 -292.381178) (xy 143.583914 -292.344348) (xy 143.542766 -292.368224)
			(xy 143.642588 -292.541452)
		)
		(stroke
			(width 0)
			(type solid)
		)
		(fill yes)
		(layer "In2.Cu")
		(net "M_I_CPU1_SB_DQS_DN<8>")
	)
	(gr_poly
		(pts
			(xy 143.68399 -290.897564) (xy 143.720566 -290.761166) (xy 143.583914 -290.724336) (xy 143.542766 -290.748212)
			(xy 143.642588 -290.92144)
		)
		(stroke
			(width 0)
			(type solid)
		)
		(fill yes)
		(layer "In2.Cu")
		(net "M_I_CPU1_SB_DQS_DP<3>")
	)
	(gr_poly
		(pts
			(xy 143.75384 -228.745796) (xy 143.715232 -228.723444) (xy 143.578834 -228.76002) (xy 143.61541 -228.896672)
			(xy 143.653764 -228.919024)
		)
		(stroke
			(width 0)
			(type solid)
		)
		(fill yes)
		(layer "In2.Cu")
		(net "M_I_CPU1_SA_DQ<9>")
	)
	(gr_poly
		(pts
			(xy 143.75384 -227.125784) (xy 143.715232 -227.103432) (xy 143.578834 -227.140008) (xy 143.61541 -227.27666)
			(xy 143.653764 -227.299012)
		)
		(stroke
			(width 0)
			(type solid)
		)
		(fill yes)
		(layer "In2.Cu")
		(net "M_I_CPU1_SA_DQ<8>")
	)
	(gr_poly
		(pts
			(xy 143.75384 -225.505772) (xy 143.715232 -225.48342) (xy 143.578834 -225.519996) (xy 143.61541 -225.656648)
			(xy 143.653764 -225.679)
		)
		(stroke
			(width 0)
			(type solid)
		)
		(fill yes)
		(layer "In2.Cu")
		(net "M_I_CPU1_SA_DQ<5>")
	)
	(gr_poly
		(pts
			(xy 143.75384 -223.88576) (xy 143.715232 -223.863408) (xy 143.578834 -223.899984) (xy 143.61541 -224.036636)
			(xy 143.653764 -224.058988)
		)
		(stroke
			(width 0)
			(type solid)
		)
		(fill yes)
		(layer "In2.Cu")
		(net "M_I_CPU1_SA_DQ<4>")
	)
	(gr_poly
		(pts
			(xy 143.756634 -231.986328) (xy 143.715486 -231.962452) (xy 143.578834 -231.999282) (xy 143.61541 -232.13568)
			(xy 143.656812 -232.159556)
		)
		(stroke
			(width 0)
			(type solid)
		)
		(fill yes)
		(layer "In2.Cu")
		(net "M_I_CPU1_SA_DQS_DN<6>")
	)
	(gr_poly
		(pts
			(xy 143.756634 -222.26651) (xy 143.715486 -222.242634) (xy 143.578834 -222.279464) (xy 143.61541 -222.415862)
			(xy 143.656812 -222.439738)
		)
		(stroke
			(width 0)
			(type solid)
		)
		(fill yes)
		(layer "In2.Cu")
		(net "M_I_CPU1_SA_DQS_DN<5>")
	)
	(gr_poly
		(pts
			(xy 143.757396 -230.3653) (xy 143.716248 -230.341424) (xy 143.579596 -230.378) (xy 143.616172 -230.514652)
			(xy 143.65732 -230.538528)
		)
		(stroke
			(width 0)
			(type solid)
		)
		(fill yes)
		(layer "In2.Cu")
		(net "M_I_CPU1_SA_DQS_DP<1>")
	)
	(gr_poly
		(pts
			(xy 143.820134 -254.812292) (xy 143.820134 -254.768096) (xy 143.620236 -254.768096) (xy 143.620236 -254.812292)
			(xy 143.720058 -254.912368)
		)
		(stroke
			(width 0)
			(type solid)
		)
		(fill yes)
		(layer "In2.Cu")
		(net "M_I_CPU1_SA_CA<5>")
	)
	(gr_poly
		(pts
			(xy 143.820134 -253.192534) (xy 143.820134 -253.148084) (xy 143.620236 -253.148084) (xy 143.620236 -253.192534)
			(xy 143.720058 -253.292356)
		)
		(stroke
			(width 0)
			(type solid)
		)
		(fill yes)
		(layer "In2.Cu")
		(net "M_I_CPU1_SA_CA<1>")
	)
	(gr_poly
		(pts
			(xy 143.820134 -248.332244) (xy 143.820134 -248.288048) (xy 143.620236 -248.288048) (xy 143.620236 -248.332244)
			(xy 143.720058 -248.43232)
		)
		(stroke
			(width 0)
			(type solid)
		)
		(fill yes)
		(layer "In2.Cu")
		(net "M_I_CPU1_SA_CB<6>")
	)
	(gr_poly
		(pts
			(xy 143.820134 -245.09222) (xy 143.820134 -245.04777) (xy 143.620236 -245.04777) (xy 143.620236 -245.09222)
			(xy 143.720058 -245.192296)
		)
		(stroke
			(width 0)
			(type solid)
		)
		(fill yes)
		(layer "In2.Cu")
		(net "M_I_CPU1_SA_CB<2>")
	)
	(gr_poly
		(pts
			(xy 143.82877 -243.472462) (xy 143.82877 -243.428012) (xy 143.628618 -243.428012) (xy 143.628618 -243.472462)
			(xy 143.728694 -243.572538)
		)
		(stroke
			(width 0)
			(type solid)
		)
		(fill yes)
		(layer "In2.Cu")
		(net "M_I_CPU1_SA_DQ<30>")
	)
	(gr_poly
		(pts
			(xy 143.82877 -241.852704) (xy 143.82877 -241.804952) (xy 143.628618 -241.804952) (xy 143.628618 -241.852704)
			(xy 143.728694 -241.952526)
		)
		(stroke
			(width 0)
			(type solid)
		)
		(fill yes)
		(layer "In2.Cu")
		(net "M_I_CPU1_SA_DQS_DN<3>")
	)
	(gr_poly
		(pts
			(xy 143.82877 -240.636298) (xy 143.728694 -240.536222) (xy 143.628618 -240.636298) (xy 143.628618 -240.680748)
			(xy 143.82877 -240.680748)
		)
		(stroke
			(width 0)
			(type solid)
		)
		(fill yes)
		(layer "In2.Cu")
		(net "M_I_CPU1_SA_DQ<25>")
	)
	(gr_poly
		(pts
			(xy 143.82877 -240.232438) (xy 143.82877 -240.187988) (xy 143.628618 -240.187988) (xy 143.628618 -240.232438)
			(xy 143.728694 -240.332514)
		)
		(stroke
			(width 0)
			(type solid)
		)
		(fill yes)
		(layer "In2.Cu")
		(net "M_I_CPU1_SA_DQ<26>")
	)
	(gr_poly
		(pts
			(xy 143.82877 -236.992668) (xy 143.82877 -236.944916) (xy 143.628618 -236.944916) (xy 143.628618 -236.992668)
			(xy 143.728694 -237.09249)
		)
		(stroke
			(width 0)
			(type solid)
		)
		(fill yes)
		(layer "In2.Cu")
		(net "M_I_CPU1_SA_DQS_DN<2>")
	)
	(gr_poly
		(pts
			(xy 143.82877 -235.372402) (xy 143.82877 -235.327952) (xy 143.628618 -235.327952) (xy 143.628618 -235.372402)
			(xy 143.728694 -235.472478)
		)
		(stroke
			(width 0)
			(type solid)
		)
		(fill yes)
		(layer "In2.Cu")
		(net "M_I_CPU1_SA_DQ<18>")
	)
	(gr_poly
		(pts
			(xy 143.82877 -233.75239) (xy 143.82877 -233.70794) (xy 143.628618 -233.70794) (xy 143.628618 -233.75239)
			(xy 143.728694 -233.852466)
		)
		(stroke
			(width 0)
			(type solid)
		)
		(fill yes)
		(layer "In2.Cu")
		(net "M_I_CPU1_SA_DQ<14>")
	)
	(gr_poly
		(pts
			(xy 143.834866 -256.432812) (xy 143.834866 -256.38506) (xy 143.634714 -256.38506) (xy 143.634714 -256.432812)
			(xy 143.73479 -256.532634)
		)
		(stroke
			(width 0)
			(type solid)
		)
		(fill yes)
		(layer "In2.Cu")
		(net "M_I_CPU1_CLK_DN<0>")
	)
	(gr_poly
		(pts
			(xy 143.834866 -253.596394) (xy 143.73479 -253.496318) (xy 143.634714 -253.596394) (xy 143.634714 -253.640844)
			(xy 143.834866 -253.640844)
		)
		(stroke
			(width 0)
			(type solid)
		)
		(fill yes)
		(layer "In2.Cu")
		(net "M_I_CPU1_SA_CA<2>")
	)
	(gr_poly
		(pts
			(xy 143.834866 -250.35637) (xy 143.73479 -250.256294) (xy 143.634714 -250.35637) (xy 143.634714 -250.40082)
			(xy 143.834866 -250.40082)
		)
		(stroke
			(width 0)
			(type solid)
		)
		(fill yes)
		(layer "In2.Cu")
		(net "M_I_CPU1_ALERT_R_N")
	)
	(gr_poly
		(pts
			(xy 143.834866 -245.496334) (xy 143.73479 -245.396258) (xy 143.634714 -245.496334) (xy 143.634714 -245.540784)
			(xy 143.834866 -245.540784)
		)
		(stroke
			(width 0)
			(type solid)
		)
		(fill yes)
		(layer "In2.Cu")
		(net "M_I_CPU1_SA_CB<1>")
	)
	(gr_poly
		(pts
			(xy 143.834866 -243.876322) (xy 143.73479 -243.776246) (xy 143.634714 -243.876322) (xy 143.634714 -243.920772)
			(xy 143.834866 -243.920772)
		)
		(stroke
			(width 0)
			(type solid)
		)
		(fill yes)
		(layer "In2.Cu")
		(net "M_I_CPU1_SA_DQ<29>")
	)
	(gr_poly
		(pts
			(xy 143.840962 -242.256056) (xy 143.740886 -242.15598) (xy 143.64081 -242.256056) (xy 143.64081 -242.303554)
			(xy 143.840962 -242.303554)
		)
		(stroke
			(width 0)
			(type solid)
		)
		(fill yes)
		(layer "In2.Cu")
		(net "M_I_CPU1_SA_DQS_DN<8>")
	)
	(gr_poly
		(pts
			(xy 143.843502 -255.216152) (xy 143.743426 -255.116076) (xy 143.643604 -255.216152) (xy 143.643604 -255.260602)
			(xy 143.843502 -255.260602)
		)
		(stroke
			(width 0)
			(type solid)
		)
		(fill yes)
		(layer "In2.Cu")
		(net "M_I_CPU1_SA_CA<6>")
	)
	(gr_poly
		(pts
			(xy 143.843502 -251.976128) (xy 143.743426 -251.876052) (xy 143.643604 -251.976128) (xy 143.643604 -252.020578)
			(xy 143.843502 -252.020578)
		)
		(stroke
			(width 0)
			(type solid)
		)
		(fill yes)
		(layer "In2.Cu")
		(net "M_I_CPU1_SA_CS_N<1>")
	)
	(gr_poly
		(pts
			(xy 143.843502 -248.736104) (xy 143.743426 -248.636028) (xy 143.643604 -248.736104) (xy 143.643604 -248.780554)
			(xy 143.843502 -248.780554)
		)
		(stroke
			(width 0)
			(type solid)
		)
		(fill yes)
		(layer "In2.Cu")
		(net "M_I_CPU1_SA_CB<5>")
	)
	(gr_poly
		(pts
			(xy 143.843502 -247.115838) (xy 143.743426 -247.016016) (xy 143.643604 -247.115838) (xy 143.643604 -247.16359)
			(xy 143.843502 -247.16359)
		)
		(stroke
			(width 0)
			(type solid)
		)
		(fill yes)
		(layer "In2.Cu")
		(net "M_I_CPU1_SA_DQS_DN<9>")
	)
	(gr_poly
		(pts
			(xy 143.890492 -232.669334) (xy 143.853916 -232.532936) (xy 143.812514 -232.50906) (xy 143.712692 -232.682288)
			(xy 143.75384 -232.706164)
		)
		(stroke
			(width 0)
			(type solid)
		)
		(fill yes)
		(layer "In2.Cu")
		(net "M_I_CPU1_SA_DQS_DP<6>")
	)
	(gr_poly
		(pts
			(xy 143.890492 -222.949516) (xy 143.853916 -222.813118) (xy 143.812514 -222.789242) (xy 143.712692 -222.96247)
			(xy 143.75384 -222.986092)
		)
		(stroke
			(width 0)
			(type solid)
		)
		(fill yes)
		(layer "In2.Cu")
		(net "M_I_CPU1_SA_DQS_DP<5>")
	)
	(gr_poly
		(pts
			(xy 143.890746 -229.429056) (xy 143.853916 -229.292404) (xy 143.815562 -229.270052) (xy 143.715486 -229.44328)
			(xy 143.754094 -229.465632)
		)
		(stroke
			(width 0)
			(type solid)
		)
		(fill yes)
		(layer "In2.Cu")
		(net "M_I_CPU1_SA_DQ<11>")
	)
	(gr_poly
		(pts
			(xy 143.890746 -227.809044) (xy 143.853916 -227.672392) (xy 143.815562 -227.65004) (xy 143.715486 -227.823268)
			(xy 143.754094 -227.84562)
		)
		(stroke
			(width 0)
			(type solid)
		)
		(fill yes)
		(layer "In2.Cu")
		(net "M_I_CPU1_SA_DQ<10>")
	)
	(gr_poly
		(pts
			(xy 143.890746 -226.189032) (xy 143.853916 -226.05238) (xy 143.815562 -226.030028) (xy 143.715486 -226.203256)
			(xy 143.754094 -226.225608)
		)
		(stroke
			(width 0)
			(type solid)
		)
		(fill yes)
		(layer "In2.Cu")
		(net "M_I_CPU1_SA_DQ<7>")
	)
	(gr_poly
		(pts
			(xy 143.890746 -224.56902) (xy 143.853916 -224.432368) (xy 143.815562 -224.410016) (xy 143.715486 -224.583244)
			(xy 143.754094 -224.605596)
		)
		(stroke
			(width 0)
			(type solid)
		)
		(fill yes)
		(layer "In2.Cu")
		(net "M_I_CPU1_SA_DQ<6>")
	)
	(gr_poly
		(pts
			(xy 143.891 -231.048306) (xy 143.854424 -230.911654) (xy 143.813276 -230.888032) (xy 143.7132 -231.06126)
			(xy 143.754602 -231.084882)
		)
		(stroke
			(width 0)
			(type solid)
		)
		(fill yes)
		(layer "In2.Cu")
		(net "M_I_CPU1_SA_DQS_DN<1>")
	)
	(gr_poly
		(pts
			(xy 144.053814 -290.634928) (xy 143.953738 -290.4617) (xy 143.915384 -290.484052) (xy 143.878554 -290.620704)
			(xy 144.015206 -290.65728)
		)
		(stroke
			(width 0)
			(type solid)
		)
		(fill yes)
		(layer "In2.Cu")
		(net "M_I_CPU1_SB_DQ<27>")
	)
	(gr_poly
		(pts
			(xy 144.054576 -295.496488) (xy 143.9545 -295.32326) (xy 143.915892 -295.345358) (xy 143.879316 -295.48201)
			(xy 144.015968 -295.518586)
		)
		(stroke
			(width 0)
			(type solid)
		)
		(fill yes)
		(layer "In2.Cu")
		(net "M_I_CPU1_SB_DQ<30>")
	)
	(gr_poly
		(pts
			(xy 144.056608 -293.87419) (xy 143.956786 -293.700962) (xy 143.915384 -293.724838) (xy 143.878808 -293.861236)
			(xy 144.01546 -293.897812)
		)
		(stroke
			(width 0)
			(type solid)
		)
		(fill yes)
		(layer "In2.Cu")
		(net "M_I_CPU1_SB_DQS_DP<8>")
	)
	(gr_poly
		(pts
			(xy 144.056862 -292.254178) (xy 143.95704 -292.08095) (xy 143.915638 -292.104826) (xy 143.879062 -292.241224)
			(xy 144.015714 -292.2778)
		)
		(stroke
			(width 0)
			(type solid)
		)
		(fill yes)
		(layer "In2.Cu")
		(net "M_I_CPU1_SB_DQS_DN<3>")
	)
	(gr_poly
		(pts
			(xy 144.118838 -286.844232) (xy 144.118838 -286.796734) (xy 143.91894 -286.796734) (xy 143.91894 -286.844232)
			(xy 144.018762 -286.944308)
		)
		(stroke
			(width 0)
			(type solid)
		)
		(fill yes)
		(layer "In2.Cu")
		(net "M_I_CPU1_SB_DQS_DP<7>")
	)
	(gr_poly
		(pts
			(xy 144.118838 -285.22422) (xy 144.118838 -285.17977) (xy 143.918686 -285.17977) (xy 143.918686 -285.22422)
			(xy 144.018762 -285.324296)
		)
		(stroke
			(width 0)
			(type solid)
		)
		(fill yes)
		(layer "In2.Cu")
		(net "M_I_CPU1_SB_DQ<19>")
	)
	(gr_poly
		(pts
			(xy 144.118838 -283.604208) (xy 144.118838 -283.559758) (xy 143.918686 -283.559758) (xy 143.918686 -283.604208)
			(xy 144.018762 -283.704284)
		)
		(stroke
			(width 0)
			(type solid)
		)
		(fill yes)
		(layer "In2.Cu")
		(net "M_I_CPU1_SB_DQ<15>")
	)
	(gr_poly
		(pts
			(xy 144.118838 -281.98445) (xy 144.118838 -281.936952) (xy 143.91894 -281.936952) (xy 143.91894 -281.98445)
			(xy 144.018762 -282.084526)
		)
		(stroke
			(width 0)
			(type solid)
		)
		(fill yes)
		(layer "In2.Cu")
		(net "M_I_CPU1_SB_DQS_DP<6>")
	)
	(gr_poly
		(pts
			(xy 144.118838 -280.364184) (xy 144.118838 -280.319734) (xy 143.918686 -280.319734) (xy 143.918686 -280.364184)
			(xy 144.018762 -280.46426)
		)
		(stroke
			(width 0)
			(type solid)
		)
		(fill yes)
		(layer "In2.Cu")
		(net "M_I_CPU1_SB_DQ<11>")
	)
	(gr_poly
		(pts
			(xy 144.118838 -278.744172) (xy 144.118838 -278.699722) (xy 143.918686 -278.699722) (xy 143.918686 -278.744172)
			(xy 144.018762 -278.844248)
		)
		(stroke
			(width 0)
			(type solid)
		)
		(fill yes)
		(layer "In2.Cu")
		(net "M_I_CPU1_SB_DQ<7>")
	)
	(gr_poly
		(pts
			(xy 144.118838 -277.124414) (xy 144.118838 -277.076916) (xy 143.91894 -277.076916) (xy 143.91894 -277.124414)
			(xy 144.018762 -277.22449)
		)
		(stroke
			(width 0)
			(type solid)
		)
		(fill yes)
		(layer "In2.Cu")
		(net "M_I_CPU1_SB_DQS_DP<5>")
	)
	(gr_poly
		(pts
			(xy 144.118838 -275.504148) (xy 144.118838 -275.459698) (xy 143.918686 -275.459698) (xy 143.918686 -275.504148)
			(xy 144.018762 -275.604224)
		)
		(stroke
			(width 0)
			(type solid)
		)
		(fill yes)
		(layer "In2.Cu")
		(net "M_I_CPU1_SB_DQ<3>")
	)
	(gr_poly
		(pts
			(xy 144.118838 -273.884136) (xy 144.118838 -273.839686) (xy 143.918686 -273.839686) (xy 143.918686 -273.884136)
			(xy 144.018762 -273.984212)
		)
		(stroke
			(width 0)
			(type solid)
		)
		(fill yes)
		(layer "In2.Cu")
		(net "M_I_CPU1_SB_CB<3>")
	)
	(gr_poly
		(pts
			(xy 144.118838 -272.264378) (xy 144.118838 -272.21688) (xy 143.91894 -272.21688) (xy 143.91894 -272.264378)
			(xy 144.018762 -272.364454)
		)
		(stroke
			(width 0)
			(type solid)
		)
		(fill yes)
		(layer "In2.Cu")
		(net "M_I_CPU1_SB_DQS_DP<4>")
	)
	(gr_poly
		(pts
			(xy 144.118838 -267.404088) (xy 144.118838 -267.359638) (xy 143.918686 -267.359638) (xy 143.918686 -267.404088)
			(xy 144.018762 -267.504164)
		)
		(stroke
			(width 0)
			(type solid)
		)
		(fill yes)
		(layer "In2.Cu")
		(net "M_I_CPU1_SB_RSP<0>")
	)
	(gr_poly
		(pts
			(xy 144.118838 -265.784076) (xy 144.118838 -265.739626) (xy 143.918686 -265.739626) (xy 143.918686 -265.784076)
			(xy 144.018762 -265.884152)
		)
		(stroke
			(width 0)
			(type solid)
		)
		(fill yes)
		(layer "In2.Cu")
		(net "M_I_CPU1_SB_CS_N<0>")
	)
	(gr_poly
		(pts
			(xy 144.118838 -264.164064) (xy 144.118838 -264.119614) (xy 143.918686 -264.119614) (xy 143.918686 -264.164064)
			(xy 144.018762 -264.26414)
		)
		(stroke
			(width 0)
			(type solid)
		)
		(fill yes)
		(layer "In2.Cu")
		(net "M_I_CPU1_SB_CA<5>")
	)
	(gr_poly
		(pts
			(xy 144.118838 -262.544052) (xy 144.118838 -262.499602) (xy 143.918686 -262.499602) (xy 143.918686 -262.544052)
			(xy 144.018762 -262.644128)
		)
		(stroke
			(width 0)
			(type solid)
		)
		(fill yes)
		(layer "In2.Cu")
		(net "M_I_CPU1_SB_CA<1>")
	)
	(gr_poly
		(pts
			(xy 144.12849 -270.644366) (xy 144.12849 -270.599916) (xy 143.928592 -270.599916) (xy 143.928592 -270.644366)
			(xy 144.028668 -270.744442)
		)
		(stroke
			(width 0)
			(type solid)
		)
		(fill yes)
		(layer "In2.Cu")
		(net "M_I_CPU1_SB_CB<7>")
	)
	(gr_poly
		(pts
			(xy 144.13484 -285.62808) (xy 144.034764 -285.528258) (xy 143.934688 -285.62808) (xy 143.934688 -285.675832)
			(xy 144.13484 -285.675832)
		)
		(stroke
			(width 0)
			(type solid)
		)
		(fill yes)
		(layer "In2.Cu")
		(net "M_I_CPU1_SB_DQS_DP<2>")
	)
	(gr_poly
		(pts
			(xy 144.13484 -284.008322) (xy 144.034764 -283.908246) (xy 143.934688 -284.008322) (xy 143.934688 -284.052772)
			(xy 144.13484 -284.052772)
		)
		(stroke
			(width 0)
			(type solid)
		)
		(fill yes)
		(layer "In2.Cu")
		(net "M_I_CPU1_SB_DQ<16>")
	)
	(gr_poly
		(pts
			(xy 144.13484 -282.38831) (xy 144.034764 -282.288234) (xy 143.934688 -282.38831) (xy 143.934688 -282.43276)
			(xy 144.13484 -282.43276)
		)
		(stroke
			(width 0)
			(type solid)
		)
		(fill yes)
		(layer "In2.Cu")
		(net "M_I_CPU1_SB_DQ<12>")
	)
	(gr_poly
		(pts
			(xy 144.13484 -279.148286) (xy 144.034764 -279.04821) (xy 143.934688 -279.148286) (xy 143.934688 -279.192736)
			(xy 144.13484 -279.192736)
		)
		(stroke
			(width 0)
			(type solid)
		)
		(fill yes)
		(layer "In2.Cu")
		(net "M_I_CPU1_SB_DQ<8>")
	)
	(gr_poly
		(pts
			(xy 144.13484 -277.528274) (xy 144.034764 -277.428198) (xy 143.934688 -277.528274) (xy 143.934688 -277.572724)
			(xy 144.13484 -277.572724)
		)
		(stroke
			(width 0)
			(type solid)
		)
		(fill yes)
		(layer "In2.Cu")
		(net "M_I_CPU1_SB_DQ<4>")
	)
	(gr_poly
		(pts
			(xy 144.13484 -274.28825) (xy 144.034764 -274.188174) (xy 143.934688 -274.28825) (xy 143.934688 -274.3327)
			(xy 144.13484 -274.3327)
		)
		(stroke
			(width 0)
			(type solid)
		)
		(fill yes)
		(layer "In2.Cu")
		(net "M_I_CPU1_SB_DQ<0>")
	)
	(gr_poly
		(pts
			(xy 144.13484 -272.668238) (xy 144.034764 -272.568162) (xy 143.934688 -272.668238) (xy 143.934688 -272.712688)
			(xy 144.13484 -272.712688)
		)
		(stroke
			(width 0)
			(type solid)
		)
		(fill yes)
		(layer "In2.Cu")
		(net "M_I_CPU1_SB_CB<0>")
	)
	(gr_poly
		(pts
			(xy 144.13484 -271.047972) (xy 144.034764 -270.94815) (xy 143.934688 -271.047972) (xy 143.934688 -271.095724)
			(xy 144.13484 -271.095724)
		)
		(stroke
			(width 0)
			(type solid)
		)
		(fill yes)
		(layer "In2.Cu")
		(net "M_I_CPU1_SB_DQS_DP<9>")
	)
	(gr_poly
		(pts
			(xy 144.13484 -269.428214) (xy 144.034764 -269.328138) (xy 143.934688 -269.428214) (xy 143.934688 -269.472664)
			(xy 144.13484 -269.472664)
		)
		(stroke
			(width 0)
			(type solid)
		)
		(fill yes)
		(layer "In2.Cu")
		(net "M_I_CPU1_SB_CB<4>")
	)
	(gr_poly
		(pts
			(xy 144.13484 -264.568178) (xy 144.034764 -264.468102) (xy 143.934688 -264.568178) (xy 143.934688 -264.612628)
			(xy 144.13484 -264.612628)
		)
		(stroke
			(width 0)
			(type solid)
		)
		(fill yes)
		(layer "In2.Cu")
		(net "M_I_CPU1_SB_CA<6>")
	)
	(gr_poly
		(pts
			(xy 144.143476 -287.247838) (xy 144.0434 -287.148016) (xy 143.943578 -287.247838) (xy 143.943578 -287.292288)
			(xy 144.143476 -287.292288)
		)
		(stroke
			(width 0)
			(type solid)
		)
		(fill yes)
		(layer "In2.Cu")
		(net "M_I_CPU1_SB_DQ<20>")
	)
	(gr_poly
		(pts
			(xy 144.143476 -280.76779) (xy 144.0434 -280.667968) (xy 143.943578 -280.76779) (xy 143.943578 -280.815542)
			(xy 144.143476 -280.815542)
		)
		(stroke
			(width 0)
			(type solid)
		)
		(fill yes)
		(layer "In2.Cu")
		(net "M_I_CPU1_SB_DQS_DP<1>")
	)
	(gr_poly
		(pts
			(xy 144.143476 -275.907754) (xy 144.0434 -275.807932) (xy 143.943578 -275.907754) (xy 143.943578 -275.955506)
			(xy 144.143476 -275.955506)
		)
		(stroke
			(width 0)
			(type solid)
		)
		(fill yes)
		(layer "In2.Cu")
		(net "M_I_CPU1_SB_DQS_DP<0>")
	)
	(gr_poly
		(pts
			(xy 144.143476 -262.947912) (xy 144.0434 -262.847836) (xy 143.943578 -262.947912) (xy 143.943578 -262.992362)
			(xy 144.143476 -262.992362)
		)
		(stroke
			(width 0)
			(type solid)
		)
		(fill yes)
		(layer "In2.Cu")
		(net "M_I_CPU1_SB_CA<2>")
	)
	(gr_poly
		(pts
			(xy 144.15262 -291.7063) (xy 144.18945 -291.569648) (xy 144.052798 -291.533072) (xy 144.011396 -291.556948)
			(xy 144.111472 -291.730176)
		)
		(stroke
			(width 0)
			(type solid)
		)
		(fill yes)
		(layer "In2.Cu")
		(net "M_I_CPU1_SB_DQS_DP<3>")
	)
	(gr_poly
		(pts
			(xy 144.153128 -294.947086) (xy 144.189704 -294.810434) (xy 144.053052 -294.773858) (xy 144.014444 -294.795956)
			(xy 144.11452 -294.969184)
		)
		(stroke
			(width 0)
			(type solid)
		)
		(fill yes)
		(layer "In2.Cu")
		(net "M_I_CPU1_SB_DQ<28>")
	)
	(gr_poly
		(pts
			(xy 144.15389 -293.327582) (xy 144.190466 -293.191184) (xy 144.053814 -293.154608) (xy 144.012666 -293.17823)
			(xy 144.112488 -293.351458)
		)
		(stroke
			(width 0)
			(type solid)
		)
		(fill yes)
		(layer "In2.Cu")
		(net "M_I_CPU1_SB_DQS_DN<8>")
	)
	(gr_poly
		(pts
			(xy 144.15389 -290.08832) (xy 144.190466 -289.951668) (xy 144.054068 -289.915092) (xy 144.01546 -289.937444)
			(xy 144.115536 -290.110672)
		)
		(stroke
			(width 0)
			(type solid)
		)
		(fill yes)
		(layer "In2.Cu")
		(net "M_I_CPU1_SB_DQ<25>")
	)
	(gr_poly
		(pts
			(xy 144.223994 -227.93579) (xy 144.185386 -227.913438) (xy 144.048734 -227.950014) (xy 144.085564 -228.086666)
			(xy 144.123918 -228.109018)
		)
		(stroke
			(width 0)
			(type solid)
		)
		(fill yes)
		(layer "In2.Cu")
		(net "M_I_CPU1_SA_DQ<9>")
	)
	(gr_poly
		(pts
			(xy 144.223994 -226.315778) (xy 144.185386 -226.293426) (xy 144.048734 -226.330002) (xy 144.085564 -226.466654)
			(xy 144.123918 -226.489006)
		)
		(stroke
			(width 0)
			(type solid)
		)
		(fill yes)
		(layer "In2.Cu")
		(net "M_I_CPU1_SA_DQ<8>")
	)
	(gr_poly
		(pts
			(xy 144.223994 -224.695766) (xy 144.185386 -224.673414) (xy 144.048734 -224.70999) (xy 144.085564 -224.846642)
			(xy 144.123918 -224.868994)
		)
		(stroke
			(width 0)
			(type solid)
		)
		(fill yes)
		(layer "In2.Cu")
		(net "M_I_CPU1_SA_DQ<5>")
	)
	(gr_poly
		(pts
			(xy 144.223994 -223.075754) (xy 144.185386 -223.053402) (xy 144.048734 -223.089978) (xy 144.085564 -223.22663)
			(xy 144.123918 -223.248982)
		)
		(stroke
			(width 0)
			(type solid)
		)
		(fill yes)
		(layer "In2.Cu")
		(net "M_I_CPU1_SA_DQ<4>")
	)
	(gr_poly
		(pts
			(xy 144.22628 -231.177592) (xy 144.184878 -231.15397) (xy 144.04848 -231.190546) (xy 144.085056 -231.327198)
			(xy 144.126204 -231.35082)
		)
		(stroke
			(width 0)
			(type solid)
		)
		(fill yes)
		(layer "In2.Cu")
		(net "M_I_CPU1_SA_DQS_DN<6>")
	)
	(gr_poly
		(pts
			(xy 144.22628 -229.55758) (xy 144.184878 -229.533958) (xy 144.04848 -229.570534) (xy 144.085056 -229.707186)
			(xy 144.126204 -229.730808)
		)
		(stroke
			(width 0)
			(type solid)
		)
		(fill yes)
		(layer "In2.Cu")
		(net "M_I_CPU1_SA_DQS_DP<1>")
	)
	(gr_poly
		(pts
			(xy 144.296892 -255.622806) (xy 144.296892 -255.578356) (xy 144.096994 -255.578356) (xy 144.096994 -255.622806)
			(xy 144.19707 -255.722628)
		)
		(stroke
			(width 0)
			(type solid)
		)
		(fill yes)
		(layer "In2.Cu")
		(net "M_I_CPU1_SA_PAR")
	)
	(gr_poly
		(pts
			(xy 144.296892 -249.142758) (xy 144.296892 -249.098308) (xy 144.096994 -249.098308) (xy 144.096994 -249.142758)
			(xy 144.19707 -249.242834)
		)
		(stroke
			(width 0)
			(type solid)
		)
		(fill yes)
		(layer "In2.Cu")
		(net "M_I_CPU1_SA_CB<7>")
	)
	(gr_poly
		(pts
			(xy 144.296892 -247.523) (xy 144.296892 -247.475248) (xy 144.096994 -247.475248) (xy 144.096994 -247.523)
			(xy 144.19707 -247.622822)
		)
		(stroke
			(width 0)
			(type solid)
		)
		(fill yes)
		(layer "In2.Cu")
		(net "M_I_CPU1_SA_DQS_DP<9>")
	)
	(gr_poly
		(pts
			(xy 144.299178 -242.66271) (xy 144.299178 -242.615212) (xy 144.09928 -242.615212) (xy 144.09928 -242.66271)
			(xy 144.199356 -242.762786)
		)
		(stroke
			(width 0)
			(type solid)
		)
		(fill yes)
		(layer "In2.Cu")
		(net "M_I_CPU1_SA_DQS_DP<8>")
	)
	(gr_poly
		(pts
			(xy 144.304766 -250.762516) (xy 144.304766 -250.718066) (xy 144.104614 -250.718066) (xy 144.104614 -250.762516)
			(xy 144.20469 -250.862592)
		)
		(stroke
			(width 0)
			(type solid)
		)
		(fill yes)
		(layer "In2.Cu")
		(net "M_I_CPU1_RESET_N")
	)
	(gr_poly
		(pts
			(xy 144.30502 -254.00254) (xy 144.30502 -253.95809) (xy 144.104868 -253.95809) (xy 144.104868 -254.00254)
			(xy 144.204944 -254.102616)
		)
		(stroke
			(width 0)
			(type solid)
		)
		(fill yes)
		(layer "In2.Cu")
		(net "M_I_CPU1_SA_CA<3>")
	)
	(gr_poly
		(pts
			(xy 144.30502 -245.90248) (xy 144.30502 -245.85803) (xy 144.104868 -245.85803) (xy 144.104868 -245.90248)
			(xy 144.204944 -246.002556)
		)
		(stroke
			(width 0)
			(type solid)
		)
		(fill yes)
		(layer "In2.Cu")
		(net "M_I_CPU1_SA_CB<3>")
	)
	(gr_poly
		(pts
			(xy 144.30502 -244.282468) (xy 144.30502 -244.238018) (xy 144.104868 -244.238018) (xy 144.104868 -244.282468)
			(xy 144.204944 -244.382544)
		)
		(stroke
			(width 0)
			(type solid)
		)
		(fill yes)
		(layer "In2.Cu")
		(net "M_I_CPU1_SA_DQ<31>")
	)
	(gr_poly
		(pts
			(xy 144.310608 -243.066316) (xy 144.210532 -242.96624) (xy 144.11071 -243.066316) (xy 144.11071 -243.110766)
			(xy 144.310608 -243.110766)
		)
		(stroke
			(width 0)
			(type solid)
		)
		(fill yes)
		(layer "In2.Cu")
		(net "M_I_CPU1_SA_DQ<28>")
	)
	(gr_poly
		(pts
			(xy 144.310608 -241.44605) (xy 144.210532 -241.346228) (xy 144.11071 -241.44605) (xy 144.11071 -241.493802)
			(xy 144.310608 -241.493802)
		)
		(stroke
			(width 0)
			(type solid)
		)
		(fill yes)
		(layer "In2.Cu")
		(net "M_I_CPU1_SA_DQS_DP<3>")
	)
	(gr_poly
		(pts
			(xy 144.310608 -241.042444) (xy 144.310608 -240.997994) (xy 144.11071 -240.997994) (xy 144.11071 -241.042444)
			(xy 144.210532 -241.14252)
		)
		(stroke
			(width 0)
			(type solid)
		)
		(fill yes)
		(layer "In2.Cu")
		(net "M_I_CPU1_SA_DQ<27>")
	)
	(gr_poly
		(pts
			(xy 144.310608 -239.826292) (xy 144.210532 -239.726216) (xy 144.11071 -239.826292) (xy 144.11071 -239.870742)
			(xy 144.310608 -239.870742)
		)
		(stroke
			(width 0)
			(type solid)
		)
		(fill yes)
		(layer "In2.Cu")
		(net "M_I_CPU1_SA_DQ<24>")
	)
	(gr_poly
		(pts
			(xy 144.316196 -254.4064) (xy 144.216374 -254.306578) (xy 144.116298 -254.4064) (xy 144.116298 -254.451104)
			(xy 144.316196 -254.451104)
		)
		(stroke
			(width 0)
			(type solid)
		)
		(fill yes)
		(layer "In2.Cu")
		(net "M_I_CPU1_SA_CA<4>")
	)
	(gr_poly
		(pts
			(xy 144.316196 -252.786388) (xy 144.216374 -252.686566) (xy 144.116298 -252.786388) (xy 144.116298 -252.830838)
			(xy 144.316196 -252.830838)
		)
		(stroke
			(width 0)
			(type solid)
		)
		(fill yes)
		(layer "In2.Cu")
		(net "M_I_CPU1_SA_CA<0>")
	)
	(gr_poly
		(pts
			(xy 144.316196 -251.166376) (xy 144.216374 -251.066554) (xy 144.116298 -251.166376) (xy 144.116298 -251.21108)
			(xy 144.316196 -251.21108)
		)
		(stroke
			(width 0)
			(type solid)
		)
		(fill yes)
		(layer "In2.Cu")
		(net "M_I_CPU1_SA_CS_N<0>")
	)
	(gr_poly
		(pts
			(xy 144.316196 -247.926352) (xy 144.216374 -247.82653) (xy 144.116298 -247.926352) (xy 144.116298 -247.970802)
			(xy 144.316196 -247.970802)
		)
		(stroke
			(width 0)
			(type solid)
		)
		(fill yes)
		(layer "In2.Cu")
		(net "M_I_CPU1_SA_CB<4>")
	)
	(gr_poly
		(pts
			(xy 144.316196 -244.686328) (xy 144.216374 -244.586506) (xy 144.116298 -244.686328) (xy 144.116298 -244.731032)
			(xy 144.316196 -244.731032)
		)
		(stroke
			(width 0)
			(type solid)
		)
		(fill yes)
		(layer "In2.Cu")
		(net "M_I_CPU1_SA_CB<0>")
	)
	(gr_poly
		(pts
			(xy 144.359884 -230.24084) (xy 144.323308 -230.104188) (xy 144.28216 -230.080312) (xy 144.182084 -230.25354)
			(xy 144.223232 -230.277416)
		)
		(stroke
			(width 0)
			(type solid)
		)
		(fill yes)
		(layer "In2.Cu")
		(net "M_I_CPU1_SA_DQS_DN<1>")
	)
	(gr_poly
		(pts
			(xy 144.360646 -231.859328) (xy 144.32407 -231.72293) (xy 144.282668 -231.699054) (xy 144.182846 -231.872282)
			(xy 144.223994 -231.895904)
		)
		(stroke
			(width 0)
			(type solid)
		)
		(fill yes)
		(layer "In2.Cu")
		(net "M_I_CPU1_SA_DQS_DP<6>")
	)
	(gr_poly
		(pts
			(xy 144.360646 -228.61905) (xy 144.32407 -228.482398) (xy 144.285716 -228.460046) (xy 144.18564 -228.633274)
			(xy 144.224248 -228.655626)
		)
		(stroke
			(width 0)
			(type solid)
		)
		(fill yes)
		(layer "In2.Cu")
		(net "M_I_CPU1_SA_DQ<11>")
	)
	(gr_poly
		(pts
			(xy 144.360646 -226.999038) (xy 144.32407 -226.862386) (xy 144.285716 -226.840034) (xy 144.18564 -227.013262)
			(xy 144.224248 -227.035614)
		)
		(stroke
			(width 0)
			(type solid)
		)
		(fill yes)
		(layer "In2.Cu")
		(net "M_I_CPU1_SA_DQ<10>")
	)
	(gr_poly
		(pts
			(xy 144.360646 -225.379026) (xy 144.32407 -225.242374) (xy 144.285716 -225.220022) (xy 144.18564 -225.39325)
			(xy 144.224248 -225.415602)
		)
		(stroke
			(width 0)
			(type solid)
		)
		(fill yes)
		(layer "In2.Cu")
		(net "M_I_CPU1_SA_DQ<7>")
	)
	(gr_poly
		(pts
			(xy 144.360646 -223.759014) (xy 144.32407 -223.622362) (xy 144.285716 -223.60001) (xy 144.18564 -223.773238)
			(xy 144.224248 -223.79559)
		)
		(stroke
			(width 0)
			(type solid)
		)
		(fill yes)
		(layer "In2.Cu")
		(net "M_I_CPU1_SA_DQ<6>")
	)
	(gr_poly
		(pts
			(xy 144.361408 -222.137732) (xy 144.324832 -222.00108) (xy 144.28343 -221.977204) (xy 144.183608 -222.150432)
			(xy 144.224756 -222.174308)
		)
		(stroke
			(width 0)
			(type solid)
		)
		(fill yes)
		(layer "In2.Cu")
		(net "M_I_CPU1_SA_DQS_DP<5>")
	)
	(gr_poly
		(pts
			(xy 144.527524 -294.685466) (xy 144.427448 -294.512238) (xy 144.3863 -294.536114) (xy 144.34947 -294.672512)
			(xy 144.486122 -294.709342)
		)
		(stroke
			(width 0)
			(type solid)
		)
		(fill yes)
		(layer "In2.Cu")
		(net "M_I_CPU1_SB_DQS_DP<8>")
	)
	(gr_poly
		(pts
			(xy 144.595342 -270.23822) (xy 144.495266 -270.138398) (xy 144.39519 -270.23822) (xy 144.39519 -270.282924)
			(xy 144.595342 -270.282924)
		)
		(stroke
			(width 0)
			(type solid)
		)
		(fill yes)
		(layer "In2.Cu")
		(net "M_I_CPU1_SB_CB<5>")
	)
	(gr_poly
		(pts
			(xy 144.596866 -281.174952) (xy 144.596866 -281.1272) (xy 144.396968 -281.1272) (xy 144.396968 -281.174952)
			(xy 144.497044 -281.274774)
		)
		(stroke
			(width 0)
			(type solid)
		)
		(fill yes)
		(layer "In2.Cu")
		(net "M_I_CPU1_SB_DQS_DN<1>")
	)
	(gr_poly
		(pts
			(xy 144.596866 -276.314916) (xy 144.596866 -276.267164) (xy 144.396968 -276.267164) (xy 144.396968 -276.314916)
			(xy 144.497044 -276.414738)
		)
		(stroke
			(width 0)
			(type solid)
		)
		(fill yes)
		(layer "In2.Cu")
		(net "M_I_CPU1_SB_DQS_DN<0>")
	)
	(gr_poly
		(pts
			(xy 144.596866 -263.354566) (xy 144.596866 -263.310116) (xy 144.396968 -263.310116) (xy 144.396968 -263.354566)
			(xy 144.497044 -263.454388)
		)
		(stroke
			(width 0)
			(type solid)
		)
		(fill yes)
		(layer "In2.Cu")
		(net "M_I_CPU1_SB_CA<3>")
	)
	(gr_poly
		(pts
			(xy 144.59839 -269.83436) (xy 144.59839 -269.78991) (xy 144.398492 -269.78991) (xy 144.398492 -269.83436)
			(xy 144.498568 -269.934436)
		)
		(stroke
			(width 0)
			(type solid)
		)
		(fill yes)
		(layer "In2.Cu")
		(net "M_I_CPU1_SB_CB<6>")
	)
	(gr_poly
		(pts
			(xy 144.60474 -286.034734) (xy 144.60474 -285.986982) (xy 144.404588 -285.986982) (xy 144.404588 -286.034734)
			(xy 144.504664 -286.134556)
		)
		(stroke
			(width 0)
			(type solid)
		)
		(fill yes)
		(layer "In2.Cu")
		(net "M_I_CPU1_SB_DQS_DN<2>")
	)
	(gr_poly
		(pts
			(xy 144.604994 -271.454626) (xy 144.604994 -271.406874) (xy 144.404842 -271.406874) (xy 144.404842 -271.454626)
			(xy 144.504918 -271.554448)
		)
		(stroke
			(width 0)
			(type solid)
		)
		(fill yes)
		(layer "In2.Cu")
		(net "M_I_CPU1_SB_DQS_DN<9>")
	)
	(gr_poly
		(pts
			(xy 144.613376 -284.414722) (xy 144.613376 -284.370272) (xy 144.413478 -284.370272) (xy 144.413478 -284.414722)
			(xy 144.5133 -284.514544)
		)
		(stroke
			(width 0)
			(type solid)
		)
		(fill yes)
		(layer "In2.Cu")
		(net "M_I_CPU1_SB_DQ<18>")
	)
	(gr_poly
		(pts
			(xy 144.613376 -282.79471) (xy 144.613376 -282.75026) (xy 144.413478 -282.75026) (xy 144.413478 -282.79471)
			(xy 144.5133 -282.894532)
		)
		(stroke
			(width 0)
			(type solid)
		)
		(fill yes)
		(layer "In2.Cu")
		(net "M_I_CPU1_SB_DQ<14>")
	)
	(gr_poly
		(pts
			(xy 144.613376 -279.554686) (xy 144.613376 -279.510236) (xy 144.413478 -279.510236) (xy 144.413478 -279.554686)
			(xy 144.5133 -279.654508)
		)
		(stroke
			(width 0)
			(type solid)
		)
		(fill yes)
		(layer "In2.Cu")
		(net "M_I_CPU1_SB_DQ<10>")
	)
	(gr_poly
		(pts
			(xy 144.613376 -277.934674) (xy 144.613376 -277.890224) (xy 144.413478 -277.890224) (xy 144.413478 -277.934674)
			(xy 144.5133 -278.034496)
		)
		(stroke
			(width 0)
			(type solid)
		)
		(fill yes)
		(layer "In2.Cu")
		(net "M_I_CPU1_SB_DQ<6>")
	)
	(gr_poly
		(pts
			(xy 144.613376 -274.69465) (xy 144.613376 -274.6502) (xy 144.413478 -274.6502) (xy 144.413478 -274.69465)
			(xy 144.5133 -274.794472)
		)
		(stroke
			(width 0)
			(type solid)
		)
		(fill yes)
		(layer "In2.Cu")
		(net "M_I_CPU1_SB_DQ<2>")
	)
	(gr_poly
		(pts
			(xy 144.613376 -273.074638) (xy 144.613376 -273.030188) (xy 144.413478 -273.030188) (xy 144.413478 -273.074638)
			(xy 144.5133 -273.17446)
		)
		(stroke
			(width 0)
			(type solid)
		)
		(fill yes)
		(layer "In2.Cu")
		(net "M_I_CPU1_SB_CB<2>")
	)
	(gr_poly
		(pts
			(xy 144.613376 -266.59459) (xy 144.613376 -266.55014) (xy 144.413478 -266.55014) (xy 144.413478 -266.59459)
			(xy 144.5133 -266.694412)
		)
		(stroke
			(width 0)
			(type solid)
		)
		(fill yes)
		(layer "In2.Cu")
		(net "M_I_CPU1_SB_CS_N<1>")
	)
	(gr_poly
		(pts
			(xy 144.617186 -281.578304) (xy 144.517364 -281.478228) (xy 144.417288 -281.578304) (xy 144.417288 -281.626056)
			(xy 144.617186 -281.626056)
		)
		(stroke
			(width 0)
			(type solid)
		)
		(fill yes)
		(layer "In2.Cu")
		(net "M_I_CPU1_SB_DQS_DN<6>")
	)
	(gr_poly
		(pts
			(xy 144.617186 -276.718268) (xy 144.517364 -276.618192) (xy 144.417288 -276.718268) (xy 144.417288 -276.76602)
			(xy 144.617186 -276.76602)
		)
		(stroke
			(width 0)
			(type solid)
		)
		(fill yes)
		(layer "In2.Cu")
		(net "M_I_CPU1_SB_DQS_DN<5>")
	)
	(gr_poly
		(pts
			(xy 144.617186 -271.858232) (xy 144.517364 -271.758156) (xy 144.417288 -271.858232) (xy 144.417288 -271.905984)
			(xy 144.617186 -271.905984)
		)
		(stroke
			(width 0)
			(type solid)
		)
		(fill yes)
		(layer "In2.Cu")
		(net "M_I_CPU1_SB_DQS_DN<4>")
	)
	(gr_poly
		(pts
			(xy 144.61744 -284.818582) (xy 144.517364 -284.718506) (xy 144.417288 -284.818582) (xy 144.417288 -284.863032)
			(xy 144.61744 -284.863032)
		)
		(stroke
			(width 0)
			(type solid)
		)
		(fill yes)
		(layer "In2.Cu")
		(net "M_I_CPU1_SB_DQ<17>")
	)
	(gr_poly
		(pts
			(xy 144.61744 -283.19857) (xy 144.517364 -283.098494) (xy 144.417288 -283.19857) (xy 144.417288 -283.24302)
			(xy 144.61744 -283.24302)
		)
		(stroke
			(width 0)
			(type solid)
		)
		(fill yes)
		(layer "In2.Cu")
		(net "M_I_CPU1_SB_DQ<13>")
	)
	(gr_poly
		(pts
			(xy 144.61744 -279.958546) (xy 144.517364 -279.85847) (xy 144.417288 -279.958546) (xy 144.417288 -280.002996)
			(xy 144.61744 -280.002996)
		)
		(stroke
			(width 0)
			(type solid)
		)
		(fill yes)
		(layer "In2.Cu")
		(net "M_I_CPU1_SB_DQ<9>")
	)
	(gr_poly
		(pts
			(xy 144.61744 -278.338534) (xy 144.517364 -278.238458) (xy 144.417288 -278.338534) (xy 144.417288 -278.382984)
			(xy 144.61744 -278.382984)
		)
		(stroke
			(width 0)
			(type solid)
		)
		(fill yes)
		(layer "In2.Cu")
		(net "M_I_CPU1_SB_DQ<5>")
	)
	(gr_poly
		(pts
			(xy 144.61744 -275.09851) (xy 144.517364 -274.998434) (xy 144.417288 -275.09851) (xy 144.417288 -275.14296)
			(xy 144.61744 -275.14296)
		)
		(stroke
			(width 0)
			(type solid)
		)
		(fill yes)
		(layer "In2.Cu")
		(net "M_I_CPU1_SB_DQ<1>")
	)
	(gr_poly
		(pts
			(xy 144.61744 -273.478498) (xy 144.517364 -273.378422) (xy 144.417288 -273.478498) (xy 144.417288 -273.522948)
			(xy 144.61744 -273.522948)
		)
		(stroke
			(width 0)
			(type solid)
		)
		(fill yes)
		(layer "In2.Cu")
		(net "M_I_CPU1_SB_CB<1>")
	)
	(gr_poly
		(pts
			(xy 144.61744 -266.99845) (xy 144.517364 -266.898374) (xy 144.417288 -266.99845) (xy 144.417288 -267.0429)
			(xy 144.61744 -267.0429)
		)
		(stroke
			(width 0)
			(type solid)
		)
		(fill yes)
		(layer "In2.Cu")
		(net "M_I_CPU1_SA_RSP<0>")
	)
	(gr_poly
		(pts
			(xy 144.61744 -265.378438) (xy 144.517364 -265.278362) (xy 144.417288 -265.378438) (xy 144.417288 -265.422888)
			(xy 144.61744 -265.422888)
		)
		(stroke
			(width 0)
			(type solid)
		)
		(fill yes)
		(layer "In2.Cu")
		(net "M_I_CPU1_SB_PAR")
	)
	(gr_poly
		(pts
			(xy 144.61744 -263.758426) (xy 144.517364 -263.65835) (xy 144.417288 -263.758426) (xy 144.417288 -263.802876)
			(xy 144.61744 -263.802876)
		)
		(stroke
			(width 0)
			(type solid)
		)
		(fill yes)
		(layer "In2.Cu")
		(net "M_I_CPU1_SB_CA<4>")
	)
	(gr_poly
		(pts
			(xy 144.61744 -262.138414) (xy 144.517364 -262.038338) (xy 144.417288 -262.138414) (xy 144.417288 -262.182864)
			(xy 144.61744 -262.182864)
		)
		(stroke
			(width 0)
			(type solid)
		)
		(fill yes)
		(layer "In2.Cu")
		(net "M_I_CPU1_SB_CA<0>")
	)
	(gr_poly
		(pts
			(xy 144.61871 -295.767252) (xy 144.66697 -295.634156) (xy 144.534128 -295.585896) (xy 144.493742 -295.604692)
			(xy 144.578324 -295.785794)
		)
		(stroke
			(width 0)
			(type solid)
		)
		(fill yes)
		(layer "In2.Cu")
		(net "M_I_CPU1_SB_DQ<28>")
	)
	(gr_poly
		(pts
			(xy 144.62252 -294.136318) (xy 144.65935 -293.99992) (xy 144.522698 -293.96309) (xy 144.481296 -293.986966)
			(xy 144.581372 -294.160194)
		)
		(stroke
			(width 0)
			(type solid)
		)
		(fill yes)
		(layer "In2.Cu")
		(net "M_I_CPU1_SB_DQS_DN<8>")
	)
	(gr_poly
		(pts
			(xy 144.624044 -292.517576) (xy 144.66062 -292.381178) (xy 144.523968 -292.344348) (xy 144.48282 -292.368224)
			(xy 144.582642 -292.541452)
		)
		(stroke
			(width 0)
			(type solid)
		)
		(fill yes)
		(layer "In2.Cu")
		(net "M_I_CPU1_SB_DQS_DP<3>")
	)
	(gr_poly
		(pts
			(xy 144.624044 -290.898326) (xy 144.660874 -290.761674) (xy 144.524222 -290.725098) (xy 144.485614 -290.74745)
			(xy 144.58569 -290.920678)
		)
		(stroke
			(width 0)
			(type solid)
		)
		(fill yes)
		(layer "In2.Cu")
		(net "M_I_CPU1_SB_DQ<25>")
	)
	(gr_poly
		(pts
			(xy 144.693894 -227.125784) (xy 144.655286 -227.103432) (xy 144.518634 -227.140008) (xy 144.555464 -227.27666)
			(xy 144.593818 -227.299012)
		)
		(stroke
			(width 0)
			(type solid)
		)
		(fill yes)
		(layer "In2.Cu")
		(net "M_I_CPU1_SA_DQ<9>")
	)
	(gr_poly
		(pts
			(xy 144.693894 -225.505772) (xy 144.655286 -225.48342) (xy 144.518634 -225.519996) (xy 144.555464 -225.656648)
			(xy 144.593818 -225.679)
		)
		(stroke
			(width 0)
			(type solid)
		)
		(fill yes)
		(layer "In2.Cu")
		(net "M_I_CPU1_SA_DQ<8>")
	)
	(gr_poly
		(pts
			(xy 144.693894 -223.88576) (xy 144.655286 -223.863408) (xy 144.518634 -223.899984) (xy 144.555464 -224.036636)
			(xy 144.593818 -224.058988)
		)
		(stroke
			(width 0)
			(type solid)
		)
		(fill yes)
		(layer "In2.Cu")
		(net "M_I_CPU1_SA_DQ<5>")
	)
	(gr_poly
		(pts
			(xy 144.695164 -222.2627) (xy 144.65681 -222.240602) (xy 144.520158 -222.277178) (xy 144.556734 -222.41383)
			(xy 144.595088 -222.435928)
		)
		(stroke
			(width 0)
			(type solid)
		)
		(fill yes)
		(layer "In2.Cu")
		(net "M_I_CPU1_SA_DQ<4>")
	)
	(gr_poly
		(pts
			(xy 144.696688 -228.746558) (xy 144.65554 -228.722936) (xy 144.518888 -228.759512) (xy 144.555464 -228.89591)
			(xy 144.596866 -228.919786)
		)
		(stroke
			(width 0)
			(type solid)
		)
		(fill yes)
		(layer "In2.Cu")
		(net "M_I_CPU1_SA_DQS_DP<1>")
	)
	(gr_poly
		(pts
			(xy 144.69745 -230.3653) (xy 144.656302 -230.341424) (xy 144.51965 -230.378) (xy 144.556226 -230.514652)
			(xy 144.597374 -230.538528)
		)
		(stroke
			(width 0)
			(type solid)
		)
		(fill yes)
		(layer "In2.Cu")
		(net "M_I_CPU1_SA_DQS_DN<6>")
	)
	(gr_poly
		(pts
			(xy 144.766792 -247.116092) (xy 144.66697 -247.01627) (xy 144.566894 -247.116092) (xy 144.566894 -247.163844)
			(xy 144.766792 -247.163844)
		)
		(stroke
			(width 0)
			(type solid)
		)
		(fill yes)
		(layer "In2.Cu")
		(net "M_I_CPU1_SA_DQS_DN<9>")
	)
	(gr_poly
		(pts
			(xy 144.766792 -242.256056) (xy 144.66697 -242.156234) (xy 144.566894 -242.256056) (xy 144.566894 -242.303808)
			(xy 144.766792 -242.303808)
		)
		(stroke
			(width 0)
			(type solid)
		)
		(fill yes)
		(layer "In2.Cu")
		(net "M_I_CPU1_SA_DQS_DN<8>")
	)
	(gr_poly
		(pts
			(xy 144.772126 -255.216406) (xy 144.67205 -255.11633) (xy 144.571974 -255.216406) (xy 144.571974 -255.260856)
			(xy 144.772126 -255.260856)
		)
		(stroke
			(width 0)
			(type solid)
		)
		(fill yes)
		(layer "In2.Cu")
		(net "M_I_CPU1_SA_CA<6>")
	)
	(gr_poly
		(pts
			(xy 144.772126 -251.976382) (xy 144.67205 -251.876306) (xy 144.571974 -251.976382) (xy 144.571974 -252.020832)
			(xy 144.772126 -252.020832)
		)
		(stroke
			(width 0)
			(type solid)
		)
		(fill yes)
		(layer "In2.Cu")
		(net "M_I_CPU1_SA_CS_N<1>")
	)
	(gr_poly
		(pts
			(xy 144.772126 -248.736358) (xy 144.67205 -248.636282) (xy 144.571974 -248.736358) (xy 144.571974 -248.780808)
			(xy 144.772126 -248.780808)
		)
		(stroke
			(width 0)
			(type solid)
		)
		(fill yes)
		(layer "In2.Cu")
		(net "M_I_CPU1_SA_CB<5>")
	)
	(gr_poly
		(pts
			(xy 144.77492 -253.596394) (xy 144.674844 -253.496318) (xy 144.574768 -253.596394) (xy 144.574768 -253.640844)
			(xy 144.77492 -253.640844)
		)
		(stroke
			(width 0)
			(type solid)
		)
		(fill yes)
		(layer "In2.Cu")
		(net "M_I_CPU1_SA_CA<2>")
	)
	(gr_poly
		(pts
			(xy 144.77492 -250.35637) (xy 144.674844 -250.256294) (xy 144.574768 -250.35637) (xy 144.574768 -250.40082)
			(xy 144.77492 -250.40082)
		)
		(stroke
			(width 0)
			(type solid)
		)
		(fill yes)
		(layer "In2.Cu")
		(net "M_I_CPU1_ALERT_R_N")
	)
	(gr_poly
		(pts
			(xy 144.77492 -245.496334) (xy 144.674844 -245.396258) (xy 144.574768 -245.496334) (xy 144.574768 -245.540784)
			(xy 144.77492 -245.540784)
		)
		(stroke
			(width 0)
			(type solid)
		)
		(fill yes)
		(layer "In2.Cu")
		(net "M_I_CPU1_SA_CB<1>")
	)
	(gr_poly
		(pts
			(xy 144.77492 -243.876322) (xy 144.674844 -243.776246) (xy 144.574768 -243.876322) (xy 144.574768 -243.920772)
			(xy 144.77492 -243.920772)
		)
		(stroke
			(width 0)
			(type solid)
		)
		(fill yes)
		(layer "In2.Cu")
		(net "M_I_CPU1_SA_DQ<29>")
	)
	(gr_poly
		(pts
			(xy 144.780508 -243.472462) (xy 144.780508 -243.428012) (xy 144.58061 -243.428012) (xy 144.58061 -243.472462)
			(xy 144.680432 -243.572538)
		)
		(stroke
			(width 0)
			(type solid)
		)
		(fill yes)
		(layer "In2.Cu")
		(net "M_I_CPU1_SA_DQ<30>")
	)
	(gr_poly
		(pts
			(xy 144.780508 -241.852704) (xy 144.780508 -241.805206) (xy 144.58061 -241.805206) (xy 144.58061 -241.852704)
			(xy 144.680432 -241.95278)
		)
		(stroke
			(width 0)
			(type solid)
		)
		(fill yes)
		(layer "In2.Cu")
		(net "M_I_CPU1_SA_DQS_DN<3>")
	)
	(gr_poly
		(pts
			(xy 144.780508 -240.636298) (xy 144.680432 -240.536222) (xy 144.58061 -240.636298) (xy 144.58061 -240.680748)
			(xy 144.780508 -240.680748)
		)
		(stroke
			(width 0)
			(type solid)
		)
		(fill yes)
		(layer "In2.Cu")
		(net "M_I_CPU1_SA_DQ<25>")
	)
	(gr_poly
		(pts
			(xy 144.780508 -240.232438) (xy 144.780508 -240.187988) (xy 144.58061 -240.187988) (xy 144.58061 -240.232438)
			(xy 144.680432 -240.332514)
		)
		(stroke
			(width 0)
			(type solid)
		)
		(fill yes)
		(layer "In2.Cu")
		(net "M_I_CPU1_SA_DQ<26>")
	)
	(gr_poly
		(pts
			(xy 144.786096 -246.713248) (xy 144.786096 -246.665496) (xy 144.586198 -246.665496) (xy 144.586198 -246.713248)
			(xy 144.686274 -246.813324)
		)
		(stroke
			(width 0)
			(type solid)
		)
		(fill yes)
		(layer "In2.Cu")
		(net "M_I_CPU1_SA_DQS_DN<4>")
	)
	(gr_poly
		(pts
			(xy 144.788382 -254.813054) (xy 144.788382 -254.768604) (xy 144.58823 -254.768604) (xy 144.58823 -254.813054)
			(xy 144.688306 -254.91313)
		)
		(stroke
			(width 0)
			(type solid)
		)
		(fill yes)
		(layer "In2.Cu")
		(net "M_I_CPU1_SA_CA<5>")
	)
	(gr_poly
		(pts
			(xy 144.788382 -253.193042) (xy 144.788382 -253.148592) (xy 144.58823 -253.148592) (xy 144.58823 -253.193042)
			(xy 144.688306 -253.293118)
		)
		(stroke
			(width 0)
			(type solid)
		)
		(fill yes)
		(layer "In2.Cu")
		(net "M_I_CPU1_SA_CA<1>")
	)
	(gr_poly
		(pts
			(xy 144.788382 -248.333006) (xy 144.788382 -248.288556) (xy 144.58823 -248.288556) (xy 144.58823 -248.333006)
			(xy 144.688306 -248.433082)
		)
		(stroke
			(width 0)
			(type solid)
		)
		(fill yes)
		(layer "In2.Cu")
		(net "M_I_CPU1_SA_CB<6>")
	)
	(gr_poly
		(pts
			(xy 144.788382 -245.092982) (xy 144.788382 -245.048532) (xy 144.58823 -245.048532) (xy 144.58823 -245.092982)
			(xy 144.688306 -245.193058)
		)
		(stroke
			(width 0)
			(type solid)
		)
		(fill yes)
		(layer "In2.Cu")
		(net "M_I_CPU1_SA_CB<2>")
	)
	(gr_poly
		(pts
			(xy 144.7927 -256.433066) (xy 144.7927 -256.385568) (xy 144.592802 -256.385568) (xy 144.592802 -256.433066)
			(xy 144.692624 -256.533142)
		)
		(stroke
			(width 0)
			(type solid)
		)
		(fill yes)
		(layer "In2.Cu")
		(net "M_I_CPU1_CLK_DN<0>")
	)
	(gr_poly
		(pts
			(xy 144.828768 -222.951802) (xy 144.791938 -222.81515) (xy 144.753584 -222.792798) (xy 144.653508 -222.966026)
			(xy 144.692116 -222.988378)
		)
		(stroke
			(width 0)
			(type solid)
		)
		(fill yes)
		(layer "In2.Cu")
		(net "M_I_CPU1_SA_DQ<6>")
	)
	(gr_poly
		(pts
			(xy 144.830546 -227.809044) (xy 144.79397 -227.672392) (xy 144.755616 -227.65004) (xy 144.65554 -227.823268)
			(xy 144.694148 -227.84562)
		)
		(stroke
			(width 0)
			(type solid)
		)
		(fill yes)
		(layer "In2.Cu")
		(net "M_I_CPU1_SA_DQ<11>")
	)
	(gr_poly
		(pts
			(xy 144.830546 -226.189032) (xy 144.79397 -226.05238) (xy 144.755616 -226.030028) (xy 144.65554 -226.203256)
			(xy 144.694148 -226.225608)
		)
		(stroke
			(width 0)
			(type solid)
		)
		(fill yes)
		(layer "In2.Cu")
		(net "M_I_CPU1_SA_DQ<10>")
	)
	(gr_poly
		(pts
			(xy 144.830546 -224.56902) (xy 144.79397 -224.432368) (xy 144.755616 -224.410016) (xy 144.65554 -224.583244)
			(xy 144.694148 -224.605596)
		)
		(stroke
			(width 0)
			(type solid)
		)
		(fill yes)
		(layer "In2.Cu")
		(net "M_I_CPU1_SA_DQ<7>")
	)
	(gr_poly
		(pts
			(xy 144.831054 -231.048306) (xy 144.794478 -230.911654) (xy 144.75333 -230.888032) (xy 144.653254 -231.06126)
			(xy 144.694402 -231.084882)
		)
		(stroke
			(width 0)
			(type solid)
		)
		(fill yes)
		(layer "In2.Cu")
		(net "M_I_CPU1_SA_DQS_DP<6>")
	)
	(gr_poly
		(pts
			(xy 144.831054 -229.428294) (xy 144.794478 -229.291642) (xy 144.75333 -229.26802) (xy 144.653254 -229.441248)
			(xy 144.694402 -229.46487)
		)
		(stroke
			(width 0)
			(type solid)
		)
		(fill yes)
		(layer "In2.Cu")
		(net "M_I_CPU1_SA_DQS_DN<1>")
	)
	(gr_poly
		(pts
			(xy 144.993868 -268.877542) (xy 144.95526 -268.85519) (xy 144.818862 -268.891766) (xy 144.855438 -269.028418)
			(xy 144.893792 -269.05077)
		)
		(stroke
			(width 0)
			(type solid)
		)
		(fill yes)
		(layer "In2.Cu")
		(net "M_I_CPU1_SB_CB<4>")
	)
	(gr_poly
		(pts
			(xy 144.996662 -295.494202) (xy 144.89684 -295.320974) (xy 144.855438 -295.34485) (xy 144.818862 -295.481248)
			(xy 144.955514 -295.517824)
		)
		(stroke
			(width 0)
			(type solid)
		)
		(fill yes)
		(layer "In2.Cu")
		(net "M_I_CPU1_SB_DQS_DP<8>")
	)
	(gr_poly
		(pts
			(xy 144.996662 -293.87419) (xy 144.89684 -293.700962) (xy 144.855438 -293.724838) (xy 144.818862 -293.861236)
			(xy 144.955514 -293.897812)
		)
		(stroke
			(width 0)
			(type solid)
		)
		(fill yes)
		(layer "In2.Cu")
		(net "M_I_CPU1_SB_DQS_DN<3>")
	)
	(gr_poly
		(pts
			(xy 145.066004 -284.008068) (xy 144.965928 -283.908246) (xy 144.866106 -284.008068) (xy 144.866106 -284.052518)
			(xy 145.066004 -284.052518)
		)
		(stroke
			(width 0)
			(type solid)
		)
		(fill yes)
		(layer "In2.Cu")
		(net "M_I_CPU1_SB_DQ<16>")
	)
	(gr_poly
		(pts
			(xy 145.066004 -282.388056) (xy 144.965928 -282.288234) (xy 144.866106 -282.388056) (xy 144.866106 -282.432506)
			(xy 145.066004 -282.432506)
		)
		(stroke
			(width 0)
			(type solid)
		)
		(fill yes)
		(layer "In2.Cu")
		(net "M_I_CPU1_SB_DQ<12>")
	)
	(gr_poly
		(pts
			(xy 145.066004 -279.148032) (xy 144.965928 -279.04821) (xy 144.866106 -279.148032) (xy 144.866106 -279.192482)
			(xy 145.066004 -279.192482)
		)
		(stroke
			(width 0)
			(type solid)
		)
		(fill yes)
		(layer "In2.Cu")
		(net "M_I_CPU1_SB_DQ<8>")
	)
	(gr_poly
		(pts
			(xy 145.066004 -277.52802) (xy 144.965928 -277.428198) (xy 144.866106 -277.52802) (xy 144.866106 -277.57247)
			(xy 145.066004 -277.57247)
		)
		(stroke
			(width 0)
			(type solid)
		)
		(fill yes)
		(layer "In2.Cu")
		(net "M_I_CPU1_SB_DQ<4>")
	)
	(gr_poly
		(pts
			(xy 145.066004 -274.287996) (xy 144.965928 -274.188174) (xy 144.866106 -274.287996) (xy 144.866106 -274.332446)
			(xy 145.066004 -274.332446)
		)
		(stroke
			(width 0)
			(type solid)
		)
		(fill yes)
		(layer "In2.Cu")
		(net "M_I_CPU1_SB_DQ<0>")
	)
	(gr_poly
		(pts
			(xy 145.066004 -272.667984) (xy 144.965928 -272.568162) (xy 144.866106 -272.667984) (xy 144.866106 -272.712434)
			(xy 145.066004 -272.712434)
		)
		(stroke
			(width 0)
			(type solid)
		)
		(fill yes)
		(layer "In2.Cu")
		(net "M_I_CPU1_SB_CB<0>")
	)
	(gr_poly
		(pts
			(xy 145.066004 -264.567924) (xy 144.965928 -264.468102) (xy 144.866106 -264.567924) (xy 144.866106 -264.612374)
			(xy 145.066004 -264.612374)
		)
		(stroke
			(width 0)
			(type solid)
		)
		(fill yes)
		(layer "In2.Cu")
		(net "M_I_CPU1_SB_CA<6>")
	)
	(gr_poly
		(pts
			(xy 145.066766 -280.768044) (xy 144.966944 -280.668222) (xy 144.866868 -280.768044) (xy 144.866868 -280.815796)
			(xy 145.066766 -280.815796)
		)
		(stroke
			(width 0)
			(type solid)
		)
		(fill yes)
		(layer "In2.Cu")
		(net "M_I_CPU1_SB_DQS_DP<1>")
	)
	(gr_poly
		(pts
			(xy 145.066766 -275.908008) (xy 144.966944 -275.808186) (xy 144.866868 -275.908008) (xy 144.866868 -275.95576)
			(xy 145.066766 -275.95576)
		)
		(stroke
			(width 0)
			(type solid)
		)
		(fill yes)
		(layer "In2.Cu")
		(net "M_I_CPU1_SB_DQS_DP<0>")
	)
	(gr_poly
		(pts
			(xy 145.0721 -262.948166) (xy 144.972024 -262.84809) (xy 144.871948 -262.948166) (xy 144.871948 -262.992616)
			(xy 145.0721 -262.992616)
		)
		(stroke
			(width 0)
			(type solid)
		)
		(fill yes)
		(layer "In2.Cu")
		(net "M_I_CPU1_SB_CA<2>")
	)
	(gr_poly
		(pts
			(xy 145.074894 -285.62808) (xy 144.974818 -285.528258) (xy 144.874742 -285.62808) (xy 144.874742 -285.675832)
			(xy 145.074894 -285.675832)
		)
		(stroke
			(width 0)
			(type solid)
		)
		(fill yes)
		(layer "In2.Cu")
		(net "M_I_CPU1_SB_DQS_DP<2>")
	)
	(gr_poly
		(pts
			(xy 145.074894 -271.047972) (xy 144.974818 -270.94815) (xy 144.874742 -271.047972) (xy 144.874742 -271.095724)
			(xy 145.074894 -271.095724)
		)
		(stroke
			(width 0)
			(type solid)
		)
		(fill yes)
		(layer "In2.Cu")
		(net "M_I_CPU1_SB_DQS_DP<9>")
	)
	(gr_poly
		(pts
			(xy 145.080482 -270.645128) (xy 145.080482 -270.600678) (xy 144.88033 -270.600678) (xy 144.88033 -270.645128)
			(xy 144.980406 -270.74495)
		)
		(stroke
			(width 0)
			(type solid)
		)
		(fill yes)
		(layer "In2.Cu")
		(net "M_I_CPU1_SB_CB<7>")
	)
	(gr_poly
		(pts
			(xy 145.08734 -281.985212) (xy 145.08734 -281.937714) (xy 144.887442 -281.937714) (xy 144.887442 -281.985212)
			(xy 144.987264 -282.085288)
		)
		(stroke
			(width 0)
			(type solid)
		)
		(fill yes)
		(layer "In2.Cu")
		(net "M_I_CPU1_SB_DQS_DP<6>")
	)
	(gr_poly
		(pts
			(xy 145.08734 -277.125176) (xy 145.08734 -277.077678) (xy 144.887442 -277.077678) (xy 144.887442 -277.125176)
			(xy 144.987264 -277.225252)
		)
		(stroke
			(width 0)
			(type solid)
		)
		(fill yes)
		(layer "In2.Cu")
		(net "M_I_CPU1_SB_DQS_DP<5>")
	)
	(gr_poly
		(pts
			(xy 145.08734 -272.26514) (xy 145.08734 -272.217642) (xy 144.887442 -272.217642) (xy 144.887442 -272.26514)
			(xy 144.987264 -272.365216)
		)
		(stroke
			(width 0)
			(type solid)
		)
		(fill yes)
		(layer "In2.Cu")
		(net "M_I_CPU1_SB_DQS_DP<4>")
	)
	(gr_poly
		(pts
			(xy 145.089118 -285.225236) (xy 145.089118 -285.180786) (xy 144.88922 -285.180786) (xy 144.88922 -285.225236)
			(xy 144.989296 -285.325312)
		)
		(stroke
			(width 0)
			(type solid)
		)
		(fill yes)
		(layer "In2.Cu")
		(net "M_I_CPU1_SB_DQ<19>")
	)
	(gr_poly
		(pts
			(xy 145.089118 -283.605224) (xy 145.089118 -283.560774) (xy 144.88922 -283.560774) (xy 144.88922 -283.605224)
			(xy 144.989296 -283.7053)
		)
		(stroke
			(width 0)
			(type solid)
		)
		(fill yes)
		(layer "In2.Cu")
		(net "M_I_CPU1_SB_DQ<15>")
	)
	(gr_poly
		(pts
			(xy 145.089118 -280.3652) (xy 145.089118 -280.32075) (xy 144.88922 -280.32075) (xy 144.88922 -280.3652)
			(xy 144.989296 -280.465276)
		)
		(stroke
			(width 0)
			(type solid)
		)
		(fill yes)
		(layer "In2.Cu")
		(net "M_I_CPU1_SB_DQ<11>")
	)
	(gr_poly
		(pts
			(xy 145.089118 -278.745188) (xy 145.089118 -278.700738) (xy 144.88922 -278.700738) (xy 144.88922 -278.745188)
			(xy 144.989296 -278.845264)
		)
		(stroke
			(width 0)
			(type solid)
		)
		(fill yes)
		(layer "In2.Cu")
		(net "M_I_CPU1_SB_DQ<7>")
	)
	(gr_poly
		(pts
			(xy 145.089118 -275.505164) (xy 145.089118 -275.460714) (xy 144.88922 -275.460714) (xy 144.88922 -275.505164)
			(xy 144.989296 -275.60524)
		)
		(stroke
			(width 0)
			(type solid)
		)
		(fill yes)
		(layer "In2.Cu")
		(net "M_I_CPU1_SB_DQ<3>")
	)
	(gr_poly
		(pts
			(xy 145.089118 -273.885152) (xy 145.089118 -273.840702) (xy 144.88922 -273.840702) (xy 144.88922 -273.885152)
			(xy 144.989296 -273.985228)
		)
		(stroke
			(width 0)
			(type solid)
		)
		(fill yes)
		(layer "In2.Cu")
		(net "M_I_CPU1_SB_CB<3>")
	)
	(gr_poly
		(pts
			(xy 145.089118 -267.405104) (xy 145.089118 -267.360654) (xy 144.88922 -267.360654) (xy 144.88922 -267.405104)
			(xy 144.989296 -267.50518)
		)
		(stroke
			(width 0)
			(type solid)
		)
		(fill yes)
		(layer "In2.Cu")
		(net "M_I_CPU1_SB_RSP<0>")
	)
	(gr_poly
		(pts
			(xy 145.089118 -265.785092) (xy 145.089118 -265.740642) (xy 144.88922 -265.740642) (xy 144.88922 -265.785092)
			(xy 144.989296 -265.885168)
		)
		(stroke
			(width 0)
			(type solid)
		)
		(fill yes)
		(layer "In2.Cu")
		(net "M_I_CPU1_SB_CS_N<0>")
	)
	(gr_poly
		(pts
			(xy 145.089118 -264.16508) (xy 145.089118 -264.12063) (xy 144.88922 -264.12063) (xy 144.88922 -264.16508)
			(xy 144.989296 -264.265156)
		)
		(stroke
			(width 0)
			(type solid)
		)
		(fill yes)
		(layer "In2.Cu")
		(net "M_I_CPU1_SB_CA<5>")
	)
	(gr_poly
		(pts
			(xy 145.089118 -262.545068) (xy 145.089118 -262.500618) (xy 144.88922 -262.500618) (xy 144.88922 -262.545068)
			(xy 144.989296 -262.645144)
		)
		(stroke
			(width 0)
			(type solid)
		)
		(fill yes)
		(layer "In2.Cu")
		(net "M_I_CPU1_SB_CA<1>")
	)
	(gr_poly
		(pts
			(xy 145.09369 -294.947594) (xy 145.130266 -294.811196) (xy 144.993614 -294.77462) (xy 144.952466 -294.798242)
			(xy 145.052288 -294.97147)
		)
		(stroke
			(width 0)
			(type solid)
		)
		(fill yes)
		(layer "In2.Cu")
		(net "M_I_CPU1_SB_DQS_DN<8>")
	)
	(gr_poly
		(pts
			(xy 145.130774 -269.560802) (xy 145.093944 -269.42415) (xy 145.05559 -269.401798) (xy 144.955514 -269.575026)
			(xy 144.994122 -269.597378)
		)
		(stroke
			(width 0)
			(type solid)
		)
		(fill yes)
		(layer "In2.Cu")
		(net "M_I_CPU1_SB_CB<6>")
	)
	(gr_poly
		(pts
			(xy 145.153634 -224.695766) (xy 145.113502 -224.67697) (xy 144.980406 -224.72523) (xy 145.02892 -224.858072)
			(xy 145.069052 -224.876868)
		)
		(stroke
			(width 0)
			(type solid)
		)
		(fill yes)
		(layer "In2.Cu")
		(net "M_I_CPU1_SA_DQ<8>")
	)
	(gr_poly
		(pts
			(xy 145.154904 -223.07423) (xy 145.114772 -223.055434) (xy 144.98193 -223.103694) (xy 145.03019 -223.236536)
			(xy 145.070322 -223.255332)
		)
		(stroke
			(width 0)
			(type solid)
		)
		(fill yes)
		(layer "In2.Cu")
		(net "M_I_CPU1_SA_DQ<5>")
	)
	(gr_poly
		(pts
			(xy 145.164048 -226.315778) (xy 145.12544 -226.293426) (xy 144.989042 -226.330002) (xy 145.025618 -226.466654)
			(xy 145.063972 -226.489006)
		)
		(stroke
			(width 0)
			(type solid)
		)
		(fill yes)
		(layer "In2.Cu")
		(net "M_I_CPU1_SA_DQ<9>")
	)
	(gr_poly
		(pts
			(xy 145.166334 -229.55758) (xy 145.125186 -229.533958) (xy 144.988534 -229.570534) (xy 145.02511 -229.707186)
			(xy 145.066258 -229.730808)
		)
		(stroke
			(width 0)
			(type solid)
		)
		(fill yes)
		(layer "In2.Cu")
		(net "M_I_CPU1_SA_DQS_DN<6>")
	)
	(gr_poly
		(pts
			(xy 145.166842 -227.936552) (xy 145.125694 -227.912676) (xy 144.989042 -227.949506) (xy 145.025618 -228.085904)
			(xy 145.06702 -228.10978)
		)
		(stroke
			(width 0)
			(type solid)
		)
		(fill yes)
		(layer "In2.Cu")
		(net "M_I_CPU1_SA_DQS_DP<1>")
	)
	(gr_poly
		(pts
			(xy 145.221198 -254.405892) (xy 145.121122 -254.30607) (xy 145.021046 -254.405892) (xy 145.021046 -254.450342)
			(xy 145.221198 -254.450342)
		)
		(stroke
			(width 0)
			(type solid)
		)
		(fill yes)
		(layer "In2.Cu")
		(net "M_I_CPU1_SA_CA<4>")
	)
	(gr_poly
		(pts
			(xy 145.221198 -252.78588) (xy 145.121122 -252.686058) (xy 145.021046 -252.78588) (xy 145.021046 -252.83033)
			(xy 145.221198 -252.83033)
		)
		(stroke
			(width 0)
			(type solid)
		)
		(fill yes)
		(layer "In2.Cu")
		(net "M_I_CPU1_SA_CA<0>")
	)
	(gr_poly
		(pts
			(xy 145.221198 -247.925844) (xy 145.121122 -247.826022) (xy 145.021046 -247.925844) (xy 145.021046 -247.970294)
			(xy 145.221198 -247.970294)
		)
		(stroke
			(width 0)
			(type solid)
		)
		(fill yes)
		(layer "In2.Cu")
		(net "M_I_CPU1_SA_CB<4>")
	)
	(gr_poly
		(pts
			(xy 145.221198 -244.68582) (xy 145.121122 -244.585998) (xy 145.021046 -244.68582) (xy 145.021046 -244.73027)
			(xy 145.221198 -244.73027)
		)
		(stroke
			(width 0)
			(type solid)
		)
		(fill yes)
		(layer "In2.Cu")
		(net "M_I_CPU1_SA_CB<0>")
	)
	(gr_poly
		(pts
			(xy 145.222722 -256.025904) (xy 145.122646 -255.926082) (xy 145.02257 -256.025904) (xy 145.02257 -256.073656)
			(xy 145.222722 -256.073656)
		)
		(stroke
			(width 0)
			(type solid)
		)
		(fill yes)
		(layer "In2.Cu")
		(net "M_I_CPU1_CLK_DP<0>")
	)
	(gr_poly
		(pts
			(xy 145.222722 -246.305832) (xy 145.122646 -246.20601) (xy 145.02257 -246.305832) (xy 145.02257 -246.353584)
			(xy 145.222722 -246.353584)
		)
		(stroke
			(width 0)
			(type solid)
		)
		(fill yes)
		(layer "In2.Cu")
		(net "M_I_CPU1_SA_DQS_DP<4>")
	)
	(gr_poly
		(pts
			(xy 145.23593 -241.042444) (xy 145.23593 -240.997994) (xy 145.036032 -240.997994) (xy 145.036032 -241.042444)
			(xy 145.136108 -241.14252)
		)
		(stroke
			(width 0)
			(type solid)
		)
		(fill yes)
		(layer "In2.Cu")
		(net "M_I_CPU1_SA_DQ<27>")
	)
	(gr_poly
		(pts
			(xy 145.24482 -254.00254) (xy 145.24482 -253.95809) (xy 145.044668 -253.95809) (xy 145.044668 -254.00254)
			(xy 145.144744 -254.102616)
		)
		(stroke
			(width 0)
			(type solid)
		)
		(fill yes)
		(layer "In2.Cu")
		(net "M_I_CPU1_SA_CA<3>")
	)
	(gr_poly
		(pts
			(xy 145.24482 -250.762516) (xy 145.24482 -250.718066) (xy 145.044668 -250.718066) (xy 145.044668 -250.762516)
			(xy 145.144744 -250.862592)
		)
		(stroke
			(width 0)
			(type solid)
		)
		(fill yes)
		(layer "In2.Cu")
		(net "M_I_CPU1_RESET_N")
	)
	(gr_poly
		(pts
			(xy 145.24482 -245.90248) (xy 145.24482 -245.85803) (xy 145.044668 -245.85803) (xy 145.044668 -245.90248)
			(xy 145.144744 -246.002556)
		)
		(stroke
			(width 0)
			(type solid)
		)
		(fill yes)
		(layer "In2.Cu")
		(net "M_I_CPU1_SA_CB<3>")
	)
	(gr_poly
		(pts
			(xy 145.24482 -244.282468) (xy 145.24482 -244.238018) (xy 145.044668 -244.238018) (xy 145.044668 -244.282468)
			(xy 145.144744 -244.382544)
		)
		(stroke
			(width 0)
			(type solid)
		)
		(fill yes)
		(layer "In2.Cu")
		(net "M_I_CPU1_SA_DQ<31>")
	)
	(gr_poly
		(pts
			(xy 145.257266 -247.522746) (xy 145.257266 -247.475248) (xy 145.057114 -247.475248) (xy 145.057114 -247.522746)
			(xy 145.15719 -247.622822)
		)
		(stroke
			(width 0)
			(type solid)
		)
		(fill yes)
		(layer "In2.Cu")
		(net "M_I_CPU1_SA_DQS_DP<9>")
	)
	(gr_poly
		(pts
			(xy 145.25879 -242.66271) (xy 145.25879 -242.615212) (xy 145.058892 -242.615212) (xy 145.058892 -242.66271)
			(xy 145.158714 -242.762786)
		)
		(stroke
			(width 0)
			(type solid)
		)
		(fill yes)
		(layer "In2.Cu")
		(net "M_I_CPU1_SA_DQS_DP<8>")
	)
	(gr_poly
		(pts
			(xy 145.299938 -230.24084) (xy 145.263362 -230.104188) (xy 145.222214 -230.080312) (xy 145.122138 -230.25354)
			(xy 145.163286 -230.277416)
		)
		(stroke
			(width 0)
			(type solid)
		)
		(fill yes)
		(layer "In2.Cu")
		(net "M_I_CPU1_SA_DQS_DP<6>")
	)
	(gr_poly
		(pts
			(xy 145.299938 -223.760284) (xy 145.263362 -223.623632) (xy 145.224754 -223.601534) (xy 145.124678 -223.774762)
			(xy 145.163286 -223.79686)
		)
		(stroke
			(width 0)
			(type solid)
		)
		(fill yes)
		(layer "In2.Cu")
		(net "M_I_CPU1_SA_DQ<7>")
	)
	(gr_poly
		(pts
			(xy 145.3007 -228.619558) (xy 145.264124 -228.48316) (xy 145.222722 -228.459284) (xy 145.1229 -228.632512)
			(xy 145.164048 -228.656134)
		)
		(stroke
			(width 0)
			(type solid)
		)
		(fill yes)
		(layer "In2.Cu")
		(net "M_I_CPU1_SA_DQS_DN<1>")
	)
	(gr_poly
		(pts
			(xy 145.300954 -226.999038) (xy 145.264124 -226.862386) (xy 145.22577 -226.840034) (xy 145.125694 -227.013262)
			(xy 145.164302 -227.035614)
		)
		(stroke
			(width 0)
			(type solid)
		)
		(fill yes)
		(layer "In2.Cu")
		(net "M_I_CPU1_SA_DQ<11>")
	)
	(gr_poly
		(pts
			(xy 145.308828 -225.364802) (xy 145.260314 -225.23196) (xy 145.220182 -225.213164) (xy 145.1356 -225.39452)
			(xy 145.175986 -225.413316)
		)
		(stroke
			(width 0)
			(type solid)
		)
		(fill yes)
		(layer "In2.Cu")
		(net "M_I_CPU1_SA_DQ<10>")
	)
	(gr_poly
		(pts
			(xy 145.455132 -269.685008) (xy 145.414746 -269.666212) (xy 145.281904 -269.714726) (xy 145.330418 -269.847568)
			(xy 145.37055 -269.866364)
		)
		(stroke
			(width 0)
			(type solid)
		)
		(fill yes)
		(layer "In2.Cu")
		(net "M_I_CPU1_SB_CB<5>")
	)
	(gr_poly
		(pts
			(xy 145.466562 -294.684196) (xy 145.36674 -294.510968) (xy 145.325338 -294.534844) (xy 145.288762 -294.671242)
			(xy 145.425414 -294.708072)
		)
		(stroke
			(width 0)
			(type solid)
		)
		(fill yes)
		(layer "In2.Cu")
		(net "M_I_CPU1_SB_DQS_DN<3>")
	)
	(gr_poly
		(pts
			(xy 145.54454 -271.454626) (xy 145.54454 -271.406874) (xy 145.344642 -271.406874) (xy 145.344642 -271.454626)
			(xy 145.444464 -271.554702)
		)
		(stroke
			(width 0)
			(type solid)
		)
		(fill yes)
		(layer "In2.Cu")
		(net "M_I_CPU1_SB_DQS_DN<9>")
	)
	(gr_poly
		(pts
			(xy 145.55724 -276.314662) (xy 145.55724 -276.267164) (xy 145.357342 -276.267164) (xy 145.357342 -276.314662)
			(xy 145.457164 -276.414738)
		)
		(stroke
			(width 0)
			(type solid)
		)
		(fill yes)
		(layer "In2.Cu")
		(net "M_I_CPU1_SB_DQS_DN<0>")
	)
	(gr_poly
		(pts
			(xy 145.563844 -294.137588) (xy 145.60042 -294.00119) (xy 145.463768 -293.96436) (xy 145.42262 -293.988236)
			(xy 145.522442 -294.161464)
		)
		(stroke
			(width 0)
			(type solid)
		)
		(fill yes)
		(layer "In2.Cu")
		(net "M_I_CPU1_SB_DQS_DP<3>")
	)
	(gr_poly
		(pts
			(xy 145.633948 -223.88576) (xy 145.59534 -223.863408) (xy 145.458942 -223.899984) (xy 145.495518 -224.036636)
			(xy 145.533872 -224.058988)
		)
		(stroke
			(width 0)
			(type solid)
		)
		(fill yes)
		(layer "In2.Cu")
		(net "M_I_CPU1_SA_DQ<8>")
	)
	(gr_poly
		(pts
			(xy 145.636742 -228.746558) (xy 145.595594 -228.722936) (xy 145.458942 -228.759512) (xy 145.495518 -228.89591)
			(xy 145.53692 -228.919786)
		)
		(stroke
			(width 0)
			(type solid)
		)
		(fill yes)
		(layer "In2.Cu")
		(net "M_I_CPU1_SA_DQS_DN<6>")
	)
	(gr_poly
		(pts
			(xy 145.637504 -227.125022) (xy 145.596102 -227.101146) (xy 145.45945 -227.137722) (xy 145.496026 -227.274374)
			(xy 145.537428 -227.29825)
		)
		(stroke
			(width 0)
			(type solid)
		)
		(fill yes)
		(layer "In2.Cu")
		(net "M_I_CPU1_SA_DQS_DP<1>")
	)
	(gr_poly
		(pts
			(xy 145.692368 -251.971048) (xy 145.592292 -251.870972) (xy 145.49247 -251.971048) (xy 145.49247 -252.015498)
			(xy 145.692368 -252.015498)
		)
		(stroke
			(width 0)
			(type solid)
		)
		(fill yes)
		(layer "In2.Cu")
		(net "M_I_CPU1_SA_CS_N<1>")
	)
	(gr_poly
		(pts
			(xy 145.706846 -247.115838) (xy 145.607024 -247.016016) (xy 145.506948 -247.115838) (xy 145.506948 -247.16359)
			(xy 145.706846 -247.16359)
		)
		(stroke
			(width 0)
			(type solid)
		)
		(fill yes)
		(layer "In2.Cu")
		(net "M_I_CPU1_SA_DQS_DN<9>")
	)
	(gr_poly
		(pts
			(xy 145.714974 -253.596394) (xy 145.614898 -253.496318) (xy 145.514822 -253.596394) (xy 145.514822 -253.640844)
			(xy 145.714974 -253.640844)
		)
		(stroke
			(width 0)
			(type solid)
		)
		(fill yes)
		(layer "In2.Cu")
		(net "M_I_CPU1_SA_CA<2>")
	)
	(gr_poly
		(pts
			(xy 145.714974 -245.496334) (xy 145.614898 -245.396258) (xy 145.514822 -245.496334) (xy 145.514822 -245.540784)
			(xy 145.714974 -245.540784)
		)
		(stroke
			(width 0)
			(type solid)
		)
		(fill yes)
		(layer "In2.Cu")
		(net "M_I_CPU1_SA_CB<1>")
	)
	(gr_poly
		(pts
			(xy 145.768568 -227.812346) (xy 145.731992 -227.675948) (xy 145.69059 -227.652072) (xy 145.590768 -227.8253)
			(xy 145.631916 -227.848922)
		)
		(stroke
			(width 0)
			(type solid)
		)
		(fill yes)
		(layer "In2.Cu")
		(net "M_I_CPU1_SA_DQS_DN<1>")
	)
	(gr_poly
		(pts
			(xy 145.771108 -229.428294) (xy 145.734532 -229.291642) (xy 145.693384 -229.26802) (xy 145.593308 -229.441248)
			(xy 145.63471 -229.46487)
		)
		(stroke
			(width 0)
			(type solid)
		)
		(fill yes)
		(layer "In2.Cu")
		(net "M_I_CPU1_SA_DQS_DP<6>")
	)
	(gr_poly
		(pts
			(xy 145.77822 -224.554796) (xy 145.729706 -224.4217) (xy 145.689574 -224.403158) (xy 145.604992 -224.58426)
			(xy 145.645378 -224.603056)
		)
		(stroke
			(width 0)
			(type solid)
		)
		(fill yes)
		(layer "In2.Cu")
		(net "M_I_CPU1_SA_DQ<10>")
	)
	(gr_poly
		(pts
			(xy 146.033998 -294.948356) (xy 146.070574 -294.811958) (xy 145.933922 -294.775382) (xy 145.892774 -294.799004)
			(xy 145.992596 -294.972232)
		)
		(stroke
			(width 0)
			(type solid)
		)
		(fill yes)
		(layer "In2.Cu")
		(net "M_I_CPU1_SB_DQS_DP<3>")
	)
	(gr_poly
		(pts
			(xy 146.106896 -223.069658) (xy 146.068542 -223.04756) (xy 145.93189 -223.084136) (xy 145.968466 -223.220788)
			(xy 146.00682 -223.242886)
		)
		(stroke
			(width 0)
			(type solid)
		)
		(fill yes)
		(layer "In2.Cu")
		(net "M_I_CPU1_SA_DQ<8>")
	)
	(gr_poly
		(pts
			(xy 146.240754 -223.759014) (xy 146.203924 -223.622362) (xy 146.16557 -223.60001) (xy 146.065494 -223.773238)
			(xy 146.104102 -223.79559)
		)
		(stroke
			(width 0)
			(type solid)
		)
		(fill yes)
		(layer "In2.Cu")
		(net "M_I_CPU1_SA_DQ<10>")
	)
	(gr_poly
		(pts
			(xy 325.433182 -227.012246) (xy 325.33336 -226.839018) (xy 325.291958 -226.862894) (xy 325.255382 -226.999292)
			(xy 325.392034 -227.035868)
		)
		(stroke
			(width 0)
			(type solid)
		)
		(fill yes)
		(layer "In2.Cu")
		(net "M_C_CPU0_SA_DQS_DN<1>")
	)
	(gr_poly
		(pts
			(xy 325.462138 -228.640132) (xy 325.362316 -228.466904) (xy 325.320914 -228.490526) (xy 325.284338 -228.627178)
			(xy 325.42099 -228.663754)
		)
		(stroke
			(width 0)
			(type solid)
		)
		(fill yes)
		(layer "In2.Cu")
		(net "M_C_CPU0_SA_DQS_DP<6>")
	)
	(gr_poly
		(pts
			(xy 325.52005 -224.828608) (xy 325.556626 -224.691956) (xy 325.419974 -224.65538) (xy 325.38162 -224.677732)
			(xy 325.481442 -224.85096)
		)
		(stroke
			(width 0)
			(type solid)
		)
		(fill yes)
		(layer "In2.Cu")
		(net "M_C_CPU0_SA_DQ<9>")
	)
	(gr_poly
		(pts
			(xy 325.890382 -224.583244) (xy 325.8058 -224.401888) (xy 325.765668 -224.420684) (xy 325.717154 -224.553526)
			(xy 325.85025 -224.60204)
		)
		(stroke
			(width 0)
			(type solid)
		)
		(fill yes)
		(layer "In2.Cu")
		(net "M_C_CPU0_SA_DQ<10>")
	)
	(gr_poly
		(pts
			(xy 325.903082 -227.822252) (xy 325.80326 -227.649024) (xy 325.761858 -227.6729) (xy 325.725282 -227.809298)
			(xy 325.861934 -227.846128)
		)
		(stroke
			(width 0)
			(type solid)
		)
		(fill yes)
		(layer "In2.Cu")
		(net "M_C_CPU0_SA_DQS_DN<1>")
	)
	(gr_poly
		(pts
			(xy 325.903844 -229.442772) (xy 325.803768 -229.269544) (xy 325.76262 -229.29342) (xy 325.726044 -229.430072)
			(xy 325.862696 -229.466648)
		)
		(stroke
			(width 0)
			(type solid)
		)
		(fill yes)
		(layer "In2.Cu")
		(net "M_C_CPU0_SA_DQS_DP<6>")
	)
	(gr_poly
		(pts
			(xy 325.904352 -226.209606) (xy 325.804276 -226.036378) (xy 325.765922 -226.05873) (xy 325.729346 -226.195128)
			(xy 325.865744 -226.231958)
		)
		(stroke
			(width 0)
			(type solid)
		)
		(fill yes)
		(layer "In2.Cu")
		(net "M_C_CPU0_SA_DQ<11>")
	)
	(gr_poly
		(pts
			(xy 325.968868 -253.596394) (xy 325.868792 -253.496318) (xy 325.768716 -253.596394) (xy 325.768716 -253.640844)
			(xy 325.968868 -253.640844)
		)
		(stroke
			(width 0)
			(type solid)
		)
		(fill yes)
		(layer "In2.Cu")
		(net "M_C_CPU0_SA_CA<2>")
	)
	(gr_poly
		(pts
			(xy 325.999094 -225.654616) (xy 326.03567 -225.517964) (xy 325.899018 -225.481388) (xy 325.86041 -225.50374)
			(xy 325.960486 -225.676968)
		)
		(stroke
			(width 0)
			(type solid)
		)
		(fill yes)
		(layer "In2.Cu")
		(net "M_C_CPU0_SA_DQ<9>")
	)
	(gr_poly
		(pts
			(xy 326.00011 -228.89464) (xy 326.036686 -228.758242) (xy 325.900034 -228.721666) (xy 325.858886 -228.745288)
			(xy 325.958962 -228.918516)
		)
		(stroke
			(width 0)
			(type solid)
		)
		(fill yes)
		(layer "In2.Cu")
		(net "M_C_CPU0_SA_DQS_DN<6>")
	)
	(gr_poly
		(pts
			(xy 326.000364 -227.275644) (xy 326.03694 -227.139246) (xy 325.900288 -227.10267) (xy 325.85914 -227.126292)
			(xy 325.958962 -227.29952)
		)
		(stroke
			(width 0)
			(type solid)
		)
		(fill yes)
		(layer "In2.Cu")
		(net "M_C_CPU0_SA_DQS_DP<1>")
	)
	(gr_poly
		(pts
			(xy 326.000618 -224.023428) (xy 326.037194 -223.886776) (xy 325.900542 -223.8502) (xy 325.862188 -223.872298)
			(xy 325.962264 -224.045526)
		)
		(stroke
			(width 0)
			(type solid)
		)
		(fill yes)
		(layer "In2.Cu")
		(net "M_C_CPU0_SA_DQ<8>")
	)
	(gr_poly
		(pts
			(xy 326.370696 -227.01377) (xy 326.27062 -226.840542) (xy 326.232266 -226.862894) (xy 326.195436 -226.999292)
			(xy 326.332088 -227.036122)
		)
		(stroke
			(width 0)
			(type solid)
		)
		(fill yes)
		(layer "In2.Cu")
		(net "M_C_CPU0_SA_DQ<11>")
	)
	(gr_poly
		(pts
			(xy 326.372474 -223.77654) (xy 326.272398 -223.603312) (xy 326.234044 -223.62541) (xy 326.197468 -223.762062)
			(xy 326.333866 -223.798638)
		)
		(stroke
			(width 0)
			(type solid)
		)
		(fill yes)
		(layer "In2.Cu")
		(net "M_C_CPU0_SA_DQ<7>")
	)
	(gr_poly
		(pts
			(xy 326.373998 -230.252524) (xy 326.273922 -230.079296) (xy 326.232774 -230.103172) (xy 326.196198 -230.239824)
			(xy 326.332596 -230.2764)
		)
		(stroke
			(width 0)
			(type solid)
		)
		(fill yes)
		(layer "In2.Cu")
		(net "M_C_CPU0_SA_DQS_DP<6>")
	)
	(gr_poly
		(pts
			(xy 326.375014 -228.634036) (xy 326.274938 -228.460808) (xy 326.23379 -228.484684) (xy 326.197214 -228.621336)
			(xy 326.333866 -228.657912)
		)
		(stroke
			(width 0)
			(type solid)
		)
		(fill yes)
		(layer "In2.Cu")
		(net "M_C_CPU0_SA_DQS_DN<1>")
	)
	(gr_poly
		(pts
			(xy 326.438514 -256.025904) (xy 326.338692 -255.925828) (xy 326.238616 -256.025904) (xy 326.238616 -256.073402)
			(xy 326.438514 -256.073402)
		)
		(stroke
			(width 0)
			(type solid)
		)
		(fill yes)
		(layer "In2.Cu")
		(net "M_C_CPU0_CLK_DP<0>")
	)
	(gr_poly
		(pts
			(xy 326.438768 -246.305578) (xy 326.338692 -246.205756) (xy 326.238616 -246.305578) (xy 326.238616 -246.35333)
			(xy 326.438768 -246.35333)
		)
		(stroke
			(width 0)
			(type solid)
		)
		(fill yes)
		(layer "In2.Cu")
		(net "M_C_CPU0_SA_DQS_DP<4>")
	)
	(gr_poly
		(pts
			(xy 326.441562 -254.405892) (xy 326.341486 -254.30607) (xy 326.24141 -254.405892) (xy 326.24141 -254.450342)
			(xy 326.441562 -254.450342)
		)
		(stroke
			(width 0)
			(type solid)
		)
		(fill yes)
		(layer "In2.Cu")
		(net "M_C_CPU0_SA_CA<4>")
	)
	(gr_poly
		(pts
			(xy 326.441562 -252.78588) (xy 326.341486 -252.686058) (xy 326.24141 -252.78588) (xy 326.24141 -252.83033)
			(xy 326.441562 -252.83033)
		)
		(stroke
			(width 0)
			(type solid)
		)
		(fill yes)
		(layer "In2.Cu")
		(net "M_C_CPU0_SA_CA<0>")
	)
	(gr_poly
		(pts
			(xy 326.441562 -247.925844) (xy 326.341486 -247.826022) (xy 326.24141 -247.925844) (xy 326.24141 -247.970294)
			(xy 326.441562 -247.970294)
		)
		(stroke
			(width 0)
			(type solid)
		)
		(fill yes)
		(layer "In2.Cu")
		(net "M_C_CPU0_SA_CB<4>")
	)
	(gr_poly
		(pts
			(xy 326.441562 -244.68582) (xy 326.341486 -244.585998) (xy 326.24141 -244.68582) (xy 326.24141 -244.73027)
			(xy 326.441562 -244.73027)
		)
		(stroke
			(width 0)
			(type solid)
		)
		(fill yes)
		(layer "In2.Cu")
		(net "M_C_CPU0_SA_CB<0>")
	)
	(gr_poly
		(pts
			(xy 326.465946 -224.854516) (xy 326.514206 -224.72142) (xy 326.381364 -224.67316) (xy 326.340978 -224.691956)
			(xy 326.42556 -224.873058)
		)
		(stroke
			(width 0)
			(type solid)
		)
		(fill yes)
		(layer "In2.Cu")
		(net "M_C_CPU0_SA_DQ<8>")
	)
	(gr_poly
		(pts
			(xy 326.468486 -226.463352) (xy 326.505062 -226.3267) (xy 326.368664 -226.290124) (xy 326.330056 -226.312222)
			(xy 326.430132 -226.48545)
		)
		(stroke
			(width 0)
			(type solid)
		)
		(fill yes)
		(layer "In2.Cu")
		(net "M_C_CPU0_SA_DQ<9>")
	)
	(gr_poly
		(pts
			(xy 326.468994 -223.224852) (xy 326.50557 -223.0882) (xy 326.369172 -223.051624) (xy 326.330564 -223.073722)
			(xy 326.43064 -223.24695)
		)
		(stroke
			(width 0)
			(type solid)
		)
		(fill yes)
		(layer "In2.Cu")
		(net "M_C_CPU0_SA_DQ<5>")
	)
	(gr_poly
		(pts
			(xy 326.470264 -228.084888) (xy 326.50684 -227.948236) (xy 326.370188 -227.91166) (xy 326.32904 -227.935536)
			(xy 326.429116 -228.108764)
		)
		(stroke
			(width 0)
			(type solid)
		)
		(fill yes)
		(layer "In2.Cu")
		(net "M_C_CPU0_SA_DQS_DP<1>")
	)
	(gr_poly
		(pts
			(xy 326.471026 -229.70617) (xy 326.507602 -229.569518) (xy 326.37095 -229.532942) (xy 326.329802 -229.556564)
			(xy 326.429624 -229.729792)
		)
		(stroke
			(width 0)
			(type solid)
		)
		(fill yes)
		(layer "In2.Cu")
		(net "M_C_CPU0_SA_DQS_DN<6>")
	)
	(gr_poly
		(pts
			(xy 326.474328 -247.522746) (xy 326.474328 -247.475248) (xy 326.27443 -247.475248) (xy 326.27443 -247.522746)
			(xy 326.374252 -247.622822)
		)
		(stroke
			(width 0)
			(type solid)
		)
		(fill yes)
		(layer "In2.Cu")
		(net "M_C_CPU0_SA_DQS_DP<9>")
	)
	(gr_poly
		(pts
			(xy 326.474328 -242.66271) (xy 326.474328 -242.615212) (xy 326.27443 -242.615212) (xy 326.27443 -242.66271)
			(xy 326.374252 -242.762786)
		)
		(stroke
			(width 0)
			(type solid)
		)
		(fill yes)
		(layer "In2.Cu")
		(net "M_C_CPU0_SA_DQS_DP<8>")
	)
	(gr_poly
		(pts
			(xy 326.479154 -253.993904) (xy 326.475344 -253.949708) (xy 326.276208 -253.967234) (xy 326.280018 -254.01143)
			(xy 326.388222 -254.102362)
		)
		(stroke
			(width 0)
			(type solid)
		)
		(fill yes)
		(layer "In2.Cu")
		(net "M_C_CPU0_SA_CA<3>")
	)
	(gr_poly
		(pts
			(xy 326.479154 -252.373892) (xy 326.475344 -252.329696) (xy 326.276208 -252.346968) (xy 326.280018 -252.391418)
			(xy 326.388222 -252.48235)
		)
		(stroke
			(width 0)
			(type solid)
		)
		(fill yes)
		(layer "In2.Cu")
		(net "M_C_CPU0_SA_CS_N<1>")
	)
	(gr_poly
		(pts
			(xy 326.479154 -245.893844) (xy 326.475344 -245.849648) (xy 326.276208 -245.86692) (xy 326.280018 -245.91137)
			(xy 326.388222 -246.002302)
		)
		(stroke
			(width 0)
			(type solid)
		)
		(fill yes)
		(layer "In2.Cu")
		(net "M_C_CPU0_SA_CB<3>")
	)
	(gr_poly
		(pts
			(xy 326.479154 -244.273832) (xy 326.475344 -244.229636) (xy 326.276208 -244.246908) (xy 326.280018 -244.291358)
			(xy 326.388222 -244.38229)
		)
		(stroke
			(width 0)
			(type solid)
		)
		(fill yes)
		(layer "In2.Cu")
		(net "M_C_CPU0_SA_DQ<31>")
	)
	(gr_poly
		(pts
			(xy 326.479154 -241.033808) (xy 326.475344 -240.989612) (xy 326.276208 -241.006884) (xy 326.280018 -241.051334)
			(xy 326.388222 -241.142266)
		)
		(stroke
			(width 0)
			(type solid)
		)
		(fill yes)
		(layer "In2.Cu")
		(net "M_C_CPU0_SA_DQ<27>")
	)
	(gr_poly
		(pts
			(xy 326.494902 -284.179772) (xy 326.476106 -284.139386) (xy 326.343264 -284.091126) (xy 326.29475 -284.223968)
			(xy 326.313546 -284.264354)
		)
		(stroke
			(width 0)
			(type solid)
		)
		(fill yes)
		(layer "In2.Cu")
		(net "M_C_CPU0_SB_DQ<16>")
	)
	(gr_poly
		(pts
			(xy 326.650858 -283.227018) (xy 326.647048 -283.182568) (xy 326.538844 -283.09189) (xy 326.447912 -283.200094)
			(xy 326.451722 -283.24429)
		)
		(stroke
			(width 0)
			(type solid)
		)
		(fill yes)
		(layer "In2.Cu")
		(net "M_C_CPU0_SB_DQ<13>")
	)
	(gr_poly
		(pts
			(xy 326.662034 -278.280622) (xy 326.591422 -278.158194) (xy 326.468994 -278.22906) (xy 326.45731 -278.271732)
			(xy 326.650604 -278.323548)
		)
		(stroke
			(width 0)
			(type solid)
		)
		(fill yes)
		(layer "In2.Cu")
		(net "M_C_CPU0_SB_DQ<5>")
	)
	(gr_poly
		(pts
			(xy 326.670416 -293.986458) (xy 326.632062 -293.964106) (xy 326.49541 -294.000682) (xy 326.531986 -294.137334)
			(xy 326.570594 -294.159686)
		)
		(stroke
			(width 0)
			(type solid)
		)
		(fill yes)
		(layer "In2.Cu")
		(net "M_C_CPU0_SB_DQ<28>")
	)
	(gr_poly
		(pts
			(xy 326.716898 -273.083274) (xy 326.720708 -273.038824) (xy 326.521318 -273.021552) (xy 326.517508 -273.065748)
			(xy 326.60844 -273.174206)
		)
		(stroke
			(width 0)
			(type solid)
		)
		(fill yes)
		(layer "In2.Cu")
		(net "M_C_CPU0_SB_CB<2>")
	)
	(gr_poly
		(pts
			(xy 326.741536 -286.437578) (xy 326.64146 -286.337756) (xy 326.541638 -286.437578) (xy 326.541638 -286.48533)
			(xy 326.741536 -286.48533)
		)
		(stroke
			(width 0)
			(type solid)
		)
		(fill yes)
		(layer "In2.Cu")
		(net "M_C_CPU0_SB_DQS_DN<7>")
	)
	(gr_poly
		(pts
			(xy 326.742298 -288.05759) (xy 326.642476 -287.957768) (xy 326.5424 -288.05759) (xy 326.5424 -288.10204)
			(xy 326.742298 -288.10204)
		)
		(stroke
			(width 0)
			(type solid)
		)
		(fill yes)
		(layer "In2.Cu")
		(net "M_C_CPU0_SB_DQ<21>")
	)
	(gr_poly
		(pts
			(xy 326.772778 -263.354312) (xy 326.772778 -263.310116) (xy 326.57288 -263.310116) (xy 326.57288 -263.354312)
			(xy 326.672956 -263.454388)
		)
		(stroke
			(width 0)
			(type solid)
		)
		(fill yes)
		(layer "In2.Cu")
		(net "M_C_CPU0_SB_CA<3>")
	)
	(gr_poly
		(pts
			(xy 326.77481 -269.834614) (xy 326.77481 -269.790164) (xy 326.574658 -269.790164) (xy 326.574658 -269.834614)
			(xy 326.674734 -269.934436)
		)
		(stroke
			(width 0)
			(type solid)
		)
		(fill yes)
		(layer "In2.Cu")
		(net "M_C_CPU0_SB_CB<6>")
	)
	(gr_poly
		(pts
			(xy 326.77481 -266.59459) (xy 326.77481 -266.55014) (xy 326.574658 -266.55014) (xy 326.574658 -266.59459)
			(xy 326.674734 -266.694412)
		)
		(stroke
			(width 0)
			(type solid)
		)
		(fill yes)
		(layer "In2.Cu")
		(net "M_C_CPU0_SB_CS_N<1>")
	)
	(gr_poly
		(pts
			(xy 326.77481 -264.974578) (xy 326.77481 -264.930128) (xy 326.574658 -264.930128) (xy 326.574658 -264.974578)
			(xy 326.674734 -265.0744)
		)
		(stroke
			(width 0)
			(type solid)
		)
		(fill yes)
		(layer "In2.Cu")
		(net "M_C_CPU0_SB_PAR")
	)
	(gr_poly
		(pts
			(xy 326.83069 -224.584514) (xy 326.746108 -224.403412) (xy 326.705722 -224.422208) (xy 326.657462 -224.55505)
			(xy 326.790304 -224.60331)
		)
		(stroke
			(width 0)
			(type solid)
		)
		(fill yes)
		(layer "In2.Cu")
		(net "M_C_CPU0_SA_DQ<7>")
	)
	(gr_poly
		(pts
			(xy 326.840342 -227.823776) (xy 326.74052 -227.650548) (xy 326.701912 -227.6729) (xy 326.665336 -227.809298)
			(xy 326.801988 -227.846128)
		)
		(stroke
			(width 0)
			(type solid)
		)
		(fill yes)
		(layer "In2.Cu")
		(net "M_C_CPU0_SA_DQ<11>")
	)
	(gr_poly
		(pts
			(xy 326.840596 -226.201986) (xy 326.740774 -226.028758) (xy 326.702166 -226.05111) (xy 326.66559 -226.187762)
			(xy 326.802242 -226.224338)
		)
		(stroke
			(width 0)
			(type solid)
		)
		(fill yes)
		(layer "In2.Cu")
		(net "M_C_CPU0_SA_DQ<10>")
	)
	(gr_poly
		(pts
			(xy 326.841866 -222.96501) (xy 326.74179 -222.791782) (xy 326.703436 -222.814134) (xy 326.66686 -222.950786)
			(xy 326.803258 -222.987362)
		)
		(stroke
			(width 0)
			(type solid)
		)
		(fill yes)
		(layer "In2.Cu")
		(net "M_C_CPU0_SA_DQ<6>")
	)
	(gr_poly
		(pts
			(xy 326.843644 -231.062022) (xy 326.743568 -230.888794) (xy 326.702166 -230.91267) (xy 326.66559 -231.049322)
			(xy 326.802242 -231.085898)
		)
		(stroke
			(width 0)
			(type solid)
		)
		(fill yes)
		(layer "In2.Cu")
		(net "M_C_CPU0_SA_DQS_DP<6>")
	)
	(gr_poly
		(pts
			(xy 326.843644 -229.44201) (xy 326.743568 -229.268782) (xy 326.702166 -229.292658) (xy 326.66559 -229.42931)
			(xy 326.802242 -229.465886)
		)
		(stroke
			(width 0)
			(type solid)
		)
		(fill yes)
		(layer "In2.Cu")
		(net "M_C_CPU0_SA_DQS_DN<1>")
	)
	(gr_poly
		(pts
			(xy 326.901302 -242.255548) (xy 326.80148 -242.155472) (xy 326.701404 -242.255548) (xy 326.701404 -242.303046)
			(xy 326.901302 -242.303046)
		)
		(stroke
			(width 0)
			(type solid)
		)
		(fill yes)
		(layer "In2.Cu")
		(net "M_C_CPU0_SA_DQS_DN<8>")
	)
	(gr_poly
		(pts
			(xy 326.906636 -255.21539) (xy 326.80656 -255.115314) (xy 326.706738 -255.21539) (xy 326.706738 -255.25984)
			(xy 326.906636 -255.25984)
		)
		(stroke
			(width 0)
			(type solid)
		)
		(fill yes)
		(layer "In2.Cu")
		(net "M_C_CPU0_SA_CA<6>")
	)
	(gr_poly
		(pts
			(xy 326.906636 -253.595378) (xy 326.80656 -253.495302) (xy 326.706738 -253.595378) (xy 326.706738 -253.639828)
			(xy 326.906636 -253.639828)
		)
		(stroke
			(width 0)
			(type solid)
		)
		(fill yes)
		(layer "In2.Cu")
		(net "M_C_CPU0_SA_CA<2>")
	)
	(gr_poly
		(pts
			(xy 326.906636 -248.735342) (xy 326.80656 -248.635266) (xy 326.706738 -248.735342) (xy 326.706738 -248.779792)
			(xy 326.906636 -248.779792)
		)
		(stroke
			(width 0)
			(type solid)
		)
		(fill yes)
		(layer "In2.Cu")
		(net "M_C_CPU0_SA_CB<5>")
	)
	(gr_poly
		(pts
			(xy 326.906636 -245.495318) (xy 326.80656 -245.395242) (xy 326.706738 -245.495318) (xy 326.706738 -245.539768)
			(xy 326.906636 -245.539768)
		)
		(stroke
			(width 0)
			(type solid)
		)
		(fill yes)
		(layer "In2.Cu")
		(net "M_C_CPU0_SA_CB<1>")
	)
	(gr_poly
		(pts
			(xy 326.906636 -243.875306) (xy 326.80656 -243.77523) (xy 326.706738 -243.875306) (xy 326.706738 -243.919756)
			(xy 326.906636 -243.919756)
		)
		(stroke
			(width 0)
			(type solid)
		)
		(fill yes)
		(layer "In2.Cu")
		(net "M_C_CPU0_SA_DQ<29>")
	)
	(gr_poly
		(pts
			(xy 326.906636 -240.635282) (xy 326.80656 -240.535206) (xy 326.706738 -240.635282) (xy 326.706738 -240.679732)
			(xy 326.906636 -240.679732)
		)
		(stroke
			(width 0)
			(type solid)
		)
		(fill yes)
		(layer "In2.Cu")
		(net "M_C_CPU0_SA_DQ<25>")
	)
	(gr_poly
		(pts
			(xy 326.908414 -247.11533) (xy 326.808592 -247.015254) (xy 326.708516 -247.11533) (xy 326.708516 -247.162828)
			(xy 326.908414 -247.162828)
		)
		(stroke
			(width 0)
			(type solid)
		)
		(fill yes)
		(layer "In2.Cu")
		(net "M_C_CPU0_SA_DQS_DN<9>")
	)
	(gr_poly
		(pts
			(xy 326.917558 -251.572268) (xy 326.917558 -251.527818) (xy 326.717406 -251.527818) (xy 326.717406 -251.572268)
			(xy 326.817482 -251.672344)
		)
		(stroke
			(width 0)
			(type solid)
		)
		(fill yes)
		(layer "In2.Cu")
		(net "M_C_CPU0_SA_CS_N<0>")
	)
	(gr_poly
		(pts
			(xy 326.921114 -250.356116) (xy 326.821038 -250.25604) (xy 326.720962 -250.356116) (xy 326.720962 -250.400566)
			(xy 326.921114 -250.400566)
		)
		(stroke
			(width 0)
			(type solid)
		)
		(fill yes)
		(layer "In2.Cu")
		(net "M_C_CPU0_ALERT_R_N")
	)
	(gr_poly
		(pts
			(xy 326.921114 -241.85245) (xy 326.921114 -241.804698) (xy 326.720962 -241.804698) (xy 326.720962 -241.85245)
			(xy 326.821038 -241.952272)
		)
		(stroke
			(width 0)
			(type solid)
		)
		(fill yes)
		(layer "In2.Cu")
		(net "M_C_CPU0_SA_DQS_DN<3>")
	)
	(gr_poly
		(pts
			(xy 326.923908 -254.812292) (xy 326.923908 -254.767842) (xy 326.723756 -254.767842) (xy 326.723756 -254.812292)
			(xy 326.823832 -254.912368)
		)
		(stroke
			(width 0)
			(type solid)
		)
		(fill yes)
		(layer "In2.Cu")
		(net "M_C_CPU0_SA_CA<5>")
	)
	(gr_poly
		(pts
			(xy 326.923908 -253.19228) (xy 326.923908 -253.14783) (xy 326.723756 -253.14783) (xy 326.723756 -253.19228)
			(xy 326.823832 -253.292356)
		)
		(stroke
			(width 0)
			(type solid)
		)
		(fill yes)
		(layer "In2.Cu")
		(net "M_C_CPU0_SA_CA<1>")
	)
	(gr_poly
		(pts
			(xy 326.923908 -248.332244) (xy 326.923908 -248.287794) (xy 326.723756 -248.287794) (xy 326.723756 -248.332244)
			(xy 326.823832 -248.43232)
		)
		(stroke
			(width 0)
			(type solid)
		)
		(fill yes)
		(layer "In2.Cu")
		(net "M_C_CPU0_SA_CB<6>")
	)
	(gr_poly
		(pts
			(xy 326.923908 -245.09222) (xy 326.923908 -245.04777) (xy 326.723756 -245.04777) (xy 326.723756 -245.09222)
			(xy 326.823832 -245.192296)
		)
		(stroke
			(width 0)
			(type solid)
		)
		(fill yes)
		(layer "In2.Cu")
		(net "M_C_CPU0_SA_CB<2>")
	)
	(gr_poly
		(pts
			(xy 326.923908 -243.472208) (xy 326.923908 -243.427758) (xy 326.723756 -243.427758) (xy 326.723756 -243.472208)
			(xy 326.823832 -243.572284)
		)
		(stroke
			(width 0)
			(type solid)
		)
		(fill yes)
		(layer "In2.Cu")
		(net "M_C_CPU0_SA_DQ<30>")
	)
	(gr_poly
		(pts
			(xy 326.928734 -246.712232) (xy 326.928734 -246.664734) (xy 326.728836 -246.664734) (xy 326.728836 -246.712232)
			(xy 326.828658 -246.812308)
		)
		(stroke
			(width 0)
			(type solid)
		)
		(fill yes)
		(layer "In2.Cu")
		(net "M_C_CPU0_SA_DQS_DN<4>")
	)
	(gr_poly
		(pts
			(xy 326.932798 -256.432558) (xy 326.932798 -256.38506) (xy 326.732646 -256.38506) (xy 326.732646 -256.432558)
			(xy 326.832722 -256.532634)
		)
		(stroke
			(width 0)
			(type solid)
		)
		(fill yes)
		(layer "In2.Cu")
		(net "M_C_CPU0_CLK_DN<0>")
	)
	(gr_poly
		(pts
			(xy 326.935846 -227.286058) (xy 326.984106 -227.153216) (xy 326.851264 -227.104702) (xy 326.810878 -227.123498)
			(xy 326.89546 -227.304854)
		)
		(stroke
			(width 0)
			(type solid)
		)
		(fill yes)
		(layer "In2.Cu")
		(net "M_C_CPU0_SA_DQ<9>")
	)
	(gr_poly
		(pts
			(xy 326.935846 -224.045526) (xy 326.984106 -223.912684) (xy 326.851264 -223.864424) (xy 326.810878 -223.88322)
			(xy 326.89546 -224.064322)
		)
		(stroke
			(width 0)
			(type solid)
		)
		(fill yes)
		(layer "In2.Cu")
		(net "M_C_CPU0_SA_DQ<5>")
	)
	(gr_poly
		(pts
			(xy 326.936608 -240.23193) (xy 326.936608 -240.18748) (xy 326.736456 -240.18748) (xy 326.736456 -240.23193)
			(xy 326.836532 -240.331752)
		)
		(stroke
			(width 0)
			(type solid)
		)
		(fill yes)
		(layer "In2.Cu")
		(net "M_C_CPU0_SA_DQ<26>")
	)
	(gr_poly
		(pts
			(xy 326.93991 -230.51516) (xy 326.976486 -230.378508) (xy 326.839834 -230.341932) (xy 326.798686 -230.365554)
			(xy 326.898762 -230.538782)
		)
		(stroke
			(width 0)
			(type solid)
		)
		(fill yes)
		(layer "In2.Cu")
		(net "M_C_CPU0_SA_DQS_DN<6>")
	)
	(gr_poly
		(pts
			(xy 326.93991 -228.895148) (xy 326.976486 -228.758496) (xy 326.839834 -228.72192) (xy 326.798686 -228.745542)
			(xy 326.898762 -228.91877)
		)
		(stroke
			(width 0)
			(type solid)
		)
		(fill yes)
		(layer "In2.Cu")
		(net "M_C_CPU0_SA_DQS_DP<1>")
	)
	(gr_poly
		(pts
			(xy 327.140316 -293.177214) (xy 327.101708 -293.154862) (xy 326.96531 -293.191438) (xy 327.001886 -293.32809)
			(xy 327.04024 -293.350442)
		)
		(stroke
			(width 0)
			(type solid)
		)
		(fill yes)
		(layer "In2.Cu")
		(net "M_C_CPU0_SB_DQ<28>")
	)
	(gr_poly
		(pts
			(xy 327.206864 -280.364946) (xy 327.206864 -280.320496) (xy 327.006966 -280.320496) (xy 327.006966 -280.364946)
			(xy 327.106788 -280.465022)
		)
		(stroke
			(width 0)
			(type solid)
		)
		(fill yes)
		(layer "In2.Cu")
		(net "M_C_CPU0_SB_DQ<11>")
	)
	(gr_poly
		(pts
			(xy 327.206864 -273.884898) (xy 327.206864 -273.840448) (xy 327.006966 -273.840448) (xy 327.006966 -273.884898)
			(xy 327.106788 -273.984974)
		)
		(stroke
			(width 0)
			(type solid)
		)
		(fill yes)
		(layer "In2.Cu")
		(net "M_C_CPU0_SB_CB<3>")
	)
	(gr_poly
		(pts
			(xy 327.206864 -264.164826) (xy 327.206864 -264.120376) (xy 327.006966 -264.120376) (xy 327.006966 -264.164826)
			(xy 327.106788 -264.264902)
		)
		(stroke
			(width 0)
			(type solid)
		)
		(fill yes)
		(layer "In2.Cu")
		(net "M_C_CPU0_SB_CA<5>")
	)
	(gr_poly
		(pts
			(xy 327.207626 -284.00756) (xy 327.10755 -283.907484) (xy 327.007474 -284.00756) (xy 327.007474 -284.05201)
			(xy 327.207626 -284.05201)
		)
		(stroke
			(width 0)
			(type solid)
		)
		(fill yes)
		(layer "In2.Cu")
		(net "M_C_CPU0_SB_DQ<16>")
	)
	(gr_poly
		(pts
			(xy 327.207626 -282.387548) (xy 327.10755 -282.287472) (xy 327.007474 -282.387548) (xy 327.007474 -282.431998)
			(xy 327.207626 -282.431998)
		)
		(stroke
			(width 0)
			(type solid)
		)
		(fill yes)
		(layer "In2.Cu")
		(net "M_C_CPU0_SB_DQ<12>")
	)
	(gr_poly
		(pts
			(xy 327.207626 -279.147524) (xy 327.10755 -279.047448) (xy 327.007474 -279.147524) (xy 327.007474 -279.191974)
			(xy 327.207626 -279.191974)
		)
		(stroke
			(width 0)
			(type solid)
		)
		(fill yes)
		(layer "In2.Cu")
		(net "M_C_CPU0_SB_DQ<8>")
	)
	(gr_poly
		(pts
			(xy 327.207626 -274.287488) (xy 327.10755 -274.187412) (xy 327.007474 -274.287488) (xy 327.007474 -274.331938)
			(xy 327.207626 -274.331938)
		)
		(stroke
			(width 0)
			(type solid)
		)
		(fill yes)
		(layer "In2.Cu")
		(net "M_C_CPU0_SB_DQ<0>")
	)
	(gr_poly
		(pts
			(xy 327.207626 -264.567416) (xy 327.10755 -264.46734) (xy 327.007474 -264.567416) (xy 327.007474 -264.611866)
			(xy 327.207626 -264.611866)
		)
		(stroke
			(width 0)
			(type solid)
		)
		(fill yes)
		(layer "In2.Cu")
		(net "M_C_CPU0_SB_CA<6>")
	)
	(gr_poly
		(pts
			(xy 327.208388 -262.947404) (xy 327.108312 -262.847328) (xy 327.008236 -262.947404) (xy 327.008236 -262.991854)
			(xy 327.208388 -262.991854)
		)
		(stroke
			(width 0)
			(type solid)
		)
		(fill yes)
		(layer "In2.Cu")
		(net "M_C_CPU0_SB_CA<2>")
	)
	(gr_poly
		(pts
			(xy 327.209658 -287.24733) (xy 327.109582 -287.147254) (xy 327.00976 -287.24733) (xy 327.00976 -287.29178)
			(xy 327.209658 -287.29178)
		)
		(stroke
			(width 0)
			(type solid)
		)
		(fill yes)
		(layer "In2.Cu")
		(net "M_C_CPU0_SB_DQ<20>")
	)
	(gr_poly
		(pts
			(xy 327.209658 -285.627318) (xy 327.109582 -285.527242) (xy 327.00976 -285.627318) (xy 327.00976 -285.67507)
			(xy 327.209658 -285.67507)
		)
		(stroke
			(width 0)
			(type solid)
		)
		(fill yes)
		(layer "In2.Cu")
		(net "M_C_CPU0_SB_DQS_DP<2>")
	)
	(gr_poly
		(pts
			(xy 327.209658 -271.04721) (xy 327.109582 -270.947134) (xy 327.00976 -271.04721) (xy 327.00976 -271.094962)
			(xy 327.209658 -271.094962)
		)
		(stroke
			(width 0)
			(type solid)
		)
		(fill yes)
		(layer "In2.Cu")
		(net "M_C_CPU0_SB_DQS_DP<9>")
	)
	(gr_poly
		(pts
			(xy 327.221088 -288.464244) (xy 327.221088 -288.419794) (xy 327.020936 -288.419794) (xy 327.020936 -288.464244)
			(xy 327.121012 -288.56432)
		)
		(stroke
			(width 0)
			(type solid)
		)
		(fill yes)
		(layer "In2.Cu")
		(net "M_C_CPU0_SB_DQ<23>")
	)
	(gr_poly
		(pts
			(xy 327.223882 -286.844232) (xy 327.223882 -286.79648) (xy 327.02373 -286.79648) (xy 327.02373 -286.844232)
			(xy 327.123806 -286.944308)
		)
		(stroke
			(width 0)
			(type solid)
		)
		(fill yes)
		(layer "In2.Cu")
		(net "M_C_CPU0_SB_DQS_DP<7>")
	)
	(gr_poly
		(pts
			(xy 327.223882 -285.22422) (xy 327.223882 -285.17977) (xy 327.02373 -285.17977) (xy 327.02373 -285.22422)
			(xy 327.123806 -285.324296)
		)
		(stroke
			(width 0)
			(type solid)
		)
		(fill yes)
		(layer "In2.Cu")
		(net "M_C_CPU0_SB_DQ<19>")
	)
	(gr_poly
		(pts
			(xy 327.223882 -283.604208) (xy 327.223882 -283.559758) (xy 327.02373 -283.559758) (xy 327.02373 -283.604208)
			(xy 327.123806 -283.704284)
		)
		(stroke
			(width 0)
			(type solid)
		)
		(fill yes)
		(layer "In2.Cu")
		(net "M_C_CPU0_SB_DQ<15>")
	)
	(gr_poly
		(pts
			(xy 327.223882 -278.744172) (xy 327.223882 -278.699722) (xy 327.02373 -278.699722) (xy 327.02373 -278.744172)
			(xy 327.123806 -278.844248)
		)
		(stroke
			(width 0)
			(type solid)
		)
		(fill yes)
		(layer "In2.Cu")
		(net "M_C_CPU0_SB_DQ<7>")
	)
	(gr_poly
		(pts
			(xy 327.223882 -275.504148) (xy 327.223882 -275.459698) (xy 327.02373 -275.459698) (xy 327.02373 -275.504148)
			(xy 327.123806 -275.604224)
		)
		(stroke
			(width 0)
			(type solid)
		)
		(fill yes)
		(layer "In2.Cu")
		(net "M_C_CPU0_SB_DQ<3>")
	)
	(gr_poly
		(pts
			(xy 327.223882 -265.784076) (xy 327.223882 -265.739626) (xy 327.02373 -265.739626) (xy 327.02373 -265.784076)
			(xy 327.123806 -265.884152)
		)
		(stroke
			(width 0)
			(type solid)
		)
		(fill yes)
		(layer "In2.Cu")
		(net "M_C_CPU0_SB_CS_N<0>")
	)
	(gr_poly
		(pts
			(xy 327.228962 -277.124414) (xy 327.228962 -277.076662) (xy 327.029064 -277.076662) (xy 327.029064 -277.124414)
			(xy 327.128886 -277.224236)
		)
		(stroke
			(width 0)
			(type solid)
		)
		(fill yes)
		(layer "In2.Cu")
		(net "M_C_CPU0_SB_DQS_DP<5>")
	)
	(gr_poly
		(pts
			(xy 327.228962 -272.264378) (xy 327.228962 -272.216626) (xy 327.029064 -272.216626) (xy 327.029064 -272.264378)
			(xy 327.128886 -272.3642)
		)
		(stroke
			(width 0)
			(type solid)
		)
		(fill yes)
		(layer "In2.Cu")
		(net "M_C_CPU0_SB_DQS_DP<4>")
	)
	(gr_poly
		(pts
			(xy 327.236582 -277.528274) (xy 327.136506 -277.428452) (xy 327.03643 -277.528274) (xy 327.03643 -277.572724)
			(xy 327.236582 -277.572724)
		)
		(stroke
			(width 0)
			(type solid)
		)
		(fill yes)
		(layer "In2.Cu")
		(net "M_C_CPU0_SB_DQ<4>")
	)
	(gr_poly
		(pts
			(xy 327.236582 -275.908262) (xy 327.136506 -275.808186) (xy 327.03643 -275.908262) (xy 327.03643 -275.95576)
			(xy 327.236582 -275.95576)
		)
		(stroke
			(width 0)
			(type solid)
		)
		(fill yes)
		(layer "In2.Cu")
		(net "M_C_CPU0_SB_DQS_DP<0>")
	)
	(gr_poly
		(pts
			(xy 327.236582 -272.668238) (xy 327.136506 -272.568416) (xy 327.03643 -272.668238) (xy 327.03643 -272.712688)
			(xy 327.236582 -272.712688)
		)
		(stroke
			(width 0)
			(type solid)
		)
		(fill yes)
		(layer "In2.Cu")
		(net "M_C_CPU0_SB_CB<0>")
	)
	(gr_poly
		(pts
			(xy 327.301606 -227.014786) (xy 327.217024 -226.833684) (xy 327.176638 -226.85248) (xy 327.128378 -226.985322)
			(xy 327.26122 -227.033582)
		)
		(stroke
			(width 0)
			(type solid)
		)
		(fill yes)
		(layer "In2.Cu")
		(net "M_C_CPU0_SA_DQ<10>")
	)
	(gr_poly
		(pts
			(xy 327.310242 -223.772476) (xy 327.210166 -223.599248) (xy 327.171812 -223.6216) (xy 327.134982 -223.757998)
			(xy 327.271634 -223.794828)
		)
		(stroke
			(width 0)
			(type solid)
		)
		(fill yes)
		(layer "In2.Cu")
		(net "M_C_CPU0_SA_DQ<6>")
	)
	(gr_poly
		(pts
			(xy 327.311512 -225.39579) (xy 327.21169 -225.222562) (xy 327.173082 -225.244914) (xy 327.136506 -225.381566)
			(xy 327.273158 -225.418142)
		)
		(stroke
			(width 0)
			(type solid)
		)
		(fill yes)
		(layer "In2.Cu")
		(net "M_C_CPU0_SA_DQ<7>")
	)
	(gr_poly
		(pts
			(xy 327.311766 -228.635306) (xy 327.21169 -228.462078) (xy 327.173082 -228.48443) (xy 327.136506 -228.620828)
			(xy 327.273158 -228.657658)
		)
		(stroke
			(width 0)
			(type solid)
		)
		(fill yes)
		(layer "In2.Cu")
		(net "M_C_CPU0_SA_DQ<11>")
	)
	(gr_poly
		(pts
			(xy 327.313798 -230.252524) (xy 327.213722 -230.079296) (xy 327.172574 -230.103172) (xy 327.135998 -230.239824)
			(xy 327.27265 -230.2764)
		)
		(stroke
			(width 0)
			(type solid)
		)
		(fill yes)
		(layer "In2.Cu")
		(net "M_C_CPU0_SA_DQS_DN<1>")
	)
	(gr_poly
		(pts
			(xy 327.314052 -231.873298) (xy 327.21423 -231.70007) (xy 327.172828 -231.723946) (xy 327.136252 -231.860598)
			(xy 327.272904 -231.897174)
		)
		(stroke
			(width 0)
			(type solid)
		)
		(fill yes)
		(layer "In2.Cu")
		(net "M_C_CPU0_SA_DQS_DP<6>")
	)
	(gr_poly
		(pts
			(xy 327.378568 -255.622044) (xy 327.378568 -255.577594) (xy 327.178416 -255.577594) (xy 327.178416 -255.622044)
			(xy 327.278492 -255.72212)
		)
		(stroke
			(width 0)
			(type solid)
		)
		(fill yes)
		(layer "In2.Cu")
		(net "M_C_CPU0_SA_PAR")
	)
	(gr_poly
		(pts
			(xy 327.378568 -254.002032) (xy 327.378568 -253.957582) (xy 327.178416 -253.957582) (xy 327.178416 -254.002032)
			(xy 327.278492 -254.102108)
		)
		(stroke
			(width 0)
			(type solid)
		)
		(fill yes)
		(layer "In2.Cu")
		(net "M_C_CPU0_SA_CA<3>")
	)
	(gr_poly
		(pts
			(xy 327.378568 -252.38202) (xy 327.378568 -252.33757) (xy 327.178416 -252.33757) (xy 327.178416 -252.38202)
			(xy 327.278492 -252.482096)
		)
		(stroke
			(width 0)
			(type solid)
		)
		(fill yes)
		(layer "In2.Cu")
		(net "M_C_CPU0_SA_CS_N<1>")
	)
	(gr_poly
		(pts
			(xy 327.378568 -249.141996) (xy 327.378568 -249.097546) (xy 327.178416 -249.097546) (xy 327.178416 -249.141996)
			(xy 327.278492 -249.242072)
		)
		(stroke
			(width 0)
			(type solid)
		)
		(fill yes)
		(layer "In2.Cu")
		(net "M_C_CPU0_SA_CB<7>")
	)
	(gr_poly
		(pts
			(xy 327.378568 -247.522238) (xy 327.378568 -247.47474) (xy 327.17867 -247.47474) (xy 327.17867 -247.522238)
			(xy 327.278492 -247.622314)
		)
		(stroke
			(width 0)
			(type solid)
		)
		(fill yes)
		(layer "In2.Cu")
		(net "M_C_CPU0_SA_DQS_DP<9>")
	)
	(gr_poly
		(pts
			(xy 327.378568 -245.901972) (xy 327.378568 -245.857522) (xy 327.178416 -245.857522) (xy 327.178416 -245.901972)
			(xy 327.278492 -246.002048)
		)
		(stroke
			(width 0)
			(type solid)
		)
		(fill yes)
		(layer "In2.Cu")
		(net "M_C_CPU0_SA_CB<3>")
	)
	(gr_poly
		(pts
			(xy 327.378568 -244.28196) (xy 327.378568 -244.23751) (xy 327.178416 -244.23751) (xy 327.178416 -244.28196)
			(xy 327.278492 -244.382036)
		)
		(stroke
			(width 0)
			(type solid)
		)
		(fill yes)
		(layer "In2.Cu")
		(net "M_C_CPU0_SA_DQ<31>")
	)
	(gr_poly
		(pts
			(xy 327.378568 -241.041936) (xy 327.378568 -240.997486) (xy 327.178416 -240.997486) (xy 327.178416 -241.041936)
			(xy 327.278492 -241.142012)
		)
		(stroke
			(width 0)
			(type solid)
		)
		(fill yes)
		(layer "In2.Cu")
		(net "M_C_CPU0_SA_DQ<27>")
	)
	(gr_poly
		(pts
			(xy 327.382378 -256.02565) (xy 327.282556 -255.925828) (xy 327.18248 -256.02565) (xy 327.18248 -256.073402)
			(xy 327.382378 -256.073402)
		)
		(stroke
			(width 0)
			(type solid)
		)
		(fill yes)
		(layer "In2.Cu")
		(net "M_C_CPU0_CLK_DP<0>")
	)
	(gr_poly
		(pts
			(xy 327.391268 -250.762262) (xy 327.391268 -250.717812) (xy 327.191116 -250.717812) (xy 327.191116 -250.762262)
			(xy 327.291192 -250.862338)
		)
		(stroke
			(width 0)
			(type solid)
		)
		(fill yes)
		(layer "In2.Cu")
		(net "M_C_CPU0_RESET_N")
	)
	(gr_poly
		(pts
			(xy 327.391268 -241.445796) (xy 327.291192 -241.345974) (xy 327.191116 -241.445796) (xy 327.191116 -241.493548)
			(xy 327.391268 -241.493548)
		)
		(stroke
			(width 0)
			(type solid)
		)
		(fill yes)
		(layer "In2.Cu")
		(net "M_C_CPU0_SA_DQS_DP<3>")
	)
	(gr_poly
		(pts
			(xy 327.398888 -254.405892) (xy 327.298812 -254.30607) (xy 327.19899 -254.405892) (xy 327.19899 -254.450342)
			(xy 327.398888 -254.450342)
		)
		(stroke
			(width 0)
			(type solid)
		)
		(fill yes)
		(layer "In2.Cu")
		(net "M_C_CPU0_SA_CA<4>")
	)
	(gr_poly
		(pts
			(xy 327.398888 -252.78588) (xy 327.298812 -252.685804) (xy 327.19899 -252.78588) (xy 327.19899 -252.83033)
			(xy 327.398888 -252.83033)
		)
		(stroke
			(width 0)
			(type solid)
		)
		(fill yes)
		(layer "In2.Cu")
		(net "M_C_CPU0_SA_CA<0>")
	)
	(gr_poly
		(pts
			(xy 327.398888 -247.925844) (xy 327.298812 -247.825768) (xy 327.19899 -247.925844) (xy 327.19899 -247.970294)
			(xy 327.398888 -247.970294)
		)
		(stroke
			(width 0)
			(type solid)
		)
		(fill yes)
		(layer "In2.Cu")
		(net "M_C_CPU0_SA_CB<4>")
	)
	(gr_poly
		(pts
			(xy 327.398888 -246.305578) (xy 327.298812 -246.205756) (xy 327.198736 -246.305578) (xy 327.198736 -246.35333)
			(xy 327.398888 -246.35333)
		)
		(stroke
			(width 0)
			(type solid)
		)
		(fill yes)
		(layer "In2.Cu")
		(net "M_C_CPU0_SA_DQS_DP<4>")
	)
	(gr_poly
		(pts
			(xy 327.398888 -244.68582) (xy 327.298812 -244.585744) (xy 327.19899 -244.68582) (xy 327.19899 -244.73027)
			(xy 327.398888 -244.73027)
		)
		(stroke
			(width 0)
			(type solid)
		)
		(fill yes)
		(layer "In2.Cu")
		(net "M_C_CPU0_SA_CB<0>")
	)
	(gr_poly
		(pts
			(xy 327.398888 -243.065808) (xy 327.298812 -242.965732) (xy 327.19899 -243.065808) (xy 327.19899 -243.110258)
			(xy 327.398888 -243.110258)
		)
		(stroke
			(width 0)
			(type solid)
		)
		(fill yes)
		(layer "In2.Cu")
		(net "M_C_CPU0_SA_DQ<28>")
	)
	(gr_poly
		(pts
			(xy 327.405746 -239.825276) (xy 327.30567 -239.7252) (xy 327.205848 -239.825276) (xy 327.205848 -239.869472)
			(xy 327.405746 -239.869472)
		)
		(stroke
			(width 0)
			(type solid)
		)
		(fill yes)
		(layer "In2.Cu")
		(net "M_C_CPU0_SA_DQ<24>")
	)
	(gr_poly
		(pts
			(xy 327.405746 -224.856294) (xy 327.454006 -224.723452) (xy 327.321164 -224.674938) (xy 327.281032 -224.693734)
			(xy 327.365614 -224.87509)
		)
		(stroke
			(width 0)
			(type solid)
		)
		(fill yes)
		(layer "In2.Cu")
		(net "M_C_CPU0_SA_DQ<5>")
	)
	(gr_poly
		(pts
			(xy 327.407016 -242.662202) (xy 327.407016 -242.614704) (xy 327.207118 -242.614704) (xy 327.207118 -242.662202)
			(xy 327.307194 -242.762278)
		)
		(stroke
			(width 0)
			(type solid)
		)
		(fill yes)
		(layer "In2.Cu")
		(net "M_C_CPU0_SA_DQS_DP<8>")
	)
	(gr_poly
		(pts
			(xy 327.409302 -226.462844) (xy 327.445878 -226.326192) (xy 327.30948 -226.289616) (xy 327.270872 -226.311714)
			(xy 327.370948 -226.484942)
		)
		(stroke
			(width 0)
			(type solid)
		)
		(fill yes)
		(layer "In2.Cu")
		(net "M_C_CPU0_SA_DQ<8>")
	)
	(gr_poly
		(pts
			(xy 327.409556 -231.32415) (xy 327.446132 -231.187498) (xy 327.30948 -231.150922) (xy 327.268332 -231.174798)
			(xy 327.368154 -231.348026)
		)
		(stroke
			(width 0)
			(type solid)
		)
		(fill yes)
		(layer "In2.Cu")
		(net "M_C_CPU0_SA_DQS_DN<6>")
	)
	(gr_poly
		(pts
			(xy 327.40981 -229.704138) (xy 327.446386 -229.567486) (xy 327.309734 -229.53091) (xy 327.268586 -229.554786)
			(xy 327.368408 -229.728014)
		)
		(stroke
			(width 0)
			(type solid)
		)
		(fill yes)
		(layer "In2.Cu")
		(net "M_C_CPU0_SA_DQS_DP<1>")
	)
	(gr_poly
		(pts
			(xy 327.40981 -228.08565) (xy 327.446386 -227.948998) (xy 327.309734 -227.912422) (xy 327.27138 -227.93452)
			(xy 327.371456 -228.107748)
		)
		(stroke
			(width 0)
			(type solid)
		)
		(fill yes)
		(layer "In2.Cu")
		(net "M_C_CPU0_SA_DQ<9>")
	)
	(gr_poly
		(pts
			(xy 327.410064 -223.225614) (xy 327.44664 -223.088962) (xy 327.309988 -223.052386) (xy 327.271634 -223.074738)
			(xy 327.371456 -223.247966)
		)
		(stroke
			(width 0)
			(type solid)
		)
		(fill yes)
		(layer "In2.Cu")
		(net "M_C_CPU0_SA_DQ<4>")
	)
	(gr_poly
		(pts
			(xy 327.595738 -262.080756) (xy 327.525126 -261.958328) (xy 327.402698 -262.02894) (xy 327.391014 -262.071866)
			(xy 327.584308 -262.123682)
		)
		(stroke
			(width 0)
			(type solid)
		)
		(fill yes)
		(layer "In2.Cu")
		(net "M_C_CPU0_SB_CA<0>")
	)
	(gr_poly
		(pts
			(xy 327.62063 -292.349174) (xy 327.582276 -292.326822) (xy 327.445624 -292.363398) (xy 327.4822 -292.50005)
			(xy 327.520808 -292.522402)
		)
		(stroke
			(width 0)
			(type solid)
		)
		(fill yes)
		(layer "In2.Cu")
		(net "M_C_CPU0_SB_DQ<28>")
	)
	(gr_poly
		(pts
			(xy 327.677526 -287.653984) (xy 327.677526 -287.609534) (xy 327.477374 -287.609534) (xy 327.477374 -287.653984)
			(xy 327.57745 -287.75406)
		)
		(stroke
			(width 0)
			(type solid)
		)
		(fill yes)
		(layer "In2.Cu")
		(net "M_C_CPU0_SB_DQ<22>")
	)
	(gr_poly
		(pts
			(xy 327.678796 -279.958292) (xy 327.57872 -279.858216) (xy 327.478644 -279.958292) (xy 327.478644 -280.002742)
			(xy 327.678796 -280.002742)
		)
		(stroke
			(width 0)
			(type solid)
		)
		(fill yes)
		(layer "In2.Cu")
		(net "M_C_CPU0_SB_DQ<9>")
	)
	(gr_poly
		(pts
			(xy 327.678796 -273.478244) (xy 327.57872 -273.378168) (xy 327.478644 -273.478244) (xy 327.478644 -273.522694)
			(xy 327.678796 -273.522694)
		)
		(stroke
			(width 0)
			(type solid)
		)
		(fill yes)
		(layer "In2.Cu")
		(net "M_C_CPU0_SB_CB<1>")
	)
	(gr_poly
		(pts
			(xy 327.678796 -263.758172) (xy 327.57872 -263.658096) (xy 327.478644 -263.758172) (xy 327.478644 -263.802622)
			(xy 327.678796 -263.802622)
		)
		(stroke
			(width 0)
			(type solid)
		)
		(fill yes)
		(layer "In2.Cu")
		(net "M_C_CPU0_SB_CA<4>")
	)
	(gr_poly
		(pts
			(xy 327.679558 -284.41396) (xy 327.679558 -284.369764) (xy 327.47966 -284.369764) (xy 327.47966 -284.41396)
			(xy 327.579482 -284.514036)
		)
		(stroke
			(width 0)
			(type solid)
		)
		(fill yes)
		(layer "In2.Cu")
		(net "M_C_CPU0_SB_DQ<18>")
	)
	(gr_poly
		(pts
			(xy 327.679558 -282.793948) (xy 327.679558 -282.749752) (xy 327.47966 -282.749752) (xy 327.47966 -282.793948)
			(xy 327.579482 -282.894024)
		)
		(stroke
			(width 0)
			(type solid)
		)
		(fill yes)
		(layer "In2.Cu")
		(net "M_C_CPU0_SB_DQ<14>")
	)
	(gr_poly
		(pts
			(xy 327.679558 -279.553924) (xy 327.679558 -279.509728) (xy 327.47966 -279.509728) (xy 327.47966 -279.553924)
			(xy 327.579482 -279.654)
		)
		(stroke
			(width 0)
			(type solid)
		)
		(fill yes)
		(layer "In2.Cu")
		(net "M_C_CPU0_SB_DQ<10>")
	)
	(gr_poly
		(pts
			(xy 327.679558 -274.693888) (xy 327.679558 -274.649692) (xy 327.47966 -274.649692) (xy 327.47966 -274.693888)
			(xy 327.579482 -274.793964)
		)
		(stroke
			(width 0)
			(type solid)
		)
		(fill yes)
		(layer "In2.Cu")
		(net "M_C_CPU0_SB_DQ<2>")
	)
	(gr_poly
		(pts
			(xy 327.679558 -266.593828) (xy 327.679558 -266.549632) (xy 327.47966 -266.549632) (xy 327.47966 -266.593828)
			(xy 327.579482 -266.693904)
		)
		(stroke
			(width 0)
			(type solid)
		)
		(fill yes)
		(layer "In2.Cu")
		(net "M_C_CPU0_SB_CS_N<1>")
	)
	(gr_poly
		(pts
			(xy 327.679558 -264.973816) (xy 327.679558 -264.92962) (xy 327.47966 -264.92962) (xy 327.47966 -264.973816)
			(xy 327.579482 -265.073892)
		)
		(stroke
			(width 0)
			(type solid)
		)
		(fill yes)
		(layer "In2.Cu")
		(net "M_C_CPU0_SB_PAR")
	)
	(gr_poly
		(pts
			(xy 327.680574 -263.353804) (xy 327.680574 -263.309354) (xy 327.480422 -263.309354) (xy 327.480422 -263.353804)
			(xy 327.580498 -263.45388)
		)
		(stroke
			(width 0)
			(type solid)
		)
		(fill yes)
		(layer "In2.Cu")
		(net "M_C_CPU0_SB_CA<3>")
	)
	(gr_poly
		(pts
			(xy 327.691242 -288.057844) (xy 327.591166 -287.957768) (xy 327.49109 -288.057844) (xy 327.49109 -288.102294)
			(xy 327.691242 -288.102294)
		)
		(stroke
			(width 0)
			(type solid)
		)
		(fill yes)
		(layer "In2.Cu")
		(net "M_C_CPU0_SB_DQ<21>")
	)
	(gr_poly
		(pts
			(xy 327.698862 -286.437578) (xy 327.598786 -286.337756) (xy 327.498964 -286.437578) (xy 327.498964 -286.48533)
			(xy 327.698862 -286.48533)
		)
		(stroke
			(width 0)
			(type solid)
		)
		(fill yes)
		(layer "In2.Cu")
		(net "M_C_CPU0_SB_DQS_DN<7>")
	)
	(gr_poly
		(pts
			(xy 327.698862 -284.81782) (xy 327.598786 -284.717744) (xy 327.498964 -284.81782) (xy 327.498964 -284.86227)
			(xy 327.698862 -284.86227)
		)
		(stroke
			(width 0)
			(type solid)
		)
		(fill yes)
		(layer "In2.Cu")
		(net "M_C_CPU0_SB_DQ<17>")
	)
	(gr_poly
		(pts
			(xy 327.698862 -283.197808) (xy 327.598786 -283.097732) (xy 327.498964 -283.197808) (xy 327.498964 -283.242258)
			(xy 327.698862 -283.242258)
		)
		(stroke
			(width 0)
			(type solid)
		)
		(fill yes)
		(layer "In2.Cu")
		(net "M_C_CPU0_SB_DQ<13>")
	)
	(gr_poly
		(pts
			(xy 327.698862 -278.337772) (xy 327.598786 -278.237696) (xy 327.498964 -278.337772) (xy 327.498964 -278.382222)
			(xy 327.698862 -278.382222)
		)
		(stroke
			(width 0)
			(type solid)
		)
		(fill yes)
		(layer "In2.Cu")
		(net "M_C_CPU0_SB_DQ<5>")
	)
	(gr_poly
		(pts
			(xy 327.698862 -276.717506) (xy 327.598786 -276.617684) (xy 327.498964 -276.717506) (xy 327.498964 -276.765258)
			(xy 327.698862 -276.765258)
		)
		(stroke
			(width 0)
			(type solid)
		)
		(fill yes)
		(layer "In2.Cu")
		(net "M_C_CPU0_SB_DQS_DN<5>")
	)
	(gr_poly
		(pts
			(xy 327.698862 -275.097748) (xy 327.598786 -274.997672) (xy 327.498964 -275.097748) (xy 327.498964 -275.142198)
			(xy 327.698862 -275.142198)
		)
		(stroke
			(width 0)
			(type solid)
		)
		(fill yes)
		(layer "In2.Cu")
		(net "M_C_CPU0_SB_DQ<1>")
	)
	(gr_poly
		(pts
			(xy 327.698862 -271.85747) (xy 327.598786 -271.757648) (xy 327.498964 -271.85747) (xy 327.498964 -271.905222)
			(xy 327.698862 -271.905222)
		)
		(stroke
			(width 0)
			(type solid)
		)
		(fill yes)
		(layer "In2.Cu")
		(net "M_C_CPU0_SB_DQS_DN<4>")
	)
	(gr_poly
		(pts
			(xy 327.70572 -277.934928) (xy 327.70572 -277.890732) (xy 327.505822 -277.890732) (xy 327.505822 -277.934928)
			(xy 327.605644 -278.035004)
		)
		(stroke
			(width 0)
			(type solid)
		)
		(fill yes)
		(layer "In2.Cu")
		(net "M_C_CPU0_SB_DQ<6>")
	)
	(gr_poly
		(pts
			(xy 327.70572 -276.31517) (xy 327.70572 -276.267672) (xy 327.505822 -276.267672) (xy 327.505822 -276.31517)
			(xy 327.605644 -276.415246)
		)
		(stroke
			(width 0)
			(type solid)
		)
		(fill yes)
		(layer "In2.Cu")
		(net "M_C_CPU0_SB_DQS_DN<0>")
	)
	(gr_poly
		(pts
			(xy 327.70572 -273.074892) (xy 327.70572 -273.030696) (xy 327.505822 -273.030696) (xy 327.505822 -273.074892)
			(xy 327.605644 -273.174968)
		)
		(stroke
			(width 0)
			(type solid)
		)
		(fill yes)
		(layer "In2.Cu")
		(net "M_C_CPU0_SB_CB<2>")
	)
	(gr_poly
		(pts
			(xy 327.70572 -269.833852) (xy 327.70572 -269.789656) (xy 327.505822 -269.789656) (xy 327.505822 -269.833852)
			(xy 327.605898 -269.933928)
		)
		(stroke
			(width 0)
			(type solid)
		)
		(fill yes)
		(layer "In2.Cu")
		(net "M_C_CPU0_SB_CB<6>")
	)
	(gr_poly
		(pts
			(xy 327.746614 -294.67175) (xy 327.710038 -294.535098) (xy 327.67143 -294.513) (xy 327.571354 -294.686228)
			(xy 327.609962 -294.708326)
		)
		(stroke
			(width 0)
			(type solid)
		)
		(fill yes)
		(layer "In2.Cu")
		(net "M_C_CPU0_SB_DQ<30>")
	)
	(gr_poly
		(pts
			(xy 327.781158 -227.824284) (xy 327.681082 -227.650802) (xy 327.642728 -227.673154) (xy 327.606152 -227.809806)
			(xy 327.74255 -227.846382)
		)
		(stroke
			(width 0)
			(type solid)
		)
		(fill yes)
		(layer "In2.Cu")
		(net "M_C_CPU0_SA_DQ<10>")
	)
	(gr_poly
		(pts
			(xy 327.781412 -229.444804) (xy 327.681336 -229.271576) (xy 327.642982 -229.293674) (xy 327.606406 -229.430326)
			(xy 327.743058 -229.466902)
		)
		(stroke
			(width 0)
			(type solid)
		)
		(fill yes)
		(layer "In2.Cu")
		(net "M_C_CPU0_SA_DQ<11>")
	)
	(gr_poly
		(pts
			(xy 327.781412 -226.20478) (xy 327.68159 -226.031552) (xy 327.642982 -226.053904) (xy 327.606406 -226.190302)
			(xy 327.743058 -226.227132)
		)
		(stroke
			(width 0)
			(type solid)
		)
		(fill yes)
		(layer "In2.Cu")
		(net "M_C_CPU0_SA_DQ<7>")
	)
	(gr_poly
		(pts
			(xy 327.781412 -224.584514) (xy 327.681336 -224.411286) (xy 327.642728 -224.433384) (xy 327.606152 -224.570036)
			(xy 327.742804 -224.606612)
		)
		(stroke
			(width 0)
			(type solid)
		)
		(fill yes)
		(layer "In2.Cu")
		(net "M_C_CPU0_SA_DQ<6>")
	)
	(gr_poly
		(pts
			(xy 327.78319 -232.682034) (xy 327.683368 -232.508806) (xy 327.641966 -232.532682) (xy 327.60539 -232.66908)
			(xy 327.742042 -232.705656)
		)
		(stroke
			(width 0)
			(type solid)
		)
		(fill yes)
		(layer "In2.Cu")
		(net "M_C_CPU0_SA_DQS_DP<6>")
	)
	(gr_poly
		(pts
			(xy 327.783444 -231.062276) (xy 327.683622 -230.889048) (xy 327.64222 -230.91267) (xy 327.605644 -231.049322)
			(xy 327.742296 -231.085898)
		)
		(stroke
			(width 0)
			(type solid)
		)
		(fill yes)
		(layer "In2.Cu")
		(net "M_C_CPU0_SA_DQS_DN<1>")
	)
	(gr_poly
		(pts
			(xy 327.784206 -222.962724) (xy 327.68413 -222.789496) (xy 327.642982 -222.813372) (xy 327.606406 -222.950024)
			(xy 327.742804 -222.9866)
		)
		(stroke
			(width 0)
			(type solid)
		)
		(fill yes)
		(layer "In2.Cu")
		(net "M_C_CPU0_SA_DQS_DP<5>")
	)
	(gr_poly
		(pts
			(xy 327.841356 -240.2332) (xy 327.841356 -240.188496) (xy 327.641458 -240.188496) (xy 327.641458 -240.2332)
			(xy 327.741534 -240.333022)
		)
		(stroke
			(width 0)
			(type solid)
		)
		(fill yes)
		(layer "In2.Cu")
		(net "M_C_CPU0_SA_DQ<26>")
	)
	(gr_poly
		(pts
			(xy 327.852278 -254.812546) (xy 327.852278 -254.768096) (xy 327.65238 -254.768096) (xy 327.65238 -254.812546)
			(xy 327.752456 -254.912368)
		)
		(stroke
			(width 0)
			(type solid)
		)
		(fill yes)
		(layer "In2.Cu")
		(net "M_C_CPU0_SA_CA<5>")
	)
	(gr_poly
		(pts
			(xy 327.852278 -253.192534) (xy 327.852278 -253.148084) (xy 327.65238 -253.148084) (xy 327.65238 -253.192534)
			(xy 327.752456 -253.292356)
		)
		(stroke
			(width 0)
			(type solid)
		)
		(fill yes)
		(layer "In2.Cu")
		(net "M_C_CPU0_SA_CA<1>")
	)
	(gr_poly
		(pts
			(xy 327.852278 -251.572522) (xy 327.852278 -251.528072) (xy 327.65238 -251.528072) (xy 327.65238 -251.572522)
			(xy 327.752456 -251.672344)
		)
		(stroke
			(width 0)
			(type solid)
		)
		(fill yes)
		(layer "In2.Cu")
		(net "M_C_CPU0_SA_CS_N<0>")
	)
	(gr_poly
		(pts
			(xy 327.852278 -248.332498) (xy 327.852278 -248.288048) (xy 327.65238 -248.288048) (xy 327.65238 -248.332498)
			(xy 327.752456 -248.43232)
		)
		(stroke
			(width 0)
			(type solid)
		)
		(fill yes)
		(layer "In2.Cu")
		(net "M_C_CPU0_SA_CB<6>")
	)
	(gr_poly
		(pts
			(xy 327.852278 -246.712486) (xy 327.852278 -246.664988) (xy 327.65238 -246.664988) (xy 327.65238 -246.712486)
			(xy 327.752202 -246.812562)
		)
		(stroke
			(width 0)
			(type solid)
		)
		(fill yes)
		(layer "In2.Cu")
		(net "M_C_CPU0_SA_DQS_DN<4>")
	)
	(gr_poly
		(pts
			(xy 327.852278 -245.092474) (xy 327.852278 -245.048024) (xy 327.65238 -245.048024) (xy 327.65238 -245.092474)
			(xy 327.752456 -245.192296)
		)
		(stroke
			(width 0)
			(type solid)
		)
		(fill yes)
		(layer "In2.Cu")
		(net "M_C_CPU0_SA_CB<2>")
	)
	(gr_poly
		(pts
			(xy 327.852278 -243.472462) (xy 327.852278 -243.428012) (xy 327.65238 -243.428012) (xy 327.65238 -243.472462)
			(xy 327.752456 -243.572284)
		)
		(stroke
			(width 0)
			(type solid)
		)
		(fill yes)
		(layer "In2.Cu")
		(net "M_C_CPU0_SA_DQ<30>")
	)
	(gr_poly
		(pts
			(xy 327.852278 -236.992668) (xy 327.852278 -236.944916) (xy 327.65238 -236.944916) (xy 327.65238 -236.992668)
			(xy 327.752456 -237.09249)
		)
		(stroke
			(width 0)
			(type solid)
		)
		(fill yes)
		(layer "In2.Cu")
		(net "M_C_CPU0_SA_DQS_DN<2>")
	)
	(gr_poly
		(pts
			(xy 327.854818 -235.372148) (xy 327.854818 -235.327698) (xy 327.65492 -235.327698) (xy 327.65492 -235.372148)
			(xy 327.754996 -235.472224)
		)
		(stroke
			(width 0)
			(type solid)
		)
		(fill yes)
		(layer "In2.Cu")
		(net "M_C_CPU0_SA_DQ<18>")
	)
	(gr_poly
		(pts
			(xy 327.861168 -256.432558) (xy 327.861168 -256.384806) (xy 327.661016 -256.384806) (xy 327.661016 -256.432558)
			(xy 327.761092 -256.53238)
		)
		(stroke
			(width 0)
			(type solid)
		)
		(fill yes)
		(layer "In2.Cu")
		(net "M_C_CPU0_CLK_DN<0>")
	)
	(gr_poly
		(pts
			(xy 327.861168 -250.356116) (xy 327.761092 -250.25604) (xy 327.661016 -250.356116) (xy 327.661016 -250.400566)
			(xy 327.861168 -250.400566)
		)
		(stroke
			(width 0)
			(type solid)
		)
		(fill yes)
		(layer "In2.Cu")
		(net "M_C_CPU0_ALERT_R_N")
	)
	(gr_poly
		(pts
			(xy 327.861168 -242.255802) (xy 327.761092 -242.15598) (xy 327.661016 -242.255802) (xy 327.661016 -242.303554)
			(xy 327.861168 -242.303554)
		)
		(stroke
			(width 0)
			(type solid)
		)
		(fill yes)
		(layer "In2.Cu")
		(net "M_C_CPU0_SA_DQS_DN<8>")
	)
	(gr_poly
		(pts
			(xy 327.861168 -241.85245) (xy 327.861168 -241.804698) (xy 327.661016 -241.804698) (xy 327.661016 -241.85245)
			(xy 327.761092 -241.952272)
		)
		(stroke
			(width 0)
			(type solid)
		)
		(fill yes)
		(layer "In2.Cu")
		(net "M_C_CPU0_SA_DQS_DN<3>")
	)
	(gr_poly
		(pts
			(xy 327.875646 -227.285042) (xy 327.92416 -227.1522) (xy 327.791318 -227.103686) (xy 327.750932 -227.122482)
			(xy 327.835514 -227.303838)
		)
		(stroke
			(width 0)
			(type solid)
		)
		(fill yes)
		(layer "In2.Cu")
		(net "M_C_CPU0_SA_DQ<8>")
	)
	(gr_poly
		(pts
			(xy 327.876916 -247.116092) (xy 327.777094 -247.016016) (xy 327.677018 -247.116092) (xy 327.677018 -247.163844)
			(xy 327.876916 -247.163844)
		)
		(stroke
			(width 0)
			(type solid)
		)
		(fill yes)
		(layer "In2.Cu")
		(net "M_C_CPU0_SA_DQS_DN<9>")
	)
	(gr_poly
		(pts
			(xy 327.87717 -255.216406) (xy 327.777094 -255.11633) (xy 327.677018 -255.216406) (xy 327.677018 -255.260856)
			(xy 327.87717 -255.260856)
		)
		(stroke
			(width 0)
			(type solid)
		)
		(fill yes)
		(layer "In2.Cu")
		(net "M_C_CPU0_SA_CA<6>")
	)
	(gr_poly
		(pts
			(xy 327.87717 -253.596394) (xy 327.777094 -253.496318) (xy 327.677018 -253.596394) (xy 327.677018 -253.640844)
			(xy 327.87717 -253.640844)
		)
		(stroke
			(width 0)
			(type solid)
		)
		(fill yes)
		(layer "In2.Cu")
		(net "M_C_CPU0_SA_CA<2>")
	)
	(gr_poly
		(pts
			(xy 327.87717 -248.736358) (xy 327.777094 -248.636282) (xy 327.677018 -248.736358) (xy 327.677018 -248.780808)
			(xy 327.87717 -248.780808)
		)
		(stroke
			(width 0)
			(type solid)
		)
		(fill yes)
		(layer "In2.Cu")
		(net "M_C_CPU0_SA_CB<5>")
	)
	(gr_poly
		(pts
			(xy 327.87717 -245.496334) (xy 327.777094 -245.396258) (xy 327.677018 -245.496334) (xy 327.677018 -245.540784)
			(xy 327.87717 -245.540784)
		)
		(stroke
			(width 0)
			(type solid)
		)
		(fill yes)
		(layer "In2.Cu")
		(net "M_C_CPU0_SA_CB<1>")
	)
	(gr_poly
		(pts
			(xy 327.87717 -243.876322) (xy 327.777094 -243.776246) (xy 327.677018 -243.876322) (xy 327.677018 -243.920772)
			(xy 327.87717 -243.920772)
		)
		(stroke
			(width 0)
			(type solid)
		)
		(fill yes)
		(layer "In2.Cu")
		(net "M_C_CPU0_SA_DQ<29>")
	)
	(gr_poly
		(pts
			(xy 327.87717 -240.636298) (xy 327.777094 -240.536222) (xy 327.677018 -240.636298) (xy 327.677018 -240.680748)
			(xy 327.87717 -240.680748)
		)
		(stroke
			(width 0)
			(type solid)
		)
		(fill yes)
		(layer "In2.Cu")
		(net "M_C_CPU0_SA_DQ<25>")
	)
	(gr_poly
		(pts
			(xy 327.87844 -225.652838) (xy 327.915016 -225.516186) (xy 327.778364 -225.47961) (xy 327.739756 -225.501708)
			(xy 327.839832 -225.674936)
		)
		(stroke
			(width 0)
			(type solid)
		)
		(fill yes)
		(layer "In2.Cu")
		(net "M_C_CPU0_SA_DQ<5>")
	)
	(gr_poly
		(pts
			(xy 327.879964 -230.514906) (xy 327.91654 -230.378254) (xy 327.779888 -230.341678) (xy 327.73874 -230.365554)
			(xy 327.838816 -230.538782)
		)
		(stroke
			(width 0)
			(type solid)
		)
		(fill yes)
		(layer "In2.Cu")
		(net "M_C_CPU0_SA_DQS_DP<1>")
	)
	(gr_poly
		(pts
			(xy 327.880472 -232.135426) (xy 327.917048 -231.999028) (xy 327.780396 -231.962452) (xy 327.739248 -231.986074)
			(xy 327.83907 -232.159302)
		)
		(stroke
			(width 0)
			(type solid)
		)
		(fill yes)
		(layer "In2.Cu")
		(net "M_C_CPU0_SA_DQS_DN<6>")
	)
	(gr_poly
		(pts
			(xy 327.880472 -224.03562) (xy 327.917048 -223.898968) (xy 327.780396 -223.862392) (xy 327.742042 -223.884744)
			(xy 327.841864 -224.057972)
		)
		(stroke
			(width 0)
			(type solid)
		)
		(fill yes)
		(layer "In2.Cu")
		(net "M_C_CPU0_SA_DQ<4>")
	)
	(gr_poly
		(pts
			(xy 327.915016 -233.74096) (xy 327.911206 -233.696764) (xy 327.711816 -233.714036) (xy 327.71588 -233.758486)
			(xy 327.824084 -233.849418)
		)
		(stroke
			(width 0)
			(type solid)
		)
		(fill yes)
		(layer "In2.Cu")
		(net "M_C_CPU0_SA_DQ<14>")
	)
	(gr_poly
		(pts
			(xy 328.081386 -294.795702) (xy 328.042778 -294.773604) (xy 327.906126 -294.81018) (xy 327.942702 -294.946832)
			(xy 327.98131 -294.96893)
		)
		(stroke
			(width 0)
			(type solid)
		)
		(fill yes)
		(layer "In2.Cu")
		(net "M_C_CPU0_SB_DQ<29>")
	)
	(gr_poly
		(pts
			(xy 328.14133 -277.527004) (xy 328.041508 -277.427182) (xy 327.941432 -277.527004) (xy 327.941432 -277.571708)
			(xy 328.14133 -277.571708)
		)
		(stroke
			(width 0)
			(type solid)
		)
		(fill yes)
		(layer "In2.Cu")
		(net "M_C_CPU0_SB_DQ<4>")
	)
	(gr_poly
		(pts
			(xy 328.14133 -275.906992) (xy 328.041508 -275.806916) (xy 327.941432 -275.906992) (xy 327.941432 -275.95449)
			(xy 328.14133 -275.95449)
		)
		(stroke
			(width 0)
			(type solid)
		)
		(fill yes)
		(layer "In2.Cu")
		(net "M_C_CPU0_SB_DQS_DP<0>")
	)
	(gr_poly
		(pts
			(xy 328.14133 -272.666968) (xy 328.041508 -272.567146) (xy 327.941432 -272.666968) (xy 327.941432 -272.711672)
			(xy 328.14133 -272.711672)
		)
		(stroke
			(width 0)
			(type solid)
		)
		(fill yes)
		(layer "In2.Cu")
		(net "M_C_CPU0_SB_CB<0>")
	)
	(gr_poly
		(pts
			(xy 328.152252 -286.844486) (xy 328.152252 -286.796734) (xy 327.952354 -286.796734) (xy 327.952354 -286.844486)
			(xy 328.05243 -286.944308)
		)
		(stroke
			(width 0)
			(type solid)
		)
		(fill yes)
		(layer "In2.Cu")
		(net "M_C_CPU0_SB_DQS_DP<7>")
	)
	(gr_poly
		(pts
			(xy 328.152252 -285.224474) (xy 328.152252 -285.180024) (xy 327.952354 -285.180024) (xy 327.952354 -285.224474)
			(xy 328.05243 -285.324296)
		)
		(stroke
			(width 0)
			(type solid)
		)
		(fill yes)
		(layer "In2.Cu")
		(net "M_C_CPU0_SB_DQ<19>")
	)
	(gr_poly
		(pts
			(xy 328.152252 -283.604462) (xy 328.152252 -283.560012) (xy 327.952354 -283.560012) (xy 327.952354 -283.604462)
			(xy 328.05243 -283.704284)
		)
		(stroke
			(width 0)
			(type solid)
		)
		(fill yes)
		(layer "In2.Cu")
		(net "M_C_CPU0_SB_DQ<15>")
	)
	(gr_poly
		(pts
			(xy 328.152252 -281.984704) (xy 328.152252 -281.936952) (xy 327.952354 -281.936952) (xy 327.952354 -281.984704)
			(xy 328.05243 -282.084526)
		)
		(stroke
			(width 0)
			(type solid)
		)
		(fill yes)
		(layer "In2.Cu")
		(net "M_C_CPU0_SB_DQS_DP<6>")
	)
	(gr_poly
		(pts
			(xy 328.152252 -278.744426) (xy 328.152252 -278.699976) (xy 327.952354 -278.699976) (xy 327.952354 -278.744426)
			(xy 328.05243 -278.844248)
		)
		(stroke
			(width 0)
			(type solid)
		)
		(fill yes)
		(layer "In2.Cu")
		(net "M_C_CPU0_SB_DQ<7>")
	)
	(gr_poly
		(pts
			(xy 328.152252 -277.124668) (xy 328.152252 -277.076916) (xy 327.952354 -277.076916) (xy 327.952354 -277.124668)
			(xy 328.05243 -277.22449)
		)
		(stroke
			(width 0)
			(type solid)
		)
		(fill yes)
		(layer "In2.Cu")
		(net "M_C_CPU0_SB_DQS_DP<5>")
	)
	(gr_poly
		(pts
			(xy 328.152252 -275.504402) (xy 328.152252 -275.459952) (xy 327.952354 -275.459952) (xy 327.952354 -275.504402)
			(xy 328.05243 -275.604224)
		)
		(stroke
			(width 0)
			(type solid)
		)
		(fill yes)
		(layer "In2.Cu")
		(net "M_C_CPU0_SB_DQ<3>")
	)
	(gr_poly
		(pts
			(xy 328.152252 -272.264632) (xy 328.152252 -272.21688) (xy 327.952354 -272.21688) (xy 327.952354 -272.264632)
			(xy 328.05243 -272.364454)
		)
		(stroke
			(width 0)
			(type solid)
		)
		(fill yes)
		(layer "In2.Cu")
		(net "M_C_CPU0_SB_DQS_DP<4>")
	)
	(gr_poly
		(pts
			(xy 328.152252 -270.644366) (xy 328.152252 -270.599916) (xy 327.952354 -270.599916) (xy 327.952354 -270.644366)
			(xy 328.05243 -270.744188)
		)
		(stroke
			(width 0)
			(type solid)
		)
		(fill yes)
		(layer "In2.Cu")
		(net "M_C_CPU0_SB_CB<7>")
	)
	(gr_poly
		(pts
			(xy 328.152252 -265.78433) (xy 328.152252 -265.73988) (xy 327.952354 -265.73988) (xy 327.952354 -265.78433)
			(xy 328.05243 -265.884152)
		)
		(stroke
			(width 0)
			(type solid)
		)
		(fill yes)
		(layer "In2.Cu")
		(net "M_C_CPU0_SB_CS_N<0>")
	)
	(gr_poly
		(pts
			(xy 328.152252 -262.544306) (xy 328.152252 -262.499856) (xy 327.952354 -262.499856) (xy 327.952354 -262.544306)
			(xy 328.05243 -262.644128)
		)
		(stroke
			(width 0)
			(type solid)
		)
		(fill yes)
		(layer "In2.Cu")
		(net "M_C_CPU0_SB_CA<1>")
	)
	(gr_poly
		(pts
			(xy 328.161142 -288.464244) (xy 328.161142 -288.419794) (xy 327.96099 -288.419794) (xy 327.96099 -288.464244)
			(xy 328.061066 -288.56432)
		)
		(stroke
			(width 0)
			(type solid)
		)
		(fill yes)
		(layer "In2.Cu")
		(net "M_C_CPU0_SB_DQ<23>")
	)
	(gr_poly
		(pts
			(xy 328.161142 -269.42796) (xy 328.061066 -269.327884) (xy 327.96099 -269.42796) (xy 327.96099 -269.47241)
			(xy 328.161142 -269.47241)
		)
		(stroke
			(width 0)
			(type solid)
		)
		(fill yes)
		(layer "In2.Cu")
		(net "M_C_CPU0_SB_CB<4>")
	)
	(gr_poly
		(pts
			(xy 328.167238 -292.107874) (xy 328.067162 -292.007798) (xy 327.967086 -292.107874) (xy 327.967086 -292.152324)
			(xy 328.167238 -292.152324)
		)
		(stroke
			(width 0)
			(type solid)
		)
		(fill yes)
		(layer "In2.Cu")
		(net "M_C_CPU0_SB_DQ<28>")
	)
	(gr_poly
		(pts
			(xy 328.17435 -262.948166) (xy 328.074274 -262.84809) (xy 327.974198 -262.948166) (xy 327.974198 -262.992616)
			(xy 328.17435 -262.992616)
		)
		(stroke
			(width 0)
			(type solid)
		)
		(fill yes)
		(layer "In2.Cu")
		(net "M_C_CPU0_SB_CA<2>")
	)
	(gr_poly
		(pts
			(xy 328.17562 -284.008068) (xy 328.075798 -283.908246) (xy 327.975722 -284.008068) (xy 327.975722 -284.052772)
			(xy 328.17562 -284.052772)
		)
		(stroke
			(width 0)
			(type solid)
		)
		(fill yes)
		(layer "In2.Cu")
		(net "M_C_CPU0_SB_DQ<16>")
	)
	(gr_poly
		(pts
			(xy 328.17562 -282.388056) (xy 328.075798 -282.288234) (xy 327.975722 -282.388056) (xy 327.975722 -282.43276)
			(xy 328.17562 -282.43276)
		)
		(stroke
			(width 0)
			(type solid)
		)
		(fill yes)
		(layer "In2.Cu")
		(net "M_C_CPU0_SB_DQ<12>")
	)
	(gr_poly
		(pts
			(xy 328.17562 -279.148032) (xy 328.075798 -279.04821) (xy 327.975722 -279.148032) (xy 327.975722 -279.192736)
			(xy 328.17562 -279.192736)
		)
		(stroke
			(width 0)
			(type solid)
		)
		(fill yes)
		(layer "In2.Cu")
		(net "M_C_CPU0_SB_DQ<8>")
	)
	(gr_poly
		(pts
			(xy 328.17562 -274.287996) (xy 328.075798 -274.188174) (xy 327.975722 -274.287996) (xy 327.975722 -274.3327)
			(xy 328.17562 -274.3327)
		)
		(stroke
			(width 0)
			(type solid)
		)
		(fill yes)
		(layer "In2.Cu")
		(net "M_C_CPU0_SB_DQ<0>")
	)
	(gr_poly
		(pts
			(xy 328.17562 -264.567924) (xy 328.075798 -264.468102) (xy 327.975722 -264.567924) (xy 327.975722 -264.612628)
			(xy 328.17562 -264.612628)
		)
		(stroke
			(width 0)
			(type solid)
		)
		(fill yes)
		(layer "In2.Cu")
		(net "M_C_CPU0_SB_CA<6>")
	)
	(gr_poly
		(pts
			(xy 328.177144 -280.36393) (xy 328.177144 -280.31948) (xy 327.976992 -280.31948) (xy 327.976992 -280.36393)
			(xy 328.077068 -280.464006)
		)
		(stroke
			(width 0)
			(type solid)
		)
		(fill yes)
		(layer "In2.Cu")
		(net "M_C_CPU0_SB_DQ<11>")
	)
	(gr_poly
		(pts
			(xy 328.177144 -273.883882) (xy 328.177144 -273.839432) (xy 327.976992 -273.839432) (xy 327.976992 -273.883882)
			(xy 328.077068 -273.983958)
		)
		(stroke
			(width 0)
			(type solid)
		)
		(fill yes)
		(layer "In2.Cu")
		(net "M_C_CPU0_SB_CB<3>")
	)
	(gr_poly
		(pts
			(xy 328.177144 -264.16381) (xy 328.177144 -264.11936) (xy 327.976992 -264.11936) (xy 327.976992 -264.16381)
			(xy 328.077068 -264.263886)
		)
		(stroke
			(width 0)
			(type solid)
		)
		(fill yes)
		(layer "In2.Cu")
		(net "M_C_CPU0_SB_CA<5>")
	)
	(gr_poly
		(pts
			(xy 328.177906 -287.248092) (xy 328.07783 -287.148016) (xy 327.977754 -287.248092) (xy 327.977754 -287.292542)
			(xy 328.177906 -287.292542)
		)
		(stroke
			(width 0)
			(type solid)
		)
		(fill yes)
		(layer "In2.Cu")
		(net "M_C_CPU0_SB_DQ<20>")
	)
	(gr_poly
		(pts
			(xy 328.181462 -288.868104) (xy 328.081386 -288.768028) (xy 327.98131 -288.868104) (xy 327.98131 -288.912554)
			(xy 328.181462 -288.912554)
		)
		(stroke
			(width 0)
			(type solid)
		)
		(fill yes)
		(layer "In2.Cu")
		(net "M_C_CPU0_SB_DQ<24>")
	)
	(gr_poly
		(pts
			(xy 328.20483 -267.801852) (xy 328.134218 -267.679424) (xy 328.01179 -267.750036) (xy 328.00036 -267.792962)
			(xy 328.1934 -267.844778)
		)
		(stroke
			(width 0)
			(type solid)
		)
		(fill yes)
		(layer "In2.Cu")
		(net "M_C_CPU0_SB_RSP<0>")
	)
	(gr_poly
		(pts
			(xy 328.217022 -293.860474) (xy 328.180446 -293.723822) (xy 328.142092 -293.70147) (xy 328.042016 -293.874698)
			(xy 328.080624 -293.89705)
		)
		(stroke
			(width 0)
			(type solid)
		)
		(fill yes)
		(layer "In2.Cu")
		(net "M_C_CPU0_SB_DQ<30>")
	)
	(gr_poly
		(pts
			(xy 328.250296 -228.63302) (xy 328.15022 -228.459792) (xy 328.111866 -228.482144) (xy 328.07529 -228.618796)
			(xy 328.211688 -228.655372)
		)
		(stroke
			(width 0)
			(type solid)
		)
		(fill yes)
		(layer "In2.Cu")
		(net "M_C_CPU0_SA_DQ<10>")
	)
	(gr_poly
		(pts
			(xy 328.250296 -227.013008) (xy 328.15022 -226.83978) (xy 328.111866 -226.862132) (xy 328.07529 -226.998784)
			(xy 328.211688 -227.03536)
		)
		(stroke
			(width 0)
			(type solid)
		)
		(fill yes)
		(layer "In2.Cu")
		(net "M_C_CPU0_SA_DQ<7>")
	)
	(gr_poly
		(pts
			(xy 328.250296 -225.392996) (xy 328.15022 -225.219768) (xy 328.111866 -225.24212) (xy 328.07529 -225.378772)
			(xy 328.211688 -225.415348)
		)
		(stroke
			(width 0)
			(type solid)
		)
		(fill yes)
		(layer "In2.Cu")
		(net "M_C_CPU0_SA_DQ<6>")
	)
	(gr_poly
		(pts
			(xy 328.251058 -230.254302) (xy 328.150982 -230.081074) (xy 328.112374 -230.103172) (xy 328.075798 -230.239824)
			(xy 328.21245 -230.2764)
		)
		(stroke
			(width 0)
			(type solid)
		)
		(fill yes)
		(layer "In2.Cu")
		(net "M_C_CPU0_SA_DQ<11>")
	)
	(gr_poly
		(pts
			(xy 328.25309 -231.872028) (xy 328.153268 -231.6988) (xy 328.111866 -231.722676) (xy 328.07529 -231.859074)
			(xy 328.211942 -231.895904)
		)
		(stroke
			(width 0)
			(type solid)
		)
		(fill yes)
		(layer "In2.Cu")
		(net "M_C_CPU0_SA_DQS_DN<1>")
	)
	(gr_poly
		(pts
			(xy 328.254106 -223.773492) (xy 328.154284 -223.600264) (xy 328.112882 -223.62414) (xy 328.076306 -223.760792)
			(xy 328.212958 -223.797368)
		)
		(stroke
			(width 0)
			(type solid)
		)
		(fill yes)
		(layer "In2.Cu")
		(net "M_C_CPU0_SA_DQS_DP<5>")
	)
	(gr_poly
		(pts
			(xy 328.331322 -256.025904) (xy 328.231246 -255.926082) (xy 328.13117 -256.025904) (xy 328.13117 -256.073656)
			(xy 328.331322 -256.073656)
		)
		(stroke
			(width 0)
			(type solid)
		)
		(fill yes)
		(layer "In2.Cu")
		(net "M_C_CPU0_CLK_DP<0>")
	)
	(gr_poly
		(pts
			(xy 328.331322 -255.622298) (xy 328.331322 -255.577848) (xy 328.13117 -255.577848) (xy 328.13117 -255.622298)
			(xy 328.231246 -255.722374)
		)
		(stroke
			(width 0)
			(type solid)
		)
		(fill yes)
		(layer "In2.Cu")
		(net "M_C_CPU0_SA_PAR")
	)
	(gr_poly
		(pts
			(xy 328.331322 -254.406146) (xy 328.231246 -254.30607) (xy 328.13117 -254.406146) (xy 328.13117 -254.450596)
			(xy 328.331322 -254.450596)
		)
		(stroke
			(width 0)
			(type solid)
		)
		(fill yes)
		(layer "In2.Cu")
		(net "M_C_CPU0_SA_CA<4>")
	)
	(gr_poly
		(pts
			(xy 328.331322 -254.002286) (xy 328.331322 -253.957836) (xy 328.13117 -253.957836) (xy 328.13117 -254.002286)
			(xy 328.231246 -254.102362)
		)
		(stroke
			(width 0)
			(type solid)
		)
		(fill yes)
		(layer "In2.Cu")
		(net "M_C_CPU0_SA_CA<3>")
	)
	(gr_poly
		(pts
			(xy 328.331322 -252.786134) (xy 328.231246 -252.686058) (xy 328.13117 -252.786134) (xy 328.13117 -252.830584)
			(xy 328.331322 -252.830584)
		)
		(stroke
			(width 0)
			(type solid)
		)
		(fill yes)
		(layer "In2.Cu")
		(net "M_C_CPU0_SA_CA<0>")
	)
	(gr_poly
		(pts
			(xy 328.331322 -252.382274) (xy 328.331322 -252.337824) (xy 328.13117 -252.337824) (xy 328.13117 -252.382274)
			(xy 328.231246 -252.48235)
		)
		(stroke
			(width 0)
			(type solid)
		)
		(fill yes)
		(layer "In2.Cu")
		(net "M_C_CPU0_SA_CS_N<1>")
	)
	(gr_poly
		(pts
			(xy 328.331322 -250.762262) (xy 328.331322 -250.717812) (xy 328.13117 -250.717812) (xy 328.13117 -250.762262)
			(xy 328.231246 -250.862338)
		)
		(stroke
			(width 0)
			(type solid)
		)
		(fill yes)
		(layer "In2.Cu")
		(net "M_C_CPU0_RESET_N")
	)
	(gr_poly
		(pts
			(xy 328.331322 -249.14225) (xy 328.331322 -249.0978) (xy 328.13117 -249.0978) (xy 328.13117 -249.14225)
			(xy 328.231246 -249.242326)
		)
		(stroke
			(width 0)
			(type solid)
		)
		(fill yes)
		(layer "In2.Cu")
		(net "M_C_CPU0_SA_CB<7>")
	)
	(gr_poly
		(pts
			(xy 328.331322 -247.926098) (xy 328.231246 -247.826022) (xy 328.13117 -247.926098) (xy 328.13117 -247.970548)
			(xy 328.331322 -247.970548)
		)
		(stroke
			(width 0)
			(type solid)
		)
		(fill yes)
		(layer "In2.Cu")
		(net "M_C_CPU0_SA_CB<4>")
	)
	(gr_poly
		(pts
			(xy 328.331322 -247.522492) (xy 328.331322 -247.47474) (xy 328.13117 -247.47474) (xy 328.13117 -247.522492)
			(xy 328.231246 -247.622314)
		)
		(stroke
			(width 0)
			(type solid)
		)
		(fill yes)
		(layer "In2.Cu")
		(net "M_C_CPU0_SA_DQS_DP<9>")
	)
	(gr_poly
		(pts
			(xy 328.331322 -245.902226) (xy 328.331322 -245.857776) (xy 328.13117 -245.857776) (xy 328.13117 -245.902226)
			(xy 328.231246 -246.002302)
		)
		(stroke
			(width 0)
			(type solid)
		)
		(fill yes)
		(layer "In2.Cu")
		(net "M_C_CPU0_SA_CB<3>")
	)
	(gr_poly
		(pts
			(xy 328.331322 -244.686074) (xy 328.231246 -244.585998) (xy 328.13117 -244.686074) (xy 328.13117 -244.730524)
			(xy 328.331322 -244.730524)
		)
		(stroke
			(width 0)
			(type solid)
		)
		(fill yes)
		(layer "In2.Cu")
		(net "M_C_CPU0_SA_CB<0>")
	)
	(gr_poly
		(pts
			(xy 328.331322 -244.282214) (xy 328.331322 -244.237764) (xy 328.13117 -244.237764) (xy 328.13117 -244.282214)
			(xy 328.231246 -244.38229)
		)
		(stroke
			(width 0)
			(type solid)
		)
		(fill yes)
		(layer "In2.Cu")
		(net "M_C_CPU0_SA_DQ<31>")
	)
	(gr_poly
		(pts
			(xy 328.331322 -243.066062) (xy 328.231246 -242.965986) (xy 328.13117 -243.066062) (xy 328.13117 -243.110512)
			(xy 328.331322 -243.110512)
		)
		(stroke
			(width 0)
			(type solid)
		)
		(fill yes)
		(layer "In2.Cu")
		(net "M_C_CPU0_SA_DQ<28>")
	)
	(gr_poly
		(pts
			(xy 328.331322 -242.662456) (xy 328.331322 -242.614704) (xy 328.13117 -242.614704) (xy 328.13117 -242.662456)
			(xy 328.231246 -242.762278)
		)
		(stroke
			(width 0)
			(type solid)
		)
		(fill yes)
		(layer "In2.Cu")
		(net "M_C_CPU0_SA_DQS_DP<8>")
	)
	(gr_poly
		(pts
			(xy 328.331322 -241.445796) (xy 328.231246 -241.345974) (xy 328.13117 -241.445796) (xy 328.13117 -241.493548)
			(xy 328.331322 -241.493548)
		)
		(stroke
			(width 0)
			(type solid)
		)
		(fill yes)
		(layer "In2.Cu")
		(net "M_C_CPU0_SA_DQS_DP<3>")
	)
	(gr_poly
		(pts
			(xy 328.331322 -241.04219) (xy 328.331322 -240.99774) (xy 328.13117 -240.99774) (xy 328.13117 -241.04219)
			(xy 328.231246 -241.142266)
		)
		(stroke
			(width 0)
			(type solid)
		)
		(fill yes)
		(layer "In2.Cu")
		(net "M_C_CPU0_SA_DQ<27>")
	)
	(gr_poly
		(pts
			(xy 328.331322 -239.826038) (xy 328.231246 -239.725962) (xy 328.13117 -239.826038) (xy 328.13117 -239.870488)
			(xy 328.331322 -239.870488)
		)
		(stroke
			(width 0)
			(type solid)
		)
		(fill yes)
		(layer "In2.Cu")
		(net "M_C_CPU0_SA_DQ<24>")
	)
	(gr_poly
		(pts
			(xy 328.331322 -239.422178) (xy 328.331322 -239.377728) (xy 328.13117 -239.377728) (xy 328.13117 -239.422178)
			(xy 328.231246 -239.522254)
		)
		(stroke
			(width 0)
			(type solid)
		)
		(fill yes)
		(layer "In2.Cu")
		(net "M_C_CPU0_SA_DQ<23>")
	)
	(gr_poly
		(pts
			(xy 328.331322 -238.206026) (xy 328.231246 -238.10595) (xy 328.13117 -238.206026) (xy 328.13117 -238.250476)
			(xy 328.331322 -238.250476)
		)
		(stroke
			(width 0)
			(type solid)
		)
		(fill yes)
		(layer "In2.Cu")
		(net "M_C_CPU0_SA_DQ<20>")
	)
	(gr_poly
		(pts
			(xy 328.331322 -237.80242) (xy 328.331322 -237.754668) (xy 328.13117 -237.754668) (xy 328.13117 -237.80242)
			(xy 328.231246 -237.902242)
		)
		(stroke
			(width 0)
			(type solid)
		)
		(fill yes)
		(layer "In2.Cu")
		(net "M_C_CPU0_SA_DQS_DP<7>")
	)
	(gr_poly
		(pts
			(xy 328.331322 -236.58576) (xy 328.231246 -236.485938) (xy 328.13117 -236.58576) (xy 328.13117 -236.633512)
			(xy 328.331322 -236.633512)
		)
		(stroke
			(width 0)
			(type solid)
		)
		(fill yes)
		(layer "In2.Cu")
		(net "M_C_CPU0_SA_DQS_DP<2>")
	)
	(gr_poly
		(pts
			(xy 328.331322 -236.182154) (xy 328.331322 -236.137704) (xy 328.13117 -236.137704) (xy 328.13117 -236.182154)
			(xy 328.231246 -236.28223)
		)
		(stroke
			(width 0)
			(type solid)
		)
		(fill yes)
		(layer "In2.Cu")
		(net "M_C_CPU0_SA_DQ<19>")
	)
	(gr_poly
		(pts
			(xy 328.331322 -234.966002) (xy 328.231246 -234.865926) (xy 328.13117 -234.966002) (xy 328.13117 -235.010452)
			(xy 328.331322 -235.010452)
		)
		(stroke
			(width 0)
			(type solid)
		)
		(fill yes)
		(layer "In2.Cu")
		(net "M_C_CPU0_SA_DQ<16>")
	)
	(gr_poly
		(pts
			(xy 328.331322 -234.562142) (xy 328.331322 -234.517692) (xy 328.13117 -234.517692) (xy 328.13117 -234.562142)
			(xy 328.231246 -234.662218)
		)
		(stroke
			(width 0)
			(type solid)
		)
		(fill yes)
		(layer "In2.Cu")
		(net "M_C_CPU0_SA_DQ<15>")
	)
	(gr_poly
		(pts
			(xy 328.331322 -233.34599) (xy 328.231246 -233.245914) (xy 328.13117 -233.34599) (xy 328.13117 -233.39044)
			(xy 328.331322 -233.39044)
		)
		(stroke
			(width 0)
			(type solid)
		)
		(fill yes)
		(layer "In2.Cu")
		(net "M_C_CPU0_SA_DQ<12>")
	)
	(gr_poly
		(pts
			(xy 328.331322 -232.942384) (xy 328.331322 -232.894632) (xy 328.13117 -232.894632) (xy 328.13117 -232.942384)
			(xy 328.231246 -233.042206)
		)
		(stroke
			(width 0)
			(type solid)
		)
		(fill yes)
		(layer "In2.Cu")
		(net "M_C_CPU0_SA_DQS_DP<6>")
	)
	(gr_poly
		(pts
			(xy 328.338942 -246.305578) (xy 328.238866 -246.205756) (xy 328.13879 -246.305578) (xy 328.13879 -246.35333)
			(xy 328.338942 -246.35333)
		)
		(stroke
			(width 0)
			(type solid)
		)
		(fill yes)
		(layer "In2.Cu")
		(net "M_C_CPU0_SA_DQS_DP<4>")
	)
	(gr_poly
		(pts
			(xy 328.349102 -223.223582) (xy 328.385678 -223.087184) (xy 328.249026 -223.050354) (xy 328.207878 -223.07423)
			(xy 328.307954 -223.247458)
		)
		(stroke
			(width 0)
			(type solid)
		)
		(fill yes)
		(layer "In2.Cu")
		(net "M_C_CPU0_SA_DQS_DN<5>")
	)
	(gr_poly
		(pts
			(xy 328.350372 -229.70617) (xy 328.387202 -229.569518) (xy 328.25055 -229.532942) (xy 328.211942 -229.555294)
			(xy 328.312018 -229.728522)
		)
		(stroke
			(width 0)
			(type solid)
		)
		(fill yes)
		(layer "In2.Cu")
		(net "M_C_CPU0_SA_DQ<9>")
	)
	(gr_poly
		(pts
			(xy 328.350372 -228.086412) (xy 328.387202 -227.94976) (xy 328.25055 -227.913184) (xy 328.211942 -227.935536)
			(xy 328.312018 -228.108764)
		)
		(stroke
			(width 0)
			(type solid)
		)
		(fill yes)
		(layer "In2.Cu")
		(net "M_C_CPU0_SA_DQ<8>")
	)
	(gr_poly
		(pts
			(xy 328.350372 -226.4664) (xy 328.387202 -226.329748) (xy 328.25055 -226.293172) (xy 328.211942 -226.315524)
			(xy 328.312018 -226.488752)
		)
		(stroke
			(width 0)
			(type solid)
		)
		(fill yes)
		(layer "In2.Cu")
		(net "M_C_CPU0_SA_DQ<5>")
	)
	(gr_poly
		(pts
			(xy 328.350372 -224.846388) (xy 328.387202 -224.709736) (xy 328.25055 -224.67316) (xy 328.211942 -224.695512)
			(xy 328.312018 -224.86874)
		)
		(stroke
			(width 0)
			(type solid)
		)
		(fill yes)
		(layer "In2.Cu")
		(net "M_C_CPU0_SA_DQ<4>")
	)
	(gr_poly
		(pts
			(xy 328.35088 -231.326944) (xy 328.387456 -231.190292) (xy 328.251058 -231.153716) (xy 328.209656 -231.177338)
			(xy 328.309732 -231.350566)
		)
		(stroke
			(width 0)
			(type solid)
		)
		(fill yes)
		(layer "In2.Cu")
		(net "M_C_CPU0_SA_DQS_DP<1>")
	)
	(gr_poly
		(pts
			(xy 328.55027 -293.98722) (xy 328.511662 -293.964868) (xy 328.37501 -294.001444) (xy 328.41184 -294.138096)
			(xy 328.450194 -294.160448)
		)
		(stroke
			(width 0)
			(type solid)
		)
		(fill yes)
		(layer "In2.Cu")
		(net "M_C_CPU0_SB_DQ<29>")
	)
	(gr_poly
		(pts
			(xy 328.600562 -289.714432) (xy 328.596498 -289.670236) (xy 328.488294 -289.579304) (xy 328.397362 -289.687508)
			(xy 328.401172 -289.731958)
		)
		(stroke
			(width 0)
			(type solid)
		)
		(fill yes)
		(layer "In2.Cu")
		(net "M_C_CPU0_SB_DQ<25>")
	)
	(gr_poly
		(pts
			(xy 328.62393 -291.297614) (xy 328.523854 -291.197792) (xy 328.423778 -291.297614) (xy 328.423778 -291.345366)
			(xy 328.62393 -291.345366)
		)
		(stroke
			(width 0)
			(type solid)
		)
		(fill yes)
		(layer "In2.Cu")
		(net "M_C_CPU0_SB_DQS_DN<8>")
	)
	(gr_poly
		(pts
			(xy 328.624946 -266.991592) (xy 328.52487 -266.891516) (xy 328.425048 -266.991592) (xy 328.425048 -267.036042)
			(xy 328.624946 -267.036042)
		)
		(stroke
			(width 0)
			(type solid)
		)
		(fill yes)
		(layer "In2.Cu")
		(net "M_C_CPU0_SA_RSP<0>")
	)
	(gr_poly
		(pts
			(xy 328.631296 -289.273996) (xy 328.631296 -289.229546) (xy 328.431144 -289.229546) (xy 328.431144 -289.273996)
			(xy 328.53122 -289.374072)
		)
		(stroke
			(width 0)
			(type solid)
		)
		(fill yes)
		(layer "In2.Cu")
		(net "M_C_CPU0_SB_DQ<26>")
	)
	(gr_poly
		(pts
			(xy 328.631296 -288.057844) (xy 328.53122 -287.957768) (xy 328.431144 -288.057844) (xy 328.431144 -288.102294)
			(xy 328.631296 -288.102294)
		)
		(stroke
			(width 0)
			(type solid)
		)
		(fill yes)
		(layer "In2.Cu")
		(net "M_C_CPU0_SB_DQ<21>")
	)
	(gr_poly
		(pts
			(xy 328.631296 -287.654238) (xy 328.631296 -287.609788) (xy 328.431144 -287.609788) (xy 328.431144 -287.654238)
			(xy 328.53122 -287.75406)
		)
		(stroke
			(width 0)
			(type solid)
		)
		(fill yes)
		(layer "In2.Cu")
		(net "M_C_CPU0_SB_DQ<22>")
	)
	(gr_poly
		(pts
			(xy 328.631296 -286.437832) (xy 328.53122 -286.337756) (xy 328.431144 -286.437832) (xy 328.431144 -286.485584)
			(xy 328.631296 -286.485584)
		)
		(stroke
			(width 0)
			(type solid)
		)
		(fill yes)
		(layer "In2.Cu")
		(net "M_C_CPU0_SB_DQS_DN<7>")
	)
	(gr_poly
		(pts
			(xy 328.631296 -286.03448) (xy 328.631296 -285.986728) (xy 328.431144 -285.986728) (xy 328.431144 -286.03448)
			(xy 328.53122 -286.134302)
		)
		(stroke
			(width 0)
			(type solid)
		)
		(fill yes)
		(layer "In2.Cu")
		(net "M_C_CPU0_SB_DQS_DN<2>")
	)
	(gr_poly
		(pts
			(xy 328.631296 -284.818074) (xy 328.53122 -284.717998) (xy 328.431144 -284.818074) (xy 328.431144 -284.862524)
			(xy 328.631296 -284.862524)
		)
		(stroke
			(width 0)
			(type solid)
		)
		(fill yes)
		(layer "In2.Cu")
		(net "M_C_CPU0_SB_DQ<17>")
	)
	(gr_poly
		(pts
			(xy 328.631296 -284.414214) (xy 328.631296 -284.369764) (xy 328.431144 -284.369764) (xy 328.431144 -284.414214)
			(xy 328.53122 -284.51429)
		)
		(stroke
			(width 0)
			(type solid)
		)
		(fill yes)
		(layer "In2.Cu")
		(net "M_C_CPU0_SB_DQ<18>")
	)
	(gr_poly
		(pts
			(xy 328.631296 -283.198062) (xy 328.53122 -283.097986) (xy 328.431144 -283.198062) (xy 328.431144 -283.242512)
			(xy 328.631296 -283.242512)
		)
		(stroke
			(width 0)
			(type solid)
		)
		(fill yes)
		(layer "In2.Cu")
		(net "M_C_CPU0_SB_DQ<13>")
	)
	(gr_poly
		(pts
			(xy 328.631296 -282.794202) (xy 328.631296 -282.749752) (xy 328.431144 -282.749752) (xy 328.431144 -282.794202)
			(xy 328.53122 -282.894278)
		)
		(stroke
			(width 0)
			(type solid)
		)
		(fill yes)
		(layer "In2.Cu")
		(net "M_C_CPU0_SB_DQ<14>")
	)
	(gr_poly
		(pts
			(xy 328.631296 -281.577796) (xy 328.53122 -281.477974) (xy 328.431144 -281.577796) (xy 328.431144 -281.625548)
			(xy 328.631296 -281.625548)
		)
		(stroke
			(width 0)
			(type solid)
		)
		(fill yes)
		(layer "In2.Cu")
		(net "M_C_CPU0_SB_DQS_DN<6>")
	)
	(gr_poly
		(pts
			(xy 328.631296 -281.174444) (xy 328.631296 -281.126692) (xy 328.431144 -281.126692) (xy 328.431144 -281.174444)
			(xy 328.53122 -281.274266)
		)
		(stroke
			(width 0)
			(type solid)
		)
		(fill yes)
		(layer "In2.Cu")
		(net "M_C_CPU0_SB_DQS_DN<1>")
	)
	(gr_poly
		(pts
			(xy 328.631296 -279.958038) (xy 328.53122 -279.857962) (xy 328.431144 -279.958038) (xy 328.431144 -280.002488)
			(xy 328.631296 -280.002488)
		)
		(stroke
			(width 0)
			(type solid)
		)
		(fill yes)
		(layer "In2.Cu")
		(net "M_C_CPU0_SB_DQ<9>")
	)
	(gr_poly
		(pts
			(xy 328.631296 -279.554178) (xy 328.631296 -279.509728) (xy 328.431144 -279.509728) (xy 328.431144 -279.554178)
			(xy 328.53122 -279.654254)
		)
		(stroke
			(width 0)
			(type solid)
		)
		(fill yes)
		(layer "In2.Cu")
		(net "M_C_CPU0_SB_DQ<10>")
	)
	(gr_poly
		(pts
			(xy 328.631296 -278.338026) (xy 328.53122 -278.23795) (xy 328.431144 -278.338026) (xy 328.431144 -278.382476)
			(xy 328.631296 -278.382476)
		)
		(stroke
			(width 0)
			(type solid)
		)
		(fill yes)
		(layer "In2.Cu")
		(net "M_C_CPU0_SB_DQ<5>")
	)
	(gr_poly
		(pts
			(xy 328.631296 -277.934166) (xy 328.631296 -277.889716) (xy 328.431144 -277.889716) (xy 328.431144 -277.934166)
			(xy 328.53122 -278.034242)
		)
		(stroke
			(width 0)
			(type solid)
		)
		(fill yes)
		(layer "In2.Cu")
		(net "M_C_CPU0_SB_DQ<6>")
	)
	(gr_poly
		(pts
			(xy 328.631296 -276.71776) (xy 328.53122 -276.617938) (xy 328.431144 -276.71776) (xy 328.431144 -276.765512)
			(xy 328.631296 -276.765512)
		)
		(stroke
			(width 0)
			(type solid)
		)
		(fill yes)
		(layer "In2.Cu")
		(net "M_C_CPU0_SB_DQS_DN<5>")
	)
	(gr_poly
		(pts
			(xy 328.631296 -276.314408) (xy 328.631296 -276.266656) (xy 328.431144 -276.266656) (xy 328.431144 -276.314408)
			(xy 328.53122 -276.41423)
		)
		(stroke
			(width 0)
			(type solid)
		)
		(fill yes)
		(layer "In2.Cu")
		(net "M_C_CPU0_SB_DQS_DN<0>")
	)
	(gr_poly
		(pts
			(xy 328.631296 -275.098002) (xy 328.53122 -274.997926) (xy 328.431144 -275.098002) (xy 328.431144 -275.142452)
			(xy 328.631296 -275.142452)
		)
		(stroke
			(width 0)
			(type solid)
		)
		(fill yes)
		(layer "In2.Cu")
		(net "M_C_CPU0_SB_DQ<1>")
	)
	(gr_poly
		(pts
			(xy 328.631296 -274.694142) (xy 328.631296 -274.649692) (xy 328.431144 -274.649692) (xy 328.431144 -274.694142)
			(xy 328.53122 -274.794218)
		)
		(stroke
			(width 0)
			(type solid)
		)
		(fill yes)
		(layer "In2.Cu")
		(net "M_C_CPU0_SB_DQ<2>")
	)
	(gr_poly
		(pts
			(xy 328.631296 -273.47799) (xy 328.53122 -273.377914) (xy 328.431144 -273.47799) (xy 328.431144 -273.52244)
			(xy 328.631296 -273.52244)
		)
		(stroke
			(width 0)
			(type solid)
		)
		(fill yes)
		(layer "In2.Cu")
		(net "M_C_CPU0_SB_CB<1>")
	)
	(gr_poly
		(pts
			(xy 328.631296 -273.07413) (xy 328.631296 -273.02968) (xy 328.431144 -273.02968) (xy 328.431144 -273.07413)
			(xy 328.53122 -273.174206)
		)
		(stroke
			(width 0)
			(type solid)
		)
		(fill yes)
		(layer "In2.Cu")
		(net "M_C_CPU0_SB_CB<2>")
	)
	(gr_poly
		(pts
			(xy 328.631296 -271.857724) (xy 328.53122 -271.757902) (xy 328.431144 -271.857724) (xy 328.431144 -271.905476)
			(xy 328.631296 -271.905476)
		)
		(stroke
			(width 0)
			(type solid)
		)
		(fill yes)
		(layer "In2.Cu")
		(net "M_C_CPU0_SB_DQS_DN<4>")
	)
	(gr_poly
		(pts
			(xy 328.631296 -271.454372) (xy 328.631296 -271.40662) (xy 328.431144 -271.40662) (xy 328.431144 -271.454372)
			(xy 328.53122 -271.554194)
		)
		(stroke
			(width 0)
			(type solid)
		)
		(fill yes)
		(layer "In2.Cu")
		(net "M_C_CPU0_SB_DQS_DN<9>")
	)
	(gr_poly
		(pts
			(xy 328.631296 -270.237966) (xy 328.53122 -270.13789) (xy 328.431144 -270.237966) (xy 328.431144 -270.282416)
			(xy 328.631296 -270.282416)
		)
		(stroke
			(width 0)
			(type solid)
		)
		(fill yes)
		(layer "In2.Cu")
		(net "M_C_CPU0_SB_CB<5>")
	)
	(gr_poly
		(pts
			(xy 328.631296 -269.834106) (xy 328.631296 -269.789656) (xy 328.431144 -269.789656) (xy 328.431144 -269.834106)
			(xy 328.53122 -269.934182)
		)
		(stroke
			(width 0)
			(type solid)
		)
		(fill yes)
		(layer "In2.Cu")
		(net "M_C_CPU0_SB_CB<6>")
	)
	(gr_poly
		(pts
			(xy 328.631296 -266.594082) (xy 328.631296 -266.549632) (xy 328.431144 -266.549632) (xy 328.431144 -266.594082)
			(xy 328.53122 -266.694158)
		)
		(stroke
			(width 0)
			(type solid)
		)
		(fill yes)
		(layer "In2.Cu")
		(net "M_C_CPU0_SB_CS_N<1>")
	)
	(gr_poly
		(pts
			(xy 328.631296 -264.97407) (xy 328.631296 -264.92962) (xy 328.431144 -264.92962) (xy 328.431144 -264.97407)
			(xy 328.53122 -265.074146)
		)
		(stroke
			(width 0)
			(type solid)
		)
		(fill yes)
		(layer "In2.Cu")
		(net "M_C_CPU0_SB_PAR")
	)
	(gr_poly
		(pts
			(xy 328.631296 -263.757918) (xy 328.53122 -263.657842) (xy 328.431144 -263.757918) (xy 328.431144 -263.802368)
			(xy 328.631296 -263.802368)
		)
		(stroke
			(width 0)
			(type solid)
		)
		(fill yes)
		(layer "In2.Cu")
		(net "M_C_CPU0_SB_CA<4>")
	)
	(gr_poly
		(pts
			(xy 328.631296 -263.354058) (xy 328.631296 -263.309608) (xy 328.431144 -263.309608) (xy 328.431144 -263.354058)
			(xy 328.53122 -263.454134)
		)
		(stroke
			(width 0)
			(type solid)
		)
		(fill yes)
		(layer "In2.Cu")
		(net "M_C_CPU0_SB_CA<3>")
	)
	(gr_poly
		(pts
			(xy 328.631296 -262.137906) (xy 328.53122 -262.03783) (xy 328.431144 -262.137906) (xy 328.431144 -262.182356)
			(xy 328.631296 -262.182356)
		)
		(stroke
			(width 0)
			(type solid)
		)
		(fill yes)
		(layer "In2.Cu")
		(net "M_C_CPU0_SB_CA<0>")
	)
	(gr_poly
		(pts
			(xy 328.686922 -293.050468) (xy 328.650346 -292.913816) (xy 328.611992 -292.891464) (xy 328.511916 -293.064692)
			(xy 328.550524 -293.087044)
		)
		(stroke
			(width 0)
			(type solid)
		)
		(fill yes)
		(layer "In2.Cu")
		(net "M_C_CPU0_SB_DQ<30>")
	)
	(gr_poly
		(pts
			(xy 328.721212 -231.064562) (xy 328.621136 -230.891334) (xy 328.582528 -230.913432) (xy 328.545952 -231.050084)
			(xy 328.682604 -231.08666)
		)
		(stroke
			(width 0)
			(type solid)
		)
		(fill yes)
		(layer "In2.Cu")
		(net "M_C_CPU0_SA_DQ<11>")
	)
	(gr_poly
		(pts
			(xy 328.721212 -229.44455) (xy 328.621136 -229.271322) (xy 328.582528 -229.29342) (xy 328.545952 -229.430072)
			(xy 328.682604 -229.466648)
		)
		(stroke
			(width 0)
			(type solid)
		)
		(fill yes)
		(layer "In2.Cu")
		(net "M_C_CPU0_SA_DQ<10>")
	)
	(gr_poly
		(pts
			(xy 328.721212 -227.824538) (xy 328.621136 -227.65131) (xy 328.582528 -227.673408) (xy 328.545952 -227.81006)
			(xy 328.682604 -227.846636)
		)
		(stroke
			(width 0)
			(type solid)
		)
		(fill yes)
		(layer "In2.Cu")
		(net "M_C_CPU0_SA_DQ<7>")
	)
	(gr_poly
		(pts
			(xy 328.721212 -226.204526) (xy 328.621136 -226.031298) (xy 328.582528 -226.053396) (xy 328.545952 -226.190048)
			(xy 328.682604 -226.226624)
		)
		(stroke
			(width 0)
			(type solid)
		)
		(fill yes)
		(layer "In2.Cu")
		(net "M_C_CPU0_SA_DQ<6>")
	)
	(gr_poly
		(pts
			(xy 328.724006 -224.583498) (xy 328.624184 -224.41027) (xy 328.582782 -224.434146) (xy 328.546206 -224.570798)
			(xy 328.682858 -224.607374)
		)
		(stroke
			(width 0)
			(type solid)
		)
		(fill yes)
		(layer "In2.Cu")
		(net "M_C_CPU0_SA_DQS_DP<5>")
	)
	(gr_poly
		(pts
			(xy 328.725276 -222.96501) (xy 328.6252 -222.791782) (xy 328.583798 -222.815658) (xy 328.547222 -222.95231)
			(xy 328.683874 -222.988886)
		)
		(stroke
			(width 0)
			(type solid)
		)
		(fill yes)
		(layer "In2.Cu")
		(net "M_C_CPU0_SA_DQS_DN<0>")
	)
	(gr_poly
		(pts
			(xy 328.800968 -246.712232) (xy 328.800968 -246.664734) (xy 328.60107 -246.664734) (xy 328.60107 -246.712232)
			(xy 328.700892 -246.812308)
		)
		(stroke
			(width 0)
			(type solid)
		)
		(fill yes)
		(layer "In2.Cu")
		(net "M_C_CPU0_SA_DQS_DN<4>")
	)
	(gr_poly
		(pts
			(xy 328.801222 -256.432558) (xy 328.801222 -256.384806) (xy 328.60107 -256.384806) (xy 328.60107 -256.432558)
			(xy 328.701146 -256.53238)
		)
		(stroke
			(width 0)
			(type solid)
		)
		(fill yes)
		(layer "In2.Cu")
		(net "M_C_CPU0_CLK_DN<0>")
	)
	(gr_poly
		(pts
			(xy 328.801222 -255.216152) (xy 328.701146 -255.116076) (xy 328.60107 -255.216152) (xy 328.60107 -255.260602)
			(xy 328.801222 -255.260602)
		)
		(stroke
			(width 0)
			(type solid)
		)
		(fill yes)
		(layer "In2.Cu")
		(net "M_C_CPU0_SA_CA<6>")
	)
	(gr_poly
		(pts
			(xy 328.801222 -254.812292) (xy 328.801222 -254.767842) (xy 328.60107 -254.767842) (xy 328.60107 -254.812292)
			(xy 328.701146 -254.912368)
		)
		(stroke
			(width 0)
			(type solid)
		)
		(fill yes)
		(layer "In2.Cu")
		(net "M_C_CPU0_SA_CA<5>")
	)
	(gr_poly
		(pts
			(xy 328.801222 -253.59614) (xy 328.701146 -253.496064) (xy 328.60107 -253.59614) (xy 328.60107 -253.64059)
			(xy 328.801222 -253.64059)
		)
		(stroke
			(width 0)
			(type solid)
		)
		(fill yes)
		(layer "In2.Cu")
		(net "M_C_CPU0_SA_CA<2>")
	)
	(gr_poly
		(pts
			(xy 328.801222 -253.19228) (xy 328.801222 -253.14783) (xy 328.60107 -253.14783) (xy 328.60107 -253.19228)
			(xy 328.701146 -253.292356)
		)
		(stroke
			(width 0)
			(type solid)
		)
		(fill yes)
		(layer "In2.Cu")
		(net "M_C_CPU0_SA_CA<1>")
	)
	(gr_poly
		(pts
			(xy 328.801222 -251.572268) (xy 328.801222 -251.527818) (xy 328.60107 -251.527818) (xy 328.60107 -251.572268)
			(xy 328.701146 -251.672344)
		)
		(stroke
			(width 0)
			(type solid)
		)
		(fill yes)
		(layer "In2.Cu")
		(net "M_C_CPU0_SA_CS_N<0>")
	)
	(gr_poly
		(pts
			(xy 328.801222 -250.356116) (xy 328.701146 -250.25604) (xy 328.60107 -250.356116) (xy 328.60107 -250.400566)
			(xy 328.801222 -250.400566)
		)
		(stroke
			(width 0)
			(type solid)
		)
		(fill yes)
		(layer "In2.Cu")
		(net "M_C_CPU0_ALERT_R_N")
	)
	(gr_poly
		(pts
			(xy 328.801222 -248.736104) (xy 328.701146 -248.636028) (xy 328.60107 -248.736104) (xy 328.60107 -248.780554)
			(xy 328.801222 -248.780554)
		)
		(stroke
			(width 0)
			(type solid)
		)
		(fill yes)
		(layer "In2.Cu")
		(net "M_C_CPU0_SA_CB<5>")
	)
	(gr_poly
		(pts
			(xy 328.801222 -248.332244) (xy 328.801222 -248.287794) (xy 328.60107 -248.287794) (xy 328.60107 -248.332244)
			(xy 328.701146 -248.43232)
		)
		(stroke
			(width 0)
			(type solid)
		)
		(fill yes)
		(layer "In2.Cu")
		(net "M_C_CPU0_SA_CB<6>")
	)
	(gr_poly
		(pts
			(xy 328.801222 -247.115838) (xy 328.701146 -247.016016) (xy 328.60107 -247.115838) (xy 328.60107 -247.16359)
			(xy 328.801222 -247.16359)
		)
		(stroke
			(width 0)
			(type solid)
		)
		(fill yes)
		(layer "In2.Cu")
		(net "M_C_CPU0_SA_DQS_DN<9>")
	)
	(gr_poly
		(pts
			(xy 328.801222 -245.49608) (xy 328.701146 -245.396004) (xy 328.60107 -245.49608) (xy 328.60107 -245.54053)
			(xy 328.801222 -245.54053)
		)
		(stroke
			(width 0)
			(type solid)
		)
		(fill yes)
		(layer "In2.Cu")
		(net "M_C_CPU0_SA_CB<1>")
	)
	(gr_poly
		(pts
			(xy 328.801222 -245.09222) (xy 328.801222 -245.04777) (xy 328.60107 -245.04777) (xy 328.60107 -245.09222)
			(xy 328.701146 -245.192296)
		)
		(stroke
			(width 0)
			(type solid)
		)
		(fill yes)
		(layer "In2.Cu")
		(net "M_C_CPU0_SA_CB<2>")
	)
	(gr_poly
		(pts
			(xy 328.801222 -243.876068) (xy 328.701146 -243.775992) (xy 328.60107 -243.876068) (xy 328.60107 -243.920518)
			(xy 328.801222 -243.920518)
		)
		(stroke
			(width 0)
			(type solid)
		)
		(fill yes)
		(layer "In2.Cu")
		(net "M_C_CPU0_SA_DQ<29>")
	)
	(gr_poly
		(pts
			(xy 328.801222 -243.472208) (xy 328.801222 -243.427758) (xy 328.60107 -243.427758) (xy 328.60107 -243.472208)
			(xy 328.701146 -243.572284)
		)
		(stroke
			(width 0)
			(type solid)
		)
		(fill yes)
		(layer "In2.Cu")
		(net "M_C_CPU0_SA_DQ<30>")
	)
	(gr_poly
		(pts
			(xy 328.801222 -242.255802) (xy 328.701146 -242.15598) (xy 328.60107 -242.255802) (xy 328.60107 -242.303554)
			(xy 328.801222 -242.303554)
		)
		(stroke
			(width 0)
			(type solid)
		)
		(fill yes)
		(layer "In2.Cu")
		(net "M_C_CPU0_SA_DQS_DN<8>")
	)
	(gr_poly
		(pts
			(xy 328.801222 -241.85245) (xy 328.801222 -241.804698) (xy 328.60107 -241.804698) (xy 328.60107 -241.85245)
			(xy 328.701146 -241.952272)
		)
		(stroke
			(width 0)
			(type solid)
		)
		(fill yes)
		(layer "In2.Cu")
		(net "M_C_CPU0_SA_DQS_DN<3>")
	)
	(gr_poly
		(pts
			(xy 328.801222 -240.636044) (xy 328.701146 -240.535968) (xy 328.60107 -240.636044) (xy 328.60107 -240.680494)
			(xy 328.801222 -240.680494)
		)
		(stroke
			(width 0)
			(type solid)
		)
		(fill yes)
		(layer "In2.Cu")
		(net "M_C_CPU0_SA_DQ<25>")
	)
	(gr_poly
		(pts
			(xy 328.801222 -240.232184) (xy 328.801222 -240.187734) (xy 328.60107 -240.187734) (xy 328.60107 -240.232184)
			(xy 328.701146 -240.33226)
		)
		(stroke
			(width 0)
			(type solid)
		)
		(fill yes)
		(layer "In2.Cu")
		(net "M_C_CPU0_SA_DQ<26>")
	)
	(gr_poly
		(pts
			(xy 328.801222 -239.016032) (xy 328.701146 -238.915956) (xy 328.60107 -239.016032) (xy 328.60107 -239.060482)
			(xy 328.801222 -239.060482)
		)
		(stroke
			(width 0)
			(type solid)
		)
		(fill yes)
		(layer "In2.Cu")
		(net "M_C_CPU0_SA_DQ<21>")
	)
	(gr_poly
		(pts
			(xy 328.801222 -238.612172) (xy 328.801222 -238.567722) (xy 328.60107 -238.567722) (xy 328.60107 -238.612172)
			(xy 328.701146 -238.712248)
		)
		(stroke
			(width 0)
			(type solid)
		)
		(fill yes)
		(layer "In2.Cu")
		(net "M_C_CPU0_SA_DQ<22>")
	)
	(gr_poly
		(pts
			(xy 328.801222 -237.395766) (xy 328.701146 -237.295944) (xy 328.60107 -237.395766) (xy 328.60107 -237.443518)
			(xy 328.801222 -237.443518)
		)
		(stroke
			(width 0)
			(type solid)
		)
		(fill yes)
		(layer "In2.Cu")
		(net "M_C_CPU0_SA_DQS_DN<7>")
	)
	(gr_poly
		(pts
			(xy 328.801222 -236.992414) (xy 328.801222 -236.944662) (xy 328.60107 -236.944662) (xy 328.60107 -236.992414)
			(xy 328.701146 -237.092236)
		)
		(stroke
			(width 0)
			(type solid)
		)
		(fill yes)
		(layer "In2.Cu")
		(net "M_C_CPU0_SA_DQS_DN<2>")
	)
	(gr_poly
		(pts
			(xy 328.801222 -235.776008) (xy 328.701146 -235.675932) (xy 328.60107 -235.776008) (xy 328.60107 -235.820458)
			(xy 328.801222 -235.820458)
		)
		(stroke
			(width 0)
			(type solid)
		)
		(fill yes)
		(layer "In2.Cu")
		(net "M_C_CPU0_SA_DQ<17>")
	)
	(gr_poly
		(pts
			(xy 328.801222 -235.372148) (xy 328.801222 -235.327698) (xy 328.60107 -235.327698) (xy 328.60107 -235.372148)
			(xy 328.701146 -235.472224)
		)
		(stroke
			(width 0)
			(type solid)
		)
		(fill yes)
		(layer "In2.Cu")
		(net "M_C_CPU0_SA_DQ<18>")
	)
	(gr_poly
		(pts
			(xy 328.801222 -234.155996) (xy 328.701146 -234.05592) (xy 328.60107 -234.155996) (xy 328.60107 -234.200446)
			(xy 328.801222 -234.200446)
		)
		(stroke
			(width 0)
			(type solid)
		)
		(fill yes)
		(layer "In2.Cu")
		(net "M_C_CPU0_SA_DQ<13>")
	)
	(gr_poly
		(pts
			(xy 328.801222 -233.752136) (xy 328.801222 -233.707686) (xy 328.60107 -233.707686) (xy 328.60107 -233.752136)
			(xy 328.701146 -233.852212)
		)
		(stroke
			(width 0)
			(type solid)
		)
		(fill yes)
		(layer "In2.Cu")
		(net "M_C_CPU0_SA_DQ<14>")
	)
	(gr_poly
		(pts
			(xy 328.801222 -232.53573) (xy 328.701146 -232.435908) (xy 328.60107 -232.53573) (xy 328.60107 -232.583482)
			(xy 328.801222 -232.583482)
		)
		(stroke
			(width 0)
			(type solid)
		)
		(fill yes)
		(layer "In2.Cu")
		(net "M_C_CPU0_SA_DQS_DN<6>")
	)
	(gr_poly
		(pts
			(xy 328.801222 -232.132378) (xy 328.801222 -232.084626) (xy 328.60107 -232.084626) (xy 328.60107 -232.132378)
			(xy 328.701146 -232.2322)
		)
		(stroke
			(width 0)
			(type solid)
		)
		(fill yes)
		(layer "In2.Cu")
		(net "M_C_CPU0_SA_DQS_DN<1>")
	)
	(gr_poly
		(pts
			(xy 328.819002 -230.513636) (xy 328.855578 -230.376984) (xy 328.718926 -230.340408) (xy 328.680318 -230.36276)
			(xy 328.780394 -230.535988)
		)
		(stroke
			(width 0)
			(type solid)
		)
		(fill yes)
		(layer "In2.Cu")
		(net "M_C_CPU0_SA_DQ<9>")
	)
	(gr_poly
		(pts
			(xy 328.81951 -224.03435) (xy 328.856086 -223.897698) (xy 328.719434 -223.861122) (xy 328.678286 -223.884998)
			(xy 328.778108 -224.058226)
		)
		(stroke
			(width 0)
			(type solid)
		)
		(fill yes)
		(layer "In2.Cu")
		(net "M_C_CPU0_SA_DQS_DN<5>")
	)
	(gr_poly
		(pts
			(xy 328.819764 -228.895148) (xy 328.85634 -228.758496) (xy 328.719688 -228.72192) (xy 328.68108 -228.744018)
			(xy 328.781156 -228.917246)
		)
		(stroke
			(width 0)
			(type solid)
		)
		(fill yes)
		(layer "In2.Cu")
		(net "M_C_CPU0_SA_DQ<8>")
	)
	(gr_poly
		(pts
			(xy 328.819764 -227.275136) (xy 328.85634 -227.138484) (xy 328.719688 -227.101908) (xy 328.68108 -227.124006)
			(xy 328.781156 -227.297234)
		)
		(stroke
			(width 0)
			(type solid)
		)
		(fill yes)
		(layer "In2.Cu")
		(net "M_C_CPU0_SA_DQ<5>")
	)
	(gr_poly
		(pts
			(xy 328.819764 -225.655124) (xy 328.85634 -225.518472) (xy 328.719688 -225.481896) (xy 328.68108 -225.503994)
			(xy 328.781156 -225.677222)
		)
		(stroke
			(width 0)
			(type solid)
		)
		(fill yes)
		(layer "In2.Cu")
		(net "M_C_CPU0_SA_DQ<4>")
	)
	(gr_poly
		(pts
			(xy 329.030838 -293.158672) (xy 328.992484 -293.136574) (xy 328.855832 -293.17315) (xy 328.892408 -293.309802)
			(xy 328.931016 -293.3319)
		)
		(stroke
			(width 0)
			(type solid)
		)
		(fill yes)
		(layer "In2.Cu")
		(net "M_C_CPU0_SB_DQ<29>")
	)
	(gr_poly
		(pts
			(xy 329.101196 -292.107874) (xy 329.00112 -292.007798) (xy 328.901044 -292.107874) (xy 328.901044 -292.152324)
			(xy 329.101196 -292.152324)
		)
		(stroke
			(width 0)
			(type solid)
		)
		(fill yes)
		(layer "In2.Cu")
		(net "M_C_CPU0_SB_DQ<28>")
	)
	(gr_poly
		(pts
			(xy 329.101196 -291.704268) (xy 329.101196 -291.656516) (xy 328.901044 -291.656516) (xy 328.901044 -291.704268)
			(xy 329.00112 -291.80409)
		)
		(stroke
			(width 0)
			(type solid)
		)
		(fill yes)
		(layer "In2.Cu")
		(net "M_C_CPU0_SB_DQS_DP<8>")
	)
	(gr_poly
		(pts
			(xy 329.101196 -290.487608) (xy 329.00112 -290.387786) (xy 328.901044 -290.487608) (xy 328.901044 -290.53536)
			(xy 329.101196 -290.53536)
		)
		(stroke
			(width 0)
			(type solid)
		)
		(fill yes)
		(layer "In2.Cu")
		(net "M_C_CPU0_SB_DQS_DP<3>")
	)
	(gr_poly
		(pts
			(xy 329.101196 -290.084002) (xy 329.101196 -290.039552) (xy 328.901044 -290.039552) (xy 328.901044 -290.084002)
			(xy 329.00112 -290.184078)
		)
		(stroke
			(width 0)
			(type solid)
		)
		(fill yes)
		(layer "In2.Cu")
		(net "M_C_CPU0_SB_DQ<27>")
	)
	(gr_poly
		(pts
			(xy 329.101196 -288.86785) (xy 329.00112 -288.767774) (xy 328.901044 -288.86785) (xy 328.901044 -288.9123)
			(xy 329.101196 -288.9123)
		)
		(stroke
			(width 0)
			(type solid)
		)
		(fill yes)
		(layer "In2.Cu")
		(net "M_C_CPU0_SB_DQ<24>")
	)
	(gr_poly
		(pts
			(xy 329.101196 -288.464244) (xy 329.101196 -288.419794) (xy 328.901044 -288.419794) (xy 328.901044 -288.464244)
			(xy 329.00112 -288.56432)
		)
		(stroke
			(width 0)
			(type solid)
		)
		(fill yes)
		(layer "In2.Cu")
		(net "M_C_CPU0_SB_DQ<23>")
	)
	(gr_poly
		(pts
			(xy 329.101196 -287.247838) (xy 329.00112 -287.148016) (xy 328.901044 -287.247838) (xy 328.901044 -287.292288)
			(xy 329.101196 -287.292288)
		)
		(stroke
			(width 0)
			(type solid)
		)
		(fill yes)
		(layer "In2.Cu")
		(net "M_C_CPU0_SB_DQ<20>")
	)
	(gr_poly
		(pts
			(xy 329.101196 -286.844232) (xy 329.101196 -286.79648) (xy 328.901044 -286.79648) (xy 328.901044 -286.844232)
			(xy 329.00112 -286.944308)
		)
		(stroke
			(width 0)
			(type solid)
		)
		(fill yes)
		(layer "In2.Cu")
		(net "M_C_CPU0_SB_DQS_DP<7>")
	)
	(gr_poly
		(pts
			(xy 329.101196 -285.627826) (xy 329.00112 -285.528004) (xy 328.901044 -285.627826) (xy 328.901044 -285.675578)
			(xy 329.101196 -285.675578)
		)
		(stroke
			(width 0)
			(type solid)
		)
		(fill yes)
		(layer "In2.Cu")
		(net "M_C_CPU0_SB_DQS_DP<2>")
	)
	(gr_poly
		(pts
			(xy 329.101196 -285.22422) (xy 329.101196 -285.17977) (xy 328.901044 -285.17977) (xy 328.901044 -285.22422)
			(xy 329.00112 -285.324296)
		)
		(stroke
			(width 0)
			(type solid)
		)
		(fill yes)
		(layer "In2.Cu")
		(net "M_C_CPU0_SB_DQ<19>")
	)
	(gr_poly
		(pts
			(xy 329.101196 -284.008068) (xy 329.00112 -283.907992) (xy 328.901044 -284.008068) (xy 328.901044 -284.052518)
			(xy 329.101196 -284.052518)
		)
		(stroke
			(width 0)
			(type solid)
		)
		(fill yes)
		(layer "In2.Cu")
		(net "M_C_CPU0_SB_DQ<16>")
	)
	(gr_poly
		(pts
			(xy 329.101196 -283.604208) (xy 329.101196 -283.559758) (xy 328.901044 -283.559758) (xy 328.901044 -283.604208)
			(xy 329.00112 -283.704284)
		)
		(stroke
			(width 0)
			(type solid)
		)
		(fill yes)
		(layer "In2.Cu")
		(net "M_C_CPU0_SB_DQ<15>")
	)
	(gr_poly
		(pts
			(xy 329.101196 -282.388056) (xy 329.00112 -282.28798) (xy 328.901044 -282.388056) (xy 328.901044 -282.432506)
			(xy 329.101196 -282.432506)
		)
		(stroke
			(width 0)
			(type solid)
		)
		(fill yes)
		(layer "In2.Cu")
		(net "M_C_CPU0_SB_DQ<12>")
	)
	(gr_poly
		(pts
			(xy 329.101196 -281.98445) (xy 329.101196 -281.936698) (xy 328.901044 -281.936698) (xy 328.901044 -281.98445)
			(xy 329.00112 -282.084272)
		)
		(stroke
			(width 0)
			(type solid)
		)
		(fill yes)
		(layer "In2.Cu")
		(net "M_C_CPU0_SB_DQS_DP<6>")
	)
	(gr_poly
		(pts
			(xy 329.101196 -280.76779) (xy 329.00112 -280.667968) (xy 328.901044 -280.76779) (xy 328.901044 -280.815542)
			(xy 329.101196 -280.815542)
		)
		(stroke
			(width 0)
			(type solid)
		)
		(fill yes)
		(layer "In2.Cu")
		(net "M_C_CPU0_SB_DQS_DP<1>")
	)
	(gr_poly
		(pts
			(xy 329.101196 -280.364184) (xy 329.101196 -280.319734) (xy 328.901044 -280.319734) (xy 328.901044 -280.364184)
			(xy 329.00112 -280.46426)
		)
		(stroke
			(width 0)
			(type solid)
		)
		(fill yes)
		(layer "In2.Cu")
		(net "M_C_CPU0_SB_DQ<11>")
	)
	(gr_poly
		(pts
			(xy 329.101196 -279.148032) (xy 329.00112 -279.047956) (xy 328.901044 -279.148032) (xy 328.901044 -279.192482)
			(xy 329.101196 -279.192482)
		)
		(stroke
			(width 0)
			(type solid)
		)
		(fill yes)
		(layer "In2.Cu")
		(net "M_C_CPU0_SB_DQ<8>")
	)
	(gr_poly
		(pts
			(xy 329.101196 -278.744172) (xy 329.101196 -278.699722) (xy 328.901044 -278.699722) (xy 328.901044 -278.744172)
			(xy 329.00112 -278.844248)
		)
		(stroke
			(width 0)
			(type solid)
		)
		(fill yes)
		(layer "In2.Cu")
		(net "M_C_CPU0_SB_DQ<7>")
	)
	(gr_poly
		(pts
			(xy 329.101196 -277.52802) (xy 329.00112 -277.427944) (xy 328.901044 -277.52802) (xy 328.901044 -277.57247)
			(xy 329.101196 -277.57247)
		)
		(stroke
			(width 0)
			(type solid)
		)
		(fill yes)
		(layer "In2.Cu")
		(net "M_C_CPU0_SB_DQ<4>")
	)
	(gr_poly
		(pts
			(xy 329.101196 -277.124414) (xy 329.101196 -277.076662) (xy 328.901044 -277.076662) (xy 328.901044 -277.124414)
			(xy 329.00112 -277.224236)
		)
		(stroke
			(width 0)
			(type solid)
		)
		(fill yes)
		(layer "In2.Cu")
		(net "M_C_CPU0_SB_DQS_DP<5>")
	)
	(gr_poly
		(pts
			(xy 329.101196 -275.907754) (xy 329.00112 -275.807932) (xy 328.901044 -275.907754) (xy 328.901044 -275.955506)
			(xy 329.101196 -275.955506)
		)
		(stroke
			(width 0)
			(type solid)
		)
		(fill yes)
		(layer "In2.Cu")
		(net "M_C_CPU0_SB_DQS_DP<0>")
	)
	(gr_poly
		(pts
			(xy 329.101196 -275.504148) (xy 329.101196 -275.459698) (xy 328.901044 -275.459698) (xy 328.901044 -275.504148)
			(xy 329.00112 -275.604224)
		)
		(stroke
			(width 0)
			(type solid)
		)
		(fill yes)
		(layer "In2.Cu")
		(net "M_C_CPU0_SB_DQ<3>")
	)
	(gr_poly
		(pts
			(xy 329.101196 -274.287996) (xy 329.00112 -274.18792) (xy 328.901044 -274.287996) (xy 328.901044 -274.332446)
			(xy 329.101196 -274.332446)
		)
		(stroke
			(width 0)
			(type solid)
		)
		(fill yes)
		(layer "In2.Cu")
		(net "M_C_CPU0_SB_DQ<0>")
	)
	(gr_poly
		(pts
			(xy 329.101196 -273.884136) (xy 329.101196 -273.839686) (xy 328.901044 -273.839686) (xy 328.901044 -273.884136)
			(xy 329.00112 -273.984212)
		)
		(stroke
			(width 0)
			(type solid)
		)
		(fill yes)
		(layer "In2.Cu")
		(net "M_C_CPU0_SB_CB<3>")
	)
	(gr_poly
		(pts
			(xy 329.101196 -272.667984) (xy 329.00112 -272.567908) (xy 328.901044 -272.667984) (xy 328.901044 -272.712434)
			(xy 329.101196 -272.712434)
		)
		(stroke
			(width 0)
			(type solid)
		)
		(fill yes)
		(layer "In2.Cu")
		(net "M_C_CPU0_SB_CB<0>")
	)
	(gr_poly
		(pts
			(xy 329.101196 -272.264378) (xy 329.101196 -272.216626) (xy 328.901044 -272.216626) (xy 328.901044 -272.264378)
			(xy 329.00112 -272.3642)
		)
		(stroke
			(width 0)
			(type solid)
		)
		(fill yes)
		(layer "In2.Cu")
		(net "M_C_CPU0_SB_DQS_DP<4>")
	)
	(gr_poly
		(pts
			(xy 329.101196 -271.047718) (xy 329.00112 -270.947896) (xy 328.901044 -271.047718) (xy 328.901044 -271.09547)
			(xy 329.101196 -271.09547)
		)
		(stroke
			(width 0)
			(type solid)
		)
		(fill yes)
		(layer "In2.Cu")
		(net "M_C_CPU0_SB_DQS_DP<9>")
	)
	(gr_poly
		(pts
			(xy 329.101196 -270.644112) (xy 329.101196 -270.599662) (xy 328.901044 -270.599662) (xy 328.901044 -270.644112)
			(xy 329.00112 -270.744188)
		)
		(stroke
			(width 0)
			(type solid)
		)
		(fill yes)
		(layer "In2.Cu")
		(net "M_C_CPU0_SB_CB<7>")
	)
	(gr_poly
		(pts
			(xy 329.101196 -269.42796) (xy 329.00112 -269.327884) (xy 328.901044 -269.42796) (xy 328.901044 -269.47241)
			(xy 329.101196 -269.47241)
		)
		(stroke
			(width 0)
			(type solid)
		)
		(fill yes)
		(layer "In2.Cu")
		(net "M_C_CPU0_SB_CB<4>")
	)
	(gr_poly
		(pts
			(xy 329.101196 -267.801598) (xy 329.00112 -267.701522) (xy 328.901044 -267.801598) (xy 328.901044 -267.846048)
			(xy 329.101196 -267.846048)
		)
		(stroke
			(width 0)
			(type solid)
		)
		(fill yes)
		(layer "In2.Cu")
		(net "M_C_CPU0_SB_RSP<0>")
	)
	(gr_poly
		(pts
			(xy 329.101196 -265.784076) (xy 329.101196 -265.739626) (xy 328.901044 -265.739626) (xy 328.901044 -265.784076)
			(xy 329.00112 -265.884152)
		)
		(stroke
			(width 0)
			(type solid)
		)
		(fill yes)
		(layer "In2.Cu")
		(net "M_C_CPU0_SB_CS_N<0>")
	)
	(gr_poly
		(pts
			(xy 329.101196 -264.567924) (xy 329.00112 -264.467848) (xy 328.901044 -264.567924) (xy 328.901044 -264.612374)
			(xy 329.101196 -264.612374)
		)
		(stroke
			(width 0)
			(type solid)
		)
		(fill yes)
		(layer "In2.Cu")
		(net "M_C_CPU0_SB_CA<6>")
	)
	(gr_poly
		(pts
			(xy 329.101196 -264.164064) (xy 329.101196 -264.119614) (xy 328.901044 -264.119614) (xy 328.901044 -264.164064)
			(xy 329.00112 -264.26414)
		)
		(stroke
			(width 0)
			(type solid)
		)
		(fill yes)
		(layer "In2.Cu")
		(net "M_C_CPU0_SB_CA<5>")
	)
	(gr_poly
		(pts
			(xy 329.101196 -262.947912) (xy 329.00112 -262.847836) (xy 328.901044 -262.947912) (xy 328.901044 -262.992362)
			(xy 329.101196 -262.992362)
		)
		(stroke
			(width 0)
			(type solid)
		)
		(fill yes)
		(layer "In2.Cu")
		(net "M_C_CPU0_SB_CA<2>")
	)
	(gr_poly
		(pts
			(xy 329.101196 -262.544052) (xy 329.101196 -262.499602) (xy 328.901044 -262.499602) (xy 328.901044 -262.544052)
			(xy 329.00112 -262.644128)
		)
		(stroke
			(width 0)
			(type solid)
		)
		(fill yes)
		(layer "In2.Cu")
		(net "M_C_CPU0_SB_CA<1>")
	)
	(gr_poly
		(pts
			(xy 329.156568 -295.481756) (xy 329.119992 -295.345104) (xy 329.081384 -295.323006) (xy 328.981308 -295.496234)
			(xy 329.019916 -295.518332)
		)
		(stroke
			(width 0)
			(type solid)
		)
		(fill yes)
		(layer "In2.Cu")
		(net "M_C_CPU0_SB_DQ<31>")
	)
	(gr_poly
		(pts
			(xy 329.19035 -228.63302) (xy 329.090274 -228.459792) (xy 329.05192 -228.482144) (xy 329.01509 -228.618796)
			(xy 329.151742 -228.655372)
		)
		(stroke
			(width 0)
			(type solid)
		)
		(fill yes)
		(layer "In2.Cu")
		(net "M_C_CPU0_SA_DQ<7>")
	)
	(gr_poly
		(pts
			(xy 329.19035 -227.013008) (xy 329.090274 -226.83978) (xy 329.05192 -226.862132) (xy 329.01509 -226.998784)
			(xy 329.151742 -227.03536)
		)
		(stroke
			(width 0)
			(type solid)
		)
		(fill yes)
		(layer "In2.Cu")
		(net "M_C_CPU0_SA_DQ<6>")
	)
	(gr_poly
		(pts
			(xy 329.191112 -230.254302) (xy 329.091036 -230.081074) (xy 329.052428 -230.103172) (xy 329.015852 -230.239824)
			(xy 329.152504 -230.2764)
		)
		(stroke
			(width 0)
			(type solid)
		)
		(fill yes)
		(layer "In2.Cu")
		(net "M_C_CPU0_SA_DQ<10>")
	)
	(gr_poly
		(pts
			(xy 329.193144 -225.392234) (xy 329.093322 -225.219006) (xy 329.05192 -225.242882) (xy 329.015344 -225.37928)
			(xy 329.151996 -225.415856)
		)
		(stroke
			(width 0)
			(type solid)
		)
		(fill yes)
		(layer "In2.Cu")
		(net "M_C_CPU0_SA_DQS_DP<5>")
	)
	(gr_poly
		(pts
			(xy 329.193144 -223.772222) (xy 329.093322 -223.598994) (xy 329.05192 -223.62287) (xy 329.015344 -223.759268)
			(xy 329.151996 -223.795844)
		)
		(stroke
			(width 0)
			(type solid)
		)
		(fill yes)
		(layer "In2.Cu")
		(net "M_C_CPU0_SA_DQS_DN<0>")
	)
	(gr_poly
		(pts
			(xy 329.271122 -256.025904) (xy 329.171046 -255.926082) (xy 329.07097 -256.025904) (xy 329.07097 -256.073656)
			(xy 329.271122 -256.073656)
		)
		(stroke
			(width 0)
			(type solid)
		)
		(fill yes)
		(layer "In2.Cu")
		(net "M_C_CPU0_CLK_DP<0>")
	)
	(gr_poly
		(pts
			(xy 329.271122 -255.622298) (xy 329.271122 -255.577848) (xy 329.07097 -255.577848) (xy 329.07097 -255.622298)
			(xy 329.171046 -255.722374)
		)
		(stroke
			(width 0)
			(type solid)
		)
		(fill yes)
		(layer "In2.Cu")
		(net "M_C_CPU0_SA_PAR")
	)
	(gr_poly
		(pts
			(xy 329.271122 -254.406146) (xy 329.171046 -254.30607) (xy 329.07097 -254.406146) (xy 329.07097 -254.450596)
			(xy 329.271122 -254.450596)
		)
		(stroke
			(width 0)
			(type solid)
		)
		(fill yes)
		(layer "In2.Cu")
		(net "M_C_CPU0_SA_CA<4>")
	)
	(gr_poly
		(pts
			(xy 329.271122 -254.002286) (xy 329.271122 -253.957836) (xy 329.07097 -253.957836) (xy 329.07097 -254.002286)
			(xy 329.171046 -254.102362)
		)
		(stroke
			(width 0)
			(type solid)
		)
		(fill yes)
		(layer "In2.Cu")
		(net "M_C_CPU0_SA_CA<3>")
	)
	(gr_poly
		(pts
			(xy 329.271122 -252.786134) (xy 329.171046 -252.686058) (xy 329.07097 -252.786134) (xy 329.07097 -252.830584)
			(xy 329.271122 -252.830584)
		)
		(stroke
			(width 0)
			(type solid)
		)
		(fill yes)
		(layer "In2.Cu")
		(net "M_C_CPU0_SA_CA<0>")
	)
	(gr_poly
		(pts
			(xy 329.271122 -252.382274) (xy 329.271122 -252.337824) (xy 329.07097 -252.337824) (xy 329.07097 -252.382274)
			(xy 329.171046 -252.48235)
		)
		(stroke
			(width 0)
			(type solid)
		)
		(fill yes)
		(layer "In2.Cu")
		(net "M_C_CPU0_SA_CS_N<1>")
	)
	(gr_poly
		(pts
			(xy 329.271122 -250.762262) (xy 329.271122 -250.717812) (xy 329.07097 -250.717812) (xy 329.07097 -250.762262)
			(xy 329.171046 -250.862338)
		)
		(stroke
			(width 0)
			(type solid)
		)
		(fill yes)
		(layer "In2.Cu")
		(net "M_C_CPU0_RESET_N")
	)
	(gr_poly
		(pts
			(xy 329.271122 -249.14225) (xy 329.271122 -249.0978) (xy 329.07097 -249.0978) (xy 329.07097 -249.14225)
			(xy 329.171046 -249.242326)
		)
		(stroke
			(width 0)
			(type solid)
		)
		(fill yes)
		(layer "In2.Cu")
		(net "M_C_CPU0_SA_CB<7>")
	)
	(gr_poly
		(pts
			(xy 329.271122 -247.926098) (xy 329.171046 -247.826022) (xy 329.07097 -247.926098) (xy 329.07097 -247.970548)
			(xy 329.271122 -247.970548)
		)
		(stroke
			(width 0)
			(type solid)
		)
		(fill yes)
		(layer "In2.Cu")
		(net "M_C_CPU0_SA_CB<4>")
	)
	(gr_poly
		(pts
			(xy 329.271122 -247.522492) (xy 329.271122 -247.47474) (xy 329.07097 -247.47474) (xy 329.07097 -247.522492)
			(xy 329.171046 -247.622314)
		)
		(stroke
			(width 0)
			(type solid)
		)
		(fill yes)
		(layer "In2.Cu")
		(net "M_C_CPU0_SA_DQS_DP<9>")
	)
	(gr_poly
		(pts
			(xy 329.271122 -246.305832) (xy 329.171046 -246.20601) (xy 329.07097 -246.305832) (xy 329.07097 -246.353584)
			(xy 329.271122 -246.353584)
		)
		(stroke
			(width 0)
			(type solid)
		)
		(fill yes)
		(layer "In2.Cu")
		(net "M_C_CPU0_SA_DQS_DP<4>")
	)
	(gr_poly
		(pts
			(xy 329.271122 -245.902226) (xy 329.271122 -245.857776) (xy 329.07097 -245.857776) (xy 329.07097 -245.902226)
			(xy 329.171046 -246.002302)
		)
		(stroke
			(width 0)
			(type solid)
		)
		(fill yes)
		(layer "In2.Cu")
		(net "M_C_CPU0_SA_CB<3>")
	)
	(gr_poly
		(pts
			(xy 329.271122 -244.686074) (xy 329.171046 -244.585998) (xy 329.07097 -244.686074) (xy 329.07097 -244.730524)
			(xy 329.271122 -244.730524)
		)
		(stroke
			(width 0)
			(type solid)
		)
		(fill yes)
		(layer "In2.Cu")
		(net "M_C_CPU0_SA_CB<0>")
	)
	(gr_poly
		(pts
			(xy 329.271122 -244.282214) (xy 329.271122 -244.237764) (xy 329.07097 -244.237764) (xy 329.07097 -244.282214)
			(xy 329.171046 -244.38229)
		)
		(stroke
			(width 0)
			(type solid)
		)
		(fill yes)
		(layer "In2.Cu")
		(net "M_C_CPU0_SA_DQ<31>")
	)
	(gr_poly
		(pts
			(xy 329.271122 -243.066062) (xy 329.171046 -242.965986) (xy 329.07097 -243.066062) (xy 329.07097 -243.110512)
			(xy 329.271122 -243.110512)
		)
		(stroke
			(width 0)
			(type solid)
		)
		(fill yes)
		(layer "In2.Cu")
		(net "M_C_CPU0_SA_DQ<28>")
	)
	(gr_poly
		(pts
			(xy 329.271122 -242.662456) (xy 329.271122 -242.614704) (xy 329.07097 -242.614704) (xy 329.07097 -242.662456)
			(xy 329.171046 -242.762278)
		)
		(stroke
			(width 0)
			(type solid)
		)
		(fill yes)
		(layer "In2.Cu")
		(net "M_C_CPU0_SA_DQS_DP<8>")
	)
	(gr_poly
		(pts
			(xy 329.271122 -241.445796) (xy 329.171046 -241.345974) (xy 329.07097 -241.445796) (xy 329.07097 -241.493548)
			(xy 329.271122 -241.493548)
		)
		(stroke
			(width 0)
			(type solid)
		)
		(fill yes)
		(layer "In2.Cu")
		(net "M_C_CPU0_SA_DQS_DP<3>")
	)
	(gr_poly
		(pts
			(xy 329.271122 -241.04219) (xy 329.271122 -240.99774) (xy 329.07097 -240.99774) (xy 329.07097 -241.04219)
			(xy 329.171046 -241.142266)
		)
		(stroke
			(width 0)
			(type solid)
		)
		(fill yes)
		(layer "In2.Cu")
		(net "M_C_CPU0_SA_DQ<27>")
	)
	(gr_poly
		(pts
			(xy 329.271122 -239.826038) (xy 329.171046 -239.725962) (xy 329.07097 -239.826038) (xy 329.07097 -239.870488)
			(xy 329.271122 -239.870488)
		)
		(stroke
			(width 0)
			(type solid)
		)
		(fill yes)
		(layer "In2.Cu")
		(net "M_C_CPU0_SA_DQ<24>")
	)
	(gr_poly
		(pts
			(xy 329.271122 -239.422178) (xy 329.271122 -239.377728) (xy 329.07097 -239.377728) (xy 329.07097 -239.422178)
			(xy 329.171046 -239.522254)
		)
		(stroke
			(width 0)
			(type solid)
		)
		(fill yes)
		(layer "In2.Cu")
		(net "M_C_CPU0_SA_DQ<23>")
	)
	(gr_poly
		(pts
			(xy 329.271122 -238.206026) (xy 329.171046 -238.10595) (xy 329.07097 -238.206026) (xy 329.07097 -238.250476)
			(xy 329.271122 -238.250476)
		)
		(stroke
			(width 0)
			(type solid)
		)
		(fill yes)
		(layer "In2.Cu")
		(net "M_C_CPU0_SA_DQ<20>")
	)
	(gr_poly
		(pts
			(xy 329.271122 -237.80242) (xy 329.271122 -237.754668) (xy 329.07097 -237.754668) (xy 329.07097 -237.80242)
			(xy 329.171046 -237.902242)
		)
		(stroke
			(width 0)
			(type solid)
		)
		(fill yes)
		(layer "In2.Cu")
		(net "M_C_CPU0_SA_DQS_DP<7>")
	)
	(gr_poly
		(pts
			(xy 329.271122 -236.58576) (xy 329.171046 -236.485938) (xy 329.07097 -236.58576) (xy 329.07097 -236.633512)
			(xy 329.271122 -236.633512)
		)
		(stroke
			(width 0)
			(type solid)
		)
		(fill yes)
		(layer "In2.Cu")
		(net "M_C_CPU0_SA_DQS_DP<2>")
	)
	(gr_poly
		(pts
			(xy 329.271122 -236.182154) (xy 329.271122 -236.137704) (xy 329.07097 -236.137704) (xy 329.07097 -236.182154)
			(xy 329.171046 -236.28223)
		)
		(stroke
			(width 0)
			(type solid)
		)
		(fill yes)
		(layer "In2.Cu")
		(net "M_C_CPU0_SA_DQ<19>")
	)
	(gr_poly
		(pts
			(xy 329.271122 -234.966002) (xy 329.171046 -234.865926) (xy 329.07097 -234.966002) (xy 329.07097 -235.010452)
			(xy 329.271122 -235.010452)
		)
		(stroke
			(width 0)
			(type solid)
		)
		(fill yes)
		(layer "In2.Cu")
		(net "M_C_CPU0_SA_DQ<16>")
	)
	(gr_poly
		(pts
			(xy 329.271122 -234.562142) (xy 329.271122 -234.517692) (xy 329.07097 -234.517692) (xy 329.07097 -234.562142)
			(xy 329.171046 -234.662218)
		)
		(stroke
			(width 0)
			(type solid)
		)
		(fill yes)
		(layer "In2.Cu")
		(net "M_C_CPU0_SA_DQ<15>")
	)
	(gr_poly
		(pts
			(xy 329.271122 -233.34599) (xy 329.171046 -233.245914) (xy 329.07097 -233.34599) (xy 329.07097 -233.39044)
			(xy 329.271122 -233.39044)
		)
		(stroke
			(width 0)
			(type solid)
		)
		(fill yes)
		(layer "In2.Cu")
		(net "M_C_CPU0_SA_DQ<12>")
	)
	(gr_poly
		(pts
			(xy 329.271122 -232.942384) (xy 329.271122 -232.894632) (xy 329.07097 -232.894632) (xy 329.07097 -232.942384)
			(xy 329.171046 -233.042206)
		)
		(stroke
			(width 0)
			(type solid)
		)
		(fill yes)
		(layer "In2.Cu")
		(net "M_C_CPU0_SA_DQS_DP<6>")
	)
	(gr_poly
		(pts
			(xy 329.271122 -231.725724) (xy 329.171046 -231.625902) (xy 329.07097 -231.725724) (xy 329.07097 -231.773476)
			(xy 329.271122 -231.773476)
		)
		(stroke
			(width 0)
			(type solid)
		)
		(fill yes)
		(layer "In2.Cu")
		(net "M_C_CPU0_SA_DQS_DP<1>")
	)
	(gr_poly
		(pts
			(xy 329.271122 -231.322372) (xy 329.271122 -231.277922) (xy 329.07097 -231.277922) (xy 329.07097 -231.322372)
			(xy 329.171046 -231.422448)
		)
		(stroke
			(width 0)
			(type solid)
		)
		(fill yes)
		(layer "In2.Cu")
		(net "M_C_CPU0_SA_DQ<11>")
	)
	(gr_poly
		(pts
			(xy 329.290426 -229.70617) (xy 329.327002 -229.569518) (xy 329.190604 -229.532942) (xy 329.151996 -229.555294)
			(xy 329.252072 -229.728522)
		)
		(stroke
			(width 0)
			(type solid)
		)
		(fill yes)
		(layer "In2.Cu")
		(net "M_C_CPU0_SA_DQ<8>")
	)
	(gr_poly
		(pts
			(xy 329.290426 -228.086412) (xy 329.327002 -227.94976) (xy 329.190604 -227.913184) (xy 329.151996 -227.935536)
			(xy 329.252072 -228.108764)
		)
		(stroke
			(width 0)
			(type solid)
		)
		(fill yes)
		(layer "In2.Cu")
		(net "M_C_CPU0_SA_DQ<5>")
	)
	(gr_poly
		(pts
			(xy 329.290426 -226.4664) (xy 329.327002 -226.329748) (xy 329.190604 -226.293172) (xy 329.151996 -226.315524)
			(xy 329.252072 -226.488752)
		)
		(stroke
			(width 0)
			(type solid)
		)
		(fill yes)
		(layer "In2.Cu")
		(net "M_C_CPU0_SA_DQ<4>")
	)
	(gr_poly
		(pts
			(xy 329.290426 -224.845626) (xy 329.327002 -224.709228) (xy 329.19035 -224.672652) (xy 329.149202 -224.696274)
			(xy 329.249024 -224.869502)
		)
		(stroke
			(width 0)
			(type solid)
		)
		(fill yes)
		(layer "In2.Cu")
		(net "M_C_CPU0_SA_DQS_DN<5>")
	)
	(gr_poly
		(pts
			(xy 329.290426 -223.225614) (xy 329.327002 -223.089216) (xy 329.19035 -223.05264) (xy 329.149202 -223.076262)
			(xy 329.249024 -223.24949)
		)
		(stroke
			(width 0)
			(type solid)
		)
		(fill yes)
		(layer "In2.Cu")
		(net "M_C_CPU0_SA_DQS_DP<0>")
	)
	(gr_poly
		(pts
			(xy 329.563984 -291.297614) (xy 329.463908 -291.197792) (xy 329.363832 -291.297614) (xy 329.363832 -291.345366)
			(xy 329.563984 -291.345366)
		)
		(stroke
			(width 0)
			(type solid)
		)
		(fill yes)
		(layer "In2.Cu")
		(net "M_C_CPU0_SB_DQS_DN<8>")
	)
	(gr_poly
		(pts
			(xy 329.571096 -292.91788) (xy 329.47102 -292.817804) (xy 329.370944 -292.91788) (xy 329.370944 -292.96233)
			(xy 329.571096 -292.96233)
		)
		(stroke
			(width 0)
			(type solid)
		)
		(fill yes)
		(layer "In2.Cu")
		(net "M_C_CPU0_SB_DQ<29>")
	)
	(gr_poly
		(pts
			(xy 329.571096 -292.51402) (xy 329.571096 -292.46957) (xy 329.370944 -292.46957) (xy 329.370944 -292.51402)
			(xy 329.47102 -292.614096)
		)
		(stroke
			(width 0)
			(type solid)
		)
		(fill yes)
		(layer "In2.Cu")
		(net "M_C_CPU0_SB_DQ<30>")
	)
	(gr_poly
		(pts
			(xy 329.571096 -290.894262) (xy 329.571096 -290.84651) (xy 329.370944 -290.84651) (xy 329.370944 -290.894262)
			(xy 329.47102 -290.994084)
		)
		(stroke
			(width 0)
			(type solid)
		)
		(fill yes)
		(layer "In2.Cu")
		(net "M_C_CPU0_SB_DQS_DN<3>")
	)
	(gr_poly
		(pts
			(xy 329.571096 -289.677856) (xy 329.47102 -289.57778) (xy 329.370944 -289.677856) (xy 329.370944 -289.722306)
			(xy 329.571096 -289.722306)
		)
		(stroke
			(width 0)
			(type solid)
		)
		(fill yes)
		(layer "In2.Cu")
		(net "M_C_CPU0_SB_DQ<25>")
	)
	(gr_poly
		(pts
			(xy 329.571096 -289.273996) (xy 329.571096 -289.229546) (xy 329.370944 -289.229546) (xy 329.370944 -289.273996)
			(xy 329.47102 -289.374072)
		)
		(stroke
			(width 0)
			(type solid)
		)
		(fill yes)
		(layer "In2.Cu")
		(net "M_C_CPU0_SB_DQ<26>")
	)
	(gr_poly
		(pts
			(xy 329.571096 -288.057844) (xy 329.47102 -287.957768) (xy 329.370944 -288.057844) (xy 329.370944 -288.102294)
			(xy 329.571096 -288.102294)
		)
		(stroke
			(width 0)
			(type solid)
		)
		(fill yes)
		(layer "In2.Cu")
		(net "M_C_CPU0_SB_DQ<21>")
	)
	(gr_poly
		(pts
			(xy 329.571096 -287.654238) (xy 329.571096 -287.609788) (xy 329.370944 -287.609788) (xy 329.370944 -287.654238)
			(xy 329.47102 -287.75406)
		)
		(stroke
			(width 0)
			(type solid)
		)
		(fill yes)
		(layer "In2.Cu")
		(net "M_C_CPU0_SB_DQ<22>")
	)
	(gr_poly
		(pts
			(xy 329.571096 -286.437832) (xy 329.47102 -286.337756) (xy 329.370944 -286.437832) (xy 329.370944 -286.485584)
			(xy 329.571096 -286.485584)
		)
		(stroke
			(width 0)
			(type solid)
		)
		(fill yes)
		(layer "In2.Cu")
		(net "M_C_CPU0_SB_DQS_DN<7>")
	)
	(gr_poly
		(pts
			(xy 329.571096 -286.03448) (xy 329.571096 -285.986728) (xy 329.370944 -285.986728) (xy 329.370944 -286.03448)
			(xy 329.47102 -286.134302)
		)
		(stroke
			(width 0)
			(type solid)
		)
		(fill yes)
		(layer "In2.Cu")
		(net "M_C_CPU0_SB_DQS_DN<2>")
	)
	(gr_poly
		(pts
			(xy 329.571096 -284.818074) (xy 329.47102 -284.717998) (xy 329.370944 -284.818074) (xy 329.370944 -284.862524)
			(xy 329.571096 -284.862524)
		)
		(stroke
			(width 0)
			(type solid)
		)
		(fill yes)
		(layer "In2.Cu")
		(net "M_C_CPU0_SB_DQ<17>")
	)
	(gr_poly
		(pts
			(xy 329.571096 -284.414214) (xy 329.571096 -284.369764) (xy 329.370944 -284.369764) (xy 329.370944 -284.414214)
			(xy 329.47102 -284.51429)
		)
		(stroke
			(width 0)
			(type solid)
		)
		(fill yes)
		(layer "In2.Cu")
		(net "M_C_CPU0_SB_DQ<18>")
	)
	(gr_poly
		(pts
			(xy 329.571096 -283.198062) (xy 329.47102 -283.097986) (xy 329.370944 -283.198062) (xy 329.370944 -283.242512)
			(xy 329.571096 -283.242512)
		)
		(stroke
			(width 0)
			(type solid)
		)
		(fill yes)
		(layer "In2.Cu")
		(net "M_C_CPU0_SB_DQ<13>")
	)
	(gr_poly
		(pts
			(xy 329.571096 -282.794202) (xy 329.571096 -282.749752) (xy 329.370944 -282.749752) (xy 329.370944 -282.794202)
			(xy 329.47102 -282.894278)
		)
		(stroke
			(width 0)
			(type solid)
		)
		(fill yes)
		(layer "In2.Cu")
		(net "M_C_CPU0_SB_DQ<14>")
	)
	(gr_poly
		(pts
			(xy 329.571096 -281.577796) (xy 329.47102 -281.477974) (xy 329.370944 -281.577796) (xy 329.370944 -281.625548)
			(xy 329.571096 -281.625548)
		)
		(stroke
			(width 0)
			(type solid)
		)
		(fill yes)
		(layer "In2.Cu")
		(net "M_C_CPU0_SB_DQS_DN<6>")
	)
	(gr_poly
		(pts
			(xy 329.571096 -281.174444) (xy 329.571096 -281.126692) (xy 329.370944 -281.126692) (xy 329.370944 -281.174444)
			(xy 329.47102 -281.274266)
		)
		(stroke
			(width 0)
			(type solid)
		)
		(fill yes)
		(layer "In2.Cu")
		(net "M_C_CPU0_SB_DQS_DN<1>")
	)
	(gr_poly
		(pts
			(xy 329.571096 -279.958038) (xy 329.47102 -279.857962) (xy 329.370944 -279.958038) (xy 329.370944 -280.002488)
			(xy 329.571096 -280.002488)
		)
		(stroke
			(width 0)
			(type solid)
		)
		(fill yes)
		(layer "In2.Cu")
		(net "M_C_CPU0_SB_DQ<9>")
	)
	(gr_poly
		(pts
			(xy 329.571096 -279.554178) (xy 329.571096 -279.509728) (xy 329.370944 -279.509728) (xy 329.370944 -279.554178)
			(xy 329.47102 -279.654254)
		)
		(stroke
			(width 0)
			(type solid)
		)
		(fill yes)
		(layer "In2.Cu")
		(net "M_C_CPU0_SB_DQ<10>")
	)
	(gr_poly
		(pts
			(xy 329.571096 -278.338026) (xy 329.47102 -278.23795) (xy 329.370944 -278.338026) (xy 329.370944 -278.382476)
			(xy 329.571096 -278.382476)
		)
		(stroke
			(width 0)
			(type solid)
		)
		(fill yes)
		(layer "In2.Cu")
		(net "M_C_CPU0_SB_DQ<5>")
	)
	(gr_poly
		(pts
			(xy 329.571096 -277.934166) (xy 329.571096 -277.889716) (xy 329.370944 -277.889716) (xy 329.370944 -277.934166)
			(xy 329.47102 -278.034242)
		)
		(stroke
			(width 0)
			(type solid)
		)
		(fill yes)
		(layer "In2.Cu")
		(net "M_C_CPU0_SB_DQ<6>")
	)
	(gr_poly
		(pts
			(xy 329.571096 -276.71776) (xy 329.47102 -276.617938) (xy 329.370944 -276.71776) (xy 329.370944 -276.765512)
			(xy 329.571096 -276.765512)
		)
		(stroke
			(width 0)
			(type solid)
		)
		(fill yes)
		(layer "In2.Cu")
		(net "M_C_CPU0_SB_DQS_DN<5>")
	)
	(gr_poly
		(pts
			(xy 329.571096 -276.314408) (xy 329.571096 -276.266656) (xy 329.370944 -276.266656) (xy 329.370944 -276.314408)
			(xy 329.47102 -276.41423)
		)
		(stroke
			(width 0)
			(type solid)
		)
		(fill yes)
		(layer "In2.Cu")
		(net "M_C_CPU0_SB_DQS_DN<0>")
	)
	(gr_poly
		(pts
			(xy 329.571096 -275.098002) (xy 329.47102 -274.997926) (xy 329.370944 -275.098002) (xy 329.370944 -275.142452)
			(xy 329.571096 -275.142452)
		)
		(stroke
			(width 0)
			(type solid)
		)
		(fill yes)
		(layer "In2.Cu")
		(net "M_C_CPU0_SB_DQ<1>")
	)
	(gr_poly
		(pts
			(xy 329.571096 -274.694142) (xy 329.571096 -274.649692) (xy 329.370944 -274.649692) (xy 329.370944 -274.694142)
			(xy 329.47102 -274.794218)
		)
		(stroke
			(width 0)
			(type solid)
		)
		(fill yes)
		(layer "In2.Cu")
		(net "M_C_CPU0_SB_DQ<2>")
	)
	(gr_poly
		(pts
			(xy 329.571096 -273.47799) (xy 329.47102 -273.377914) (xy 329.370944 -273.47799) (xy 329.370944 -273.52244)
			(xy 329.571096 -273.52244)
		)
		(stroke
			(width 0)
			(type solid)
		)
		(fill yes)
		(layer "In2.Cu")
		(net "M_C_CPU0_SB_CB<1>")
	)
	(gr_poly
		(pts
			(xy 329.571096 -273.07413) (xy 329.571096 -273.02968) (xy 329.370944 -273.02968) (xy 329.370944 -273.07413)
			(xy 329.47102 -273.174206)
		)
		(stroke
			(width 0)
			(type solid)
		)
		(fill yes)
		(layer "In2.Cu")
		(net "M_C_CPU0_SB_CB<2>")
	)
	(gr_poly
		(pts
			(xy 329.571096 -271.857724) (xy 329.47102 -271.757902) (xy 329.370944 -271.857724) (xy 329.370944 -271.905476)
			(xy 329.571096 -271.905476)
		)
		(stroke
			(width 0)
			(type solid)
		)
		(fill yes)
		(layer "In2.Cu")
		(net "M_C_CPU0_SB_DQS_DN<4>")
	)
	(gr_poly
		(pts
			(xy 329.571096 -271.454372) (xy 329.571096 -271.40662) (xy 329.370944 -271.40662) (xy 329.370944 -271.454372)
			(xy 329.47102 -271.554194)
		)
		(stroke
			(width 0)
			(type solid)
		)
		(fill yes)
		(layer "In2.Cu")
		(net "M_C_CPU0_SB_DQS_DN<9>")
	)
	(gr_poly
		(pts
			(xy 329.571096 -270.237966) (xy 329.47102 -270.13789) (xy 329.370944 -270.237966) (xy 329.370944 -270.282416)
			(xy 329.571096 -270.282416)
		)
		(stroke
			(width 0)
			(type solid)
		)
		(fill yes)
		(layer "In2.Cu")
		(net "M_C_CPU0_SB_CB<5>")
	)
	(gr_poly
		(pts
			(xy 329.571096 -269.834106) (xy 329.571096 -269.789656) (xy 329.370944 -269.789656) (xy 329.370944 -269.834106)
			(xy 329.47102 -269.934182)
		)
		(stroke
			(width 0)
			(type solid)
		)
		(fill yes)
		(layer "In2.Cu")
		(net "M_C_CPU0_SB_CB<6>")
	)
	(gr_poly
		(pts
			(xy 329.571096 -266.594082) (xy 329.571096 -266.549632) (xy 329.370944 -266.549632) (xy 329.370944 -266.594082)
			(xy 329.47102 -266.694158)
		)
		(stroke
			(width 0)
			(type solid)
		)
		(fill yes)
		(layer "In2.Cu")
		(net "M_C_CPU0_SB_CS_N<1>")
	)
	(gr_poly
		(pts
			(xy 329.571096 -264.97407) (xy 329.571096 -264.92962) (xy 329.370944 -264.92962) (xy 329.370944 -264.97407)
			(xy 329.47102 -265.074146)
		)
		(stroke
			(width 0)
			(type solid)
		)
		(fill yes)
		(layer "In2.Cu")
		(net "M_C_CPU0_SB_PAR")
	)
	(gr_poly
		(pts
			(xy 329.571096 -263.757918) (xy 329.47102 -263.657842) (xy 329.370944 -263.757918) (xy 329.370944 -263.802368)
			(xy 329.571096 -263.802368)
		)
		(stroke
			(width 0)
			(type solid)
		)
		(fill yes)
		(layer "In2.Cu")
		(net "M_C_CPU0_SB_CA<4>")
	)
	(gr_poly
		(pts
			(xy 329.571096 -263.354058) (xy 329.571096 -263.309608) (xy 329.370944 -263.309608) (xy 329.370944 -263.354058)
			(xy 329.47102 -263.454134)
		)
		(stroke
			(width 0)
			(type solid)
		)
		(fill yes)
		(layer "In2.Cu")
		(net "M_C_CPU0_SB_CA<3>")
	)
	(gr_poly
		(pts
			(xy 329.571096 -262.137906) (xy 329.47102 -262.03783) (xy 329.370944 -262.137906) (xy 329.370944 -262.182356)
			(xy 329.571096 -262.182356)
		)
		(stroke
			(width 0)
			(type solid)
		)
		(fill yes)
		(layer "In2.Cu")
		(net "M_C_CPU0_SB_CA<0>")
	)
	(gr_poly
		(pts
			(xy 329.577192 -266.991592) (xy 329.47737 -266.891516) (xy 329.377294 -266.991592) (xy 329.377294 -267.036042)
			(xy 329.577192 -267.036042)
		)
		(stroke
			(width 0)
			(type solid)
		)
		(fill yes)
		(layer "In2.Cu")
		(net "M_C_CPU0_SA_RSP<0>")
	)
	(gr_poly
		(pts
			(xy 329.62723 -294.67048) (xy 329.5904 -294.533828) (xy 329.552046 -294.511476) (xy 329.45197 -294.684704)
			(xy 329.490578 -294.707056)
		)
		(stroke
			(width 0)
			(type solid)
		)
		(fill yes)
		(layer "In2.Cu")
		(net "M_C_CPU0_SB_DQ<31>")
	)
	(gr_poly
		(pts
			(xy 329.66025 -229.443026) (xy 329.560174 -229.269798) (xy 329.52182 -229.29215) (xy 329.48499 -229.428802)
			(xy 329.621642 -229.465378)
		)
		(stroke
			(width 0)
			(type solid)
		)
		(fill yes)
		(layer "In2.Cu")
		(net "M_C_CPU0_SA_DQ<7>")
	)
	(gr_poly
		(pts
			(xy 329.66025 -227.823014) (xy 329.560174 -227.649786) (xy 329.52182 -227.672138) (xy 329.48499 -227.80879)
			(xy 329.621642 -227.845366)
		)
		(stroke
			(width 0)
			(type solid)
		)
		(fill yes)
		(layer "In2.Cu")
		(net "M_C_CPU0_SA_DQ<6>")
	)
	(gr_poly
		(pts
			(xy 329.66025 -222.962978) (xy 329.560174 -222.78975) (xy 329.52182 -222.812102) (xy 329.48499 -222.948754)
			(xy 329.621642 -222.98533)
		)
		(stroke
			(width 0)
			(type solid)
		)
		(fill yes)
		(layer "In2.Cu")
		(net "M_C_CPU0_SA_DQ<3>")
	)
	(gr_poly
		(pts
			(xy 329.663044 -226.20224) (xy 329.563222 -226.029012) (xy 329.52182 -226.052888) (xy 329.485244 -226.189286)
			(xy 329.621896 -226.226116)
		)
		(stroke
			(width 0)
			(type solid)
		)
		(fill yes)
		(layer "In2.Cu")
		(net "M_C_CPU0_SA_DQS_DP<5>")
	)
	(gr_poly
		(pts
			(xy 329.663044 -224.582228) (xy 329.563222 -224.409) (xy 329.52182 -224.432876) (xy 329.485244 -224.569274)
			(xy 329.621896 -224.606104)
		)
		(stroke
			(width 0)
			(type solid)
		)
		(fill yes)
		(layer "In2.Cu")
		(net "M_C_CPU0_SA_DQS_DN<0>")
	)
	(gr_poly
		(pts
			(xy 329.741022 -246.712232) (xy 329.741022 -246.664734) (xy 329.541124 -246.664734) (xy 329.541124 -246.712232)
			(xy 329.640946 -246.812308)
		)
		(stroke
			(width 0)
			(type solid)
		)
		(fill yes)
		(layer "In2.Cu")
		(net "M_C_CPU0_SA_DQS_DN<4>")
	)
	(gr_poly
		(pts
			(xy 329.741276 -256.432558) (xy 329.741276 -256.384806) (xy 329.541124 -256.384806) (xy 329.541124 -256.432558)
			(xy 329.6412 -256.53238)
		)
		(stroke
			(width 0)
			(type solid)
		)
		(fill yes)
		(layer "In2.Cu")
		(net "M_C_CPU0_CLK_DN<0>")
	)
	(gr_poly
		(pts
			(xy 329.741276 -255.216152) (xy 329.6412 -255.116076) (xy 329.541124 -255.216152) (xy 329.541124 -255.260602)
			(xy 329.741276 -255.260602)
		)
		(stroke
			(width 0)
			(type solid)
		)
		(fill yes)
		(layer "In2.Cu")
		(net "M_C_CPU0_SA_CA<6>")
	)
	(gr_poly
		(pts
			(xy 329.741276 -254.812292) (xy 329.741276 -254.767842) (xy 329.541124 -254.767842) (xy 329.541124 -254.812292)
			(xy 329.6412 -254.912368)
		)
		(stroke
			(width 0)
			(type solid)
		)
		(fill yes)
		(layer "In2.Cu")
		(net "M_C_CPU0_SA_CA<5>")
	)
	(gr_poly
		(pts
			(xy 329.741276 -253.59614) (xy 329.6412 -253.496064) (xy 329.541124 -253.59614) (xy 329.541124 -253.64059)
			(xy 329.741276 -253.64059)
		)
		(stroke
			(width 0)
			(type solid)
		)
		(fill yes)
		(layer "In2.Cu")
		(net "M_C_CPU0_SA_CA<2>")
	)
	(gr_poly
		(pts
			(xy 329.741276 -253.19228) (xy 329.741276 -253.14783) (xy 329.541124 -253.14783) (xy 329.541124 -253.19228)
			(xy 329.6412 -253.292356)
		)
		(stroke
			(width 0)
			(type solid)
		)
		(fill yes)
		(layer "In2.Cu")
		(net "M_C_CPU0_SA_CA<1>")
	)
	(gr_poly
		(pts
			(xy 329.741276 -251.572268) (xy 329.741276 -251.527818) (xy 329.541124 -251.527818) (xy 329.541124 -251.572268)
			(xy 329.6412 -251.672344)
		)
		(stroke
			(width 0)
			(type solid)
		)
		(fill yes)
		(layer "In2.Cu")
		(net "M_C_CPU0_SA_CS_N<0>")
	)
	(gr_poly
		(pts
			(xy 329.741276 -250.356116) (xy 329.6412 -250.25604) (xy 329.541124 -250.356116) (xy 329.541124 -250.400566)
			(xy 329.741276 -250.400566)
		)
		(stroke
			(width 0)
			(type solid)
		)
		(fill yes)
		(layer "In2.Cu")
		(net "M_C_CPU0_ALERT_R_N")
	)
	(gr_poly
		(pts
			(xy 329.741276 -248.736104) (xy 329.6412 -248.636028) (xy 329.541124 -248.736104) (xy 329.541124 -248.780554)
			(xy 329.741276 -248.780554)
		)
		(stroke
			(width 0)
			(type solid)
		)
		(fill yes)
		(layer "In2.Cu")
		(net "M_C_CPU0_SA_CB<5>")
	)
	(gr_poly
		(pts
			(xy 329.741276 -248.332244) (xy 329.741276 -248.287794) (xy 329.541124 -248.287794) (xy 329.541124 -248.332244)
			(xy 329.6412 -248.43232)
		)
		(stroke
			(width 0)
			(type solid)
		)
		(fill yes)
		(layer "In2.Cu")
		(net "M_C_CPU0_SA_CB<6>")
	)
	(gr_poly
		(pts
			(xy 329.741276 -247.115838) (xy 329.6412 -247.016016) (xy 329.541124 -247.115838) (xy 329.541124 -247.16359)
			(xy 329.741276 -247.16359)
		)
		(stroke
			(width 0)
			(type solid)
		)
		(fill yes)
		(layer "In2.Cu")
		(net "M_C_CPU0_SA_DQS_DN<9>")
	)
	(gr_poly
		(pts
			(xy 329.741276 -245.49608) (xy 329.6412 -245.396004) (xy 329.541124 -245.49608) (xy 329.541124 -245.54053)
			(xy 329.741276 -245.54053)
		)
		(stroke
			(width 0)
			(type solid)
		)
		(fill yes)
		(layer "In2.Cu")
		(net "M_C_CPU0_SA_CB<1>")
	)
	(gr_poly
		(pts
			(xy 329.741276 -245.09222) (xy 329.741276 -245.04777) (xy 329.541124 -245.04777) (xy 329.541124 -245.09222)
			(xy 329.6412 -245.192296)
		)
		(stroke
			(width 0)
			(type solid)
		)
		(fill yes)
		(layer "In2.Cu")
		(net "M_C_CPU0_SA_CB<2>")
	)
	(gr_poly
		(pts
			(xy 329.741276 -243.876068) (xy 329.6412 -243.775992) (xy 329.541124 -243.876068) (xy 329.541124 -243.920518)
			(xy 329.741276 -243.920518)
		)
		(stroke
			(width 0)
			(type solid)
		)
		(fill yes)
		(layer "In2.Cu")
		(net "M_C_CPU0_SA_DQ<29>")
	)
	(gr_poly
		(pts
			(xy 329.741276 -243.472208) (xy 329.741276 -243.427758) (xy 329.541124 -243.427758) (xy 329.541124 -243.472208)
			(xy 329.6412 -243.572284)
		)
		(stroke
			(width 0)
			(type solid)
		)
		(fill yes)
		(layer "In2.Cu")
		(net "M_C_CPU0_SA_DQ<30>")
	)
	(gr_poly
		(pts
			(xy 329.741276 -242.255802) (xy 329.6412 -242.15598) (xy 329.541124 -242.255802) (xy 329.541124 -242.303554)
			(xy 329.741276 -242.303554)
		)
		(stroke
			(width 0)
			(type solid)
		)
		(fill yes)
		(layer "In2.Cu")
		(net "M_C_CPU0_SA_DQS_DN<8>")
	)
	(gr_poly
		(pts
			(xy 329.741276 -241.85245) (xy 329.741276 -241.804698) (xy 329.541124 -241.804698) (xy 329.541124 -241.85245)
			(xy 329.6412 -241.952272)
		)
		(stroke
			(width 0)
			(type solid)
		)
		(fill yes)
		(layer "In2.Cu")
		(net "M_C_CPU0_SA_DQS_DN<3>")
	)
	(gr_poly
		(pts
			(xy 329.741276 -240.636044) (xy 329.6412 -240.535968) (xy 329.541124 -240.636044) (xy 329.541124 -240.680494)
			(xy 329.741276 -240.680494)
		)
		(stroke
			(width 0)
			(type solid)
		)
		(fill yes)
		(layer "In2.Cu")
		(net "M_C_CPU0_SA_DQ<25>")
	)
	(gr_poly
		(pts
			(xy 329.741276 -240.232184) (xy 329.741276 -240.187734) (xy 329.541124 -240.187734) (xy 329.541124 -240.232184)
			(xy 329.6412 -240.33226)
		)
		(stroke
			(width 0)
			(type solid)
		)
		(fill yes)
		(layer "In2.Cu")
		(net "M_C_CPU0_SA_DQ<26>")
	)
	(gr_poly
		(pts
			(xy 329.741276 -239.016032) (xy 329.6412 -238.915956) (xy 329.541124 -239.016032) (xy 329.541124 -239.060482)
			(xy 329.741276 -239.060482)
		)
		(stroke
			(width 0)
			(type solid)
		)
		(fill yes)
		(layer "In2.Cu")
		(net "M_C_CPU0_SA_DQ<21>")
	)
	(gr_poly
		(pts
			(xy 329.741276 -238.612172) (xy 329.741276 -238.567722) (xy 329.541124 -238.567722) (xy 329.541124 -238.612172)
			(xy 329.6412 -238.712248)
		)
		(stroke
			(width 0)
			(type solid)
		)
		(fill yes)
		(layer "In2.Cu")
		(net "M_C_CPU0_SA_DQ<22>")
	)
	(gr_poly
		(pts
			(xy 329.741276 -237.395766) (xy 329.6412 -237.295944) (xy 329.541124 -237.395766) (xy 329.541124 -237.443518)
			(xy 329.741276 -237.443518)
		)
		(stroke
			(width 0)
			(type solid)
		)
		(fill yes)
		(layer "In2.Cu")
		(net "M_C_CPU0_SA_DQS_DN<7>")
	)
	(gr_poly
		(pts
			(xy 329.741276 -236.992414) (xy 329.741276 -236.944662) (xy 329.541124 -236.944662) (xy 329.541124 -236.992414)
			(xy 329.6412 -237.092236)
		)
		(stroke
			(width 0)
			(type solid)
		)
		(fill yes)
		(layer "In2.Cu")
		(net "M_C_CPU0_SA_DQS_DN<2>")
	)
	(gr_poly
		(pts
			(xy 329.741276 -235.776008) (xy 329.6412 -235.675932) (xy 329.541124 -235.776008) (xy 329.541124 -235.820458)
			(xy 329.741276 -235.820458)
		)
		(stroke
			(width 0)
			(type solid)
		)
		(fill yes)
		(layer "In2.Cu")
		(net "M_C_CPU0_SA_DQ<17>")
	)
	(gr_poly
		(pts
			(xy 329.741276 -235.372148) (xy 329.741276 -235.327698) (xy 329.541124 -235.327698) (xy 329.541124 -235.372148)
			(xy 329.6412 -235.472224)
		)
		(stroke
			(width 0)
			(type solid)
		)
		(fill yes)
		(layer "In2.Cu")
		(net "M_C_CPU0_SA_DQ<18>")
	)
	(gr_poly
		(pts
			(xy 329.741276 -234.155996) (xy 329.6412 -234.05592) (xy 329.541124 -234.155996) (xy 329.541124 -234.200446)
			(xy 329.741276 -234.200446)
		)
		(stroke
			(width 0)
			(type solid)
		)
		(fill yes)
		(layer "In2.Cu")
		(net "M_C_CPU0_SA_DQ<13>")
	)
	(gr_poly
		(pts
			(xy 329.741276 -233.752136) (xy 329.741276 -233.707686) (xy 329.541124 -233.707686) (xy 329.541124 -233.752136)
			(xy 329.6412 -233.852212)
		)
		(stroke
			(width 0)
			(type solid)
		)
		(fill yes)
		(layer "In2.Cu")
		(net "M_C_CPU0_SA_DQ<14>")
	)
	(gr_poly
		(pts
			(xy 329.741276 -232.53573) (xy 329.6412 -232.435908) (xy 329.541124 -232.53573) (xy 329.541124 -232.583482)
			(xy 329.741276 -232.583482)
		)
		(stroke
			(width 0)
			(type solid)
		)
		(fill yes)
		(layer "In2.Cu")
		(net "M_C_CPU0_SA_DQS_DN<6>")
	)
	(gr_poly
		(pts
			(xy 329.741276 -232.132378) (xy 329.741276 -232.084626) (xy 329.541124 -232.084626) (xy 329.541124 -232.132378)
			(xy 329.6412 -232.2322)
		)
		(stroke
			(width 0)
			(type solid)
		)
		(fill yes)
		(layer "In2.Cu")
		(net "M_C_CPU0_SA_DQS_DN<1>")
	)
	(gr_poly
		(pts
			(xy 329.741276 -230.915972) (xy 329.6412 -230.815896) (xy 329.541124 -230.915972) (xy 329.541124 -230.960422)
			(xy 329.741276 -230.960422)
		)
		(stroke
			(width 0)
			(type solid)
		)
		(fill yes)
		(layer "In2.Cu")
		(net "M_C_CPU0_SA_DQ<9>")
	)
	(gr_poly
		(pts
			(xy 329.741276 -230.512366) (xy 329.741276 -230.467916) (xy 329.541124 -230.467916) (xy 329.541124 -230.512366)
			(xy 329.6412 -230.612188)
		)
		(stroke
			(width 0)
			(type solid)
		)
		(fill yes)
		(layer "In2.Cu")
		(net "M_C_CPU0_SA_DQ<10>")
	)
	(gr_poly
		(pts
			(xy 329.760326 -228.896418) (xy 329.796902 -228.759766) (xy 329.660504 -228.72319) (xy 329.621896 -228.745542)
			(xy 329.721972 -228.91877)
		)
		(stroke
			(width 0)
			(type solid)
		)
		(fill yes)
		(layer "In2.Cu")
		(net "M_C_CPU0_SA_DQ<5>")
	)
	(gr_poly
		(pts
			(xy 329.760326 -227.276406) (xy 329.796902 -227.139754) (xy 329.660504 -227.103178) (xy 329.621896 -227.12553)
			(xy 329.721972 -227.298758)
		)
		(stroke
			(width 0)
			(type solid)
		)
		(fill yes)
		(layer "In2.Cu")
		(net "M_C_CPU0_SA_DQ<4>")
	)
	(gr_poly
		(pts
			(xy 329.760326 -225.655632) (xy 329.796902 -225.519234) (xy 329.66025 -225.482404) (xy 329.619102 -225.50628)
			(xy 329.718924 -225.679508)
		)
		(stroke
			(width 0)
			(type solid)
		)
		(fill yes)
		(layer "In2.Cu")
		(net "M_C_CPU0_SA_DQS_DN<5>")
	)
	(gr_poly
		(pts
			(xy 329.760326 -224.03562) (xy 329.796902 -223.899222) (xy 329.66025 -223.862392) (xy 329.619102 -223.886268)
			(xy 329.718924 -224.059496)
		)
		(stroke
			(width 0)
			(type solid)
		)
		(fill yes)
		(layer "In2.Cu")
		(net "M_C_CPU0_SA_DQS_DP<0>")
	)
	(gr_poly
		(pts
			(xy 330.0349 -267.801598) (xy 329.934824 -267.701522) (xy 329.835002 -267.801598) (xy 329.835002 -267.846048)
			(xy 330.0349 -267.846048)
		)
		(stroke
			(width 0)
			(type solid)
		)
		(fill yes)
		(layer "In2.Cu")
		(net "M_C_CPU0_SB_RSP<0>")
	)
	(gr_poly
		(pts
			(xy 330.040996 -291.704268) (xy 330.040996 -291.656516) (xy 329.840844 -291.656516) (xy 329.840844 -291.704268)
			(xy 329.94092 -291.80409)
		)
		(stroke
			(width 0)
			(type solid)
		)
		(fill yes)
		(layer "In2.Cu")
		(net "M_C_CPU0_SB_DQS_DP<8>")
	)
	(gr_poly
		(pts
			(xy 330.04125 -292.107874) (xy 329.941174 -292.007798) (xy 329.841098 -292.107874) (xy 329.841098 -292.152324)
			(xy 330.04125 -292.152324)
		)
		(stroke
			(width 0)
			(type solid)
		)
		(fill yes)
		(layer "In2.Cu")
		(net "M_C_CPU0_SB_DQ<28>")
	)
	(gr_poly
		(pts
			(xy 330.04125 -290.487608) (xy 329.941174 -290.387786) (xy 329.841098 -290.487608) (xy 329.841098 -290.53536)
			(xy 330.04125 -290.53536)
		)
		(stroke
			(width 0)
			(type solid)
		)
		(fill yes)
		(layer "In2.Cu")
		(net "M_C_CPU0_SB_DQS_DP<3>")
	)
	(gr_poly
		(pts
			(xy 330.04125 -290.084002) (xy 330.04125 -290.039552) (xy 329.841098 -290.039552) (xy 329.841098 -290.084002)
			(xy 329.941174 -290.184078)
		)
		(stroke
			(width 0)
			(type solid)
		)
		(fill yes)
		(layer "In2.Cu")
		(net "M_C_CPU0_SB_DQ<27>")
	)
	(gr_poly
		(pts
			(xy 330.04125 -288.86785) (xy 329.941174 -288.767774) (xy 329.841098 -288.86785) (xy 329.841098 -288.9123)
			(xy 330.04125 -288.9123)
		)
		(stroke
			(width 0)
			(type solid)
		)
		(fill yes)
		(layer "In2.Cu")
		(net "M_C_CPU0_SB_DQ<24>")
	)
	(gr_poly
		(pts
			(xy 330.04125 -288.464244) (xy 330.04125 -288.419794) (xy 329.841098 -288.419794) (xy 329.841098 -288.464244)
			(xy 329.941174 -288.56432)
		)
		(stroke
			(width 0)
			(type solid)
		)
		(fill yes)
		(layer "In2.Cu")
		(net "M_C_CPU0_SB_DQ<23>")
	)
	(gr_poly
		(pts
			(xy 330.04125 -287.247838) (xy 329.941174 -287.148016) (xy 329.841098 -287.247838) (xy 329.841098 -287.292288)
			(xy 330.04125 -287.292288)
		)
		(stroke
			(width 0)
			(type solid)
		)
		(fill yes)
		(layer "In2.Cu")
		(net "M_C_CPU0_SB_DQ<20>")
	)
	(gr_poly
		(pts
			(xy 330.04125 -286.844232) (xy 330.04125 -286.79648) (xy 329.841098 -286.79648) (xy 329.841098 -286.844232)
			(xy 329.941174 -286.944308)
		)
		(stroke
			(width 0)
			(type solid)
		)
		(fill yes)
		(layer "In2.Cu")
		(net "M_C_CPU0_SB_DQS_DP<7>")
	)
	(gr_poly
		(pts
			(xy 330.04125 -285.627826) (xy 329.941174 -285.528004) (xy 329.841098 -285.627826) (xy 329.841098 -285.675578)
			(xy 330.04125 -285.675578)
		)
		(stroke
			(width 0)
			(type solid)
		)
		(fill yes)
		(layer "In2.Cu")
		(net "M_C_CPU0_SB_DQS_DP<2>")
	)
	(gr_poly
		(pts
			(xy 330.04125 -285.22422) (xy 330.04125 -285.17977) (xy 329.841098 -285.17977) (xy 329.841098 -285.22422)
			(xy 329.941174 -285.324296)
		)
		(stroke
			(width 0)
			(type solid)
		)
		(fill yes)
		(layer "In2.Cu")
		(net "M_C_CPU0_SB_DQ<19>")
	)
	(gr_poly
		(pts
			(xy 330.04125 -284.008068) (xy 329.941174 -283.907992) (xy 329.841098 -284.008068) (xy 329.841098 -284.052518)
			(xy 330.04125 -284.052518)
		)
		(stroke
			(width 0)
			(type solid)
		)
		(fill yes)
		(layer "In2.Cu")
		(net "M_C_CPU0_SB_DQ<16>")
	)
	(gr_poly
		(pts
			(xy 330.04125 -283.604208) (xy 330.04125 -283.559758) (xy 329.841098 -283.559758) (xy 329.841098 -283.604208)
			(xy 329.941174 -283.704284)
		)
		(stroke
			(width 0)
			(type solid)
		)
		(fill yes)
		(layer "In2.Cu")
		(net "M_C_CPU0_SB_DQ<15>")
	)
	(gr_poly
		(pts
			(xy 330.04125 -282.388056) (xy 329.941174 -282.28798) (xy 329.841098 -282.388056) (xy 329.841098 -282.432506)
			(xy 330.04125 -282.432506)
		)
		(stroke
			(width 0)
			(type solid)
		)
		(fill yes)
		(layer "In2.Cu")
		(net "M_C_CPU0_SB_DQ<12>")
	)
	(gr_poly
		(pts
			(xy 330.04125 -281.98445) (xy 330.04125 -281.936698) (xy 329.841098 -281.936698) (xy 329.841098 -281.98445)
			(xy 329.941174 -282.084272)
		)
		(stroke
			(width 0)
			(type solid)
		)
		(fill yes)
		(layer "In2.Cu")
		(net "M_C_CPU0_SB_DQS_DP<6>")
	)
	(gr_poly
		(pts
			(xy 330.04125 -280.76779) (xy 329.941174 -280.667968) (xy 329.841098 -280.76779) (xy 329.841098 -280.815542)
			(xy 330.04125 -280.815542)
		)
		(stroke
			(width 0)
			(type solid)
		)
		(fill yes)
		(layer "In2.Cu")
		(net "M_C_CPU0_SB_DQS_DP<1>")
	)
	(gr_poly
		(pts
			(xy 330.04125 -280.364184) (xy 330.04125 -280.319734) (xy 329.841098 -280.319734) (xy 329.841098 -280.364184)
			(xy 329.941174 -280.46426)
		)
		(stroke
			(width 0)
			(type solid)
		)
		(fill yes)
		(layer "In2.Cu")
		(net "M_C_CPU0_SB_DQ<11>")
	)
	(gr_poly
		(pts
			(xy 330.04125 -279.148032) (xy 329.941174 -279.047956) (xy 329.841098 -279.148032) (xy 329.841098 -279.192482)
			(xy 330.04125 -279.192482)
		)
		(stroke
			(width 0)
			(type solid)
		)
		(fill yes)
		(layer "In2.Cu")
		(net "M_C_CPU0_SB_DQ<8>")
	)
	(gr_poly
		(pts
			(xy 330.04125 -278.744172) (xy 330.04125 -278.699722) (xy 329.841098 -278.699722) (xy 329.841098 -278.744172)
			(xy 329.941174 -278.844248)
		)
		(stroke
			(width 0)
			(type solid)
		)
		(fill yes)
		(layer "In2.Cu")
		(net "M_C_CPU0_SB_DQ<7>")
	)
	(gr_poly
		(pts
			(xy 330.04125 -277.52802) (xy 329.941174 -277.427944) (xy 329.841098 -277.52802) (xy 329.841098 -277.57247)
			(xy 330.04125 -277.57247)
		)
		(stroke
			(width 0)
			(type solid)
		)
		(fill yes)
		(layer "In2.Cu")
		(net "M_C_CPU0_SB_DQ<4>")
	)
	(gr_poly
		(pts
			(xy 330.04125 -277.124414) (xy 330.04125 -277.076662) (xy 329.841098 -277.076662) (xy 329.841098 -277.124414)
			(xy 329.941174 -277.224236)
		)
		(stroke
			(width 0)
			(type solid)
		)
		(fill yes)
		(layer "In2.Cu")
		(net "M_C_CPU0_SB_DQS_DP<5>")
	)
	(gr_poly
		(pts
			(xy 330.04125 -275.907754) (xy 329.941174 -275.807932) (xy 329.841098 -275.907754) (xy 329.841098 -275.955506)
			(xy 330.04125 -275.955506)
		)
		(stroke
			(width 0)
			(type solid)
		)
		(fill yes)
		(layer "In2.Cu")
		(net "M_C_CPU0_SB_DQS_DP<0>")
	)
	(gr_poly
		(pts
			(xy 330.04125 -275.504148) (xy 330.04125 -275.459698) (xy 329.841098 -275.459698) (xy 329.841098 -275.504148)
			(xy 329.941174 -275.604224)
		)
		(stroke
			(width 0)
			(type solid)
		)
		(fill yes)
		(layer "In2.Cu")
		(net "M_C_CPU0_SB_DQ<3>")
	)
	(gr_poly
		(pts
			(xy 330.04125 -274.287996) (xy 329.941174 -274.18792) (xy 329.841098 -274.287996) (xy 329.841098 -274.332446)
			(xy 330.04125 -274.332446)
		)
		(stroke
			(width 0)
			(type solid)
		)
		(fill yes)
		(layer "In2.Cu")
		(net "M_C_CPU0_SB_DQ<0>")
	)
	(gr_poly
		(pts
			(xy 330.04125 -273.884136) (xy 330.04125 -273.839686) (xy 329.841098 -273.839686) (xy 329.841098 -273.884136)
			(xy 329.941174 -273.984212)
		)
		(stroke
			(width 0)
			(type solid)
		)
		(fill yes)
		(layer "In2.Cu")
		(net "M_C_CPU0_SB_CB<3>")
	)
	(gr_poly
		(pts
			(xy 330.04125 -272.667984) (xy 329.941174 -272.567908) (xy 329.841098 -272.667984) (xy 329.841098 -272.712434)
			(xy 330.04125 -272.712434)
		)
		(stroke
			(width 0)
			(type solid)
		)
		(fill yes)
		(layer "In2.Cu")
		(net "M_C_CPU0_SB_CB<0>")
	)
	(gr_poly
		(pts
			(xy 330.04125 -272.264378) (xy 330.04125 -272.216626) (xy 329.841098 -272.216626) (xy 329.841098 -272.264378)
			(xy 329.941174 -272.3642)
		)
		(stroke
			(width 0)
			(type solid)
		)
		(fill yes)
		(layer "In2.Cu")
		(net "M_C_CPU0_SB_DQS_DP<4>")
	)
	(gr_poly
		(pts
			(xy 330.04125 -271.047718) (xy 329.941174 -270.947896) (xy 329.841098 -271.047718) (xy 329.841098 -271.09547)
			(xy 330.04125 -271.09547)
		)
		(stroke
			(width 0)
			(type solid)
		)
		(fill yes)
		(layer "In2.Cu")
		(net "M_C_CPU0_SB_DQS_DP<9>")
	)
	(gr_poly
		(pts
			(xy 330.04125 -270.644112) (xy 330.04125 -270.599662) (xy 329.841098 -270.599662) (xy 329.841098 -270.644112)
			(xy 329.941174 -270.744188)
		)
		(stroke
			(width 0)
			(type solid)
		)
		(fill yes)
		(layer "In2.Cu")
		(net "M_C_CPU0_SB_CB<7>")
	)
	(gr_poly
		(pts
			(xy 330.04125 -269.42796) (xy 329.941174 -269.327884) (xy 329.841098 -269.42796) (xy 329.841098 -269.47241)
			(xy 330.04125 -269.47241)
		)
		(stroke
			(width 0)
			(type solid)
		)
		(fill yes)
		(layer "In2.Cu")
		(net "M_C_CPU0_SB_CB<4>")
	)
	(gr_poly
		(pts
			(xy 330.04125 -265.784076) (xy 330.04125 -265.739626) (xy 329.841098 -265.739626) (xy 329.841098 -265.784076)
			(xy 329.941174 -265.884152)
		)
		(stroke
			(width 0)
			(type solid)
		)
		(fill yes)
		(layer "In2.Cu")
		(net "M_C_CPU0_SB_CS_N<0>")
	)
	(gr_poly
		(pts
			(xy 330.04125 -264.567924) (xy 329.941174 -264.467848) (xy 329.841098 -264.567924) (xy 329.841098 -264.612374)
			(xy 330.04125 -264.612374)
		)
		(stroke
			(width 0)
			(type solid)
		)
		(fill yes)
		(layer "In2.Cu")
		(net "M_C_CPU0_SB_CA<6>")
	)
	(gr_poly
		(pts
			(xy 330.04125 -264.164064) (xy 330.04125 -264.119614) (xy 329.841098 -264.119614) (xy 329.841098 -264.164064)
			(xy 329.941174 -264.26414)
		)
		(stroke
			(width 0)
			(type solid)
		)
		(fill yes)
		(layer "In2.Cu")
		(net "M_C_CPU0_SB_CA<5>")
	)
	(gr_poly
		(pts
			(xy 330.04125 -262.947912) (xy 329.941174 -262.847836) (xy 329.841098 -262.947912) (xy 329.841098 -262.992362)
			(xy 330.04125 -262.992362)
		)
		(stroke
			(width 0)
			(type solid)
		)
		(fill yes)
		(layer "In2.Cu")
		(net "M_C_CPU0_SB_CA<2>")
	)
	(gr_poly
		(pts
			(xy 330.04125 -262.544052) (xy 330.04125 -262.499602) (xy 329.841098 -262.499602) (xy 329.841098 -262.544052)
			(xy 329.941174 -262.644128)
		)
		(stroke
			(width 0)
			(type solid)
		)
		(fill yes)
		(layer "In2.Cu")
		(net "M_C_CPU0_SB_CA<1>")
	)
	(gr_poly
		(pts
			(xy 330.09713 -293.860474) (xy 330.0603 -293.723822) (xy 330.021946 -293.70147) (xy 329.92187 -293.874698)
			(xy 329.960478 -293.89705)
		)
		(stroke
			(width 0)
			(type solid)
		)
		(fill yes)
		(layer "In2.Cu")
		(net "M_C_CPU0_SB_DQ<31>")
	)
	(gr_poly
		(pts
			(xy 330.131166 -228.634544) (xy 330.03109 -228.461316) (xy 329.992482 -228.483414) (xy 329.955906 -228.620066)
			(xy 330.092558 -228.656642)
		)
		(stroke
			(width 0)
			(type solid)
		)
		(fill yes)
		(layer "In2.Cu")
		(net "M_C_CPU0_SA_DQ<6>")
	)
	(gr_poly
		(pts
			(xy 330.131166 -223.774508) (xy 330.03109 -223.60128) (xy 329.992482 -223.623378) (xy 329.955906 -223.76003)
			(xy 330.092558 -223.796606)
		)
		(stroke
			(width 0)
			(type solid)
		)
		(fill yes)
		(layer "In2.Cu")
		(net "M_C_CPU0_SA_DQ<3>")
	)
	(gr_poly
		(pts
			(xy 330.13396 -227.013516) (xy 330.034138 -226.840288) (xy 329.992736 -226.864164) (xy 329.95616 -227.000816)
			(xy 330.092812 -227.037392)
		)
		(stroke
			(width 0)
			(type solid)
		)
		(fill yes)
		(layer "In2.Cu")
		(net "M_C_CPU0_SA_DQS_DP<5>")
	)
	(gr_poly
		(pts
			(xy 330.13396 -225.393504) (xy 330.034138 -225.220276) (xy 329.992736 -225.244152) (xy 329.95616 -225.380804)
			(xy 330.092812 -225.41738)
		)
		(stroke
			(width 0)
			(type solid)
		)
		(fill yes)
		(layer "In2.Cu")
		(net "M_C_CPU0_SA_DQS_DN<0>")
	)
	(gr_poly
		(pts
			(xy 330.211176 -256.025904) (xy 330.1111 -255.926082) (xy 330.011024 -256.025904) (xy 330.011024 -256.073656)
			(xy 330.211176 -256.073656)
		)
		(stroke
			(width 0)
			(type solid)
		)
		(fill yes)
		(layer "In2.Cu")
		(net "M_C_CPU0_CLK_DP<0>")
	)
	(gr_poly
		(pts
			(xy 330.211176 -255.622298) (xy 330.211176 -255.577848) (xy 330.011024 -255.577848) (xy 330.011024 -255.622298)
			(xy 330.1111 -255.722374)
		)
		(stroke
			(width 0)
			(type solid)
		)
		(fill yes)
		(layer "In2.Cu")
		(net "M_C_CPU0_SA_PAR")
	)
	(gr_poly
		(pts
			(xy 330.211176 -254.406146) (xy 330.1111 -254.30607) (xy 330.011024 -254.406146) (xy 330.011024 -254.450596)
			(xy 330.211176 -254.450596)
		)
		(stroke
			(width 0)
			(type solid)
		)
		(fill yes)
		(layer "In2.Cu")
		(net "M_C_CPU0_SA_CA<4>")
	)
	(gr_poly
		(pts
			(xy 330.211176 -254.002286) (xy 330.211176 -253.957836) (xy 330.011024 -253.957836) (xy 330.011024 -254.002286)
			(xy 330.1111 -254.102362)
		)
		(stroke
			(width 0)
			(type solid)
		)
		(fill yes)
		(layer "In2.Cu")
		(net "M_C_CPU0_SA_CA<3>")
	)
	(gr_poly
		(pts
			(xy 330.211176 -252.786134) (xy 330.1111 -252.686058) (xy 330.011024 -252.786134) (xy 330.011024 -252.830584)
			(xy 330.211176 -252.830584)
		)
		(stroke
			(width 0)
			(type solid)
		)
		(fill yes)
		(layer "In2.Cu")
		(net "M_C_CPU0_SA_CA<0>")
	)
	(gr_poly
		(pts
			(xy 330.211176 -252.382274) (xy 330.211176 -252.337824) (xy 330.011024 -252.337824) (xy 330.011024 -252.382274)
			(xy 330.1111 -252.48235)
		)
		(stroke
			(width 0)
			(type solid)
		)
		(fill yes)
		(layer "In2.Cu")
		(net "M_C_CPU0_SA_CS_N<1>")
	)
	(gr_poly
		(pts
			(xy 330.211176 -250.762262) (xy 330.211176 -250.717812) (xy 330.011024 -250.717812) (xy 330.011024 -250.762262)
			(xy 330.1111 -250.862338)
		)
		(stroke
			(width 0)
			(type solid)
		)
		(fill yes)
		(layer "In2.Cu")
		(net "M_C_CPU0_RESET_N")
	)
	(gr_poly
		(pts
			(xy 330.211176 -249.14225) (xy 330.211176 -249.0978) (xy 330.011024 -249.0978) (xy 330.011024 -249.14225)
			(xy 330.1111 -249.242326)
		)
		(stroke
			(width 0)
			(type solid)
		)
		(fill yes)
		(layer "In2.Cu")
		(net "M_C_CPU0_SA_CB<7>")
	)
	(gr_poly
		(pts
			(xy 330.211176 -247.926098) (xy 330.1111 -247.826022) (xy 330.011024 -247.926098) (xy 330.011024 -247.970548)
			(xy 330.211176 -247.970548)
		)
		(stroke
			(width 0)
			(type solid)
		)
		(fill yes)
		(layer "In2.Cu")
		(net "M_C_CPU0_SA_CB<4>")
	)
	(gr_poly
		(pts
			(xy 330.211176 -247.522492) (xy 330.211176 -247.47474) (xy 330.011024 -247.47474) (xy 330.011024 -247.522492)
			(xy 330.1111 -247.622314)
		)
		(stroke
			(width 0)
			(type solid)
		)
		(fill yes)
		(layer "In2.Cu")
		(net "M_C_CPU0_SA_DQS_DP<9>")
	)
	(gr_poly
		(pts
			(xy 330.211176 -246.305832) (xy 330.1111 -246.20601) (xy 330.011024 -246.305832) (xy 330.011024 -246.353584)
			(xy 330.211176 -246.353584)
		)
		(stroke
			(width 0)
			(type solid)
		)
		(fill yes)
		(layer "In2.Cu")
		(net "M_C_CPU0_SA_DQS_DP<4>")
	)
	(gr_poly
		(pts
			(xy 330.211176 -245.902226) (xy 330.211176 -245.857776) (xy 330.011024 -245.857776) (xy 330.011024 -245.902226)
			(xy 330.1111 -246.002302)
		)
		(stroke
			(width 0)
			(type solid)
		)
		(fill yes)
		(layer "In2.Cu")
		(net "M_C_CPU0_SA_CB<3>")
	)
	(gr_poly
		(pts
			(xy 330.211176 -244.686074) (xy 330.1111 -244.585998) (xy 330.011024 -244.686074) (xy 330.011024 -244.730524)
			(xy 330.211176 -244.730524)
		)
		(stroke
			(width 0)
			(type solid)
		)
		(fill yes)
		(layer "In2.Cu")
		(net "M_C_CPU0_SA_CB<0>")
	)
	(gr_poly
		(pts
			(xy 330.211176 -244.282214) (xy 330.211176 -244.237764) (xy 330.011024 -244.237764) (xy 330.011024 -244.282214)
			(xy 330.1111 -244.38229)
		)
		(stroke
			(width 0)
			(type solid)
		)
		(fill yes)
		(layer "In2.Cu")
		(net "M_C_CPU0_SA_DQ<31>")
	)
	(gr_poly
		(pts
			(xy 330.211176 -243.066062) (xy 330.1111 -242.965986) (xy 330.011024 -243.066062) (xy 330.011024 -243.110512)
			(xy 330.211176 -243.110512)
		)
		(stroke
			(width 0)
			(type solid)
		)
		(fill yes)
		(layer "In2.Cu")
		(net "M_C_CPU0_SA_DQ<28>")
	)
	(gr_poly
		(pts
			(xy 330.211176 -242.662456) (xy 330.211176 -242.614704) (xy 330.011024 -242.614704) (xy 330.011024 -242.662456)
			(xy 330.1111 -242.762278)
		)
		(stroke
			(width 0)
			(type solid)
		)
		(fill yes)
		(layer "In2.Cu")
		(net "M_C_CPU0_SA_DQS_DP<8>")
	)
	(gr_poly
		(pts
			(xy 330.211176 -241.445796) (xy 330.1111 -241.345974) (xy 330.011024 -241.445796) (xy 330.011024 -241.493548)
			(xy 330.211176 -241.493548)
		)
		(stroke
			(width 0)
			(type solid)
		)
		(fill yes)
		(layer "In2.Cu")
		(net "M_C_CPU0_SA_DQS_DP<3>")
	)
	(gr_poly
		(pts
			(xy 330.211176 -241.04219) (xy 330.211176 -240.99774) (xy 330.011024 -240.99774) (xy 330.011024 -241.04219)
			(xy 330.1111 -241.142266)
		)
		(stroke
			(width 0)
			(type solid)
		)
		(fill yes)
		(layer "In2.Cu")
		(net "M_C_CPU0_SA_DQ<27>")
	)
	(gr_poly
		(pts
			(xy 330.211176 -239.826038) (xy 330.1111 -239.725962) (xy 330.011024 -239.826038) (xy 330.011024 -239.870488)
			(xy 330.211176 -239.870488)
		)
		(stroke
			(width 0)
			(type solid)
		)
		(fill yes)
		(layer "In2.Cu")
		(net "M_C_CPU0_SA_DQ<24>")
	)
	(gr_poly
		(pts
			(xy 330.211176 -239.422178) (xy 330.211176 -239.377728) (xy 330.011024 -239.377728) (xy 330.011024 -239.422178)
			(xy 330.1111 -239.522254)
		)
		(stroke
			(width 0)
			(type solid)
		)
		(fill yes)
		(layer "In2.Cu")
		(net "M_C_CPU0_SA_DQ<23>")
	)
	(gr_poly
		(pts
			(xy 330.211176 -238.206026) (xy 330.1111 -238.10595) (xy 330.011024 -238.206026) (xy 330.011024 -238.250476)
			(xy 330.211176 -238.250476)
		)
		(stroke
			(width 0)
			(type solid)
		)
		(fill yes)
		(layer "In2.Cu")
		(net "M_C_CPU0_SA_DQ<20>")
	)
	(gr_poly
		(pts
			(xy 330.211176 -237.80242) (xy 330.211176 -237.754668) (xy 330.011024 -237.754668) (xy 330.011024 -237.80242)
			(xy 330.1111 -237.902242)
		)
		(stroke
			(width 0)
			(type solid)
		)
		(fill yes)
		(layer "In2.Cu")
		(net "M_C_CPU0_SA_DQS_DP<7>")
	)
	(gr_poly
		(pts
			(xy 330.211176 -236.58576) (xy 330.1111 -236.485938) (xy 330.011024 -236.58576) (xy 330.011024 -236.633512)
			(xy 330.211176 -236.633512)
		)
		(stroke
			(width 0)
			(type solid)
		)
		(fill yes)
		(layer "In2.Cu")
		(net "M_C_CPU0_SA_DQS_DP<2>")
	)
	(gr_poly
		(pts
			(xy 330.211176 -236.182154) (xy 330.211176 -236.137704) (xy 330.011024 -236.137704) (xy 330.011024 -236.182154)
			(xy 330.1111 -236.28223)
		)
		(stroke
			(width 0)
			(type solid)
		)
		(fill yes)
		(layer "In2.Cu")
		(net "M_C_CPU0_SA_DQ<19>")
	)
	(gr_poly
		(pts
			(xy 330.211176 -234.966002) (xy 330.1111 -234.865926) (xy 330.011024 -234.966002) (xy 330.011024 -235.010452)
			(xy 330.211176 -235.010452)
		)
		(stroke
			(width 0)
			(type solid)
		)
		(fill yes)
		(layer "In2.Cu")
		(net "M_C_CPU0_SA_DQ<16>")
	)
	(gr_poly
		(pts
			(xy 330.211176 -234.562142) (xy 330.211176 -234.517692) (xy 330.011024 -234.517692) (xy 330.011024 -234.562142)
			(xy 330.1111 -234.662218)
		)
		(stroke
			(width 0)
			(type solid)
		)
		(fill yes)
		(layer "In2.Cu")
		(net "M_C_CPU0_SA_DQ<15>")
	)
	(gr_poly
		(pts
			(xy 330.211176 -233.34599) (xy 330.1111 -233.245914) (xy 330.011024 -233.34599) (xy 330.011024 -233.39044)
			(xy 330.211176 -233.39044)
		)
		(stroke
			(width 0)
			(type solid)
		)
		(fill yes)
		(layer "In2.Cu")
		(net "M_C_CPU0_SA_DQ<12>")
	)
	(gr_poly
		(pts
			(xy 330.211176 -232.942384) (xy 330.211176 -232.894632) (xy 330.011024 -232.894632) (xy 330.011024 -232.942384)
			(xy 330.1111 -233.042206)
		)
		(stroke
			(width 0)
			(type solid)
		)
		(fill yes)
		(layer "In2.Cu")
		(net "M_C_CPU0_SA_DQS_DP<6>")
	)
	(gr_poly
		(pts
			(xy 330.211176 -231.725724) (xy 330.1111 -231.625902) (xy 330.011024 -231.725724) (xy 330.011024 -231.773476)
			(xy 330.211176 -231.773476)
		)
		(stroke
			(width 0)
			(type solid)
		)
		(fill yes)
		(layer "In2.Cu")
		(net "M_C_CPU0_SA_DQS_DP<1>")
	)
	(gr_poly
		(pts
			(xy 330.211176 -231.322372) (xy 330.211176 -231.277922) (xy 330.011024 -231.277922) (xy 330.011024 -231.322372)
			(xy 330.1111 -231.422448)
		)
		(stroke
			(width 0)
			(type solid)
		)
		(fill yes)
		(layer "In2.Cu")
		(net "M_C_CPU0_SA_DQ<11>")
	)
	(gr_poly
		(pts
			(xy 330.211176 -230.105966) (xy 330.1111 -230.006144) (xy 330.011024 -230.105966) (xy 330.011024 -230.150416)
			(xy 330.211176 -230.150416)
		)
		(stroke
			(width 0)
			(type solid)
		)
		(fill yes)
		(layer "In2.Cu")
		(net "M_C_CPU0_SA_DQ<8>")
	)
	(gr_poly
		(pts
			(xy 330.211176 -229.70236) (xy 330.211176 -229.65791) (xy 330.011024 -229.65791) (xy 330.011024 -229.70236)
			(xy 330.1111 -229.802436)
		)
		(stroke
			(width 0)
			(type solid)
		)
		(fill yes)
		(layer "In2.Cu")
		(net "M_C_CPU0_SA_DQ<7>")
	)
	(gr_poly
		(pts
			(xy 330.229464 -226.464368) (xy 330.26604 -226.327716) (xy 330.129388 -226.29114) (xy 330.08824 -226.315016)
			(xy 330.188062 -226.488244)
		)
		(stroke
			(width 0)
			(type solid)
		)
		(fill yes)
		(layer "In2.Cu")
		(net "M_C_CPU0_SA_DQS_DN<5>")
	)
	(gr_poly
		(pts
			(xy 330.229464 -224.844356) (xy 330.26604 -224.707704) (xy 330.129388 -224.671128) (xy 330.08824 -224.695004)
			(xy 330.188062 -224.868232)
		)
		(stroke
			(width 0)
			(type solid)
		)
		(fill yes)
		(layer "In2.Cu")
		(net "M_C_CPU0_SA_DQS_DP<0>")
	)
	(gr_poly
		(pts
			(xy 330.229718 -228.085142) (xy 330.266294 -227.94849) (xy 330.129642 -227.911914) (xy 330.091034 -227.934012)
			(xy 330.19111 -228.10724)
		)
		(stroke
			(width 0)
			(type solid)
		)
		(fill yes)
		(layer "In2.Cu")
		(net "M_C_CPU0_SA_DQ<4>")
	)
	(gr_poly
		(pts
			(xy 330.229718 -223.225106) (xy 330.266294 -223.088454) (xy 330.129642 -223.051878) (xy 330.091034 -223.073976)
			(xy 330.19111 -223.247204)
		)
		(stroke
			(width 0)
			(type solid)
		)
		(fill yes)
		(layer "In2.Cu")
		(net "M_C_CPU0_SA_DQ<1>")
	)
	(gr_poly
		(pts
			(xy 330.51115 -292.91788) (xy 330.411074 -292.817804) (xy 330.310998 -292.91788) (xy 330.310998 -292.96233)
			(xy 330.51115 -292.96233)
		)
		(stroke
			(width 0)
			(type solid)
		)
		(fill yes)
		(layer "In2.Cu")
		(net "M_C_CPU0_SB_DQ<29>")
	)
	(gr_poly
		(pts
			(xy 330.51115 -292.51402) (xy 330.51115 -292.46957) (xy 330.310998 -292.46957) (xy 330.310998 -292.51402)
			(xy 330.411074 -292.614096)
		)
		(stroke
			(width 0)
			(type solid)
		)
		(fill yes)
		(layer "In2.Cu")
		(net "M_C_CPU0_SB_DQ<30>")
	)
	(gr_poly
		(pts
			(xy 330.51115 -291.297614) (xy 330.411074 -291.197792) (xy 330.310998 -291.297614) (xy 330.310998 -291.345366)
			(xy 330.51115 -291.345366)
		)
		(stroke
			(width 0)
			(type solid)
		)
		(fill yes)
		(layer "In2.Cu")
		(net "M_C_CPU0_SB_DQS_DN<8>")
	)
	(gr_poly
		(pts
			(xy 330.51115 -290.894262) (xy 330.51115 -290.84651) (xy 330.310998 -290.84651) (xy 330.310998 -290.894262)
			(xy 330.411074 -290.994084)
		)
		(stroke
			(width 0)
			(type solid)
		)
		(fill yes)
		(layer "In2.Cu")
		(net "M_C_CPU0_SB_DQS_DN<3>")
	)
	(gr_poly
		(pts
			(xy 330.51115 -289.677856) (xy 330.411074 -289.57778) (xy 330.310998 -289.677856) (xy 330.310998 -289.722306)
			(xy 330.51115 -289.722306)
		)
		(stroke
			(width 0)
			(type solid)
		)
		(fill yes)
		(layer "In2.Cu")
		(net "M_C_CPU0_SB_DQ<25>")
	)
	(gr_poly
		(pts
			(xy 330.51115 -289.273996) (xy 330.51115 -289.229546) (xy 330.310998 -289.229546) (xy 330.310998 -289.273996)
			(xy 330.411074 -289.374072)
		)
		(stroke
			(width 0)
			(type solid)
		)
		(fill yes)
		(layer "In2.Cu")
		(net "M_C_CPU0_SB_DQ<26>")
	)
	(gr_poly
		(pts
			(xy 330.51115 -288.057844) (xy 330.411074 -287.957768) (xy 330.310998 -288.057844) (xy 330.310998 -288.102294)
			(xy 330.51115 -288.102294)
		)
		(stroke
			(width 0)
			(type solid)
		)
		(fill yes)
		(layer "In2.Cu")
		(net "M_C_CPU0_SB_DQ<21>")
	)
	(gr_poly
		(pts
			(xy 330.51115 -287.654238) (xy 330.51115 -287.609788) (xy 330.310998 -287.609788) (xy 330.310998 -287.654238)
			(xy 330.411074 -287.75406)
		)
		(stroke
			(width 0)
			(type solid)
		)
		(fill yes)
		(layer "In2.Cu")
		(net "M_C_CPU0_SB_DQ<22>")
	)
	(gr_poly
		(pts
			(xy 330.51115 -286.437832) (xy 330.411074 -286.337756) (xy 330.310998 -286.437832) (xy 330.310998 -286.485584)
			(xy 330.51115 -286.485584)
		)
		(stroke
			(width 0)
			(type solid)
		)
		(fill yes)
		(layer "In2.Cu")
		(net "M_C_CPU0_SB_DQS_DN<7>")
	)
	(gr_poly
		(pts
			(xy 330.51115 -286.03448) (xy 330.51115 -285.986728) (xy 330.310998 -285.986728) (xy 330.310998 -286.03448)
			(xy 330.411074 -286.134302)
		)
		(stroke
			(width 0)
			(type solid)
		)
		(fill yes)
		(layer "In2.Cu")
		(net "M_C_CPU0_SB_DQS_DN<2>")
	)
	(gr_poly
		(pts
			(xy 330.51115 -284.818074) (xy 330.411074 -284.717998) (xy 330.310998 -284.818074) (xy 330.310998 -284.862524)
			(xy 330.51115 -284.862524)
		)
		(stroke
			(width 0)
			(type solid)
		)
		(fill yes)
		(layer "In2.Cu")
		(net "M_C_CPU0_SB_DQ<17>")
	)
	(gr_poly
		(pts
			(xy 330.51115 -284.414214) (xy 330.51115 -284.369764) (xy 330.310998 -284.369764) (xy 330.310998 -284.414214)
			(xy 330.411074 -284.51429)
		)
		(stroke
			(width 0)
			(type solid)
		)
		(fill yes)
		(layer "In2.Cu")
		(net "M_C_CPU0_SB_DQ<18>")
	)
	(gr_poly
		(pts
			(xy 330.51115 -283.198062) (xy 330.411074 -283.097986) (xy 330.310998 -283.198062) (xy 330.310998 -283.242512)
			(xy 330.51115 -283.242512)
		)
		(stroke
			(width 0)
			(type solid)
		)
		(fill yes)
		(layer "In2.Cu")
		(net "M_C_CPU0_SB_DQ<13>")
	)
	(gr_poly
		(pts
			(xy 330.51115 -282.794202) (xy 330.51115 -282.749752) (xy 330.310998 -282.749752) (xy 330.310998 -282.794202)
			(xy 330.411074 -282.894278)
		)
		(stroke
			(width 0)
			(type solid)
		)
		(fill yes)
		(layer "In2.Cu")
		(net "M_C_CPU0_SB_DQ<14>")
	)
	(gr_poly
		(pts
			(xy 330.51115 -281.577796) (xy 330.411074 -281.477974) (xy 330.310998 -281.577796) (xy 330.310998 -281.625548)
			(xy 330.51115 -281.625548)
		)
		(stroke
			(width 0)
			(type solid)
		)
		(fill yes)
		(layer "In2.Cu")
		(net "M_C_CPU0_SB_DQS_DN<6>")
	)
	(gr_poly
		(pts
			(xy 330.51115 -281.174444) (xy 330.51115 -281.126692) (xy 330.310998 -281.126692) (xy 330.310998 -281.174444)
			(xy 330.411074 -281.274266)
		)
		(stroke
			(width 0)
			(type solid)
		)
		(fill yes)
		(layer "In2.Cu")
		(net "M_C_CPU0_SB_DQS_DN<1>")
	)
	(gr_poly
		(pts
			(xy 330.51115 -279.958038) (xy 330.411074 -279.857962) (xy 330.310998 -279.958038) (xy 330.310998 -280.002488)
			(xy 330.51115 -280.002488)
		)
		(stroke
			(width 0)
			(type solid)
		)
		(fill yes)
		(layer "In2.Cu")
		(net "M_C_CPU0_SB_DQ<9>")
	)
	(gr_poly
		(pts
			(xy 330.51115 -279.554178) (xy 330.51115 -279.509728) (xy 330.310998 -279.509728) (xy 330.310998 -279.554178)
			(xy 330.411074 -279.654254)
		)
		(stroke
			(width 0)
			(type solid)
		)
		(fill yes)
		(layer "In2.Cu")
		(net "M_C_CPU0_SB_DQ<10>")
	)
	(gr_poly
		(pts
			(xy 330.51115 -278.338026) (xy 330.411074 -278.23795) (xy 330.310998 -278.338026) (xy 330.310998 -278.382476)
			(xy 330.51115 -278.382476)
		)
		(stroke
			(width 0)
			(type solid)
		)
		(fill yes)
		(layer "In2.Cu")
		(net "M_C_CPU0_SB_DQ<5>")
	)
	(gr_poly
		(pts
			(xy 330.51115 -277.934166) (xy 330.51115 -277.889716) (xy 330.310998 -277.889716) (xy 330.310998 -277.934166)
			(xy 330.411074 -278.034242)
		)
		(stroke
			(width 0)
			(type solid)
		)
		(fill yes)
		(layer "In2.Cu")
		(net "M_C_CPU0_SB_DQ<6>")
	)
	(gr_poly
		(pts
			(xy 330.51115 -276.71776) (xy 330.411074 -276.617938) (xy 330.310998 -276.71776) (xy 330.310998 -276.765512)
			(xy 330.51115 -276.765512)
		)
		(stroke
			(width 0)
			(type solid)
		)
		(fill yes)
		(layer "In2.Cu")
		(net "M_C_CPU0_SB_DQS_DN<5>")
	)
	(gr_poly
		(pts
			(xy 330.51115 -276.314408) (xy 330.51115 -276.266656) (xy 330.310998 -276.266656) (xy 330.310998 -276.314408)
			(xy 330.411074 -276.41423)
		)
		(stroke
			(width 0)
			(type solid)
		)
		(fill yes)
		(layer "In2.Cu")
		(net "M_C_CPU0_SB_DQS_DN<0>")
	)
	(gr_poly
		(pts
			(xy 330.51115 -275.098002) (xy 330.411074 -274.997926) (xy 330.310998 -275.098002) (xy 330.310998 -275.142452)
			(xy 330.51115 -275.142452)
		)
		(stroke
			(width 0)
			(type solid)
		)
		(fill yes)
		(layer "In2.Cu")
		(net "M_C_CPU0_SB_DQ<1>")
	)
	(gr_poly
		(pts
			(xy 330.51115 -274.694142) (xy 330.51115 -274.649692) (xy 330.310998 -274.649692) (xy 330.310998 -274.694142)
			(xy 330.411074 -274.794218)
		)
		(stroke
			(width 0)
			(type solid)
		)
		(fill yes)
		(layer "In2.Cu")
		(net "M_C_CPU0_SB_DQ<2>")
	)
	(gr_poly
		(pts
			(xy 330.51115 -273.47799) (xy 330.411074 -273.377914) (xy 330.310998 -273.47799) (xy 330.310998 -273.52244)
			(xy 330.51115 -273.52244)
		)
		(stroke
			(width 0)
			(type solid)
		)
		(fill yes)
		(layer "In2.Cu")
		(net "M_C_CPU0_SB_CB<1>")
	)
	(gr_poly
		(pts
			(xy 330.51115 -273.07413) (xy 330.51115 -273.02968) (xy 330.310998 -273.02968) (xy 330.310998 -273.07413)
			(xy 330.411074 -273.174206)
		)
		(stroke
			(width 0)
			(type solid)
		)
		(fill yes)
		(layer "In2.Cu")
		(net "M_C_CPU0_SB_CB<2>")
	)
	(gr_poly
		(pts
			(xy 330.51115 -271.857724) (xy 330.411074 -271.757902) (xy 330.310998 -271.857724) (xy 330.310998 -271.905476)
			(xy 330.51115 -271.905476)
		)
		(stroke
			(width 0)
			(type solid)
		)
		(fill yes)
		(layer "In2.Cu")
		(net "M_C_CPU0_SB_DQS_DN<4>")
	)
	(gr_poly
		(pts
			(xy 330.51115 -271.454372) (xy 330.51115 -271.40662) (xy 330.310998 -271.40662) (xy 330.310998 -271.454372)
			(xy 330.411074 -271.554194)
		)
		(stroke
			(width 0)
			(type solid)
		)
		(fill yes)
		(layer "In2.Cu")
		(net "M_C_CPU0_SB_DQS_DN<9>")
	)
	(gr_poly
		(pts
			(xy 330.51115 -270.237966) (xy 330.411074 -270.13789) (xy 330.310998 -270.237966) (xy 330.310998 -270.282416)
			(xy 330.51115 -270.282416)
		)
		(stroke
			(width 0)
			(type solid)
		)
		(fill yes)
		(layer "In2.Cu")
		(net "M_C_CPU0_SB_CB<5>")
	)
	(gr_poly
		(pts
			(xy 330.51115 -269.834106) (xy 330.51115 -269.789656) (xy 330.310998 -269.789656) (xy 330.310998 -269.834106)
			(xy 330.411074 -269.934182)
		)
		(stroke
			(width 0)
			(type solid)
		)
		(fill yes)
		(layer "In2.Cu")
		(net "M_C_CPU0_SB_CB<6>")
	)
	(gr_poly
		(pts
			(xy 330.51115 -266.991592) (xy 330.411074 -266.891516) (xy 330.310998 -266.991592) (xy 330.310998 -267.036042)
			(xy 330.51115 -267.036042)
		)
		(stroke
			(width 0)
			(type solid)
		)
		(fill yes)
		(layer "In2.Cu")
		(net "M_C_CPU0_SA_RSP<0>")
	)
	(gr_poly
		(pts
			(xy 330.51115 -266.594082) (xy 330.51115 -266.549632) (xy 330.310998 -266.549632) (xy 330.310998 -266.594082)
			(xy 330.411074 -266.694158)
		)
		(stroke
			(width 0)
			(type solid)
		)
		(fill yes)
		(layer "In2.Cu")
		(net "M_C_CPU0_SB_CS_N<1>")
	)
	(gr_poly
		(pts
			(xy 330.51115 -264.97407) (xy 330.51115 -264.92962) (xy 330.310998 -264.92962) (xy 330.310998 -264.97407)
			(xy 330.411074 -265.074146)
		)
		(stroke
			(width 0)
			(type solid)
		)
		(fill yes)
		(layer "In2.Cu")
		(net "M_C_CPU0_SB_PAR")
	)
	(gr_poly
		(pts
			(xy 330.51115 -263.757918) (xy 330.411074 -263.657842) (xy 330.310998 -263.757918) (xy 330.310998 -263.802368)
			(xy 330.51115 -263.802368)
		)
		(stroke
			(width 0)
			(type solid)
		)
		(fill yes)
		(layer "In2.Cu")
		(net "M_C_CPU0_SB_CA<4>")
	)
	(gr_poly
		(pts
			(xy 330.51115 -263.354058) (xy 330.51115 -263.309608) (xy 330.310998 -263.309608) (xy 330.310998 -263.354058)
			(xy 330.411074 -263.454134)
		)
		(stroke
			(width 0)
			(type solid)
		)
		(fill yes)
		(layer "In2.Cu")
		(net "M_C_CPU0_SB_CA<3>")
	)
	(gr_poly
		(pts
			(xy 330.51115 -262.137906) (xy 330.411074 -262.03783) (xy 330.310998 -262.137906) (xy 330.310998 -262.182356)
			(xy 330.51115 -262.182356)
		)
		(stroke
			(width 0)
			(type solid)
		)
		(fill yes)
		(layer "In2.Cu")
		(net "M_C_CPU0_SB_CA<0>")
	)
	(gr_poly
		(pts
			(xy 330.600304 -224.58299) (xy 330.500228 -224.409762) (xy 330.461874 -224.432114) (xy 330.425298 -224.568766)
			(xy 330.561696 -224.605342)
		)
		(stroke
			(width 0)
			(type solid)
		)
		(fill yes)
		(layer "In2.Cu")
		(net "M_C_CPU0_SA_DQ<3>")
	)
	(gr_poly
		(pts
			(xy 330.600304 -222.962978) (xy 330.500228 -222.78975) (xy 330.461874 -222.812102) (xy 330.425298 -222.948754)
			(xy 330.561696 -222.98533)
		)
		(stroke
			(width 0)
			(type solid)
		)
		(fill yes)
		(layer "In2.Cu")
		(net "M_C_CPU0_SA_DQ<2>")
	)
	(gr_poly
		(pts
			(xy 330.603098 -227.822252) (xy 330.503276 -227.649024) (xy 330.461874 -227.6729) (xy 330.425298 -227.809298)
			(xy 330.56195 -227.846128)
		)
		(stroke
			(width 0)
			(type solid)
		)
		(fill yes)
		(layer "In2.Cu")
		(net "M_C_CPU0_SA_DQS_DP<5>")
	)
	(gr_poly
		(pts
			(xy 330.603098 -226.20224) (xy 330.503276 -226.029012) (xy 330.461874 -226.052888) (xy 330.425298 -226.189286)
			(xy 330.56195 -226.226116)
		)
		(stroke
			(width 0)
			(type solid)
		)
		(fill yes)
		(layer "In2.Cu")
		(net "M_C_CPU0_SA_DQS_DN<0>")
	)
	(gr_poly
		(pts
			(xy 330.680822 -246.712232) (xy 330.680822 -246.664734) (xy 330.480924 -246.664734) (xy 330.480924 -246.712232)
			(xy 330.580746 -246.812308)
		)
		(stroke
			(width 0)
			(type solid)
		)
		(fill yes)
		(layer "In2.Cu")
		(net "M_C_CPU0_SA_DQS_DN<4>")
	)
	(gr_poly
		(pts
			(xy 330.681076 -256.432558) (xy 330.681076 -256.384806) (xy 330.480924 -256.384806) (xy 330.480924 -256.432558)
			(xy 330.581 -256.53238)
		)
		(stroke
			(width 0)
			(type solid)
		)
		(fill yes)
		(layer "In2.Cu")
		(net "M_C_CPU0_CLK_DN<0>")
	)
	(gr_poly
		(pts
			(xy 330.681076 -255.216152) (xy 330.581 -255.116076) (xy 330.480924 -255.216152) (xy 330.480924 -255.260602)
			(xy 330.681076 -255.260602)
		)
		(stroke
			(width 0)
			(type solid)
		)
		(fill yes)
		(layer "In2.Cu")
		(net "M_C_CPU0_SA_CA<6>")
	)
	(gr_poly
		(pts
			(xy 330.681076 -254.812292) (xy 330.681076 -254.767842) (xy 330.480924 -254.767842) (xy 330.480924 -254.812292)
			(xy 330.581 -254.912368)
		)
		(stroke
			(width 0)
			(type solid)
		)
		(fill yes)
		(layer "In2.Cu")
		(net "M_C_CPU0_SA_CA<5>")
	)
	(gr_poly
		(pts
			(xy 330.681076 -253.59614) (xy 330.581 -253.496064) (xy 330.480924 -253.59614) (xy 330.480924 -253.64059)
			(xy 330.681076 -253.64059)
		)
		(stroke
			(width 0)
			(type solid)
		)
		(fill yes)
		(layer "In2.Cu")
		(net "M_C_CPU0_SA_CA<2>")
	)
	(gr_poly
		(pts
			(xy 330.681076 -253.19228) (xy 330.681076 -253.14783) (xy 330.480924 -253.14783) (xy 330.480924 -253.19228)
			(xy 330.581 -253.292356)
		)
		(stroke
			(width 0)
			(type solid)
		)
		(fill yes)
		(layer "In2.Cu")
		(net "M_C_CPU0_SA_CA<1>")
	)
	(gr_poly
		(pts
			(xy 330.681076 -251.572268) (xy 330.681076 -251.527818) (xy 330.480924 -251.527818) (xy 330.480924 -251.572268)
			(xy 330.581 -251.672344)
		)
		(stroke
			(width 0)
			(type solid)
		)
		(fill yes)
		(layer "In2.Cu")
		(net "M_C_CPU0_SA_CS_N<0>")
	)
	(gr_poly
		(pts
			(xy 330.681076 -250.356116) (xy 330.581 -250.25604) (xy 330.480924 -250.356116) (xy 330.480924 -250.400566)
			(xy 330.681076 -250.400566)
		)
		(stroke
			(width 0)
			(type solid)
		)
		(fill yes)
		(layer "In2.Cu")
		(net "M_C_CPU0_ALERT_R_N")
	)
	(gr_poly
		(pts
			(xy 330.681076 -248.736104) (xy 330.581 -248.636028) (xy 330.480924 -248.736104) (xy 330.480924 -248.780554)
			(xy 330.681076 -248.780554)
		)
		(stroke
			(width 0)
			(type solid)
		)
		(fill yes)
		(layer "In2.Cu")
		(net "M_C_CPU0_SA_CB<5>")
	)
	(gr_poly
		(pts
			(xy 330.681076 -248.332244) (xy 330.681076 -248.287794) (xy 330.480924 -248.287794) (xy 330.480924 -248.332244)
			(xy 330.581 -248.43232)
		)
		(stroke
			(width 0)
			(type solid)
		)
		(fill yes)
		(layer "In2.Cu")
		(net "M_C_CPU0_SA_CB<6>")
	)
	(gr_poly
		(pts
			(xy 330.681076 -247.115838) (xy 330.581 -247.016016) (xy 330.480924 -247.115838) (xy 330.480924 -247.16359)
			(xy 330.681076 -247.16359)
		)
		(stroke
			(width 0)
			(type solid)
		)
		(fill yes)
		(layer "In2.Cu")
		(net "M_C_CPU0_SA_DQS_DN<9>")
	)
	(gr_poly
		(pts
			(xy 330.681076 -245.49608) (xy 330.581 -245.396004) (xy 330.480924 -245.49608) (xy 330.480924 -245.54053)
			(xy 330.681076 -245.54053)
		)
		(stroke
			(width 0)
			(type solid)
		)
		(fill yes)
		(layer "In2.Cu")
		(net "M_C_CPU0_SA_CB<1>")
	)
	(gr_poly
		(pts
			(xy 330.681076 -245.09222) (xy 330.681076 -245.04777) (xy 330.480924 -245.04777) (xy 330.480924 -245.09222)
			(xy 330.581 -245.192296)
		)
		(stroke
			(width 0)
			(type solid)
		)
		(fill yes)
		(layer "In2.Cu")
		(net "M_C_CPU0_SA_CB<2>")
	)
	(gr_poly
		(pts
			(xy 330.681076 -243.876068) (xy 330.581 -243.775992) (xy 330.480924 -243.876068) (xy 330.480924 -243.920518)
			(xy 330.681076 -243.920518)
		)
		(stroke
			(width 0)
			(type solid)
		)
		(fill yes)
		(layer "In2.Cu")
		(net "M_C_CPU0_SA_DQ<29>")
	)
	(gr_poly
		(pts
			(xy 330.681076 -243.472208) (xy 330.681076 -243.427758) (xy 330.480924 -243.427758) (xy 330.480924 -243.472208)
			(xy 330.581 -243.572284)
		)
		(stroke
			(width 0)
			(type solid)
		)
		(fill yes)
		(layer "In2.Cu")
		(net "M_C_CPU0_SA_DQ<30>")
	)
	(gr_poly
		(pts
			(xy 330.681076 -242.255802) (xy 330.581 -242.15598) (xy 330.480924 -242.255802) (xy 330.480924 -242.303554)
			(xy 330.681076 -242.303554)
		)
		(stroke
			(width 0)
			(type solid)
		)
		(fill yes)
		(layer "In2.Cu")
		(net "M_C_CPU0_SA_DQS_DN<8>")
	)
	(gr_poly
		(pts
			(xy 330.681076 -241.85245) (xy 330.681076 -241.804698) (xy 330.480924 -241.804698) (xy 330.480924 -241.85245)
			(xy 330.581 -241.952272)
		)
		(stroke
			(width 0)
			(type solid)
		)
		(fill yes)
		(layer "In2.Cu")
		(net "M_C_CPU0_SA_DQS_DN<3>")
	)
	(gr_poly
		(pts
			(xy 330.681076 -240.636044) (xy 330.581 -240.535968) (xy 330.480924 -240.636044) (xy 330.480924 -240.680494)
			(xy 330.681076 -240.680494)
		)
		(stroke
			(width 0)
			(type solid)
		)
		(fill yes)
		(layer "In2.Cu")
		(net "M_C_CPU0_SA_DQ<25>")
	)
	(gr_poly
		(pts
			(xy 330.681076 -240.232184) (xy 330.681076 -240.187734) (xy 330.480924 -240.187734) (xy 330.480924 -240.232184)
			(xy 330.581 -240.33226)
		)
		(stroke
			(width 0)
			(type solid)
		)
		(fill yes)
		(layer "In2.Cu")
		(net "M_C_CPU0_SA_DQ<26>")
	)
	(gr_poly
		(pts
			(xy 330.681076 -239.016032) (xy 330.581 -238.915956) (xy 330.480924 -239.016032) (xy 330.480924 -239.060482)
			(xy 330.681076 -239.060482)
		)
		(stroke
			(width 0)
			(type solid)
		)
		(fill yes)
		(layer "In2.Cu")
		(net "M_C_CPU0_SA_DQ<21>")
	)
	(gr_poly
		(pts
			(xy 330.681076 -238.612172) (xy 330.681076 -238.567722) (xy 330.480924 -238.567722) (xy 330.480924 -238.612172)
			(xy 330.581 -238.712248)
		)
		(stroke
			(width 0)
			(type solid)
		)
		(fill yes)
		(layer "In2.Cu")
		(net "M_C_CPU0_SA_DQ<22>")
	)
	(gr_poly
		(pts
			(xy 330.681076 -237.395766) (xy 330.581 -237.295944) (xy 330.480924 -237.395766) (xy 330.480924 -237.443518)
			(xy 330.681076 -237.443518)
		)
		(stroke
			(width 0)
			(type solid)
		)
		(fill yes)
		(layer "In2.Cu")
		(net "M_C_CPU0_SA_DQS_DN<7>")
	)
	(gr_poly
		(pts
			(xy 330.681076 -236.992414) (xy 330.681076 -236.944662) (xy 330.480924 -236.944662) (xy 330.480924 -236.992414)
			(xy 330.581 -237.092236)
		)
		(stroke
			(width 0)
			(type solid)
		)
		(fill yes)
		(layer "In2.Cu")
		(net "M_C_CPU0_SA_DQS_DN<2>")
	)
	(gr_poly
		(pts
			(xy 330.681076 -235.776008) (xy 330.581 -235.675932) (xy 330.480924 -235.776008) (xy 330.480924 -235.820458)
			(xy 330.681076 -235.820458)
		)
		(stroke
			(width 0)
			(type solid)
		)
		(fill yes)
		(layer "In2.Cu")
		(net "M_C_CPU0_SA_DQ<17>")
	)
	(gr_poly
		(pts
			(xy 330.681076 -235.372148) (xy 330.681076 -235.327698) (xy 330.480924 -235.327698) (xy 330.480924 -235.372148)
			(xy 330.581 -235.472224)
		)
		(stroke
			(width 0)
			(type solid)
		)
		(fill yes)
		(layer "In2.Cu")
		(net "M_C_CPU0_SA_DQ<18>")
	)
	(gr_poly
		(pts
			(xy 330.681076 -234.155996) (xy 330.581 -234.05592) (xy 330.480924 -234.155996) (xy 330.480924 -234.200446)
			(xy 330.681076 -234.200446)
		)
		(stroke
			(width 0)
			(type solid)
		)
		(fill yes)
		(layer "In2.Cu")
		(net "M_C_CPU0_SA_DQ<13>")
	)
	(gr_poly
		(pts
			(xy 330.681076 -233.752136) (xy 330.681076 -233.707686) (xy 330.480924 -233.707686) (xy 330.480924 -233.752136)
			(xy 330.581 -233.852212)
		)
		(stroke
			(width 0)
			(type solid)
		)
		(fill yes)
		(layer "In2.Cu")
		(net "M_C_CPU0_SA_DQ<14>")
	)
	(gr_poly
		(pts
			(xy 330.681076 -232.53573) (xy 330.581 -232.435908) (xy 330.480924 -232.53573) (xy 330.480924 -232.583482)
			(xy 330.681076 -232.583482)
		)
		(stroke
			(width 0)
			(type solid)
		)
		(fill yes)
		(layer "In2.Cu")
		(net "M_C_CPU0_SA_DQS_DN<6>")
	)
	(gr_poly
		(pts
			(xy 330.681076 -232.132378) (xy 330.681076 -232.084626) (xy 330.480924 -232.084626) (xy 330.480924 -232.132378)
			(xy 330.581 -232.2322)
		)
		(stroke
			(width 0)
			(type solid)
		)
		(fill yes)
		(layer "In2.Cu")
		(net "M_C_CPU0_SA_DQS_DN<1>")
	)
	(gr_poly
		(pts
			(xy 330.681076 -230.915972) (xy 330.581 -230.815896) (xy 330.480924 -230.915972) (xy 330.480924 -230.960422)
			(xy 330.681076 -230.960422)
		)
		(stroke
			(width 0)
			(type solid)
		)
		(fill yes)
		(layer "In2.Cu")
		(net "M_C_CPU0_SA_DQ<9>")
	)
	(gr_poly
		(pts
			(xy 330.681076 -230.512366) (xy 330.681076 -230.467916) (xy 330.480924 -230.467916) (xy 330.480924 -230.512366)
			(xy 330.581 -230.612188)
		)
		(stroke
			(width 0)
			(type solid)
		)
		(fill yes)
		(layer "In2.Cu")
		(net "M_C_CPU0_SA_DQ<10>")
	)
	(gr_poly
		(pts
			(xy 330.681076 -229.29596) (xy 330.581 -229.195884) (xy 330.480924 -229.29596) (xy 330.480924 -229.34041)
			(xy 330.681076 -229.34041)
		)
		(stroke
			(width 0)
			(type solid)
		)
		(fill yes)
		(layer "In2.Cu")
		(net "M_C_CPU0_SA_DQ<5>")
	)
	(gr_poly
		(pts
			(xy 330.681076 -228.892354) (xy 330.681076 -228.847904) (xy 330.480924 -228.847904) (xy 330.480924 -228.892354)
			(xy 330.581 -228.99243)
		)
		(stroke
			(width 0)
			(type solid)
		)
		(fill yes)
		(layer "In2.Cu")
		(net "M_C_CPU0_SA_DQ<6>")
	)
	(gr_poly
		(pts
			(xy 330.70038 -227.275644) (xy 330.736956 -227.139246) (xy 330.600304 -227.10267) (xy 330.559156 -227.126292)
			(xy 330.658978 -227.29952)
		)
		(stroke
			(width 0)
			(type solid)
		)
		(fill yes)
		(layer "In2.Cu")
		(net "M_C_CPU0_SA_DQS_DN<5>")
	)
	(gr_poly
		(pts
			(xy 330.70038 -225.655632) (xy 330.736956 -225.519234) (xy 330.600304 -225.482404) (xy 330.559156 -225.50628)
			(xy 330.658978 -225.679508)
		)
		(stroke
			(width 0)
			(type solid)
		)
		(fill yes)
		(layer "In2.Cu")
		(net "M_C_CPU0_SA_DQS_DP<0>")
	)
	(gr_poly
		(pts
			(xy 330.70038 -224.036382) (xy 330.73721 -223.89973) (xy 330.600558 -223.863154) (xy 330.56195 -223.885506)
			(xy 330.662026 -224.058734)
		)
		(stroke
			(width 0)
			(type solid)
		)
		(fill yes)
		(layer "In2.Cu")
		(net "M_C_CPU0_SA_DQ<1>")
	)
	(gr_poly
		(pts
			(xy 330.98105 -293.324026) (xy 330.98105 -293.279576) (xy 330.780898 -293.279576) (xy 330.780898 -293.324026)
			(xy 330.880974 -293.424102)
		)
		(stroke
			(width 0)
			(type solid)
		)
		(fill yes)
		(layer "In2.Cu")
		(net "M_C_CPU0_SB_DQ<31>")
	)
	(gr_poly
		(pts
			(xy 330.98105 -292.107874) (xy 330.880974 -292.007798) (xy 330.780898 -292.107874) (xy 330.780898 -292.152324)
			(xy 330.98105 -292.152324)
		)
		(stroke
			(width 0)
			(type solid)
		)
		(fill yes)
		(layer "In2.Cu")
		(net "M_C_CPU0_SB_DQ<28>")
	)
	(gr_poly
		(pts
			(xy 330.98105 -291.704268) (xy 330.98105 -291.656516) (xy 330.780898 -291.656516) (xy 330.780898 -291.704268)
			(xy 330.880974 -291.80409)
		)
		(stroke
			(width 0)
			(type solid)
		)
		(fill yes)
		(layer "In2.Cu")
		(net "M_C_CPU0_SB_DQS_DP<8>")
	)
	(gr_poly
		(pts
			(xy 330.98105 -290.487608) (xy 330.880974 -290.387786) (xy 330.780898 -290.487608) (xy 330.780898 -290.53536)
			(xy 330.98105 -290.53536)
		)
		(stroke
			(width 0)
			(type solid)
		)
		(fill yes)
		(layer "In2.Cu")
		(net "M_C_CPU0_SB_DQS_DP<3>")
	)
	(gr_poly
		(pts
			(xy 330.98105 -290.084002) (xy 330.98105 -290.039552) (xy 330.780898 -290.039552) (xy 330.780898 -290.084002)
			(xy 330.880974 -290.184078)
		)
		(stroke
			(width 0)
			(type solid)
		)
		(fill yes)
		(layer "In2.Cu")
		(net "M_C_CPU0_SB_DQ<27>")
	)
	(gr_poly
		(pts
			(xy 330.98105 -288.86785) (xy 330.880974 -288.767774) (xy 330.780898 -288.86785) (xy 330.780898 -288.9123)
			(xy 330.98105 -288.9123)
		)
		(stroke
			(width 0)
			(type solid)
		)
		(fill yes)
		(layer "In2.Cu")
		(net "M_C_CPU0_SB_DQ<24>")
	)
	(gr_poly
		(pts
			(xy 330.98105 -288.464244) (xy 330.98105 -288.419794) (xy 330.780898 -288.419794) (xy 330.780898 -288.464244)
			(xy 330.880974 -288.56432)
		)
		(stroke
			(width 0)
			(type solid)
		)
		(fill yes)
		(layer "In2.Cu")
		(net "M_C_CPU0_SB_DQ<23>")
	)
	(gr_poly
		(pts
			(xy 330.98105 -287.247838) (xy 330.880974 -287.148016) (xy 330.780898 -287.247838) (xy 330.780898 -287.292288)
			(xy 330.98105 -287.292288)
		)
		(stroke
			(width 0)
			(type solid)
		)
		(fill yes)
		(layer "In2.Cu")
		(net "M_C_CPU0_SB_DQ<20>")
	)
	(gr_poly
		(pts
			(xy 330.98105 -286.844232) (xy 330.98105 -286.79648) (xy 330.780898 -286.79648) (xy 330.780898 -286.844232)
			(xy 330.880974 -286.944308)
		)
		(stroke
			(width 0)
			(type solid)
		)
		(fill yes)
		(layer "In2.Cu")
		(net "M_C_CPU0_SB_DQS_DP<7>")
	)
	(gr_poly
		(pts
			(xy 330.98105 -285.627826) (xy 330.880974 -285.528004) (xy 330.780898 -285.627826) (xy 330.780898 -285.675578)
			(xy 330.98105 -285.675578)
		)
		(stroke
			(width 0)
			(type solid)
		)
		(fill yes)
		(layer "In2.Cu")
		(net "M_C_CPU0_SB_DQS_DP<2>")
	)
	(gr_poly
		(pts
			(xy 330.98105 -285.22422) (xy 330.98105 -285.17977) (xy 330.780898 -285.17977) (xy 330.780898 -285.22422)
			(xy 330.880974 -285.324296)
		)
		(stroke
			(width 0)
			(type solid)
		)
		(fill yes)
		(layer "In2.Cu")
		(net "M_C_CPU0_SB_DQ<19>")
	)
	(gr_poly
		(pts
			(xy 330.98105 -284.008068) (xy 330.880974 -283.907992) (xy 330.780898 -284.008068) (xy 330.780898 -284.052518)
			(xy 330.98105 -284.052518)
		)
		(stroke
			(width 0)
			(type solid)
		)
		(fill yes)
		(layer "In2.Cu")
		(net "M_C_CPU0_SB_DQ<16>")
	)
	(gr_poly
		(pts
			(xy 330.98105 -283.604208) (xy 330.98105 -283.559758) (xy 330.780898 -283.559758) (xy 330.780898 -283.604208)
			(xy 330.880974 -283.704284)
		)
		(stroke
			(width 0)
			(type solid)
		)
		(fill yes)
		(layer "In2.Cu")
		(net "M_C_CPU0_SB_DQ<15>")
	)
	(gr_poly
		(pts
			(xy 330.98105 -282.388056) (xy 330.880974 -282.28798) (xy 330.780898 -282.388056) (xy 330.780898 -282.432506)
			(xy 330.98105 -282.432506)
		)
		(stroke
			(width 0)
			(type solid)
		)
		(fill yes)
		(layer "In2.Cu")
		(net "M_C_CPU0_SB_DQ<12>")
	)
	(gr_poly
		(pts
			(xy 330.98105 -281.98445) (xy 330.98105 -281.936698) (xy 330.780898 -281.936698) (xy 330.780898 -281.98445)
			(xy 330.880974 -282.084272)
		)
		(stroke
			(width 0)
			(type solid)
		)
		(fill yes)
		(layer "In2.Cu")
		(net "M_C_CPU0_SB_DQS_DP<6>")
	)
	(gr_poly
		(pts
			(xy 330.98105 -280.76779) (xy 330.880974 -280.667968) (xy 330.780898 -280.76779) (xy 330.780898 -280.815542)
			(xy 330.98105 -280.815542)
		)
		(stroke
			(width 0)
			(type solid)
		)
		(fill yes)
		(layer "In2.Cu")
		(net "M_C_CPU0_SB_DQS_DP<1>")
	)
	(gr_poly
		(pts
			(xy 330.98105 -280.364184) (xy 330.98105 -280.319734) (xy 330.780898 -280.319734) (xy 330.780898 -280.364184)
			(xy 330.880974 -280.46426)
		)
		(stroke
			(width 0)
			(type solid)
		)
		(fill yes)
		(layer "In2.Cu")
		(net "M_C_CPU0_SB_DQ<11>")
	)
	(gr_poly
		(pts
			(xy 330.98105 -279.148032) (xy 330.880974 -279.047956) (xy 330.780898 -279.148032) (xy 330.780898 -279.192482)
			(xy 330.98105 -279.192482)
		)
		(stroke
			(width 0)
			(type solid)
		)
		(fill yes)
		(layer "In2.Cu")
		(net "M_C_CPU0_SB_DQ<8>")
	)
	(gr_poly
		(pts
			(xy 330.98105 -278.744172) (xy 330.98105 -278.699722) (xy 330.780898 -278.699722) (xy 330.780898 -278.744172)
			(xy 330.880974 -278.844248)
		)
		(stroke
			(width 0)
			(type solid)
		)
		(fill yes)
		(layer "In2.Cu")
		(net "M_C_CPU0_SB_DQ<7>")
	)
	(gr_poly
		(pts
			(xy 330.98105 -277.52802) (xy 330.880974 -277.427944) (xy 330.780898 -277.52802) (xy 330.780898 -277.57247)
			(xy 330.98105 -277.57247)
		)
		(stroke
			(width 0)
			(type solid)
		)
		(fill yes)
		(layer "In2.Cu")
		(net "M_C_CPU0_SB_DQ<4>")
	)
	(gr_poly
		(pts
			(xy 330.98105 -277.124414) (xy 330.98105 -277.076662) (xy 330.780898 -277.076662) (xy 330.780898 -277.124414)
			(xy 330.880974 -277.224236)
		)
		(stroke
			(width 0)
			(type solid)
		)
		(fill yes)
		(layer "In2.Cu")
		(net "M_C_CPU0_SB_DQS_DP<5>")
	)
	(gr_poly
		(pts
			(xy 330.98105 -275.907754) (xy 330.880974 -275.807932) (xy 330.780898 -275.907754) (xy 330.780898 -275.955506)
			(xy 330.98105 -275.955506)
		)
		(stroke
			(width 0)
			(type solid)
		)
		(fill yes)
		(layer "In2.Cu")
		(net "M_C_CPU0_SB_DQS_DP<0>")
	)
	(gr_poly
		(pts
			(xy 330.98105 -275.504148) (xy 330.98105 -275.459698) (xy 330.780898 -275.459698) (xy 330.780898 -275.504148)
			(xy 330.880974 -275.604224)
		)
		(stroke
			(width 0)
			(type solid)
		)
		(fill yes)
		(layer "In2.Cu")
		(net "M_C_CPU0_SB_DQ<3>")
	)
	(gr_poly
		(pts
			(xy 330.98105 -274.287996) (xy 330.880974 -274.18792) (xy 330.780898 -274.287996) (xy 330.780898 -274.332446)
			(xy 330.98105 -274.332446)
		)
		(stroke
			(width 0)
			(type solid)
		)
		(fill yes)
		(layer "In2.Cu")
		(net "M_C_CPU0_SB_DQ<0>")
	)
	(gr_poly
		(pts
			(xy 330.98105 -273.884136) (xy 330.98105 -273.839686) (xy 330.780898 -273.839686) (xy 330.780898 -273.884136)
			(xy 330.880974 -273.984212)
		)
		(stroke
			(width 0)
			(type solid)
		)
		(fill yes)
		(layer "In2.Cu")
		(net "M_C_CPU0_SB_CB<3>")
	)
	(gr_poly
		(pts
			(xy 330.98105 -272.667984) (xy 330.880974 -272.567908) (xy 330.780898 -272.667984) (xy 330.780898 -272.712434)
			(xy 330.98105 -272.712434)
		)
		(stroke
			(width 0)
			(type solid)
		)
		(fill yes)
		(layer "In2.Cu")
		(net "M_C_CPU0_SB_CB<0>")
	)
	(gr_poly
		(pts
			(xy 330.98105 -272.264378) (xy 330.98105 -272.216626) (xy 330.780898 -272.216626) (xy 330.780898 -272.264378)
			(xy 330.880974 -272.3642)
		)
		(stroke
			(width 0)
			(type solid)
		)
		(fill yes)
		(layer "In2.Cu")
		(net "M_C_CPU0_SB_DQS_DP<4>")
	)
	(gr_poly
		(pts
			(xy 330.98105 -271.047718) (xy 330.880974 -270.947896) (xy 330.780898 -271.047718) (xy 330.780898 -271.09547)
			(xy 330.98105 -271.09547)
		)
		(stroke
			(width 0)
			(type solid)
		)
		(fill yes)
		(layer "In2.Cu")
		(net "M_C_CPU0_SB_DQS_DP<9>")
	)
	(gr_poly
		(pts
			(xy 330.98105 -270.644112) (xy 330.98105 -270.599662) (xy 330.780898 -270.599662) (xy 330.780898 -270.644112)
			(xy 330.880974 -270.744188)
		)
		(stroke
			(width 0)
			(type solid)
		)
		(fill yes)
		(layer "In2.Cu")
		(net "M_C_CPU0_SB_CB<7>")
	)
	(gr_poly
		(pts
			(xy 330.98105 -269.42796) (xy 330.880974 -269.327884) (xy 330.780898 -269.42796) (xy 330.780898 -269.47241)
			(xy 330.98105 -269.47241)
		)
		(stroke
			(width 0)
			(type solid)
		)
		(fill yes)
		(layer "In2.Cu")
		(net "M_C_CPU0_SB_CB<4>")
	)
	(gr_poly
		(pts
			(xy 330.98105 -264.164064) (xy 330.98105 -264.119614) (xy 330.780898 -264.119614) (xy 330.780898 -264.164064)
			(xy 330.880974 -264.26414)
		)
		(stroke
			(width 0)
			(type solid)
		)
		(fill yes)
		(layer "In2.Cu")
		(net "M_C_CPU0_SB_CA<5>")
	)
	(gr_poly
		(pts
			(xy 330.98105 -262.947912) (xy 330.880974 -262.847836) (xy 330.780898 -262.947912) (xy 330.780898 -262.992362)
			(xy 330.98105 -262.992362)
		)
		(stroke
			(width 0)
			(type solid)
		)
		(fill yes)
		(layer "In2.Cu")
		(net "M_C_CPU0_SB_CA<2>")
	)
	(gr_poly
		(pts
			(xy 330.98105 -262.544052) (xy 330.98105 -262.499602) (xy 330.780898 -262.499602) (xy 330.780898 -262.544052)
			(xy 330.880974 -262.644128)
		)
		(stroke
			(width 0)
			(type solid)
		)
		(fill yes)
		(layer "In2.Cu")
		(net "M_C_CPU0_SB_CA<1>")
	)
	(gr_poly
		(pts
			(xy 330.981304 -265.784076) (xy 330.981304 -265.739626) (xy 330.781152 -265.739626) (xy 330.781152 -265.784076)
			(xy 330.881228 -265.884152)
		)
		(stroke
			(width 0)
			(type solid)
		)
		(fill yes)
		(layer "In2.Cu")
		(net "M_C_CPU0_SB_CS_N<0>")
	)
	(gr_poly
		(pts
			(xy 330.981304 -264.567924) (xy 330.881228 -264.467848) (xy 330.781152 -264.567924) (xy 330.781152 -264.612374)
			(xy 330.981304 -264.612374)
		)
		(stroke
			(width 0)
			(type solid)
		)
		(fill yes)
		(layer "In2.Cu")
		(net "M_C_CPU0_SB_CA<6>")
	)
	(gr_poly
		(pts
			(xy 330.987146 -267.801598) (xy 330.887324 -267.701522) (xy 330.787248 -267.801598) (xy 330.787248 -267.846048)
			(xy 330.987146 -267.846048)
		)
		(stroke
			(width 0)
			(type solid)
		)
		(fill yes)
		(layer "In2.Cu")
		(net "M_C_CPU0_SB_RSP<0>")
	)
	(gr_poly
		(pts
			(xy 331.070204 -225.392996) (xy 330.970128 -225.219768) (xy 330.931774 -225.24212) (xy 330.895198 -225.378772)
			(xy 331.031596 -225.415348)
		)
		(stroke
			(width 0)
			(type solid)
		)
		(fill yes)
		(layer "In2.Cu")
		(net "M_C_CPU0_SA_DQ<3>")
	)
	(gr_poly
		(pts
			(xy 331.070204 -223.772984) (xy 330.970128 -223.599756) (xy 330.931774 -223.622108) (xy 330.895198 -223.75876)
			(xy 331.031596 -223.795336)
		)
		(stroke
			(width 0)
			(type solid)
		)
		(fill yes)
		(layer "In2.Cu")
		(net "M_C_CPU0_SA_DQ<2>")
	)
	(gr_poly
		(pts
			(xy 331.072998 -227.012246) (xy 330.973176 -226.839018) (xy 330.931774 -226.862894) (xy 330.895198 -226.999292)
			(xy 331.03185 -227.035868)
		)
		(stroke
			(width 0)
			(type solid)
		)
		(fill yes)
		(layer "In2.Cu")
		(net "M_C_CPU0_SA_DQS_DN<0>")
	)
	(gr_poly
		(pts
			(xy 331.15123 -256.025904) (xy 331.051154 -255.926082) (xy 330.951078 -256.025904) (xy 330.951078 -256.073656)
			(xy 331.15123 -256.073656)
		)
		(stroke
			(width 0)
			(type solid)
		)
		(fill yes)
		(layer "In2.Cu")
		(net "M_C_CPU0_CLK_DP<0>")
	)
	(gr_poly
		(pts
			(xy 331.15123 -255.622298) (xy 331.15123 -255.577848) (xy 330.951078 -255.577848) (xy 330.951078 -255.622298)
			(xy 331.051154 -255.722374)
		)
		(stroke
			(width 0)
			(type solid)
		)
		(fill yes)
		(layer "In2.Cu")
		(net "M_C_CPU0_SA_PAR")
	)
	(gr_poly
		(pts
			(xy 331.15123 -254.406146) (xy 331.051154 -254.30607) (xy 330.951078 -254.406146) (xy 330.951078 -254.450596)
			(xy 331.15123 -254.450596)
		)
		(stroke
			(width 0)
			(type solid)
		)
		(fill yes)
		(layer "In2.Cu")
		(net "M_C_CPU0_SA_CA<4>")
	)
	(gr_poly
		(pts
			(xy 331.15123 -254.002286) (xy 331.15123 -253.957836) (xy 330.951078 -253.957836) (xy 330.951078 -254.002286)
			(xy 331.051154 -254.102362)
		)
		(stroke
			(width 0)
			(type solid)
		)
		(fill yes)
		(layer "In2.Cu")
		(net "M_C_CPU0_SA_CA<3>")
	)
	(gr_poly
		(pts
			(xy 331.15123 -252.786134) (xy 331.051154 -252.686058) (xy 330.951078 -252.786134) (xy 330.951078 -252.830584)
			(xy 331.15123 -252.830584)
		)
		(stroke
			(width 0)
			(type solid)
		)
		(fill yes)
		(layer "In2.Cu")
		(net "M_C_CPU0_SA_CA<0>")
	)
	(gr_poly
		(pts
			(xy 331.15123 -252.382274) (xy 331.15123 -252.337824) (xy 330.951078 -252.337824) (xy 330.951078 -252.382274)
			(xy 331.051154 -252.48235)
		)
		(stroke
			(width 0)
			(type solid)
		)
		(fill yes)
		(layer "In2.Cu")
		(net "M_C_CPU0_SA_CS_N<1>")
	)
	(gr_poly
		(pts
			(xy 331.15123 -250.762262) (xy 331.15123 -250.717812) (xy 330.951078 -250.717812) (xy 330.951078 -250.762262)
			(xy 331.051154 -250.862338)
		)
		(stroke
			(width 0)
			(type solid)
		)
		(fill yes)
		(layer "In2.Cu")
		(net "M_C_CPU0_RESET_N")
	)
	(gr_poly
		(pts
			(xy 331.15123 -249.14225) (xy 331.15123 -249.0978) (xy 330.951078 -249.0978) (xy 330.951078 -249.14225)
			(xy 331.051154 -249.242326)
		)
		(stroke
			(width 0)
			(type solid)
		)
		(fill yes)
		(layer "In2.Cu")
		(net "M_C_CPU0_SA_CB<7>")
	)
	(gr_poly
		(pts
			(xy 331.15123 -247.926098) (xy 331.051154 -247.826022) (xy 330.951078 -247.926098) (xy 330.951078 -247.970548)
			(xy 331.15123 -247.970548)
		)
		(stroke
			(width 0)
			(type solid)
		)
		(fill yes)
		(layer "In2.Cu")
		(net "M_C_CPU0_SA_CB<4>")
	)
	(gr_poly
		(pts
			(xy 331.15123 -247.522492) (xy 331.15123 -247.47474) (xy 330.951078 -247.47474) (xy 330.951078 -247.522492)
			(xy 331.051154 -247.622314)
		)
		(stroke
			(width 0)
			(type solid)
		)
		(fill yes)
		(layer "In2.Cu")
		(net "M_C_CPU0_SA_DQS_DP<9>")
	)
	(gr_poly
		(pts
			(xy 331.15123 -246.305832) (xy 331.051154 -246.20601) (xy 330.951078 -246.305832) (xy 330.951078 -246.353584)
			(xy 331.15123 -246.353584)
		)
		(stroke
			(width 0)
			(type solid)
		)
		(fill yes)
		(layer "In2.Cu")
		(net "M_C_CPU0_SA_DQS_DP<4>")
	)
	(gr_poly
		(pts
			(xy 331.15123 -245.902226) (xy 331.15123 -245.857776) (xy 330.951078 -245.857776) (xy 330.951078 -245.902226)
			(xy 331.051154 -246.002302)
		)
		(stroke
			(width 0)
			(type solid)
		)
		(fill yes)
		(layer "In2.Cu")
		(net "M_C_CPU0_SA_CB<3>")
	)
	(gr_poly
		(pts
			(xy 331.15123 -244.686074) (xy 331.051154 -244.585998) (xy 330.951078 -244.686074) (xy 330.951078 -244.730524)
			(xy 331.15123 -244.730524)
		)
		(stroke
			(width 0)
			(type solid)
		)
		(fill yes)
		(layer "In2.Cu")
		(net "M_C_CPU0_SA_CB<0>")
	)
	(gr_poly
		(pts
			(xy 331.15123 -244.282214) (xy 331.15123 -244.237764) (xy 330.951078 -244.237764) (xy 330.951078 -244.282214)
			(xy 331.051154 -244.38229)
		)
		(stroke
			(width 0)
			(type solid)
		)
		(fill yes)
		(layer "In2.Cu")
		(net "M_C_CPU0_SA_DQ<31>")
	)
	(gr_poly
		(pts
			(xy 331.15123 -243.066062) (xy 331.051154 -242.965986) (xy 330.951078 -243.066062) (xy 330.951078 -243.110512)
			(xy 331.15123 -243.110512)
		)
		(stroke
			(width 0)
			(type solid)
		)
		(fill yes)
		(layer "In2.Cu")
		(net "M_C_CPU0_SA_DQ<28>")
	)
	(gr_poly
		(pts
			(xy 331.15123 -242.662456) (xy 331.15123 -242.614704) (xy 330.951078 -242.614704) (xy 330.951078 -242.662456)
			(xy 331.051154 -242.762278)
		)
		(stroke
			(width 0)
			(type solid)
		)
		(fill yes)
		(layer "In2.Cu")
		(net "M_C_CPU0_SA_DQS_DP<8>")
	)
	(gr_poly
		(pts
			(xy 331.15123 -241.445796) (xy 331.051154 -241.345974) (xy 330.951078 -241.445796) (xy 330.951078 -241.493548)
			(xy 331.15123 -241.493548)
		)
		(stroke
			(width 0)
			(type solid)
		)
		(fill yes)
		(layer "In2.Cu")
		(net "M_C_CPU0_SA_DQS_DP<3>")
	)
	(gr_poly
		(pts
			(xy 331.15123 -241.04219) (xy 331.15123 -240.99774) (xy 330.951078 -240.99774) (xy 330.951078 -241.04219)
			(xy 331.051154 -241.142266)
		)
		(stroke
			(width 0)
			(type solid)
		)
		(fill yes)
		(layer "In2.Cu")
		(net "M_C_CPU0_SA_DQ<27>")
	)
	(gr_poly
		(pts
			(xy 331.15123 -239.826038) (xy 331.051154 -239.725962) (xy 330.951078 -239.826038) (xy 330.951078 -239.870488)
			(xy 331.15123 -239.870488)
		)
		(stroke
			(width 0)
			(type solid)
		)
		(fill yes)
		(layer "In2.Cu")
		(net "M_C_CPU0_SA_DQ<24>")
	)
	(gr_poly
		(pts
			(xy 331.15123 -239.422178) (xy 331.15123 -239.377728) (xy 330.951078 -239.377728) (xy 330.951078 -239.422178)
			(xy 331.051154 -239.522254)
		)
		(stroke
			(width 0)
			(type solid)
		)
		(fill yes)
		(layer "In2.Cu")
		(net "M_C_CPU0_SA_DQ<23>")
	)
	(gr_poly
		(pts
			(xy 331.15123 -238.206026) (xy 331.051154 -238.10595) (xy 330.951078 -238.206026) (xy 330.951078 -238.250476)
			(xy 331.15123 -238.250476)
		)
		(stroke
			(width 0)
			(type solid)
		)
		(fill yes)
		(layer "In2.Cu")
		(net "M_C_CPU0_SA_DQ<20>")
	)
	(gr_poly
		(pts
			(xy 331.15123 -237.80242) (xy 331.15123 -237.754668) (xy 330.951078 -237.754668) (xy 330.951078 -237.80242)
			(xy 331.051154 -237.902242)
		)
		(stroke
			(width 0)
			(type solid)
		)
		(fill yes)
		(layer "In2.Cu")
		(net "M_C_CPU0_SA_DQS_DP<7>")
	)
	(gr_poly
		(pts
			(xy 331.15123 -236.58576) (xy 331.051154 -236.485938) (xy 330.951078 -236.58576) (xy 330.951078 -236.633512)
			(xy 331.15123 -236.633512)
		)
		(stroke
			(width 0)
			(type solid)
		)
		(fill yes)
		(layer "In2.Cu")
		(net "M_C_CPU0_SA_DQS_DP<2>")
	)
	(gr_poly
		(pts
			(xy 331.15123 -236.182154) (xy 331.15123 -236.137704) (xy 330.951078 -236.137704) (xy 330.951078 -236.182154)
			(xy 331.051154 -236.28223)
		)
		(stroke
			(width 0)
			(type solid)
		)
		(fill yes)
		(layer "In2.Cu")
		(net "M_C_CPU0_SA_DQ<19>")
	)
	(gr_poly
		(pts
			(xy 331.15123 -234.966002) (xy 331.051154 -234.865926) (xy 330.951078 -234.966002) (xy 330.951078 -235.010452)
			(xy 331.15123 -235.010452)
		)
		(stroke
			(width 0)
			(type solid)
		)
		(fill yes)
		(layer "In2.Cu")
		(net "M_C_CPU0_SA_DQ<16>")
	)
	(gr_poly
		(pts
			(xy 331.15123 -234.562142) (xy 331.15123 -234.517692) (xy 330.951078 -234.517692) (xy 330.951078 -234.562142)
			(xy 331.051154 -234.662218)
		)
		(stroke
			(width 0)
			(type solid)
		)
		(fill yes)
		(layer "In2.Cu")
		(net "M_C_CPU0_SA_DQ<15>")
	)
	(gr_poly
		(pts
			(xy 331.15123 -233.34599) (xy 331.051154 -233.245914) (xy 330.951078 -233.34599) (xy 330.951078 -233.39044)
			(xy 331.15123 -233.39044)
		)
		(stroke
			(width 0)
			(type solid)
		)
		(fill yes)
		(layer "In2.Cu")
		(net "M_C_CPU0_SA_DQ<12>")
	)
	(gr_poly
		(pts
			(xy 331.15123 -232.942384) (xy 331.15123 -232.894632) (xy 330.951078 -232.894632) (xy 330.951078 -232.942384)
			(xy 331.051154 -233.042206)
		)
		(stroke
			(width 0)
			(type solid)
		)
		(fill yes)
		(layer "In2.Cu")
		(net "M_C_CPU0_SA_DQS_DP<6>")
	)
	(gr_poly
		(pts
			(xy 331.15123 -231.725724) (xy 331.051154 -231.625902) (xy 330.951078 -231.725724) (xy 330.951078 -231.773476)
			(xy 331.15123 -231.773476)
		)
		(stroke
			(width 0)
			(type solid)
		)
		(fill yes)
		(layer "In2.Cu")
		(net "M_C_CPU0_SA_DQS_DP<1>")
	)
	(gr_poly
		(pts
			(xy 331.15123 -231.322372) (xy 331.15123 -231.277922) (xy 330.951078 -231.277922) (xy 330.951078 -231.322372)
			(xy 331.051154 -231.422448)
		)
		(stroke
			(width 0)
			(type solid)
		)
		(fill yes)
		(layer "In2.Cu")
		(net "M_C_CPU0_SA_DQ<11>")
	)
	(gr_poly
		(pts
			(xy 331.15123 -230.105966) (xy 331.051154 -230.006144) (xy 330.951078 -230.105966) (xy 330.951078 -230.150416)
			(xy 331.15123 -230.150416)
		)
		(stroke
			(width 0)
			(type solid)
		)
		(fill yes)
		(layer "In2.Cu")
		(net "M_C_CPU0_SA_DQ<8>")
	)
	(gr_poly
		(pts
			(xy 331.15123 -229.70236) (xy 331.15123 -229.65791) (xy 330.951078 -229.65791) (xy 330.951078 -229.70236)
			(xy 331.051154 -229.802436)
		)
		(stroke
			(width 0)
			(type solid)
		)
		(fill yes)
		(layer "In2.Cu")
		(net "M_C_CPU0_SA_DQ<7>")
	)
	(gr_poly
		(pts
			(xy 331.15123 -228.486208) (xy 331.051154 -228.386132) (xy 330.951078 -228.486208) (xy 330.951078 -228.530658)
			(xy 331.15123 -228.530658)
		)
		(stroke
			(width 0)
			(type solid)
		)
		(fill yes)
		(layer "In2.Cu")
		(net "M_C_CPU0_SA_DQ<4>")
	)
	(gr_poly
		(pts
			(xy 331.15123 -228.082602) (xy 331.15123 -228.03485) (xy 330.951078 -228.03485) (xy 330.951078 -228.082602)
			(xy 331.051154 -228.182424)
		)
		(stroke
			(width 0)
			(type solid)
		)
		(fill yes)
		(layer "In2.Cu")
		(net "M_C_CPU0_SA_DQS_DP<5>")
	)
	(gr_poly
		(pts
			(xy 331.17028 -226.465638) (xy 331.206856 -226.32924) (xy 331.070204 -226.292664) (xy 331.029056 -226.316286)
			(xy 331.128878 -226.489514)
		)
		(stroke
			(width 0)
			(type solid)
		)
		(fill yes)
		(layer "In2.Cu")
		(net "M_C_CPU0_SA_DQS_DP<0>")
	)
	(gr_poly
		(pts
			(xy 331.17028 -224.846388) (xy 331.20711 -224.709736) (xy 331.070458 -224.67316) (xy 331.03185 -224.695512)
			(xy 331.131926 -224.86874)
		)
		(stroke
			(width 0)
			(type solid)
		)
		(fill yes)
		(layer "In2.Cu")
		(net "M_C_CPU0_SA_DQ<1>")
	)
	(gr_poly
		(pts
			(xy 331.17028 -223.226376) (xy 331.20711 -223.089724) (xy 331.070458 -223.053148) (xy 331.03185 -223.0755)
			(xy 331.131926 -223.248728)
		)
		(stroke
			(width 0)
			(type solid)
		)
		(fill yes)
		(layer "In2.Cu")
		(net "M_C_CPU0_SA_DQ<0>")
	)
	(gr_poly
		(pts
			(xy 331.444854 -266.991592) (xy 331.344778 -266.891516) (xy 331.244956 -266.991592) (xy 331.244956 -267.036042)
			(xy 331.444854 -267.036042)
		)
		(stroke
			(width 0)
			(type solid)
		)
		(fill yes)
		(layer "In2.Cu")
		(net "M_C_CPU0_SA_RSP<0>")
	)
	(gr_poly
		(pts
			(xy 331.451204 -292.91788) (xy 331.351128 -292.817804) (xy 331.251052 -292.91788) (xy 331.251052 -292.96233)
			(xy 331.451204 -292.96233)
		)
		(stroke
			(width 0)
			(type solid)
		)
		(fill yes)
		(layer "In2.Cu")
		(net "M_C_CPU0_SB_DQ<29>")
	)
	(gr_poly
		(pts
			(xy 331.451204 -292.51402) (xy 331.451204 -292.46957) (xy 331.251052 -292.46957) (xy 331.251052 -292.51402)
			(xy 331.351128 -292.614096)
		)
		(stroke
			(width 0)
			(type solid)
		)
		(fill yes)
		(layer "In2.Cu")
		(net "M_C_CPU0_SB_DQ<30>")
	)
	(gr_poly
		(pts
			(xy 331.451204 -291.297614) (xy 331.351128 -291.197792) (xy 331.251052 -291.297614) (xy 331.251052 -291.345366)
			(xy 331.451204 -291.345366)
		)
		(stroke
			(width 0)
			(type solid)
		)
		(fill yes)
		(layer "In2.Cu")
		(net "M_C_CPU0_SB_DQS_DN<8>")
	)
	(gr_poly
		(pts
			(xy 331.451204 -290.894262) (xy 331.451204 -290.84651) (xy 331.251052 -290.84651) (xy 331.251052 -290.894262)
			(xy 331.351128 -290.994084)
		)
		(stroke
			(width 0)
			(type solid)
		)
		(fill yes)
		(layer "In2.Cu")
		(net "M_C_CPU0_SB_DQS_DN<3>")
	)
	(gr_poly
		(pts
			(xy 331.451204 -289.677856) (xy 331.351128 -289.57778) (xy 331.251052 -289.677856) (xy 331.251052 -289.722306)
			(xy 331.451204 -289.722306)
		)
		(stroke
			(width 0)
			(type solid)
		)
		(fill yes)
		(layer "In2.Cu")
		(net "M_C_CPU0_SB_DQ<25>")
	)
	(gr_poly
		(pts
			(xy 331.451204 -289.273996) (xy 331.451204 -289.229546) (xy 331.251052 -289.229546) (xy 331.251052 -289.273996)
			(xy 331.351128 -289.374072)
		)
		(stroke
			(width 0)
			(type solid)
		)
		(fill yes)
		(layer "In2.Cu")
		(net "M_C_CPU0_SB_DQ<26>")
	)
	(gr_poly
		(pts
			(xy 331.451204 -288.057844) (xy 331.351128 -287.957768) (xy 331.251052 -288.057844) (xy 331.251052 -288.102294)
			(xy 331.451204 -288.102294)
		)
		(stroke
			(width 0)
			(type solid)
		)
		(fill yes)
		(layer "In2.Cu")
		(net "M_C_CPU0_SB_DQ<21>")
	)
	(gr_poly
		(pts
			(xy 331.451204 -287.654238) (xy 331.451204 -287.609788) (xy 331.251052 -287.609788) (xy 331.251052 -287.654238)
			(xy 331.351128 -287.75406)
		)
		(stroke
			(width 0)
			(type solid)
		)
		(fill yes)
		(layer "In2.Cu")
		(net "M_C_CPU0_SB_DQ<22>")
	)
	(gr_poly
		(pts
			(xy 331.451204 -286.437832) (xy 331.351128 -286.337756) (xy 331.251052 -286.437832) (xy 331.251052 -286.485584)
			(xy 331.451204 -286.485584)
		)
		(stroke
			(width 0)
			(type solid)
		)
		(fill yes)
		(layer "In2.Cu")
		(net "M_C_CPU0_SB_DQS_DN<7>")
	)
	(gr_poly
		(pts
			(xy 331.451204 -286.03448) (xy 331.451204 -285.986728) (xy 331.251052 -285.986728) (xy 331.251052 -286.03448)
			(xy 331.351128 -286.134302)
		)
		(stroke
			(width 0)
			(type solid)
		)
		(fill yes)
		(layer "In2.Cu")
		(net "M_C_CPU0_SB_DQS_DN<2>")
	)
	(gr_poly
		(pts
			(xy 331.451204 -284.818074) (xy 331.351128 -284.717998) (xy 331.251052 -284.818074) (xy 331.251052 -284.862524)
			(xy 331.451204 -284.862524)
		)
		(stroke
			(width 0)
			(type solid)
		)
		(fill yes)
		(layer "In2.Cu")
		(net "M_C_CPU0_SB_DQ<17>")
	)
	(gr_poly
		(pts
			(xy 331.451204 -284.414214) (xy 331.451204 -284.369764) (xy 331.251052 -284.369764) (xy 331.251052 -284.414214)
			(xy 331.351128 -284.51429)
		)
		(stroke
			(width 0)
			(type solid)
		)
		(fill yes)
		(layer "In2.Cu")
		(net "M_C_CPU0_SB_DQ<18>")
	)
	(gr_poly
		(pts
			(xy 331.451204 -283.198062) (xy 331.351128 -283.097986) (xy 331.251052 -283.198062) (xy 331.251052 -283.242512)
			(xy 331.451204 -283.242512)
		)
		(stroke
			(width 0)
			(type solid)
		)
		(fill yes)
		(layer "In2.Cu")
		(net "M_C_CPU0_SB_DQ<13>")
	)
	(gr_poly
		(pts
			(xy 331.451204 -282.794202) (xy 331.451204 -282.749752) (xy 331.251052 -282.749752) (xy 331.251052 -282.794202)
			(xy 331.351128 -282.894278)
		)
		(stroke
			(width 0)
			(type solid)
		)
		(fill yes)
		(layer "In2.Cu")
		(net "M_C_CPU0_SB_DQ<14>")
	)
	(gr_poly
		(pts
			(xy 331.451204 -281.577796) (xy 331.351128 -281.477974) (xy 331.251052 -281.577796) (xy 331.251052 -281.625548)
			(xy 331.451204 -281.625548)
		)
		(stroke
			(width 0)
			(type solid)
		)
		(fill yes)
		(layer "In2.Cu")
		(net "M_C_CPU0_SB_DQS_DN<6>")
	)
	(gr_poly
		(pts
			(xy 331.451204 -281.174444) (xy 331.451204 -281.126692) (xy 331.251052 -281.126692) (xy 331.251052 -281.174444)
			(xy 331.351128 -281.274266)
		)
		(stroke
			(width 0)
			(type solid)
		)
		(fill yes)
		(layer "In2.Cu")
		(net "M_C_CPU0_SB_DQS_DN<1>")
	)
	(gr_poly
		(pts
			(xy 331.451204 -279.958038) (xy 331.351128 -279.857962) (xy 331.251052 -279.958038) (xy 331.251052 -280.002488)
			(xy 331.451204 -280.002488)
		)
		(stroke
			(width 0)
			(type solid)
		)
		(fill yes)
		(layer "In2.Cu")
		(net "M_C_CPU0_SB_DQ<9>")
	)
	(gr_poly
		(pts
			(xy 331.451204 -279.554178) (xy 331.451204 -279.509728) (xy 331.251052 -279.509728) (xy 331.251052 -279.554178)
			(xy 331.351128 -279.654254)
		)
		(stroke
			(width 0)
			(type solid)
		)
		(fill yes)
		(layer "In2.Cu")
		(net "M_C_CPU0_SB_DQ<10>")
	)
	(gr_poly
		(pts
			(xy 331.451204 -278.338026) (xy 331.351128 -278.23795) (xy 331.251052 -278.338026) (xy 331.251052 -278.382476)
			(xy 331.451204 -278.382476)
		)
		(stroke
			(width 0)
			(type solid)
		)
		(fill yes)
		(layer "In2.Cu")
		(net "M_C_CPU0_SB_DQ<5>")
	)
	(gr_poly
		(pts
			(xy 331.451204 -277.934166) (xy 331.451204 -277.889716) (xy 331.251052 -277.889716) (xy 331.251052 -277.934166)
			(xy 331.351128 -278.034242)
		)
		(stroke
			(width 0)
			(type solid)
		)
		(fill yes)
		(layer "In2.Cu")
		(net "M_C_CPU0_SB_DQ<6>")
	)
	(gr_poly
		(pts
			(xy 331.451204 -276.71776) (xy 331.351128 -276.617938) (xy 331.251052 -276.71776) (xy 331.251052 -276.765512)
			(xy 331.451204 -276.765512)
		)
		(stroke
			(width 0)
			(type solid)
		)
		(fill yes)
		(layer "In2.Cu")
		(net "M_C_CPU0_SB_DQS_DN<5>")
	)
	(gr_poly
		(pts
			(xy 331.451204 -276.314408) (xy 331.451204 -276.266656) (xy 331.251052 -276.266656) (xy 331.251052 -276.314408)
			(xy 331.351128 -276.41423)
		)
		(stroke
			(width 0)
			(type solid)
		)
		(fill yes)
		(layer "In2.Cu")
		(net "M_C_CPU0_SB_DQS_DN<0>")
	)
	(gr_poly
		(pts
			(xy 331.451204 -275.098002) (xy 331.351128 -274.997926) (xy 331.251052 -275.098002) (xy 331.251052 -275.142452)
			(xy 331.451204 -275.142452)
		)
		(stroke
			(width 0)
			(type solid)
		)
		(fill yes)
		(layer "In2.Cu")
		(net "M_C_CPU0_SB_DQ<1>")
	)
	(gr_poly
		(pts
			(xy 331.451204 -274.694142) (xy 331.451204 -274.649692) (xy 331.251052 -274.649692) (xy 331.251052 -274.694142)
			(xy 331.351128 -274.794218)
		)
		(stroke
			(width 0)
			(type solid)
		)
		(fill yes)
		(layer "In2.Cu")
		(net "M_C_CPU0_SB_DQ<2>")
	)
	(gr_poly
		(pts
			(xy 331.451204 -273.47799) (xy 331.351128 -273.377914) (xy 331.251052 -273.47799) (xy 331.251052 -273.52244)
			(xy 331.451204 -273.52244)
		)
		(stroke
			(width 0)
			(type solid)
		)
		(fill yes)
		(layer "In2.Cu")
		(net "M_C_CPU0_SB_CB<1>")
	)
	(gr_poly
		(pts
			(xy 331.451204 -273.07413) (xy 331.451204 -273.02968) (xy 331.251052 -273.02968) (xy 331.251052 -273.07413)
			(xy 331.351128 -273.174206)
		)
		(stroke
			(width 0)
			(type solid)
		)
		(fill yes)
		(layer "In2.Cu")
		(net "M_C_CPU0_SB_CB<2>")
	)
	(gr_poly
		(pts
			(xy 331.451204 -271.857724) (xy 331.351128 -271.757902) (xy 331.251052 -271.857724) (xy 331.251052 -271.905476)
			(xy 331.451204 -271.905476)
		)
		(stroke
			(width 0)
			(type solid)
		)
		(fill yes)
		(layer "In2.Cu")
		(net "M_C_CPU0_SB_DQS_DN<4>")
	)
	(gr_poly
		(pts
			(xy 331.451204 -271.454372) (xy 331.451204 -271.40662) (xy 331.251052 -271.40662) (xy 331.251052 -271.454372)
			(xy 331.351128 -271.554194)
		)
		(stroke
			(width 0)
			(type solid)
		)
		(fill yes)
		(layer "In2.Cu")
		(net "M_C_CPU0_SB_DQS_DN<9>")
	)
	(gr_poly
		(pts
			(xy 331.451204 -270.237966) (xy 331.351128 -270.13789) (xy 331.251052 -270.237966) (xy 331.251052 -270.282416)
			(xy 331.451204 -270.282416)
		)
		(stroke
			(width 0)
			(type solid)
		)
		(fill yes)
		(layer "In2.Cu")
		(net "M_C_CPU0_SB_CB<5>")
	)
	(gr_poly
		(pts
			(xy 331.451204 -269.834106) (xy 331.451204 -269.789656) (xy 331.251052 -269.789656) (xy 331.251052 -269.834106)
			(xy 331.351128 -269.934182)
		)
		(stroke
			(width 0)
			(type solid)
		)
		(fill yes)
		(layer "In2.Cu")
		(net "M_C_CPU0_SB_CB<6>")
	)
	(gr_poly
		(pts
			(xy 331.451204 -266.594082) (xy 331.451204 -266.549632) (xy 331.251052 -266.549632) (xy 331.251052 -266.594082)
			(xy 331.351128 -266.694158)
		)
		(stroke
			(width 0)
			(type solid)
		)
		(fill yes)
		(layer "In2.Cu")
		(net "M_C_CPU0_SB_CS_N<1>")
	)
	(gr_poly
		(pts
			(xy 331.451204 -264.97407) (xy 331.451204 -264.92962) (xy 331.251052 -264.92962) (xy 331.251052 -264.97407)
			(xy 331.351128 -265.074146)
		)
		(stroke
			(width 0)
			(type solid)
		)
		(fill yes)
		(layer "In2.Cu")
		(net "M_C_CPU0_SB_PAR")
	)
	(gr_poly
		(pts
			(xy 331.451204 -263.757918) (xy 331.351128 -263.657842) (xy 331.251052 -263.757918) (xy 331.251052 -263.802368)
			(xy 331.451204 -263.802368)
		)
		(stroke
			(width 0)
			(type solid)
		)
		(fill yes)
		(layer "In2.Cu")
		(net "M_C_CPU0_SB_CA<4>")
	)
	(gr_poly
		(pts
			(xy 331.451204 -263.354058) (xy 331.451204 -263.309608) (xy 331.251052 -263.309608) (xy 331.251052 -263.354058)
			(xy 331.351128 -263.454134)
		)
		(stroke
			(width 0)
			(type solid)
		)
		(fill yes)
		(layer "In2.Cu")
		(net "M_C_CPU0_SB_CA<3>")
	)
	(gr_poly
		(pts
			(xy 331.451204 -262.137906) (xy 331.351128 -262.03783) (xy 331.251052 -262.137906) (xy 331.251052 -262.182356)
			(xy 331.451204 -262.182356)
		)
		(stroke
			(width 0)
			(type solid)
		)
		(fill yes)
		(layer "In2.Cu")
		(net "M_C_CPU0_SB_CA<0>")
	)
	(gr_poly
		(pts
			(xy 331.540358 -226.203002) (xy 331.440282 -226.029774) (xy 331.401928 -226.052126) (xy 331.365098 -226.188778)
			(xy 331.50175 -226.225354)
		)
		(stroke
			(width 0)
			(type solid)
		)
		(fill yes)
		(layer "In2.Cu")
		(net "M_C_CPU0_SA_DQ<3>")
	)
	(gr_poly
		(pts
			(xy 331.540358 -224.58299) (xy 331.440282 -224.409762) (xy 331.401928 -224.432114) (xy 331.365098 -224.568766)
			(xy 331.50175 -224.605342)
		)
		(stroke
			(width 0)
			(type solid)
		)
		(fill yes)
		(layer "In2.Cu")
		(net "M_C_CPU0_SA_DQ<2>")
	)
	(gr_poly
		(pts
			(xy 331.620876 -246.712232) (xy 331.620876 -246.664734) (xy 331.420978 -246.664734) (xy 331.420978 -246.712232)
			(xy 331.5208 -246.812308)
		)
		(stroke
			(width 0)
			(type solid)
		)
		(fill yes)
		(layer "In2.Cu")
		(net "M_C_CPU0_SA_DQS_DN<4>")
	)
	(gr_poly
		(pts
			(xy 331.62113 -256.432558) (xy 331.62113 -256.384806) (xy 331.420978 -256.384806) (xy 331.420978 -256.432558)
			(xy 331.521054 -256.53238)
		)
		(stroke
			(width 0)
			(type solid)
		)
		(fill yes)
		(layer "In2.Cu")
		(net "M_C_CPU0_CLK_DN<0>")
	)
	(gr_poly
		(pts
			(xy 331.62113 -255.216152) (xy 331.521054 -255.116076) (xy 331.420978 -255.216152) (xy 331.420978 -255.260602)
			(xy 331.62113 -255.260602)
		)
		(stroke
			(width 0)
			(type solid)
		)
		(fill yes)
		(layer "In2.Cu")
		(net "M_C_CPU0_SA_CA<6>")
	)
	(gr_poly
		(pts
			(xy 331.62113 -254.812292) (xy 331.62113 -254.767842) (xy 331.420978 -254.767842) (xy 331.420978 -254.812292)
			(xy 331.521054 -254.912368)
		)
		(stroke
			(width 0)
			(type solid)
		)
		(fill yes)
		(layer "In2.Cu")
		(net "M_C_CPU0_SA_CA<5>")
	)
	(gr_poly
		(pts
			(xy 331.62113 -253.59614) (xy 331.521054 -253.496064) (xy 331.420978 -253.59614) (xy 331.420978 -253.64059)
			(xy 331.62113 -253.64059)
		)
		(stroke
			(width 0)
			(type solid)
		)
		(fill yes)
		(layer "In2.Cu")
		(net "M_C_CPU0_SA_CA<2>")
	)
	(gr_poly
		(pts
			(xy 331.62113 -253.19228) (xy 331.62113 -253.14783) (xy 331.420978 -253.14783) (xy 331.420978 -253.19228)
			(xy 331.521054 -253.292356)
		)
		(stroke
			(width 0)
			(type solid)
		)
		(fill yes)
		(layer "In2.Cu")
		(net "M_C_CPU0_SA_CA<1>")
	)
	(gr_poly
		(pts
			(xy 331.62113 -251.572268) (xy 331.62113 -251.527818) (xy 331.420978 -251.527818) (xy 331.420978 -251.572268)
			(xy 331.521054 -251.672344)
		)
		(stroke
			(width 0)
			(type solid)
		)
		(fill yes)
		(layer "In2.Cu")
		(net "M_C_CPU0_SA_CS_N<0>")
	)
	(gr_poly
		(pts
			(xy 331.62113 -250.356116) (xy 331.521054 -250.25604) (xy 331.420978 -250.356116) (xy 331.420978 -250.400566)
			(xy 331.62113 -250.400566)
		)
		(stroke
			(width 0)
			(type solid)
		)
		(fill yes)
		(layer "In2.Cu")
		(net "M_C_CPU0_ALERT_R_N")
	)
	(gr_poly
		(pts
			(xy 331.62113 -248.736104) (xy 331.521054 -248.636028) (xy 331.420978 -248.736104) (xy 331.420978 -248.780554)
			(xy 331.62113 -248.780554)
		)
		(stroke
			(width 0)
			(type solid)
		)
		(fill yes)
		(layer "In2.Cu")
		(net "M_C_CPU0_SA_CB<5>")
	)
	(gr_poly
		(pts
			(xy 331.62113 -248.332244) (xy 331.62113 -248.287794) (xy 331.420978 -248.287794) (xy 331.420978 -248.332244)
			(xy 331.521054 -248.43232)
		)
		(stroke
			(width 0)
			(type solid)
		)
		(fill yes)
		(layer "In2.Cu")
		(net "M_C_CPU0_SA_CB<6>")
	)
	(gr_poly
		(pts
			(xy 331.62113 -247.115838) (xy 331.521054 -247.016016) (xy 331.420978 -247.115838) (xy 331.420978 -247.16359)
			(xy 331.62113 -247.16359)
		)
		(stroke
			(width 0)
			(type solid)
		)
		(fill yes)
		(layer "In2.Cu")
		(net "M_C_CPU0_SA_DQS_DN<9>")
	)
	(gr_poly
		(pts
			(xy 331.62113 -245.49608) (xy 331.521054 -245.396004) (xy 331.420978 -245.49608) (xy 331.420978 -245.54053)
			(xy 331.62113 -245.54053)
		)
		(stroke
			(width 0)
			(type solid)
		)
		(fill yes)
		(layer "In2.Cu")
		(net "M_C_CPU0_SA_CB<1>")
	)
	(gr_poly
		(pts
			(xy 331.62113 -245.09222) (xy 331.62113 -245.04777) (xy 331.420978 -245.04777) (xy 331.420978 -245.09222)
			(xy 331.521054 -245.192296)
		)
		(stroke
			(width 0)
			(type solid)
		)
		(fill yes)
		(layer "In2.Cu")
		(net "M_C_CPU0_SA_CB<2>")
	)
	(gr_poly
		(pts
			(xy 331.62113 -243.876068) (xy 331.521054 -243.775992) (xy 331.420978 -243.876068) (xy 331.420978 -243.920518)
			(xy 331.62113 -243.920518)
		)
		(stroke
			(width 0)
			(type solid)
		)
		(fill yes)
		(layer "In2.Cu")
		(net "M_C_CPU0_SA_DQ<29>")
	)
	(gr_poly
		(pts
			(xy 331.62113 -243.472208) (xy 331.62113 -243.427758) (xy 331.420978 -243.427758) (xy 331.420978 -243.472208)
			(xy 331.521054 -243.572284)
		)
		(stroke
			(width 0)
			(type solid)
		)
		(fill yes)
		(layer "In2.Cu")
		(net "M_C_CPU0_SA_DQ<30>")
	)
	(gr_poly
		(pts
			(xy 331.62113 -242.255802) (xy 331.521054 -242.15598) (xy 331.420978 -242.255802) (xy 331.420978 -242.303554)
			(xy 331.62113 -242.303554)
		)
		(stroke
			(width 0)
			(type solid)
		)
		(fill yes)
		(layer "In2.Cu")
		(net "M_C_CPU0_SA_DQS_DN<8>")
	)
	(gr_poly
		(pts
			(xy 331.62113 -241.85245) (xy 331.62113 -241.804698) (xy 331.420978 -241.804698) (xy 331.420978 -241.85245)
			(xy 331.521054 -241.952272)
		)
		(stroke
			(width 0)
			(type solid)
		)
		(fill yes)
		(layer "In2.Cu")
		(net "M_C_CPU0_SA_DQS_DN<3>")
	)
	(gr_poly
		(pts
			(xy 331.62113 -240.636044) (xy 331.521054 -240.535968) (xy 331.420978 -240.636044) (xy 331.420978 -240.680494)
			(xy 331.62113 -240.680494)
		)
		(stroke
			(width 0)
			(type solid)
		)
		(fill yes)
		(layer "In2.Cu")
		(net "M_C_CPU0_SA_DQ<25>")
	)
	(gr_poly
		(pts
			(xy 331.62113 -240.232184) (xy 331.62113 -240.187734) (xy 331.420978 -240.187734) (xy 331.420978 -240.232184)
			(xy 331.521054 -240.33226)
		)
		(stroke
			(width 0)
			(type solid)
		)
		(fill yes)
		(layer "In2.Cu")
		(net "M_C_CPU0_SA_DQ<26>")
	)
	(gr_poly
		(pts
			(xy 331.62113 -239.016032) (xy 331.521054 -238.915956) (xy 331.420978 -239.016032) (xy 331.420978 -239.060482)
			(xy 331.62113 -239.060482)
		)
		(stroke
			(width 0)
			(type solid)
		)
		(fill yes)
		(layer "In2.Cu")
		(net "M_C_CPU0_SA_DQ<21>")
	)
	(gr_poly
		(pts
			(xy 331.62113 -238.612172) (xy 331.62113 -238.567722) (xy 331.420978 -238.567722) (xy 331.420978 -238.612172)
			(xy 331.521054 -238.712248)
		)
		(stroke
			(width 0)
			(type solid)
		)
		(fill yes)
		(layer "In2.Cu")
		(net "M_C_CPU0_SA_DQ<22>")
	)
	(gr_poly
		(pts
			(xy 331.62113 -237.395766) (xy 331.521054 -237.295944) (xy 331.420978 -237.395766) (xy 331.420978 -237.443518)
			(xy 331.62113 -237.443518)
		)
		(stroke
			(width 0)
			(type solid)
		)
		(fill yes)
		(layer "In2.Cu")
		(net "M_C_CPU0_SA_DQS_DN<7>")
	)
	(gr_poly
		(pts
			(xy 331.62113 -236.992414) (xy 331.62113 -236.944662) (xy 331.420978 -236.944662) (xy 331.420978 -236.992414)
			(xy 331.521054 -237.092236)
		)
		(stroke
			(width 0)
			(type solid)
		)
		(fill yes)
		(layer "In2.Cu")
		(net "M_C_CPU0_SA_DQS_DN<2>")
	)
	(gr_poly
		(pts
			(xy 331.62113 -235.776008) (xy 331.521054 -235.675932) (xy 331.420978 -235.776008) (xy 331.420978 -235.820458)
			(xy 331.62113 -235.820458)
		)
		(stroke
			(width 0)
			(type solid)
		)
		(fill yes)
		(layer "In2.Cu")
		(net "M_C_CPU0_SA_DQ<17>")
	)
	(gr_poly
		(pts
			(xy 331.62113 -235.372148) (xy 331.62113 -235.327698) (xy 331.420978 -235.327698) (xy 331.420978 -235.372148)
			(xy 331.521054 -235.472224)
		)
		(stroke
			(width 0)
			(type solid)
		)
		(fill yes)
		(layer "In2.Cu")
		(net "M_C_CPU0_SA_DQ<18>")
	)
	(gr_poly
		(pts
			(xy 331.62113 -234.155996) (xy 331.521054 -234.05592) (xy 331.420978 -234.155996) (xy 331.420978 -234.200446)
			(xy 331.62113 -234.200446)
		)
		(stroke
			(width 0)
			(type solid)
		)
		(fill yes)
		(layer "In2.Cu")
		(net "M_C_CPU0_SA_DQ<13>")
	)
	(gr_poly
		(pts
			(xy 331.62113 -233.752136) (xy 331.62113 -233.707686) (xy 331.420978 -233.707686) (xy 331.420978 -233.752136)
			(xy 331.521054 -233.852212)
		)
		(stroke
			(width 0)
			(type solid)
		)
		(fill yes)
		(layer "In2.Cu")
		(net "M_C_CPU0_SA_DQ<14>")
	)
	(gr_poly
		(pts
			(xy 331.62113 -232.53573) (xy 331.521054 -232.435908) (xy 331.420978 -232.53573) (xy 331.420978 -232.583482)
			(xy 331.62113 -232.583482)
		)
		(stroke
			(width 0)
			(type solid)
		)
		(fill yes)
		(layer "In2.Cu")
		(net "M_C_CPU0_SA_DQS_DN<6>")
	)
	(gr_poly
		(pts
			(xy 331.62113 -232.132378) (xy 331.62113 -232.084626) (xy 331.420978 -232.084626) (xy 331.420978 -232.132378)
			(xy 331.521054 -232.2322)
		)
		(stroke
			(width 0)
			(type solid)
		)
		(fill yes)
		(layer "In2.Cu")
		(net "M_C_CPU0_SA_DQS_DN<1>")
	)
	(gr_poly
		(pts
			(xy 331.62113 -230.915972) (xy 331.521054 -230.815896) (xy 331.420978 -230.915972) (xy 331.420978 -230.960422)
			(xy 331.62113 -230.960422)
		)
		(stroke
			(width 0)
			(type solid)
		)
		(fill yes)
		(layer "In2.Cu")
		(net "M_C_CPU0_SA_DQ<9>")
	)
	(gr_poly
		(pts
			(xy 331.62113 -230.512366) (xy 331.62113 -230.467916) (xy 331.420978 -230.467916) (xy 331.420978 -230.512366)
			(xy 331.521054 -230.612188)
		)
		(stroke
			(width 0)
			(type solid)
		)
		(fill yes)
		(layer "In2.Cu")
		(net "M_C_CPU0_SA_DQ<10>")
	)
	(gr_poly
		(pts
			(xy 331.62113 -229.29596) (xy 331.521054 -229.195884) (xy 331.420978 -229.29596) (xy 331.420978 -229.34041)
			(xy 331.62113 -229.34041)
		)
		(stroke
			(width 0)
			(type solid)
		)
		(fill yes)
		(layer "In2.Cu")
		(net "M_C_CPU0_SA_DQ<5>")
	)
	(gr_poly
		(pts
			(xy 331.62113 -228.892354) (xy 331.62113 -228.847904) (xy 331.420978 -228.847904) (xy 331.420978 -228.892354)
			(xy 331.521054 -228.99243)
		)
		(stroke
			(width 0)
			(type solid)
		)
		(fill yes)
		(layer "In2.Cu")
		(net "M_C_CPU0_SA_DQ<6>")
	)
	(gr_poly
		(pts
			(xy 331.62113 -227.675948) (xy 331.521054 -227.576126) (xy 331.420978 -227.675948) (xy 331.420978 -227.7237)
			(xy 331.62113 -227.7237)
		)
		(stroke
			(width 0)
			(type solid)
		)
		(fill yes)
		(layer "In2.Cu")
		(net "M_C_CPU0_SA_DQS_DN<5>")
	)
	(gr_poly
		(pts
			(xy 331.62113 -227.272596) (xy 331.62113 -227.224844) (xy 331.420978 -227.224844) (xy 331.420978 -227.272596)
			(xy 331.521054 -227.372418)
		)
		(stroke
			(width 0)
			(type solid)
		)
		(fill yes)
		(layer "In2.Cu")
		(net "M_C_CPU0_SA_DQS_DN<0>")
	)
	(gr_poly
		(pts
			(xy 331.640434 -225.656394) (xy 331.67701 -225.519742) (xy 331.540612 -225.483166) (xy 331.502004 -225.505518)
			(xy 331.60208 -225.678746)
		)
		(stroke
			(width 0)
			(type solid)
		)
		(fill yes)
		(layer "In2.Cu")
		(net "M_C_CPU0_SA_DQ<1>")
	)
	(gr_poly
		(pts
			(xy 331.640434 -224.036382) (xy 331.67701 -223.89973) (xy 331.540612 -223.863154) (xy 331.502004 -223.885506)
			(xy 331.60208 -224.058734)
		)
		(stroke
			(width 0)
			(type solid)
		)
		(fill yes)
		(layer "In2.Cu")
		(net "M_C_CPU0_SA_DQ<0>")
	)
	(gr_poly
		(pts
			(xy 331.921104 -293.324026) (xy 331.921104 -293.279576) (xy 331.720952 -293.279576) (xy 331.720952 -293.324026)
			(xy 331.821028 -293.424102)
		)
		(stroke
			(width 0)
			(type solid)
		)
		(fill yes)
		(layer "In2.Cu")
		(net "M_C_CPU0_SB_DQ<31>")
	)
	(gr_poly
		(pts
			(xy 331.921104 -292.107874) (xy 331.821028 -292.007798) (xy 331.720952 -292.107874) (xy 331.720952 -292.152324)
			(xy 331.921104 -292.152324)
		)
		(stroke
			(width 0)
			(type solid)
		)
		(fill yes)
		(layer "In2.Cu")
		(net "M_C_CPU0_SB_DQ<28>")
	)
	(gr_poly
		(pts
			(xy 331.921104 -291.704268) (xy 331.921104 -291.656516) (xy 331.720952 -291.656516) (xy 331.720952 -291.704268)
			(xy 331.821028 -291.80409)
		)
		(stroke
			(width 0)
			(type solid)
		)
		(fill yes)
		(layer "In2.Cu")
		(net "M_C_CPU0_SB_DQS_DP<8>")
	)
	(gr_poly
		(pts
			(xy 331.921104 -290.487608) (xy 331.821028 -290.387786) (xy 331.720952 -290.487608) (xy 331.720952 -290.53536)
			(xy 331.921104 -290.53536)
		)
		(stroke
			(width 0)
			(type solid)
		)
		(fill yes)
		(layer "In2.Cu")
		(net "M_C_CPU0_SB_DQS_DP<3>")
	)
	(gr_poly
		(pts
			(xy 331.921104 -290.084002) (xy 331.921104 -290.039552) (xy 331.720952 -290.039552) (xy 331.720952 -290.084002)
			(xy 331.821028 -290.184078)
		)
		(stroke
			(width 0)
			(type solid)
		)
		(fill yes)
		(layer "In2.Cu")
		(net "M_C_CPU0_SB_DQ<27>")
	)
	(gr_poly
		(pts
			(xy 331.921104 -288.86785) (xy 331.821028 -288.767774) (xy 331.720952 -288.86785) (xy 331.720952 -288.9123)
			(xy 331.921104 -288.9123)
		)
		(stroke
			(width 0)
			(type solid)
		)
		(fill yes)
		(layer "In2.Cu")
		(net "M_C_CPU0_SB_DQ<24>")
	)
	(gr_poly
		(pts
			(xy 331.921104 -288.464244) (xy 331.921104 -288.419794) (xy 331.720952 -288.419794) (xy 331.720952 -288.464244)
			(xy 331.821028 -288.56432)
		)
		(stroke
			(width 0)
			(type solid)
		)
		(fill yes)
		(layer "In2.Cu")
		(net "M_C_CPU0_SB_DQ<23>")
	)
	(gr_poly
		(pts
			(xy 331.921104 -287.247838) (xy 331.821028 -287.148016) (xy 331.720952 -287.247838) (xy 331.720952 -287.292288)
			(xy 331.921104 -287.292288)
		)
		(stroke
			(width 0)
			(type solid)
		)
		(fill yes)
		(layer "In2.Cu")
		(net "M_C_CPU0_SB_DQ<20>")
	)
	(gr_poly
		(pts
			(xy 331.921104 -286.844232) (xy 331.921104 -286.79648) (xy 331.720952 -286.79648) (xy 331.720952 -286.844232)
			(xy 331.821028 -286.944308)
		)
		(stroke
			(width 0)
			(type solid)
		)
		(fill yes)
		(layer "In2.Cu")
		(net "M_C_CPU0_SB_DQS_DP<7>")
	)
	(gr_poly
		(pts
			(xy 331.921104 -285.627826) (xy 331.821028 -285.528004) (xy 331.720952 -285.627826) (xy 331.720952 -285.675578)
			(xy 331.921104 -285.675578)
		)
		(stroke
			(width 0)
			(type solid)
		)
		(fill yes)
		(layer "In2.Cu")
		(net "M_C_CPU0_SB_DQS_DP<2>")
	)
	(gr_poly
		(pts
			(xy 331.921104 -285.22422) (xy 331.921104 -285.17977) (xy 331.720952 -285.17977) (xy 331.720952 -285.22422)
			(xy 331.821028 -285.324296)
		)
		(stroke
			(width 0)
			(type solid)
		)
		(fill yes)
		(layer "In2.Cu")
		(net "M_C_CPU0_SB_DQ<19>")
	)
	(gr_poly
		(pts
			(xy 331.921104 -284.008068) (xy 331.821028 -283.907992) (xy 331.720952 -284.008068) (xy 331.720952 -284.052518)
			(xy 331.921104 -284.052518)
		)
		(stroke
			(width 0)
			(type solid)
		)
		(fill yes)
		(layer "In2.Cu")
		(net "M_C_CPU0_SB_DQ<16>")
	)
	(gr_poly
		(pts
			(xy 331.921104 -283.604208) (xy 331.921104 -283.559758) (xy 331.720952 -283.559758) (xy 331.720952 -283.604208)
			(xy 331.821028 -283.704284)
		)
		(stroke
			(width 0)
			(type solid)
		)
		(fill yes)
		(layer "In2.Cu")
		(net "M_C_CPU0_SB_DQ<15>")
	)
	(gr_poly
		(pts
			(xy 331.921104 -282.388056) (xy 331.821028 -282.28798) (xy 331.720952 -282.388056) (xy 331.720952 -282.432506)
			(xy 331.921104 -282.432506)
		)
		(stroke
			(width 0)
			(type solid)
		)
		(fill yes)
		(layer "In2.Cu")
		(net "M_C_CPU0_SB_DQ<12>")
	)
	(gr_poly
		(pts
			(xy 331.921104 -281.98445) (xy 331.921104 -281.936698) (xy 331.720952 -281.936698) (xy 331.720952 -281.98445)
			(xy 331.821028 -282.084272)
		)
		(stroke
			(width 0)
			(type solid)
		)
		(fill yes)
		(layer "In2.Cu")
		(net "M_C_CPU0_SB_DQS_DP<6>")
	)
	(gr_poly
		(pts
			(xy 331.921104 -280.76779) (xy 331.821028 -280.667968) (xy 331.720952 -280.76779) (xy 331.720952 -280.815542)
			(xy 331.921104 -280.815542)
		)
		(stroke
			(width 0)
			(type solid)
		)
		(fill yes)
		(layer "In2.Cu")
		(net "M_C_CPU0_SB_DQS_DP<1>")
	)
	(gr_poly
		(pts
			(xy 331.921104 -280.364184) (xy 331.921104 -280.319734) (xy 331.720952 -280.319734) (xy 331.720952 -280.364184)
			(xy 331.821028 -280.46426)
		)
		(stroke
			(width 0)
			(type solid)
		)
		(fill yes)
		(layer "In2.Cu")
		(net "M_C_CPU0_SB_DQ<11>")
	)
	(gr_poly
		(pts
			(xy 331.921104 -279.148032) (xy 331.821028 -279.047956) (xy 331.720952 -279.148032) (xy 331.720952 -279.192482)
			(xy 331.921104 -279.192482)
		)
		(stroke
			(width 0)
			(type solid)
		)
		(fill yes)
		(layer "In2.Cu")
		(net "M_C_CPU0_SB_DQ<8>")
	)
	(gr_poly
		(pts
			(xy 331.921104 -278.744172) (xy 331.921104 -278.699722) (xy 331.720952 -278.699722) (xy 331.720952 -278.744172)
			(xy 331.821028 -278.844248)
		)
		(stroke
			(width 0)
			(type solid)
		)
		(fill yes)
		(layer "In2.Cu")
		(net "M_C_CPU0_SB_DQ<7>")
	)
	(gr_poly
		(pts
			(xy 331.921104 -277.52802) (xy 331.821028 -277.427944) (xy 331.720952 -277.52802) (xy 331.720952 -277.57247)
			(xy 331.921104 -277.57247)
		)
		(stroke
			(width 0)
			(type solid)
		)
		(fill yes)
		(layer "In2.Cu")
		(net "M_C_CPU0_SB_DQ<4>")
	)
	(gr_poly
		(pts
			(xy 331.921104 -277.124414) (xy 331.921104 -277.076662) (xy 331.720952 -277.076662) (xy 331.720952 -277.124414)
			(xy 331.821028 -277.224236)
		)
		(stroke
			(width 0)
			(type solid)
		)
		(fill yes)
		(layer "In2.Cu")
		(net "M_C_CPU0_SB_DQS_DP<5>")
	)
	(gr_poly
		(pts
			(xy 331.921104 -275.907754) (xy 331.821028 -275.807932) (xy 331.720952 -275.907754) (xy 331.720952 -275.955506)
			(xy 331.921104 -275.955506)
		)
		(stroke
			(width 0)
			(type solid)
		)
		(fill yes)
		(layer "In2.Cu")
		(net "M_C_CPU0_SB_DQS_DP<0>")
	)
	(gr_poly
		(pts
			(xy 331.921104 -275.504148) (xy 331.921104 -275.459698) (xy 331.720952 -275.459698) (xy 331.720952 -275.504148)
			(xy 331.821028 -275.604224)
		)
		(stroke
			(width 0)
			(type solid)
		)
		(fill yes)
		(layer "In2.Cu")
		(net "M_C_CPU0_SB_DQ<3>")
	)
	(gr_poly
		(pts
			(xy 331.921104 -274.287996) (xy 331.821028 -274.18792) (xy 331.720952 -274.287996) (xy 331.720952 -274.332446)
			(xy 331.921104 -274.332446)
		)
		(stroke
			(width 0)
			(type solid)
		)
		(fill yes)
		(layer "In2.Cu")
		(net "M_C_CPU0_SB_DQ<0>")
	)
	(gr_poly
		(pts
			(xy 331.921104 -273.884136) (xy 331.921104 -273.839686) (xy 331.720952 -273.839686) (xy 331.720952 -273.884136)
			(xy 331.821028 -273.984212)
		)
		(stroke
			(width 0)
			(type solid)
		)
		(fill yes)
		(layer "In2.Cu")
		(net "M_C_CPU0_SB_CB<3>")
	)
	(gr_poly
		(pts
			(xy 331.921104 -272.667984) (xy 331.821028 -272.567908) (xy 331.720952 -272.667984) (xy 331.720952 -272.712434)
			(xy 331.921104 -272.712434)
		)
		(stroke
			(width 0)
			(type solid)
		)
		(fill yes)
		(layer "In2.Cu")
		(net "M_C_CPU0_SB_CB<0>")
	)
	(gr_poly
		(pts
			(xy 331.921104 -272.264378) (xy 331.921104 -272.216626) (xy 331.720952 -272.216626) (xy 331.720952 -272.264378)
			(xy 331.821028 -272.3642)
		)
		(stroke
			(width 0)
			(type solid)
		)
		(fill yes)
		(layer "In2.Cu")
		(net "M_C_CPU0_SB_DQS_DP<4>")
	)
	(gr_poly
		(pts
			(xy 331.921104 -271.047718) (xy 331.821028 -270.947896) (xy 331.720952 -271.047718) (xy 331.720952 -271.09547)
			(xy 331.921104 -271.09547)
		)
		(stroke
			(width 0)
			(type solid)
		)
		(fill yes)
		(layer "In2.Cu")
		(net "M_C_CPU0_SB_DQS_DP<9>")
	)
	(gr_poly
		(pts
			(xy 331.921104 -270.644112) (xy 331.921104 -270.599662) (xy 331.720952 -270.599662) (xy 331.720952 -270.644112)
			(xy 331.821028 -270.744188)
		)
		(stroke
			(width 0)
			(type solid)
		)
		(fill yes)
		(layer "In2.Cu")
		(net "M_C_CPU0_SB_CB<7>")
	)
	(gr_poly
		(pts
			(xy 331.921104 -269.42796) (xy 331.821028 -269.327884) (xy 331.720952 -269.42796) (xy 331.720952 -269.47241)
			(xy 331.921104 -269.47241)
		)
		(stroke
			(width 0)
			(type solid)
		)
		(fill yes)
		(layer "In2.Cu")
		(net "M_C_CPU0_SB_CB<4>")
	)
	(gr_poly
		(pts
			(xy 331.921104 -265.784076) (xy 331.921104 -265.739626) (xy 331.720952 -265.739626) (xy 331.720952 -265.784076)
			(xy 331.821028 -265.884152)
		)
		(stroke
			(width 0)
			(type solid)
		)
		(fill yes)
		(layer "In2.Cu")
		(net "M_C_CPU0_SB_CS_N<0>")
	)
	(gr_poly
		(pts
			(xy 331.921104 -264.567924) (xy 331.821028 -264.467848) (xy 331.720952 -264.567924) (xy 331.720952 -264.612374)
			(xy 331.921104 -264.612374)
		)
		(stroke
			(width 0)
			(type solid)
		)
		(fill yes)
		(layer "In2.Cu")
		(net "M_C_CPU0_SB_CA<6>")
	)
	(gr_poly
		(pts
			(xy 331.921104 -264.164064) (xy 331.921104 -264.119614) (xy 331.720952 -264.119614) (xy 331.720952 -264.164064)
			(xy 331.821028 -264.26414)
		)
		(stroke
			(width 0)
			(type solid)
		)
		(fill yes)
		(layer "In2.Cu")
		(net "M_C_CPU0_SB_CA<5>")
	)
	(gr_poly
		(pts
			(xy 331.921104 -262.947912) (xy 331.821028 -262.847836) (xy 331.720952 -262.947912) (xy 331.720952 -262.992362)
			(xy 331.921104 -262.992362)
		)
		(stroke
			(width 0)
			(type solid)
		)
		(fill yes)
		(layer "In2.Cu")
		(net "M_C_CPU0_SB_CA<2>")
	)
	(gr_poly
		(pts
			(xy 331.921104 -262.544052) (xy 331.921104 -262.499602) (xy 331.720952 -262.499602) (xy 331.720952 -262.544052)
			(xy 331.821028 -262.644128)
		)
		(stroke
			(width 0)
			(type solid)
		)
		(fill yes)
		(layer "In2.Cu")
		(net "M_C_CPU0_SB_CA<1>")
	)
	(gr_poly
		(pts
			(xy 331.9272 -267.801598) (xy 331.827378 -267.701522) (xy 331.727302 -267.801598) (xy 331.727302 -267.846048)
			(xy 331.9272 -267.846048)
		)
		(stroke
			(width 0)
			(type solid)
		)
		(fill yes)
		(layer "In2.Cu")
		(net "M_C_CPU0_SB_RSP<0>")
	)
	(gr_poly
		(pts
			(xy 332.010258 -225.392996) (xy 331.910182 -225.219768) (xy 331.871828 -225.24212) (xy 331.834998 -225.378772)
			(xy 331.97165 -225.415348)
		)
		(stroke
			(width 0)
			(type solid)
		)
		(fill yes)
		(layer "In2.Cu")
		(net "M_C_CPU0_SA_DQ<2>")
	)
	(gr_poly
		(pts
			(xy 332.091284 -256.025904) (xy 331.991208 -255.926082) (xy 331.891132 -256.025904) (xy 331.891132 -256.073656)
			(xy 332.091284 -256.073656)
		)
		(stroke
			(width 0)
			(type solid)
		)
		(fill yes)
		(layer "In2.Cu")
		(net "M_C_CPU0_CLK_DP<0>")
	)
	(gr_poly
		(pts
			(xy 332.091284 -255.622298) (xy 332.091284 -255.577848) (xy 331.891132 -255.577848) (xy 331.891132 -255.622298)
			(xy 331.991208 -255.722374)
		)
		(stroke
			(width 0)
			(type solid)
		)
		(fill yes)
		(layer "In2.Cu")
		(net "M_C_CPU0_SA_PAR")
	)
	(gr_poly
		(pts
			(xy 332.091284 -254.406146) (xy 331.991208 -254.30607) (xy 331.891132 -254.406146) (xy 331.891132 -254.450596)
			(xy 332.091284 -254.450596)
		)
		(stroke
			(width 0)
			(type solid)
		)
		(fill yes)
		(layer "In2.Cu")
		(net "M_C_CPU0_SA_CA<4>")
	)
	(gr_poly
		(pts
			(xy 332.091284 -254.002286) (xy 332.091284 -253.957836) (xy 331.891132 -253.957836) (xy 331.891132 -254.002286)
			(xy 331.991208 -254.102362)
		)
		(stroke
			(width 0)
			(type solid)
		)
		(fill yes)
		(layer "In2.Cu")
		(net "M_C_CPU0_SA_CA<3>")
	)
	(gr_poly
		(pts
			(xy 332.091284 -252.786134) (xy 331.991208 -252.686058) (xy 331.891132 -252.786134) (xy 331.891132 -252.830584)
			(xy 332.091284 -252.830584)
		)
		(stroke
			(width 0)
			(type solid)
		)
		(fill yes)
		(layer "In2.Cu")
		(net "M_C_CPU0_SA_CA<0>")
	)
	(gr_poly
		(pts
			(xy 332.091284 -252.382274) (xy 332.091284 -252.337824) (xy 331.891132 -252.337824) (xy 331.891132 -252.382274)
			(xy 331.991208 -252.48235)
		)
		(stroke
			(width 0)
			(type solid)
		)
		(fill yes)
		(layer "In2.Cu")
		(net "M_C_CPU0_SA_CS_N<1>")
	)
	(gr_poly
		(pts
			(xy 332.091284 -250.762262) (xy 332.091284 -250.717812) (xy 331.891132 -250.717812) (xy 331.891132 -250.762262)
			(xy 331.991208 -250.862338)
		)
		(stroke
			(width 0)
			(type solid)
		)
		(fill yes)
		(layer "In2.Cu")
		(net "M_C_CPU0_RESET_N")
	)
	(gr_poly
		(pts
			(xy 332.091284 -249.14225) (xy 332.091284 -249.0978) (xy 331.891132 -249.0978) (xy 331.891132 -249.14225)
			(xy 331.991208 -249.242326)
		)
		(stroke
			(width 0)
			(type solid)
		)
		(fill yes)
		(layer "In2.Cu")
		(net "M_C_CPU0_SA_CB<7>")
	)
	(gr_poly
		(pts
			(xy 332.091284 -247.926098) (xy 331.991208 -247.826022) (xy 331.891132 -247.926098) (xy 331.891132 -247.970548)
			(xy 332.091284 -247.970548)
		)
		(stroke
			(width 0)
			(type solid)
		)
		(fill yes)
		(layer "In2.Cu")
		(net "M_C_CPU0_SA_CB<4>")
	)
	(gr_poly
		(pts
			(xy 332.091284 -247.522492) (xy 332.091284 -247.47474) (xy 331.891132 -247.47474) (xy 331.891132 -247.522492)
			(xy 331.991208 -247.622314)
		)
		(stroke
			(width 0)
			(type solid)
		)
		(fill yes)
		(layer "In2.Cu")
		(net "M_C_CPU0_SA_DQS_DP<9>")
	)
	(gr_poly
		(pts
			(xy 332.091284 -246.305832) (xy 331.991208 -246.20601) (xy 331.891132 -246.305832) (xy 331.891132 -246.353584)
			(xy 332.091284 -246.353584)
		)
		(stroke
			(width 0)
			(type solid)
		)
		(fill yes)
		(layer "In2.Cu")
		(net "M_C_CPU0_SA_DQS_DP<4>")
	)
	(gr_poly
		(pts
			(xy 332.091284 -245.902226) (xy 332.091284 -245.857776) (xy 331.891132 -245.857776) (xy 331.891132 -245.902226)
			(xy 331.991208 -246.002302)
		)
		(stroke
			(width 0)
			(type solid)
		)
		(fill yes)
		(layer "In2.Cu")
		(net "M_C_CPU0_SA_CB<3>")
	)
	(gr_poly
		(pts
			(xy 332.091284 -244.686074) (xy 331.991208 -244.585998) (xy 331.891132 -244.686074) (xy 331.891132 -244.730524)
			(xy 332.091284 -244.730524)
		)
		(stroke
			(width 0)
			(type solid)
		)
		(fill yes)
		(layer "In2.Cu")
		(net "M_C_CPU0_SA_CB<0>")
	)
	(gr_poly
		(pts
			(xy 332.091284 -244.282214) (xy 332.091284 -244.237764) (xy 331.891132 -244.237764) (xy 331.891132 -244.282214)
			(xy 331.991208 -244.38229)
		)
		(stroke
			(width 0)
			(type solid)
		)
		(fill yes)
		(layer "In2.Cu")
		(net "M_C_CPU0_SA_DQ<31>")
	)
	(gr_poly
		(pts
			(xy 332.091284 -243.066062) (xy 331.991208 -242.965986) (xy 331.891132 -243.066062) (xy 331.891132 -243.110512)
			(xy 332.091284 -243.110512)
		)
		(stroke
			(width 0)
			(type solid)
		)
		(fill yes)
		(layer "In2.Cu")
		(net "M_C_CPU0_SA_DQ<28>")
	)
	(gr_poly
		(pts
			(xy 332.091284 -242.662456) (xy 332.091284 -242.614704) (xy 331.891132 -242.614704) (xy 331.891132 -242.662456)
			(xy 331.991208 -242.762278)
		)
		(stroke
			(width 0)
			(type solid)
		)
		(fill yes)
		(layer "In2.Cu")
		(net "M_C_CPU0_SA_DQS_DP<8>")
	)
	(gr_poly
		(pts
			(xy 332.091284 -241.445796) (xy 331.991208 -241.345974) (xy 331.891132 -241.445796) (xy 331.891132 -241.493548)
			(xy 332.091284 -241.493548)
		)
		(stroke
			(width 0)
			(type solid)
		)
		(fill yes)
		(layer "In2.Cu")
		(net "M_C_CPU0_SA_DQS_DP<3>")
	)
	(gr_poly
		(pts
			(xy 332.091284 -241.04219) (xy 332.091284 -240.99774) (xy 331.891132 -240.99774) (xy 331.891132 -241.04219)
			(xy 331.991208 -241.142266)
		)
		(stroke
			(width 0)
			(type solid)
		)
		(fill yes)
		(layer "In2.Cu")
		(net "M_C_CPU0_SA_DQ<27>")
	)
	(gr_poly
		(pts
			(xy 332.091284 -239.826038) (xy 331.991208 -239.725962) (xy 331.891132 -239.826038) (xy 331.891132 -239.870488)
			(xy 332.091284 -239.870488)
		)
		(stroke
			(width 0)
			(type solid)
		)
		(fill yes)
		(layer "In2.Cu")
		(net "M_C_CPU0_SA_DQ<24>")
	)
	(gr_poly
		(pts
			(xy 332.091284 -239.422178) (xy 332.091284 -239.377728) (xy 331.891132 -239.377728) (xy 331.891132 -239.422178)
			(xy 331.991208 -239.522254)
		)
		(stroke
			(width 0)
			(type solid)
		)
		(fill yes)
		(layer "In2.Cu")
		(net "M_C_CPU0_SA_DQ<23>")
	)
	(gr_poly
		(pts
			(xy 332.091284 -238.206026) (xy 331.991208 -238.10595) (xy 331.891132 -238.206026) (xy 331.891132 -238.250476)
			(xy 332.091284 -238.250476)
		)
		(stroke
			(width 0)
			(type solid)
		)
		(fill yes)
		(layer "In2.Cu")
		(net "M_C_CPU0_SA_DQ<20>")
	)
	(gr_poly
		(pts
			(xy 332.091284 -237.80242) (xy 332.091284 -237.754668) (xy 331.891132 -237.754668) (xy 331.891132 -237.80242)
			(xy 331.991208 -237.902242)
		)
		(stroke
			(width 0)
			(type solid)
		)
		(fill yes)
		(layer "In2.Cu")
		(net "M_C_CPU0_SA_DQS_DP<7>")
	)
	(gr_poly
		(pts
			(xy 332.091284 -236.58576) (xy 331.991208 -236.485938) (xy 331.891132 -236.58576) (xy 331.891132 -236.633512)
			(xy 332.091284 -236.633512)
		)
		(stroke
			(width 0)
			(type solid)
		)
		(fill yes)
		(layer "In2.Cu")
		(net "M_C_CPU0_SA_DQS_DP<2>")
	)
	(gr_poly
		(pts
			(xy 332.091284 -236.182154) (xy 332.091284 -236.137704) (xy 331.891132 -236.137704) (xy 331.891132 -236.182154)
			(xy 331.991208 -236.28223)
		)
		(stroke
			(width 0)
			(type solid)
		)
		(fill yes)
		(layer "In2.Cu")
		(net "M_C_CPU0_SA_DQ<19>")
	)
	(gr_poly
		(pts
			(xy 332.091284 -234.966002) (xy 331.991208 -234.865926) (xy 331.891132 -234.966002) (xy 331.891132 -235.010452)
			(xy 332.091284 -235.010452)
		)
		(stroke
			(width 0)
			(type solid)
		)
		(fill yes)
		(layer "In2.Cu")
		(net "M_C_CPU0_SA_DQ<16>")
	)
	(gr_poly
		(pts
			(xy 332.091284 -234.562142) (xy 332.091284 -234.517692) (xy 331.891132 -234.517692) (xy 331.891132 -234.562142)
			(xy 331.991208 -234.662218)
		)
		(stroke
			(width 0)
			(type solid)
		)
		(fill yes)
		(layer "In2.Cu")
		(net "M_C_CPU0_SA_DQ<15>")
	)
	(gr_poly
		(pts
			(xy 332.091284 -233.34599) (xy 331.991208 -233.245914) (xy 331.891132 -233.34599) (xy 331.891132 -233.39044)
			(xy 332.091284 -233.39044)
		)
		(stroke
			(width 0)
			(type solid)
		)
		(fill yes)
		(layer "In2.Cu")
		(net "M_C_CPU0_SA_DQ<12>")
	)
	(gr_poly
		(pts
			(xy 332.091284 -232.942384) (xy 332.091284 -232.894632) (xy 331.891132 -232.894632) (xy 331.891132 -232.942384)
			(xy 331.991208 -233.042206)
		)
		(stroke
			(width 0)
			(type solid)
		)
		(fill yes)
		(layer "In2.Cu")
		(net "M_C_CPU0_SA_DQS_DP<6>")
	)
	(gr_poly
		(pts
			(xy 332.091284 -231.725724) (xy 331.991208 -231.625902) (xy 331.891132 -231.725724) (xy 331.891132 -231.773476)
			(xy 332.091284 -231.773476)
		)
		(stroke
			(width 0)
			(type solid)
		)
		(fill yes)
		(layer "In2.Cu")
		(net "M_C_CPU0_SA_DQS_DP<1>")
	)
	(gr_poly
		(pts
			(xy 332.091284 -231.322372) (xy 332.091284 -231.277922) (xy 331.891132 -231.277922) (xy 331.891132 -231.322372)
			(xy 331.991208 -231.422448)
		)
		(stroke
			(width 0)
			(type solid)
		)
		(fill yes)
		(layer "In2.Cu")
		(net "M_C_CPU0_SA_DQ<11>")
	)
	(gr_poly
		(pts
			(xy 332.091284 -230.105966) (xy 331.991208 -230.006144) (xy 331.891132 -230.105966) (xy 331.891132 -230.150416)
			(xy 332.091284 -230.150416)
		)
		(stroke
			(width 0)
			(type solid)
		)
		(fill yes)
		(layer "In2.Cu")
		(net "M_C_CPU0_SA_DQ<8>")
	)
	(gr_poly
		(pts
			(xy 332.091284 -229.70236) (xy 332.091284 -229.65791) (xy 331.891132 -229.65791) (xy 331.891132 -229.70236)
			(xy 331.991208 -229.802436)
		)
		(stroke
			(width 0)
			(type solid)
		)
		(fill yes)
		(layer "In2.Cu")
		(net "M_C_CPU0_SA_DQ<7>")
	)
	(gr_poly
		(pts
			(xy 332.091284 -228.486208) (xy 331.991208 -228.386132) (xy 331.891132 -228.486208) (xy 331.891132 -228.530658)
			(xy 332.091284 -228.530658)
		)
		(stroke
			(width 0)
			(type solid)
		)
		(fill yes)
		(layer "In2.Cu")
		(net "M_C_CPU0_SA_DQ<4>")
	)
	(gr_poly
		(pts
			(xy 332.091284 -228.082602) (xy 332.091284 -228.03485) (xy 331.891132 -228.03485) (xy 331.891132 -228.082602)
			(xy 331.991208 -228.182424)
		)
		(stroke
			(width 0)
			(type solid)
		)
		(fill yes)
		(layer "In2.Cu")
		(net "M_C_CPU0_SA_DQS_DP<5>")
	)
	(gr_poly
		(pts
			(xy 332.091284 -226.865942) (xy 331.991208 -226.76612) (xy 331.891132 -226.865942) (xy 331.891132 -226.913694)
			(xy 332.091284 -226.913694)
		)
		(stroke
			(width 0)
			(type solid)
		)
		(fill yes)
		(layer "In2.Cu")
		(net "M_C_CPU0_SA_DQS_DP<0>")
	)
	(gr_poly
		(pts
			(xy 332.091284 -226.462336) (xy 332.091284 -226.417886) (xy 331.891132 -226.417886) (xy 331.891132 -226.462336)
			(xy 331.991208 -226.562412)
		)
		(stroke
			(width 0)
			(type solid)
		)
		(fill yes)
		(layer "In2.Cu")
		(net "M_C_CPU0_SA_DQ<3>")
	)
	(gr_poly
		(pts
			(xy 332.110334 -224.846388) (xy 332.14691 -224.709736) (xy 332.010512 -224.67316) (xy 331.971904 -224.695512)
			(xy 332.07198 -224.86874)
		)
		(stroke
			(width 0)
			(type solid)
		)
		(fill yes)
		(layer "In2.Cu")
		(net "M_C_CPU0_SA_DQ<0>")
	)
	(gr_poly
		(pts
			(xy 332.383892 -291.297614) (xy 332.283816 -291.197792) (xy 332.18374 -291.297614) (xy 332.18374 -291.345366)
			(xy 332.383892 -291.345366)
		)
		(stroke
			(width 0)
			(type solid)
		)
		(fill yes)
		(layer "In2.Cu")
		(net "M_C_CPU0_SB_DQS_DN<8>")
	)
	(gr_poly
		(pts
			(xy 332.384908 -266.991592) (xy 332.284832 -266.891516) (xy 332.18501 -266.991592) (xy 332.18501 -267.036042)
			(xy 332.384908 -267.036042)
		)
		(stroke
			(width 0)
			(type solid)
		)
		(fill yes)
		(layer "In2.Cu")
		(net "M_C_CPU0_SA_RSP<0>")
	)
	(gr_poly
		(pts
			(xy 332.391258 -292.91788) (xy 332.291182 -292.817804) (xy 332.191106 -292.91788) (xy 332.191106 -292.96233)
			(xy 332.391258 -292.96233)
		)
		(stroke
			(width 0)
			(type solid)
		)
		(fill yes)
		(layer "In2.Cu")
		(net "M_C_CPU0_SB_DQ<29>")
	)
	(gr_poly
		(pts
			(xy 332.391258 -292.51402) (xy 332.391258 -292.46957) (xy 332.191106 -292.46957) (xy 332.191106 -292.51402)
			(xy 332.291182 -292.614096)
		)
		(stroke
			(width 0)
			(type solid)
		)
		(fill yes)
		(layer "In2.Cu")
		(net "M_C_CPU0_SB_DQ<30>")
	)
	(gr_poly
		(pts
			(xy 332.391258 -290.894262) (xy 332.391258 -290.84651) (xy 332.191106 -290.84651) (xy 332.191106 -290.894262)
			(xy 332.291182 -290.994084)
		)
		(stroke
			(width 0)
			(type solid)
		)
		(fill yes)
		(layer "In2.Cu")
		(net "M_C_CPU0_SB_DQS_DN<3>")
	)
	(gr_poly
		(pts
			(xy 332.391258 -289.677856) (xy 332.291182 -289.57778) (xy 332.191106 -289.677856) (xy 332.191106 -289.722306)
			(xy 332.391258 -289.722306)
		)
		(stroke
			(width 0)
			(type solid)
		)
		(fill yes)
		(layer "In2.Cu")
		(net "M_C_CPU0_SB_DQ<25>")
	)
	(gr_poly
		(pts
			(xy 332.391258 -289.273996) (xy 332.391258 -289.229546) (xy 332.191106 -289.229546) (xy 332.191106 -289.273996)
			(xy 332.291182 -289.374072)
		)
		(stroke
			(width 0)
			(type solid)
		)
		(fill yes)
		(layer "In2.Cu")
		(net "M_C_CPU0_SB_DQ<26>")
	)
	(gr_poly
		(pts
			(xy 332.391258 -288.057844) (xy 332.291182 -287.957768) (xy 332.191106 -288.057844) (xy 332.191106 -288.102294)
			(xy 332.391258 -288.102294)
		)
		(stroke
			(width 0)
			(type solid)
		)
		(fill yes)
		(layer "In2.Cu")
		(net "M_C_CPU0_SB_DQ<21>")
	)
	(gr_poly
		(pts
			(xy 332.391258 -287.654238) (xy 332.391258 -287.609788) (xy 332.191106 -287.609788) (xy 332.191106 -287.654238)
			(xy 332.291182 -287.75406)
		)
		(stroke
			(width 0)
			(type solid)
		)
		(fill yes)
		(layer "In2.Cu")
		(net "M_C_CPU0_SB_DQ<22>")
	)
	(gr_poly
		(pts
			(xy 332.391258 -286.437832) (xy 332.291182 -286.337756) (xy 332.191106 -286.437832) (xy 332.191106 -286.485584)
			(xy 332.391258 -286.485584)
		)
		(stroke
			(width 0)
			(type solid)
		)
		(fill yes)
		(layer "In2.Cu")
		(net "M_C_CPU0_SB_DQS_DN<7>")
	)
	(gr_poly
		(pts
			(xy 332.391258 -286.03448) (xy 332.391258 -285.986728) (xy 332.191106 -285.986728) (xy 332.191106 -286.03448)
			(xy 332.291182 -286.134302)
		)
		(stroke
			(width 0)
			(type solid)
		)
		(fill yes)
		(layer "In2.Cu")
		(net "M_C_CPU0_SB_DQS_DN<2>")
	)
	(gr_poly
		(pts
			(xy 332.391258 -284.818074) (xy 332.291182 -284.717998) (xy 332.191106 -284.818074) (xy 332.191106 -284.862524)
			(xy 332.391258 -284.862524)
		)
		(stroke
			(width 0)
			(type solid)
		)
		(fill yes)
		(layer "In2.Cu")
		(net "M_C_CPU0_SB_DQ<17>")
	)
	(gr_poly
		(pts
			(xy 332.391258 -284.414214) (xy 332.391258 -284.369764) (xy 332.191106 -284.369764) (xy 332.191106 -284.414214)
			(xy 332.291182 -284.51429)
		)
		(stroke
			(width 0)
			(type solid)
		)
		(fill yes)
		(layer "In2.Cu")
		(net "M_C_CPU0_SB_DQ<18>")
	)
	(gr_poly
		(pts
			(xy 332.391258 -283.198062) (xy 332.291182 -283.097986) (xy 332.191106 -283.198062) (xy 332.191106 -283.242512)
			(xy 332.391258 -283.242512)
		)
		(stroke
			(width 0)
			(type solid)
		)
		(fill yes)
		(layer "In2.Cu")
		(net "M_C_CPU0_SB_DQ<13>")
	)
	(gr_poly
		(pts
			(xy 332.391258 -282.794202) (xy 332.391258 -282.749752) (xy 332.191106 -282.749752) (xy 332.191106 -282.794202)
			(xy 332.291182 -282.894278)
		)
		(stroke
			(width 0)
			(type solid)
		)
		(fill yes)
		(layer "In2.Cu")
		(net "M_C_CPU0_SB_DQ<14>")
	)
	(gr_poly
		(pts
			(xy 332.391258 -281.577796) (xy 332.291182 -281.477974) (xy 332.191106 -281.577796) (xy 332.191106 -281.625548)
			(xy 332.391258 -281.625548)
		)
		(stroke
			(width 0)
			(type solid)
		)
		(fill yes)
		(layer "In2.Cu")
		(net "M_C_CPU0_SB_DQS_DN<6>")
	)
	(gr_poly
		(pts
			(xy 332.391258 -281.174444) (xy 332.391258 -281.126692) (xy 332.191106 -281.126692) (xy 332.191106 -281.174444)
			(xy 332.291182 -281.274266)
		)
		(stroke
			(width 0)
			(type solid)
		)
		(fill yes)
		(layer "In2.Cu")
		(net "M_C_CPU0_SB_DQS_DN<1>")
	)
	(gr_poly
		(pts
			(xy 332.391258 -279.958038) (xy 332.291182 -279.857962) (xy 332.191106 -279.958038) (xy 332.191106 -280.002488)
			(xy 332.391258 -280.002488)
		)
		(stroke
			(width 0)
			(type solid)
		)
		(fill yes)
		(layer "In2.Cu")
		(net "M_C_CPU0_SB_DQ<9>")
	)
	(gr_poly
		(pts
			(xy 332.391258 -279.554178) (xy 332.391258 -279.509728) (xy 332.191106 -279.509728) (xy 332.191106 -279.554178)
			(xy 332.291182 -279.654254)
		)
		(stroke
			(width 0)
			(type solid)
		)
		(fill yes)
		(layer "In2.Cu")
		(net "M_C_CPU0_SB_DQ<10>")
	)
	(gr_poly
		(pts
			(xy 332.391258 -278.338026) (xy 332.291182 -278.23795) (xy 332.191106 -278.338026) (xy 332.191106 -278.382476)
			(xy 332.391258 -278.382476)
		)
		(stroke
			(width 0)
			(type solid)
		)
		(fill yes)
		(layer "In2.Cu")
		(net "M_C_CPU0_SB_DQ<5>")
	)
	(gr_poly
		(pts
			(xy 332.391258 -277.934166) (xy 332.391258 -277.889716) (xy 332.191106 -277.889716) (xy 332.191106 -277.934166)
			(xy 332.291182 -278.034242)
		)
		(stroke
			(width 0)
			(type solid)
		)
		(fill yes)
		(layer "In2.Cu")
		(net "M_C_CPU0_SB_DQ<6>")
	)
	(gr_poly
		(pts
			(xy 332.391258 -276.71776) (xy 332.291182 -276.617938) (xy 332.191106 -276.71776) (xy 332.191106 -276.765512)
			(xy 332.391258 -276.765512)
		)
		(stroke
			(width 0)
			(type solid)
		)
		(fill yes)
		(layer "In2.Cu")
		(net "M_C_CPU0_SB_DQS_DN<5>")
	)
	(gr_poly
		(pts
			(xy 332.391258 -276.314408) (xy 332.391258 -276.266656) (xy 332.191106 -276.266656) (xy 332.191106 -276.314408)
			(xy 332.291182 -276.41423)
		)
		(stroke
			(width 0)
			(type solid)
		)
		(fill yes)
		(layer "In2.Cu")
		(net "M_C_CPU0_SB_DQS_DN<0>")
	)
	(gr_poly
		(pts
			(xy 332.391258 -275.098002) (xy 332.291182 -274.997926) (xy 332.191106 -275.098002) (xy 332.191106 -275.142452)
			(xy 332.391258 -275.142452)
		)
		(stroke
			(width 0)
			(type solid)
		)
		(fill yes)
		(layer "In2.Cu")
		(net "M_C_CPU0_SB_DQ<1>")
	)
	(gr_poly
		(pts
			(xy 332.391258 -274.694142) (xy 332.391258 -274.649692) (xy 332.191106 -274.649692) (xy 332.191106 -274.694142)
			(xy 332.291182 -274.794218)
		)
		(stroke
			(width 0)
			(type solid)
		)
		(fill yes)
		(layer "In2.Cu")
		(net "M_C_CPU0_SB_DQ<2>")
	)
	(gr_poly
		(pts
			(xy 332.391258 -273.47799) (xy 332.291182 -273.377914) (xy 332.191106 -273.47799) (xy 332.191106 -273.52244)
			(xy 332.391258 -273.52244)
		)
		(stroke
			(width 0)
			(type solid)
		)
		(fill yes)
		(layer "In2.Cu")
		(net "M_C_CPU0_SB_CB<1>")
	)
	(gr_poly
		(pts
			(xy 332.391258 -273.07413) (xy 332.391258 -273.02968) (xy 332.191106 -273.02968) (xy 332.191106 -273.07413)
			(xy 332.291182 -273.174206)
		)
		(stroke
			(width 0)
			(type solid)
		)
		(fill yes)
		(layer "In2.Cu")
		(net "M_C_CPU0_SB_CB<2>")
	)
	(gr_poly
		(pts
			(xy 332.391258 -271.857724) (xy 332.291182 -271.757902) (xy 332.191106 -271.857724) (xy 332.191106 -271.905476)
			(xy 332.391258 -271.905476)
		)
		(stroke
			(width 0)
			(type solid)
		)
		(fill yes)
		(layer "In2.Cu")
		(net "M_C_CPU0_SB_DQS_DN<4>")
	)
	(gr_poly
		(pts
			(xy 332.391258 -271.454372) (xy 332.391258 -271.40662) (xy 332.191106 -271.40662) (xy 332.191106 -271.454372)
			(xy 332.291182 -271.554194)
		)
		(stroke
			(width 0)
			(type solid)
		)
		(fill yes)
		(layer "In2.Cu")
		(net "M_C_CPU0_SB_DQS_DN<9>")
	)
	(gr_poly
		(pts
			(xy 332.391258 -270.237966) (xy 332.291182 -270.13789) (xy 332.191106 -270.237966) (xy 332.191106 -270.282416)
			(xy 332.391258 -270.282416)
		)
		(stroke
			(width 0)
			(type solid)
		)
		(fill yes)
		(layer "In2.Cu")
		(net "M_C_CPU0_SB_CB<5>")
	)
	(gr_poly
		(pts
			(xy 332.391258 -269.834106) (xy 332.391258 -269.789656) (xy 332.191106 -269.789656) (xy 332.191106 -269.834106)
			(xy 332.291182 -269.934182)
		)
		(stroke
			(width 0)
			(type solid)
		)
		(fill yes)
		(layer "In2.Cu")
		(net "M_C_CPU0_SB_CB<6>")
	)
	(gr_poly
		(pts
			(xy 332.391258 -266.594082) (xy 332.391258 -266.549632) (xy 332.191106 -266.549632) (xy 332.191106 -266.594082)
			(xy 332.291182 -266.694158)
		)
		(stroke
			(width 0)
			(type solid)
		)
		(fill yes)
		(layer "In2.Cu")
		(net "M_C_CPU0_SB_CS_N<1>")
	)
	(gr_poly
		(pts
			(xy 332.391258 -264.97407) (xy 332.391258 -264.92962) (xy 332.191106 -264.92962) (xy 332.191106 -264.97407)
			(xy 332.291182 -265.074146)
		)
		(stroke
			(width 0)
			(type solid)
		)
		(fill yes)
		(layer "In2.Cu")
		(net "M_C_CPU0_SB_PAR")
	)
	(gr_poly
		(pts
			(xy 332.391258 -263.757918) (xy 332.291182 -263.657842) (xy 332.191106 -263.757918) (xy 332.191106 -263.802368)
			(xy 332.391258 -263.802368)
		)
		(stroke
			(width 0)
			(type solid)
		)
		(fill yes)
		(layer "In2.Cu")
		(net "M_C_CPU0_SB_CA<4>")
	)
	(gr_poly
		(pts
			(xy 332.391258 -263.354058) (xy 332.391258 -263.309608) (xy 332.191106 -263.309608) (xy 332.191106 -263.354058)
			(xy 332.291182 -263.454134)
		)
		(stroke
			(width 0)
			(type solid)
		)
		(fill yes)
		(layer "In2.Cu")
		(net "M_C_CPU0_SB_CA<3>")
	)
	(gr_poly
		(pts
			(xy 332.391258 -262.137906) (xy 332.291182 -262.03783) (xy 332.191106 -262.137906) (xy 332.191106 -262.182356)
			(xy 332.391258 -262.182356)
		)
		(stroke
			(width 0)
			(type solid)
		)
		(fill yes)
		(layer "In2.Cu")
		(net "M_C_CPU0_SB_CA<0>")
	)
	(gr_poly
		(pts
			(xy 332.56093 -246.712232) (xy 332.56093 -246.664734) (xy 332.361032 -246.664734) (xy 332.361032 -246.712232)
			(xy 332.460854 -246.812308)
		)
		(stroke
			(width 0)
			(type solid)
		)
		(fill yes)
		(layer "In2.Cu")
		(net "M_C_CPU0_SA_DQS_DN<4>")
	)
	(gr_poly
		(pts
			(xy 332.561184 -256.432558) (xy 332.561184 -256.384806) (xy 332.361032 -256.384806) (xy 332.361032 -256.432558)
			(xy 332.461108 -256.53238)
		)
		(stroke
			(width 0)
			(type solid)
		)
		(fill yes)
		(layer "In2.Cu")
		(net "M_C_CPU0_CLK_DN<0>")
	)
	(gr_poly
		(pts
			(xy 332.561184 -255.216152) (xy 332.461108 -255.116076) (xy 332.361032 -255.216152) (xy 332.361032 -255.260602)
			(xy 332.561184 -255.260602)
		)
		(stroke
			(width 0)
			(type solid)
		)
		(fill yes)
		(layer "In2.Cu")
		(net "M_C_CPU0_SA_CA<6>")
	)
	(gr_poly
		(pts
			(xy 332.561184 -254.812292) (xy 332.561184 -254.767842) (xy 332.361032 -254.767842) (xy 332.361032 -254.812292)
			(xy 332.461108 -254.912368)
		)
		(stroke
			(width 0)
			(type solid)
		)
		(fill yes)
		(layer "In2.Cu")
		(net "M_C_CPU0_SA_CA<5>")
	)
	(gr_poly
		(pts
			(xy 332.561184 -253.59614) (xy 332.461108 -253.496064) (xy 332.361032 -253.59614) (xy 332.361032 -253.64059)
			(xy 332.561184 -253.64059)
		)
		(stroke
			(width 0)
			(type solid)
		)
		(fill yes)
		(layer "In2.Cu")
		(net "M_C_CPU0_SA_CA<2>")
	)
	(gr_poly
		(pts
			(xy 332.561184 -253.19228) (xy 332.561184 -253.14783) (xy 332.361032 -253.14783) (xy 332.361032 -253.19228)
			(xy 332.461108 -253.292356)
		)
		(stroke
			(width 0)
			(type solid)
		)
		(fill yes)
		(layer "In2.Cu")
		(net "M_C_CPU0_SA_CA<1>")
	)
	(gr_poly
		(pts
			(xy 332.561184 -251.572268) (xy 332.561184 -251.527818) (xy 332.361032 -251.527818) (xy 332.361032 -251.572268)
			(xy 332.461108 -251.672344)
		)
		(stroke
			(width 0)
			(type solid)
		)
		(fill yes)
		(layer "In2.Cu")
		(net "M_C_CPU0_SA_CS_N<0>")
	)
	(gr_poly
		(pts
			(xy 332.561184 -250.356116) (xy 332.461108 -250.25604) (xy 332.361032 -250.356116) (xy 332.361032 -250.400566)
			(xy 332.561184 -250.400566)
		)
		(stroke
			(width 0)
			(type solid)
		)
		(fill yes)
		(layer "In2.Cu")
		(net "M_C_CPU0_ALERT_R_N")
	)
	(gr_poly
		(pts
			(xy 332.561184 -248.736104) (xy 332.461108 -248.636028) (xy 332.361032 -248.736104) (xy 332.361032 -248.780554)
			(xy 332.561184 -248.780554)
		)
		(stroke
			(width 0)
			(type solid)
		)
		(fill yes)
		(layer "In2.Cu")
		(net "M_C_CPU0_SA_CB<5>")
	)
	(gr_poly
		(pts
			(xy 332.561184 -248.332244) (xy 332.561184 -248.287794) (xy 332.361032 -248.287794) (xy 332.361032 -248.332244)
			(xy 332.461108 -248.43232)
		)
		(stroke
			(width 0)
			(type solid)
		)
		(fill yes)
		(layer "In2.Cu")
		(net "M_C_CPU0_SA_CB<6>")
	)
	(gr_poly
		(pts
			(xy 332.561184 -247.115838) (xy 332.461108 -247.016016) (xy 332.361032 -247.115838) (xy 332.361032 -247.16359)
			(xy 332.561184 -247.16359)
		)
		(stroke
			(width 0)
			(type solid)
		)
		(fill yes)
		(layer "In2.Cu")
		(net "M_C_CPU0_SA_DQS_DN<9>")
	)
	(gr_poly
		(pts
			(xy 332.561184 -245.49608) (xy 332.461108 -245.396004) (xy 332.361032 -245.49608) (xy 332.361032 -245.54053)
			(xy 332.561184 -245.54053)
		)
		(stroke
			(width 0)
			(type solid)
		)
		(fill yes)
		(layer "In2.Cu")
		(net "M_C_CPU0_SA_CB<1>")
	)
	(gr_poly
		(pts
			(xy 332.561184 -245.09222) (xy 332.561184 -245.04777) (xy 332.361032 -245.04777) (xy 332.361032 -245.09222)
			(xy 332.461108 -245.192296)
		)
		(stroke
			(width 0)
			(type solid)
		)
		(fill yes)
		(layer "In2.Cu")
		(net "M_C_CPU0_SA_CB<2>")
	)
	(gr_poly
		(pts
			(xy 332.561184 -243.876068) (xy 332.461108 -243.775992) (xy 332.361032 -243.876068) (xy 332.361032 -243.920518)
			(xy 332.561184 -243.920518)
		)
		(stroke
			(width 0)
			(type solid)
		)
		(fill yes)
		(layer "In2.Cu")
		(net "M_C_CPU0_SA_DQ<29>")
	)
	(gr_poly
		(pts
			(xy 332.561184 -243.472208) (xy 332.561184 -243.427758) (xy 332.361032 -243.427758) (xy 332.361032 -243.472208)
			(xy 332.461108 -243.572284)
		)
		(stroke
			(width 0)
			(type solid)
		)
		(fill yes)
		(layer "In2.Cu")
		(net "M_C_CPU0_SA_DQ<30>")
	)
	(gr_poly
		(pts
			(xy 332.561184 -242.255802) (xy 332.461108 -242.15598) (xy 332.361032 -242.255802) (xy 332.361032 -242.303554)
			(xy 332.561184 -242.303554)
		)
		(stroke
			(width 0)
			(type solid)
		)
		(fill yes)
		(layer "In2.Cu")
		(net "M_C_CPU0_SA_DQS_DN<8>")
	)
	(gr_poly
		(pts
			(xy 332.561184 -241.85245) (xy 332.561184 -241.804698) (xy 332.361032 -241.804698) (xy 332.361032 -241.85245)
			(xy 332.461108 -241.952272)
		)
		(stroke
			(width 0)
			(type solid)
		)
		(fill yes)
		(layer "In2.Cu")
		(net "M_C_CPU0_SA_DQS_DN<3>")
	)
	(gr_poly
		(pts
			(xy 332.561184 -240.636044) (xy 332.461108 -240.535968) (xy 332.361032 -240.636044) (xy 332.361032 -240.680494)
			(xy 332.561184 -240.680494)
		)
		(stroke
			(width 0)
			(type solid)
		)
		(fill yes)
		(layer "In2.Cu")
		(net "M_C_CPU0_SA_DQ<25>")
	)
	(gr_poly
		(pts
			(xy 332.561184 -240.232184) (xy 332.561184 -240.187734) (xy 332.361032 -240.187734) (xy 332.361032 -240.232184)
			(xy 332.461108 -240.33226)
		)
		(stroke
			(width 0)
			(type solid)
		)
		(fill yes)
		(layer "In2.Cu")
		(net "M_C_CPU0_SA_DQ<26>")
	)
	(gr_poly
		(pts
			(xy 332.561184 -239.016032) (xy 332.461108 -238.915956) (xy 332.361032 -239.016032) (xy 332.361032 -239.060482)
			(xy 332.561184 -239.060482)
		)
		(stroke
			(width 0)
			(type solid)
		)
		(fill yes)
		(layer "In2.Cu")
		(net "M_C_CPU0_SA_DQ<21>")
	)
	(gr_poly
		(pts
			(xy 332.561184 -238.612172) (xy 332.561184 -238.567722) (xy 332.361032 -238.567722) (xy 332.361032 -238.612172)
			(xy 332.461108 -238.712248)
		)
		(stroke
			(width 0)
			(type solid)
		)
		(fill yes)
		(layer "In2.Cu")
		(net "M_C_CPU0_SA_DQ<22>")
	)
	(gr_poly
		(pts
			(xy 332.561184 -237.395766) (xy 332.461108 -237.295944) (xy 332.361032 -237.395766) (xy 332.361032 -237.443518)
			(xy 332.561184 -237.443518)
		)
		(stroke
			(width 0)
			(type solid)
		)
		(fill yes)
		(layer "In2.Cu")
		(net "M_C_CPU0_SA_DQS_DN<7>")
	)
	(gr_poly
		(pts
			(xy 332.561184 -236.992414) (xy 332.561184 -236.944662) (xy 332.361032 -236.944662) (xy 332.361032 -236.992414)
			(xy 332.461108 -237.092236)
		)
		(stroke
			(width 0)
			(type solid)
		)
		(fill yes)
		(layer "In2.Cu")
		(net "M_C_CPU0_SA_DQS_DN<2>")
	)
	(gr_poly
		(pts
			(xy 332.561184 -235.776008) (xy 332.461108 -235.675932) (xy 332.361032 -235.776008) (xy 332.361032 -235.820458)
			(xy 332.561184 -235.820458)
		)
		(stroke
			(width 0)
			(type solid)
		)
		(fill yes)
		(layer "In2.Cu")
		(net "M_C_CPU0_SA_DQ<17>")
	)
	(gr_poly
		(pts
			(xy 332.561184 -235.372148) (xy 332.561184 -235.327698) (xy 332.361032 -235.327698) (xy 332.361032 -235.372148)
			(xy 332.461108 -235.472224)
		)
		(stroke
			(width 0)
			(type solid)
		)
		(fill yes)
		(layer "In2.Cu")
		(net "M_C_CPU0_SA_DQ<18>")
	)
	(gr_poly
		(pts
			(xy 332.561184 -234.155996) (xy 332.461108 -234.05592) (xy 332.361032 -234.155996) (xy 332.361032 -234.200446)
			(xy 332.561184 -234.200446)
		)
		(stroke
			(width 0)
			(type solid)
		)
		(fill yes)
		(layer "In2.Cu")
		(net "M_C_CPU0_SA_DQ<13>")
	)
	(gr_poly
		(pts
			(xy 332.561184 -233.752136) (xy 332.561184 -233.707686) (xy 332.361032 -233.707686) (xy 332.361032 -233.752136)
			(xy 332.461108 -233.852212)
		)
		(stroke
			(width 0)
			(type solid)
		)
		(fill yes)
		(layer "In2.Cu")
		(net "M_C_CPU0_SA_DQ<14>")
	)
	(gr_poly
		(pts
			(xy 332.561184 -232.53573) (xy 332.461108 -232.435908) (xy 332.361032 -232.53573) (xy 332.361032 -232.583482)
			(xy 332.561184 -232.583482)
		)
		(stroke
			(width 0)
			(type solid)
		)
		(fill yes)
		(layer "In2.Cu")
		(net "M_C_CPU0_SA_DQS_DN<6>")
	)
	(gr_poly
		(pts
			(xy 332.561184 -232.132378) (xy 332.561184 -232.084626) (xy 332.361032 -232.084626) (xy 332.361032 -232.132378)
			(xy 332.461108 -232.2322)
		)
		(stroke
			(width 0)
			(type solid)
		)
		(fill yes)
		(layer "In2.Cu")
		(net "M_C_CPU0_SA_DQS_DN<1>")
	)
	(gr_poly
		(pts
			(xy 332.561184 -230.915972) (xy 332.461108 -230.815896) (xy 332.361032 -230.915972) (xy 332.361032 -230.960422)
			(xy 332.561184 -230.960422)
		)
		(stroke
			(width 0)
			(type solid)
		)
		(fill yes)
		(layer "In2.Cu")
		(net "M_C_CPU0_SA_DQ<9>")
	)
	(gr_poly
		(pts
			(xy 332.561184 -230.512366) (xy 332.561184 -230.467916) (xy 332.361032 -230.467916) (xy 332.361032 -230.512366)
			(xy 332.461108 -230.612188)
		)
		(stroke
			(width 0)
			(type solid)
		)
		(fill yes)
		(layer "In2.Cu")
		(net "M_C_CPU0_SA_DQ<10>")
	)
	(gr_poly
		(pts
			(xy 332.561184 -229.29596) (xy 332.461108 -229.195884) (xy 332.361032 -229.29596) (xy 332.361032 -229.34041)
			(xy 332.561184 -229.34041)
		)
		(stroke
			(width 0)
			(type solid)
		)
		(fill yes)
		(layer "In2.Cu")
		(net "M_C_CPU0_SA_DQ<5>")
	)
	(gr_poly
		(pts
			(xy 332.561184 -228.892354) (xy 332.561184 -228.847904) (xy 332.361032 -228.847904) (xy 332.361032 -228.892354)
			(xy 332.461108 -228.99243)
		)
		(stroke
			(width 0)
			(type solid)
		)
		(fill yes)
		(layer "In2.Cu")
		(net "M_C_CPU0_SA_DQ<6>")
	)
	(gr_poly
		(pts
			(xy 332.561184 -227.675948) (xy 332.461108 -227.576126) (xy 332.361032 -227.675948) (xy 332.361032 -227.7237)
			(xy 332.561184 -227.7237)
		)
		(stroke
			(width 0)
			(type solid)
		)
		(fill yes)
		(layer "In2.Cu")
		(net "M_C_CPU0_SA_DQS_DN<5>")
	)
	(gr_poly
		(pts
			(xy 332.561184 -227.272596) (xy 332.561184 -227.224844) (xy 332.361032 -227.224844) (xy 332.361032 -227.272596)
			(xy 332.461108 -227.372418)
		)
		(stroke
			(width 0)
			(type solid)
		)
		(fill yes)
		(layer "In2.Cu")
		(net "M_C_CPU0_SA_DQS_DN<0>")
	)
	(gr_poly
		(pts
			(xy 332.561184 -226.05619) (xy 332.461108 -225.956114) (xy 332.361032 -226.05619) (xy 332.361032 -226.10064)
			(xy 332.561184 -226.10064)
		)
		(stroke
			(width 0)
			(type solid)
		)
		(fill yes)
		(layer "In2.Cu")
		(net "M_C_CPU0_SA_DQ<1>")
	)
	(gr_poly
		(pts
			(xy 332.561184 -225.65233) (xy 332.561184 -225.60788) (xy 332.361032 -225.60788) (xy 332.361032 -225.65233)
			(xy 332.461108 -225.752406)
		)
		(stroke
			(width 0)
			(type solid)
		)
		(fill yes)
		(layer "In2.Cu")
		(net "M_C_CPU0_SA_DQ<2>")
	)
	(gr_poly
		(pts
			(xy 332.861158 -293.324026) (xy 332.861158 -293.279576) (xy 332.661006 -293.279576) (xy 332.661006 -293.324026)
			(xy 332.761082 -293.424102)
		)
		(stroke
			(width 0)
			(type solid)
		)
		(fill yes)
		(layer "In2.Cu")
		(net "M_C_CPU0_SB_DQ<31>")
	)
	(gr_poly
		(pts
			(xy 332.861158 -292.107874) (xy 332.761082 -292.007798) (xy 332.661006 -292.107874) (xy 332.661006 -292.152324)
			(xy 332.861158 -292.152324)
		)
		(stroke
			(width 0)
			(type solid)
		)
		(fill yes)
		(layer "In2.Cu")
		(net "M_C_CPU0_SB_DQ<28>")
	)
	(gr_poly
		(pts
			(xy 332.861158 -291.704268) (xy 332.861158 -291.656516) (xy 332.661006 -291.656516) (xy 332.661006 -291.704268)
			(xy 332.761082 -291.80409)
		)
		(stroke
			(width 0)
			(type solid)
		)
		(fill yes)
		(layer "In2.Cu")
		(net "M_C_CPU0_SB_DQS_DP<8>")
	)
	(gr_poly
		(pts
			(xy 332.861158 -290.487608) (xy 332.761082 -290.387786) (xy 332.661006 -290.487608) (xy 332.661006 -290.53536)
			(xy 332.861158 -290.53536)
		)
		(stroke
			(width 0)
			(type solid)
		)
		(fill yes)
		(layer "In2.Cu")
		(net "M_C_CPU0_SB_DQS_DP<3>")
	)
	(gr_poly
		(pts
			(xy 332.861158 -290.084002) (xy 332.861158 -290.039552) (xy 332.661006 -290.039552) (xy 332.661006 -290.084002)
			(xy 332.761082 -290.184078)
		)
		(stroke
			(width 0)
			(type solid)
		)
		(fill yes)
		(layer "In2.Cu")
		(net "M_C_CPU0_SB_DQ<27>")
	)
	(gr_poly
		(pts
			(xy 332.861158 -288.86785) (xy 332.761082 -288.767774) (xy 332.661006 -288.86785) (xy 332.661006 -288.9123)
			(xy 332.861158 -288.9123)
		)
		(stroke
			(width 0)
			(type solid)
		)
		(fill yes)
		(layer "In2.Cu")
		(net "M_C_CPU0_SB_DQ<24>")
	)
	(gr_poly
		(pts
			(xy 332.861158 -288.464244) (xy 332.861158 -288.419794) (xy 332.661006 -288.419794) (xy 332.661006 -288.464244)
			(xy 332.761082 -288.56432)
		)
		(stroke
			(width 0)
			(type solid)
		)
		(fill yes)
		(layer "In2.Cu")
		(net "M_C_CPU0_SB_DQ<23>")
	)
	(gr_poly
		(pts
			(xy 332.861158 -287.247838) (xy 332.761082 -287.148016) (xy 332.661006 -287.247838) (xy 332.661006 -287.292288)
			(xy 332.861158 -287.292288)
		)
		(stroke
			(width 0)
			(type solid)
		)
		(fill yes)
		(layer "In2.Cu")
		(net "M_C_CPU0_SB_DQ<20>")
	)
	(gr_poly
		(pts
			(xy 332.861158 -286.844232) (xy 332.861158 -286.79648) (xy 332.661006 -286.79648) (xy 332.661006 -286.844232)
			(xy 332.761082 -286.944308)
		)
		(stroke
			(width 0)
			(type solid)
		)
		(fill yes)
		(layer "In2.Cu")
		(net "M_C_CPU0_SB_DQS_DP<7>")
	)
	(gr_poly
		(pts
			(xy 332.861158 -285.627826) (xy 332.761082 -285.528004) (xy 332.661006 -285.627826) (xy 332.661006 -285.675578)
			(xy 332.861158 -285.675578)
		)
		(stroke
			(width 0)
			(type solid)
		)
		(fill yes)
		(layer "In2.Cu")
		(net "M_C_CPU0_SB_DQS_DP<2>")
	)
	(gr_poly
		(pts
			(xy 332.861158 -285.22422) (xy 332.861158 -285.17977) (xy 332.661006 -285.17977) (xy 332.661006 -285.22422)
			(xy 332.761082 -285.324296)
		)
		(stroke
			(width 0)
			(type solid)
		)
		(fill yes)
		(layer "In2.Cu")
		(net "M_C_CPU0_SB_DQ<19>")
	)
	(gr_poly
		(pts
			(xy 332.861158 -284.008068) (xy 332.761082 -283.907992) (xy 332.661006 -284.008068) (xy 332.661006 -284.052518)
			(xy 332.861158 -284.052518)
		)
		(stroke
			(width 0)
			(type solid)
		)
		(fill yes)
		(layer "In2.Cu")
		(net "M_C_CPU0_SB_DQ<16>")
	)
	(gr_poly
		(pts
			(xy 332.861158 -283.604208) (xy 332.861158 -283.559758) (xy 332.661006 -283.559758) (xy 332.661006 -283.604208)
			(xy 332.761082 -283.704284)
		)
		(stroke
			(width 0)
			(type solid)
		)
		(fill yes)
		(layer "In2.Cu")
		(net "M_C_CPU0_SB_DQ<15>")
	)
	(gr_poly
		(pts
			(xy 332.861158 -282.388056) (xy 332.761082 -282.28798) (xy 332.661006 -282.388056) (xy 332.661006 -282.432506)
			(xy 332.861158 -282.432506)
		)
		(stroke
			(width 0)
			(type solid)
		)
		(fill yes)
		(layer "In2.Cu")
		(net "M_C_CPU0_SB_DQ<12>")
	)
	(gr_poly
		(pts
			(xy 332.861158 -281.98445) (xy 332.861158 -281.936698) (xy 332.661006 -281.936698) (xy 332.661006 -281.98445)
			(xy 332.761082 -282.084272)
		)
		(stroke
			(width 0)
			(type solid)
		)
		(fill yes)
		(layer "In2.Cu")
		(net "M_C_CPU0_SB_DQS_DP<6>")
	)
	(gr_poly
		(pts
			(xy 332.861158 -280.76779) (xy 332.761082 -280.667968) (xy 332.661006 -280.76779) (xy 332.661006 -280.815542)
			(xy 332.861158 -280.815542)
		)
		(stroke
			(width 0)
			(type solid)
		)
		(fill yes)
		(layer "In2.Cu")
		(net "M_C_CPU0_SB_DQS_DP<1>")
	)
	(gr_poly
		(pts
			(xy 332.861158 -280.364184) (xy 332.861158 -280.319734) (xy 332.661006 -280.319734) (xy 332.661006 -280.364184)
			(xy 332.761082 -280.46426)
		)
		(stroke
			(width 0)
			(type solid)
		)
		(fill yes)
		(layer "In2.Cu")
		(net "M_C_CPU0_SB_DQ<11>")
	)
	(gr_poly
		(pts
			(xy 332.861158 -279.148032) (xy 332.761082 -279.047956) (xy 332.661006 -279.148032) (xy 332.661006 -279.192482)
			(xy 332.861158 -279.192482)
		)
		(stroke
			(width 0)
			(type solid)
		)
		(fill yes)
		(layer "In2.Cu")
		(net "M_C_CPU0_SB_DQ<8>")
	)
	(gr_poly
		(pts
			(xy 332.861158 -278.744172) (xy 332.861158 -278.699722) (xy 332.661006 -278.699722) (xy 332.661006 -278.744172)
			(xy 332.761082 -278.844248)
		)
		(stroke
			(width 0)
			(type solid)
		)
		(fill yes)
		(layer "In2.Cu")
		(net "M_C_CPU0_SB_DQ<7>")
	)
	(gr_poly
		(pts
			(xy 332.861158 -277.52802) (xy 332.761082 -277.427944) (xy 332.661006 -277.52802) (xy 332.661006 -277.57247)
			(xy 332.861158 -277.57247)
		)
		(stroke
			(width 0)
			(type solid)
		)
		(fill yes)
		(layer "In2.Cu")
		(net "M_C_CPU0_SB_DQ<4>")
	)
	(gr_poly
		(pts
			(xy 332.861158 -277.124414) (xy 332.861158 -277.076662) (xy 332.661006 -277.076662) (xy 332.661006 -277.124414)
			(xy 332.761082 -277.224236)
		)
		(stroke
			(width 0)
			(type solid)
		)
		(fill yes)
		(layer "In2.Cu")
		(net "M_C_CPU0_SB_DQS_DP<5>")
	)
	(gr_poly
		(pts
			(xy 332.861158 -275.907754) (xy 332.761082 -275.807932) (xy 332.661006 -275.907754) (xy 332.661006 -275.955506)
			(xy 332.861158 -275.955506)
		)
		(stroke
			(width 0)
			(type solid)
		)
		(fill yes)
		(layer "In2.Cu")
		(net "M_C_CPU0_SB_DQS_DP<0>")
	)
	(gr_poly
		(pts
			(xy 332.861158 -275.504148) (xy 332.861158 -275.459698) (xy 332.661006 -275.459698) (xy 332.661006 -275.504148)
			(xy 332.761082 -275.604224)
		)
		(stroke
			(width 0)
			(type solid)
		)
		(fill yes)
		(layer "In2.Cu")
		(net "M_C_CPU0_SB_DQ<3>")
	)
	(gr_poly
		(pts
			(xy 332.861158 -274.287996) (xy 332.761082 -274.18792) (xy 332.661006 -274.287996) (xy 332.661006 -274.332446)
			(xy 332.861158 -274.332446)
		)
		(stroke
			(width 0)
			(type solid)
		)
		(fill yes)
		(layer "In2.Cu")
		(net "M_C_CPU0_SB_DQ<0>")
	)
	(gr_poly
		(pts
			(xy 332.861158 -273.884136) (xy 332.861158 -273.839686) (xy 332.661006 -273.839686) (xy 332.661006 -273.884136)
			(xy 332.761082 -273.984212)
		)
		(stroke
			(width 0)
			(type solid)
		)
		(fill yes)
		(layer "In2.Cu")
		(net "M_C_CPU0_SB_CB<3>")
	)
	(gr_poly
		(pts
			(xy 332.861158 -272.667984) (xy 332.761082 -272.567908) (xy 332.661006 -272.667984) (xy 332.661006 -272.712434)
			(xy 332.861158 -272.712434)
		)
		(stroke
			(width 0)
			(type solid)
		)
		(fill yes)
		(layer "In2.Cu")
		(net "M_C_CPU0_SB_CB<0>")
	)
	(gr_poly
		(pts
			(xy 332.861158 -272.264378) (xy 332.861158 -272.216626) (xy 332.661006 -272.216626) (xy 332.661006 -272.264378)
			(xy 332.761082 -272.3642)
		)
		(stroke
			(width 0)
			(type solid)
		)
		(fill yes)
		(layer "In2.Cu")
		(net "M_C_CPU0_SB_DQS_DP<4>")
	)
	(gr_poly
		(pts
			(xy 332.861158 -271.047718) (xy 332.761082 -270.947896) (xy 332.661006 -271.047718) (xy 332.661006 -271.09547)
			(xy 332.861158 -271.09547)
		)
		(stroke
			(width 0)
			(type solid)
		)
		(fill yes)
		(layer "In2.Cu")
		(net "M_C_CPU0_SB_DQS_DP<9>")
	)
	(gr_poly
		(pts
			(xy 332.861158 -270.644112) (xy 332.861158 -270.599662) (xy 332.661006 -270.599662) (xy 332.661006 -270.644112)
			(xy 332.761082 -270.744188)
		)
		(stroke
			(width 0)
			(type solid)
		)
		(fill yes)
		(layer "In2.Cu")
		(net "M_C_CPU0_SB_CB<7>")
	)
	(gr_poly
		(pts
			(xy 332.861158 -269.42796) (xy 332.761082 -269.327884) (xy 332.661006 -269.42796) (xy 332.661006 -269.47241)
			(xy 332.861158 -269.47241)
		)
		(stroke
			(width 0)
			(type solid)
		)
		(fill yes)
		(layer "In2.Cu")
		(net "M_C_CPU0_SB_CB<4>")
	)
	(gr_poly
		(pts
			(xy 332.861158 -267.801598) (xy 332.761082 -267.701522) (xy 332.661006 -267.801598) (xy 332.661006 -267.846048)
			(xy 332.861158 -267.846048)
		)
		(stroke
			(width 0)
			(type solid)
		)
		(fill yes)
		(layer "In2.Cu")
		(net "M_C_CPU0_SB_RSP<0>")
	)
	(gr_poly
		(pts
			(xy 332.861158 -265.784076) (xy 332.861158 -265.739626) (xy 332.661006 -265.739626) (xy 332.661006 -265.784076)
			(xy 332.761082 -265.884152)
		)
		(stroke
			(width 0)
			(type solid)
		)
		(fill yes)
		(layer "In2.Cu")
		(net "M_C_CPU0_SB_CS_N<0>")
	)
	(gr_poly
		(pts
			(xy 332.861158 -264.567924) (xy 332.761082 -264.467848) (xy 332.661006 -264.567924) (xy 332.661006 -264.612374)
			(xy 332.861158 -264.612374)
		)
		(stroke
			(width 0)
			(type solid)
		)
		(fill yes)
		(layer "In2.Cu")
		(net "M_C_CPU0_SB_CA<6>")
	)
	(gr_poly
		(pts
			(xy 332.861158 -264.164064) (xy 332.861158 -264.119614) (xy 332.661006 -264.119614) (xy 332.661006 -264.164064)
			(xy 332.761082 -264.26414)
		)
		(stroke
			(width 0)
			(type solid)
		)
		(fill yes)
		(layer "In2.Cu")
		(net "M_C_CPU0_SB_CA<5>")
	)
	(gr_poly
		(pts
			(xy 332.861158 -262.947912) (xy 332.761082 -262.847836) (xy 332.661006 -262.947912) (xy 332.661006 -262.992362)
			(xy 332.861158 -262.992362)
		)
		(stroke
			(width 0)
			(type solid)
		)
		(fill yes)
		(layer "In2.Cu")
		(net "M_C_CPU0_SB_CA<2>")
	)
	(gr_poly
		(pts
			(xy 332.861158 -262.544052) (xy 332.861158 -262.499602) (xy 332.661006 -262.499602) (xy 332.661006 -262.544052)
			(xy 332.761082 -262.644128)
		)
		(stroke
			(width 0)
			(type solid)
		)
		(fill yes)
		(layer "In2.Cu")
		(net "M_C_CPU0_SB_CA<1>")
	)
	(gr_poly
		(pts
			(xy 333.031084 -256.025904) (xy 332.931008 -255.926082) (xy 332.830932 -256.025904) (xy 332.830932 -256.073656)
			(xy 333.031084 -256.073656)
		)
		(stroke
			(width 0)
			(type solid)
		)
		(fill yes)
		(layer "In2.Cu")
		(net "M_C_CPU0_CLK_DP<0>")
	)
	(gr_poly
		(pts
			(xy 333.031084 -255.622298) (xy 333.031084 -255.577848) (xy 332.830932 -255.577848) (xy 332.830932 -255.622298)
			(xy 332.931008 -255.722374)
		)
		(stroke
			(width 0)
			(type solid)
		)
		(fill yes)
		(layer "In2.Cu")
		(net "M_C_CPU0_SA_PAR")
	)
	(gr_poly
		(pts
			(xy 333.031084 -254.406146) (xy 332.931008 -254.30607) (xy 332.830932 -254.406146) (xy 332.830932 -254.450596)
			(xy 333.031084 -254.450596)
		)
		(stroke
			(width 0)
			(type solid)
		)
		(fill yes)
		(layer "In2.Cu")
		(net "M_C_CPU0_SA_CA<4>")
	)
	(gr_poly
		(pts
			(xy 333.031084 -254.002286) (xy 333.031084 -253.957836) (xy 332.830932 -253.957836) (xy 332.830932 -254.002286)
			(xy 332.931008 -254.102362)
		)
		(stroke
			(width 0)
			(type solid)
		)
		(fill yes)
		(layer "In2.Cu")
		(net "M_C_CPU0_SA_CA<3>")
	)
	(gr_poly
		(pts
			(xy 333.031084 -252.786134) (xy 332.931008 -252.686058) (xy 332.830932 -252.786134) (xy 332.830932 -252.830584)
			(xy 333.031084 -252.830584)
		)
		(stroke
			(width 0)
			(type solid)
		)
		(fill yes)
		(layer "In2.Cu")
		(net "M_C_CPU0_SA_CA<0>")
	)
	(gr_poly
		(pts
			(xy 333.031084 -252.382274) (xy 333.031084 -252.337824) (xy 332.830932 -252.337824) (xy 332.830932 -252.382274)
			(xy 332.931008 -252.48235)
		)
		(stroke
			(width 0)
			(type solid)
		)
		(fill yes)
		(layer "In2.Cu")
		(net "M_C_CPU0_SA_CS_N<1>")
	)
	(gr_poly
		(pts
			(xy 333.031084 -250.762262) (xy 333.031084 -250.717812) (xy 332.830932 -250.717812) (xy 332.830932 -250.762262)
			(xy 332.931008 -250.862338)
		)
		(stroke
			(width 0)
			(type solid)
		)
		(fill yes)
		(layer "In2.Cu")
		(net "M_C_CPU0_RESET_N")
	)
	(gr_poly
		(pts
			(xy 333.031084 -249.14225) (xy 333.031084 -249.0978) (xy 332.830932 -249.0978) (xy 332.830932 -249.14225)
			(xy 332.931008 -249.242326)
		)
		(stroke
			(width 0)
			(type solid)
		)
		(fill yes)
		(layer "In2.Cu")
		(net "M_C_CPU0_SA_CB<7>")
	)
	(gr_poly
		(pts
			(xy 333.031084 -247.926098) (xy 332.931008 -247.826022) (xy 332.830932 -247.926098) (xy 332.830932 -247.970548)
			(xy 333.031084 -247.970548)
		)
		(stroke
			(width 0)
			(type solid)
		)
		(fill yes)
		(layer "In2.Cu")
		(net "M_C_CPU0_SA_CB<4>")
	)
	(gr_poly
		(pts
			(xy 333.031084 -247.522492) (xy 333.031084 -247.47474) (xy 332.830932 -247.47474) (xy 332.830932 -247.522492)
			(xy 332.931008 -247.622314)
		)
		(stroke
			(width 0)
			(type solid)
		)
		(fill yes)
		(layer "In2.Cu")
		(net "M_C_CPU0_SA_DQS_DP<9>")
	)
	(gr_poly
		(pts
			(xy 333.031084 -246.305832) (xy 332.931008 -246.20601) (xy 332.830932 -246.305832) (xy 332.830932 -246.353584)
			(xy 333.031084 -246.353584)
		)
		(stroke
			(width 0)
			(type solid)
		)
		(fill yes)
		(layer "In2.Cu")
		(net "M_C_CPU0_SA_DQS_DP<4>")
	)
	(gr_poly
		(pts
			(xy 333.031084 -245.902226) (xy 333.031084 -245.857776) (xy 332.830932 -245.857776) (xy 332.830932 -245.902226)
			(xy 332.931008 -246.002302)
		)
		(stroke
			(width 0)
			(type solid)
		)
		(fill yes)
		(layer "In2.Cu")
		(net "M_C_CPU0_SA_CB<3>")
	)
	(gr_poly
		(pts
			(xy 333.031084 -244.686074) (xy 332.931008 -244.585998) (xy 332.830932 -244.686074) (xy 332.830932 -244.730524)
			(xy 333.031084 -244.730524)
		)
		(stroke
			(width 0)
			(type solid)
		)
		(fill yes)
		(layer "In2.Cu")
		(net "M_C_CPU0_SA_CB<0>")
	)
	(gr_poly
		(pts
			(xy 333.031084 -244.282214) (xy 333.031084 -244.237764) (xy 332.830932 -244.237764) (xy 332.830932 -244.282214)
			(xy 332.931008 -244.38229)
		)
		(stroke
			(width 0)
			(type solid)
		)
		(fill yes)
		(layer "In2.Cu")
		(net "M_C_CPU0_SA_DQ<31>")
	)
	(gr_poly
		(pts
			(xy 333.031084 -243.066062) (xy 332.931008 -242.965986) (xy 332.830932 -243.066062) (xy 332.830932 -243.110512)
			(xy 333.031084 -243.110512)
		)
		(stroke
			(width 0)
			(type solid)
		)
		(fill yes)
		(layer "In2.Cu")
		(net "M_C_CPU0_SA_DQ<28>")
	)
	(gr_poly
		(pts
			(xy 333.031084 -242.662456) (xy 333.031084 -242.614704) (xy 332.830932 -242.614704) (xy 332.830932 -242.662456)
			(xy 332.931008 -242.762278)
		)
		(stroke
			(width 0)
			(type solid)
		)
		(fill yes)
		(layer "In2.Cu")
		(net "M_C_CPU0_SA_DQS_DP<8>")
	)
	(gr_poly
		(pts
			(xy 333.031084 -241.445796) (xy 332.931008 -241.345974) (xy 332.830932 -241.445796) (xy 332.830932 -241.493548)
			(xy 333.031084 -241.493548)
		)
		(stroke
			(width 0)
			(type solid)
		)
		(fill yes)
		(layer "In2.Cu")
		(net "M_C_CPU0_SA_DQS_DP<3>")
	)
	(gr_poly
		(pts
			(xy 333.031084 -241.04219) (xy 333.031084 -240.99774) (xy 332.830932 -240.99774) (xy 332.830932 -241.04219)
			(xy 332.931008 -241.142266)
		)
		(stroke
			(width 0)
			(type solid)
		)
		(fill yes)
		(layer "In2.Cu")
		(net "M_C_CPU0_SA_DQ<27>")
	)
	(gr_poly
		(pts
			(xy 333.031084 -239.826038) (xy 332.931008 -239.725962) (xy 332.830932 -239.826038) (xy 332.830932 -239.870488)
			(xy 333.031084 -239.870488)
		)
		(stroke
			(width 0)
			(type solid)
		)
		(fill yes)
		(layer "In2.Cu")
		(net "M_C_CPU0_SA_DQ<24>")
	)
	(gr_poly
		(pts
			(xy 333.031084 -239.422178) (xy 333.031084 -239.377728) (xy 332.830932 -239.377728) (xy 332.830932 -239.422178)
			(xy 332.931008 -239.522254)
		)
		(stroke
			(width 0)
			(type solid)
		)
		(fill yes)
		(layer "In2.Cu")
		(net "M_C_CPU0_SA_DQ<23>")
	)
	(gr_poly
		(pts
			(xy 333.031084 -238.206026) (xy 332.931008 -238.10595) (xy 332.830932 -238.206026) (xy 332.830932 -238.250476)
			(xy 333.031084 -238.250476)
		)
		(stroke
			(width 0)
			(type solid)
		)
		(fill yes)
		(layer "In2.Cu")
		(net "M_C_CPU0_SA_DQ<20>")
	)
	(gr_poly
		(pts
			(xy 333.031084 -237.80242) (xy 333.031084 -237.754668) (xy 332.830932 -237.754668) (xy 332.830932 -237.80242)
			(xy 332.931008 -237.902242)
		)
		(stroke
			(width 0)
			(type solid)
		)
		(fill yes)
		(layer "In2.Cu")
		(net "M_C_CPU0_SA_DQS_DP<7>")
	)
	(gr_poly
		(pts
			(xy 333.031084 -236.58576) (xy 332.931008 -236.485938) (xy 332.830932 -236.58576) (xy 332.830932 -236.633512)
			(xy 333.031084 -236.633512)
		)
		(stroke
			(width 0)
			(type solid)
		)
		(fill yes)
		(layer "In2.Cu")
		(net "M_C_CPU0_SA_DQS_DP<2>")
	)
	(gr_poly
		(pts
			(xy 333.031084 -236.182154) (xy 333.031084 -236.137704) (xy 332.830932 -236.137704) (xy 332.830932 -236.182154)
			(xy 332.931008 -236.28223)
		)
		(stroke
			(width 0)
			(type solid)
		)
		(fill yes)
		(layer "In2.Cu")
		(net "M_C_CPU0_SA_DQ<19>")
	)
	(gr_poly
		(pts
			(xy 333.031084 -234.966002) (xy 332.931008 -234.865926) (xy 332.830932 -234.966002) (xy 332.830932 -235.010452)
			(xy 333.031084 -235.010452)
		)
		(stroke
			(width 0)
			(type solid)
		)
		(fill yes)
		(layer "In2.Cu")
		(net "M_C_CPU0_SA_DQ<16>")
	)
	(gr_poly
		(pts
			(xy 333.031084 -234.562142) (xy 333.031084 -234.517692) (xy 332.830932 -234.517692) (xy 332.830932 -234.562142)
			(xy 332.931008 -234.662218)
		)
		(stroke
			(width 0)
			(type solid)
		)
		(fill yes)
		(layer "In2.Cu")
		(net "M_C_CPU0_SA_DQ<15>")
	)
	(gr_poly
		(pts
			(xy 333.031084 -233.34599) (xy 332.931008 -233.245914) (xy 332.830932 -233.34599) (xy 332.830932 -233.39044)
			(xy 333.031084 -233.39044)
		)
		(stroke
			(width 0)
			(type solid)
		)
		(fill yes)
		(layer "In2.Cu")
		(net "M_C_CPU0_SA_DQ<12>")
	)
	(gr_poly
		(pts
			(xy 333.031084 -232.942384) (xy 333.031084 -232.894632) (xy 332.830932 -232.894632) (xy 332.830932 -232.942384)
			(xy 332.931008 -233.042206)
		)
		(stroke
			(width 0)
			(type solid)
		)
		(fill yes)
		(layer "In2.Cu")
		(net "M_C_CPU0_SA_DQS_DP<6>")
	)
	(gr_poly
		(pts
			(xy 333.031084 -231.725724) (xy 332.931008 -231.625902) (xy 332.830932 -231.725724) (xy 332.830932 -231.773476)
			(xy 333.031084 -231.773476)
		)
		(stroke
			(width 0)
			(type solid)
		)
		(fill yes)
		(layer "In2.Cu")
		(net "M_C_CPU0_SA_DQS_DP<1>")
	)
	(gr_poly
		(pts
			(xy 333.031084 -231.322372) (xy 333.031084 -231.277922) (xy 332.830932 -231.277922) (xy 332.830932 -231.322372)
			(xy 332.931008 -231.422448)
		)
		(stroke
			(width 0)
			(type solid)
		)
		(fill yes)
		(layer "In2.Cu")
		(net "M_C_CPU0_SA_DQ<11>")
	)
	(gr_poly
		(pts
			(xy 333.031084 -230.105966) (xy 332.931008 -230.006144) (xy 332.830932 -230.105966) (xy 332.830932 -230.150416)
			(xy 333.031084 -230.150416)
		)
		(stroke
			(width 0)
			(type solid)
		)
		(fill yes)
		(layer "In2.Cu")
		(net "M_C_CPU0_SA_DQ<8>")
	)
	(gr_poly
		(pts
			(xy 333.031084 -229.70236) (xy 333.031084 -229.65791) (xy 332.830932 -229.65791) (xy 332.830932 -229.70236)
			(xy 332.931008 -229.802436)
		)
		(stroke
			(width 0)
			(type solid)
		)
		(fill yes)
		(layer "In2.Cu")
		(net "M_C_CPU0_SA_DQ<7>")
	)
	(gr_poly
		(pts
			(xy 333.031084 -228.486208) (xy 332.931008 -228.386132) (xy 332.830932 -228.486208) (xy 332.830932 -228.530658)
			(xy 333.031084 -228.530658)
		)
		(stroke
			(width 0)
			(type solid)
		)
		(fill yes)
		(layer "In2.Cu")
		(net "M_C_CPU0_SA_DQ<4>")
	)
	(gr_poly
		(pts
			(xy 333.031084 -228.082602) (xy 333.031084 -228.03485) (xy 332.830932 -228.03485) (xy 332.830932 -228.082602)
			(xy 332.931008 -228.182424)
		)
		(stroke
			(width 0)
			(type solid)
		)
		(fill yes)
		(layer "In2.Cu")
		(net "M_C_CPU0_SA_DQS_DP<5>")
	)
	(gr_poly
		(pts
			(xy 333.031084 -226.865942) (xy 332.931008 -226.76612) (xy 332.830932 -226.865942) (xy 332.830932 -226.913694)
			(xy 333.031084 -226.913694)
		)
		(stroke
			(width 0)
			(type solid)
		)
		(fill yes)
		(layer "In2.Cu")
		(net "M_C_CPU0_SA_DQS_DP<0>")
	)
	(gr_poly
		(pts
			(xy 333.031084 -226.462336) (xy 333.031084 -226.417886) (xy 332.830932 -226.417886) (xy 332.830932 -226.462336)
			(xy 332.931008 -226.562412)
		)
		(stroke
			(width 0)
			(type solid)
		)
		(fill yes)
		(layer "In2.Cu")
		(net "M_C_CPU0_SA_DQ<3>")
	)
	(gr_poly
		(pts
			(xy 333.031084 -225.246184) (xy 332.931008 -225.146108) (xy 332.830932 -225.246184) (xy 332.830932 -225.290634)
			(xy 333.031084 -225.290634)
		)
		(stroke
			(width 0)
			(type solid)
		)
		(fill yes)
		(layer "In2.Cu")
		(net "M_C_CPU0_SA_DQ<0>")
	)
	(gr_poly
		(pts
			(xy 333.323946 -291.297614) (xy 333.22387 -291.197792) (xy 333.123794 -291.297614) (xy 333.123794 -291.345366)
			(xy 333.323946 -291.345366)
		)
		(stroke
			(width 0)
			(type solid)
		)
		(fill yes)
		(layer "In2.Cu")
		(net "M_C_CPU0_SB_DQS_DN<8>")
	)
	(gr_poly
		(pts
			(xy 333.331058 -292.91788) (xy 333.230982 -292.817804) (xy 333.130906 -292.91788) (xy 333.130906 -292.96233)
			(xy 333.331058 -292.96233)
		)
		(stroke
			(width 0)
			(type solid)
		)
		(fill yes)
		(layer "In2.Cu")
		(net "M_C_CPU0_SB_DQ<29>")
	)
	(gr_poly
		(pts
			(xy 333.331058 -292.51402) (xy 333.331058 -292.46957) (xy 333.130906 -292.46957) (xy 333.130906 -292.51402)
			(xy 333.230982 -292.614096)
		)
		(stroke
			(width 0)
			(type solid)
		)
		(fill yes)
		(layer "In2.Cu")
		(net "M_C_CPU0_SB_DQ<30>")
	)
	(gr_poly
		(pts
			(xy 333.331058 -290.894262) (xy 333.331058 -290.84651) (xy 333.130906 -290.84651) (xy 333.130906 -290.894262)
			(xy 333.230982 -290.994084)
		)
		(stroke
			(width 0)
			(type solid)
		)
		(fill yes)
		(layer "In2.Cu")
		(net "M_C_CPU0_SB_DQS_DN<3>")
	)
	(gr_poly
		(pts
			(xy 333.331058 -289.677856) (xy 333.230982 -289.57778) (xy 333.130906 -289.677856) (xy 333.130906 -289.722306)
			(xy 333.331058 -289.722306)
		)
		(stroke
			(width 0)
			(type solid)
		)
		(fill yes)
		(layer "In2.Cu")
		(net "M_C_CPU0_SB_DQ<25>")
	)
	(gr_poly
		(pts
			(xy 333.331058 -289.273996) (xy 333.331058 -289.229546) (xy 333.130906 -289.229546) (xy 333.130906 -289.273996)
			(xy 333.230982 -289.374072)
		)
		(stroke
			(width 0)
			(type solid)
		)
		(fill yes)
		(layer "In2.Cu")
		(net "M_C_CPU0_SB_DQ<26>")
	)
	(gr_poly
		(pts
			(xy 333.331058 -288.057844) (xy 333.230982 -287.957768) (xy 333.130906 -288.057844) (xy 333.130906 -288.102294)
			(xy 333.331058 -288.102294)
		)
		(stroke
			(width 0)
			(type solid)
		)
		(fill yes)
		(layer "In2.Cu")
		(net "M_C_CPU0_SB_DQ<21>")
	)
	(gr_poly
		(pts
			(xy 333.331058 -287.654238) (xy 333.331058 -287.609788) (xy 333.130906 -287.609788) (xy 333.130906 -287.654238)
			(xy 333.230982 -287.75406)
		)
		(stroke
			(width 0)
			(type solid)
		)
		(fill yes)
		(layer "In2.Cu")
		(net "M_C_CPU0_SB_DQ<22>")
	)
	(gr_poly
		(pts
			(xy 333.331058 -286.437832) (xy 333.230982 -286.337756) (xy 333.130906 -286.437832) (xy 333.130906 -286.485584)
			(xy 333.331058 -286.485584)
		)
		(stroke
			(width 0)
			(type solid)
		)
		(fill yes)
		(layer "In2.Cu")
		(net "M_C_CPU0_SB_DQS_DN<7>")
	)
	(gr_poly
		(pts
			(xy 333.331058 -286.03448) (xy 333.331058 -285.986728) (xy 333.130906 -285.986728) (xy 333.130906 -286.03448)
			(xy 333.230982 -286.134302)
		)
		(stroke
			(width 0)
			(type solid)
		)
		(fill yes)
		(layer "In2.Cu")
		(net "M_C_CPU0_SB_DQS_DN<2>")
	)
	(gr_poly
		(pts
			(xy 333.331058 -284.818074) (xy 333.230982 -284.717998) (xy 333.130906 -284.818074) (xy 333.130906 -284.862524)
			(xy 333.331058 -284.862524)
		)
		(stroke
			(width 0)
			(type solid)
		)
		(fill yes)
		(layer "In2.Cu")
		(net "M_C_CPU0_SB_DQ<17>")
	)
	(gr_poly
		(pts
			(xy 333.331058 -284.414214) (xy 333.331058 -284.369764) (xy 333.130906 -284.369764) (xy 333.130906 -284.414214)
			(xy 333.230982 -284.51429)
		)
		(stroke
			(width 0)
			(type solid)
		)
		(fill yes)
		(layer "In2.Cu")
		(net "M_C_CPU0_SB_DQ<18>")
	)
	(gr_poly
		(pts
			(xy 333.331058 -283.198062) (xy 333.230982 -283.097986) (xy 333.130906 -283.198062) (xy 333.130906 -283.242512)
			(xy 333.331058 -283.242512)
		)
		(stroke
			(width 0)
			(type solid)
		)
		(fill yes)
		(layer "In2.Cu")
		(net "M_C_CPU0_SB_DQ<13>")
	)
	(gr_poly
		(pts
			(xy 333.331058 -282.794202) (xy 333.331058 -282.749752) (xy 333.130906 -282.749752) (xy 333.130906 -282.794202)
			(xy 333.230982 -282.894278)
		)
		(stroke
			(width 0)
			(type solid)
		)
		(fill yes)
		(layer "In2.Cu")
		(net "M_C_CPU0_SB_DQ<14>")
	)
	(gr_poly
		(pts
			(xy 333.331058 -281.577796) (xy 333.230982 -281.477974) (xy 333.130906 -281.577796) (xy 333.130906 -281.625548)
			(xy 333.331058 -281.625548)
		)
		(stroke
			(width 0)
			(type solid)
		)
		(fill yes)
		(layer "In2.Cu")
		(net "M_C_CPU0_SB_DQS_DN<6>")
	)
	(gr_poly
		(pts
			(xy 333.331058 -281.174444) (xy 333.331058 -281.126692) (xy 333.130906 -281.126692) (xy 333.130906 -281.174444)
			(xy 333.230982 -281.274266)
		)
		(stroke
			(width 0)
			(type solid)
		)
		(fill yes)
		(layer "In2.Cu")
		(net "M_C_CPU0_SB_DQS_DN<1>")
	)
	(gr_poly
		(pts
			(xy 333.331058 -279.958038) (xy 333.230982 -279.857962) (xy 333.130906 -279.958038) (xy 333.130906 -280.002488)
			(xy 333.331058 -280.002488)
		)
		(stroke
			(width 0)
			(type solid)
		)
		(fill yes)
		(layer "In2.Cu")
		(net "M_C_CPU0_SB_DQ<9>")
	)
	(gr_poly
		(pts
			(xy 333.331058 -279.554178) (xy 333.331058 -279.509728) (xy 333.130906 -279.509728) (xy 333.130906 -279.554178)
			(xy 333.230982 -279.654254)
		)
		(stroke
			(width 0)
			(type solid)
		)
		(fill yes)
		(layer "In2.Cu")
		(net "M_C_CPU0_SB_DQ<10>")
	)
	(gr_poly
		(pts
			(xy 333.331058 -278.338026) (xy 333.230982 -278.23795) (xy 333.130906 -278.338026) (xy 333.130906 -278.382476)
			(xy 333.331058 -278.382476)
		)
		(stroke
			(width 0)
			(type solid)
		)
		(fill yes)
		(layer "In2.Cu")
		(net "M_C_CPU0_SB_DQ<5>")
	)
	(gr_poly
		(pts
			(xy 333.331058 -277.934166) (xy 333.331058 -277.889716) (xy 333.130906 -277.889716) (xy 333.130906 -277.934166)
			(xy 333.230982 -278.034242)
		)
		(stroke
			(width 0)
			(type solid)
		)
		(fill yes)
		(layer "In2.Cu")
		(net "M_C_CPU0_SB_DQ<6>")
	)
	(gr_poly
		(pts
			(xy 333.331058 -276.71776) (xy 333.230982 -276.617938) (xy 333.130906 -276.71776) (xy 333.130906 -276.765512)
			(xy 333.331058 -276.765512)
		)
		(stroke
			(width 0)
			(type solid)
		)
		(fill yes)
		(layer "In2.Cu")
		(net "M_C_CPU0_SB_DQS_DN<5>")
	)
	(gr_poly
		(pts
			(xy 333.331058 -276.314408) (xy 333.331058 -276.266656) (xy 333.130906 -276.266656) (xy 333.130906 -276.314408)
			(xy 333.230982 -276.41423)
		)
		(stroke
			(width 0)
			(type solid)
		)
		(fill yes)
		(layer "In2.Cu")
		(net "M_C_CPU0_SB_DQS_DN<0>")
	)
	(gr_poly
		(pts
			(xy 333.331058 -275.098002) (xy 333.230982 -274.997926) (xy 333.130906 -275.098002) (xy 333.130906 -275.142452)
			(xy 333.331058 -275.142452)
		)
		(stroke
			(width 0)
			(type solid)
		)
		(fill yes)
		(layer "In2.Cu")
		(net "M_C_CPU0_SB_DQ<1>")
	)
	(gr_poly
		(pts
			(xy 333.331058 -274.694142) (xy 333.331058 -274.649692) (xy 333.130906 -274.649692) (xy 333.130906 -274.694142)
			(xy 333.230982 -274.794218)
		)
		(stroke
			(width 0)
			(type solid)
		)
		(fill yes)
		(layer "In2.Cu")
		(net "M_C_CPU0_SB_DQ<2>")
	)
	(gr_poly
		(pts
			(xy 333.331058 -273.47799) (xy 333.230982 -273.377914) (xy 333.130906 -273.47799) (xy 333.130906 -273.52244)
			(xy 333.331058 -273.52244)
		)
		(stroke
			(width 0)
			(type solid)
		)
		(fill yes)
		(layer "In2.Cu")
		(net "M_C_CPU0_SB_CB<1>")
	)
	(gr_poly
		(pts
			(xy 333.331058 -273.07413) (xy 333.331058 -273.02968) (xy 333.130906 -273.02968) (xy 333.130906 -273.07413)
			(xy 333.230982 -273.174206)
		)
		(stroke
			(width 0)
			(type solid)
		)
		(fill yes)
		(layer "In2.Cu")
		(net "M_C_CPU0_SB_CB<2>")
	)
	(gr_poly
		(pts
			(xy 333.331058 -271.857724) (xy 333.230982 -271.757902) (xy 333.130906 -271.857724) (xy 333.130906 -271.905476)
			(xy 333.331058 -271.905476)
		)
		(stroke
			(width 0)
			(type solid)
		)
		(fill yes)
		(layer "In2.Cu")
		(net "M_C_CPU0_SB_DQS_DN<4>")
	)
	(gr_poly
		(pts
			(xy 333.331058 -271.454372) (xy 333.331058 -271.40662) (xy 333.130906 -271.40662) (xy 333.130906 -271.454372)
			(xy 333.230982 -271.554194)
		)
		(stroke
			(width 0)
			(type solid)
		)
		(fill yes)
		(layer "In2.Cu")
		(net "M_C_CPU0_SB_DQS_DN<9>")
	)
	(gr_poly
		(pts
			(xy 333.331058 -270.237966) (xy 333.230982 -270.13789) (xy 333.130906 -270.237966) (xy 333.130906 -270.282416)
			(xy 333.331058 -270.282416)
		)
		(stroke
			(width 0)
			(type solid)
		)
		(fill yes)
		(layer "In2.Cu")
		(net "M_C_CPU0_SB_CB<5>")
	)
	(gr_poly
		(pts
			(xy 333.331058 -269.834106) (xy 333.331058 -269.789656) (xy 333.130906 -269.789656) (xy 333.130906 -269.834106)
			(xy 333.230982 -269.934182)
		)
		(stroke
			(width 0)
			(type solid)
		)
		(fill yes)
		(layer "In2.Cu")
		(net "M_C_CPU0_SB_CB<6>")
	)
	(gr_poly
		(pts
			(xy 333.331058 -266.594082) (xy 333.331058 -266.549632) (xy 333.130906 -266.549632) (xy 333.130906 -266.594082)
			(xy 333.230982 -266.694158)
		)
		(stroke
			(width 0)
			(type solid)
		)
		(fill yes)
		(layer "In2.Cu")
		(net "M_C_CPU0_SB_CS_N<1>")
	)
	(gr_poly
		(pts
			(xy 333.331058 -264.97407) (xy 333.331058 -264.92962) (xy 333.130906 -264.92962) (xy 333.130906 -264.97407)
			(xy 333.230982 -265.074146)
		)
		(stroke
			(width 0)
			(type solid)
		)
		(fill yes)
		(layer "In2.Cu")
		(net "M_C_CPU0_SB_PAR")
	)
	(gr_poly
		(pts
			(xy 333.331058 -263.757918) (xy 333.230982 -263.657842) (xy 333.130906 -263.757918) (xy 333.130906 -263.802368)
			(xy 333.331058 -263.802368)
		)
		(stroke
			(width 0)
			(type solid)
		)
		(fill yes)
		(layer "In2.Cu")
		(net "M_C_CPU0_SB_CA<4>")
	)
	(gr_poly
		(pts
			(xy 333.331058 -263.354058) (xy 333.331058 -263.309608) (xy 333.130906 -263.309608) (xy 333.130906 -263.354058)
			(xy 333.230982 -263.454134)
		)
		(stroke
			(width 0)
			(type solid)
		)
		(fill yes)
		(layer "In2.Cu")
		(net "M_C_CPU0_SB_CA<3>")
	)
	(gr_poly
		(pts
			(xy 333.331058 -262.137906) (xy 333.230982 -262.03783) (xy 333.130906 -262.137906) (xy 333.130906 -262.182356)
			(xy 333.331058 -262.182356)
		)
		(stroke
			(width 0)
			(type solid)
		)
		(fill yes)
		(layer "In2.Cu")
		(net "M_C_CPU0_SB_CA<0>")
	)
	(gr_poly
		(pts
			(xy 333.337154 -266.991592) (xy 333.237332 -266.891516) (xy 333.137256 -266.991592) (xy 333.137256 -267.036042)
			(xy 333.337154 -267.036042)
		)
		(stroke
			(width 0)
			(type solid)
		)
		(fill yes)
		(layer "In2.Cu")
		(net "M_C_CPU0_SA_RSP<0>")
	)
	(gr_poly
		(pts
			(xy 333.500984 -246.712232) (xy 333.500984 -246.664734) (xy 333.301086 -246.664734) (xy 333.301086 -246.712232)
			(xy 333.400908 -246.812308)
		)
		(stroke
			(width 0)
			(type solid)
		)
		(fill yes)
		(layer "In2.Cu")
		(net "M_C_CPU0_SA_DQS_DN<4>")
	)
	(gr_poly
		(pts
			(xy 333.501238 -256.432558) (xy 333.501238 -256.384806) (xy 333.301086 -256.384806) (xy 333.301086 -256.432558)
			(xy 333.401162 -256.53238)
		)
		(stroke
			(width 0)
			(type solid)
		)
		(fill yes)
		(layer "In2.Cu")
		(net "M_C_CPU0_CLK_DN<0>")
	)
	(gr_poly
		(pts
			(xy 333.501238 -255.216152) (xy 333.401162 -255.116076) (xy 333.301086 -255.216152) (xy 333.301086 -255.260602)
			(xy 333.501238 -255.260602)
		)
		(stroke
			(width 0)
			(type solid)
		)
		(fill yes)
		(layer "In2.Cu")
		(net "M_C_CPU0_SA_CA<6>")
	)
	(gr_poly
		(pts
			(xy 333.501238 -254.812292) (xy 333.501238 -254.767842) (xy 333.301086 -254.767842) (xy 333.301086 -254.812292)
			(xy 333.401162 -254.912368)
		)
		(stroke
			(width 0)
			(type solid)
		)
		(fill yes)
		(layer "In2.Cu")
		(net "M_C_CPU0_SA_CA<5>")
	)
	(gr_poly
		(pts
			(xy 333.501238 -253.59614) (xy 333.401162 -253.496064) (xy 333.301086 -253.59614) (xy 333.301086 -253.64059)
			(xy 333.501238 -253.64059)
		)
		(stroke
			(width 0)
			(type solid)
		)
		(fill yes)
		(layer "In2.Cu")
		(net "M_C_CPU0_SA_CA<2>")
	)
	(gr_poly
		(pts
			(xy 333.501238 -253.19228) (xy 333.501238 -253.14783) (xy 333.301086 -253.14783) (xy 333.301086 -253.19228)
			(xy 333.401162 -253.292356)
		)
		(stroke
			(width 0)
			(type solid)
		)
		(fill yes)
		(layer "In2.Cu")
		(net "M_C_CPU0_SA_CA<1>")
	)
	(gr_poly
		(pts
			(xy 333.501238 -251.572268) (xy 333.501238 -251.527818) (xy 333.301086 -251.527818) (xy 333.301086 -251.572268)
			(xy 333.401162 -251.672344)
		)
		(stroke
			(width 0)
			(type solid)
		)
		(fill yes)
		(layer "In2.Cu")
		(net "M_C_CPU0_SA_CS_N<0>")
	)
	(gr_poly
		(pts
			(xy 333.501238 -250.356116) (xy 333.401162 -250.25604) (xy 333.301086 -250.356116) (xy 333.301086 -250.400566)
			(xy 333.501238 -250.400566)
		)
		(stroke
			(width 0)
			(type solid)
		)
		(fill yes)
		(layer "In2.Cu")
		(net "M_C_CPU0_ALERT_R_N")
	)
	(gr_poly
		(pts
			(xy 333.501238 -248.736104) (xy 333.401162 -248.636028) (xy 333.301086 -248.736104) (xy 333.301086 -248.780554)
			(xy 333.501238 -248.780554)
		)
		(stroke
			(width 0)
			(type solid)
		)
		(fill yes)
		(layer "In2.Cu")
		(net "M_C_CPU0_SA_CB<5>")
	)
	(gr_poly
		(pts
			(xy 333.501238 -248.332244) (xy 333.501238 -248.287794) (xy 333.301086 -248.287794) (xy 333.301086 -248.332244)
			(xy 333.401162 -248.43232)
		)
		(stroke
			(width 0)
			(type solid)
		)
		(fill yes)
		(layer "In2.Cu")
		(net "M_C_CPU0_SA_CB<6>")
	)
	(gr_poly
		(pts
			(xy 333.501238 -247.115838) (xy 333.401162 -247.016016) (xy 333.301086 -247.115838) (xy 333.301086 -247.16359)
			(xy 333.501238 -247.16359)
		)
		(stroke
			(width 0)
			(type solid)
		)
		(fill yes)
		(layer "In2.Cu")
		(net "M_C_CPU0_SA_DQS_DN<9>")
	)
	(gr_poly
		(pts
			(xy 333.501238 -245.49608) (xy 333.401162 -245.396004) (xy 333.301086 -245.49608) (xy 333.301086 -245.54053)
			(xy 333.501238 -245.54053)
		)
		(stroke
			(width 0)
			(type solid)
		)
		(fill yes)
		(layer "In2.Cu")
		(net "M_C_CPU0_SA_CB<1>")
	)
	(gr_poly
		(pts
			(xy 333.501238 -245.09222) (xy 333.501238 -245.04777) (xy 333.301086 -245.04777) (xy 333.301086 -245.09222)
			(xy 333.401162 -245.192296)
		)
		(stroke
			(width 0)
			(type solid)
		)
		(fill yes)
		(layer "In2.Cu")
		(net "M_C_CPU0_SA_CB<2>")
	)
	(gr_poly
		(pts
			(xy 333.501238 -243.876068) (xy 333.401162 -243.775992) (xy 333.301086 -243.876068) (xy 333.301086 -243.920518)
			(xy 333.501238 -243.920518)
		)
		(stroke
			(width 0)
			(type solid)
		)
		(fill yes)
		(layer "In2.Cu")
		(net "M_C_CPU0_SA_DQ<29>")
	)
	(gr_poly
		(pts
			(xy 333.501238 -243.472208) (xy 333.501238 -243.427758) (xy 333.301086 -243.427758) (xy 333.301086 -243.472208)
			(xy 333.401162 -243.572284)
		)
		(stroke
			(width 0)
			(type solid)
		)
		(fill yes)
		(layer "In2.Cu")
		(net "M_C_CPU0_SA_DQ<30>")
	)
	(gr_poly
		(pts
			(xy 333.501238 -242.255802) (xy 333.401162 -242.15598) (xy 333.301086 -242.255802) (xy 333.301086 -242.303554)
			(xy 333.501238 -242.303554)
		)
		(stroke
			(width 0)
			(type solid)
		)
		(fill yes)
		(layer "In2.Cu")
		(net "M_C_CPU0_SA_DQS_DN<8>")
	)
	(gr_poly
		(pts
			(xy 333.501238 -241.85245) (xy 333.501238 -241.804698) (xy 333.301086 -241.804698) (xy 333.301086 -241.85245)
			(xy 333.401162 -241.952272)
		)
		(stroke
			(width 0)
			(type solid)
		)
		(fill yes)
		(layer "In2.Cu")
		(net "M_C_CPU0_SA_DQS_DN<3>")
	)
	(gr_poly
		(pts
			(xy 333.501238 -240.636044) (xy 333.401162 -240.535968) (xy 333.301086 -240.636044) (xy 333.301086 -240.680494)
			(xy 333.501238 -240.680494)
		)
		(stroke
			(width 0)
			(type solid)
		)
		(fill yes)
		(layer "In2.Cu")
		(net "M_C_CPU0_SA_DQ<25>")
	)
	(gr_poly
		(pts
			(xy 333.501238 -240.232184) (xy 333.501238 -240.187734) (xy 333.301086 -240.187734) (xy 333.301086 -240.232184)
			(xy 333.401162 -240.33226)
		)
		(stroke
			(width 0)
			(type solid)
		)
		(fill yes)
		(layer "In2.Cu")
		(net "M_C_CPU0_SA_DQ<26>")
	)
	(gr_poly
		(pts
			(xy 333.501238 -239.016032) (xy 333.401162 -238.915956) (xy 333.301086 -239.016032) (xy 333.301086 -239.060482)
			(xy 333.501238 -239.060482)
		)
		(stroke
			(width 0)
			(type solid)
		)
		(fill yes)
		(layer "In2.Cu")
		(net "M_C_CPU0_SA_DQ<21>")
	)
	(gr_poly
		(pts
			(xy 333.501238 -238.612172) (xy 333.501238 -238.567722) (xy 333.301086 -238.567722) (xy 333.301086 -238.612172)
			(xy 333.401162 -238.712248)
		)
		(stroke
			(width 0)
			(type solid)
		)
		(fill yes)
		(layer "In2.Cu")
		(net "M_C_CPU0_SA_DQ<22>")
	)
	(gr_poly
		(pts
			(xy 333.501238 -237.395766) (xy 333.401162 -237.295944) (xy 333.301086 -237.395766) (xy 333.301086 -237.443518)
			(xy 333.501238 -237.443518)
		)
		(stroke
			(width 0)
			(type solid)
		)
		(fill yes)
		(layer "In2.Cu")
		(net "M_C_CPU0_SA_DQS_DN<7>")
	)
	(gr_poly
		(pts
			(xy 333.501238 -236.992414) (xy 333.501238 -236.944662) (xy 333.301086 -236.944662) (xy 333.301086 -236.992414)
			(xy 333.401162 -237.092236)
		)
		(stroke
			(width 0)
			(type solid)
		)
		(fill yes)
		(layer "In2.Cu")
		(net "M_C_CPU0_SA_DQS_DN<2>")
	)
	(gr_poly
		(pts
			(xy 333.501238 -235.776008) (xy 333.401162 -235.675932) (xy 333.301086 -235.776008) (xy 333.301086 -235.820458)
			(xy 333.501238 -235.820458)
		)
		(stroke
			(width 0)
			(type solid)
		)
		(fill yes)
		(layer "In2.Cu")
		(net "M_C_CPU0_SA_DQ<17>")
	)
	(gr_poly
		(pts
			(xy 333.501238 -235.372148) (xy 333.501238 -235.327698) (xy 333.301086 -235.327698) (xy 333.301086 -235.372148)
			(xy 333.401162 -235.472224)
		)
		(stroke
			(width 0)
			(type solid)
		)
		(fill yes)
		(layer "In2.Cu")
		(net "M_C_CPU0_SA_DQ<18>")
	)
	(gr_poly
		(pts
			(xy 333.501238 -234.155996) (xy 333.401162 -234.05592) (xy 333.301086 -234.155996) (xy 333.301086 -234.200446)
			(xy 333.501238 -234.200446)
		)
		(stroke
			(width 0)
			(type solid)
		)
		(fill yes)
		(layer "In2.Cu")
		(net "M_C_CPU0_SA_DQ<13>")
	)
	(gr_poly
		(pts
			(xy 333.501238 -233.752136) (xy 333.501238 -233.707686) (xy 333.301086 -233.707686) (xy 333.301086 -233.752136)
			(xy 333.401162 -233.852212)
		)
		(stroke
			(width 0)
			(type solid)
		)
		(fill yes)
		(layer "In2.Cu")
		(net "M_C_CPU0_SA_DQ<14>")
	)
	(gr_poly
		(pts
			(xy 333.501238 -232.53573) (xy 333.401162 -232.435908) (xy 333.301086 -232.53573) (xy 333.301086 -232.583482)
			(xy 333.501238 -232.583482)
		)
		(stroke
			(width 0)
			(type solid)
		)
		(fill yes)
		(layer "In2.Cu")
		(net "M_C_CPU0_SA_DQS_DN<6>")
	)
	(gr_poly
		(pts
			(xy 333.501238 -232.132378) (xy 333.501238 -232.084626) (xy 333.301086 -232.084626) (xy 333.301086 -232.132378)
			(xy 333.401162 -232.2322)
		)
		(stroke
			(width 0)
			(type solid)
		)
		(fill yes)
		(layer "In2.Cu")
		(net "M_C_CPU0_SA_DQS_DN<1>")
	)
	(gr_poly
		(pts
			(xy 333.501238 -230.915972) (xy 333.401162 -230.815896) (xy 333.301086 -230.915972) (xy 333.301086 -230.960422)
			(xy 333.501238 -230.960422)
		)
		(stroke
			(width 0)
			(type solid)
		)
		(fill yes)
		(layer "In2.Cu")
		(net "M_C_CPU0_SA_DQ<9>")
	)
	(gr_poly
		(pts
			(xy 333.501238 -230.512366) (xy 333.501238 -230.467916) (xy 333.301086 -230.467916) (xy 333.301086 -230.512366)
			(xy 333.401162 -230.612188)
		)
		(stroke
			(width 0)
			(type solid)
		)
		(fill yes)
		(layer "In2.Cu")
		(net "M_C_CPU0_SA_DQ<10>")
	)
	(gr_poly
		(pts
			(xy 333.501238 -229.29596) (xy 333.401162 -229.195884) (xy 333.301086 -229.29596) (xy 333.301086 -229.34041)
			(xy 333.501238 -229.34041)
		)
		(stroke
			(width 0)
			(type solid)
		)
		(fill yes)
		(layer "In2.Cu")
		(net "M_C_CPU0_SA_DQ<5>")
	)
	(gr_poly
		(pts
			(xy 333.501238 -228.892354) (xy 333.501238 -228.847904) (xy 333.301086 -228.847904) (xy 333.301086 -228.892354)
			(xy 333.401162 -228.99243)
		)
		(stroke
			(width 0)
			(type solid)
		)
		(fill yes)
		(layer "In2.Cu")
		(net "M_C_CPU0_SA_DQ<6>")
	)
	(gr_poly
		(pts
			(xy 333.501238 -227.675948) (xy 333.401162 -227.576126) (xy 333.301086 -227.675948) (xy 333.301086 -227.7237)
			(xy 333.501238 -227.7237)
		)
		(stroke
			(width 0)
			(type solid)
		)
		(fill yes)
		(layer "In2.Cu")
		(net "M_C_CPU0_SA_DQS_DN<5>")
	)
	(gr_poly
		(pts
			(xy 333.501238 -227.272596) (xy 333.501238 -227.224844) (xy 333.301086 -227.224844) (xy 333.301086 -227.272596)
			(xy 333.401162 -227.372418)
		)
		(stroke
			(width 0)
			(type solid)
		)
		(fill yes)
		(layer "In2.Cu")
		(net "M_C_CPU0_SA_DQS_DN<0>")
	)
	(gr_poly
		(pts
			(xy 333.501238 -226.05619) (xy 333.401162 -225.956114) (xy 333.301086 -226.05619) (xy 333.301086 -226.10064)
			(xy 333.501238 -226.10064)
		)
		(stroke
			(width 0)
			(type solid)
		)
		(fill yes)
		(layer "In2.Cu")
		(net "M_C_CPU0_SA_DQ<1>")
	)
	(gr_poly
		(pts
			(xy 333.501238 -225.65233) (xy 333.501238 -225.60788) (xy 333.301086 -225.60788) (xy 333.301086 -225.65233)
			(xy 333.401162 -225.752406)
		)
		(stroke
			(width 0)
			(type solid)
		)
		(fill yes)
		(layer "In2.Cu")
		(net "M_C_CPU0_SA_DQ<2>")
	)
	(gr_poly
		(pts
			(xy 333.793846 -291.704268) (xy 333.793846 -291.656516) (xy 333.593694 -291.656516) (xy 333.593694 -291.704268)
			(xy 333.69377 -291.80409)
		)
		(stroke
			(width 0)
			(type solid)
		)
		(fill yes)
		(layer "In2.Cu")
		(net "M_C_CPU0_SB_DQS_DP<8>")
	)
	(gr_poly
		(pts
			(xy 333.794862 -267.801598) (xy 333.694786 -267.701522) (xy 333.594964 -267.801598) (xy 333.594964 -267.846048)
			(xy 333.794862 -267.846048)
		)
		(stroke
			(width 0)
			(type solid)
		)
		(fill yes)
		(layer "In2.Cu")
		(net "M_C_CPU0_SB_RSP<0>")
	)
	(gr_poly
		(pts
			(xy 333.801212 -293.324026) (xy 333.801212 -293.279576) (xy 333.60106 -293.279576) (xy 333.60106 -293.324026)
			(xy 333.701136 -293.424102)
		)
		(stroke
			(width 0)
			(type solid)
		)
		(fill yes)
		(layer "In2.Cu")
		(net "M_C_CPU0_SB_DQ<31>")
	)
	(gr_poly
		(pts
			(xy 333.801212 -292.107874) (xy 333.701136 -292.007798) (xy 333.60106 -292.107874) (xy 333.60106 -292.152324)
			(xy 333.801212 -292.152324)
		)
		(stroke
			(width 0)
			(type solid)
		)
		(fill yes)
		(layer "In2.Cu")
		(net "M_C_CPU0_SB_DQ<28>")
	)
	(gr_poly
		(pts
			(xy 333.801212 -290.487608) (xy 333.701136 -290.387786) (xy 333.60106 -290.487608) (xy 333.60106 -290.53536)
			(xy 333.801212 -290.53536)
		)
		(stroke
			(width 0)
			(type solid)
		)
		(fill yes)
		(layer "In2.Cu")
		(net "M_C_CPU0_SB_DQS_DP<3>")
	)
	(gr_poly
		(pts
			(xy 333.801212 -290.084002) (xy 333.801212 -290.039552) (xy 333.60106 -290.039552) (xy 333.60106 -290.084002)
			(xy 333.701136 -290.184078)
		)
		(stroke
			(width 0)
			(type solid)
		)
		(fill yes)
		(layer "In2.Cu")
		(net "M_C_CPU0_SB_DQ<27>")
	)
	(gr_poly
		(pts
			(xy 333.801212 -288.86785) (xy 333.701136 -288.767774) (xy 333.60106 -288.86785) (xy 333.60106 -288.9123)
			(xy 333.801212 -288.9123)
		)
		(stroke
			(width 0)
			(type solid)
		)
		(fill yes)
		(layer "In2.Cu")
		(net "M_C_CPU0_SB_DQ<24>")
	)
	(gr_poly
		(pts
			(xy 333.801212 -288.464244) (xy 333.801212 -288.419794) (xy 333.60106 -288.419794) (xy 333.60106 -288.464244)
			(xy 333.701136 -288.56432)
		)
		(stroke
			(width 0)
			(type solid)
		)
		(fill yes)
		(layer "In2.Cu")
		(net "M_C_CPU0_SB_DQ<23>")
	)
	(gr_poly
		(pts
			(xy 333.801212 -287.247838) (xy 333.701136 -287.148016) (xy 333.60106 -287.247838) (xy 333.60106 -287.292288)
			(xy 333.801212 -287.292288)
		)
		(stroke
			(width 0)
			(type solid)
		)
		(fill yes)
		(layer "In2.Cu")
		(net "M_C_CPU0_SB_DQ<20>")
	)
	(gr_poly
		(pts
			(xy 333.801212 -286.844232) (xy 333.801212 -286.79648) (xy 333.60106 -286.79648) (xy 333.60106 -286.844232)
			(xy 333.701136 -286.944308)
		)
		(stroke
			(width 0)
			(type solid)
		)
		(fill yes)
		(layer "In2.Cu")
		(net "M_C_CPU0_SB_DQS_DP<7>")
	)
	(gr_poly
		(pts
			(xy 333.801212 -285.627826) (xy 333.701136 -285.528004) (xy 333.60106 -285.627826) (xy 333.60106 -285.675578)
			(xy 333.801212 -285.675578)
		)
		(stroke
			(width 0)
			(type solid)
		)
		(fill yes)
		(layer "In2.Cu")
		(net "M_C_CPU0_SB_DQS_DP<2>")
	)
	(gr_poly
		(pts
			(xy 333.801212 -285.22422) (xy 333.801212 -285.17977) (xy 333.60106 -285.17977) (xy 333.60106 -285.22422)
			(xy 333.701136 -285.324296)
		)
		(stroke
			(width 0)
			(type solid)
		)
		(fill yes)
		(layer "In2.Cu")
		(net "M_C_CPU0_SB_DQ<19>")
	)
	(gr_poly
		(pts
			(xy 333.801212 -284.008068) (xy 333.701136 -283.907992) (xy 333.60106 -284.008068) (xy 333.60106 -284.052518)
			(xy 333.801212 -284.052518)
		)
		(stroke
			(width 0)
			(type solid)
		)
		(fill yes)
		(layer "In2.Cu")
		(net "M_C_CPU0_SB_DQ<16>")
	)
	(gr_poly
		(pts
			(xy 333.801212 -283.604208) (xy 333.801212 -283.559758) (xy 333.60106 -283.559758) (xy 333.60106 -283.604208)
			(xy 333.701136 -283.704284)
		)
		(stroke
			(width 0)
			(type solid)
		)
		(fill yes)
		(layer "In2.Cu")
		(net "M_C_CPU0_SB_DQ<15>")
	)
	(gr_poly
		(pts
			(xy 333.801212 -282.388056) (xy 333.701136 -282.28798) (xy 333.60106 -282.388056) (xy 333.60106 -282.432506)
			(xy 333.801212 -282.432506)
		)
		(stroke
			(width 0)
			(type solid)
		)
		(fill yes)
		(layer "In2.Cu")
		(net "M_C_CPU0_SB_DQ<12>")
	)
	(gr_poly
		(pts
			(xy 333.801212 -281.98445) (xy 333.801212 -281.936698) (xy 333.60106 -281.936698) (xy 333.60106 -281.98445)
			(xy 333.701136 -282.084272)
		)
		(stroke
			(width 0)
			(type solid)
		)
		(fill yes)
		(layer "In2.Cu")
		(net "M_C_CPU0_SB_DQS_DP<6>")
	)
	(gr_poly
		(pts
			(xy 333.801212 -280.76779) (xy 333.701136 -280.667968) (xy 333.60106 -280.76779) (xy 333.60106 -280.815542)
			(xy 333.801212 -280.815542)
		)
		(stroke
			(width 0)
			(type solid)
		)
		(fill yes)
		(layer "In2.Cu")
		(net "M_C_CPU0_SB_DQS_DP<1>")
	)
	(gr_poly
		(pts
			(xy 333.801212 -280.364184) (xy 333.801212 -280.319734) (xy 333.60106 -280.319734) (xy 333.60106 -280.364184)
			(xy 333.701136 -280.46426)
		)
		(stroke
			(width 0)
			(type solid)
		)
		(fill yes)
		(layer "In2.Cu")
		(net "M_C_CPU0_SB_DQ<11>")
	)
	(gr_poly
		(pts
			(xy 333.801212 -279.148032) (xy 333.701136 -279.047956) (xy 333.60106 -279.148032) (xy 333.60106 -279.192482)
			(xy 333.801212 -279.192482)
		)
		(stroke
			(width 0)
			(type solid)
		)
		(fill yes)
		(layer "In2.Cu")
		(net "M_C_CPU0_SB_DQ<8>")
	)
	(gr_poly
		(pts
			(xy 333.801212 -278.744172) (xy 333.801212 -278.699722) (xy 333.60106 -278.699722) (xy 333.60106 -278.744172)
			(xy 333.701136 -278.844248)
		)
		(stroke
			(width 0)
			(type solid)
		)
		(fill yes)
		(layer "In2.Cu")
		(net "M_C_CPU0_SB_DQ<7>")
	)
	(gr_poly
		(pts
			(xy 333.801212 -277.52802) (xy 333.701136 -277.427944) (xy 333.60106 -277.52802) (xy 333.60106 -277.57247)
			(xy 333.801212 -277.57247)
		)
		(stroke
			(width 0)
			(type solid)
		)
		(fill yes)
		(layer "In2.Cu")
		(net "M_C_CPU0_SB_DQ<4>")
	)
	(gr_poly
		(pts
			(xy 333.801212 -277.124414) (xy 333.801212 -277.076662) (xy 333.60106 -277.076662) (xy 333.60106 -277.124414)
			(xy 333.701136 -277.224236)
		)
		(stroke
			(width 0)
			(type solid)
		)
		(fill yes)
		(layer "In2.Cu")
		(net "M_C_CPU0_SB_DQS_DP<5>")
	)
	(gr_poly
		(pts
			(xy 333.801212 -275.907754) (xy 333.701136 -275.807932) (xy 333.60106 -275.907754) (xy 333.60106 -275.955506)
			(xy 333.801212 -275.955506)
		)
		(stroke
			(width 0)
			(type solid)
		)
		(fill yes)
		(layer "In2.Cu")
		(net "M_C_CPU0_SB_DQS_DP<0>")
	)
	(gr_poly
		(pts
			(xy 333.801212 -275.504148) (xy 333.801212 -275.459698) (xy 333.60106 -275.459698) (xy 333.60106 -275.504148)
			(xy 333.701136 -275.604224)
		)
		(stroke
			(width 0)
			(type solid)
		)
		(fill yes)
		(layer "In2.Cu")
		(net "M_C_CPU0_SB_DQ<3>")
	)
	(gr_poly
		(pts
			(xy 333.801212 -274.287996) (xy 333.701136 -274.18792) (xy 333.60106 -274.287996) (xy 333.60106 -274.332446)
			(xy 333.801212 -274.332446)
		)
		(stroke
			(width 0)
			(type solid)
		)
		(fill yes)
		(layer "In2.Cu")
		(net "M_C_CPU0_SB_DQ<0>")
	)
	(gr_poly
		(pts
			(xy 333.801212 -273.884136) (xy 333.801212 -273.839686) (xy 333.60106 -273.839686) (xy 333.60106 -273.884136)
			(xy 333.701136 -273.984212)
		)
		(stroke
			(width 0)
			(type solid)
		)
		(fill yes)
		(layer "In2.Cu")
		(net "M_C_CPU0_SB_CB<3>")
	)
	(gr_poly
		(pts
			(xy 333.801212 -272.667984) (xy 333.701136 -272.567908) (xy 333.60106 -272.667984) (xy 333.60106 -272.712434)
			(xy 333.801212 -272.712434)
		)
		(stroke
			(width 0)
			(type solid)
		)
		(fill yes)
		(layer "In2.Cu")
		(net "M_C_CPU0_SB_CB<0>")
	)
	(gr_poly
		(pts
			(xy 333.801212 -272.264378) (xy 333.801212 -272.216626) (xy 333.60106 -272.216626) (xy 333.60106 -272.264378)
			(xy 333.701136 -272.3642)
		)
		(stroke
			(width 0)
			(type solid)
		)
		(fill yes)
		(layer "In2.Cu")
		(net "M_C_CPU0_SB_DQS_DP<4>")
	)
	(gr_poly
		(pts
			(xy 333.801212 -271.047718) (xy 333.701136 -270.947896) (xy 333.60106 -271.047718) (xy 333.60106 -271.09547)
			(xy 333.801212 -271.09547)
		)
		(stroke
			(width 0)
			(type solid)
		)
		(fill yes)
		(layer "In2.Cu")
		(net "M_C_CPU0_SB_DQS_DP<9>")
	)
	(gr_poly
		(pts
			(xy 333.801212 -270.644112) (xy 333.801212 -270.599662) (xy 333.60106 -270.599662) (xy 333.60106 -270.644112)
			(xy 333.701136 -270.744188)
		)
		(stroke
			(width 0)
			(type solid)
		)
		(fill yes)
		(layer "In2.Cu")
		(net "M_C_CPU0_SB_CB<7>")
	)
	(gr_poly
		(pts
			(xy 333.801212 -269.42796) (xy 333.701136 -269.327884) (xy 333.60106 -269.42796) (xy 333.60106 -269.47241)
			(xy 333.801212 -269.47241)
		)
		(stroke
			(width 0)
			(type solid)
		)
		(fill yes)
		(layer "In2.Cu")
		(net "M_C_CPU0_SB_CB<4>")
	)
	(gr_poly
		(pts
			(xy 333.801212 -265.784076) (xy 333.801212 -265.739626) (xy 333.60106 -265.739626) (xy 333.60106 -265.784076)
			(xy 333.701136 -265.884152)
		)
		(stroke
			(width 0)
			(type solid)
		)
		(fill yes)
		(layer "In2.Cu")
		(net "M_C_CPU0_SB_CS_N<0>")
	)
	(gr_poly
		(pts
			(xy 333.801212 -264.567924) (xy 333.701136 -264.467848) (xy 333.60106 -264.567924) (xy 333.60106 -264.612374)
			(xy 333.801212 -264.612374)
		)
		(stroke
			(width 0)
			(type solid)
		)
		(fill yes)
		(layer "In2.Cu")
		(net "M_C_CPU0_SB_CA<6>")
	)
	(gr_poly
		(pts
			(xy 333.801212 -264.164064) (xy 333.801212 -264.119614) (xy 333.60106 -264.119614) (xy 333.60106 -264.164064)
			(xy 333.701136 -264.26414)
		)
		(stroke
			(width 0)
			(type solid)
		)
		(fill yes)
		(layer "In2.Cu")
		(net "M_C_CPU0_SB_CA<5>")
	)
	(gr_poly
		(pts
			(xy 333.801212 -262.947912) (xy 333.701136 -262.847836) (xy 333.60106 -262.947912) (xy 333.60106 -262.992362)
			(xy 333.801212 -262.992362)
		)
		(stroke
			(width 0)
			(type solid)
		)
		(fill yes)
		(layer "In2.Cu")
		(net "M_C_CPU0_SB_CA<2>")
	)
	(gr_poly
		(pts
			(xy 333.801212 -262.544052) (xy 333.801212 -262.499602) (xy 333.60106 -262.499602) (xy 333.60106 -262.544052)
			(xy 333.701136 -262.644128)
		)
		(stroke
			(width 0)
			(type solid)
		)
		(fill yes)
		(layer "In2.Cu")
		(net "M_C_CPU0_SB_CA<1>")
	)
	(gr_poly
		(pts
			(xy 333.971138 -256.025904) (xy 333.871062 -255.926082) (xy 333.770986 -256.025904) (xy 333.770986 -256.073656)
			(xy 333.971138 -256.073656)
		)
		(stroke
			(width 0)
			(type solid)
		)
		(fill yes)
		(layer "In2.Cu")
		(net "M_C_CPU0_CLK_DP<0>")
	)
	(gr_poly
		(pts
			(xy 333.971138 -255.622298) (xy 333.971138 -255.577848) (xy 333.770986 -255.577848) (xy 333.770986 -255.622298)
			(xy 333.871062 -255.722374)
		)
		(stroke
			(width 0)
			(type solid)
		)
		(fill yes)
		(layer "In2.Cu")
		(net "M_C_CPU0_SA_PAR")
	)
	(gr_poly
		(pts
			(xy 333.971138 -254.406146) (xy 333.871062 -254.30607) (xy 333.770986 -254.406146) (xy 333.770986 -254.450596)
			(xy 333.971138 -254.450596)
		)
		(stroke
			(width 0)
			(type solid)
		)
		(fill yes)
		(layer "In2.Cu")
		(net "M_C_CPU0_SA_CA<4>")
	)
	(gr_poly
		(pts
			(xy 333.971138 -254.002286) (xy 333.971138 -253.957836) (xy 333.770986 -253.957836) (xy 333.770986 -254.002286)
			(xy 333.871062 -254.102362)
		)
		(stroke
			(width 0)
			(type solid)
		)
		(fill yes)
		(layer "In2.Cu")
		(net "M_C_CPU0_SA_CA<3>")
	)
	(gr_poly
		(pts
			(xy 333.971138 -252.786134) (xy 333.871062 -252.686058) (xy 333.770986 -252.786134) (xy 333.770986 -252.830584)
			(xy 333.971138 -252.830584)
		)
		(stroke
			(width 0)
			(type solid)
		)
		(fill yes)
		(layer "In2.Cu")
		(net "M_C_CPU0_SA_CA<0>")
	)
	(gr_poly
		(pts
			(xy 333.971138 -252.382274) (xy 333.971138 -252.337824) (xy 333.770986 -252.337824) (xy 333.770986 -252.382274)
			(xy 333.871062 -252.48235)
		)
		(stroke
			(width 0)
			(type solid)
		)
		(fill yes)
		(layer "In2.Cu")
		(net "M_C_CPU0_SA_CS_N<1>")
	)
	(gr_poly
		(pts
			(xy 333.971138 -250.762262) (xy 333.971138 -250.717812) (xy 333.770986 -250.717812) (xy 333.770986 -250.762262)
			(xy 333.871062 -250.862338)
		)
		(stroke
			(width 0)
			(type solid)
		)
		(fill yes)
		(layer "In2.Cu")
		(net "M_C_CPU0_RESET_N")
	)
	(gr_poly
		(pts
			(xy 333.971138 -249.14225) (xy 333.971138 -249.0978) (xy 333.770986 -249.0978) (xy 333.770986 -249.14225)
			(xy 333.871062 -249.242326)
		)
		(stroke
			(width 0)
			(type solid)
		)
		(fill yes)
		(layer "In2.Cu")
		(net "M_C_CPU0_SA_CB<7>")
	)
	(gr_poly
		(pts
			(xy 333.971138 -247.926098) (xy 333.871062 -247.826022) (xy 333.770986 -247.926098) (xy 333.770986 -247.970548)
			(xy 333.971138 -247.970548)
		)
		(stroke
			(width 0)
			(type solid)
		)
		(fill yes)
		(layer "In2.Cu")
		(net "M_C_CPU0_SA_CB<4>")
	)
	(gr_poly
		(pts
			(xy 333.971138 -247.522492) (xy 333.971138 -247.47474) (xy 333.770986 -247.47474) (xy 333.770986 -247.522492)
			(xy 333.871062 -247.622314)
		)
		(stroke
			(width 0)
			(type solid)
		)
		(fill yes)
		(layer "In2.Cu")
		(net "M_C_CPU0_SA_DQS_DP<9>")
	)
	(gr_poly
		(pts
			(xy 333.971138 -246.305832) (xy 333.871062 -246.20601) (xy 333.770986 -246.305832) (xy 333.770986 -246.353584)
			(xy 333.971138 -246.353584)
		)
		(stroke
			(width 0)
			(type solid)
		)
		(fill yes)
		(layer "In2.Cu")
		(net "M_C_CPU0_SA_DQS_DP<4>")
	)
	(gr_poly
		(pts
			(xy 333.971138 -245.902226) (xy 333.971138 -245.857776) (xy 333.770986 -245.857776) (xy 333.770986 -245.902226)
			(xy 333.871062 -246.002302)
		)
		(stroke
			(width 0)
			(type solid)
		)
		(fill yes)
		(layer "In2.Cu")
		(net "M_C_CPU0_SA_CB<3>")
	)
	(gr_poly
		(pts
			(xy 333.971138 -244.686074) (xy 333.871062 -244.585998) (xy 333.770986 -244.686074) (xy 333.770986 -244.730524)
			(xy 333.971138 -244.730524)
		)
		(stroke
			(width 0)
			(type solid)
		)
		(fill yes)
		(layer "In2.Cu")
		(net "M_C_CPU0_SA_CB<0>")
	)
	(gr_poly
		(pts
			(xy 333.971138 -244.282214) (xy 333.971138 -244.237764) (xy 333.770986 -244.237764) (xy 333.770986 -244.282214)
			(xy 333.871062 -244.38229)
		)
		(stroke
			(width 0)
			(type solid)
		)
		(fill yes)
		(layer "In2.Cu")
		(net "M_C_CPU0_SA_DQ<31>")
	)
	(gr_poly
		(pts
			(xy 333.971138 -243.066062) (xy 333.871062 -242.965986) (xy 333.770986 -243.066062) (xy 333.770986 -243.110512)
			(xy 333.971138 -243.110512)
		)
		(stroke
			(width 0)
			(type solid)
		)
		(fill yes)
		(layer "In2.Cu")
		(net "M_C_CPU0_SA_DQ<28>")
	)
	(gr_poly
		(pts
			(xy 333.971138 -242.662456) (xy 333.971138 -242.614704) (xy 333.770986 -242.614704) (xy 333.770986 -242.662456)
			(xy 333.871062 -242.762278)
		)
		(stroke
			(width 0)
			(type solid)
		)
		(fill yes)
		(layer "In2.Cu")
		(net "M_C_CPU0_SA_DQS_DP<8>")
	)
	(gr_poly
		(pts
			(xy 333.971138 -241.445796) (xy 333.871062 -241.345974) (xy 333.770986 -241.445796) (xy 333.770986 -241.493548)
			(xy 333.971138 -241.493548)
		)
		(stroke
			(width 0)
			(type solid)
		)
		(fill yes)
		(layer "In2.Cu")
		(net "M_C_CPU0_SA_DQS_DP<3>")
	)
	(gr_poly
		(pts
			(xy 333.971138 -241.04219) (xy 333.971138 -240.99774) (xy 333.770986 -240.99774) (xy 333.770986 -241.04219)
			(xy 333.871062 -241.142266)
		)
		(stroke
			(width 0)
			(type solid)
		)
		(fill yes)
		(layer "In2.Cu")
		(net "M_C_CPU0_SA_DQ<27>")
	)
	(gr_poly
		(pts
			(xy 333.971138 -239.826038) (xy 333.871062 -239.725962) (xy 333.770986 -239.826038) (xy 333.770986 -239.870488)
			(xy 333.971138 -239.870488)
		)
		(stroke
			(width 0)
			(type solid)
		)
		(fill yes)
		(layer "In2.Cu")
		(net "M_C_CPU0_SA_DQ<24>")
	)
	(gr_poly
		(pts
			(xy 333.971138 -239.422178) (xy 333.971138 -239.377728) (xy 333.770986 -239.377728) (xy 333.770986 -239.422178)
			(xy 333.871062 -239.522254)
		)
		(stroke
			(width 0)
			(type solid)
		)
		(fill yes)
		(layer "In2.Cu")
		(net "M_C_CPU0_SA_DQ<23>")
	)
	(gr_poly
		(pts
			(xy 333.971138 -238.206026) (xy 333.871062 -238.10595) (xy 333.770986 -238.206026) (xy 333.770986 -238.250476)
			(xy 333.971138 -238.250476)
		)
		(stroke
			(width 0)
			(type solid)
		)
		(fill yes)
		(layer "In2.Cu")
		(net "M_C_CPU0_SA_DQ<20>")
	)
	(gr_poly
		(pts
			(xy 333.971138 -237.80242) (xy 333.971138 -237.754668) (xy 333.770986 -237.754668) (xy 333.770986 -237.80242)
			(xy 333.871062 -237.902242)
		)
		(stroke
			(width 0)
			(type solid)
		)
		(fill yes)
		(layer "In2.Cu")
		(net "M_C_CPU0_SA_DQS_DP<7>")
	)
	(gr_poly
		(pts
			(xy 333.971138 -236.58576) (xy 333.871062 -236.485938) (xy 333.770986 -236.58576) (xy 333.770986 -236.633512)
			(xy 333.971138 -236.633512)
		)
		(stroke
			(width 0)
			(type solid)
		)
		(fill yes)
		(layer "In2.Cu")
		(net "M_C_CPU0_SA_DQS_DP<2>")
	)
	(gr_poly
		(pts
			(xy 333.971138 -236.182154) (xy 333.971138 -236.137704) (xy 333.770986 -236.137704) (xy 333.770986 -236.182154)
			(xy 333.871062 -236.28223)
		)
		(stroke
			(width 0)
			(type solid)
		)
		(fill yes)
		(layer "In2.Cu")
		(net "M_C_CPU0_SA_DQ<19>")
	)
	(gr_poly
		(pts
			(xy 333.971138 -234.966002) (xy 333.871062 -234.865926) (xy 333.770986 -234.966002) (xy 333.770986 -235.010452)
			(xy 333.971138 -235.010452)
		)
		(stroke
			(width 0)
			(type solid)
		)
		(fill yes)
		(layer "In2.Cu")
		(net "M_C_CPU0_SA_DQ<16>")
	)
	(gr_poly
		(pts
			(xy 333.971138 -234.562142) (xy 333.971138 -234.517692) (xy 333.770986 -234.517692) (xy 333.770986 -234.562142)
			(xy 333.871062 -234.662218)
		)
		(stroke
			(width 0)
			(type solid)
		)
		(fill yes)
		(layer "In2.Cu")
		(net "M_C_CPU0_SA_DQ<15>")
	)
	(gr_poly
		(pts
			(xy 333.971138 -233.34599) (xy 333.871062 -233.245914) (xy 333.770986 -233.34599) (xy 333.770986 -233.39044)
			(xy 333.971138 -233.39044)
		)
		(stroke
			(width 0)
			(type solid)
		)
		(fill yes)
		(layer "In2.Cu")
		(net "M_C_CPU0_SA_DQ<12>")
	)
	(gr_poly
		(pts
			(xy 333.971138 -232.942384) (xy 333.971138 -232.894632) (xy 333.770986 -232.894632) (xy 333.770986 -232.942384)
			(xy 333.871062 -233.042206)
		)
		(stroke
			(width 0)
			(type solid)
		)
		(fill yes)
		(layer "In2.Cu")
		(net "M_C_CPU0_SA_DQS_DP<6>")
	)
	(gr_poly
		(pts
			(xy 333.971138 -231.725724) (xy 333.871062 -231.625902) (xy 333.770986 -231.725724) (xy 333.770986 -231.773476)
			(xy 333.971138 -231.773476)
		)
		(stroke
			(width 0)
			(type solid)
		)
		(fill yes)
		(layer "In2.Cu")
		(net "M_C_CPU0_SA_DQS_DP<1>")
	)
	(gr_poly
		(pts
			(xy 333.971138 -231.322372) (xy 333.971138 -231.277922) (xy 333.770986 -231.277922) (xy 333.770986 -231.322372)
			(xy 333.871062 -231.422448)
		)
		(stroke
			(width 0)
			(type solid)
		)
		(fill yes)
		(layer "In2.Cu")
		(net "M_C_CPU0_SA_DQ<11>")
	)
	(gr_poly
		(pts
			(xy 333.971138 -230.105966) (xy 333.871062 -230.006144) (xy 333.770986 -230.105966) (xy 333.770986 -230.150416)
			(xy 333.971138 -230.150416)
		)
		(stroke
			(width 0)
			(type solid)
		)
		(fill yes)
		(layer "In2.Cu")
		(net "M_C_CPU0_SA_DQ<8>")
	)
	(gr_poly
		(pts
			(xy 333.971138 -229.70236) (xy 333.971138 -229.65791) (xy 333.770986 -229.65791) (xy 333.770986 -229.70236)
			(xy 333.871062 -229.802436)
		)
		(stroke
			(width 0)
			(type solid)
		)
		(fill yes)
		(layer "In2.Cu")
		(net "M_C_CPU0_SA_DQ<7>")
	)
	(gr_poly
		(pts
			(xy 333.971138 -228.486208) (xy 333.871062 -228.386132) (xy 333.770986 -228.486208) (xy 333.770986 -228.530658)
			(xy 333.971138 -228.530658)
		)
		(stroke
			(width 0)
			(type solid)
		)
		(fill yes)
		(layer "In2.Cu")
		(net "M_C_CPU0_SA_DQ<4>")
	)
	(gr_poly
		(pts
			(xy 333.971138 -228.082602) (xy 333.971138 -228.03485) (xy 333.770986 -228.03485) (xy 333.770986 -228.082602)
			(xy 333.871062 -228.182424)
		)
		(stroke
			(width 0)
			(type solid)
		)
		(fill yes)
		(layer "In2.Cu")
		(net "M_C_CPU0_SA_DQS_DP<5>")
	)
	(gr_poly
		(pts
			(xy 333.971138 -226.865942) (xy 333.871062 -226.76612) (xy 333.770986 -226.865942) (xy 333.770986 -226.913694)
			(xy 333.971138 -226.913694)
		)
		(stroke
			(width 0)
			(type solid)
		)
		(fill yes)
		(layer "In2.Cu")
		(net "M_C_CPU0_SA_DQS_DP<0>")
	)
	(gr_poly
		(pts
			(xy 333.971138 -226.462336) (xy 333.971138 -226.417886) (xy 333.770986 -226.417886) (xy 333.770986 -226.462336)
			(xy 333.871062 -226.562412)
		)
		(stroke
			(width 0)
			(type solid)
		)
		(fill yes)
		(layer "In2.Cu")
		(net "M_C_CPU0_SA_DQ<3>")
	)
	(gr_poly
		(pts
			(xy 333.971138 -225.246184) (xy 333.871062 -225.146108) (xy 333.770986 -225.246184) (xy 333.770986 -225.290634)
			(xy 333.971138 -225.290634)
		)
		(stroke
			(width 0)
			(type solid)
		)
		(fill yes)
		(layer "In2.Cu")
		(net "M_C_CPU0_SA_DQ<0>")
	)
	(gr_poly
		(pts
			(xy 334.271112 -292.91788) (xy 334.171036 -292.817804) (xy 334.07096 -292.91788) (xy 334.07096 -292.96233)
			(xy 334.271112 -292.96233)
		)
		(stroke
			(width 0)
			(type solid)
		)
		(fill yes)
		(layer "In2.Cu")
		(net "M_C_CPU0_SB_DQ<29>")
	)
	(gr_poly
		(pts
			(xy 334.271112 -292.51402) (xy 334.271112 -292.46957) (xy 334.07096 -292.46957) (xy 334.07096 -292.51402)
			(xy 334.171036 -292.614096)
		)
		(stroke
			(width 0)
			(type solid)
		)
		(fill yes)
		(layer "In2.Cu")
		(net "M_C_CPU0_SB_DQ<30>")
	)
	(gr_poly
		(pts
			(xy 334.271112 -290.894262) (xy 334.271112 -290.84651) (xy 334.07096 -290.84651) (xy 334.07096 -290.894262)
			(xy 334.171036 -290.994084)
		)
		(stroke
			(width 0)
			(type solid)
		)
		(fill yes)
		(layer "In2.Cu")
		(net "M_C_CPU0_SB_DQS_DN<3>")
	)
	(gr_poly
		(pts
			(xy 334.271112 -289.677856) (xy 334.171036 -289.57778) (xy 334.07096 -289.677856) (xy 334.07096 -289.722306)
			(xy 334.271112 -289.722306)
		)
		(stroke
			(width 0)
			(type solid)
		)
		(fill yes)
		(layer "In2.Cu")
		(net "M_C_CPU0_SB_DQ<25>")
	)
	(gr_poly
		(pts
			(xy 334.271112 -289.273996) (xy 334.271112 -289.229546) (xy 334.07096 -289.229546) (xy 334.07096 -289.273996)
			(xy 334.171036 -289.374072)
		)
		(stroke
			(width 0)
			(type solid)
		)
		(fill yes)
		(layer "In2.Cu")
		(net "M_C_CPU0_SB_DQ<26>")
	)
	(gr_poly
		(pts
			(xy 334.271112 -288.057844) (xy 334.171036 -287.957768) (xy 334.07096 -288.057844) (xy 334.07096 -288.102294)
			(xy 334.271112 -288.102294)
		)
		(stroke
			(width 0)
			(type solid)
		)
		(fill yes)
		(layer "In2.Cu")
		(net "M_C_CPU0_SB_DQ<21>")
	)
	(gr_poly
		(pts
			(xy 334.271112 -287.654238) (xy 334.271112 -287.609788) (xy 334.07096 -287.609788) (xy 334.07096 -287.654238)
			(xy 334.171036 -287.75406)
		)
		(stroke
			(width 0)
			(type solid)
		)
		(fill yes)
		(layer "In2.Cu")
		(net "M_C_CPU0_SB_DQ<22>")
	)
	(gr_poly
		(pts
			(xy 334.271112 -286.437832) (xy 334.171036 -286.337756) (xy 334.07096 -286.437832) (xy 334.07096 -286.485584)
			(xy 334.271112 -286.485584)
		)
		(stroke
			(width 0)
			(type solid)
		)
		(fill yes)
		(layer "In2.Cu")
		(net "M_C_CPU0_SB_DQS_DN<7>")
	)
	(gr_poly
		(pts
			(xy 334.271112 -286.03448) (xy 334.271112 -285.986728) (xy 334.07096 -285.986728) (xy 334.07096 -286.03448)
			(xy 334.171036 -286.134302)
		)
		(stroke
			(width 0)
			(type solid)
		)
		(fill yes)
		(layer "In2.Cu")
		(net "M_C_CPU0_SB_DQS_DN<2>")
	)
	(gr_poly
		(pts
			(xy 334.271112 -284.818074) (xy 334.171036 -284.717998) (xy 334.07096 -284.818074) (xy 334.07096 -284.862524)
			(xy 334.271112 -284.862524)
		)
		(stroke
			(width 0)
			(type solid)
		)
		(fill yes)
		(layer "In2.Cu")
		(net "M_C_CPU0_SB_DQ<17>")
	)
	(gr_poly
		(pts
			(xy 334.271112 -284.414214) (xy 334.271112 -284.369764) (xy 334.07096 -284.369764) (xy 334.07096 -284.414214)
			(xy 334.171036 -284.51429)
		)
		(stroke
			(width 0)
			(type solid)
		)
		(fill yes)
		(layer "In2.Cu")
		(net "M_C_CPU0_SB_DQ<18>")
	)
	(gr_poly
		(pts
			(xy 334.271112 -283.198062) (xy 334.171036 -283.097986) (xy 334.07096 -283.198062) (xy 334.07096 -283.242512)
			(xy 334.271112 -283.242512)
		)
		(stroke
			(width 0)
			(type solid)
		)
		(fill yes)
		(layer "In2.Cu")
		(net "M_C_CPU0_SB_DQ<13>")
	)
	(gr_poly
		(pts
			(xy 334.271112 -282.794202) (xy 334.271112 -282.749752) (xy 334.07096 -282.749752) (xy 334.07096 -282.794202)
			(xy 334.171036 -282.894278)
		)
		(stroke
			(width 0)
			(type solid)
		)
		(fill yes)
		(layer "In2.Cu")
		(net "M_C_CPU0_SB_DQ<14>")
	)
	(gr_poly
		(pts
			(xy 334.271112 -281.577796) (xy 334.171036 -281.477974) (xy 334.07096 -281.577796) (xy 334.07096 -281.625548)
			(xy 334.271112 -281.625548)
		)
		(stroke
			(width 0)
			(type solid)
		)
		(fill yes)
		(layer "In2.Cu")
		(net "M_C_CPU0_SB_DQS_DN<6>")
	)
	(gr_poly
		(pts
			(xy 334.271112 -281.174444) (xy 334.271112 -281.126692) (xy 334.07096 -281.126692) (xy 334.07096 -281.174444)
			(xy 334.171036 -281.274266)
		)
		(stroke
			(width 0)
			(type solid)
		)
		(fill yes)
		(layer "In2.Cu")
		(net "M_C_CPU0_SB_DQS_DN<1>")
	)
	(gr_poly
		(pts
			(xy 334.271112 -279.958038) (xy 334.171036 -279.857962) (xy 334.07096 -279.958038) (xy 334.07096 -280.002488)
			(xy 334.271112 -280.002488)
		)
		(stroke
			(width 0)
			(type solid)
		)
		(fill yes)
		(layer "In2.Cu")
		(net "M_C_CPU0_SB_DQ<9>")
	)
	(gr_poly
		(pts
			(xy 334.271112 -279.554178) (xy 334.271112 -279.509728) (xy 334.07096 -279.509728) (xy 334.07096 -279.554178)
			(xy 334.171036 -279.654254)
		)
		(stroke
			(width 0)
			(type solid)
		)
		(fill yes)
		(layer "In2.Cu")
		(net "M_C_CPU0_SB_DQ<10>")
	)
	(gr_poly
		(pts
			(xy 334.271112 -278.338026) (xy 334.171036 -278.23795) (xy 334.07096 -278.338026) (xy 334.07096 -278.382476)
			(xy 334.271112 -278.382476)
		)
		(stroke
			(width 0)
			(type solid)
		)
		(fill yes)
		(layer "In2.Cu")
		(net "M_C_CPU0_SB_DQ<5>")
	)
	(gr_poly
		(pts
			(xy 334.271112 -277.934166) (xy 334.271112 -277.889716) (xy 334.07096 -277.889716) (xy 334.07096 -277.934166)
			(xy 334.171036 -278.034242)
		)
		(stroke
			(width 0)
			(type solid)
		)
		(fill yes)
		(layer "In2.Cu")
		(net "M_C_CPU0_SB_DQ<6>")
	)
	(gr_poly
		(pts
			(xy 334.271112 -276.71776) (xy 334.171036 -276.617938) (xy 334.07096 -276.71776) (xy 334.07096 -276.765512)
			(xy 334.271112 -276.765512)
		)
		(stroke
			(width 0)
			(type solid)
		)
		(fill yes)
		(layer "In2.Cu")
		(net "M_C_CPU0_SB_DQS_DN<5>")
	)
	(gr_poly
		(pts
			(xy 334.271112 -276.314408) (xy 334.271112 -276.266656) (xy 334.07096 -276.266656) (xy 334.07096 -276.314408)
			(xy 334.171036 -276.41423)
		)
		(stroke
			(width 0)
			(type solid)
		)
		(fill yes)
		(layer "In2.Cu")
		(net "M_C_CPU0_SB_DQS_DN<0>")
	)
	(gr_poly
		(pts
			(xy 334.271112 -275.098002) (xy 334.171036 -274.997926) (xy 334.07096 -275.098002) (xy 334.07096 -275.142452)
			(xy 334.271112 -275.142452)
		)
		(stroke
			(width 0)
			(type solid)
		)
		(fill yes)
		(layer "In2.Cu")
		(net "M_C_CPU0_SB_DQ<1>")
	)
	(gr_poly
		(pts
			(xy 334.271112 -274.694142) (xy 334.271112 -274.649692) (xy 334.07096 -274.649692) (xy 334.07096 -274.694142)
			(xy 334.171036 -274.794218)
		)
		(stroke
			(width 0)
			(type solid)
		)
		(fill yes)
		(layer "In2.Cu")
		(net "M_C_CPU0_SB_DQ<2>")
	)
	(gr_poly
		(pts
			(xy 334.271112 -273.47799) (xy 334.171036 -273.377914) (xy 334.07096 -273.47799) (xy 334.07096 -273.52244)
			(xy 334.271112 -273.52244)
		)
		(stroke
			(width 0)
			(type solid)
		)
		(fill yes)
		(layer "In2.Cu")
		(net "M_C_CPU0_SB_CB<1>")
	)
	(gr_poly
		(pts
			(xy 334.271112 -273.07413) (xy 334.271112 -273.02968) (xy 334.07096 -273.02968) (xy 334.07096 -273.07413)
			(xy 334.171036 -273.174206)
		)
		(stroke
			(width 0)
			(type solid)
		)
		(fill yes)
		(layer "In2.Cu")
		(net "M_C_CPU0_SB_CB<2>")
	)
	(gr_poly
		(pts
			(xy 334.271112 -271.857724) (xy 334.171036 -271.757902) (xy 334.07096 -271.857724) (xy 334.07096 -271.905476)
			(xy 334.271112 -271.905476)
		)
		(stroke
			(width 0)
			(type solid)
		)
		(fill yes)
		(layer "In2.Cu")
		(net "M_C_CPU0_SB_DQS_DN<4>")
	)
	(gr_poly
		(pts
			(xy 334.271112 -271.454372) (xy 334.271112 -271.40662) (xy 334.07096 -271.40662) (xy 334.07096 -271.454372)
			(xy 334.171036 -271.554194)
		)
		(stroke
			(width 0)
			(type solid)
		)
		(fill yes)
		(layer "In2.Cu")
		(net "M_C_CPU0_SB_DQS_DN<9>")
	)
	(gr_poly
		(pts
			(xy 334.271112 -270.237966) (xy 334.171036 -270.13789) (xy 334.07096 -270.237966) (xy 334.07096 -270.282416)
			(xy 334.271112 -270.282416)
		)
		(stroke
			(width 0)
			(type solid)
		)
		(fill yes)
		(layer "In2.Cu")
		(net "M_C_CPU0_SB_CB<5>")
	)
	(gr_poly
		(pts
			(xy 334.271112 -269.834106) (xy 334.271112 -269.789656) (xy 334.07096 -269.789656) (xy 334.07096 -269.834106)
			(xy 334.171036 -269.934182)
		)
		(stroke
			(width 0)
			(type solid)
		)
		(fill yes)
		(layer "In2.Cu")
		(net "M_C_CPU0_SB_CB<6>")
	)
	(gr_poly
		(pts
			(xy 334.271112 -266.594082) (xy 334.271112 -266.549632) (xy 334.07096 -266.549632) (xy 334.07096 -266.594082)
			(xy 334.171036 -266.694158)
		)
		(stroke
			(width 0)
			(type solid)
		)
		(fill yes)
		(layer "In2.Cu")
		(net "M_C_CPU0_SB_CS_N<1>")
	)
	(gr_poly
		(pts
			(xy 334.271112 -264.97407) (xy 334.271112 -264.92962) (xy 334.07096 -264.92962) (xy 334.07096 -264.97407)
			(xy 334.171036 -265.074146)
		)
		(stroke
			(width 0)
			(type solid)
		)
		(fill yes)
		(layer "In2.Cu")
		(net "M_C_CPU0_SB_PAR")
	)
	(gr_poly
		(pts
			(xy 334.271112 -263.757918) (xy 334.171036 -263.657842) (xy 334.07096 -263.757918) (xy 334.07096 -263.802368)
			(xy 334.271112 -263.802368)
		)
		(stroke
			(width 0)
			(type solid)
		)
		(fill yes)
		(layer "In2.Cu")
		(net "M_C_CPU0_SB_CA<4>")
	)
	(gr_poly
		(pts
			(xy 334.271112 -263.354058) (xy 334.271112 -263.309608) (xy 334.07096 -263.309608) (xy 334.07096 -263.354058)
			(xy 334.171036 -263.454134)
		)
		(stroke
			(width 0)
			(type solid)
		)
		(fill yes)
		(layer "In2.Cu")
		(net "M_C_CPU0_SB_CA<3>")
	)
	(gr_poly
		(pts
			(xy 334.271112 -262.137906) (xy 334.171036 -262.03783) (xy 334.07096 -262.137906) (xy 334.07096 -262.182356)
			(xy 334.271112 -262.182356)
		)
		(stroke
			(width 0)
			(type solid)
		)
		(fill yes)
		(layer "In2.Cu")
		(net "M_C_CPU0_SB_CA<0>")
	)
	(gr_poly
		(pts
			(xy 334.277208 -266.991592) (xy 334.177386 -266.891516) (xy 334.07731 -266.991592) (xy 334.07731 -267.036042)
			(xy 334.277208 -267.036042)
		)
		(stroke
			(width 0)
			(type solid)
		)
		(fill yes)
		(layer "In2.Cu")
		(net "M_C_CPU0_SA_RSP<0>")
	)
	(gr_poly
		(pts
			(xy 334.278478 -291.297614) (xy 334.178402 -291.197792) (xy 334.078326 -291.297614) (xy 334.078326 -291.345366)
			(xy 334.278478 -291.345366)
		)
		(stroke
			(width 0)
			(type solid)
		)
		(fill yes)
		(layer "In2.Cu")
		(net "M_C_CPU0_SB_DQS_DN<8>")
	)
	(gr_poly
		(pts
			(xy 334.441038 -246.712232) (xy 334.441038 -246.664734) (xy 334.24114 -246.664734) (xy 334.24114 -246.712232)
			(xy 334.340962 -246.812308)
		)
		(stroke
			(width 0)
			(type solid)
		)
		(fill yes)
		(layer "In2.Cu")
		(net "M_C_CPU0_SA_DQS_DN<4>")
	)
	(gr_poly
		(pts
			(xy 334.441292 -256.432558) (xy 334.441292 -256.384806) (xy 334.24114 -256.384806) (xy 334.24114 -256.432558)
			(xy 334.341216 -256.53238)
		)
		(stroke
			(width 0)
			(type solid)
		)
		(fill yes)
		(layer "In2.Cu")
		(net "M_C_CPU0_CLK_DN<0>")
	)
	(gr_poly
		(pts
			(xy 334.441292 -255.216152) (xy 334.341216 -255.116076) (xy 334.24114 -255.216152) (xy 334.24114 -255.260602)
			(xy 334.441292 -255.260602)
		)
		(stroke
			(width 0)
			(type solid)
		)
		(fill yes)
		(layer "In2.Cu")
		(net "M_C_CPU0_SA_CA<6>")
	)
	(gr_poly
		(pts
			(xy 334.441292 -254.812292) (xy 334.441292 -254.767842) (xy 334.24114 -254.767842) (xy 334.24114 -254.812292)
			(xy 334.341216 -254.912368)
		)
		(stroke
			(width 0)
			(type solid)
		)
		(fill yes)
		(layer "In2.Cu")
		(net "M_C_CPU0_SA_CA<5>")
	)
	(gr_poly
		(pts
			(xy 334.441292 -253.59614) (xy 334.341216 -253.496064) (xy 334.24114 -253.59614) (xy 334.24114 -253.64059)
			(xy 334.441292 -253.64059)
		)
		(stroke
			(width 0)
			(type solid)
		)
		(fill yes)
		(layer "In2.Cu")
		(net "M_C_CPU0_SA_CA<2>")
	)
	(gr_poly
		(pts
			(xy 334.441292 -253.19228) (xy 334.441292 -253.14783) (xy 334.24114 -253.14783) (xy 334.24114 -253.19228)
			(xy 334.341216 -253.292356)
		)
		(stroke
			(width 0)
			(type solid)
		)
		(fill yes)
		(layer "In2.Cu")
		(net "M_C_CPU0_SA_CA<1>")
	)
	(gr_poly
		(pts
			(xy 334.441292 -251.572268) (xy 334.441292 -251.527818) (xy 334.24114 -251.527818) (xy 334.24114 -251.572268)
			(xy 334.341216 -251.672344)
		)
		(stroke
			(width 0)
			(type solid)
		)
		(fill yes)
		(layer "In2.Cu")
		(net "M_C_CPU0_SA_CS_N<0>")
	)
	(gr_poly
		(pts
			(xy 334.441292 -250.356116) (xy 334.341216 -250.25604) (xy 334.24114 -250.356116) (xy 334.24114 -250.400566)
			(xy 334.441292 -250.400566)
		)
		(stroke
			(width 0)
			(type solid)
		)
		(fill yes)
		(layer "In2.Cu")
		(net "M_C_CPU0_ALERT_R_N")
	)
	(gr_poly
		(pts
			(xy 334.441292 -248.736104) (xy 334.341216 -248.636028) (xy 334.24114 -248.736104) (xy 334.24114 -248.780554)
			(xy 334.441292 -248.780554)
		)
		(stroke
			(width 0)
			(type solid)
		)
		(fill yes)
		(layer "In2.Cu")
		(net "M_C_CPU0_SA_CB<5>")
	)
	(gr_poly
		(pts
			(xy 334.441292 -248.332244) (xy 334.441292 -248.287794) (xy 334.24114 -248.287794) (xy 334.24114 -248.332244)
			(xy 334.341216 -248.43232)
		)
		(stroke
			(width 0)
			(type solid)
		)
		(fill yes)
		(layer "In2.Cu")
		(net "M_C_CPU0_SA_CB<6>")
	)
	(gr_poly
		(pts
			(xy 334.441292 -247.115838) (xy 334.341216 -247.016016) (xy 334.24114 -247.115838) (xy 334.24114 -247.16359)
			(xy 334.441292 -247.16359)
		)
		(stroke
			(width 0)
			(type solid)
		)
		(fill yes)
		(layer "In2.Cu")
		(net "M_C_CPU0_SA_DQS_DN<9>")
	)
	(gr_poly
		(pts
			(xy 334.441292 -245.49608) (xy 334.341216 -245.396004) (xy 334.24114 -245.49608) (xy 334.24114 -245.54053)
			(xy 334.441292 -245.54053)
		)
		(stroke
			(width 0)
			(type solid)
		)
		(fill yes)
		(layer "In2.Cu")
		(net "M_C_CPU0_SA_CB<1>")
	)
	(gr_poly
		(pts
			(xy 334.441292 -245.09222) (xy 334.441292 -245.04777) (xy 334.24114 -245.04777) (xy 334.24114 -245.09222)
			(xy 334.341216 -245.192296)
		)
		(stroke
			(width 0)
			(type solid)
		)
		(fill yes)
		(layer "In2.Cu")
		(net "M_C_CPU0_SA_CB<2>")
	)
	(gr_poly
		(pts
			(xy 334.441292 -243.876068) (xy 334.341216 -243.775992) (xy 334.24114 -243.876068) (xy 334.24114 -243.920518)
			(xy 334.441292 -243.920518)
		)
		(stroke
			(width 0)
			(type solid)
		)
		(fill yes)
		(layer "In2.Cu")
		(net "M_C_CPU0_SA_DQ<29>")
	)
	(gr_poly
		(pts
			(xy 334.441292 -243.472208) (xy 334.441292 -243.427758) (xy 334.24114 -243.427758) (xy 334.24114 -243.472208)
			(xy 334.341216 -243.572284)
		)
		(stroke
			(width 0)
			(type solid)
		)
		(fill yes)
		(layer "In2.Cu")
		(net "M_C_CPU0_SA_DQ<30>")
	)
	(gr_poly
		(pts
			(xy 334.441292 -242.255802) (xy 334.341216 -242.15598) (xy 334.24114 -242.255802) (xy 334.24114 -242.303554)
			(xy 334.441292 -242.303554)
		)
		(stroke
			(width 0)
			(type solid)
		)
		(fill yes)
		(layer "In2.Cu")
		(net "M_C_CPU0_SA_DQS_DN<8>")
	)
	(gr_poly
		(pts
			(xy 334.441292 -241.85245) (xy 334.441292 -241.804698) (xy 334.24114 -241.804698) (xy 334.24114 -241.85245)
			(xy 334.341216 -241.952272)
		)
		(stroke
			(width 0)
			(type solid)
		)
		(fill yes)
		(layer "In2.Cu")
		(net "M_C_CPU0_SA_DQS_DN<3>")
	)
	(gr_poly
		(pts
			(xy 334.441292 -240.636044) (xy 334.341216 -240.535968) (xy 334.24114 -240.636044) (xy 334.24114 -240.680494)
			(xy 334.441292 -240.680494)
		)
		(stroke
			(width 0)
			(type solid)
		)
		(fill yes)
		(layer "In2.Cu")
		(net "M_C_CPU0_SA_DQ<25>")
	)
	(gr_poly
		(pts
			(xy 334.441292 -240.232184) (xy 334.441292 -240.187734) (xy 334.24114 -240.187734) (xy 334.24114 -240.232184)
			(xy 334.341216 -240.33226)
		)
		(stroke
			(width 0)
			(type solid)
		)
		(fill yes)
		(layer "In2.Cu")
		(net "M_C_CPU0_SA_DQ<26>")
	)
	(gr_poly
		(pts
			(xy 334.441292 -239.016032) (xy 334.341216 -238.915956) (xy 334.24114 -239.016032) (xy 334.24114 -239.060482)
			(xy 334.441292 -239.060482)
		)
		(stroke
			(width 0)
			(type solid)
		)
		(fill yes)
		(layer "In2.Cu")
		(net "M_C_CPU0_SA_DQ<21>")
	)
	(gr_poly
		(pts
			(xy 334.441292 -238.612172) (xy 334.441292 -238.567722) (xy 334.24114 -238.567722) (xy 334.24114 -238.612172)
			(xy 334.341216 -238.712248)
		)
		(stroke
			(width 0)
			(type solid)
		)
		(fill yes)
		(layer "In2.Cu")
		(net "M_C_CPU0_SA_DQ<22>")
	)
	(gr_poly
		(pts
			(xy 334.441292 -237.395766) (xy 334.341216 -237.295944) (xy 334.24114 -237.395766) (xy 334.24114 -237.443518)
			(xy 334.441292 -237.443518)
		)
		(stroke
			(width 0)
			(type solid)
		)
		(fill yes)
		(layer "In2.Cu")
		(net "M_C_CPU0_SA_DQS_DN<7>")
	)
	(gr_poly
		(pts
			(xy 334.441292 -236.992414) (xy 334.441292 -236.944662) (xy 334.24114 -236.944662) (xy 334.24114 -236.992414)
			(xy 334.341216 -237.092236)
		)
		(stroke
			(width 0)
			(type solid)
		)
		(fill yes)
		(layer "In2.Cu")
		(net "M_C_CPU0_SA_DQS_DN<2>")
	)
	(gr_poly
		(pts
			(xy 334.441292 -235.776008) (xy 334.341216 -235.675932) (xy 334.24114 -235.776008) (xy 334.24114 -235.820458)
			(xy 334.441292 -235.820458)
		)
		(stroke
			(width 0)
			(type solid)
		)
		(fill yes)
		(layer "In2.Cu")
		(net "M_C_CPU0_SA_DQ<17>")
	)
	(gr_poly
		(pts
			(xy 334.441292 -235.372148) (xy 334.441292 -235.327698) (xy 334.24114 -235.327698) (xy 334.24114 -235.372148)
			(xy 334.341216 -235.472224)
		)
		(stroke
			(width 0)
			(type solid)
		)
		(fill yes)
		(layer "In2.Cu")
		(net "M_C_CPU0_SA_DQ<18>")
	)
	(gr_poly
		(pts
			(xy 334.441292 -234.155996) (xy 334.341216 -234.05592) (xy 334.24114 -234.155996) (xy 334.24114 -234.200446)
			(xy 334.441292 -234.200446)
		)
		(stroke
			(width 0)
			(type solid)
		)
		(fill yes)
		(layer "In2.Cu")
		(net "M_C_CPU0_SA_DQ<13>")
	)
	(gr_poly
		(pts
			(xy 334.441292 -233.752136) (xy 334.441292 -233.707686) (xy 334.24114 -233.707686) (xy 334.24114 -233.752136)
			(xy 334.341216 -233.852212)
		)
		(stroke
			(width 0)
			(type solid)
		)
		(fill yes)
		(layer "In2.Cu")
		(net "M_C_CPU0_SA_DQ<14>")
	)
	(gr_poly
		(pts
			(xy 334.441292 -232.53573) (xy 334.341216 -232.435908) (xy 334.24114 -232.53573) (xy 334.24114 -232.583482)
			(xy 334.441292 -232.583482)
		)
		(stroke
			(width 0)
			(type solid)
		)
		(fill yes)
		(layer "In2.Cu")
		(net "M_C_CPU0_SA_DQS_DN<6>")
	)
	(gr_poly
		(pts
			(xy 334.441292 -232.132378) (xy 334.441292 -232.084626) (xy 334.24114 -232.084626) (xy 334.24114 -232.132378)
			(xy 334.341216 -232.2322)
		)
		(stroke
			(width 0)
			(type solid)
		)
		(fill yes)
		(layer "In2.Cu")
		(net "M_C_CPU0_SA_DQS_DN<1>")
	)
	(gr_poly
		(pts
			(xy 334.441292 -230.915972) (xy 334.341216 -230.815896) (xy 334.24114 -230.915972) (xy 334.24114 -230.960422)
			(xy 334.441292 -230.960422)
		)
		(stroke
			(width 0)
			(type solid)
		)
		(fill yes)
		(layer "In2.Cu")
		(net "M_C_CPU0_SA_DQ<9>")
	)
	(gr_poly
		(pts
			(xy 334.441292 -230.512366) (xy 334.441292 -230.467916) (xy 334.24114 -230.467916) (xy 334.24114 -230.512366)
			(xy 334.341216 -230.612188)
		)
		(stroke
			(width 0)
			(type solid)
		)
		(fill yes)
		(layer "In2.Cu")
		(net "M_C_CPU0_SA_DQ<10>")
	)
	(gr_poly
		(pts
			(xy 334.441292 -229.29596) (xy 334.341216 -229.195884) (xy 334.24114 -229.29596) (xy 334.24114 -229.34041)
			(xy 334.441292 -229.34041)
		)
		(stroke
			(width 0)
			(type solid)
		)
		(fill yes)
		(layer "In2.Cu")
		(net "M_C_CPU0_SA_DQ<5>")
	)
	(gr_poly
		(pts
			(xy 334.441292 -228.892354) (xy 334.441292 -228.847904) (xy 334.24114 -228.847904) (xy 334.24114 -228.892354)
			(xy 334.341216 -228.99243)
		)
		(stroke
			(width 0)
			(type solid)
		)
		(fill yes)
		(layer "In2.Cu")
		(net "M_C_CPU0_SA_DQ<6>")
	)
	(gr_poly
		(pts
			(xy 334.441292 -227.675948) (xy 334.341216 -227.576126) (xy 334.24114 -227.675948) (xy 334.24114 -227.7237)
			(xy 334.441292 -227.7237)
		)
		(stroke
			(width 0)
			(type solid)
		)
		(fill yes)
		(layer "In2.Cu")
		(net "M_C_CPU0_SA_DQS_DN<5>")
	)
	(gr_poly
		(pts
			(xy 334.441292 -227.272596) (xy 334.441292 -227.224844) (xy 334.24114 -227.224844) (xy 334.24114 -227.272596)
			(xy 334.341216 -227.372418)
		)
		(stroke
			(width 0)
			(type solid)
		)
		(fill yes)
		(layer "In2.Cu")
		(net "M_C_CPU0_SA_DQS_DN<0>")
	)
	(gr_poly
		(pts
			(xy 334.441292 -226.05619) (xy 334.341216 -225.956114) (xy 334.24114 -226.05619) (xy 334.24114 -226.10064)
			(xy 334.441292 -226.10064)
		)
		(stroke
			(width 0)
			(type solid)
		)
		(fill yes)
		(layer "In2.Cu")
		(net "M_C_CPU0_SA_DQ<1>")
	)
	(gr_poly
		(pts
			(xy 334.441292 -225.65233) (xy 334.441292 -225.60788) (xy 334.24114 -225.60788) (xy 334.24114 -225.65233)
			(xy 334.341216 -225.752406)
		)
		(stroke
			(width 0)
			(type solid)
		)
		(fill yes)
		(layer "In2.Cu")
		(net "M_C_CPU0_SA_DQ<2>")
	)
	(gr_poly
		(pts
			(xy 334.7339 -291.704268) (xy 334.7339 -291.656516) (xy 334.533748 -291.656516) (xy 334.533748 -291.704268)
			(xy 334.633824 -291.80409)
		)
		(stroke
			(width 0)
			(type solid)
		)
		(fill yes)
		(layer "In2.Cu")
		(net "M_C_CPU0_SB_DQS_DP<8>")
	)
	(gr_poly
		(pts
			(xy 334.734916 -267.801598) (xy 334.63484 -267.701522) (xy 334.535018 -267.801598) (xy 334.535018 -267.846048)
			(xy 334.734916 -267.846048)
		)
		(stroke
			(width 0)
			(type solid)
		)
		(fill yes)
		(layer "In2.Cu")
		(net "M_C_CPU0_SB_RSP<0>")
	)
	(gr_poly
		(pts
			(xy 334.741266 -293.324026) (xy 334.741266 -293.279576) (xy 334.541114 -293.279576) (xy 334.541114 -293.324026)
			(xy 334.64119 -293.424102)
		)
		(stroke
			(width 0)
			(type solid)
		)
		(fill yes)
		(layer "In2.Cu")
		(net "M_C_CPU0_SB_DQ<31>")
	)
	(gr_poly
		(pts
			(xy 334.741266 -292.107874) (xy 334.64119 -292.007798) (xy 334.541114 -292.107874) (xy 334.541114 -292.152324)
			(xy 334.741266 -292.152324)
		)
		(stroke
			(width 0)
			(type solid)
		)
		(fill yes)
		(layer "In2.Cu")
		(net "M_C_CPU0_SB_DQ<28>")
	)
	(gr_poly
		(pts
			(xy 334.741266 -290.487608) (xy 334.64119 -290.387786) (xy 334.541114 -290.487608) (xy 334.541114 -290.53536)
			(xy 334.741266 -290.53536)
		)
		(stroke
			(width 0)
			(type solid)
		)
		(fill yes)
		(layer "In2.Cu")
		(net "M_C_CPU0_SB_DQS_DP<3>")
	)
	(gr_poly
		(pts
			(xy 334.741266 -290.084002) (xy 334.741266 -290.039552) (xy 334.541114 -290.039552) (xy 334.541114 -290.084002)
			(xy 334.64119 -290.184078)
		)
		(stroke
			(width 0)
			(type solid)
		)
		(fill yes)
		(layer "In2.Cu")
		(net "M_C_CPU0_SB_DQ<27>")
	)
	(gr_poly
		(pts
			(xy 334.741266 -288.86785) (xy 334.64119 -288.767774) (xy 334.541114 -288.86785) (xy 334.541114 -288.9123)
			(xy 334.741266 -288.9123)
		)
		(stroke
			(width 0)
			(type solid)
		)
		(fill yes)
		(layer "In2.Cu")
		(net "M_C_CPU0_SB_DQ<24>")
	)
	(gr_poly
		(pts
			(xy 334.741266 -288.464244) (xy 334.741266 -288.419794) (xy 334.541114 -288.419794) (xy 334.541114 -288.464244)
			(xy 334.64119 -288.56432)
		)
		(stroke
			(width 0)
			(type solid)
		)
		(fill yes)
		(layer "In2.Cu")
		(net "M_C_CPU0_SB_DQ<23>")
	)
	(gr_poly
		(pts
			(xy 334.741266 -287.247838) (xy 334.64119 -287.148016) (xy 334.541114 -287.247838) (xy 334.541114 -287.292288)
			(xy 334.741266 -287.292288)
		)
		(stroke
			(width 0)
			(type solid)
		)
		(fill yes)
		(layer "In2.Cu")
		(net "M_C_CPU0_SB_DQ<20>")
	)
	(gr_poly
		(pts
			(xy 334.741266 -286.844232) (xy 334.741266 -286.79648) (xy 334.541114 -286.79648) (xy 334.541114 -286.844232)
			(xy 334.64119 -286.944308)
		)
		(stroke
			(width 0)
			(type solid)
		)
		(fill yes)
		(layer "In2.Cu")
		(net "M_C_CPU0_SB_DQS_DP<7>")
	)
	(gr_poly
		(pts
			(xy 334.741266 -285.627826) (xy 334.64119 -285.528004) (xy 334.541114 -285.627826) (xy 334.541114 -285.675578)
			(xy 334.741266 -285.675578)
		)
		(stroke
			(width 0)
			(type solid)
		)
		(fill yes)
		(layer "In2.Cu")
		(net "M_C_CPU0_SB_DQS_DP<2>")
	)
	(gr_poly
		(pts
			(xy 334.741266 -285.22422) (xy 334.741266 -285.17977) (xy 334.541114 -285.17977) (xy 334.541114 -285.22422)
			(xy 334.64119 -285.324296)
		)
		(stroke
			(width 0)
			(type solid)
		)
		(fill yes)
		(layer "In2.Cu")
		(net "M_C_CPU0_SB_DQ<19>")
	)
	(gr_poly
		(pts
			(xy 334.741266 -284.008068) (xy 334.64119 -283.907992) (xy 334.541114 -284.008068) (xy 334.541114 -284.052518)
			(xy 334.741266 -284.052518)
		)
		(stroke
			(width 0)
			(type solid)
		)
		(fill yes)
		(layer "In2.Cu")
		(net "M_C_CPU0_SB_DQ<16>")
	)
	(gr_poly
		(pts
			(xy 334.741266 -283.604208) (xy 334.741266 -283.559758) (xy 334.541114 -283.559758) (xy 334.541114 -283.604208)
			(xy 334.64119 -283.704284)
		)
		(stroke
			(width 0)
			(type solid)
		)
		(fill yes)
		(layer "In2.Cu")
		(net "M_C_CPU0_SB_DQ<15>")
	)
	(gr_poly
		(pts
			(xy 334.741266 -282.388056) (xy 334.64119 -282.28798) (xy 334.541114 -282.388056) (xy 334.541114 -282.432506)
			(xy 334.741266 -282.432506)
		)
		(stroke
			(width 0)
			(type solid)
		)
		(fill yes)
		(layer "In2.Cu")
		(net "M_C_CPU0_SB_DQ<12>")
	)
	(gr_poly
		(pts
			(xy 334.741266 -281.98445) (xy 334.741266 -281.936698) (xy 334.541114 -281.936698) (xy 334.541114 -281.98445)
			(xy 334.64119 -282.084272)
		)
		(stroke
			(width 0)
			(type solid)
		)
		(fill yes)
		(layer "In2.Cu")
		(net "M_C_CPU0_SB_DQS_DP<6>")
	)
	(gr_poly
		(pts
			(xy 334.741266 -280.76779) (xy 334.64119 -280.667968) (xy 334.541114 -280.76779) (xy 334.541114 -280.815542)
			(xy 334.741266 -280.815542)
		)
		(stroke
			(width 0)
			(type solid)
		)
		(fill yes)
		(layer "In2.Cu")
		(net "M_C_CPU0_SB_DQS_DP<1>")
	)
	(gr_poly
		(pts
			(xy 334.741266 -280.364184) (xy 334.741266 -280.319734) (xy 334.541114 -280.319734) (xy 334.541114 -280.364184)
			(xy 334.64119 -280.46426)
		)
		(stroke
			(width 0)
			(type solid)
		)
		(fill yes)
		(layer "In2.Cu")
		(net "M_C_CPU0_SB_DQ<11>")
	)
	(gr_poly
		(pts
			(xy 334.741266 -279.148032) (xy 334.64119 -279.047956) (xy 334.541114 -279.148032) (xy 334.541114 -279.192482)
			(xy 334.741266 -279.192482)
		)
		(stroke
			(width 0)
			(type solid)
		)
		(fill yes)
		(layer "In2.Cu")
		(net "M_C_CPU0_SB_DQ<8>")
	)
	(gr_poly
		(pts
			(xy 334.741266 -278.744172) (xy 334.741266 -278.699722) (xy 334.541114 -278.699722) (xy 334.541114 -278.744172)
			(xy 334.64119 -278.844248)
		)
		(stroke
			(width 0)
			(type solid)
		)
		(fill yes)
		(layer "In2.Cu")
		(net "M_C_CPU0_SB_DQ<7>")
	)
	(gr_poly
		(pts
			(xy 334.741266 -277.52802) (xy 334.64119 -277.427944) (xy 334.541114 -277.52802) (xy 334.541114 -277.57247)
			(xy 334.741266 -277.57247)
		)
		(stroke
			(width 0)
			(type solid)
		)
		(fill yes)
		(layer "In2.Cu")
		(net "M_C_CPU0_SB_DQ<4>")
	)
	(gr_poly
		(pts
			(xy 334.741266 -277.124414) (xy 334.741266 -277.076662) (xy 334.541114 -277.076662) (xy 334.541114 -277.124414)
			(xy 334.64119 -277.224236)
		)
		(stroke
			(width 0)
			(type solid)
		)
		(fill yes)
		(layer "In2.Cu")
		(net "M_C_CPU0_SB_DQS_DP<5>")
	)
	(gr_poly
		(pts
			(xy 334.741266 -275.907754) (xy 334.64119 -275.807932) (xy 334.541114 -275.907754) (xy 334.541114 -275.955506)
			(xy 334.741266 -275.955506)
		)
		(stroke
			(width 0)
			(type solid)
		)
		(fill yes)
		(layer "In2.Cu")
		(net "M_C_CPU0_SB_DQS_DP<0>")
	)
	(gr_poly
		(pts
			(xy 334.741266 -275.504148) (xy 334.741266 -275.459698) (xy 334.541114 -275.459698) (xy 334.541114 -275.504148)
			(xy 334.64119 -275.604224)
		)
		(stroke
			(width 0)
			(type solid)
		)
		(fill yes)
		(layer "In2.Cu")
		(net "M_C_CPU0_SB_DQ<3>")
	)
	(gr_poly
		(pts
			(xy 334.741266 -274.287996) (xy 334.64119 -274.18792) (xy 334.541114 -274.287996) (xy 334.541114 -274.332446)
			(xy 334.741266 -274.332446)
		)
		(stroke
			(width 0)
			(type solid)
		)
		(fill yes)
		(layer "In2.Cu")
		(net "M_C_CPU0_SB_DQ<0>")
	)
	(gr_poly
		(pts
			(xy 334.741266 -273.884136) (xy 334.741266 -273.839686) (xy 334.541114 -273.839686) (xy 334.541114 -273.884136)
			(xy 334.64119 -273.984212)
		)
		(stroke
			(width 0)
			(type solid)
		)
		(fill yes)
		(layer "In2.Cu")
		(net "M_C_CPU0_SB_CB<3>")
	)
	(gr_poly
		(pts
			(xy 334.741266 -272.667984) (xy 334.64119 -272.567908) (xy 334.541114 -272.667984) (xy 334.541114 -272.712434)
			(xy 334.741266 -272.712434)
		)
		(stroke
			(width 0)
			(type solid)
		)
		(fill yes)
		(layer "In2.Cu")
		(net "M_C_CPU0_SB_CB<0>")
	)
	(gr_poly
		(pts
			(xy 334.741266 -272.264378) (xy 334.741266 -272.216626) (xy 334.541114 -272.216626) (xy 334.541114 -272.264378)
			(xy 334.64119 -272.3642)
		)
		(stroke
			(width 0)
			(type solid)
		)
		(fill yes)
		(layer "In2.Cu")
		(net "M_C_CPU0_SB_DQS_DP<4>")
	)
	(gr_poly
		(pts
			(xy 334.741266 -271.047718) (xy 334.64119 -270.947896) (xy 334.541114 -271.047718) (xy 334.541114 -271.09547)
			(xy 334.741266 -271.09547)
		)
		(stroke
			(width 0)
			(type solid)
		)
		(fill yes)
		(layer "In2.Cu")
		(net "M_C_CPU0_SB_DQS_DP<9>")
	)
	(gr_poly
		(pts
			(xy 334.741266 -270.644112) (xy 334.741266 -270.599662) (xy 334.541114 -270.599662) (xy 334.541114 -270.644112)
			(xy 334.64119 -270.744188)
		)
		(stroke
			(width 0)
			(type solid)
		)
		(fill yes)
		(layer "In2.Cu")
		(net "M_C_CPU0_SB_CB<7>")
	)
	(gr_poly
		(pts
			(xy 334.741266 -269.42796) (xy 334.64119 -269.327884) (xy 334.541114 -269.42796) (xy 334.541114 -269.47241)
			(xy 334.741266 -269.47241)
		)
		(stroke
			(width 0)
			(type solid)
		)
		(fill yes)
		(layer "In2.Cu")
		(net "M_C_CPU0_SB_CB<4>")
	)
	(gr_poly
		(pts
			(xy 334.741266 -265.784076) (xy 334.741266 -265.739626) (xy 334.541114 -265.739626) (xy 334.541114 -265.784076)
			(xy 334.64119 -265.884152)
		)
		(stroke
			(width 0)
			(type solid)
		)
		(fill yes)
		(layer "In2.Cu")
		(net "M_C_CPU0_SB_CS_N<0>")
	)
	(gr_poly
		(pts
			(xy 334.741266 -264.567924) (xy 334.64119 -264.467848) (xy 334.541114 -264.567924) (xy 334.541114 -264.612374)
			(xy 334.741266 -264.612374)
		)
		(stroke
			(width 0)
			(type solid)
		)
		(fill yes)
		(layer "In2.Cu")
		(net "M_C_CPU0_SB_CA<6>")
	)
	(gr_poly
		(pts
			(xy 334.741266 -264.164064) (xy 334.741266 -264.119614) (xy 334.541114 -264.119614) (xy 334.541114 -264.164064)
			(xy 334.64119 -264.26414)
		)
		(stroke
			(width 0)
			(type solid)
		)
		(fill yes)
		(layer "In2.Cu")
		(net "M_C_CPU0_SB_CA<5>")
	)
	(gr_poly
		(pts
			(xy 334.741266 -262.947912) (xy 334.64119 -262.847836) (xy 334.541114 -262.947912) (xy 334.541114 -262.992362)
			(xy 334.741266 -262.992362)
		)
		(stroke
			(width 0)
			(type solid)
		)
		(fill yes)
		(layer "In2.Cu")
		(net "M_C_CPU0_SB_CA<2>")
	)
	(gr_poly
		(pts
			(xy 334.741266 -262.544052) (xy 334.741266 -262.499602) (xy 334.541114 -262.499602) (xy 334.541114 -262.544052)
			(xy 334.64119 -262.644128)
		)
		(stroke
			(width 0)
			(type solid)
		)
		(fill yes)
		(layer "In2.Cu")
		(net "M_C_CPU0_SB_CA<1>")
	)
	(gr_poly
		(pts
			(xy 334.911192 -256.025904) (xy 334.811116 -255.926082) (xy 334.71104 -256.025904) (xy 334.71104 -256.073656)
			(xy 334.911192 -256.073656)
		)
		(stroke
			(width 0)
			(type solid)
		)
		(fill yes)
		(layer "In2.Cu")
		(net "M_C_CPU0_CLK_DP<0>")
	)
	(gr_poly
		(pts
			(xy 334.911192 -255.622298) (xy 334.911192 -255.577848) (xy 334.71104 -255.577848) (xy 334.71104 -255.622298)
			(xy 334.811116 -255.722374)
		)
		(stroke
			(width 0)
			(type solid)
		)
		(fill yes)
		(layer "In2.Cu")
		(net "M_C_CPU0_SA_PAR")
	)
	(gr_poly
		(pts
			(xy 334.911192 -254.406146) (xy 334.811116 -254.30607) (xy 334.71104 -254.406146) (xy 334.71104 -254.450596)
			(xy 334.911192 -254.450596)
		)
		(stroke
			(width 0)
			(type solid)
		)
		(fill yes)
		(layer "In2.Cu")
		(net "M_C_CPU0_SA_CA<4>")
	)
	(gr_poly
		(pts
			(xy 334.911192 -254.002286) (xy 334.911192 -253.957836) (xy 334.71104 -253.957836) (xy 334.71104 -254.002286)
			(xy 334.811116 -254.102362)
		)
		(stroke
			(width 0)
			(type solid)
		)
		(fill yes)
		(layer "In2.Cu")
		(net "M_C_CPU0_SA_CA<3>")
	)
	(gr_poly
		(pts
			(xy 334.911192 -252.786134) (xy 334.811116 -252.686058) (xy 334.71104 -252.786134) (xy 334.71104 -252.830584)
			(xy 334.911192 -252.830584)
		)
		(stroke
			(width 0)
			(type solid)
		)
		(fill yes)
		(layer "In2.Cu")
		(net "M_C_CPU0_SA_CA<0>")
	)
	(gr_poly
		(pts
			(xy 334.911192 -252.382274) (xy 334.911192 -252.337824) (xy 334.71104 -252.337824) (xy 334.71104 -252.382274)
			(xy 334.811116 -252.48235)
		)
		(stroke
			(width 0)
			(type solid)
		)
		(fill yes)
		(layer "In2.Cu")
		(net "M_C_CPU0_SA_CS_N<1>")
	)
	(gr_poly
		(pts
			(xy 334.911192 -250.762262) (xy 334.911192 -250.717812) (xy 334.71104 -250.717812) (xy 334.71104 -250.762262)
			(xy 334.811116 -250.862338)
		)
		(stroke
			(width 0)
			(type solid)
		)
		(fill yes)
		(layer "In2.Cu")
		(net "M_C_CPU0_RESET_N")
	)
	(gr_poly
		(pts
			(xy 334.911192 -249.14225) (xy 334.911192 -249.0978) (xy 334.71104 -249.0978) (xy 334.71104 -249.14225)
			(xy 334.811116 -249.242326)
		)
		(stroke
			(width 0)
			(type solid)
		)
		(fill yes)
		(layer "In2.Cu")
		(net "M_C_CPU0_SA_CB<7>")
	)
	(gr_poly
		(pts
			(xy 334.911192 -247.926098) (xy 334.811116 -247.826022) (xy 334.71104 -247.926098) (xy 334.71104 -247.970548)
			(xy 334.911192 -247.970548)
		)
		(stroke
			(width 0)
			(type solid)
		)
		(fill yes)
		(layer "In2.Cu")
		(net "M_C_CPU0_SA_CB<4>")
	)
	(gr_poly
		(pts
			(xy 334.911192 -247.522492) (xy 334.911192 -247.47474) (xy 334.71104 -247.47474) (xy 334.71104 -247.522492)
			(xy 334.811116 -247.622314)
		)
		(stroke
			(width 0)
			(type solid)
		)
		(fill yes)
		(layer "In2.Cu")
		(net "M_C_CPU0_SA_DQS_DP<9>")
	)
	(gr_poly
		(pts
			(xy 334.911192 -246.305832) (xy 334.811116 -246.20601) (xy 334.71104 -246.305832) (xy 334.71104 -246.353584)
			(xy 334.911192 -246.353584)
		)
		(stroke
			(width 0)
			(type solid)
		)
		(fill yes)
		(layer "In2.Cu")
		(net "M_C_CPU0_SA_DQS_DP<4>")
	)
	(gr_poly
		(pts
			(xy 334.911192 -245.902226) (xy 334.911192 -245.857776) (xy 334.71104 -245.857776) (xy 334.71104 -245.902226)
			(xy 334.811116 -246.002302)
		)
		(stroke
			(width 0)
			(type solid)
		)
		(fill yes)
		(layer "In2.Cu")
		(net "M_C_CPU0_SA_CB<3>")
	)
	(gr_poly
		(pts
			(xy 334.911192 -244.686074) (xy 334.811116 -244.585998) (xy 334.71104 -244.686074) (xy 334.71104 -244.730524)
			(xy 334.911192 -244.730524)
		)
		(stroke
			(width 0)
			(type solid)
		)
		(fill yes)
		(layer "In2.Cu")
		(net "M_C_CPU0_SA_CB<0>")
	)
	(gr_poly
		(pts
			(xy 334.911192 -244.282214) (xy 334.911192 -244.237764) (xy 334.71104 -244.237764) (xy 334.71104 -244.282214)
			(xy 334.811116 -244.38229)
		)
		(stroke
			(width 0)
			(type solid)
		)
		(fill yes)
		(layer "In2.Cu")
		(net "M_C_CPU0_SA_DQ<31>")
	)
	(gr_poly
		(pts
			(xy 334.911192 -243.066062) (xy 334.811116 -242.965986) (xy 334.71104 -243.066062) (xy 334.71104 -243.110512)
			(xy 334.911192 -243.110512)
		)
		(stroke
			(width 0)
			(type solid)
		)
		(fill yes)
		(layer "In2.Cu")
		(net "M_C_CPU0_SA_DQ<28>")
	)
	(gr_poly
		(pts
			(xy 334.911192 -242.662456) (xy 334.911192 -242.614704) (xy 334.71104 -242.614704) (xy 334.71104 -242.662456)
			(xy 334.811116 -242.762278)
		)
		(stroke
			(width 0)
			(type solid)
		)
		(fill yes)
		(layer "In2.Cu")
		(net "M_C_CPU0_SA_DQS_DP<8>")
	)
	(gr_poly
		(pts
			(xy 334.911192 -241.445796) (xy 334.811116 -241.345974) (xy 334.71104 -241.445796) (xy 334.71104 -241.493548)
			(xy 334.911192 -241.493548)
		)
		(stroke
			(width 0)
			(type solid)
		)
		(fill yes)
		(layer "In2.Cu")
		(net "M_C_CPU0_SA_DQS_DP<3>")
	)
	(gr_poly
		(pts
			(xy 334.911192 -241.04219) (xy 334.911192 -240.99774) (xy 334.71104 -240.99774) (xy 334.71104 -241.04219)
			(xy 334.811116 -241.142266)
		)
		(stroke
			(width 0)
			(type solid)
		)
		(fill yes)
		(layer "In2.Cu")
		(net "M_C_CPU0_SA_DQ<27>")
	)
	(gr_poly
		(pts
			(xy 334.911192 -239.826038) (xy 334.811116 -239.725962) (xy 334.71104 -239.826038) (xy 334.71104 -239.870488)
			(xy 334.911192 -239.870488)
		)
		(stroke
			(width 0)
			(type solid)
		)
		(fill yes)
		(layer "In2.Cu")
		(net "M_C_CPU0_SA_DQ<24>")
	)
	(gr_poly
		(pts
			(xy 334.911192 -239.422178) (xy 334.911192 -239.377728) (xy 334.71104 -239.377728) (xy 334.71104 -239.422178)
			(xy 334.811116 -239.522254)
		)
		(stroke
			(width 0)
			(type solid)
		)
		(fill yes)
		(layer "In2.Cu")
		(net "M_C_CPU0_SA_DQ<23>")
	)
	(gr_poly
		(pts
			(xy 334.911192 -238.206026) (xy 334.811116 -238.10595) (xy 334.71104 -238.206026) (xy 334.71104 -238.250476)
			(xy 334.911192 -238.250476)
		)
		(stroke
			(width 0)
			(type solid)
		)
		(fill yes)
		(layer "In2.Cu")
		(net "M_C_CPU0_SA_DQ<20>")
	)
	(gr_poly
		(pts
			(xy 334.911192 -237.80242) (xy 334.911192 -237.754668) (xy 334.71104 -237.754668) (xy 334.71104 -237.80242)
			(xy 334.811116 -237.902242)
		)
		(stroke
			(width 0)
			(type solid)
		)
		(fill yes)
		(layer "In2.Cu")
		(net "M_C_CPU0_SA_DQS_DP<7>")
	)
	(gr_poly
		(pts
			(xy 334.911192 -236.58576) (xy 334.811116 -236.485938) (xy 334.71104 -236.58576) (xy 334.71104 -236.633512)
			(xy 334.911192 -236.633512)
		)
		(stroke
			(width 0)
			(type solid)
		)
		(fill yes)
		(layer "In2.Cu")
		(net "M_C_CPU0_SA_DQS_DP<2>")
	)
	(gr_poly
		(pts
			(xy 334.911192 -236.182154) (xy 334.911192 -236.137704) (xy 334.71104 -236.137704) (xy 334.71104 -236.182154)
			(xy 334.811116 -236.28223)
		)
		(stroke
			(width 0)
			(type solid)
		)
		(fill yes)
		(layer "In2.Cu")
		(net "M_C_CPU0_SA_DQ<19>")
	)
	(gr_poly
		(pts
			(xy 334.911192 -234.966002) (xy 334.811116 -234.865926) (xy 334.71104 -234.966002) (xy 334.71104 -235.010452)
			(xy 334.911192 -235.010452)
		)
		(stroke
			(width 0)
			(type solid)
		)
		(fill yes)
		(layer "In2.Cu")
		(net "M_C_CPU0_SA_DQ<16>")
	)
	(gr_poly
		(pts
			(xy 334.911192 -234.562142) (xy 334.911192 -234.517692) (xy 334.71104 -234.517692) (xy 334.71104 -234.562142)
			(xy 334.811116 -234.662218)
		)
		(stroke
			(width 0)
			(type solid)
		)
		(fill yes)
		(layer "In2.Cu")
		(net "M_C_CPU0_SA_DQ<15>")
	)
	(gr_poly
		(pts
			(xy 334.911192 -233.34599) (xy 334.811116 -233.245914) (xy 334.71104 -233.34599) (xy 334.71104 -233.39044)
			(xy 334.911192 -233.39044)
		)
		(stroke
			(width 0)
			(type solid)
		)
		(fill yes)
		(layer "In2.Cu")
		(net "M_C_CPU0_SA_DQ<12>")
	)
	(gr_poly
		(pts
			(xy 334.911192 -232.942384) (xy 334.911192 -232.894632) (xy 334.71104 -232.894632) (xy 334.71104 -232.942384)
			(xy 334.811116 -233.042206)
		)
		(stroke
			(width 0)
			(type solid)
		)
		(fill yes)
		(layer "In2.Cu")
		(net "M_C_CPU0_SA_DQS_DP<6>")
	)
	(gr_poly
		(pts
			(xy 334.911192 -231.725724) (xy 334.811116 -231.625902) (xy 334.71104 -231.725724) (xy 334.71104 -231.773476)
			(xy 334.911192 -231.773476)
		)
		(stroke
			(width 0)
			(type solid)
		)
		(fill yes)
		(layer "In2.Cu")
		(net "M_C_CPU0_SA_DQS_DP<1>")
	)
	(gr_poly
		(pts
			(xy 334.911192 -231.322372) (xy 334.911192 -231.277922) (xy 334.71104 -231.277922) (xy 334.71104 -231.322372)
			(xy 334.811116 -231.422448)
		)
		(stroke
			(width 0)
			(type solid)
		)
		(fill yes)
		(layer "In2.Cu")
		(net "M_C_CPU0_SA_DQ<11>")
	)
	(gr_poly
		(pts
			(xy 334.911192 -230.105966) (xy 334.811116 -230.006144) (xy 334.71104 -230.105966) (xy 334.71104 -230.150416)
			(xy 334.911192 -230.150416)
		)
		(stroke
			(width 0)
			(type solid)
		)
		(fill yes)
		(layer "In2.Cu")
		(net "M_C_CPU0_SA_DQ<8>")
	)
	(gr_poly
		(pts
			(xy 334.911192 -229.70236) (xy 334.911192 -229.65791) (xy 334.71104 -229.65791) (xy 334.71104 -229.70236)
			(xy 334.811116 -229.802436)
		)
		(stroke
			(width 0)
			(type solid)
		)
		(fill yes)
		(layer "In2.Cu")
		(net "M_C_CPU0_SA_DQ<7>")
	)
	(gr_poly
		(pts
			(xy 334.911192 -228.486208) (xy 334.811116 -228.386132) (xy 334.71104 -228.486208) (xy 334.71104 -228.530658)
			(xy 334.911192 -228.530658)
		)
		(stroke
			(width 0)
			(type solid)
		)
		(fill yes)
		(layer "In2.Cu")
		(net "M_C_CPU0_SA_DQ<4>")
	)
	(gr_poly
		(pts
			(xy 334.911192 -228.082602) (xy 334.911192 -228.03485) (xy 334.71104 -228.03485) (xy 334.71104 -228.082602)
			(xy 334.811116 -228.182424)
		)
		(stroke
			(width 0)
			(type solid)
		)
		(fill yes)
		(layer "In2.Cu")
		(net "M_C_CPU0_SA_DQS_DP<5>")
	)
	(gr_poly
		(pts
			(xy 334.911192 -226.865942) (xy 334.811116 -226.76612) (xy 334.71104 -226.865942) (xy 334.71104 -226.913694)
			(xy 334.911192 -226.913694)
		)
		(stroke
			(width 0)
			(type solid)
		)
		(fill yes)
		(layer "In2.Cu")
		(net "M_C_CPU0_SA_DQS_DP<0>")
	)
	(gr_poly
		(pts
			(xy 334.911192 -226.462336) (xy 334.911192 -226.417886) (xy 334.71104 -226.417886) (xy 334.71104 -226.462336)
			(xy 334.811116 -226.562412)
		)
		(stroke
			(width 0)
			(type solid)
		)
		(fill yes)
		(layer "In2.Cu")
		(net "M_C_CPU0_SA_DQ<3>")
	)
	(gr_poly
		(pts
			(xy 334.911192 -225.246184) (xy 334.811116 -225.146108) (xy 334.71104 -225.246184) (xy 334.71104 -225.290634)
			(xy 334.911192 -225.290634)
		)
		(stroke
			(width 0)
			(type solid)
		)
		(fill yes)
		(layer "In2.Cu")
		(net "M_C_CPU0_SA_DQ<0>")
	)
	(gr_poly
		(pts
			(xy 335.211166 -292.91788) (xy 335.11109 -292.817804) (xy 335.011014 -292.91788) (xy 335.011014 -292.96233)
			(xy 335.211166 -292.96233)
		)
		(stroke
			(width 0)
			(type solid)
		)
		(fill yes)
		(layer "In2.Cu")
		(net "M_C_CPU0_SB_DQ<29>")
	)
	(gr_poly
		(pts
			(xy 335.211166 -292.51402) (xy 335.211166 -292.46957) (xy 335.011014 -292.46957) (xy 335.011014 -292.51402)
			(xy 335.11109 -292.614096)
		)
		(stroke
			(width 0)
			(type solid)
		)
		(fill yes)
		(layer "In2.Cu")
		(net "M_C_CPU0_SB_DQ<30>")
	)
	(gr_poly
		(pts
			(xy 335.211166 -290.894262) (xy 335.211166 -290.84651) (xy 335.011014 -290.84651) (xy 335.011014 -290.894262)
			(xy 335.11109 -290.994084)
		)
		(stroke
			(width 0)
			(type solid)
		)
		(fill yes)
		(layer "In2.Cu")
		(net "M_C_CPU0_SB_DQS_DN<3>")
	)
	(gr_poly
		(pts
			(xy 335.211166 -289.677856) (xy 335.11109 -289.57778) (xy 335.011014 -289.677856) (xy 335.011014 -289.722306)
			(xy 335.211166 -289.722306)
		)
		(stroke
			(width 0)
			(type solid)
		)
		(fill yes)
		(layer "In2.Cu")
		(net "M_C_CPU0_SB_DQ<25>")
	)
	(gr_poly
		(pts
			(xy 335.211166 -289.273996) (xy 335.211166 -289.229546) (xy 335.011014 -289.229546) (xy 335.011014 -289.273996)
			(xy 335.11109 -289.374072)
		)
		(stroke
			(width 0)
			(type solid)
		)
		(fill yes)
		(layer "In2.Cu")
		(net "M_C_CPU0_SB_DQ<26>")
	)
	(gr_poly
		(pts
			(xy 335.211166 -288.057844) (xy 335.11109 -287.957768) (xy 335.011014 -288.057844) (xy 335.011014 -288.102294)
			(xy 335.211166 -288.102294)
		)
		(stroke
			(width 0)
			(type solid)
		)
		(fill yes)
		(layer "In2.Cu")
		(net "M_C_CPU0_SB_DQ<21>")
	)
	(gr_poly
		(pts
			(xy 335.211166 -287.654238) (xy 335.211166 -287.609788) (xy 335.011014 -287.609788) (xy 335.011014 -287.654238)
			(xy 335.11109 -287.75406)
		)
		(stroke
			(width 0)
			(type solid)
		)
		(fill yes)
		(layer "In2.Cu")
		(net "M_C_CPU0_SB_DQ<22>")
	)
	(gr_poly
		(pts
			(xy 335.211166 -286.437832) (xy 335.11109 -286.337756) (xy 335.011014 -286.437832) (xy 335.011014 -286.485584)
			(xy 335.211166 -286.485584)
		)
		(stroke
			(width 0)
			(type solid)
		)
		(fill yes)
		(layer "In2.Cu")
		(net "M_C_CPU0_SB_DQS_DN<7>")
	)
	(gr_poly
		(pts
			(xy 335.211166 -286.03448) (xy 335.211166 -285.986728) (xy 335.011014 -285.986728) (xy 335.011014 -286.03448)
			(xy 335.11109 -286.134302)
		)
		(stroke
			(width 0)
			(type solid)
		)
		(fill yes)
		(layer "In2.Cu")
		(net "M_C_CPU0_SB_DQS_DN<2>")
	)
	(gr_poly
		(pts
			(xy 335.211166 -284.818074) (xy 335.11109 -284.717998) (xy 335.011014 -284.818074) (xy 335.011014 -284.862524)
			(xy 335.211166 -284.862524)
		)
		(stroke
			(width 0)
			(type solid)
		)
		(fill yes)
		(layer "In2.Cu")
		(net "M_C_CPU0_SB_DQ<17>")
	)
	(gr_poly
		(pts
			(xy 335.211166 -284.414214) (xy 335.211166 -284.369764) (xy 335.011014 -284.369764) (xy 335.011014 -284.414214)
			(xy 335.11109 -284.51429)
		)
		(stroke
			(width 0)
			(type solid)
		)
		(fill yes)
		(layer "In2.Cu")
		(net "M_C_CPU0_SB_DQ<18>")
	)
	(gr_poly
		(pts
			(xy 335.211166 -283.198062) (xy 335.11109 -283.097986) (xy 335.011014 -283.198062) (xy 335.011014 -283.242512)
			(xy 335.211166 -283.242512)
		)
		(stroke
			(width 0)
			(type solid)
		)
		(fill yes)
		(layer "In2.Cu")
		(net "M_C_CPU0_SB_DQ<13>")
	)
	(gr_poly
		(pts
			(xy 335.211166 -282.794202) (xy 335.211166 -282.749752) (xy 335.011014 -282.749752) (xy 335.011014 -282.794202)
			(xy 335.11109 -282.894278)
		)
		(stroke
			(width 0)
			(type solid)
		)
		(fill yes)
		(layer "In2.Cu")
		(net "M_C_CPU0_SB_DQ<14>")
	)
	(gr_poly
		(pts
			(xy 335.211166 -281.577796) (xy 335.11109 -281.477974) (xy 335.011014 -281.577796) (xy 335.011014 -281.625548)
			(xy 335.211166 -281.625548)
		)
		(stroke
			(width 0)
			(type solid)
		)
		(fill yes)
		(layer "In2.Cu")
		(net "M_C_CPU0_SB_DQS_DN<6>")
	)
	(gr_poly
		(pts
			(xy 335.211166 -281.174444) (xy 335.211166 -281.126692) (xy 335.011014 -281.126692) (xy 335.011014 -281.174444)
			(xy 335.11109 -281.274266)
		)
		(stroke
			(width 0)
			(type solid)
		)
		(fill yes)
		(layer "In2.Cu")
		(net "M_C_CPU0_SB_DQS_DN<1>")
	)
	(gr_poly
		(pts
			(xy 335.211166 -279.958038) (xy 335.11109 -279.857962) (xy 335.011014 -279.958038) (xy 335.011014 -280.002488)
			(xy 335.211166 -280.002488)
		)
		(stroke
			(width 0)
			(type solid)
		)
		(fill yes)
		(layer "In2.Cu")
		(net "M_C_CPU0_SB_DQ<9>")
	)
	(gr_poly
		(pts
			(xy 335.211166 -279.554178) (xy 335.211166 -279.509728) (xy 335.011014 -279.509728) (xy 335.011014 -279.554178)
			(xy 335.11109 -279.654254)
		)
		(stroke
			(width 0)
			(type solid)
		)
		(fill yes)
		(layer "In2.Cu")
		(net "M_C_CPU0_SB_DQ<10>")
	)
	(gr_poly
		(pts
			(xy 335.211166 -278.338026) (xy 335.11109 -278.23795) (xy 335.011014 -278.338026) (xy 335.011014 -278.382476)
			(xy 335.211166 -278.382476)
		)
		(stroke
			(width 0)
			(type solid)
		)
		(fill yes)
		(layer "In2.Cu")
		(net "M_C_CPU0_SB_DQ<5>")
	)
	(gr_poly
		(pts
			(xy 335.211166 -277.934166) (xy 335.211166 -277.889716) (xy 335.011014 -277.889716) (xy 335.011014 -277.934166)
			(xy 335.11109 -278.034242)
		)
		(stroke
			(width 0)
			(type solid)
		)
		(fill yes)
		(layer "In2.Cu")
		(net "M_C_CPU0_SB_DQ<6>")
	)
	(gr_poly
		(pts
			(xy 335.211166 -276.71776) (xy 335.11109 -276.617938) (xy 335.011014 -276.71776) (xy 335.011014 -276.765512)
			(xy 335.211166 -276.765512)
		)
		(stroke
			(width 0)
			(type solid)
		)
		(fill yes)
		(layer "In2.Cu")
		(net "M_C_CPU0_SB_DQS_DN<5>")
	)
	(gr_poly
		(pts
			(xy 335.211166 -276.314408) (xy 335.211166 -276.266656) (xy 335.011014 -276.266656) (xy 335.011014 -276.314408)
			(xy 335.11109 -276.41423)
		)
		(stroke
			(width 0)
			(type solid)
		)
		(fill yes)
		(layer "In2.Cu")
		(net "M_C_CPU0_SB_DQS_DN<0>")
	)
	(gr_poly
		(pts
			(xy 335.211166 -275.098002) (xy 335.11109 -274.997926) (xy 335.011014 -275.098002) (xy 335.011014 -275.142452)
			(xy 335.211166 -275.142452)
		)
		(stroke
			(width 0)
			(type solid)
		)
		(fill yes)
		(layer "In2.Cu")
		(net "M_C_CPU0_SB_DQ<1>")
	)
	(gr_poly
		(pts
			(xy 335.211166 -274.694142) (xy 335.211166 -274.649692) (xy 335.011014 -274.649692) (xy 335.011014 -274.694142)
			(xy 335.11109 -274.794218)
		)
		(stroke
			(width 0)
			(type solid)
		)
		(fill yes)
		(layer "In2.Cu")
		(net "M_C_CPU0_SB_DQ<2>")
	)
	(gr_poly
		(pts
			(xy 335.211166 -273.47799) (xy 335.11109 -273.377914) (xy 335.011014 -273.47799) (xy 335.011014 -273.52244)
			(xy 335.211166 -273.52244)
		)
		(stroke
			(width 0)
			(type solid)
		)
		(fill yes)
		(layer "In2.Cu")
		(net "M_C_CPU0_SB_CB<1>")
	)
	(gr_poly
		(pts
			(xy 335.211166 -273.07413) (xy 335.211166 -273.02968) (xy 335.011014 -273.02968) (xy 335.011014 -273.07413)
			(xy 335.11109 -273.174206)
		)
		(stroke
			(width 0)
			(type solid)
		)
		(fill yes)
		(layer "In2.Cu")
		(net "M_C_CPU0_SB_CB<2>")
	)
	(gr_poly
		(pts
			(xy 335.211166 -271.857724) (xy 335.11109 -271.757902) (xy 335.011014 -271.857724) (xy 335.011014 -271.905476)
			(xy 335.211166 -271.905476)
		)
		(stroke
			(width 0)
			(type solid)
		)
		(fill yes)
		(layer "In2.Cu")
		(net "M_C_CPU0_SB_DQS_DN<4>")
	)
	(gr_poly
		(pts
			(xy 335.211166 -271.454372) (xy 335.211166 -271.40662) (xy 335.011014 -271.40662) (xy 335.011014 -271.454372)
			(xy 335.11109 -271.554194)
		)
		(stroke
			(width 0)
			(type solid)
		)
		(fill yes)
		(layer "In2.Cu")
		(net "M_C_CPU0_SB_DQS_DN<9>")
	)
	(gr_poly
		(pts
			(xy 335.211166 -270.237966) (xy 335.11109 -270.13789) (xy 335.011014 -270.237966) (xy 335.011014 -270.282416)
			(xy 335.211166 -270.282416)
		)
		(stroke
			(width 0)
			(type solid)
		)
		(fill yes)
		(layer "In2.Cu")
		(net "M_C_CPU0_SB_CB<5>")
	)
	(gr_poly
		(pts
			(xy 335.211166 -269.834106) (xy 335.211166 -269.789656) (xy 335.011014 -269.789656) (xy 335.011014 -269.834106)
			(xy 335.11109 -269.934182)
		)
		(stroke
			(width 0)
			(type solid)
		)
		(fill yes)
		(layer "In2.Cu")
		(net "M_C_CPU0_SB_CB<6>")
	)
	(gr_poly
		(pts
			(xy 335.211166 -266.991592) (xy 335.11109 -266.891516) (xy 335.011014 -266.991592) (xy 335.011014 -267.036042)
			(xy 335.211166 -267.036042)
		)
		(stroke
			(width 0)
			(type solid)
		)
		(fill yes)
		(layer "In2.Cu")
		(net "M_C_CPU0_SA_RSP<0>")
	)
	(gr_poly
		(pts
			(xy 335.211166 -266.594082) (xy 335.211166 -266.549632) (xy 335.011014 -266.549632) (xy 335.011014 -266.594082)
			(xy 335.11109 -266.694158)
		)
		(stroke
			(width 0)
			(type solid)
		)
		(fill yes)
		(layer "In2.Cu")
		(net "M_C_CPU0_SB_CS_N<1>")
	)
	(gr_poly
		(pts
			(xy 335.211166 -264.97407) (xy 335.211166 -264.92962) (xy 335.011014 -264.92962) (xy 335.011014 -264.97407)
			(xy 335.11109 -265.074146)
		)
		(stroke
			(width 0)
			(type solid)
		)
		(fill yes)
		(layer "In2.Cu")
		(net "M_C_CPU0_SB_PAR")
	)
	(gr_poly
		(pts
			(xy 335.211166 -263.757918) (xy 335.11109 -263.657842) (xy 335.011014 -263.757918) (xy 335.011014 -263.802368)
			(xy 335.211166 -263.802368)
		)
		(stroke
			(width 0)
			(type solid)
		)
		(fill yes)
		(layer "In2.Cu")
		(net "M_C_CPU0_SB_CA<4>")
	)
	(gr_poly
		(pts
			(xy 335.211166 -263.354058) (xy 335.211166 -263.309608) (xy 335.011014 -263.309608) (xy 335.011014 -263.354058)
			(xy 335.11109 -263.454134)
		)
		(stroke
			(width 0)
			(type solid)
		)
		(fill yes)
		(layer "In2.Cu")
		(net "M_C_CPU0_SB_CA<3>")
	)
	(gr_poly
		(pts
			(xy 335.211166 -262.137906) (xy 335.11109 -262.03783) (xy 335.011014 -262.137906) (xy 335.011014 -262.182356)
			(xy 335.211166 -262.182356)
		)
		(stroke
			(width 0)
			(type solid)
		)
		(fill yes)
		(layer "In2.Cu")
		(net "M_C_CPU0_SB_CA<0>")
	)
	(gr_poly
		(pts
			(xy 335.218532 -291.297614) (xy 335.118456 -291.197792) (xy 335.01838 -291.297614) (xy 335.01838 -291.345366)
			(xy 335.218532 -291.345366)
		)
		(stroke
			(width 0)
			(type solid)
		)
		(fill yes)
		(layer "In2.Cu")
		(net "M_C_CPU0_SB_DQS_DN<8>")
	)
	(gr_poly
		(pts
			(xy 335.380838 -246.712232) (xy 335.380838 -246.664734) (xy 335.18094 -246.664734) (xy 335.18094 -246.712232)
			(xy 335.280762 -246.812308)
		)
		(stroke
			(width 0)
			(type solid)
		)
		(fill yes)
		(layer "In2.Cu")
		(net "M_C_CPU0_SA_DQS_DN<4>")
	)
	(gr_poly
		(pts
			(xy 335.381092 -256.432558) (xy 335.381092 -256.384806) (xy 335.18094 -256.384806) (xy 335.18094 -256.432558)
			(xy 335.281016 -256.53238)
		)
		(stroke
			(width 0)
			(type solid)
		)
		(fill yes)
		(layer "In2.Cu")
		(net "M_C_CPU0_CLK_DN<0>")
	)
	(gr_poly
		(pts
			(xy 335.381092 -255.216152) (xy 335.281016 -255.116076) (xy 335.18094 -255.216152) (xy 335.18094 -255.260602)
			(xy 335.381092 -255.260602)
		)
		(stroke
			(width 0)
			(type solid)
		)
		(fill yes)
		(layer "In2.Cu")
		(net "M_C_CPU0_SA_CA<6>")
	)
	(gr_poly
		(pts
			(xy 335.381092 -254.812292) (xy 335.381092 -254.767842) (xy 335.18094 -254.767842) (xy 335.18094 -254.812292)
			(xy 335.281016 -254.912368)
		)
		(stroke
			(width 0)
			(type solid)
		)
		(fill yes)
		(layer "In2.Cu")
		(net "M_C_CPU0_SA_CA<5>")
	)
	(gr_poly
		(pts
			(xy 335.381092 -253.59614) (xy 335.281016 -253.496064) (xy 335.18094 -253.59614) (xy 335.18094 -253.64059)
			(xy 335.381092 -253.64059)
		)
		(stroke
			(width 0)
			(type solid)
		)
		(fill yes)
		(layer "In2.Cu")
		(net "M_C_CPU0_SA_CA<2>")
	)
	(gr_poly
		(pts
			(xy 335.381092 -253.19228) (xy 335.381092 -253.14783) (xy 335.18094 -253.14783) (xy 335.18094 -253.19228)
			(xy 335.281016 -253.292356)
		)
		(stroke
			(width 0)
			(type solid)
		)
		(fill yes)
		(layer "In2.Cu")
		(net "M_C_CPU0_SA_CA<1>")
	)
	(gr_poly
		(pts
			(xy 335.381092 -251.572268) (xy 335.381092 -251.527818) (xy 335.18094 -251.527818) (xy 335.18094 -251.572268)
			(xy 335.281016 -251.672344)
		)
		(stroke
			(width 0)
			(type solid)
		)
		(fill yes)
		(layer "In2.Cu")
		(net "M_C_CPU0_SA_CS_N<0>")
	)
	(gr_poly
		(pts
			(xy 335.381092 -250.356116) (xy 335.281016 -250.25604) (xy 335.18094 -250.356116) (xy 335.18094 -250.400566)
			(xy 335.381092 -250.400566)
		)
		(stroke
			(width 0)
			(type solid)
		)
		(fill yes)
		(layer "In2.Cu")
		(net "M_C_CPU0_ALERT_R_N")
	)
	(gr_poly
		(pts
			(xy 335.381092 -248.736104) (xy 335.281016 -248.636028) (xy 335.18094 -248.736104) (xy 335.18094 -248.780554)
			(xy 335.381092 -248.780554)
		)
		(stroke
			(width 0)
			(type solid)
		)
		(fill yes)
		(layer "In2.Cu")
		(net "M_C_CPU0_SA_CB<5>")
	)
	(gr_poly
		(pts
			(xy 335.381092 -248.332244) (xy 335.381092 -248.287794) (xy 335.18094 -248.287794) (xy 335.18094 -248.332244)
			(xy 335.281016 -248.43232)
		)
		(stroke
			(width 0)
			(type solid)
		)
		(fill yes)
		(layer "In2.Cu")
		(net "M_C_CPU0_SA_CB<6>")
	)
	(gr_poly
		(pts
			(xy 335.381092 -247.115838) (xy 335.281016 -247.016016) (xy 335.18094 -247.115838) (xy 335.18094 -247.16359)
			(xy 335.381092 -247.16359)
		)
		(stroke
			(width 0)
			(type solid)
		)
		(fill yes)
		(layer "In2.Cu")
		(net "M_C_CPU0_SA_DQS_DN<9>")
	)
	(gr_poly
		(pts
			(xy 335.381092 -245.49608) (xy 335.281016 -245.396004) (xy 335.18094 -245.49608) (xy 335.18094 -245.54053)
			(xy 335.381092 -245.54053)
		)
		(stroke
			(width 0)
			(type solid)
		)
		(fill yes)
		(layer "In2.Cu")
		(net "M_C_CPU0_SA_CB<1>")
	)
	(gr_poly
		(pts
			(xy 335.381092 -245.09222) (xy 335.381092 -245.04777) (xy 335.18094 -245.04777) (xy 335.18094 -245.09222)
			(xy 335.281016 -245.192296)
		)
		(stroke
			(width 0)
			(type solid)
		)
		(fill yes)
		(layer "In2.Cu")
		(net "M_C_CPU0_SA_CB<2>")
	)
	(gr_poly
		(pts
			(xy 335.381092 -243.876068) (xy 335.281016 -243.775992) (xy 335.18094 -243.876068) (xy 335.18094 -243.920518)
			(xy 335.381092 -243.920518)
		)
		(stroke
			(width 0)
			(type solid)
		)
		(fill yes)
		(layer "In2.Cu")
		(net "M_C_CPU0_SA_DQ<29>")
	)
	(gr_poly
		(pts
			(xy 335.381092 -243.472208) (xy 335.381092 -243.427758) (xy 335.18094 -243.427758) (xy 335.18094 -243.472208)
			(xy 335.281016 -243.572284)
		)
		(stroke
			(width 0)
			(type solid)
		)
		(fill yes)
		(layer "In2.Cu")
		(net "M_C_CPU0_SA_DQ<30>")
	)
	(gr_poly
		(pts
			(xy 335.381092 -242.255802) (xy 335.281016 -242.15598) (xy 335.18094 -242.255802) (xy 335.18094 -242.303554)
			(xy 335.381092 -242.303554)
		)
		(stroke
			(width 0)
			(type solid)
		)
		(fill yes)
		(layer "In2.Cu")
		(net "M_C_CPU0_SA_DQS_DN<8>")
	)
	(gr_poly
		(pts
			(xy 335.381092 -241.85245) (xy 335.381092 -241.804698) (xy 335.18094 -241.804698) (xy 335.18094 -241.85245)
			(xy 335.281016 -241.952272)
		)
		(stroke
			(width 0)
			(type solid)
		)
		(fill yes)
		(layer "In2.Cu")
		(net "M_C_CPU0_SA_DQS_DN<3>")
	)
	(gr_poly
		(pts
			(xy 335.381092 -240.636044) (xy 335.281016 -240.535968) (xy 335.18094 -240.636044) (xy 335.18094 -240.680494)
			(xy 335.381092 -240.680494)
		)
		(stroke
			(width 0)
			(type solid)
		)
		(fill yes)
		(layer "In2.Cu")
		(net "M_C_CPU0_SA_DQ<25>")
	)
	(gr_poly
		(pts
			(xy 335.381092 -240.232184) (xy 335.381092 -240.187734) (xy 335.18094 -240.187734) (xy 335.18094 -240.232184)
			(xy 335.281016 -240.33226)
		)
		(stroke
			(width 0)
			(type solid)
		)
		(fill yes)
		(layer "In2.Cu")
		(net "M_C_CPU0_SA_DQ<26>")
	)
	(gr_poly
		(pts
			(xy 335.381092 -239.016032) (xy 335.281016 -238.915956) (xy 335.18094 -239.016032) (xy 335.18094 -239.060482)
			(xy 335.381092 -239.060482)
		)
		(stroke
			(width 0)
			(type solid)
		)
		(fill yes)
		(layer "In2.Cu")
		(net "M_C_CPU0_SA_DQ<21>")
	)
	(gr_poly
		(pts
			(xy 335.381092 -238.612172) (xy 335.381092 -238.567722) (xy 335.18094 -238.567722) (xy 335.18094 -238.612172)
			(xy 335.281016 -238.712248)
		)
		(stroke
			(width 0)
			(type solid)
		)
		(fill yes)
		(layer "In2.Cu")
		(net "M_C_CPU0_SA_DQ<22>")
	)
	(gr_poly
		(pts
			(xy 335.381092 -237.395766) (xy 335.281016 -237.295944) (xy 335.18094 -237.395766) (xy 335.18094 -237.443518)
			(xy 335.381092 -237.443518)
		)
		(stroke
			(width 0)
			(type solid)
		)
		(fill yes)
		(layer "In2.Cu")
		(net "M_C_CPU0_SA_DQS_DN<7>")
	)
	(gr_poly
		(pts
			(xy 335.381092 -236.992414) (xy 335.381092 -236.944662) (xy 335.18094 -236.944662) (xy 335.18094 -236.992414)
			(xy 335.281016 -237.092236)
		)
		(stroke
			(width 0)
			(type solid)
		)
		(fill yes)
		(layer "In2.Cu")
		(net "M_C_CPU0_SA_DQS_DN<2>")
	)
	(gr_poly
		(pts
			(xy 335.381092 -235.776008) (xy 335.281016 -235.675932) (xy 335.18094 -235.776008) (xy 335.18094 -235.820458)
			(xy 335.381092 -235.820458)
		)
		(stroke
			(width 0)
			(type solid)
		)
		(fill yes)
		(layer "In2.Cu")
		(net "M_C_CPU0_SA_DQ<17>")
	)
	(gr_poly
		(pts
			(xy 335.381092 -235.372148) (xy 335.381092 -235.327698) (xy 335.18094 -235.327698) (xy 335.18094 -235.372148)
			(xy 335.281016 -235.472224)
		)
		(stroke
			(width 0)
			(type solid)
		)
		(fill yes)
		(layer "In2.Cu")
		(net "M_C_CPU0_SA_DQ<18>")
	)
	(gr_poly
		(pts
			(xy 335.381092 -234.155996) (xy 335.281016 -234.05592) (xy 335.18094 -234.155996) (xy 335.18094 -234.200446)
			(xy 335.381092 -234.200446)
		)
		(stroke
			(width 0)
			(type solid)
		)
		(fill yes)
		(layer "In2.Cu")
		(net "M_C_CPU0_SA_DQ<13>")
	)
	(gr_poly
		(pts
			(xy 335.381092 -233.752136) (xy 335.381092 -233.707686) (xy 335.18094 -233.707686) (xy 335.18094 -233.752136)
			(xy 335.281016 -233.852212)
		)
		(stroke
			(width 0)
			(type solid)
		)
		(fill yes)
		(layer "In2.Cu")
		(net "M_C_CPU0_SA_DQ<14>")
	)
	(gr_poly
		(pts
			(xy 335.381092 -232.53573) (xy 335.281016 -232.435908) (xy 335.18094 -232.53573) (xy 335.18094 -232.583482)
			(xy 335.381092 -232.583482)
		)
		(stroke
			(width 0)
			(type solid)
		)
		(fill yes)
		(layer "In2.Cu")
		(net "M_C_CPU0_SA_DQS_DN<6>")
	)
	(gr_poly
		(pts
			(xy 335.381092 -232.132378) (xy 335.381092 -232.084626) (xy 335.18094 -232.084626) (xy 335.18094 -232.132378)
			(xy 335.281016 -232.2322)
		)
		(stroke
			(width 0)
			(type solid)
		)
		(fill yes)
		(layer "In2.Cu")
		(net "M_C_CPU0_SA_DQS_DN<1>")
	)
	(gr_poly
		(pts
			(xy 335.381092 -230.915972) (xy 335.281016 -230.815896) (xy 335.18094 -230.915972) (xy 335.18094 -230.960422)
			(xy 335.381092 -230.960422)
		)
		(stroke
			(width 0)
			(type solid)
		)
		(fill yes)
		(layer "In2.Cu")
		(net "M_C_CPU0_SA_DQ<9>")
	)
	(gr_poly
		(pts
			(xy 335.381092 -230.512366) (xy 335.381092 -230.467916) (xy 335.18094 -230.467916) (xy 335.18094 -230.512366)
			(xy 335.281016 -230.612188)
		)
		(stroke
			(width 0)
			(type solid)
		)
		(fill yes)
		(layer "In2.Cu")
		(net "M_C_CPU0_SA_DQ<10>")
	)
	(gr_poly
		(pts
			(xy 335.381092 -229.29596) (xy 335.281016 -229.195884) (xy 335.18094 -229.29596) (xy 335.18094 -229.34041)
			(xy 335.381092 -229.34041)
		)
		(stroke
			(width 0)
			(type solid)
		)
		(fill yes)
		(layer "In2.Cu")
		(net "M_C_CPU0_SA_DQ<5>")
	)
	(gr_poly
		(pts
			(xy 335.381092 -228.892354) (xy 335.381092 -228.847904) (xy 335.18094 -228.847904) (xy 335.18094 -228.892354)
			(xy 335.281016 -228.99243)
		)
		(stroke
			(width 0)
			(type solid)
		)
		(fill yes)
		(layer "In2.Cu")
		(net "M_C_CPU0_SA_DQ<6>")
	)
	(gr_poly
		(pts
			(xy 335.381092 -227.675948) (xy 335.281016 -227.576126) (xy 335.18094 -227.675948) (xy 335.18094 -227.7237)
			(xy 335.381092 -227.7237)
		)
		(stroke
			(width 0)
			(type solid)
		)
		(fill yes)
		(layer "In2.Cu")
		(net "M_C_CPU0_SA_DQS_DN<5>")
	)
	(gr_poly
		(pts
			(xy 335.381092 -227.272596) (xy 335.381092 -227.224844) (xy 335.18094 -227.224844) (xy 335.18094 -227.272596)
			(xy 335.281016 -227.372418)
		)
		(stroke
			(width 0)
			(type solid)
		)
		(fill yes)
		(layer "In2.Cu")
		(net "M_C_CPU0_SA_DQS_DN<0>")
	)
	(gr_poly
		(pts
			(xy 335.381092 -226.05619) (xy 335.281016 -225.956114) (xy 335.18094 -226.05619) (xy 335.18094 -226.10064)
			(xy 335.381092 -226.10064)
		)
		(stroke
			(width 0)
			(type solid)
		)
		(fill yes)
		(layer "In2.Cu")
		(net "M_C_CPU0_SA_DQ<1>")
	)
	(gr_poly
		(pts
			(xy 335.381092 -225.65233) (xy 335.381092 -225.60788) (xy 335.18094 -225.60788) (xy 335.18094 -225.65233)
			(xy 335.281016 -225.752406)
		)
		(stroke
			(width 0)
			(type solid)
		)
		(fill yes)
		(layer "In2.Cu")
		(net "M_C_CPU0_SA_DQ<2>")
	)
	(gr_poly
		(pts
			(xy 335.681066 -293.324026) (xy 335.681066 -293.279576) (xy 335.480914 -293.279576) (xy 335.480914 -293.324026)
			(xy 335.58099 -293.424102)
		)
		(stroke
			(width 0)
			(type solid)
		)
		(fill yes)
		(layer "In2.Cu")
		(net "M_C_CPU0_SB_DQ<31>")
	)
	(gr_poly
		(pts
			(xy 335.681066 -292.107874) (xy 335.58099 -292.007798) (xy 335.480914 -292.107874) (xy 335.480914 -292.152324)
			(xy 335.681066 -292.152324)
		)
		(stroke
			(width 0)
			(type solid)
		)
		(fill yes)
		(layer "In2.Cu")
		(net "M_C_CPU0_SB_DQ<28>")
	)
	(gr_poly
		(pts
			(xy 335.681066 -291.704268) (xy 335.681066 -291.656516) (xy 335.480914 -291.656516) (xy 335.480914 -291.704268)
			(xy 335.58099 -291.80409)
		)
		(stroke
			(width 0)
			(type solid)
		)
		(fill yes)
		(layer "In2.Cu")
		(net "M_C_CPU0_SB_DQS_DP<8>")
	)
	(gr_poly
		(pts
			(xy 335.681066 -290.487608) (xy 335.58099 -290.387786) (xy 335.480914 -290.487608) (xy 335.480914 -290.53536)
			(xy 335.681066 -290.53536)
		)
		(stroke
			(width 0)
			(type solid)
		)
		(fill yes)
		(layer "In2.Cu")
		(net "M_C_CPU0_SB_DQS_DP<3>")
	)
	(gr_poly
		(pts
			(xy 335.681066 -290.084002) (xy 335.681066 -290.039552) (xy 335.480914 -290.039552) (xy 335.480914 -290.084002)
			(xy 335.58099 -290.184078)
		)
		(stroke
			(width 0)
			(type solid)
		)
		(fill yes)
		(layer "In2.Cu")
		(net "M_C_CPU0_SB_DQ<27>")
	)
	(gr_poly
		(pts
			(xy 335.681066 -288.86785) (xy 335.58099 -288.767774) (xy 335.480914 -288.86785) (xy 335.480914 -288.9123)
			(xy 335.681066 -288.9123)
		)
		(stroke
			(width 0)
			(type solid)
		)
		(fill yes)
		(layer "In2.Cu")
		(net "M_C_CPU0_SB_DQ<24>")
	)
	(gr_poly
		(pts
			(xy 335.681066 -288.464244) (xy 335.681066 -288.419794) (xy 335.480914 -288.419794) (xy 335.480914 -288.464244)
			(xy 335.58099 -288.56432)
		)
		(stroke
			(width 0)
			(type solid)
		)
		(fill yes)
		(layer "In2.Cu")
		(net "M_C_CPU0_SB_DQ<23>")
	)
	(gr_poly
		(pts
			(xy 335.681066 -287.247838) (xy 335.58099 -287.148016) (xy 335.480914 -287.247838) (xy 335.480914 -287.292288)
			(xy 335.681066 -287.292288)
		)
		(stroke
			(width 0)
			(type solid)
		)
		(fill yes)
		(layer "In2.Cu")
		(net "M_C_CPU0_SB_DQ<20>")
	)
	(gr_poly
		(pts
			(xy 335.681066 -286.844232) (xy 335.681066 -286.79648) (xy 335.480914 -286.79648) (xy 335.480914 -286.844232)
			(xy 335.58099 -286.944308)
		)
		(stroke
			(width 0)
			(type solid)
		)
		(fill yes)
		(layer "In2.Cu")
		(net "M_C_CPU0_SB_DQS_DP<7>")
	)
	(gr_poly
		(pts
			(xy 335.681066 -285.627826) (xy 335.58099 -285.528004) (xy 335.480914 -285.627826) (xy 335.480914 -285.675578)
			(xy 335.681066 -285.675578)
		)
		(stroke
			(width 0)
			(type solid)
		)
		(fill yes)
		(layer "In2.Cu")
		(net "M_C_CPU0_SB_DQS_DP<2>")
	)
	(gr_poly
		(pts
			(xy 335.681066 -285.22422) (xy 335.681066 -285.17977) (xy 335.480914 -285.17977) (xy 335.480914 -285.22422)
			(xy 335.58099 -285.324296)
		)
		(stroke
			(width 0)
			(type solid)
		)
		(fill yes)
		(layer "In2.Cu")
		(net "M_C_CPU0_SB_DQ<19>")
	)
	(gr_poly
		(pts
			(xy 335.681066 -284.008068) (xy 335.58099 -283.907992) (xy 335.480914 -284.008068) (xy 335.480914 -284.052518)
			(xy 335.681066 -284.052518)
		)
		(stroke
			(width 0)
			(type solid)
		)
		(fill yes)
		(layer "In2.Cu")
		(net "M_C_CPU0_SB_DQ<16>")
	)
	(gr_poly
		(pts
			(xy 335.681066 -283.604208) (xy 335.681066 -283.559758) (xy 335.480914 -283.559758) (xy 335.480914 -283.604208)
			(xy 335.58099 -283.704284)
		)
		(stroke
			(width 0)
			(type solid)
		)
		(fill yes)
		(layer "In2.Cu")
		(net "M_C_CPU0_SB_DQ<15>")
	)
	(gr_poly
		(pts
			(xy 335.681066 -282.388056) (xy 335.58099 -282.28798) (xy 335.480914 -282.388056) (xy 335.480914 -282.432506)
			(xy 335.681066 -282.432506)
		)
		(stroke
			(width 0)
			(type solid)
		)
		(fill yes)
		(layer "In2.Cu")
		(net "M_C_CPU0_SB_DQ<12>")
	)
	(gr_poly
		(pts
			(xy 335.681066 -281.98445) (xy 335.681066 -281.936698) (xy 335.480914 -281.936698) (xy 335.480914 -281.98445)
			(xy 335.58099 -282.084272)
		)
		(stroke
			(width 0)
			(type solid)
		)
		(fill yes)
		(layer "In2.Cu")
		(net "M_C_CPU0_SB_DQS_DP<6>")
	)
	(gr_poly
		(pts
			(xy 335.681066 -280.76779) (xy 335.58099 -280.667968) (xy 335.480914 -280.76779) (xy 335.480914 -280.815542)
			(xy 335.681066 -280.815542)
		)
		(stroke
			(width 0)
			(type solid)
		)
		(fill yes)
		(layer "In2.Cu")
		(net "M_C_CPU0_SB_DQS_DP<1>")
	)
	(gr_poly
		(pts
			(xy 335.681066 -280.364184) (xy 335.681066 -280.319734) (xy 335.480914 -280.319734) (xy 335.480914 -280.364184)
			(xy 335.58099 -280.46426)
		)
		(stroke
			(width 0)
			(type solid)
		)
		(fill yes)
		(layer "In2.Cu")
		(net "M_C_CPU0_SB_DQ<11>")
	)
	(gr_poly
		(pts
			(xy 335.681066 -279.148032) (xy 335.58099 -279.047956) (xy 335.480914 -279.148032) (xy 335.480914 -279.192482)
			(xy 335.681066 -279.192482)
		)
		(stroke
			(width 0)
			(type solid)
		)
		(fill yes)
		(layer "In2.Cu")
		(net "M_C_CPU0_SB_DQ<8>")
	)
	(gr_poly
		(pts
			(xy 335.681066 -278.744172) (xy 335.681066 -278.699722) (xy 335.480914 -278.699722) (xy 335.480914 -278.744172)
			(xy 335.58099 -278.844248)
		)
		(stroke
			(width 0)
			(type solid)
		)
		(fill yes)
		(layer "In2.Cu")
		(net "M_C_CPU0_SB_DQ<7>")
	)
	(gr_poly
		(pts
			(xy 335.681066 -277.52802) (xy 335.58099 -277.427944) (xy 335.480914 -277.52802) (xy 335.480914 -277.57247)
			(xy 335.681066 -277.57247)
		)
		(stroke
			(width 0)
			(type solid)
		)
		(fill yes)
		(layer "In2.Cu")
		(net "M_C_CPU0_SB_DQ<4>")
	)
	(gr_poly
		(pts
			(xy 335.681066 -277.124414) (xy 335.681066 -277.076662) (xy 335.480914 -277.076662) (xy 335.480914 -277.124414)
			(xy 335.58099 -277.224236)
		)
		(stroke
			(width 0)
			(type solid)
		)
		(fill yes)
		(layer "In2.Cu")
		(net "M_C_CPU0_SB_DQS_DP<5>")
	)
	(gr_poly
		(pts
			(xy 335.681066 -275.907754) (xy 335.58099 -275.807932) (xy 335.480914 -275.907754) (xy 335.480914 -275.955506)
			(xy 335.681066 -275.955506)
		)
		(stroke
			(width 0)
			(type solid)
		)
		(fill yes)
		(layer "In2.Cu")
		(net "M_C_CPU0_SB_DQS_DP<0>")
	)
	(gr_poly
		(pts
			(xy 335.681066 -275.504148) (xy 335.681066 -275.459698) (xy 335.480914 -275.459698) (xy 335.480914 -275.504148)
			(xy 335.58099 -275.604224)
		)
		(stroke
			(width 0)
			(type solid)
		)
		(fill yes)
		(layer "In2.Cu")
		(net "M_C_CPU0_SB_DQ<3>")
	)
	(gr_poly
		(pts
			(xy 335.681066 -274.287996) (xy 335.58099 -274.18792) (xy 335.480914 -274.287996) (xy 335.480914 -274.332446)
			(xy 335.681066 -274.332446)
		)
		(stroke
			(width 0)
			(type solid)
		)
		(fill yes)
		(layer "In2.Cu")
		(net "M_C_CPU0_SB_DQ<0>")
	)
	(gr_poly
		(pts
			(xy 335.681066 -273.884136) (xy 335.681066 -273.839686) (xy 335.480914 -273.839686) (xy 335.480914 -273.884136)
			(xy 335.58099 -273.984212)
		)
		(stroke
			(width 0)
			(type solid)
		)
		(fill yes)
		(layer "In2.Cu")
		(net "M_C_CPU0_SB_CB<3>")
	)
	(gr_poly
		(pts
			(xy 335.681066 -272.667984) (xy 335.58099 -272.567908) (xy 335.480914 -272.667984) (xy 335.480914 -272.712434)
			(xy 335.681066 -272.712434)
		)
		(stroke
			(width 0)
			(type solid)
		)
		(fill yes)
		(layer "In2.Cu")
		(net "M_C_CPU0_SB_CB<0>")
	)
	(gr_poly
		(pts
			(xy 335.681066 -272.264378) (xy 335.681066 -272.216626) (xy 335.480914 -272.216626) (xy 335.480914 -272.264378)
			(xy 335.58099 -272.3642)
		)
		(stroke
			(width 0)
			(type solid)
		)
		(fill yes)
		(layer "In2.Cu")
		(net "M_C_CPU0_SB_DQS_DP<4>")
	)
	(gr_poly
		(pts
			(xy 335.681066 -271.047718) (xy 335.58099 -270.947896) (xy 335.480914 -271.047718) (xy 335.480914 -271.09547)
			(xy 335.681066 -271.09547)
		)
		(stroke
			(width 0)
			(type solid)
		)
		(fill yes)
		(layer "In2.Cu")
		(net "M_C_CPU0_SB_DQS_DP<9>")
	)
	(gr_poly
		(pts
			(xy 335.681066 -270.644112) (xy 335.681066 -270.599662) (xy 335.480914 -270.599662) (xy 335.480914 -270.644112)
			(xy 335.58099 -270.744188)
		)
		(stroke
			(width 0)
			(type solid)
		)
		(fill yes)
		(layer "In2.Cu")
		(net "M_C_CPU0_SB_CB<7>")
	)
	(gr_poly
		(pts
			(xy 335.681066 -269.42796) (xy 335.58099 -269.327884) (xy 335.480914 -269.42796) (xy 335.480914 -269.47241)
			(xy 335.681066 -269.47241)
		)
		(stroke
			(width 0)
			(type solid)
		)
		(fill yes)
		(layer "In2.Cu")
		(net "M_C_CPU0_SB_CB<4>")
	)
	(gr_poly
		(pts
			(xy 335.681066 -265.784076) (xy 335.681066 -265.739626) (xy 335.480914 -265.739626) (xy 335.480914 -265.784076)
			(xy 335.58099 -265.884152)
		)
		(stroke
			(width 0)
			(type solid)
		)
		(fill yes)
		(layer "In2.Cu")
		(net "M_C_CPU0_SB_CS_N<0>")
	)
	(gr_poly
		(pts
			(xy 335.681066 -264.567924) (xy 335.58099 -264.467848) (xy 335.480914 -264.567924) (xy 335.480914 -264.612374)
			(xy 335.681066 -264.612374)
		)
		(stroke
			(width 0)
			(type solid)
		)
		(fill yes)
		(layer "In2.Cu")
		(net "M_C_CPU0_SB_CA<6>")
	)
	(gr_poly
		(pts
			(xy 335.681066 -264.164064) (xy 335.681066 -264.119614) (xy 335.480914 -264.119614) (xy 335.480914 -264.164064)
			(xy 335.58099 -264.26414)
		)
		(stroke
			(width 0)
			(type solid)
		)
		(fill yes)
		(layer "In2.Cu")
		(net "M_C_CPU0_SB_CA<5>")
	)
	(gr_poly
		(pts
			(xy 335.681066 -262.947912) (xy 335.58099 -262.847836) (xy 335.480914 -262.947912) (xy 335.480914 -262.992362)
			(xy 335.681066 -262.992362)
		)
		(stroke
			(width 0)
			(type solid)
		)
		(fill yes)
		(layer "In2.Cu")
		(net "M_C_CPU0_SB_CA<2>")
	)
	(gr_poly
		(pts
			(xy 335.681066 -262.544052) (xy 335.681066 -262.499602) (xy 335.480914 -262.499602) (xy 335.480914 -262.544052)
			(xy 335.58099 -262.644128)
		)
		(stroke
			(width 0)
			(type solid)
		)
		(fill yes)
		(layer "In2.Cu")
		(net "M_C_CPU0_SB_CA<1>")
	)
	(gr_poly
		(pts
			(xy 335.687162 -267.801598) (xy 335.58734 -267.701522) (xy 335.487264 -267.801598) (xy 335.487264 -267.846048)
			(xy 335.687162 -267.846048)
		)
		(stroke
			(width 0)
			(type solid)
		)
		(fill yes)
		(layer "In2.Cu")
		(net "M_C_CPU0_SB_RSP<0>")
	)
	(gr_poly
		(pts
			(xy 335.851246 -256.025904) (xy 335.75117 -255.926082) (xy 335.651094 -256.025904) (xy 335.651094 -256.073656)
			(xy 335.851246 -256.073656)
		)
		(stroke
			(width 0)
			(type solid)
		)
		(fill yes)
		(layer "In2.Cu")
		(net "M_C_CPU0_CLK_DP<0>")
	)
	(gr_poly
		(pts
			(xy 335.851246 -255.622298) (xy 335.851246 -255.577848) (xy 335.651094 -255.577848) (xy 335.651094 -255.622298)
			(xy 335.75117 -255.722374)
		)
		(stroke
			(width 0)
			(type solid)
		)
		(fill yes)
		(layer "In2.Cu")
		(net "M_C_CPU0_SA_PAR")
	)
	(gr_poly
		(pts
			(xy 335.851246 -254.406146) (xy 335.75117 -254.30607) (xy 335.651094 -254.406146) (xy 335.651094 -254.450596)
			(xy 335.851246 -254.450596)
		)
		(stroke
			(width 0)
			(type solid)
		)
		(fill yes)
		(layer "In2.Cu")
		(net "M_C_CPU0_SA_CA<4>")
	)
	(gr_poly
		(pts
			(xy 335.851246 -254.002286) (xy 335.851246 -253.957836) (xy 335.651094 -253.957836) (xy 335.651094 -254.002286)
			(xy 335.75117 -254.102362)
		)
		(stroke
			(width 0)
			(type solid)
		)
		(fill yes)
		(layer "In2.Cu")
		(net "M_C_CPU0_SA_CA<3>")
	)
	(gr_poly
		(pts
			(xy 335.851246 -252.786134) (xy 335.75117 -252.686058) (xy 335.651094 -252.786134) (xy 335.651094 -252.830584)
			(xy 335.851246 -252.830584)
		)
		(stroke
			(width 0)
			(type solid)
		)
		(fill yes)
		(layer "In2.Cu")
		(net "M_C_CPU0_SA_CA<0>")
	)
	(gr_poly
		(pts
			(xy 335.851246 -252.382274) (xy 335.851246 -252.337824) (xy 335.651094 -252.337824) (xy 335.651094 -252.382274)
			(xy 335.75117 -252.48235)
		)
		(stroke
			(width 0)
			(type solid)
		)
		(fill yes)
		(layer "In2.Cu")
		(net "M_C_CPU0_SA_CS_N<1>")
	)
	(gr_poly
		(pts
			(xy 335.851246 -250.762262) (xy 335.851246 -250.717812) (xy 335.651094 -250.717812) (xy 335.651094 -250.762262)
			(xy 335.75117 -250.862338)
		)
		(stroke
			(width 0)
			(type solid)
		)
		(fill yes)
		(layer "In2.Cu")
		(net "M_C_CPU0_RESET_N")
	)
	(gr_poly
		(pts
			(xy 335.851246 -249.14225) (xy 335.851246 -249.0978) (xy 335.651094 -249.0978) (xy 335.651094 -249.14225)
			(xy 335.75117 -249.242326)
		)
		(stroke
			(width 0)
			(type solid)
		)
		(fill yes)
		(layer "In2.Cu")
		(net "M_C_CPU0_SA_CB<7>")
	)
	(gr_poly
		(pts
			(xy 335.851246 -247.926098) (xy 335.75117 -247.826022) (xy 335.651094 -247.926098) (xy 335.651094 -247.970548)
			(xy 335.851246 -247.970548)
		)
		(stroke
			(width 0)
			(type solid)
		)
		(fill yes)
		(layer "In2.Cu")
		(net "M_C_CPU0_SA_CB<4>")
	)
	(gr_poly
		(pts
			(xy 335.851246 -247.522492) (xy 335.851246 -247.47474) (xy 335.651094 -247.47474) (xy 335.651094 -247.522492)
			(xy 335.75117 -247.622314)
		)
		(stroke
			(width 0)
			(type solid)
		)
		(fill yes)
		(layer "In2.Cu")
		(net "M_C_CPU0_SA_DQS_DP<9>")
	)
	(gr_poly
		(pts
			(xy 335.851246 -246.305832) (xy 335.75117 -246.20601) (xy 335.651094 -246.305832) (xy 335.651094 -246.353584)
			(xy 335.851246 -246.353584)
		)
		(stroke
			(width 0)
			(type solid)
		)
		(fill yes)
		(layer "In2.Cu")
		(net "M_C_CPU0_SA_DQS_DP<4>")
	)
	(gr_poly
		(pts
			(xy 335.851246 -245.902226) (xy 335.851246 -245.857776) (xy 335.651094 -245.857776) (xy 335.651094 -245.902226)
			(xy 335.75117 -246.002302)
		)
		(stroke
			(width 0)
			(type solid)
		)
		(fill yes)
		(layer "In2.Cu")
		(net "M_C_CPU0_SA_CB<3>")
	)
	(gr_poly
		(pts
			(xy 335.851246 -244.686074) (xy 335.75117 -244.585998) (xy 335.651094 -244.686074) (xy 335.651094 -244.730524)
			(xy 335.851246 -244.730524)
		)
		(stroke
			(width 0)
			(type solid)
		)
		(fill yes)
		(layer "In2.Cu")
		(net "M_C_CPU0_SA_CB<0>")
	)
	(gr_poly
		(pts
			(xy 335.851246 -244.282214) (xy 335.851246 -244.237764) (xy 335.651094 -244.237764) (xy 335.651094 -244.282214)
			(xy 335.75117 -244.38229)
		)
		(stroke
			(width 0)
			(type solid)
		)
		(fill yes)
		(layer "In2.Cu")
		(net "M_C_CPU0_SA_DQ<31>")
	)
	(gr_poly
		(pts
			(xy 335.851246 -243.066062) (xy 335.75117 -242.965986) (xy 335.651094 -243.066062) (xy 335.651094 -243.110512)
			(xy 335.851246 -243.110512)
		)
		(stroke
			(width 0)
			(type solid)
		)
		(fill yes)
		(layer "In2.Cu")
		(net "M_C_CPU0_SA_DQ<28>")
	)
	(gr_poly
		(pts
			(xy 335.851246 -242.662456) (xy 335.851246 -242.614704) (xy 335.651094 -242.614704) (xy 335.651094 -242.662456)
			(xy 335.75117 -242.762278)
		)
		(stroke
			(width 0)
			(type solid)
		)
		(fill yes)
		(layer "In2.Cu")
		(net "M_C_CPU0_SA_DQS_DP<8>")
	)
	(gr_poly
		(pts
			(xy 335.851246 -241.445796) (xy 335.75117 -241.345974) (xy 335.651094 -241.445796) (xy 335.651094 -241.493548)
			(xy 335.851246 -241.493548)
		)
		(stroke
			(width 0)
			(type solid)
		)
		(fill yes)
		(layer "In2.Cu")
		(net "M_C_CPU0_SA_DQS_DP<3>")
	)
	(gr_poly
		(pts
			(xy 335.851246 -241.04219) (xy 335.851246 -240.99774) (xy 335.651094 -240.99774) (xy 335.651094 -241.04219)
			(xy 335.75117 -241.142266)
		)
		(stroke
			(width 0)
			(type solid)
		)
		(fill yes)
		(layer "In2.Cu")
		(net "M_C_CPU0_SA_DQ<27>")
	)
	(gr_poly
		(pts
			(xy 335.851246 -239.826038) (xy 335.75117 -239.725962) (xy 335.651094 -239.826038) (xy 335.651094 -239.870488)
			(xy 335.851246 -239.870488)
		)
		(stroke
			(width 0)
			(type solid)
		)
		(fill yes)
		(layer "In2.Cu")
		(net "M_C_CPU0_SA_DQ<24>")
	)
	(gr_poly
		(pts
			(xy 335.851246 -239.422178) (xy 335.851246 -239.377728) (xy 335.651094 -239.377728) (xy 335.651094 -239.422178)
			(xy 335.75117 -239.522254)
		)
		(stroke
			(width 0)
			(type solid)
		)
		(fill yes)
		(layer "In2.Cu")
		(net "M_C_CPU0_SA_DQ<23>")
	)
	(gr_poly
		(pts
			(xy 335.851246 -238.206026) (xy 335.75117 -238.10595) (xy 335.651094 -238.206026) (xy 335.651094 -238.250476)
			(xy 335.851246 -238.250476)
		)
		(stroke
			(width 0)
			(type solid)
		)
		(fill yes)
		(layer "In2.Cu")
		(net "M_C_CPU0_SA_DQ<20>")
	)
	(gr_poly
		(pts
			(xy 335.851246 -237.80242) (xy 335.851246 -237.754668) (xy 335.651094 -237.754668) (xy 335.651094 -237.80242)
			(xy 335.75117 -237.902242)
		)
		(stroke
			(width 0)
			(type solid)
		)
		(fill yes)
		(layer "In2.Cu")
		(net "M_C_CPU0_SA_DQS_DP<7>")
	)
	(gr_poly
		(pts
			(xy 335.851246 -236.58576) (xy 335.75117 -236.485938) (xy 335.651094 -236.58576) (xy 335.651094 -236.633512)
			(xy 335.851246 -236.633512)
		)
		(stroke
			(width 0)
			(type solid)
		)
		(fill yes)
		(layer "In2.Cu")
		(net "M_C_CPU0_SA_DQS_DP<2>")
	)
	(gr_poly
		(pts
			(xy 335.851246 -236.182154) (xy 335.851246 -236.137704) (xy 335.651094 -236.137704) (xy 335.651094 -236.182154)
			(xy 335.75117 -236.28223)
		)
		(stroke
			(width 0)
			(type solid)
		)
		(fill yes)
		(layer "In2.Cu")
		(net "M_C_CPU0_SA_DQ<19>")
	)
	(gr_poly
		(pts
			(xy 335.851246 -234.966002) (xy 335.75117 -234.865926) (xy 335.651094 -234.966002) (xy 335.651094 -235.010452)
			(xy 335.851246 -235.010452)
		)
		(stroke
			(width 0)
			(type solid)
		)
		(fill yes)
		(layer "In2.Cu")
		(net "M_C_CPU0_SA_DQ<16>")
	)
	(gr_poly
		(pts
			(xy 335.851246 -234.562142) (xy 335.851246 -234.517692) (xy 335.651094 -234.517692) (xy 335.651094 -234.562142)
			(xy 335.75117 -234.662218)
		)
		(stroke
			(width 0)
			(type solid)
		)
		(fill yes)
		(layer "In2.Cu")
		(net "M_C_CPU0_SA_DQ<15>")
	)
	(gr_poly
		(pts
			(xy 335.851246 -233.34599) (xy 335.75117 -233.245914) (xy 335.651094 -233.34599) (xy 335.651094 -233.39044)
			(xy 335.851246 -233.39044)
		)
		(stroke
			(width 0)
			(type solid)
		)
		(fill yes)
		(layer "In2.Cu")
		(net "M_C_CPU0_SA_DQ<12>")
	)
	(gr_poly
		(pts
			(xy 335.851246 -232.942384) (xy 335.851246 -232.894632) (xy 335.651094 -232.894632) (xy 335.651094 -232.942384)
			(xy 335.75117 -233.042206)
		)
		(stroke
			(width 0)
			(type solid)
		)
		(fill yes)
		(layer "In2.Cu")
		(net "M_C_CPU0_SA_DQS_DP<6>")
	)
	(gr_poly
		(pts
			(xy 335.851246 -231.725724) (xy 335.75117 -231.625902) (xy 335.651094 -231.725724) (xy 335.651094 -231.773476)
			(xy 335.851246 -231.773476)
		)
		(stroke
			(width 0)
			(type solid)
		)
		(fill yes)
		(layer "In2.Cu")
		(net "M_C_CPU0_SA_DQS_DP<1>")
	)
	(gr_poly
		(pts
			(xy 335.851246 -231.322372) (xy 335.851246 -231.277922) (xy 335.651094 -231.277922) (xy 335.651094 -231.322372)
			(xy 335.75117 -231.422448)
		)
		(stroke
			(width 0)
			(type solid)
		)
		(fill yes)
		(layer "In2.Cu")
		(net "M_C_CPU0_SA_DQ<11>")
	)
	(gr_poly
		(pts
			(xy 335.851246 -230.105966) (xy 335.75117 -230.006144) (xy 335.651094 -230.105966) (xy 335.651094 -230.150416)
			(xy 335.851246 -230.150416)
		)
		(stroke
			(width 0)
			(type solid)
		)
		(fill yes)
		(layer "In2.Cu")
		(net "M_C_CPU0_SA_DQ<8>")
	)
	(gr_poly
		(pts
			(xy 335.851246 -229.70236) (xy 335.851246 -229.65791) (xy 335.651094 -229.65791) (xy 335.651094 -229.70236)
			(xy 335.75117 -229.802436)
		)
		(stroke
			(width 0)
			(type solid)
		)
		(fill yes)
		(layer "In2.Cu")
		(net "M_C_CPU0_SA_DQ<7>")
	)
	(gr_poly
		(pts
			(xy 335.851246 -228.486208) (xy 335.75117 -228.386132) (xy 335.651094 -228.486208) (xy 335.651094 -228.530658)
			(xy 335.851246 -228.530658)
		)
		(stroke
			(width 0)
			(type solid)
		)
		(fill yes)
		(layer "In2.Cu")
		(net "M_C_CPU0_SA_DQ<4>")
	)
	(gr_poly
		(pts
			(xy 335.851246 -228.082602) (xy 335.851246 -228.03485) (xy 335.651094 -228.03485) (xy 335.651094 -228.082602)
			(xy 335.75117 -228.182424)
		)
		(stroke
			(width 0)
			(type solid)
		)
		(fill yes)
		(layer "In2.Cu")
		(net "M_C_CPU0_SA_DQS_DP<5>")
	)
	(gr_poly
		(pts
			(xy 335.851246 -226.865942) (xy 335.75117 -226.76612) (xy 335.651094 -226.865942) (xy 335.651094 -226.913694)
			(xy 335.851246 -226.913694)
		)
		(stroke
			(width 0)
			(type solid)
		)
		(fill yes)
		(layer "In2.Cu")
		(net "M_C_CPU0_SA_DQS_DP<0>")
	)
	(gr_poly
		(pts
			(xy 335.851246 -226.462336) (xy 335.851246 -226.417886) (xy 335.651094 -226.417886) (xy 335.651094 -226.462336)
			(xy 335.75117 -226.562412)
		)
		(stroke
			(width 0)
			(type solid)
		)
		(fill yes)
		(layer "In2.Cu")
		(net "M_C_CPU0_SA_DQ<3>")
	)
	(gr_poly
		(pts
			(xy 335.851246 -225.246184) (xy 335.75117 -225.146108) (xy 335.651094 -225.246184) (xy 335.651094 -225.290634)
			(xy 335.851246 -225.290634)
		)
		(stroke
			(width 0)
			(type solid)
		)
		(fill yes)
		(layer "In2.Cu")
		(net "M_C_CPU0_SA_DQ<0>")
	)
	(gr_poly
		(pts
			(xy 336.143854 -291.297614) (xy 336.043778 -291.197792) (xy 335.943702 -291.297614) (xy 335.943702 -291.345366)
			(xy 336.143854 -291.345366)
		)
		(stroke
			(width 0)
			(type solid)
		)
		(fill yes)
		(layer "In2.Cu")
		(net "M_C_CPU0_SB_DQS_DN<8>")
	)
	(gr_poly
		(pts
			(xy 336.14487 -266.991592) (xy 336.044794 -266.891516) (xy 335.944972 -266.991592) (xy 335.944972 -267.036042)
			(xy 336.14487 -267.036042)
		)
		(stroke
			(width 0)
			(type solid)
		)
		(fill yes)
		(layer "In2.Cu")
		(net "M_C_CPU0_SA_RSP<0>")
	)
	(gr_poly
		(pts
			(xy 336.15122 -292.91788) (xy 336.051144 -292.817804) (xy 335.951068 -292.91788) (xy 335.951068 -292.96233)
			(xy 336.15122 -292.96233)
		)
		(stroke
			(width 0)
			(type solid)
		)
		(fill yes)
		(layer "In2.Cu")
		(net "M_C_CPU0_SB_DQ<29>")
	)
	(gr_poly
		(pts
			(xy 336.15122 -292.51402) (xy 336.15122 -292.46957) (xy 335.951068 -292.46957) (xy 335.951068 -292.51402)
			(xy 336.051144 -292.614096)
		)
		(stroke
			(width 0)
			(type solid)
		)
		(fill yes)
		(layer "In2.Cu")
		(net "M_C_CPU0_SB_DQ<30>")
	)
	(gr_poly
		(pts
			(xy 336.15122 -290.894262) (xy 336.15122 -290.84651) (xy 335.951068 -290.84651) (xy 335.951068 -290.894262)
			(xy 336.051144 -290.994084)
		)
		(stroke
			(width 0)
			(type solid)
		)
		(fill yes)
		(layer "In2.Cu")
		(net "M_C_CPU0_SB_DQS_DN<3>")
	)
	(gr_poly
		(pts
			(xy 336.15122 -289.677856) (xy 336.051144 -289.57778) (xy 335.951068 -289.677856) (xy 335.951068 -289.722306)
			(xy 336.15122 -289.722306)
		)
		(stroke
			(width 0)
			(type solid)
		)
		(fill yes)
		(layer "In2.Cu")
		(net "M_C_CPU0_SB_DQ<25>")
	)
	(gr_poly
		(pts
			(xy 336.15122 -289.273996) (xy 336.15122 -289.229546) (xy 335.951068 -289.229546) (xy 335.951068 -289.273996)
			(xy 336.051144 -289.374072)
		)
		(stroke
			(width 0)
			(type solid)
		)
		(fill yes)
		(layer "In2.Cu")
		(net "M_C_CPU0_SB_DQ<26>")
	)
	(gr_poly
		(pts
			(xy 336.15122 -288.057844) (xy 336.051144 -287.957768) (xy 335.951068 -288.057844) (xy 335.951068 -288.102294)
			(xy 336.15122 -288.102294)
		)
		(stroke
			(width 0)
			(type solid)
		)
		(fill yes)
		(layer "In2.Cu")
		(net "M_C_CPU0_SB_DQ<21>")
	)
	(gr_poly
		(pts
			(xy 336.15122 -287.654238) (xy 336.15122 -287.609788) (xy 335.951068 -287.609788) (xy 335.951068 -287.654238)
			(xy 336.051144 -287.75406)
		)
		(stroke
			(width 0)
			(type solid)
		)
		(fill yes)
		(layer "In2.Cu")
		(net "M_C_CPU0_SB_DQ<22>")
	)
	(gr_poly
		(pts
			(xy 336.15122 -286.437832) (xy 336.051144 -286.337756) (xy 335.951068 -286.437832) (xy 335.951068 -286.485584)
			(xy 336.15122 -286.485584)
		)
		(stroke
			(width 0)
			(type solid)
		)
		(fill yes)
		(layer "In2.Cu")
		(net "M_C_CPU0_SB_DQS_DN<7>")
	)
	(gr_poly
		(pts
			(xy 336.15122 -286.03448) (xy 336.15122 -285.986728) (xy 335.951068 -285.986728) (xy 335.951068 -286.03448)
			(xy 336.051144 -286.134302)
		)
		(stroke
			(width 0)
			(type solid)
		)
		(fill yes)
		(layer "In2.Cu")
		(net "M_C_CPU0_SB_DQS_DN<2>")
	)
	(gr_poly
		(pts
			(xy 336.15122 -284.818074) (xy 336.051144 -284.717998) (xy 335.951068 -284.818074) (xy 335.951068 -284.862524)
			(xy 336.15122 -284.862524)
		)
		(stroke
			(width 0)
			(type solid)
		)
		(fill yes)
		(layer "In2.Cu")
		(net "M_C_CPU0_SB_DQ<17>")
	)
	(gr_poly
		(pts
			(xy 336.15122 -284.414214) (xy 336.15122 -284.369764) (xy 335.951068 -284.369764) (xy 335.951068 -284.414214)
			(xy 336.051144 -284.51429)
		)
		(stroke
			(width 0)
			(type solid)
		)
		(fill yes)
		(layer "In2.Cu")
		(net "M_C_CPU0_SB_DQ<18>")
	)
	(gr_poly
		(pts
			(xy 336.15122 -283.198062) (xy 336.051144 -283.097986) (xy 335.951068 -283.198062) (xy 335.951068 -283.242512)
			(xy 336.15122 -283.242512)
		)
		(stroke
			(width 0)
			(type solid)
		)
		(fill yes)
		(layer "In2.Cu")
		(net "M_C_CPU0_SB_DQ<13>")
	)
	(gr_poly
		(pts
			(xy 336.15122 -282.794202) (xy 336.15122 -282.749752) (xy 335.951068 -282.749752) (xy 335.951068 -282.794202)
			(xy 336.051144 -282.894278)
		)
		(stroke
			(width 0)
			(type solid)
		)
		(fill yes)
		(layer "In2.Cu")
		(net "M_C_CPU0_SB_DQ<14>")
	)
	(gr_poly
		(pts
			(xy 336.15122 -281.577796) (xy 336.051144 -281.477974) (xy 335.951068 -281.577796) (xy 335.951068 -281.625548)
			(xy 336.15122 -281.625548)
		)
		(stroke
			(width 0)
			(type solid)
		)
		(fill yes)
		(layer "In2.Cu")
		(net "M_C_CPU0_SB_DQS_DN<6>")
	)
	(gr_poly
		(pts
			(xy 336.15122 -281.174444) (xy 336.15122 -281.126692) (xy 335.951068 -281.126692) (xy 335.951068 -281.174444)
			(xy 336.051144 -281.274266)
		)
		(stroke
			(width 0)
			(type solid)
		)
		(fill yes)
		(layer "In2.Cu")
		(net "M_C_CPU0_SB_DQS_DN<1>")
	)
	(gr_poly
		(pts
			(xy 336.15122 -279.958038) (xy 336.051144 -279.857962) (xy 335.951068 -279.958038) (xy 335.951068 -280.002488)
			(xy 336.15122 -280.002488)
		)
		(stroke
			(width 0)
			(type solid)
		)
		(fill yes)
		(layer "In2.Cu")
		(net "M_C_CPU0_SB_DQ<9>")
	)
	(gr_poly
		(pts
			(xy 336.15122 -279.554178) (xy 336.15122 -279.509728) (xy 335.951068 -279.509728) (xy 335.951068 -279.554178)
			(xy 336.051144 -279.654254)
		)
		(stroke
			(width 0)
			(type solid)
		)
		(fill yes)
		(layer "In2.Cu")
		(net "M_C_CPU0_SB_DQ<10>")
	)
	(gr_poly
		(pts
			(xy 336.15122 -278.338026) (xy 336.051144 -278.23795) (xy 335.951068 -278.338026) (xy 335.951068 -278.382476)
			(xy 336.15122 -278.382476)
		)
		(stroke
			(width 0)
			(type solid)
		)
		(fill yes)
		(layer "In2.Cu")
		(net "M_C_CPU0_SB_DQ<5>")
	)
	(gr_poly
		(pts
			(xy 336.15122 -277.934166) (xy 336.15122 -277.889716) (xy 335.951068 -277.889716) (xy 335.951068 -277.934166)
			(xy 336.051144 -278.034242)
		)
		(stroke
			(width 0)
			(type solid)
		)
		(fill yes)
		(layer "In2.Cu")
		(net "M_C_CPU0_SB_DQ<6>")
	)
	(gr_poly
		(pts
			(xy 336.15122 -276.71776) (xy 336.051144 -276.617938) (xy 335.951068 -276.71776) (xy 335.951068 -276.765512)
			(xy 336.15122 -276.765512)
		)
		(stroke
			(width 0)
			(type solid)
		)
		(fill yes)
		(layer "In2.Cu")
		(net "M_C_CPU0_SB_DQS_DN<5>")
	)
	(gr_poly
		(pts
			(xy 336.15122 -276.314408) (xy 336.15122 -276.266656) (xy 335.951068 -276.266656) (xy 335.951068 -276.314408)
			(xy 336.051144 -276.41423)
		)
		(stroke
			(width 0)
			(type solid)
		)
		(fill yes)
		(layer "In2.Cu")
		(net "M_C_CPU0_SB_DQS_DN<0>")
	)
	(gr_poly
		(pts
			(xy 336.15122 -275.098002) (xy 336.051144 -274.997926) (xy 335.951068 -275.098002) (xy 335.951068 -275.142452)
			(xy 336.15122 -275.142452)
		)
		(stroke
			(width 0)
			(type solid)
		)
		(fill yes)
		(layer "In2.Cu")
		(net "M_C_CPU0_SB_DQ<1>")
	)
	(gr_poly
		(pts
			(xy 336.15122 -274.694142) (xy 336.15122 -274.649692) (xy 335.951068 -274.649692) (xy 335.951068 -274.694142)
			(xy 336.051144 -274.794218)
		)
		(stroke
			(width 0)
			(type solid)
		)
		(fill yes)
		(layer "In2.Cu")
		(net "M_C_CPU0_SB_DQ<2>")
	)
	(gr_poly
		(pts
			(xy 336.15122 -273.47799) (xy 336.051144 -273.377914) (xy 335.951068 -273.47799) (xy 335.951068 -273.52244)
			(xy 336.15122 -273.52244)
		)
		(stroke
			(width 0)
			(type solid)
		)
		(fill yes)
		(layer "In2.Cu")
		(net "M_C_CPU0_SB_CB<1>")
	)
	(gr_poly
		(pts
			(xy 336.15122 -273.07413) (xy 336.15122 -273.02968) (xy 335.951068 -273.02968) (xy 335.951068 -273.07413)
			(xy 336.051144 -273.174206)
		)
		(stroke
			(width 0)
			(type solid)
		)
		(fill yes)
		(layer "In2.Cu")
		(net "M_C_CPU0_SB_CB<2>")
	)
	(gr_poly
		(pts
			(xy 336.15122 -271.857724) (xy 336.051144 -271.757902) (xy 335.951068 -271.857724) (xy 335.951068 -271.905476)
			(xy 336.15122 -271.905476)
		)
		(stroke
			(width 0)
			(type solid)
		)
		(fill yes)
		(layer "In2.Cu")
		(net "M_C_CPU0_SB_DQS_DN<4>")
	)
	(gr_poly
		(pts
			(xy 336.15122 -271.454372) (xy 336.15122 -271.40662) (xy 335.951068 -271.40662) (xy 335.951068 -271.454372)
			(xy 336.051144 -271.554194)
		)
		(stroke
			(width 0)
			(type solid)
		)
		(fill yes)
		(layer "In2.Cu")
		(net "M_C_CPU0_SB_DQS_DN<9>")
	)
	(gr_poly
		(pts
			(xy 336.15122 -270.237966) (xy 336.051144 -270.13789) (xy 335.951068 -270.237966) (xy 335.951068 -270.282416)
			(xy 336.15122 -270.282416)
		)
		(stroke
			(width 0)
			(type solid)
		)
		(fill yes)
		(layer "In2.Cu")
		(net "M_C_CPU0_SB_CB<5>")
	)
	(gr_poly
		(pts
			(xy 336.15122 -269.834106) (xy 336.15122 -269.789656) (xy 335.951068 -269.789656) (xy 335.951068 -269.834106)
			(xy 336.051144 -269.934182)
		)
		(stroke
			(width 0)
			(type solid)
		)
		(fill yes)
		(layer "In2.Cu")
		(net "M_C_CPU0_SB_CB<6>")
	)
	(gr_poly
		(pts
			(xy 336.15122 -266.594082) (xy 336.15122 -266.549632) (xy 335.951068 -266.549632) (xy 335.951068 -266.594082)
			(xy 336.051144 -266.694158)
		)
		(stroke
			(width 0)
			(type solid)
		)
		(fill yes)
		(layer "In2.Cu")
		(net "M_C_CPU0_SB_CS_N<1>")
	)
	(gr_poly
		(pts
			(xy 336.15122 -264.97407) (xy 336.15122 -264.92962) (xy 335.951068 -264.92962) (xy 335.951068 -264.97407)
			(xy 336.051144 -265.074146)
		)
		(stroke
			(width 0)
			(type solid)
		)
		(fill yes)
		(layer "In2.Cu")
		(net "M_C_CPU0_SB_PAR")
	)
	(gr_poly
		(pts
			(xy 336.15122 -263.757918) (xy 336.051144 -263.657842) (xy 335.951068 -263.757918) (xy 335.951068 -263.802368)
			(xy 336.15122 -263.802368)
		)
		(stroke
			(width 0)
			(type solid)
		)
		(fill yes)
		(layer "In2.Cu")
		(net "M_C_CPU0_SB_CA<4>")
	)
	(gr_poly
		(pts
			(xy 336.15122 -263.354058) (xy 336.15122 -263.309608) (xy 335.951068 -263.309608) (xy 335.951068 -263.354058)
			(xy 336.051144 -263.454134)
		)
		(stroke
			(width 0)
			(type solid)
		)
		(fill yes)
		(layer "In2.Cu")
		(net "M_C_CPU0_SB_CA<3>")
	)
	(gr_poly
		(pts
			(xy 336.15122 -262.137906) (xy 336.051144 -262.03783) (xy 335.951068 -262.137906) (xy 335.951068 -262.182356)
			(xy 336.15122 -262.182356)
		)
		(stroke
			(width 0)
			(type solid)
		)
		(fill yes)
		(layer "In2.Cu")
		(net "M_C_CPU0_SB_CA<0>")
	)
	(gr_poly
		(pts
			(xy 336.320892 -246.712232) (xy 336.320892 -246.664734) (xy 336.120994 -246.664734) (xy 336.120994 -246.712232)
			(xy 336.220816 -246.812308)
		)
		(stroke
			(width 0)
			(type solid)
		)
		(fill yes)
		(layer "In2.Cu")
		(net "M_C_CPU0_SA_DQS_DN<4>")
	)
	(gr_poly
		(pts
			(xy 336.321146 -256.432558) (xy 336.321146 -256.384806) (xy 336.120994 -256.384806) (xy 336.120994 -256.432558)
			(xy 336.22107 -256.53238)
		)
		(stroke
			(width 0)
			(type solid)
		)
		(fill yes)
		(layer "In2.Cu")
		(net "M_C_CPU0_CLK_DN<0>")
	)
	(gr_poly
		(pts
			(xy 336.321146 -255.216152) (xy 336.22107 -255.116076) (xy 336.120994 -255.216152) (xy 336.120994 -255.260602)
			(xy 336.321146 -255.260602)
		)
		(stroke
			(width 0)
			(type solid)
		)
		(fill yes)
		(layer "In2.Cu")
		(net "M_C_CPU0_SA_CA<6>")
	)
	(gr_poly
		(pts
			(xy 336.321146 -254.812292) (xy 336.321146 -254.767842) (xy 336.120994 -254.767842) (xy 336.120994 -254.812292)
			(xy 336.22107 -254.912368)
		)
		(stroke
			(width 0)
			(type solid)
		)
		(fill yes)
		(layer "In2.Cu")
		(net "M_C_CPU0_SA_CA<5>")
	)
	(gr_poly
		(pts
			(xy 336.321146 -253.59614) (xy 336.22107 -253.496064) (xy 336.120994 -253.59614) (xy 336.120994 -253.64059)
			(xy 336.321146 -253.64059)
		)
		(stroke
			(width 0)
			(type solid)
		)
		(fill yes)
		(layer "In2.Cu")
		(net "M_C_CPU0_SA_CA<2>")
	)
	(gr_poly
		(pts
			(xy 336.321146 -253.19228) (xy 336.321146 -253.14783) (xy 336.120994 -253.14783) (xy 336.120994 -253.19228)
			(xy 336.22107 -253.292356)
		)
		(stroke
			(width 0)
			(type solid)
		)
		(fill yes)
		(layer "In2.Cu")
		(net "M_C_CPU0_SA_CA<1>")
	)
	(gr_poly
		(pts
			(xy 336.321146 -251.572268) (xy 336.321146 -251.527818) (xy 336.120994 -251.527818) (xy 336.120994 -251.572268)
			(xy 336.22107 -251.672344)
		)
		(stroke
			(width 0)
			(type solid)
		)
		(fill yes)
		(layer "In2.Cu")
		(net "M_C_CPU0_SA_CS_N<0>")
	)
	(gr_poly
		(pts
			(xy 336.321146 -250.356116) (xy 336.22107 -250.25604) (xy 336.120994 -250.356116) (xy 336.120994 -250.400566)
			(xy 336.321146 -250.400566)
		)
		(stroke
			(width 0)
			(type solid)
		)
		(fill yes)
		(layer "In2.Cu")
		(net "M_C_CPU0_ALERT_R_N")
	)
	(gr_poly
		(pts
			(xy 336.321146 -248.736104) (xy 336.22107 -248.636028) (xy 336.120994 -248.736104) (xy 336.120994 -248.780554)
			(xy 336.321146 -248.780554)
		)
		(stroke
			(width 0)
			(type solid)
		)
		(fill yes)
		(layer "In2.Cu")
		(net "M_C_CPU0_SA_CB<5>")
	)
	(gr_poly
		(pts
			(xy 336.321146 -248.332244) (xy 336.321146 -248.287794) (xy 336.120994 -248.287794) (xy 336.120994 -248.332244)
			(xy 336.22107 -248.43232)
		)
		(stroke
			(width 0)
			(type solid)
		)
		(fill yes)
		(layer "In2.Cu")
		(net "M_C_CPU0_SA_CB<6>")
	)
	(gr_poly
		(pts
			(xy 336.321146 -247.115838) (xy 336.22107 -247.016016) (xy 336.120994 -247.115838) (xy 336.120994 -247.16359)
			(xy 336.321146 -247.16359)
		)
		(stroke
			(width 0)
			(type solid)
		)
		(fill yes)
		(layer "In2.Cu")
		(net "M_C_CPU0_SA_DQS_DN<9>")
	)
	(gr_poly
		(pts
			(xy 336.321146 -245.49608) (xy 336.22107 -245.396004) (xy 336.120994 -245.49608) (xy 336.120994 -245.54053)
			(xy 336.321146 -245.54053)
		)
		(stroke
			(width 0)
			(type solid)
		)
		(fill yes)
		(layer "In2.Cu")
		(net "M_C_CPU0_SA_CB<1>")
	)
	(gr_poly
		(pts
			(xy 336.321146 -245.09222) (xy 336.321146 -245.04777) (xy 336.120994 -245.04777) (xy 336.120994 -245.09222)
			(xy 336.22107 -245.192296)
		)
		(stroke
			(width 0)
			(type solid)
		)
		(fill yes)
		(layer "In2.Cu")
		(net "M_C_CPU0_SA_CB<2>")
	)
	(gr_poly
		(pts
			(xy 336.321146 -243.876068) (xy 336.22107 -243.775992) (xy 336.120994 -243.876068) (xy 336.120994 -243.920518)
			(xy 336.321146 -243.920518)
		)
		(stroke
			(width 0)
			(type solid)
		)
		(fill yes)
		(layer "In2.Cu")
		(net "M_C_CPU0_SA_DQ<29>")
	)
	(gr_poly
		(pts
			(xy 336.321146 -243.472208) (xy 336.321146 -243.427758) (xy 336.120994 -243.427758) (xy 336.120994 -243.472208)
			(xy 336.22107 -243.572284)
		)
		(stroke
			(width 0)
			(type solid)
		)
		(fill yes)
		(layer "In2.Cu")
		(net "M_C_CPU0_SA_DQ<30>")
	)
	(gr_poly
		(pts
			(xy 336.321146 -242.255802) (xy 336.22107 -242.15598) (xy 336.120994 -242.255802) (xy 336.120994 -242.303554)
			(xy 336.321146 -242.303554)
		)
		(stroke
			(width 0)
			(type solid)
		)
		(fill yes)
		(layer "In2.Cu")
		(net "M_C_CPU0_SA_DQS_DN<8>")
	)
	(gr_poly
		(pts
			(xy 336.321146 -241.85245) (xy 336.321146 -241.804698) (xy 336.120994 -241.804698) (xy 336.120994 -241.85245)
			(xy 336.22107 -241.952272)
		)
		(stroke
			(width 0)
			(type solid)
		)
		(fill yes)
		(layer "In2.Cu")
		(net "M_C_CPU0_SA_DQS_DN<3>")
	)
	(gr_poly
		(pts
			(xy 336.321146 -240.636044) (xy 336.22107 -240.535968) (xy 336.120994 -240.636044) (xy 336.120994 -240.680494)
			(xy 336.321146 -240.680494)
		)
		(stroke
			(width 0)
			(type solid)
		)
		(fill yes)
		(layer "In2.Cu")
		(net "M_C_CPU0_SA_DQ<25>")
	)
	(gr_poly
		(pts
			(xy 336.321146 -240.232184) (xy 336.321146 -240.187734) (xy 336.120994 -240.187734) (xy 336.120994 -240.232184)
			(xy 336.22107 -240.33226)
		)
		(stroke
			(width 0)
			(type solid)
		)
		(fill yes)
		(layer "In2.Cu")
		(net "M_C_CPU0_SA_DQ<26>")
	)
	(gr_poly
		(pts
			(xy 336.321146 -239.016032) (xy 336.22107 -238.915956) (xy 336.120994 -239.016032) (xy 336.120994 -239.060482)
			(xy 336.321146 -239.060482)
		)
		(stroke
			(width 0)
			(type solid)
		)
		(fill yes)
		(layer "In2.Cu")
		(net "M_C_CPU0_SA_DQ<21>")
	)
	(gr_poly
		(pts
			(xy 336.321146 -238.612172) (xy 336.321146 -238.567722) (xy 336.120994 -238.567722) (xy 336.120994 -238.612172)
			(xy 336.22107 -238.712248)
		)
		(stroke
			(width 0)
			(type solid)
		)
		(fill yes)
		(layer "In2.Cu")
		(net "M_C_CPU0_SA_DQ<22>")
	)
	(gr_poly
		(pts
			(xy 336.321146 -237.395766) (xy 336.22107 -237.295944) (xy 336.120994 -237.395766) (xy 336.120994 -237.443518)
			(xy 336.321146 -237.443518)
		)
		(stroke
			(width 0)
			(type solid)
		)
		(fill yes)
		(layer "In2.Cu")
		(net "M_C_CPU0_SA_DQS_DN<7>")
	)
	(gr_poly
		(pts
			(xy 336.321146 -236.992414) (xy 336.321146 -236.944662) (xy 336.120994 -236.944662) (xy 336.120994 -236.992414)
			(xy 336.22107 -237.092236)
		)
		(stroke
			(width 0)
			(type solid)
		)
		(fill yes)
		(layer "In2.Cu")
		(net "M_C_CPU0_SA_DQS_DN<2>")
	)
	(gr_poly
		(pts
			(xy 336.321146 -235.776008) (xy 336.22107 -235.675932) (xy 336.120994 -235.776008) (xy 336.120994 -235.820458)
			(xy 336.321146 -235.820458)
		)
		(stroke
			(width 0)
			(type solid)
		)
		(fill yes)
		(layer "In2.Cu")
		(net "M_C_CPU0_SA_DQ<17>")
	)
	(gr_poly
		(pts
			(xy 336.321146 -235.372148) (xy 336.321146 -235.327698) (xy 336.120994 -235.327698) (xy 336.120994 -235.372148)
			(xy 336.22107 -235.472224)
		)
		(stroke
			(width 0)
			(type solid)
		)
		(fill yes)
		(layer "In2.Cu")
		(net "M_C_CPU0_SA_DQ<18>")
	)
	(gr_poly
		(pts
			(xy 336.321146 -234.155996) (xy 336.22107 -234.05592) (xy 336.120994 -234.155996) (xy 336.120994 -234.200446)
			(xy 336.321146 -234.200446)
		)
		(stroke
			(width 0)
			(type solid)
		)
		(fill yes)
		(layer "In2.Cu")
		(net "M_C_CPU0_SA_DQ<13>")
	)
	(gr_poly
		(pts
			(xy 336.321146 -233.752136) (xy 336.321146 -233.707686) (xy 336.120994 -233.707686) (xy 336.120994 -233.752136)
			(xy 336.22107 -233.852212)
		)
		(stroke
			(width 0)
			(type solid)
		)
		(fill yes)
		(layer "In2.Cu")
		(net "M_C_CPU0_SA_DQ<14>")
	)
	(gr_poly
		(pts
			(xy 336.321146 -232.53573) (xy 336.22107 -232.435908) (xy 336.120994 -232.53573) (xy 336.120994 -232.583482)
			(xy 336.321146 -232.583482)
		)
		(stroke
			(width 0)
			(type solid)
		)
		(fill yes)
		(layer "In2.Cu")
		(net "M_C_CPU0_SA_DQS_DN<6>")
	)
	(gr_poly
		(pts
			(xy 336.321146 -232.132378) (xy 336.321146 -232.084626) (xy 336.120994 -232.084626) (xy 336.120994 -232.132378)
			(xy 336.22107 -232.2322)
		)
		(stroke
			(width 0)
			(type solid)
		)
		(fill yes)
		(layer "In2.Cu")
		(net "M_C_CPU0_SA_DQS_DN<1>")
	)
	(gr_poly
		(pts
			(xy 336.321146 -230.915972) (xy 336.22107 -230.815896) (xy 336.120994 -230.915972) (xy 336.120994 -230.960422)
			(xy 336.321146 -230.960422)
		)
		(stroke
			(width 0)
			(type solid)
		)
		(fill yes)
		(layer "In2.Cu")
		(net "M_C_CPU0_SA_DQ<9>")
	)
	(gr_poly
		(pts
			(xy 336.321146 -230.512366) (xy 336.321146 -230.467916) (xy 336.120994 -230.467916) (xy 336.120994 -230.512366)
			(xy 336.22107 -230.612188)
		)
		(stroke
			(width 0)
			(type solid)
		)
		(fill yes)
		(layer "In2.Cu")
		(net "M_C_CPU0_SA_DQ<10>")
	)
	(gr_poly
		(pts
			(xy 336.321146 -229.29596) (xy 336.22107 -229.195884) (xy 336.120994 -229.29596) (xy 336.120994 -229.34041)
			(xy 336.321146 -229.34041)
		)
		(stroke
			(width 0)
			(type solid)
		)
		(fill yes)
		(layer "In2.Cu")
		(net "M_C_CPU0_SA_DQ<5>")
	)
	(gr_poly
		(pts
			(xy 336.321146 -228.892354) (xy 336.321146 -228.847904) (xy 336.120994 -228.847904) (xy 336.120994 -228.892354)
			(xy 336.22107 -228.99243)
		)
		(stroke
			(width 0)
			(type solid)
		)
		(fill yes)
		(layer "In2.Cu")
		(net "M_C_CPU0_SA_DQ<6>")
	)
	(gr_poly
		(pts
			(xy 336.321146 -227.675948) (xy 336.22107 -227.576126) (xy 336.120994 -227.675948) (xy 336.120994 -227.7237)
			(xy 336.321146 -227.7237)
		)
		(stroke
			(width 0)
			(type solid)
		)
		(fill yes)
		(layer "In2.Cu")
		(net "M_C_CPU0_SA_DQS_DN<5>")
	)
	(gr_poly
		(pts
			(xy 336.321146 -227.272596) (xy 336.321146 -227.224844) (xy 336.120994 -227.224844) (xy 336.120994 -227.272596)
			(xy 336.22107 -227.372418)
		)
		(stroke
			(width 0)
			(type solid)
		)
		(fill yes)
		(layer "In2.Cu")
		(net "M_C_CPU0_SA_DQS_DN<0>")
	)
	(gr_poly
		(pts
			(xy 336.321146 -226.05619) (xy 336.22107 -225.956114) (xy 336.120994 -226.05619) (xy 336.120994 -226.10064)
			(xy 336.321146 -226.10064)
		)
		(stroke
			(width 0)
			(type solid)
		)
		(fill yes)
		(layer "In2.Cu")
		(net "M_C_CPU0_SA_DQ<1>")
	)
	(gr_poly
		(pts
			(xy 336.321146 -225.65233) (xy 336.321146 -225.60788) (xy 336.120994 -225.60788) (xy 336.120994 -225.65233)
			(xy 336.22107 -225.752406)
		)
		(stroke
			(width 0)
			(type solid)
		)
		(fill yes)
		(layer "In2.Cu")
		(net "M_C_CPU0_SA_DQ<2>")
	)
	(gr_poly
		(pts
			(xy 336.62112 -293.324026) (xy 336.62112 -293.279576) (xy 336.420968 -293.279576) (xy 336.420968 -293.324026)
			(xy 336.521044 -293.424102)
		)
		(stroke
			(width 0)
			(type solid)
		)
		(fill yes)
		(layer "In2.Cu")
		(net "M_C_CPU0_SB_DQ<31>")
	)
	(gr_poly
		(pts
			(xy 336.62112 -292.107874) (xy 336.521044 -292.007798) (xy 336.420968 -292.107874) (xy 336.420968 -292.152324)
			(xy 336.62112 -292.152324)
		)
		(stroke
			(width 0)
			(type solid)
		)
		(fill yes)
		(layer "In2.Cu")
		(net "M_C_CPU0_SB_DQ<28>")
	)
	(gr_poly
		(pts
			(xy 336.62112 -291.704268) (xy 336.62112 -291.656516) (xy 336.420968 -291.656516) (xy 336.420968 -291.704268)
			(xy 336.521044 -291.80409)
		)
		(stroke
			(width 0)
			(type solid)
		)
		(fill yes)
		(layer "In2.Cu")
		(net "M_C_CPU0_SB_DQS_DP<8>")
	)
	(gr_poly
		(pts
			(xy 336.62112 -290.487608) (xy 336.521044 -290.387786) (xy 336.420968 -290.487608) (xy 336.420968 -290.53536)
			(xy 336.62112 -290.53536)
		)
		(stroke
			(width 0)
			(type solid)
		)
		(fill yes)
		(layer "In2.Cu")
		(net "M_C_CPU0_SB_DQS_DP<3>")
	)
	(gr_poly
		(pts
			(xy 336.62112 -290.084002) (xy 336.62112 -290.039552) (xy 336.420968 -290.039552) (xy 336.420968 -290.084002)
			(xy 336.521044 -290.184078)
		)
		(stroke
			(width 0)
			(type solid)
		)
		(fill yes)
		(layer "In2.Cu")
		(net "M_C_CPU0_SB_DQ<27>")
	)
	(gr_poly
		(pts
			(xy 336.62112 -288.86785) (xy 336.521044 -288.767774) (xy 336.420968 -288.86785) (xy 336.420968 -288.9123)
			(xy 336.62112 -288.9123)
		)
		(stroke
			(width 0)
			(type solid)
		)
		(fill yes)
		(layer "In2.Cu")
		(net "M_C_CPU0_SB_DQ<24>")
	)
	(gr_poly
		(pts
			(xy 336.62112 -288.464244) (xy 336.62112 -288.419794) (xy 336.420968 -288.419794) (xy 336.420968 -288.464244)
			(xy 336.521044 -288.56432)
		)
		(stroke
			(width 0)
			(type solid)
		)
		(fill yes)
		(layer "In2.Cu")
		(net "M_C_CPU0_SB_DQ<23>")
	)
	(gr_poly
		(pts
			(xy 336.62112 -287.247838) (xy 336.521044 -287.148016) (xy 336.420968 -287.247838) (xy 336.420968 -287.292288)
			(xy 336.62112 -287.292288)
		)
		(stroke
			(width 0)
			(type solid)
		)
		(fill yes)
		(layer "In2.Cu")
		(net "M_C_CPU0_SB_DQ<20>")
	)
	(gr_poly
		(pts
			(xy 336.62112 -286.844232) (xy 336.62112 -286.79648) (xy 336.420968 -286.79648) (xy 336.420968 -286.844232)
			(xy 336.521044 -286.944308)
		)
		(stroke
			(width 0)
			(type solid)
		)
		(fill yes)
		(layer "In2.Cu")
		(net "M_C_CPU0_SB_DQS_DP<7>")
	)
	(gr_poly
		(pts
			(xy 336.62112 -285.627826) (xy 336.521044 -285.528004) (xy 336.420968 -285.627826) (xy 336.420968 -285.675578)
			(xy 336.62112 -285.675578)
		)
		(stroke
			(width 0)
			(type solid)
		)
		(fill yes)
		(layer "In2.Cu")
		(net "M_C_CPU0_SB_DQS_DP<2>")
	)
	(gr_poly
		(pts
			(xy 336.62112 -285.22422) (xy 336.62112 -285.17977) (xy 336.420968 -285.17977) (xy 336.420968 -285.22422)
			(xy 336.521044 -285.324296)
		)
		(stroke
			(width 0)
			(type solid)
		)
		(fill yes)
		(layer "In2.Cu")
		(net "M_C_CPU0_SB_DQ<19>")
	)
	(gr_poly
		(pts
			(xy 336.62112 -284.008068) (xy 336.521044 -283.907992) (xy 336.420968 -284.008068) (xy 336.420968 -284.052518)
			(xy 336.62112 -284.052518)
		)
		(stroke
			(width 0)
			(type solid)
		)
		(fill yes)
		(layer "In2.Cu")
		(net "M_C_CPU0_SB_DQ<16>")
	)
	(gr_poly
		(pts
			(xy 336.62112 -283.604208) (xy 336.62112 -283.559758) (xy 336.420968 -283.559758) (xy 336.420968 -283.604208)
			(xy 336.521044 -283.704284)
		)
		(stroke
			(width 0)
			(type solid)
		)
		(fill yes)
		(layer "In2.Cu")
		(net "M_C_CPU0_SB_DQ<15>")
	)
	(gr_poly
		(pts
			(xy 336.62112 -282.388056) (xy 336.521044 -282.28798) (xy 336.420968 -282.388056) (xy 336.420968 -282.432506)
			(xy 336.62112 -282.432506)
		)
		(stroke
			(width 0)
			(type solid)
		)
		(fill yes)
		(layer "In2.Cu")
		(net "M_C_CPU0_SB_DQ<12>")
	)
	(gr_poly
		(pts
			(xy 336.62112 -281.98445) (xy 336.62112 -281.936698) (xy 336.420968 -281.936698) (xy 336.420968 -281.98445)
			(xy 336.521044 -282.084272)
		)
		(stroke
			(width 0)
			(type solid)
		)
		(fill yes)
		(layer "In2.Cu")
		(net "M_C_CPU0_SB_DQS_DP<6>")
	)
	(gr_poly
		(pts
			(xy 336.62112 -280.76779) (xy 336.521044 -280.667968) (xy 336.420968 -280.76779) (xy 336.420968 -280.815542)
			(xy 336.62112 -280.815542)
		)
		(stroke
			(width 0)
			(type solid)
		)
		(fill yes)
		(layer "In2.Cu")
		(net "M_C_CPU0_SB_DQS_DP<1>")
	)
	(gr_poly
		(pts
			(xy 336.62112 -280.364184) (xy 336.62112 -280.319734) (xy 336.420968 -280.319734) (xy 336.420968 -280.364184)
			(xy 336.521044 -280.46426)
		)
		(stroke
			(width 0)
			(type solid)
		)
		(fill yes)
		(layer "In2.Cu")
		(net "M_C_CPU0_SB_DQ<11>")
	)
	(gr_poly
		(pts
			(xy 336.62112 -279.148032) (xy 336.521044 -279.047956) (xy 336.420968 -279.148032) (xy 336.420968 -279.192482)
			(xy 336.62112 -279.192482)
		)
		(stroke
			(width 0)
			(type solid)
		)
		(fill yes)
		(layer "In2.Cu")
		(net "M_C_CPU0_SB_DQ<8>")
	)
	(gr_poly
		(pts
			(xy 336.62112 -278.744172) (xy 336.62112 -278.699722) (xy 336.420968 -278.699722) (xy 336.420968 -278.744172)
			(xy 336.521044 -278.844248)
		)
		(stroke
			(width 0)
			(type solid)
		)
		(fill yes)
		(layer "In2.Cu")
		(net "M_C_CPU0_SB_DQ<7>")
	)
	(gr_poly
		(pts
			(xy 336.62112 -277.52802) (xy 336.521044 -277.427944) (xy 336.420968 -277.52802) (xy 336.420968 -277.57247)
			(xy 336.62112 -277.57247)
		)
		(stroke
			(width 0)
			(type solid)
		)
		(fill yes)
		(layer "In2.Cu")
		(net "M_C_CPU0_SB_DQ<4>")
	)
	(gr_poly
		(pts
			(xy 336.62112 -277.124414) (xy 336.62112 -277.076662) (xy 336.420968 -277.076662) (xy 336.420968 -277.124414)
			(xy 336.521044 -277.224236)
		)
		(stroke
			(width 0)
			(type solid)
		)
		(fill yes)
		(layer "In2.Cu")
		(net "M_C_CPU0_SB_DQS_DP<5>")
	)
	(gr_poly
		(pts
			(xy 336.62112 -275.907754) (xy 336.521044 -275.807932) (xy 336.420968 -275.907754) (xy 336.420968 -275.955506)
			(xy 336.62112 -275.955506)
		)
		(stroke
			(width 0)
			(type solid)
		)
		(fill yes)
		(layer "In2.Cu")
		(net "M_C_CPU0_SB_DQS_DP<0>")
	)
	(gr_poly
		(pts
			(xy 336.62112 -275.504148) (xy 336.62112 -275.459698) (xy 336.420968 -275.459698) (xy 336.420968 -275.504148)
			(xy 336.521044 -275.604224)
		)
		(stroke
			(width 0)
			(type solid)
		)
		(fill yes)
		(layer "In2.Cu")
		(net "M_C_CPU0_SB_DQ<3>")
	)
	(gr_poly
		(pts
			(xy 336.62112 -274.287996) (xy 336.521044 -274.18792) (xy 336.420968 -274.287996) (xy 336.420968 -274.332446)
			(xy 336.62112 -274.332446)
		)
		(stroke
			(width 0)
			(type solid)
		)
		(fill yes)
		(layer "In2.Cu")
		(net "M_C_CPU0_SB_DQ<0>")
	)
	(gr_poly
		(pts
			(xy 336.62112 -273.884136) (xy 336.62112 -273.839686) (xy 336.420968 -273.839686) (xy 336.420968 -273.884136)
			(xy 336.521044 -273.984212)
		)
		(stroke
			(width 0)
			(type solid)
		)
		(fill yes)
		(layer "In2.Cu")
		(net "M_C_CPU0_SB_CB<3>")
	)
	(gr_poly
		(pts
			(xy 336.62112 -272.667984) (xy 336.521044 -272.567908) (xy 336.420968 -272.667984) (xy 336.420968 -272.712434)
			(xy 336.62112 -272.712434)
		)
		(stroke
			(width 0)
			(type solid)
		)
		(fill yes)
		(layer "In2.Cu")
		(net "M_C_CPU0_SB_CB<0>")
	)
	(gr_poly
		(pts
			(xy 336.62112 -272.264378) (xy 336.62112 -272.216626) (xy 336.420968 -272.216626) (xy 336.420968 -272.264378)
			(xy 336.521044 -272.3642)
		)
		(stroke
			(width 0)
			(type solid)
		)
		(fill yes)
		(layer "In2.Cu")
		(net "M_C_CPU0_SB_DQS_DP<4>")
	)
	(gr_poly
		(pts
			(xy 336.62112 -271.047718) (xy 336.521044 -270.947896) (xy 336.420968 -271.047718) (xy 336.420968 -271.09547)
			(xy 336.62112 -271.09547)
		)
		(stroke
			(width 0)
			(type solid)
		)
		(fill yes)
		(layer "In2.Cu")
		(net "M_C_CPU0_SB_DQS_DP<9>")
	)
	(gr_poly
		(pts
			(xy 336.62112 -270.644112) (xy 336.62112 -270.599662) (xy 336.420968 -270.599662) (xy 336.420968 -270.644112)
			(xy 336.521044 -270.744188)
		)
		(stroke
			(width 0)
			(type solid)
		)
		(fill yes)
		(layer "In2.Cu")
		(net "M_C_CPU0_SB_CB<7>")
	)
	(gr_poly
		(pts
			(xy 336.62112 -269.42796) (xy 336.521044 -269.327884) (xy 336.420968 -269.42796) (xy 336.420968 -269.47241)
			(xy 336.62112 -269.47241)
		)
		(stroke
			(width 0)
			(type solid)
		)
		(fill yes)
		(layer "In2.Cu")
		(net "M_C_CPU0_SB_CB<4>")
	)
	(gr_poly
		(pts
			(xy 336.62112 -265.784076) (xy 336.62112 -265.739626) (xy 336.420968 -265.739626) (xy 336.420968 -265.784076)
			(xy 336.521044 -265.884152)
		)
		(stroke
			(width 0)
			(type solid)
		)
		(fill yes)
		(layer "In2.Cu")
		(net "M_C_CPU0_SB_CS_N<0>")
	)
	(gr_poly
		(pts
			(xy 336.62112 -264.567924) (xy 336.521044 -264.467848) (xy 336.420968 -264.567924) (xy 336.420968 -264.612374)
			(xy 336.62112 -264.612374)
		)
		(stroke
			(width 0)
			(type solid)
		)
		(fill yes)
		(layer "In2.Cu")
		(net "M_C_CPU0_SB_CA<6>")
	)
	(gr_poly
		(pts
			(xy 336.62112 -264.164064) (xy 336.62112 -264.119614) (xy 336.420968 -264.119614) (xy 336.420968 -264.164064)
			(xy 336.521044 -264.26414)
		)
		(stroke
			(width 0)
			(type solid)
		)
		(fill yes)
		(layer "In2.Cu")
		(net "M_C_CPU0_SB_CA<5>")
	)
	(gr_poly
		(pts
			(xy 336.62112 -262.947912) (xy 336.521044 -262.847836) (xy 336.420968 -262.947912) (xy 336.420968 -262.992362)
			(xy 336.62112 -262.992362)
		)
		(stroke
			(width 0)
			(type solid)
		)
		(fill yes)
		(layer "In2.Cu")
		(net "M_C_CPU0_SB_CA<2>")
	)
	(gr_poly
		(pts
			(xy 336.62112 -262.544052) (xy 336.62112 -262.499602) (xy 336.420968 -262.499602) (xy 336.420968 -262.544052)
			(xy 336.521044 -262.644128)
		)
		(stroke
			(width 0)
			(type solid)
		)
		(fill yes)
		(layer "In2.Cu")
		(net "M_C_CPU0_SB_CA<1>")
	)
	(gr_poly
		(pts
			(xy 336.627216 -267.801598) (xy 336.527394 -267.701522) (xy 336.427318 -267.801598) (xy 336.427318 -267.846048)
			(xy 336.627216 -267.846048)
		)
		(stroke
			(width 0)
			(type solid)
		)
		(fill yes)
		(layer "In2.Cu")
		(net "M_C_CPU0_SB_RSP<0>")
	)
	(gr_poly
		(pts
			(xy 336.7913 -256.025904) (xy 336.691224 -255.926082) (xy 336.591148 -256.025904) (xy 336.591148 -256.073656)
			(xy 336.7913 -256.073656)
		)
		(stroke
			(width 0)
			(type solid)
		)
		(fill yes)
		(layer "In2.Cu")
		(net "M_C_CPU0_CLK_DP<0>")
	)
	(gr_poly
		(pts
			(xy 336.7913 -255.622298) (xy 336.7913 -255.577848) (xy 336.591148 -255.577848) (xy 336.591148 -255.622298)
			(xy 336.691224 -255.722374)
		)
		(stroke
			(width 0)
			(type solid)
		)
		(fill yes)
		(layer "In2.Cu")
		(net "M_C_CPU0_SA_PAR")
	)
	(gr_poly
		(pts
			(xy 336.7913 -254.406146) (xy 336.691224 -254.30607) (xy 336.591148 -254.406146) (xy 336.591148 -254.450596)
			(xy 336.7913 -254.450596)
		)
		(stroke
			(width 0)
			(type solid)
		)
		(fill yes)
		(layer "In2.Cu")
		(net "M_C_CPU0_SA_CA<4>")
	)
	(gr_poly
		(pts
			(xy 336.7913 -254.002286) (xy 336.7913 -253.957836) (xy 336.591148 -253.957836) (xy 336.591148 -254.002286)
			(xy 336.691224 -254.102362)
		)
		(stroke
			(width 0)
			(type solid)
		)
		(fill yes)
		(layer "In2.Cu")
		(net "M_C_CPU0_SA_CA<3>")
	)
	(gr_poly
		(pts
			(xy 336.7913 -252.786134) (xy 336.691224 -252.686058) (xy 336.591148 -252.786134) (xy 336.591148 -252.830584)
			(xy 336.7913 -252.830584)
		)
		(stroke
			(width 0)
			(type solid)
		)
		(fill yes)
		(layer "In2.Cu")
		(net "M_C_CPU0_SA_CA<0>")
	)
	(gr_poly
		(pts
			(xy 336.7913 -252.382274) (xy 336.7913 -252.337824) (xy 336.591148 -252.337824) (xy 336.591148 -252.382274)
			(xy 336.691224 -252.48235)
		)
		(stroke
			(width 0)
			(type solid)
		)
		(fill yes)
		(layer "In2.Cu")
		(net "M_C_CPU0_SA_CS_N<1>")
	)
	(gr_poly
		(pts
			(xy 336.7913 -250.762262) (xy 336.7913 -250.717812) (xy 336.591148 -250.717812) (xy 336.591148 -250.762262)
			(xy 336.691224 -250.862338)
		)
		(stroke
			(width 0)
			(type solid)
		)
		(fill yes)
		(layer "In2.Cu")
		(net "M_C_CPU0_RESET_N")
	)
	(gr_poly
		(pts
			(xy 336.7913 -249.14225) (xy 336.7913 -249.0978) (xy 336.591148 -249.0978) (xy 336.591148 -249.14225)
			(xy 336.691224 -249.242326)
		)
		(stroke
			(width 0)
			(type solid)
		)
		(fill yes)
		(layer "In2.Cu")
		(net "M_C_CPU0_SA_CB<7>")
	)
	(gr_poly
		(pts
			(xy 336.7913 -247.926098) (xy 336.691224 -247.826022) (xy 336.591148 -247.926098) (xy 336.591148 -247.970548)
			(xy 336.7913 -247.970548)
		)
		(stroke
			(width 0)
			(type solid)
		)
		(fill yes)
		(layer "In2.Cu")
		(net "M_C_CPU0_SA_CB<4>")
	)
	(gr_poly
		(pts
			(xy 336.7913 -247.522492) (xy 336.7913 -247.47474) (xy 336.591148 -247.47474) (xy 336.591148 -247.522492)
			(xy 336.691224 -247.622314)
		)
		(stroke
			(width 0)
			(type solid)
		)
		(fill yes)
		(layer "In2.Cu")
		(net "M_C_CPU0_SA_DQS_DP<9>")
	)
	(gr_poly
		(pts
			(xy 336.7913 -246.305832) (xy 336.691224 -246.20601) (xy 336.591148 -246.305832) (xy 336.591148 -246.353584)
			(xy 336.7913 -246.353584)
		)
		(stroke
			(width 0)
			(type solid)
		)
		(fill yes)
		(layer "In2.Cu")
		(net "M_C_CPU0_SA_DQS_DP<4>")
	)
	(gr_poly
		(pts
			(xy 336.7913 -245.902226) (xy 336.7913 -245.857776) (xy 336.591148 -245.857776) (xy 336.591148 -245.902226)
			(xy 336.691224 -246.002302)
		)
		(stroke
			(width 0)
			(type solid)
		)
		(fill yes)
		(layer "In2.Cu")
		(net "M_C_CPU0_SA_CB<3>")
	)
	(gr_poly
		(pts
			(xy 336.7913 -244.686074) (xy 336.691224 -244.585998) (xy 336.591148 -244.686074) (xy 336.591148 -244.730524)
			(xy 336.7913 -244.730524)
		)
		(stroke
			(width 0)
			(type solid)
		)
		(fill yes)
		(layer "In2.Cu")
		(net "M_C_CPU0_SA_CB<0>")
	)
	(gr_poly
		(pts
			(xy 336.7913 -244.282214) (xy 336.7913 -244.237764) (xy 336.591148 -244.237764) (xy 336.591148 -244.282214)
			(xy 336.691224 -244.38229)
		)
		(stroke
			(width 0)
			(type solid)
		)
		(fill yes)
		(layer "In2.Cu")
		(net "M_C_CPU0_SA_DQ<31>")
	)
	(gr_poly
		(pts
			(xy 336.7913 -243.066062) (xy 336.691224 -242.965986) (xy 336.591148 -243.066062) (xy 336.591148 -243.110512)
			(xy 336.7913 -243.110512)
		)
		(stroke
			(width 0)
			(type solid)
		)
		(fill yes)
		(layer "In2.Cu")
		(net "M_C_CPU0_SA_DQ<28>")
	)
	(gr_poly
		(pts
			(xy 336.7913 -242.662456) (xy 336.7913 -242.614704) (xy 336.591148 -242.614704) (xy 336.591148 -242.662456)
			(xy 336.691224 -242.762278)
		)
		(stroke
			(width 0)
			(type solid)
		)
		(fill yes)
		(layer "In2.Cu")
		(net "M_C_CPU0_SA_DQS_DP<8>")
	)
	(gr_poly
		(pts
			(xy 336.7913 -241.445796) (xy 336.691224 -241.345974) (xy 336.591148 -241.445796) (xy 336.591148 -241.493548)
			(xy 336.7913 -241.493548)
		)
		(stroke
			(width 0)
			(type solid)
		)
		(fill yes)
		(layer "In2.Cu")
		(net "M_C_CPU0_SA_DQS_DP<3>")
	)
	(gr_poly
		(pts
			(xy 336.7913 -241.04219) (xy 336.7913 -240.99774) (xy 336.591148 -240.99774) (xy 336.591148 -241.04219)
			(xy 336.691224 -241.142266)
		)
		(stroke
			(width 0)
			(type solid)
		)
		(fill yes)
		(layer "In2.Cu")
		(net "M_C_CPU0_SA_DQ<27>")
	)
	(gr_poly
		(pts
			(xy 336.7913 -239.826038) (xy 336.691224 -239.725962) (xy 336.591148 -239.826038) (xy 336.591148 -239.870488)
			(xy 336.7913 -239.870488)
		)
		(stroke
			(width 0)
			(type solid)
		)
		(fill yes)
		(layer "In2.Cu")
		(net "M_C_CPU0_SA_DQ<24>")
	)
	(gr_poly
		(pts
			(xy 336.7913 -239.422178) (xy 336.7913 -239.377728) (xy 336.591148 -239.377728) (xy 336.591148 -239.422178)
			(xy 336.691224 -239.522254)
		)
		(stroke
			(width 0)
			(type solid)
		)
		(fill yes)
		(layer "In2.Cu")
		(net "M_C_CPU0_SA_DQ<23>")
	)
	(gr_poly
		(pts
			(xy 336.7913 -238.206026) (xy 336.691224 -238.10595) (xy 336.591148 -238.206026) (xy 336.591148 -238.250476)
			(xy 336.7913 -238.250476)
		)
		(stroke
			(width 0)
			(type solid)
		)
		(fill yes)
		(layer "In2.Cu")
		(net "M_C_CPU0_SA_DQ<20>")
	)
	(gr_poly
		(pts
			(xy 336.7913 -237.80242) (xy 336.7913 -237.754668) (xy 336.591148 -237.754668) (xy 336.591148 -237.80242)
			(xy 336.691224 -237.902242)
		)
		(stroke
			(width 0)
			(type solid)
		)
		(fill yes)
		(layer "In2.Cu")
		(net "M_C_CPU0_SA_DQS_DP<7>")
	)
	(gr_poly
		(pts
			(xy 336.7913 -236.58576) (xy 336.691224 -236.485938) (xy 336.591148 -236.58576) (xy 336.591148 -236.633512)
			(xy 336.7913 -236.633512)
		)
		(stroke
			(width 0)
			(type solid)
		)
		(fill yes)
		(layer "In2.Cu")
		(net "M_C_CPU0_SA_DQS_DP<2>")
	)
	(gr_poly
		(pts
			(xy 336.7913 -236.182154) (xy 336.7913 -236.137704) (xy 336.591148 -236.137704) (xy 336.591148 -236.182154)
			(xy 336.691224 -236.28223)
		)
		(stroke
			(width 0)
			(type solid)
		)
		(fill yes)
		(layer "In2.Cu")
		(net "M_C_CPU0_SA_DQ<19>")
	)
	(gr_poly
		(pts
			(xy 336.7913 -234.966002) (xy 336.691224 -234.865926) (xy 336.591148 -234.966002) (xy 336.591148 -235.010452)
			(xy 336.7913 -235.010452)
		)
		(stroke
			(width 0)
			(type solid)
		)
		(fill yes)
		(layer "In2.Cu")
		(net "M_C_CPU0_SA_DQ<16>")
	)
	(gr_poly
		(pts
			(xy 336.7913 -234.562142) (xy 336.7913 -234.517692) (xy 336.591148 -234.517692) (xy 336.591148 -234.562142)
			(xy 336.691224 -234.662218)
		)
		(stroke
			(width 0)
			(type solid)
		)
		(fill yes)
		(layer "In2.Cu")
		(net "M_C_CPU0_SA_DQ<15>")
	)
	(gr_poly
		(pts
			(xy 336.7913 -233.34599) (xy 336.691224 -233.245914) (xy 336.591148 -233.34599) (xy 336.591148 -233.39044)
			(xy 336.7913 -233.39044)
		)
		(stroke
			(width 0)
			(type solid)
		)
		(fill yes)
		(layer "In2.Cu")
		(net "M_C_CPU0_SA_DQ<12>")
	)
	(gr_poly
		(pts
			(xy 336.7913 -232.942384) (xy 336.7913 -232.894632) (xy 336.591148 -232.894632) (xy 336.591148 -232.942384)
			(xy 336.691224 -233.042206)
		)
		(stroke
			(width 0)
			(type solid)
		)
		(fill yes)
		(layer "In2.Cu")
		(net "M_C_CPU0_SA_DQS_DP<6>")
	)
	(gr_poly
		(pts
			(xy 336.7913 -231.725724) (xy 336.691224 -231.625902) (xy 336.591148 -231.725724) (xy 336.591148 -231.773476)
			(xy 336.7913 -231.773476)
		)
		(stroke
			(width 0)
			(type solid)
		)
		(fill yes)
		(layer "In2.Cu")
		(net "M_C_CPU0_SA_DQS_DP<1>")
	)
	(gr_poly
		(pts
			(xy 336.7913 -231.322372) (xy 336.7913 -231.277922) (xy 336.591148 -231.277922) (xy 336.591148 -231.322372)
			(xy 336.691224 -231.422448)
		)
		(stroke
			(width 0)
			(type solid)
		)
		(fill yes)
		(layer "In2.Cu")
		(net "M_C_CPU0_SA_DQ<11>")
	)
	(gr_poly
		(pts
			(xy 336.7913 -230.105966) (xy 336.691224 -230.006144) (xy 336.591148 -230.105966) (xy 336.591148 -230.150416)
			(xy 336.7913 -230.150416)
		)
		(stroke
			(width 0)
			(type solid)
		)
		(fill yes)
		(layer "In2.Cu")
		(net "M_C_CPU0_SA_DQ<8>")
	)
	(gr_poly
		(pts
			(xy 336.7913 -229.70236) (xy 336.7913 -229.65791) (xy 336.591148 -229.65791) (xy 336.591148 -229.70236)
			(xy 336.691224 -229.802436)
		)
		(stroke
			(width 0)
			(type solid)
		)
		(fill yes)
		(layer "In2.Cu")
		(net "M_C_CPU0_SA_DQ<7>")
	)
	(gr_poly
		(pts
			(xy 336.7913 -228.486208) (xy 336.691224 -228.386132) (xy 336.591148 -228.486208) (xy 336.591148 -228.530658)
			(xy 336.7913 -228.530658)
		)
		(stroke
			(width 0)
			(type solid)
		)
		(fill yes)
		(layer "In2.Cu")
		(net "M_C_CPU0_SA_DQ<4>")
	)
	(gr_poly
		(pts
			(xy 336.7913 -228.082602) (xy 336.7913 -228.03485) (xy 336.591148 -228.03485) (xy 336.591148 -228.082602)
			(xy 336.691224 -228.182424)
		)
		(stroke
			(width 0)
			(type solid)
		)
		(fill yes)
		(layer "In2.Cu")
		(net "M_C_CPU0_SA_DQS_DP<5>")
	)
	(gr_poly
		(pts
			(xy 336.7913 -226.865942) (xy 336.691224 -226.76612) (xy 336.591148 -226.865942) (xy 336.591148 -226.913694)
			(xy 336.7913 -226.913694)
		)
		(stroke
			(width 0)
			(type solid)
		)
		(fill yes)
		(layer "In2.Cu")
		(net "M_C_CPU0_SA_DQS_DP<0>")
	)
	(gr_poly
		(pts
			(xy 336.7913 -226.462336) (xy 336.7913 -226.417886) (xy 336.591148 -226.417886) (xy 336.591148 -226.462336)
			(xy 336.691224 -226.562412)
		)
		(stroke
			(width 0)
			(type solid)
		)
		(fill yes)
		(layer "In2.Cu")
		(net "M_C_CPU0_SA_DQ<3>")
	)
	(gr_poly
		(pts
			(xy 336.7913 -225.246184) (xy 336.691224 -225.146108) (xy 336.591148 -225.246184) (xy 336.591148 -225.290634)
			(xy 336.7913 -225.290634)
		)
		(stroke
			(width 0)
			(type solid)
		)
		(fill yes)
		(layer "In2.Cu")
		(net "M_C_CPU0_SA_DQ<0>")
	)
	(gr_poly
		(pts
			(xy 337.083908 -291.297614) (xy 336.983832 -291.197792) (xy 336.883756 -291.297614) (xy 336.883756 -291.345366)
			(xy 337.083908 -291.345366)
		)
		(stroke
			(width 0)
			(type solid)
		)
		(fill yes)
		(layer "In2.Cu")
		(net "M_C_CPU0_SB_DQS_DN<8>")
	)
	(gr_poly
		(pts
			(xy 337.084924 -266.991592) (xy 336.984848 -266.891516) (xy 336.885026 -266.991592) (xy 336.885026 -267.036042)
			(xy 337.084924 -267.036042)
		)
		(stroke
			(width 0)
			(type solid)
		)
		(fill yes)
		(layer "In2.Cu")
		(net "M_C_CPU0_SA_RSP<0>")
	)
	(gr_poly
		(pts
			(xy 337.091274 -292.91788) (xy 336.991198 -292.817804) (xy 336.891122 -292.91788) (xy 336.891122 -292.96233)
			(xy 337.091274 -292.96233)
		)
		(stroke
			(width 0)
			(type solid)
		)
		(fill yes)
		(layer "In2.Cu")
		(net "M_C_CPU0_SB_DQ<29>")
	)
	(gr_poly
		(pts
			(xy 337.091274 -292.51402) (xy 337.091274 -292.46957) (xy 336.891122 -292.46957) (xy 336.891122 -292.51402)
			(xy 336.991198 -292.614096)
		)
		(stroke
			(width 0)
			(type solid)
		)
		(fill yes)
		(layer "In2.Cu")
		(net "M_C_CPU0_SB_DQ<30>")
	)
	(gr_poly
		(pts
			(xy 337.091274 -290.894262) (xy 337.091274 -290.84651) (xy 336.891122 -290.84651) (xy 336.891122 -290.894262)
			(xy 336.991198 -290.994084)
		)
		(stroke
			(width 0)
			(type solid)
		)
		(fill yes)
		(layer "In2.Cu")
		(net "M_C_CPU0_SB_DQS_DN<3>")
	)
	(gr_poly
		(pts
			(xy 337.091274 -289.677856) (xy 336.991198 -289.57778) (xy 336.891122 -289.677856) (xy 336.891122 -289.722306)
			(xy 337.091274 -289.722306)
		)
		(stroke
			(width 0)
			(type solid)
		)
		(fill yes)
		(layer "In2.Cu")
		(net "M_C_CPU0_SB_DQ<25>")
	)
	(gr_poly
		(pts
			(xy 337.091274 -289.273996) (xy 337.091274 -289.229546) (xy 336.891122 -289.229546) (xy 336.891122 -289.273996)
			(xy 336.991198 -289.374072)
		)
		(stroke
			(width 0)
			(type solid)
		)
		(fill yes)
		(layer "In2.Cu")
		(net "M_C_CPU0_SB_DQ<26>")
	)
	(gr_poly
		(pts
			(xy 337.091274 -288.057844) (xy 336.991198 -287.957768) (xy 336.891122 -288.057844) (xy 336.891122 -288.102294)
			(xy 337.091274 -288.102294)
		)
		(stroke
			(width 0)
			(type solid)
		)
		(fill yes)
		(layer "In2.Cu")
		(net "M_C_CPU0_SB_DQ<21>")
	)
	(gr_poly
		(pts
			(xy 337.091274 -287.654238) (xy 337.091274 -287.609788) (xy 336.891122 -287.609788) (xy 336.891122 -287.654238)
			(xy 336.991198 -287.75406)
		)
		(stroke
			(width 0)
			(type solid)
		)
		(fill yes)
		(layer "In2.Cu")
		(net "M_C_CPU0_SB_DQ<22>")
	)
	(gr_poly
		(pts
			(xy 337.091274 -286.437832) (xy 336.991198 -286.337756) (xy 336.891122 -286.437832) (xy 336.891122 -286.485584)
			(xy 337.091274 -286.485584)
		)
		(stroke
			(width 0)
			(type solid)
		)
		(fill yes)
		(layer "In2.Cu")
		(net "M_C_CPU0_SB_DQS_DN<7>")
	)
	(gr_poly
		(pts
			(xy 337.091274 -286.03448) (xy 337.091274 -285.986728) (xy 336.891122 -285.986728) (xy 336.891122 -286.03448)
			(xy 336.991198 -286.134302)
		)
		(stroke
			(width 0)
			(type solid)
		)
		(fill yes)
		(layer "In2.Cu")
		(net "M_C_CPU0_SB_DQS_DN<2>")
	)
	(gr_poly
		(pts
			(xy 337.091274 -284.818074) (xy 336.991198 -284.717998) (xy 336.891122 -284.818074) (xy 336.891122 -284.862524)
			(xy 337.091274 -284.862524)
		)
		(stroke
			(width 0)
			(type solid)
		)
		(fill yes)
		(layer "In2.Cu")
		(net "M_C_CPU0_SB_DQ<17>")
	)
	(gr_poly
		(pts
			(xy 337.091274 -284.414214) (xy 337.091274 -284.369764) (xy 336.891122 -284.369764) (xy 336.891122 -284.414214)
			(xy 336.991198 -284.51429)
		)
		(stroke
			(width 0)
			(type solid)
		)
		(fill yes)
		(layer "In2.Cu")
		(net "M_C_CPU0_SB_DQ<18>")
	)
	(gr_poly
		(pts
			(xy 337.091274 -283.198062) (xy 336.991198 -283.097986) (xy 336.891122 -283.198062) (xy 336.891122 -283.242512)
			(xy 337.091274 -283.242512)
		)
		(stroke
			(width 0)
			(type solid)
		)
		(fill yes)
		(layer "In2.Cu")
		(net "M_C_CPU0_SB_DQ<13>")
	)
	(gr_poly
		(pts
			(xy 337.091274 -282.794202) (xy 337.091274 -282.749752) (xy 336.891122 -282.749752) (xy 336.891122 -282.794202)
			(xy 336.991198 -282.894278)
		)
		(stroke
			(width 0)
			(type solid)
		)
		(fill yes)
		(layer "In2.Cu")
		(net "M_C_CPU0_SB_DQ<14>")
	)
	(gr_poly
		(pts
			(xy 337.091274 -281.577796) (xy 336.991198 -281.477974) (xy 336.891122 -281.577796) (xy 336.891122 -281.625548)
			(xy 337.091274 -281.625548)
		)
		(stroke
			(width 0)
			(type solid)
		)
		(fill yes)
		(layer "In2.Cu")
		(net "M_C_CPU0_SB_DQS_DN<6>")
	)
	(gr_poly
		(pts
			(xy 337.091274 -281.174444) (xy 337.091274 -281.126692) (xy 336.891122 -281.126692) (xy 336.891122 -281.174444)
			(xy 336.991198 -281.274266)
		)
		(stroke
			(width 0)
			(type solid)
		)
		(fill yes)
		(layer "In2.Cu")
		(net "M_C_CPU0_SB_DQS_DN<1>")
	)
	(gr_poly
		(pts
			(xy 337.091274 -279.958038) (xy 336.991198 -279.857962) (xy 336.891122 -279.958038) (xy 336.891122 -280.002488)
			(xy 337.091274 -280.002488)
		)
		(stroke
			(width 0)
			(type solid)
		)
		(fill yes)
		(layer "In2.Cu")
		(net "M_C_CPU0_SB_DQ<9>")
	)
	(gr_poly
		(pts
			(xy 337.091274 -279.554178) (xy 337.091274 -279.509728) (xy 336.891122 -279.509728) (xy 336.891122 -279.554178)
			(xy 336.991198 -279.654254)
		)
		(stroke
			(width 0)
			(type solid)
		)
		(fill yes)
		(layer "In2.Cu")
		(net "M_C_CPU0_SB_DQ<10>")
	)
	(gr_poly
		(pts
			(xy 337.091274 -278.338026) (xy 336.991198 -278.23795) (xy 336.891122 -278.338026) (xy 336.891122 -278.382476)
			(xy 337.091274 -278.382476)
		)
		(stroke
			(width 0)
			(type solid)
		)
		(fill yes)
		(layer "In2.Cu")
		(net "M_C_CPU0_SB_DQ<5>")
	)
	(gr_poly
		(pts
			(xy 337.091274 -277.934166) (xy 337.091274 -277.889716) (xy 336.891122 -277.889716) (xy 336.891122 -277.934166)
			(xy 336.991198 -278.034242)
		)
		(stroke
			(width 0)
			(type solid)
		)
		(fill yes)
		(layer "In2.Cu")
		(net "M_C_CPU0_SB_DQ<6>")
	)
	(gr_poly
		(pts
			(xy 337.091274 -276.71776) (xy 336.991198 -276.617938) (xy 336.891122 -276.71776) (xy 336.891122 -276.765512)
			(xy 337.091274 -276.765512)
		)
		(stroke
			(width 0)
			(type solid)
		)
		(fill yes)
		(layer "In2.Cu")
		(net "M_C_CPU0_SB_DQS_DN<5>")
	)
	(gr_poly
		(pts
			(xy 337.091274 -276.314408) (xy 337.091274 -276.266656) (xy 336.891122 -276.266656) (xy 336.891122 -276.314408)
			(xy 336.991198 -276.41423)
		)
		(stroke
			(width 0)
			(type solid)
		)
		(fill yes)
		(layer "In2.Cu")
		(net "M_C_CPU0_SB_DQS_DN<0>")
	)
	(gr_poly
		(pts
			(xy 337.091274 -275.098002) (xy 336.991198 -274.997926) (xy 336.891122 -275.098002) (xy 336.891122 -275.142452)
			(xy 337.091274 -275.142452)
		)
		(stroke
			(width 0)
			(type solid)
		)
		(fill yes)
		(layer "In2.Cu")
		(net "M_C_CPU0_SB_DQ<1>")
	)
	(gr_poly
		(pts
			(xy 337.091274 -274.694142) (xy 337.091274 -274.649692) (xy 336.891122 -274.649692) (xy 336.891122 -274.694142)
			(xy 336.991198 -274.794218)
		)
		(stroke
			(width 0)
			(type solid)
		)
		(fill yes)
		(layer "In2.Cu")
		(net "M_C_CPU0_SB_DQ<2>")
	)
	(gr_poly
		(pts
			(xy 337.091274 -273.47799) (xy 336.991198 -273.377914) (xy 336.891122 -273.47799) (xy 336.891122 -273.52244)
			(xy 337.091274 -273.52244)
		)
		(stroke
			(width 0)
			(type solid)
		)
		(fill yes)
		(layer "In2.Cu")
		(net "M_C_CPU0_SB_CB<1>")
	)
	(gr_poly
		(pts
			(xy 337.091274 -273.07413) (xy 337.091274 -273.02968) (xy 336.891122 -273.02968) (xy 336.891122 -273.07413)
			(xy 336.991198 -273.174206)
		)
		(stroke
			(width 0)
			(type solid)
		)
		(fill yes)
		(layer "In2.Cu")
		(net "M_C_CPU0_SB_CB<2>")
	)
	(gr_poly
		(pts
			(xy 337.091274 -271.857724) (xy 336.991198 -271.757902) (xy 336.891122 -271.857724) (xy 336.891122 -271.905476)
			(xy 337.091274 -271.905476)
		)
		(stroke
			(width 0)
			(type solid)
		)
		(fill yes)
		(layer "In2.Cu")
		(net "M_C_CPU0_SB_DQS_DN<4>")
	)
	(gr_poly
		(pts
			(xy 337.091274 -271.454372) (xy 337.091274 -271.40662) (xy 336.891122 -271.40662) (xy 336.891122 -271.454372)
			(xy 336.991198 -271.554194)
		)
		(stroke
			(width 0)
			(type solid)
		)
		(fill yes)
		(layer "In2.Cu")
		(net "M_C_CPU0_SB_DQS_DN<9>")
	)
	(gr_poly
		(pts
			(xy 337.091274 -270.237966) (xy 336.991198 -270.13789) (xy 336.891122 -270.237966) (xy 336.891122 -270.282416)
			(xy 337.091274 -270.282416)
		)
		(stroke
			(width 0)
			(type solid)
		)
		(fill yes)
		(layer "In2.Cu")
		(net "M_C_CPU0_SB_CB<5>")
	)
	(gr_poly
		(pts
			(xy 337.091274 -269.834106) (xy 337.091274 -269.789656) (xy 336.891122 -269.789656) (xy 336.891122 -269.834106)
			(xy 336.991198 -269.934182)
		)
		(stroke
			(width 0)
			(type solid)
		)
		(fill yes)
		(layer "In2.Cu")
		(net "M_C_CPU0_SB_CB<6>")
	)
	(gr_poly
		(pts
			(xy 337.091274 -266.594082) (xy 337.091274 -266.549632) (xy 336.891122 -266.549632) (xy 336.891122 -266.594082)
			(xy 336.991198 -266.694158)
		)
		(stroke
			(width 0)
			(type solid)
		)
		(fill yes)
		(layer "In2.Cu")
		(net "M_C_CPU0_SB_CS_N<1>")
	)
	(gr_poly
		(pts
			(xy 337.091274 -264.97407) (xy 337.091274 -264.92962) (xy 336.891122 -264.92962) (xy 336.891122 -264.97407)
			(xy 336.991198 -265.074146)
		)
		(stroke
			(width 0)
			(type solid)
		)
		(fill yes)
		(layer "In2.Cu")
		(net "M_C_CPU0_SB_PAR")
	)
	(gr_poly
		(pts
			(xy 337.091274 -263.757918) (xy 336.991198 -263.657842) (xy 336.891122 -263.757918) (xy 336.891122 -263.802368)
			(xy 337.091274 -263.802368)
		)
		(stroke
			(width 0)
			(type solid)
		)
		(fill yes)
		(layer "In2.Cu")
		(net "M_C_CPU0_SB_CA<4>")
	)
	(gr_poly
		(pts
			(xy 337.091274 -263.354058) (xy 337.091274 -263.309608) (xy 336.891122 -263.309608) (xy 336.891122 -263.354058)
			(xy 336.991198 -263.454134)
		)
		(stroke
			(width 0)
			(type solid)
		)
		(fill yes)
		(layer "In2.Cu")
		(net "M_C_CPU0_SB_CA<3>")
	)
	(gr_poly
		(pts
			(xy 337.091274 -262.137906) (xy 336.991198 -262.03783) (xy 336.891122 -262.137906) (xy 336.891122 -262.182356)
			(xy 337.091274 -262.182356)
		)
		(stroke
			(width 0)
			(type solid)
		)
		(fill yes)
		(layer "In2.Cu")
		(net "M_C_CPU0_SB_CA<0>")
	)
	(gr_poly
		(pts
			(xy 337.260946 -246.712232) (xy 337.260946 -246.664734) (xy 337.061048 -246.664734) (xy 337.061048 -246.712232)
			(xy 337.16087 -246.812308)
		)
		(stroke
			(width 0)
			(type solid)
		)
		(fill yes)
		(layer "In2.Cu")
		(net "M_C_CPU0_SA_DQS_DN<4>")
	)
	(gr_poly
		(pts
			(xy 337.2612 -256.432558) (xy 337.2612 -256.384806) (xy 337.061048 -256.384806) (xy 337.061048 -256.432558)
			(xy 337.161124 -256.53238)
		)
		(stroke
			(width 0)
			(type solid)
		)
		(fill yes)
		(layer "In2.Cu")
		(net "M_C_CPU0_CLK_DN<0>")
	)
	(gr_poly
		(pts
			(xy 337.2612 -255.216152) (xy 337.161124 -255.116076) (xy 337.061048 -255.216152) (xy 337.061048 -255.260602)
			(xy 337.2612 -255.260602)
		)
		(stroke
			(width 0)
			(type solid)
		)
		(fill yes)
		(layer "In2.Cu")
		(net "M_C_CPU0_SA_CA<6>")
	)
	(gr_poly
		(pts
			(xy 337.2612 -254.812292) (xy 337.2612 -254.767842) (xy 337.061048 -254.767842) (xy 337.061048 -254.812292)
			(xy 337.161124 -254.912368)
		)
		(stroke
			(width 0)
			(type solid)
		)
		(fill yes)
		(layer "In2.Cu")
		(net "M_C_CPU0_SA_CA<5>")
	)
	(gr_poly
		(pts
			(xy 337.2612 -253.59614) (xy 337.161124 -253.496064) (xy 337.061048 -253.59614) (xy 337.061048 -253.64059)
			(xy 337.2612 -253.64059)
		)
		(stroke
			(width 0)
			(type solid)
		)
		(fill yes)
		(layer "In2.Cu")
		(net "M_C_CPU0_SA_CA<2>")
	)
	(gr_poly
		(pts
			(xy 337.2612 -253.19228) (xy 337.2612 -253.14783) (xy 337.061048 -253.14783) (xy 337.061048 -253.19228)
			(xy 337.161124 -253.292356)
		)
		(stroke
			(width 0)
			(type solid)
		)
		(fill yes)
		(layer "In2.Cu")
		(net "M_C_CPU0_SA_CA<1>")
	)
	(gr_poly
		(pts
			(xy 337.2612 -251.572268) (xy 337.2612 -251.527818) (xy 337.061048 -251.527818) (xy 337.061048 -251.572268)
			(xy 337.161124 -251.672344)
		)
		(stroke
			(width 0)
			(type solid)
		)
		(fill yes)
		(layer "In2.Cu")
		(net "M_C_CPU0_SA_CS_N<0>")
	)
	(gr_poly
		(pts
			(xy 337.2612 -250.356116) (xy 337.161124 -250.25604) (xy 337.061048 -250.356116) (xy 337.061048 -250.400566)
			(xy 337.2612 -250.400566)
		)
		(stroke
			(width 0)
			(type solid)
		)
		(fill yes)
		(layer "In2.Cu")
		(net "M_C_CPU0_ALERT_R_N")
	)
	(gr_poly
		(pts
			(xy 337.2612 -248.736104) (xy 337.161124 -248.636028) (xy 337.061048 -248.736104) (xy 337.061048 -248.780554)
			(xy 337.2612 -248.780554)
		)
		(stroke
			(width 0)
			(type solid)
		)
		(fill yes)
		(layer "In2.Cu")
		(net "M_C_CPU0_SA_CB<5>")
	)
	(gr_poly
		(pts
			(xy 337.2612 -248.332244) (xy 337.2612 -248.287794) (xy 337.061048 -248.287794) (xy 337.061048 -248.332244)
			(xy 337.161124 -248.43232)
		)
		(stroke
			(width 0)
			(type solid)
		)
		(fill yes)
		(layer "In2.Cu")
		(net "M_C_CPU0_SA_CB<6>")
	)
	(gr_poly
		(pts
			(xy 337.2612 -247.115838) (xy 337.161124 -247.016016) (xy 337.061048 -247.115838) (xy 337.061048 -247.16359)
			(xy 337.2612 -247.16359)
		)
		(stroke
			(width 0)
			(type solid)
		)
		(fill yes)
		(layer "In2.Cu")
		(net "M_C_CPU0_SA_DQS_DN<9>")
	)
	(gr_poly
		(pts
			(xy 337.2612 -245.49608) (xy 337.161124 -245.396004) (xy 337.061048 -245.49608) (xy 337.061048 -245.54053)
			(xy 337.2612 -245.54053)
		)
		(stroke
			(width 0)
			(type solid)
		)
		(fill yes)
		(layer "In2.Cu")
		(net "M_C_CPU0_SA_CB<1>")
	)
	(gr_poly
		(pts
			(xy 337.2612 -245.09222) (xy 337.2612 -245.04777) (xy 337.061048 -245.04777) (xy 337.061048 -245.09222)
			(xy 337.161124 -245.192296)
		)
		(stroke
			(width 0)
			(type solid)
		)
		(fill yes)
		(layer "In2.Cu")
		(net "M_C_CPU0_SA_CB<2>")
	)
	(gr_poly
		(pts
			(xy 337.2612 -243.876068) (xy 337.161124 -243.775992) (xy 337.061048 -243.876068) (xy 337.061048 -243.920518)
			(xy 337.2612 -243.920518)
		)
		(stroke
			(width 0)
			(type solid)
		)
		(fill yes)
		(layer "In2.Cu")
		(net "M_C_CPU0_SA_DQ<29>")
	)
	(gr_poly
		(pts
			(xy 337.2612 -243.472208) (xy 337.2612 -243.427758) (xy 337.061048 -243.427758) (xy 337.061048 -243.472208)
			(xy 337.161124 -243.572284)
		)
		(stroke
			(width 0)
			(type solid)
		)
		(fill yes)
		(layer "In2.Cu")
		(net "M_C_CPU0_SA_DQ<30>")
	)
	(gr_poly
		(pts
			(xy 337.2612 -242.255802) (xy 337.161124 -242.15598) (xy 337.061048 -242.255802) (xy 337.061048 -242.303554)
			(xy 337.2612 -242.303554)
		)
		(stroke
			(width 0)
			(type solid)
		)
		(fill yes)
		(layer "In2.Cu")
		(net "M_C_CPU0_SA_DQS_DN<8>")
	)
	(gr_poly
		(pts
			(xy 337.2612 -241.85245) (xy 337.2612 -241.804698) (xy 337.061048 -241.804698) (xy 337.061048 -241.85245)
			(xy 337.161124 -241.952272)
		)
		(stroke
			(width 0)
			(type solid)
		)
		(fill yes)
		(layer "In2.Cu")
		(net "M_C_CPU0_SA_DQS_DN<3>")
	)
	(gr_poly
		(pts
			(xy 337.2612 -240.636044) (xy 337.161124 -240.535968) (xy 337.061048 -240.636044) (xy 337.061048 -240.680494)
			(xy 337.2612 -240.680494)
		)
		(stroke
			(width 0)
			(type solid)
		)
		(fill yes)
		(layer "In2.Cu")
		(net "M_C_CPU0_SA_DQ<25>")
	)
	(gr_poly
		(pts
			(xy 337.2612 -240.232184) (xy 337.2612 -240.187734) (xy 337.061048 -240.187734) (xy 337.061048 -240.232184)
			(xy 337.161124 -240.33226)
		)
		(stroke
			(width 0)
			(type solid)
		)
		(fill yes)
		(layer "In2.Cu")
		(net "M_C_CPU0_SA_DQ<26>")
	)
	(gr_poly
		(pts
			(xy 337.2612 -239.016032) (xy 337.161124 -238.915956) (xy 337.061048 -239.016032) (xy 337.061048 -239.060482)
			(xy 337.2612 -239.060482)
		)
		(stroke
			(width 0)
			(type solid)
		)
		(fill yes)
		(layer "In2.Cu")
		(net "M_C_CPU0_SA_DQ<21>")
	)
	(gr_poly
		(pts
			(xy 337.2612 -238.612172) (xy 337.2612 -238.567722) (xy 337.061048 -238.567722) (xy 337.061048 -238.612172)
			(xy 337.161124 -238.712248)
		)
		(stroke
			(width 0)
			(type solid)
		)
		(fill yes)
		(layer "In2.Cu")
		(net "M_C_CPU0_SA_DQ<22>")
	)
	(gr_poly
		(pts
			(xy 337.2612 -237.395766) (xy 337.161124 -237.295944) (xy 337.061048 -237.395766) (xy 337.061048 -237.443518)
			(xy 337.2612 -237.443518)
		)
		(stroke
			(width 0)
			(type solid)
		)
		(fill yes)
		(layer "In2.Cu")
		(net "M_C_CPU0_SA_DQS_DN<7>")
	)
	(gr_poly
		(pts
			(xy 337.2612 -236.992414) (xy 337.2612 -236.944662) (xy 337.061048 -236.944662) (xy 337.061048 -236.992414)
			(xy 337.161124 -237.092236)
		)
		(stroke
			(width 0)
			(type solid)
		)
		(fill yes)
		(layer "In2.Cu")
		(net "M_C_CPU0_SA_DQS_DN<2>")
	)
	(gr_poly
		(pts
			(xy 337.2612 -235.776008) (xy 337.161124 -235.675932) (xy 337.061048 -235.776008) (xy 337.061048 -235.820458)
			(xy 337.2612 -235.820458)
		)
		(stroke
			(width 0)
			(type solid)
		)
		(fill yes)
		(layer "In2.Cu")
		(net "M_C_CPU0_SA_DQ<17>")
	)
	(gr_poly
		(pts
			(xy 337.2612 -235.372148) (xy 337.2612 -235.327698) (xy 337.061048 -235.327698) (xy 337.061048 -235.372148)
			(xy 337.161124 -235.472224)
		)
		(stroke
			(width 0)
			(type solid)
		)
		(fill yes)
		(layer "In2.Cu")
		(net "M_C_CPU0_SA_DQ<18>")
	)
	(gr_poly
		(pts
			(xy 337.2612 -234.155996) (xy 337.161124 -234.05592) (xy 337.061048 -234.155996) (xy 337.061048 -234.200446)
			(xy 337.2612 -234.200446)
		)
		(stroke
			(width 0)
			(type solid)
		)
		(fill yes)
		(layer "In2.Cu")
		(net "M_C_CPU0_SA_DQ<13>")
	)
	(gr_poly
		(pts
			(xy 337.2612 -233.752136) (xy 337.2612 -233.707686) (xy 337.061048 -233.707686) (xy 337.061048 -233.752136)
			(xy 337.161124 -233.852212)
		)
		(stroke
			(width 0)
			(type solid)
		)
		(fill yes)
		(layer "In2.Cu")
		(net "M_C_CPU0_SA_DQ<14>")
	)
	(gr_poly
		(pts
			(xy 337.2612 -232.53573) (xy 337.161124 -232.435908) (xy 337.061048 -232.53573) (xy 337.061048 -232.583482)
			(xy 337.2612 -232.583482)
		)
		(stroke
			(width 0)
			(type solid)
		)
		(fill yes)
		(layer "In2.Cu")
		(net "M_C_CPU0_SA_DQS_DN<6>")
	)
	(gr_poly
		(pts
			(xy 337.2612 -232.132378) (xy 337.2612 -232.084626) (xy 337.061048 -232.084626) (xy 337.061048 -232.132378)
			(xy 337.161124 -232.2322)
		)
		(stroke
			(width 0)
			(type solid)
		)
		(fill yes)
		(layer "In2.Cu")
		(net "M_C_CPU0_SA_DQS_DN<1>")
	)
	(gr_poly
		(pts
			(xy 337.2612 -230.915972) (xy 337.161124 -230.815896) (xy 337.061048 -230.915972) (xy 337.061048 -230.960422)
			(xy 337.2612 -230.960422)
		)
		(stroke
			(width 0)
			(type solid)
		)
		(fill yes)
		(layer "In2.Cu")
		(net "M_C_CPU0_SA_DQ<9>")
	)
	(gr_poly
		(pts
			(xy 337.2612 -230.512366) (xy 337.2612 -230.467916) (xy 337.061048 -230.467916) (xy 337.061048 -230.512366)
			(xy 337.161124 -230.612188)
		)
		(stroke
			(width 0)
			(type solid)
		)
		(fill yes)
		(layer "In2.Cu")
		(net "M_C_CPU0_SA_DQ<10>")
	)
	(gr_poly
		(pts
			(xy 337.2612 -229.29596) (xy 337.161124 -229.195884) (xy 337.061048 -229.29596) (xy 337.061048 -229.34041)
			(xy 337.2612 -229.34041)
		)
		(stroke
			(width 0)
			(type solid)
		)
		(fill yes)
		(layer "In2.Cu")
		(net "M_C_CPU0_SA_DQ<5>")
	)
	(gr_poly
		(pts
			(xy 337.2612 -228.892354) (xy 337.2612 -228.847904) (xy 337.061048 -228.847904) (xy 337.061048 -228.892354)
			(xy 337.161124 -228.99243)
		)
		(stroke
			(width 0)
			(type solid)
		)
		(fill yes)
		(layer "In2.Cu")
		(net "M_C_CPU0_SA_DQ<6>")
	)
	(gr_poly
		(pts
			(xy 337.2612 -227.675948) (xy 337.161124 -227.576126) (xy 337.061048 -227.675948) (xy 337.061048 -227.7237)
			(xy 337.2612 -227.7237)
		)
		(stroke
			(width 0)
			(type solid)
		)
		(fill yes)
		(layer "In2.Cu")
		(net "M_C_CPU0_SA_DQS_DN<5>")
	)
	(gr_poly
		(pts
			(xy 337.2612 -227.272596) (xy 337.2612 -227.224844) (xy 337.061048 -227.224844) (xy 337.061048 -227.272596)
			(xy 337.161124 -227.372418)
		)
		(stroke
			(width 0)
			(type solid)
		)
		(fill yes)
		(layer "In2.Cu")
		(net "M_C_CPU0_SA_DQS_DN<0>")
	)
	(gr_poly
		(pts
			(xy 337.2612 -226.05619) (xy 337.161124 -225.956114) (xy 337.061048 -226.05619) (xy 337.061048 -226.10064)
			(xy 337.2612 -226.10064)
		)
		(stroke
			(width 0)
			(type solid)
		)
		(fill yes)
		(layer "In2.Cu")
		(net "M_C_CPU0_SA_DQ<1>")
	)
	(gr_poly
		(pts
			(xy 337.2612 -225.65233) (xy 337.2612 -225.60788) (xy 337.061048 -225.60788) (xy 337.061048 -225.65233)
			(xy 337.161124 -225.752406)
		)
		(stroke
			(width 0)
			(type solid)
		)
		(fill yes)
		(layer "In2.Cu")
		(net "M_C_CPU0_SA_DQ<2>")
	)
	(gr_poly
		(pts
			(xy 337.553808 -291.704268) (xy 337.553808 -291.656516) (xy 337.353656 -291.656516) (xy 337.353656 -291.704268)
			(xy 337.453732 -291.80409)
		)
		(stroke
			(width 0)
			(type solid)
		)
		(fill yes)
		(layer "In2.Cu")
		(net "M_C_CPU0_SB_DQS_DP<8>")
	)
	(gr_poly
		(pts
			(xy 337.561174 -293.324026) (xy 337.561174 -293.279576) (xy 337.361022 -293.279576) (xy 337.361022 -293.324026)
			(xy 337.461098 -293.424102)
		)
		(stroke
			(width 0)
			(type solid)
		)
		(fill yes)
		(layer "In2.Cu")
		(net "M_C_CPU0_SB_DQ<31>")
	)
	(gr_poly
		(pts
			(xy 337.561174 -292.107874) (xy 337.461098 -292.007798) (xy 337.361022 -292.107874) (xy 337.361022 -292.152324)
			(xy 337.561174 -292.152324)
		)
		(stroke
			(width 0)
			(type solid)
		)
		(fill yes)
		(layer "In2.Cu")
		(net "M_C_CPU0_SB_DQ<28>")
	)
	(gr_poly
		(pts
			(xy 337.561174 -290.487608) (xy 337.461098 -290.387786) (xy 337.361022 -290.487608) (xy 337.361022 -290.53536)
			(xy 337.561174 -290.53536)
		)
		(stroke
			(width 0)
			(type solid)
		)
		(fill yes)
		(layer "In2.Cu")
		(net "M_C_CPU0_SB_DQS_DP<3>")
	)
	(gr_poly
		(pts
			(xy 337.561174 -290.084002) (xy 337.561174 -290.039552) (xy 337.361022 -290.039552) (xy 337.361022 -290.084002)
			(xy 337.461098 -290.184078)
		)
		(stroke
			(width 0)
			(type solid)
		)
		(fill yes)
		(layer "In2.Cu")
		(net "M_C_CPU0_SB_DQ<27>")
	)
	(gr_poly
		(pts
			(xy 337.561174 -288.86785) (xy 337.461098 -288.767774) (xy 337.361022 -288.86785) (xy 337.361022 -288.9123)
			(xy 337.561174 -288.9123)
		)
		(stroke
			(width 0)
			(type solid)
		)
		(fill yes)
		(layer "In2.Cu")
		(net "M_C_CPU0_SB_DQ<24>")
	)
	(gr_poly
		(pts
			(xy 337.561174 -288.464244) (xy 337.561174 -288.419794) (xy 337.361022 -288.419794) (xy 337.361022 -288.464244)
			(xy 337.461098 -288.56432)
		)
		(stroke
			(width 0)
			(type solid)
		)
		(fill yes)
		(layer "In2.Cu")
		(net "M_C_CPU0_SB_DQ<23>")
	)
	(gr_poly
		(pts
			(xy 337.561174 -287.247838) (xy 337.461098 -287.148016) (xy 337.361022 -287.247838) (xy 337.361022 -287.292288)
			(xy 337.561174 -287.292288)
		)
		(stroke
			(width 0)
			(type solid)
		)
		(fill yes)
		(layer "In2.Cu")
		(net "M_C_CPU0_SB_DQ<20>")
	)
	(gr_poly
		(pts
			(xy 337.561174 -286.844232) (xy 337.561174 -286.79648) (xy 337.361022 -286.79648) (xy 337.361022 -286.844232)
			(xy 337.461098 -286.944308)
		)
		(stroke
			(width 0)
			(type solid)
		)
		(fill yes)
		(layer "In2.Cu")
		(net "M_C_CPU0_SB_DQS_DP<7>")
	)
	(gr_poly
		(pts
			(xy 337.561174 -285.627826) (xy 337.461098 -285.528004) (xy 337.361022 -285.627826) (xy 337.361022 -285.675578)
			(xy 337.561174 -285.675578)
		)
		(stroke
			(width 0)
			(type solid)
		)
		(fill yes)
		(layer "In2.Cu")
		(net "M_C_CPU0_SB_DQS_DP<2>")
	)
	(gr_poly
		(pts
			(xy 337.561174 -285.22422) (xy 337.561174 -285.17977) (xy 337.361022 -285.17977) (xy 337.361022 -285.22422)
			(xy 337.461098 -285.324296)
		)
		(stroke
			(width 0)
			(type solid)
		)
		(fill yes)
		(layer "In2.Cu")
		(net "M_C_CPU0_SB_DQ<19>")
	)
	(gr_poly
		(pts
			(xy 337.561174 -284.008068) (xy 337.461098 -283.907992) (xy 337.361022 -284.008068) (xy 337.361022 -284.052518)
			(xy 337.561174 -284.052518)
		)
		(stroke
			(width 0)
			(type solid)
		)
		(fill yes)
		(layer "In2.Cu")
		(net "M_C_CPU0_SB_DQ<16>")
	)
	(gr_poly
		(pts
			(xy 337.561174 -283.604208) (xy 337.561174 -283.559758) (xy 337.361022 -283.559758) (xy 337.361022 -283.604208)
			(xy 337.461098 -283.704284)
		)
		(stroke
			(width 0)
			(type solid)
		)
		(fill yes)
		(layer "In2.Cu")
		(net "M_C_CPU0_SB_DQ<15>")
	)
	(gr_poly
		(pts
			(xy 337.561174 -282.388056) (xy 337.461098 -282.28798) (xy 337.361022 -282.388056) (xy 337.361022 -282.432506)
			(xy 337.561174 -282.432506)
		)
		(stroke
			(width 0)
			(type solid)
		)
		(fill yes)
		(layer "In2.Cu")
		(net "M_C_CPU0_SB_DQ<12>")
	)
	(gr_poly
		(pts
			(xy 337.561174 -281.98445) (xy 337.561174 -281.936698) (xy 337.361022 -281.936698) (xy 337.361022 -281.98445)
			(xy 337.461098 -282.084272)
		)
		(stroke
			(width 0)
			(type solid)
		)
		(fill yes)
		(layer "In2.Cu")
		(net "M_C_CPU0_SB_DQS_DP<6>")
	)
	(gr_poly
		(pts
			(xy 337.561174 -280.76779) (xy 337.461098 -280.667968) (xy 337.361022 -280.76779) (xy 337.361022 -280.815542)
			(xy 337.561174 -280.815542)
		)
		(stroke
			(width 0)
			(type solid)
		)
		(fill yes)
		(layer "In2.Cu")
		(net "M_C_CPU0_SB_DQS_DP<1>")
	)
	(gr_poly
		(pts
			(xy 337.561174 -280.364184) (xy 337.561174 -280.319734) (xy 337.361022 -280.319734) (xy 337.361022 -280.364184)
			(xy 337.461098 -280.46426)
		)
		(stroke
			(width 0)
			(type solid)
		)
		(fill yes)
		(layer "In2.Cu")
		(net "M_C_CPU0_SB_DQ<11>")
	)
	(gr_poly
		(pts
			(xy 337.561174 -279.148032) (xy 337.461098 -279.047956) (xy 337.361022 -279.148032) (xy 337.361022 -279.192482)
			(xy 337.561174 -279.192482)
		)
		(stroke
			(width 0)
			(type solid)
		)
		(fill yes)
		(layer "In2.Cu")
		(net "M_C_CPU0_SB_DQ<8>")
	)
	(gr_poly
		(pts
			(xy 337.561174 -278.744172) (xy 337.561174 -278.699722) (xy 337.361022 -278.699722) (xy 337.361022 -278.744172)
			(xy 337.461098 -278.844248)
		)
		(stroke
			(width 0)
			(type solid)
		)
		(fill yes)
		(layer "In2.Cu")
		(net "M_C_CPU0_SB_DQ<7>")
	)
	(gr_poly
		(pts
			(xy 337.561174 -277.52802) (xy 337.461098 -277.427944) (xy 337.361022 -277.52802) (xy 337.361022 -277.57247)
			(xy 337.561174 -277.57247)
		)
		(stroke
			(width 0)
			(type solid)
		)
		(fill yes)
		(layer "In2.Cu")
		(net "M_C_CPU0_SB_DQ<4>")
	)
	(gr_poly
		(pts
			(xy 337.561174 -277.124414) (xy 337.561174 -277.076662) (xy 337.361022 -277.076662) (xy 337.361022 -277.124414)
			(xy 337.461098 -277.224236)
		)
		(stroke
			(width 0)
			(type solid)
		)
		(fill yes)
		(layer "In2.Cu")
		(net "M_C_CPU0_SB_DQS_DP<5>")
	)
	(gr_poly
		(pts
			(xy 337.561174 -275.907754) (xy 337.461098 -275.807932) (xy 337.361022 -275.907754) (xy 337.361022 -275.955506)
			(xy 337.561174 -275.955506)
		)
		(stroke
			(width 0)
			(type solid)
		)
		(fill yes)
		(layer "In2.Cu")
		(net "M_C_CPU0_SB_DQS_DP<0>")
	)
	(gr_poly
		(pts
			(xy 337.561174 -275.504148) (xy 337.561174 -275.459698) (xy 337.361022 -275.459698) (xy 337.361022 -275.504148)
			(xy 337.461098 -275.604224)
		)
		(stroke
			(width 0)
			(type solid)
		)
		(fill yes)
		(layer "In2.Cu")
		(net "M_C_CPU0_SB_DQ<3>")
	)
	(gr_poly
		(pts
			(xy 337.561174 -274.287996) (xy 337.461098 -274.18792) (xy 337.361022 -274.287996) (xy 337.361022 -274.332446)
			(xy 337.561174 -274.332446)
		)
		(stroke
			(width 0)
			(type solid)
		)
		(fill yes)
		(layer "In2.Cu")
		(net "M_C_CPU0_SB_DQ<0>")
	)
	(gr_poly
		(pts
			(xy 337.561174 -273.884136) (xy 337.561174 -273.839686) (xy 337.361022 -273.839686) (xy 337.361022 -273.884136)
			(xy 337.461098 -273.984212)
		)
		(stroke
			(width 0)
			(type solid)
		)
		(fill yes)
		(layer "In2.Cu")
		(net "M_C_CPU0_SB_CB<3>")
	)
	(gr_poly
		(pts
			(xy 337.561174 -272.667984) (xy 337.461098 -272.567908) (xy 337.361022 -272.667984) (xy 337.361022 -272.712434)
			(xy 337.561174 -272.712434)
		)
		(stroke
			(width 0)
			(type solid)
		)
		(fill yes)
		(layer "In2.Cu")
		(net "M_C_CPU0_SB_CB<0>")
	)
	(gr_poly
		(pts
			(xy 337.561174 -272.264378) (xy 337.561174 -272.216626) (xy 337.361022 -272.216626) (xy 337.361022 -272.264378)
			(xy 337.461098 -272.3642)
		)
		(stroke
			(width 0)
			(type solid)
		)
		(fill yes)
		(layer "In2.Cu")
		(net "M_C_CPU0_SB_DQS_DP<4>")
	)
	(gr_poly
		(pts
			(xy 337.561174 -271.047718) (xy 337.461098 -270.947896) (xy 337.361022 -271.047718) (xy 337.361022 -271.09547)
			(xy 337.561174 -271.09547)
		)
		(stroke
			(width 0)
			(type solid)
		)
		(fill yes)
		(layer "In2.Cu")
		(net "M_C_CPU0_SB_DQS_DP<9>")
	)
	(gr_poly
		(pts
			(xy 337.561174 -270.644112) (xy 337.561174 -270.599662) (xy 337.361022 -270.599662) (xy 337.361022 -270.644112)
			(xy 337.461098 -270.744188)
		)
		(stroke
			(width 0)
			(type solid)
		)
		(fill yes)
		(layer "In2.Cu")
		(net "M_C_CPU0_SB_CB<7>")
	)
	(gr_poly
		(pts
			(xy 337.561174 -269.42796) (xy 337.461098 -269.327884) (xy 337.361022 -269.42796) (xy 337.361022 -269.47241)
			(xy 337.561174 -269.47241)
		)
		(stroke
			(width 0)
			(type solid)
		)
		(fill yes)
		(layer "In2.Cu")
		(net "M_C_CPU0_SB_CB<4>")
	)
	(gr_poly
		(pts
			(xy 337.561174 -267.801598) (xy 337.461098 -267.701522) (xy 337.361022 -267.801598) (xy 337.361022 -267.846048)
			(xy 337.561174 -267.846048)
		)
		(stroke
			(width 0)
			(type solid)
		)
		(fill yes)
		(layer "In2.Cu")
		(net "M_C_CPU0_SB_RSP<0>")
	)
	(gr_poly
		(pts
			(xy 337.561174 -265.784076) (xy 337.561174 -265.739626) (xy 337.361022 -265.739626) (xy 337.361022 -265.784076)
			(xy 337.461098 -265.884152)
		)
		(stroke
			(width 0)
			(type solid)
		)
		(fill yes)
		(layer "In2.Cu")
		(net "M_C_CPU0_SB_CS_N<0>")
	)
	(gr_poly
		(pts
			(xy 337.561174 -264.567924) (xy 337.461098 -264.467848) (xy 337.361022 -264.567924) (xy 337.361022 -264.612374)
			(xy 337.561174 -264.612374)
		)
		(stroke
			(width 0)
			(type solid)
		)
		(fill yes)
		(layer "In2.Cu")
		(net "M_C_CPU0_SB_CA<6>")
	)
	(gr_poly
		(pts
			(xy 337.561174 -264.164064) (xy 337.561174 -264.119614) (xy 337.361022 -264.119614) (xy 337.361022 -264.164064)
			(xy 337.461098 -264.26414)
		)
		(stroke
			(width 0)
			(type solid)
		)
		(fill yes)
		(layer "In2.Cu")
		(net "M_C_CPU0_SB_CA<5>")
	)
	(gr_poly
		(pts
			(xy 337.561174 -262.947912) (xy 337.461098 -262.847836) (xy 337.361022 -262.947912) (xy 337.361022 -262.992362)
			(xy 337.561174 -262.992362)
		)
		(stroke
			(width 0)
			(type solid)
		)
		(fill yes)
		(layer "In2.Cu")
		(net "M_C_CPU0_SB_CA<2>")
	)
	(gr_poly
		(pts
			(xy 337.561174 -262.544052) (xy 337.561174 -262.499602) (xy 337.361022 -262.499602) (xy 337.361022 -262.544052)
			(xy 337.461098 -262.644128)
		)
		(stroke
			(width 0)
			(type solid)
		)
		(fill yes)
		(layer "In2.Cu")
		(net "M_C_CPU0_SB_CA<1>")
	)
	(gr_poly
		(pts
			(xy 337.7311 -256.025904) (xy 337.631024 -255.926082) (xy 337.530948 -256.025904) (xy 337.530948 -256.073656)
			(xy 337.7311 -256.073656)
		)
		(stroke
			(width 0)
			(type solid)
		)
		(fill yes)
		(layer "In2.Cu")
		(net "M_C_CPU0_CLK_DP<0>")
	)
	(gr_poly
		(pts
			(xy 337.7311 -255.622298) (xy 337.7311 -255.577848) (xy 337.530948 -255.577848) (xy 337.530948 -255.622298)
			(xy 337.631024 -255.722374)
		)
		(stroke
			(width 0)
			(type solid)
		)
		(fill yes)
		(layer "In2.Cu")
		(net "M_C_CPU0_SA_PAR")
	)
	(gr_poly
		(pts
			(xy 337.7311 -254.406146) (xy 337.631024 -254.30607) (xy 337.530948 -254.406146) (xy 337.530948 -254.450596)
			(xy 337.7311 -254.450596)
		)
		(stroke
			(width 0)
			(type solid)
		)
		(fill yes)
		(layer "In2.Cu")
		(net "M_C_CPU0_SA_CA<4>")
	)
	(gr_poly
		(pts
			(xy 337.7311 -254.002286) (xy 337.7311 -253.957836) (xy 337.530948 -253.957836) (xy 337.530948 -254.002286)
			(xy 337.631024 -254.102362)
		)
		(stroke
			(width 0)
			(type solid)
		)
		(fill yes)
		(layer "In2.Cu")
		(net "M_C_CPU0_SA_CA<3>")
	)
	(gr_poly
		(pts
			(xy 337.7311 -252.786134) (xy 337.631024 -252.686058) (xy 337.530948 -252.786134) (xy 337.530948 -252.830584)
			(xy 337.7311 -252.830584)
		)
		(stroke
			(width 0)
			(type solid)
		)
		(fill yes)
		(layer "In2.Cu")
		(net "M_C_CPU0_SA_CA<0>")
	)
	(gr_poly
		(pts
			(xy 337.7311 -252.382274) (xy 337.7311 -252.337824) (xy 337.530948 -252.337824) (xy 337.530948 -252.382274)
			(xy 337.631024 -252.48235)
		)
		(stroke
			(width 0)
			(type solid)
		)
		(fill yes)
		(layer "In2.Cu")
		(net "M_C_CPU0_SA_CS_N<1>")
	)
	(gr_poly
		(pts
			(xy 337.7311 -250.762262) (xy 337.7311 -250.717812) (xy 337.530948 -250.717812) (xy 337.530948 -250.762262)
			(xy 337.631024 -250.862338)
		)
		(stroke
			(width 0)
			(type solid)
		)
		(fill yes)
		(layer "In2.Cu")
		(net "M_C_CPU0_RESET_N")
	)
	(gr_poly
		(pts
			(xy 337.7311 -249.14225) (xy 337.7311 -249.0978) (xy 337.530948 -249.0978) (xy 337.530948 -249.14225)
			(xy 337.631024 -249.242326)
		)
		(stroke
			(width 0)
			(type solid)
		)
		(fill yes)
		(layer "In2.Cu")
		(net "M_C_CPU0_SA_CB<7>")
	)
	(gr_poly
		(pts
			(xy 337.7311 -247.926098) (xy 337.631024 -247.826022) (xy 337.530948 -247.926098) (xy 337.530948 -247.970548)
			(xy 337.7311 -247.970548)
		)
		(stroke
			(width 0)
			(type solid)
		)
		(fill yes)
		(layer "In2.Cu")
		(net "M_C_CPU0_SA_CB<4>")
	)
	(gr_poly
		(pts
			(xy 337.7311 -247.522492) (xy 337.7311 -247.47474) (xy 337.530948 -247.47474) (xy 337.530948 -247.522492)
			(xy 337.631024 -247.622314)
		)
		(stroke
			(width 0)
			(type solid)
		)
		(fill yes)
		(layer "In2.Cu")
		(net "M_C_CPU0_SA_DQS_DP<9>")
	)
	(gr_poly
		(pts
			(xy 337.7311 -245.902226) (xy 337.7311 -245.857776) (xy 337.530948 -245.857776) (xy 337.530948 -245.902226)
			(xy 337.631024 -246.002302)
		)
		(stroke
			(width 0)
			(type solid)
		)
		(fill yes)
		(layer "In2.Cu")
		(net "M_C_CPU0_SA_CB<3>")
	)
	(gr_poly
		(pts
			(xy 337.7311 -244.686074) (xy 337.631024 -244.585998) (xy 337.530948 -244.686074) (xy 337.530948 -244.730524)
			(xy 337.7311 -244.730524)
		)
		(stroke
			(width 0)
			(type solid)
		)
		(fill yes)
		(layer "In2.Cu")
		(net "M_C_CPU0_SA_CB<0>")
	)
	(gr_poly
		(pts
			(xy 337.7311 -244.282214) (xy 337.7311 -244.237764) (xy 337.530948 -244.237764) (xy 337.530948 -244.282214)
			(xy 337.631024 -244.38229)
		)
		(stroke
			(width 0)
			(type solid)
		)
		(fill yes)
		(layer "In2.Cu")
		(net "M_C_CPU0_SA_DQ<31>")
	)
	(gr_poly
		(pts
			(xy 337.7311 -243.066062) (xy 337.631024 -242.965986) (xy 337.530948 -243.066062) (xy 337.530948 -243.110512)
			(xy 337.7311 -243.110512)
		)
		(stroke
			(width 0)
			(type solid)
		)
		(fill yes)
		(layer "In2.Cu")
		(net "M_C_CPU0_SA_DQ<28>")
	)
	(gr_poly
		(pts
			(xy 337.7311 -242.662456) (xy 337.7311 -242.614704) (xy 337.530948 -242.614704) (xy 337.530948 -242.662456)
			(xy 337.631024 -242.762278)
		)
		(stroke
			(width 0)
			(type solid)
		)
		(fill yes)
		(layer "In2.Cu")
		(net "M_C_CPU0_SA_DQS_DP<8>")
	)
	(gr_poly
		(pts
			(xy 337.7311 -241.445796) (xy 337.631024 -241.345974) (xy 337.530948 -241.445796) (xy 337.530948 -241.493548)
			(xy 337.7311 -241.493548)
		)
		(stroke
			(width 0)
			(type solid)
		)
		(fill yes)
		(layer "In2.Cu")
		(net "M_C_CPU0_SA_DQS_DP<3>")
	)
	(gr_poly
		(pts
			(xy 337.7311 -241.04219) (xy 337.7311 -240.99774) (xy 337.530948 -240.99774) (xy 337.530948 -241.04219)
			(xy 337.631024 -241.142266)
		)
		(stroke
			(width 0)
			(type solid)
		)
		(fill yes)
		(layer "In2.Cu")
		(net "M_C_CPU0_SA_DQ<27>")
	)
	(gr_poly
		(pts
			(xy 337.7311 -239.826038) (xy 337.631024 -239.725962) (xy 337.530948 -239.826038) (xy 337.530948 -239.870488)
			(xy 337.7311 -239.870488)
		)
		(stroke
			(width 0)
			(type solid)
		)
		(fill yes)
		(layer "In2.Cu")
		(net "M_C_CPU0_SA_DQ<24>")
	)
	(gr_poly
		(pts
			(xy 337.7311 -239.422178) (xy 337.7311 -239.377728) (xy 337.530948 -239.377728) (xy 337.530948 -239.422178)
			(xy 337.631024 -239.522254)
		)
		(stroke
			(width 0)
			(type solid)
		)
		(fill yes)
		(layer "In2.Cu")
		(net "M_C_CPU0_SA_DQ<23>")
	)
	(gr_poly
		(pts
			(xy 337.7311 -238.206026) (xy 337.631024 -238.10595) (xy 337.530948 -238.206026) (xy 337.530948 -238.250476)
			(xy 337.7311 -238.250476)
		)
		(stroke
			(width 0)
			(type solid)
		)
		(fill yes)
		(layer "In2.Cu")
		(net "M_C_CPU0_SA_DQ<20>")
	)
	(gr_poly
		(pts
			(xy 337.7311 -237.80242) (xy 337.7311 -237.754668) (xy 337.530948 -237.754668) (xy 337.530948 -237.80242)
			(xy 337.631024 -237.902242)
		)
		(stroke
			(width 0)
			(type solid)
		)
		(fill yes)
		(layer "In2.Cu")
		(net "M_C_CPU0_SA_DQS_DP<7>")
	)
	(gr_poly
		(pts
			(xy 337.7311 -236.58576) (xy 337.631024 -236.485938) (xy 337.530948 -236.58576) (xy 337.530948 -236.633512)
			(xy 337.7311 -236.633512)
		)
		(stroke
			(width 0)
			(type solid)
		)
		(fill yes)
		(layer "In2.Cu")
		(net "M_C_CPU0_SA_DQS_DP<2>")
	)
	(gr_poly
		(pts
			(xy 337.7311 -236.182154) (xy 337.7311 -236.137704) (xy 337.530948 -236.137704) (xy 337.530948 -236.182154)
			(xy 337.631024 -236.28223)
		)
		(stroke
			(width 0)
			(type solid)
		)
		(fill yes)
		(layer "In2.Cu")
		(net "M_C_CPU0_SA_DQ<19>")
	)
	(gr_poly
		(pts
			(xy 337.7311 -234.966002) (xy 337.631024 -234.865926) (xy 337.530948 -234.966002) (xy 337.530948 -235.010452)
			(xy 337.7311 -235.010452)
		)
		(stroke
			(width 0)
			(type solid)
		)
		(fill yes)
		(layer "In2.Cu")
		(net "M_C_CPU0_SA_DQ<16>")
	)
	(gr_poly
		(pts
			(xy 337.7311 -234.562142) (xy 337.7311 -234.517692) (xy 337.530948 -234.517692) (xy 337.530948 -234.562142)
			(xy 337.631024 -234.662218)
		)
		(stroke
			(width 0)
			(type solid)
		)
		(fill yes)
		(layer "In2.Cu")
		(net "M_C_CPU0_SA_DQ<15>")
	)
	(gr_poly
		(pts
			(xy 337.7311 -233.34599) (xy 337.631024 -233.245914) (xy 337.530948 -233.34599) (xy 337.530948 -233.39044)
			(xy 337.7311 -233.39044)
		)
		(stroke
			(width 0)
			(type solid)
		)
		(fill yes)
		(layer "In2.Cu")
		(net "M_C_CPU0_SA_DQ<12>")
	)
	(gr_poly
		(pts
			(xy 337.7311 -232.942384) (xy 337.7311 -232.894632) (xy 337.530948 -232.894632) (xy 337.530948 -232.942384)
			(xy 337.631024 -233.042206)
		)
		(stroke
			(width 0)
			(type solid)
		)
		(fill yes)
		(layer "In2.Cu")
		(net "M_C_CPU0_SA_DQS_DP<6>")
	)
	(gr_poly
		(pts
			(xy 337.7311 -231.725724) (xy 337.631024 -231.625902) (xy 337.530948 -231.725724) (xy 337.530948 -231.773476)
			(xy 337.7311 -231.773476)
		)
		(stroke
			(width 0)
			(type solid)
		)
		(fill yes)
		(layer "In2.Cu")
		(net "M_C_CPU0_SA_DQS_DP<1>")
	)
	(gr_poly
		(pts
			(xy 337.7311 -231.322372) (xy 337.7311 -231.277922) (xy 337.530948 -231.277922) (xy 337.530948 -231.322372)
			(xy 337.631024 -231.422448)
		)
		(stroke
			(width 0)
			(type solid)
		)
		(fill yes)
		(layer "In2.Cu")
		(net "M_C_CPU0_SA_DQ<11>")
	)
	(gr_poly
		(pts
			(xy 337.7311 -230.105966) (xy 337.631024 -230.006144) (xy 337.530948 -230.105966) (xy 337.530948 -230.150416)
			(xy 337.7311 -230.150416)
		)
		(stroke
			(width 0)
			(type solid)
		)
		(fill yes)
		(layer "In2.Cu")
		(net "M_C_CPU0_SA_DQ<8>")
	)
	(gr_poly
		(pts
			(xy 337.7311 -229.70236) (xy 337.7311 -229.65791) (xy 337.530948 -229.65791) (xy 337.530948 -229.70236)
			(xy 337.631024 -229.802436)
		)
		(stroke
			(width 0)
			(type solid)
		)
		(fill yes)
		(layer "In2.Cu")
		(net "M_C_CPU0_SA_DQ<7>")
	)
	(gr_poly
		(pts
			(xy 337.7311 -228.486208) (xy 337.631024 -228.386132) (xy 337.530948 -228.486208) (xy 337.530948 -228.530658)
			(xy 337.7311 -228.530658)
		)
		(stroke
			(width 0)
			(type solid)
		)
		(fill yes)
		(layer "In2.Cu")
		(net "M_C_CPU0_SA_DQ<4>")
	)
	(gr_poly
		(pts
			(xy 337.7311 -228.082602) (xy 337.7311 -228.03485) (xy 337.530948 -228.03485) (xy 337.530948 -228.082602)
			(xy 337.631024 -228.182424)
		)
		(stroke
			(width 0)
			(type solid)
		)
		(fill yes)
		(layer "In2.Cu")
		(net "M_C_CPU0_SA_DQS_DP<5>")
	)
	(gr_poly
		(pts
			(xy 337.7311 -226.865942) (xy 337.631024 -226.76612) (xy 337.530948 -226.865942) (xy 337.530948 -226.913694)
			(xy 337.7311 -226.913694)
		)
		(stroke
			(width 0)
			(type solid)
		)
		(fill yes)
		(layer "In2.Cu")
		(net "M_C_CPU0_SA_DQS_DP<0>")
	)
	(gr_poly
		(pts
			(xy 337.7311 -226.462336) (xy 337.7311 -226.417886) (xy 337.530948 -226.417886) (xy 337.530948 -226.462336)
			(xy 337.631024 -226.562412)
		)
		(stroke
			(width 0)
			(type solid)
		)
		(fill yes)
		(layer "In2.Cu")
		(net "M_C_CPU0_SA_DQ<3>")
	)
	(gr_poly
		(pts
			(xy 337.7311 -225.246184) (xy 337.631024 -225.146108) (xy 337.530948 -225.246184) (xy 337.530948 -225.290634)
			(xy 337.7311 -225.290634)
		)
		(stroke
			(width 0)
			(type solid)
		)
		(fill yes)
		(layer "In2.Cu")
		(net "M_C_CPU0_SA_DQ<0>")
	)
	(gr_poly
		(pts
			(xy 337.731354 -246.305832) (xy 337.631278 -246.20601) (xy 337.531202 -246.305832) (xy 337.531202 -246.353584)
			(xy 337.731354 -246.353584)
		)
		(stroke
			(width 0)
			(type solid)
		)
		(fill yes)
		(layer "In2.Cu")
		(net "M_C_CPU0_SA_DQS_DP<4>")
	)
	(gr_poly
		(pts
			(xy 338.031074 -292.91788) (xy 337.930998 -292.817804) (xy 337.830922 -292.91788) (xy 337.830922 -292.96233)
			(xy 338.031074 -292.96233)
		)
		(stroke
			(width 0)
			(type solid)
		)
		(fill yes)
		(layer "In2.Cu")
		(net "M_C_CPU0_SB_DQ<29>")
	)
	(gr_poly
		(pts
			(xy 338.031074 -292.51402) (xy 338.031074 -292.46957) (xy 337.830922 -292.46957) (xy 337.830922 -292.51402)
			(xy 337.930998 -292.614096)
		)
		(stroke
			(width 0)
			(type solid)
		)
		(fill yes)
		(layer "In2.Cu")
		(net "M_C_CPU0_SB_DQ<30>")
	)
	(gr_poly
		(pts
			(xy 338.031074 -290.894262) (xy 338.031074 -290.84651) (xy 337.830922 -290.84651) (xy 337.830922 -290.894262)
			(xy 337.930998 -290.994084)
		)
		(stroke
			(width 0)
			(type solid)
		)
		(fill yes)
		(layer "In2.Cu")
		(net "M_C_CPU0_SB_DQS_DN<3>")
	)
	(gr_poly
		(pts
			(xy 338.031074 -289.677856) (xy 337.930998 -289.57778) (xy 337.830922 -289.677856) (xy 337.830922 -289.722306)
			(xy 338.031074 -289.722306)
		)
		(stroke
			(width 0)
			(type solid)
		)
		(fill yes)
		(layer "In2.Cu")
		(net "M_C_CPU0_SB_DQ<25>")
	)
	(gr_poly
		(pts
			(xy 338.031074 -289.273996) (xy 338.031074 -289.229546) (xy 337.830922 -289.229546) (xy 337.830922 -289.273996)
			(xy 337.930998 -289.374072)
		)
		(stroke
			(width 0)
			(type solid)
		)
		(fill yes)
		(layer "In2.Cu")
		(net "M_C_CPU0_SB_DQ<26>")
	)
	(gr_poly
		(pts
			(xy 338.031074 -288.057844) (xy 337.930998 -287.957768) (xy 337.830922 -288.057844) (xy 337.830922 -288.102294)
			(xy 338.031074 -288.102294)
		)
		(stroke
			(width 0)
			(type solid)
		)
		(fill yes)
		(layer "In2.Cu")
		(net "M_C_CPU0_SB_DQ<21>")
	)
	(gr_poly
		(pts
			(xy 338.031074 -287.654238) (xy 338.031074 -287.609788) (xy 337.830922 -287.609788) (xy 337.830922 -287.654238)
			(xy 337.930998 -287.75406)
		)
		(stroke
			(width 0)
			(type solid)
		)
		(fill yes)
		(layer "In2.Cu")
		(net "M_C_CPU0_SB_DQ<22>")
	)
	(gr_poly
		(pts
			(xy 338.031074 -286.437832) (xy 337.930998 -286.337756) (xy 337.830922 -286.437832) (xy 337.830922 -286.485584)
			(xy 338.031074 -286.485584)
		)
		(stroke
			(width 0)
			(type solid)
		)
		(fill yes)
		(layer "In2.Cu")
		(net "M_C_CPU0_SB_DQS_DN<7>")
	)
	(gr_poly
		(pts
			(xy 338.031074 -286.03448) (xy 338.031074 -285.986728) (xy 337.830922 -285.986728) (xy 337.830922 -286.03448)
			(xy 337.930998 -286.134302)
		)
		(stroke
			(width 0)
			(type solid)
		)
		(fill yes)
		(layer "In2.Cu")
		(net "M_C_CPU0_SB_DQS_DN<2>")
	)
	(gr_poly
		(pts
			(xy 338.031074 -284.818074) (xy 337.930998 -284.717998) (xy 337.830922 -284.818074) (xy 337.830922 -284.862524)
			(xy 338.031074 -284.862524)
		)
		(stroke
			(width 0)
			(type solid)
		)
		(fill yes)
		(layer "In2.Cu")
		(net "M_C_CPU0_SB_DQ<17>")
	)
	(gr_poly
		(pts
			(xy 338.031074 -284.414214) (xy 338.031074 -284.369764) (xy 337.830922 -284.369764) (xy 337.830922 -284.414214)
			(xy 337.930998 -284.51429)
		)
		(stroke
			(width 0)
			(type solid)
		)
		(fill yes)
		(layer "In2.Cu")
		(net "M_C_CPU0_SB_DQ<18>")
	)
	(gr_poly
		(pts
			(xy 338.031074 -283.198062) (xy 337.930998 -283.097986) (xy 337.830922 -283.198062) (xy 337.830922 -283.242512)
			(xy 338.031074 -283.242512)
		)
		(stroke
			(width 0)
			(type solid)
		)
		(fill yes)
		(layer "In2.Cu")
		(net "M_C_CPU0_SB_DQ<13>")
	)
	(gr_poly
		(pts
			(xy 338.031074 -282.794202) (xy 338.031074 -282.749752) (xy 337.830922 -282.749752) (xy 337.830922 -282.794202)
			(xy 337.930998 -282.894278)
		)
		(stroke
			(width 0)
			(type solid)
		)
		(fill yes)
		(layer "In2.Cu")
		(net "M_C_CPU0_SB_DQ<14>")
	)
	(gr_poly
		(pts
			(xy 338.031074 -281.577796) (xy 337.930998 -281.477974) (xy 337.830922 -281.577796) (xy 337.830922 -281.625548)
			(xy 338.031074 -281.625548)
		)
		(stroke
			(width 0)
			(type solid)
		)
		(fill yes)
		(layer "In2.Cu")
		(net "M_C_CPU0_SB_DQS_DN<6>")
	)
	(gr_poly
		(pts
			(xy 338.031074 -281.174444) (xy 338.031074 -281.126692) (xy 337.830922 -281.126692) (xy 337.830922 -281.174444)
			(xy 337.930998 -281.274266)
		)
		(stroke
			(width 0)
			(type solid)
		)
		(fill yes)
		(layer "In2.Cu")
		(net "M_C_CPU0_SB_DQS_DN<1>")
	)
	(gr_poly
		(pts
			(xy 338.031074 -279.958038) (xy 337.930998 -279.857962) (xy 337.830922 -279.958038) (xy 337.830922 -280.002488)
			(xy 338.031074 -280.002488)
		)
		(stroke
			(width 0)
			(type solid)
		)
		(fill yes)
		(layer "In2.Cu")
		(net "M_C_CPU0_SB_DQ<9>")
	)
	(gr_poly
		(pts
			(xy 338.031074 -279.554178) (xy 338.031074 -279.509728) (xy 337.830922 -279.509728) (xy 337.830922 -279.554178)
			(xy 337.930998 -279.654254)
		)
		(stroke
			(width 0)
			(type solid)
		)
		(fill yes)
		(layer "In2.Cu")
		(net "M_C_CPU0_SB_DQ<10>")
	)
	(gr_poly
		(pts
			(xy 338.031074 -278.338026) (xy 337.930998 -278.23795) (xy 337.830922 -278.338026) (xy 337.830922 -278.382476)
			(xy 338.031074 -278.382476)
		)
		(stroke
			(width 0)
			(type solid)
		)
		(fill yes)
		(layer "In2.Cu")
		(net "M_C_CPU0_SB_DQ<5>")
	)
	(gr_poly
		(pts
			(xy 338.031074 -277.934166) (xy 338.031074 -277.889716) (xy 337.830922 -277.889716) (xy 337.830922 -277.934166)
			(xy 337.930998 -278.034242)
		)
		(stroke
			(width 0)
			(type solid)
		)
		(fill yes)
		(layer "In2.Cu")
		(net "M_C_CPU0_SB_DQ<6>")
	)
	(gr_poly
		(pts
			(xy 338.031074 -276.71776) (xy 337.930998 -276.617938) (xy 337.830922 -276.71776) (xy 337.830922 -276.765512)
			(xy 338.031074 -276.765512)
		)
		(stroke
			(width 0)
			(type solid)
		)
		(fill yes)
		(layer "In2.Cu")
		(net "M_C_CPU0_SB_DQS_DN<5>")
	)
	(gr_poly
		(pts
			(xy 338.031074 -276.314408) (xy 338.031074 -276.266656) (xy 337.830922 -276.266656) (xy 337.830922 -276.314408)
			(xy 337.930998 -276.41423)
		)
		(stroke
			(width 0)
			(type solid)
		)
		(fill yes)
		(layer "In2.Cu")
		(net "M_C_CPU0_SB_DQS_DN<0>")
	)
	(gr_poly
		(pts
			(xy 338.031074 -275.098002) (xy 337.930998 -274.997926) (xy 337.830922 -275.098002) (xy 337.830922 -275.142452)
			(xy 338.031074 -275.142452)
		)
		(stroke
			(width 0)
			(type solid)
		)
		(fill yes)
		(layer "In2.Cu")
		(net "M_C_CPU0_SB_DQ<1>")
	)
	(gr_poly
		(pts
			(xy 338.031074 -274.694142) (xy 338.031074 -274.649692) (xy 337.830922 -274.649692) (xy 337.830922 -274.694142)
			(xy 337.930998 -274.794218)
		)
		(stroke
			(width 0)
			(type solid)
		)
		(fill yes)
		(layer "In2.Cu")
		(net "M_C_CPU0_SB_DQ<2>")
	)
	(gr_poly
		(pts
			(xy 338.031074 -273.47799) (xy 337.930998 -273.377914) (xy 337.830922 -273.47799) (xy 337.830922 -273.52244)
			(xy 338.031074 -273.52244)
		)
		(stroke
			(width 0)
			(type solid)
		)
		(fill yes)
		(layer "In2.Cu")
		(net "M_C_CPU0_SB_CB<1>")
	)
	(gr_poly
		(pts
			(xy 338.031074 -273.07413) (xy 338.031074 -273.02968) (xy 337.830922 -273.02968) (xy 337.830922 -273.07413)
			(xy 337.930998 -273.174206)
		)
		(stroke
			(width 0)
			(type solid)
		)
		(fill yes)
		(layer "In2.Cu")
		(net "M_C_CPU0_SB_CB<2>")
	)
	(gr_poly
		(pts
			(xy 338.031074 -271.857724) (xy 337.930998 -271.757902) (xy 337.830922 -271.857724) (xy 337.830922 -271.905476)
			(xy 338.031074 -271.905476)
		)
		(stroke
			(width 0)
			(type solid)
		)
		(fill yes)
		(layer "In2.Cu")
		(net "M_C_CPU0_SB_DQS_DN<4>")
	)
	(gr_poly
		(pts
			(xy 338.031074 -271.454372) (xy 338.031074 -271.40662) (xy 337.830922 -271.40662) (xy 337.830922 -271.454372)
			(xy 337.930998 -271.554194)
		)
		(stroke
			(width 0)
			(type solid)
		)
		(fill yes)
		(layer "In2.Cu")
		(net "M_C_CPU0_SB_DQS_DN<9>")
	)
	(gr_poly
		(pts
			(xy 338.031074 -270.237966) (xy 337.930998 -270.13789) (xy 337.830922 -270.237966) (xy 337.830922 -270.282416)
			(xy 338.031074 -270.282416)
		)
		(stroke
			(width 0)
			(type solid)
		)
		(fill yes)
		(layer "In2.Cu")
		(net "M_C_CPU0_SB_CB<5>")
	)
	(gr_poly
		(pts
			(xy 338.031074 -269.834106) (xy 338.031074 -269.789656) (xy 337.830922 -269.789656) (xy 337.830922 -269.834106)
			(xy 337.930998 -269.934182)
		)
		(stroke
			(width 0)
			(type solid)
		)
		(fill yes)
		(layer "In2.Cu")
		(net "M_C_CPU0_SB_CB<6>")
	)
	(gr_poly
		(pts
			(xy 338.031074 -266.594082) (xy 338.031074 -266.549632) (xy 337.830922 -266.549632) (xy 337.830922 -266.594082)
			(xy 337.930998 -266.694158)
		)
		(stroke
			(width 0)
			(type solid)
		)
		(fill yes)
		(layer "In2.Cu")
		(net "M_C_CPU0_SB_CS_N<1>")
	)
	(gr_poly
		(pts
			(xy 338.031074 -264.97407) (xy 338.031074 -264.92962) (xy 337.830922 -264.92962) (xy 337.830922 -264.97407)
			(xy 337.930998 -265.074146)
		)
		(stroke
			(width 0)
			(type solid)
		)
		(fill yes)
		(layer "In2.Cu")
		(net "M_C_CPU0_SB_PAR")
	)
	(gr_poly
		(pts
			(xy 338.031074 -263.757918) (xy 337.930998 -263.657842) (xy 337.830922 -263.757918) (xy 337.830922 -263.802368)
			(xy 338.031074 -263.802368)
		)
		(stroke
			(width 0)
			(type solid)
		)
		(fill yes)
		(layer "In2.Cu")
		(net "M_C_CPU0_SB_CA<4>")
	)
	(gr_poly
		(pts
			(xy 338.031074 -263.354058) (xy 338.031074 -263.309608) (xy 337.830922 -263.309608) (xy 337.830922 -263.354058)
			(xy 337.930998 -263.454134)
		)
		(stroke
			(width 0)
			(type solid)
		)
		(fill yes)
		(layer "In2.Cu")
		(net "M_C_CPU0_SB_CA<3>")
	)
	(gr_poly
		(pts
			(xy 338.031074 -262.137906) (xy 337.930998 -262.03783) (xy 337.830922 -262.137906) (xy 337.830922 -262.182356)
			(xy 338.031074 -262.182356)
		)
		(stroke
			(width 0)
			(type solid)
		)
		(fill yes)
		(layer "In2.Cu")
		(net "M_C_CPU0_SB_CA<0>")
	)
	(gr_poly
		(pts
			(xy 338.03717 -266.991592) (xy 337.937348 -266.891516) (xy 337.837272 -266.991592) (xy 337.837272 -267.036042)
			(xy 338.03717 -267.036042)
		)
		(stroke
			(width 0)
			(type solid)
		)
		(fill yes)
		(layer "In2.Cu")
		(net "M_C_CPU0_SA_RSP<0>")
	)
	(gr_poly
		(pts
			(xy 338.03844 -291.297614) (xy 337.938364 -291.197792) (xy 337.838288 -291.297614) (xy 337.838288 -291.345366)
			(xy 338.03844 -291.345366)
		)
		(stroke
			(width 0)
			(type solid)
		)
		(fill yes)
		(layer "In2.Cu")
		(net "M_C_CPU0_SB_DQS_DN<8>")
	)
	(gr_poly
		(pts
			(xy 338.201 -246.712232) (xy 338.201 -246.664734) (xy 338.001102 -246.664734) (xy 338.001102 -246.712232)
			(xy 338.100924 -246.812308)
		)
		(stroke
			(width 0)
			(type solid)
		)
		(fill yes)
		(layer "In2.Cu")
		(net "M_C_CPU0_SA_DQS_DN<4>")
	)
	(gr_poly
		(pts
			(xy 338.201254 -256.432558) (xy 338.201254 -256.384806) (xy 338.001102 -256.384806) (xy 338.001102 -256.432558)
			(xy 338.101178 -256.53238)
		)
		(stroke
			(width 0)
			(type solid)
		)
		(fill yes)
		(layer "In2.Cu")
		(net "M_C_CPU0_CLK_DN<0>")
	)
	(gr_poly
		(pts
			(xy 338.201254 -255.216152) (xy 338.101178 -255.116076) (xy 338.001102 -255.216152) (xy 338.001102 -255.260602)
			(xy 338.201254 -255.260602)
		)
		(stroke
			(width 0)
			(type solid)
		)
		(fill yes)
		(layer "In2.Cu")
		(net "M_C_CPU0_SA_CA<6>")
	)
	(gr_poly
		(pts
			(xy 338.201254 -254.812292) (xy 338.201254 -254.767842) (xy 338.001102 -254.767842) (xy 338.001102 -254.812292)
			(xy 338.101178 -254.912368)
		)
		(stroke
			(width 0)
			(type solid)
		)
		(fill yes)
		(layer "In2.Cu")
		(net "M_C_CPU0_SA_CA<5>")
	)
	(gr_poly
		(pts
			(xy 338.201254 -253.59614) (xy 338.101178 -253.496064) (xy 338.001102 -253.59614) (xy 338.001102 -253.64059)
			(xy 338.201254 -253.64059)
		)
		(stroke
			(width 0)
			(type solid)
		)
		(fill yes)
		(layer "In2.Cu")
		(net "M_C_CPU0_SA_CA<2>")
	)
	(gr_poly
		(pts
			(xy 338.201254 -253.19228) (xy 338.201254 -253.14783) (xy 338.001102 -253.14783) (xy 338.001102 -253.19228)
			(xy 338.101178 -253.292356)
		)
		(stroke
			(width 0)
			(type solid)
		)
		(fill yes)
		(layer "In2.Cu")
		(net "M_C_CPU0_SA_CA<1>")
	)
	(gr_poly
		(pts
			(xy 338.201254 -251.572268) (xy 338.201254 -251.527818) (xy 338.001102 -251.527818) (xy 338.001102 -251.572268)
			(xy 338.101178 -251.672344)
		)
		(stroke
			(width 0)
			(type solid)
		)
		(fill yes)
		(layer "In2.Cu")
		(net "M_C_CPU0_SA_CS_N<0>")
	)
	(gr_poly
		(pts
			(xy 338.201254 -250.356116) (xy 338.101178 -250.25604) (xy 338.001102 -250.356116) (xy 338.001102 -250.400566)
			(xy 338.201254 -250.400566)
		)
		(stroke
			(width 0)
			(type solid)
		)
		(fill yes)
		(layer "In2.Cu")
		(net "M_C_CPU0_ALERT_R_N")
	)
	(gr_poly
		(pts
			(xy 338.201254 -248.736104) (xy 338.101178 -248.636028) (xy 338.001102 -248.736104) (xy 338.001102 -248.780554)
			(xy 338.201254 -248.780554)
		)
		(stroke
			(width 0)
			(type solid)
		)
		(fill yes)
		(layer "In2.Cu")
		(net "M_C_CPU0_SA_CB<5>")
	)
	(gr_poly
		(pts
			(xy 338.201254 -248.332244) (xy 338.201254 -248.287794) (xy 338.001102 -248.287794) (xy 338.001102 -248.332244)
			(xy 338.101178 -248.43232)
		)
		(stroke
			(width 0)
			(type solid)
		)
		(fill yes)
		(layer "In2.Cu")
		(net "M_C_CPU0_SA_CB<6>")
	)
	(gr_poly
		(pts
			(xy 338.201254 -247.115838) (xy 338.101178 -247.016016) (xy 338.001102 -247.115838) (xy 338.001102 -247.16359)
			(xy 338.201254 -247.16359)
		)
		(stroke
			(width 0)
			(type solid)
		)
		(fill yes)
		(layer "In2.Cu")
		(net "M_C_CPU0_SA_DQS_DN<9>")
	)
	(gr_poly
		(pts
			(xy 338.201254 -245.49608) (xy 338.101178 -245.396004) (xy 338.001102 -245.49608) (xy 338.001102 -245.54053)
			(xy 338.201254 -245.54053)
		)
		(stroke
			(width 0)
			(type solid)
		)
		(fill yes)
		(layer "In2.Cu")
		(net "M_C_CPU0_SA_CB<1>")
	)
	(gr_poly
		(pts
			(xy 338.201254 -245.09222) (xy 338.201254 -245.04777) (xy 338.001102 -245.04777) (xy 338.001102 -245.09222)
			(xy 338.101178 -245.192296)
		)
		(stroke
			(width 0)
			(type solid)
		)
		(fill yes)
		(layer "In2.Cu")
		(net "M_C_CPU0_SA_CB<2>")
	)
	(gr_poly
		(pts
			(xy 338.201254 -243.876068) (xy 338.101178 -243.775992) (xy 338.001102 -243.876068) (xy 338.001102 -243.920518)
			(xy 338.201254 -243.920518)
		)
		(stroke
			(width 0)
			(type solid)
		)
		(fill yes)
		(layer "In2.Cu")
		(net "M_C_CPU0_SA_DQ<29>")
	)
	(gr_poly
		(pts
			(xy 338.201254 -243.472208) (xy 338.201254 -243.427758) (xy 338.001102 -243.427758) (xy 338.001102 -243.472208)
			(xy 338.101178 -243.572284)
		)
		(stroke
			(width 0)
			(type solid)
		)
		(fill yes)
		(layer "In2.Cu")
		(net "M_C_CPU0_SA_DQ<30>")
	)
	(gr_poly
		(pts
			(xy 338.201254 -242.255802) (xy 338.101178 -242.15598) (xy 338.001102 -242.255802) (xy 338.001102 -242.303554)
			(xy 338.201254 -242.303554)
		)
		(stroke
			(width 0)
			(type solid)
		)
		(fill yes)
		(layer "In2.Cu")
		(net "M_C_CPU0_SA_DQS_DN<8>")
	)
	(gr_poly
		(pts
			(xy 338.201254 -241.85245) (xy 338.201254 -241.804698) (xy 338.001102 -241.804698) (xy 338.001102 -241.85245)
			(xy 338.101178 -241.952272)
		)
		(stroke
			(width 0)
			(type solid)
		)
		(fill yes)
		(layer "In2.Cu")
		(net "M_C_CPU0_SA_DQS_DN<3>")
	)
	(gr_poly
		(pts
			(xy 338.201254 -240.636044) (xy 338.101178 -240.535968) (xy 338.001102 -240.636044) (xy 338.001102 -240.680494)
			(xy 338.201254 -240.680494)
		)
		(stroke
			(width 0)
			(type solid)
		)
		(fill yes)
		(layer "In2.Cu")
		(net "M_C_CPU0_SA_DQ<25>")
	)
	(gr_poly
		(pts
			(xy 338.201254 -240.232184) (xy 338.201254 -240.187734) (xy 338.001102 -240.187734) (xy 338.001102 -240.232184)
			(xy 338.101178 -240.33226)
		)
		(stroke
			(width 0)
			(type solid)
		)
		(fill yes)
		(layer "In2.Cu")
		(net "M_C_CPU0_SA_DQ<26>")
	)
	(gr_poly
		(pts
			(xy 338.201254 -239.016032) (xy 338.101178 -238.915956) (xy 338.001102 -239.016032) (xy 338.001102 -239.060482)
			(xy 338.201254 -239.060482)
		)
		(stroke
			(width 0)
			(type solid)
		)
		(fill yes)
		(layer "In2.Cu")
		(net "M_C_CPU0_SA_DQ<21>")
	)
	(gr_poly
		(pts
			(xy 338.201254 -238.612172) (xy 338.201254 -238.567722) (xy 338.001102 -238.567722) (xy 338.001102 -238.612172)
			(xy 338.101178 -238.712248)
		)
		(stroke
			(width 0)
			(type solid)
		)
		(fill yes)
		(layer "In2.Cu")
		(net "M_C_CPU0_SA_DQ<22>")
	)
	(gr_poly
		(pts
			(xy 338.201254 -237.395766) (xy 338.101178 -237.295944) (xy 338.001102 -237.395766) (xy 338.001102 -237.443518)
			(xy 338.201254 -237.443518)
		)
		(stroke
			(width 0)
			(type solid)
		)
		(fill yes)
		(layer "In2.Cu")
		(net "M_C_CPU0_SA_DQS_DN<7>")
	)
	(gr_poly
		(pts
			(xy 338.201254 -236.992414) (xy 338.201254 -236.944662) (xy 338.001102 -236.944662) (xy 338.001102 -236.992414)
			(xy 338.101178 -237.092236)
		)
		(stroke
			(width 0)
			(type solid)
		)
		(fill yes)
		(layer "In2.Cu")
		(net "M_C_CPU0_SA_DQS_DN<2>")
	)
	(gr_poly
		(pts
			(xy 338.201254 -235.776008) (xy 338.101178 -235.675932) (xy 338.001102 -235.776008) (xy 338.001102 -235.820458)
			(xy 338.201254 -235.820458)
		)
		(stroke
			(width 0)
			(type solid)
		)
		(fill yes)
		(layer "In2.Cu")
		(net "M_C_CPU0_SA_DQ<17>")
	)
	(gr_poly
		(pts
			(xy 338.201254 -235.372148) (xy 338.201254 -235.327698) (xy 338.001102 -235.327698) (xy 338.001102 -235.372148)
			(xy 338.101178 -235.472224)
		)
		(stroke
			(width 0)
			(type solid)
		)
		(fill yes)
		(layer "In2.Cu")
		(net "M_C_CPU0_SA_DQ<18>")
	)
	(gr_poly
		(pts
			(xy 338.201254 -234.155996) (xy 338.101178 -234.05592) (xy 338.001102 -234.155996) (xy 338.001102 -234.200446)
			(xy 338.201254 -234.200446)
		)
		(stroke
			(width 0)
			(type solid)
		)
		(fill yes)
		(layer "In2.Cu")
		(net "M_C_CPU0_SA_DQ<13>")
	)
	(gr_poly
		(pts
			(xy 338.201254 -233.752136) (xy 338.201254 -233.707686) (xy 338.001102 -233.707686) (xy 338.001102 -233.752136)
			(xy 338.101178 -233.852212)
		)
		(stroke
			(width 0)
			(type solid)
		)
		(fill yes)
		(layer "In2.Cu")
		(net "M_C_CPU0_SA_DQ<14>")
	)
	(gr_poly
		(pts
			(xy 338.201254 -232.53573) (xy 338.101178 -232.435908) (xy 338.001102 -232.53573) (xy 338.001102 -232.583482)
			(xy 338.201254 -232.583482)
		)
		(stroke
			(width 0)
			(type solid)
		)
		(fill yes)
		(layer "In2.Cu")
		(net "M_C_CPU0_SA_DQS_DN<6>")
	)
	(gr_poly
		(pts
			(xy 338.201254 -232.132378) (xy 338.201254 -232.084626) (xy 338.001102 -232.084626) (xy 338.001102 -232.132378)
			(xy 338.101178 -232.2322)
		)
		(stroke
			(width 0)
			(type solid)
		)
		(fill yes)
		(layer "In2.Cu")
		(net "M_C_CPU0_SA_DQS_DN<1>")
	)
	(gr_poly
		(pts
			(xy 338.201254 -230.915972) (xy 338.101178 -230.815896) (xy 338.001102 -230.915972) (xy 338.001102 -230.960422)
			(xy 338.201254 -230.960422)
		)
		(stroke
			(width 0)
			(type solid)
		)
		(fill yes)
		(layer "In2.Cu")
		(net "M_C_CPU0_SA_DQ<9>")
	)
	(gr_poly
		(pts
			(xy 338.201254 -230.512366) (xy 338.201254 -230.467916) (xy 338.001102 -230.467916) (xy 338.001102 -230.512366)
			(xy 338.101178 -230.612188)
		)
		(stroke
			(width 0)
			(type solid)
		)
		(fill yes)
		(layer "In2.Cu")
		(net "M_C_CPU0_SA_DQ<10>")
	)
	(gr_poly
		(pts
			(xy 338.201254 -229.29596) (xy 338.101178 -229.195884) (xy 338.001102 -229.29596) (xy 338.001102 -229.34041)
			(xy 338.201254 -229.34041)
		)
		(stroke
			(width 0)
			(type solid)
		)
		(fill yes)
		(layer "In2.Cu")
		(net "M_C_CPU0_SA_DQ<5>")
	)
	(gr_poly
		(pts
			(xy 338.201254 -228.892354) (xy 338.201254 -228.847904) (xy 338.001102 -228.847904) (xy 338.001102 -228.892354)
			(xy 338.101178 -228.99243)
		)
		(stroke
			(width 0)
			(type solid)
		)
		(fill yes)
		(layer "In2.Cu")
		(net "M_C_CPU0_SA_DQ<6>")
	)
	(gr_poly
		(pts
			(xy 338.201254 -227.675948) (xy 338.101178 -227.576126) (xy 338.001102 -227.675948) (xy 338.001102 -227.7237)
			(xy 338.201254 -227.7237)
		)
		(stroke
			(width 0)
			(type solid)
		)
		(fill yes)
		(layer "In2.Cu")
		(net "M_C_CPU0_SA_DQS_DN<5>")
	)
	(gr_poly
		(pts
			(xy 338.201254 -227.272596) (xy 338.201254 -227.224844) (xy 338.001102 -227.224844) (xy 338.001102 -227.272596)
			(xy 338.101178 -227.372418)
		)
		(stroke
			(width 0)
			(type solid)
		)
		(fill yes)
		(layer "In2.Cu")
		(net "M_C_CPU0_SA_DQS_DN<0>")
	)
	(gr_poly
		(pts
			(xy 338.201254 -226.05619) (xy 338.101178 -225.956114) (xy 338.001102 -226.05619) (xy 338.001102 -226.10064)
			(xy 338.201254 -226.10064)
		)
		(stroke
			(width 0)
			(type solid)
		)
		(fill yes)
		(layer "In2.Cu")
		(net "M_C_CPU0_SA_DQ<1>")
	)
	(gr_poly
		(pts
			(xy 338.201254 -225.65233) (xy 338.201254 -225.60788) (xy 338.001102 -225.60788) (xy 338.001102 -225.65233)
			(xy 338.101178 -225.752406)
		)
		(stroke
			(width 0)
			(type solid)
		)
		(fill yes)
		(layer "In2.Cu")
		(net "M_C_CPU0_SA_DQ<2>")
	)
	(gr_poly
		(pts
			(xy 338.493862 -291.704268) (xy 338.493862 -291.656516) (xy 338.29371 -291.656516) (xy 338.29371 -291.704268)
			(xy 338.393786 -291.80409)
		)
		(stroke
			(width 0)
			(type solid)
		)
		(fill yes)
		(layer "In2.Cu")
		(net "M_C_CPU0_SB_DQS_DP<8>")
	)
	(gr_poly
		(pts
			(xy 338.494878 -267.801598) (xy 338.394802 -267.701522) (xy 338.29498 -267.801598) (xy 338.29498 -267.846048)
			(xy 338.494878 -267.846048)
		)
		(stroke
			(width 0)
			(type solid)
		)
		(fill yes)
		(layer "In2.Cu")
		(net "M_C_CPU0_SB_RSP<0>")
	)
	(gr_poly
		(pts
			(xy 338.501228 -293.324026) (xy 338.501228 -293.279576) (xy 338.301076 -293.279576) (xy 338.301076 -293.324026)
			(xy 338.401152 -293.424102)
		)
		(stroke
			(width 0)
			(type solid)
		)
		(fill yes)
		(layer "In2.Cu")
		(net "M_C_CPU0_SB_DQ<31>")
	)
	(gr_poly
		(pts
			(xy 338.501228 -292.107874) (xy 338.401152 -292.007798) (xy 338.301076 -292.107874) (xy 338.301076 -292.152324)
			(xy 338.501228 -292.152324)
		)
		(stroke
			(width 0)
			(type solid)
		)
		(fill yes)
		(layer "In2.Cu")
		(net "M_C_CPU0_SB_DQ<28>")
	)
	(gr_poly
		(pts
			(xy 338.501228 -290.487608) (xy 338.401152 -290.387786) (xy 338.301076 -290.487608) (xy 338.301076 -290.53536)
			(xy 338.501228 -290.53536)
		)
		(stroke
			(width 0)
			(type solid)
		)
		(fill yes)
		(layer "In2.Cu")
		(net "M_C_CPU0_SB_DQS_DP<3>")
	)
	(gr_poly
		(pts
			(xy 338.501228 -290.084002) (xy 338.501228 -290.039552) (xy 338.301076 -290.039552) (xy 338.301076 -290.084002)
			(xy 338.401152 -290.184078)
		)
		(stroke
			(width 0)
			(type solid)
		)
		(fill yes)
		(layer "In2.Cu")
		(net "M_C_CPU0_SB_DQ<27>")
	)
	(gr_poly
		(pts
			(xy 338.501228 -288.86785) (xy 338.401152 -288.767774) (xy 338.301076 -288.86785) (xy 338.301076 -288.9123)
			(xy 338.501228 -288.9123)
		)
		(stroke
			(width 0)
			(type solid)
		)
		(fill yes)
		(layer "In2.Cu")
		(net "M_C_CPU0_SB_DQ<24>")
	)
	(gr_poly
		(pts
			(xy 338.501228 -288.464244) (xy 338.501228 -288.419794) (xy 338.301076 -288.419794) (xy 338.301076 -288.464244)
			(xy 338.401152 -288.56432)
		)
		(stroke
			(width 0)
			(type solid)
		)
		(fill yes)
		(layer "In2.Cu")
		(net "M_C_CPU0_SB_DQ<23>")
	)
	(gr_poly
		(pts
			(xy 338.501228 -287.247838) (xy 338.401152 -287.148016) (xy 338.301076 -287.247838) (xy 338.301076 -287.292288)
			(xy 338.501228 -287.292288)
		)
		(stroke
			(width 0)
			(type solid)
		)
		(fill yes)
		(layer "In2.Cu")
		(net "M_C_CPU0_SB_DQ<20>")
	)
	(gr_poly
		(pts
			(xy 338.501228 -286.844232) (xy 338.501228 -286.79648) (xy 338.301076 -286.79648) (xy 338.301076 -286.844232)
			(xy 338.401152 -286.944308)
		)
		(stroke
			(width 0)
			(type solid)
		)
		(fill yes)
		(layer "In2.Cu")
		(net "M_C_CPU0_SB_DQS_DP<7>")
	)
	(gr_poly
		(pts
			(xy 338.501228 -285.627826) (xy 338.401152 -285.528004) (xy 338.301076 -285.627826) (xy 338.301076 -285.675578)
			(xy 338.501228 -285.675578)
		)
		(stroke
			(width 0)
			(type solid)
		)
		(fill yes)
		(layer "In2.Cu")
		(net "M_C_CPU0_SB_DQS_DP<2>")
	)
	(gr_poly
		(pts
			(xy 338.501228 -285.22422) (xy 338.501228 -285.17977) (xy 338.301076 -285.17977) (xy 338.301076 -285.22422)
			(xy 338.401152 -285.324296)
		)
		(stroke
			(width 0)
			(type solid)
		)
		(fill yes)
		(layer "In2.Cu")
		(net "M_C_CPU0_SB_DQ<19>")
	)
	(gr_poly
		(pts
			(xy 338.501228 -284.008068) (xy 338.401152 -283.907992) (xy 338.301076 -284.008068) (xy 338.301076 -284.052518)
			(xy 338.501228 -284.052518)
		)
		(stroke
			(width 0)
			(type solid)
		)
		(fill yes)
		(layer "In2.Cu")
		(net "M_C_CPU0_SB_DQ<16>")
	)
	(gr_poly
		(pts
			(xy 338.501228 -283.604208) (xy 338.501228 -283.559758) (xy 338.301076 -283.559758) (xy 338.301076 -283.604208)
			(xy 338.401152 -283.704284)
		)
		(stroke
			(width 0)
			(type solid)
		)
		(fill yes)
		(layer "In2.Cu")
		(net "M_C_CPU0_SB_DQ<15>")
	)
	(gr_poly
		(pts
			(xy 338.501228 -282.388056) (xy 338.401152 -282.28798) (xy 338.301076 -282.388056) (xy 338.301076 -282.432506)
			(xy 338.501228 -282.432506)
		)
		(stroke
			(width 0)
			(type solid)
		)
		(fill yes)
		(layer "In2.Cu")
		(net "M_C_CPU0_SB_DQ<12>")
	)
	(gr_poly
		(pts
			(xy 338.501228 -281.98445) (xy 338.501228 -281.936698) (xy 338.301076 -281.936698) (xy 338.301076 -281.98445)
			(xy 338.401152 -282.084272)
		)
		(stroke
			(width 0)
			(type solid)
		)
		(fill yes)
		(layer "In2.Cu")
		(net "M_C_CPU0_SB_DQS_DP<6>")
	)
	(gr_poly
		(pts
			(xy 338.501228 -280.76779) (xy 338.401152 -280.667968) (xy 338.301076 -280.76779) (xy 338.301076 -280.815542)
			(xy 338.501228 -280.815542)
		)
		(stroke
			(width 0)
			(type solid)
		)
		(fill yes)
		(layer "In2.Cu")
		(net "M_C_CPU0_SB_DQS_DP<1>")
	)
	(gr_poly
		(pts
			(xy 338.501228 -280.364184) (xy 338.501228 -280.319734) (xy 338.301076 -280.319734) (xy 338.301076 -280.364184)
			(xy 338.401152 -280.46426)
		)
		(stroke
			(width 0)
			(type solid)
		)
		(fill yes)
		(layer "In2.Cu")
		(net "M_C_CPU0_SB_DQ<11>")
	)
	(gr_poly
		(pts
			(xy 338.501228 -279.148032) (xy 338.401152 -279.047956) (xy 338.301076 -279.148032) (xy 338.301076 -279.192482)
			(xy 338.501228 -279.192482)
		)
		(stroke
			(width 0)
			(type solid)
		)
		(fill yes)
		(layer "In2.Cu")
		(net "M_C_CPU0_SB_DQ<8>")
	)
	(gr_poly
		(pts
			(xy 338.501228 -278.744172) (xy 338.501228 -278.699722) (xy 338.301076 -278.699722) (xy 338.301076 -278.744172)
			(xy 338.401152 -278.844248)
		)
		(stroke
			(width 0)
			(type solid)
		)
		(fill yes)
		(layer "In2.Cu")
		(net "M_C_CPU0_SB_DQ<7>")
	)
	(gr_poly
		(pts
			(xy 338.501228 -277.52802) (xy 338.401152 -277.427944) (xy 338.301076 -277.52802) (xy 338.301076 -277.57247)
			(xy 338.501228 -277.57247)
		)
		(stroke
			(width 0)
			(type solid)
		)
		(fill yes)
		(layer "In2.Cu")
		(net "M_C_CPU0_SB_DQ<4>")
	)
	(gr_poly
		(pts
			(xy 338.501228 -277.124414) (xy 338.501228 -277.076662) (xy 338.301076 -277.076662) (xy 338.301076 -277.124414)
			(xy 338.401152 -277.224236)
		)
		(stroke
			(width 0)
			(type solid)
		)
		(fill yes)
		(layer "In2.Cu")
		(net "M_C_CPU0_SB_DQS_DP<5>")
	)
	(gr_poly
		(pts
			(xy 338.501228 -275.907754) (xy 338.401152 -275.807932) (xy 338.301076 -275.907754) (xy 338.301076 -275.955506)
			(xy 338.501228 -275.955506)
		)
		(stroke
			(width 0)
			(type solid)
		)
		(fill yes)
		(layer "In2.Cu")
		(net "M_C_CPU0_SB_DQS_DP<0>")
	)
	(gr_poly
		(pts
			(xy 338.501228 -275.504148) (xy 338.501228 -275.459698) (xy 338.301076 -275.459698) (xy 338.301076 -275.504148)
			(xy 338.401152 -275.604224)
		)
		(stroke
			(width 0)
			(type solid)
		)
		(fill yes)
		(layer "In2.Cu")
		(net "M_C_CPU0_SB_DQ<3>")
	)
	(gr_poly
		(pts
			(xy 338.501228 -274.287996) (xy 338.401152 -274.18792) (xy 338.301076 -274.287996) (xy 338.301076 -274.332446)
			(xy 338.501228 -274.332446)
		)
		(stroke
			(width 0)
			(type solid)
		)
		(fill yes)
		(layer "In2.Cu")
		(net "M_C_CPU0_SB_DQ<0>")
	)
	(gr_poly
		(pts
			(xy 338.501228 -273.884136) (xy 338.501228 -273.839686) (xy 338.301076 -273.839686) (xy 338.301076 -273.884136)
			(xy 338.401152 -273.984212)
		)
		(stroke
			(width 0)
			(type solid)
		)
		(fill yes)
		(layer "In2.Cu")
		(net "M_C_CPU0_SB_CB<3>")
	)
	(gr_poly
		(pts
			(xy 338.501228 -272.667984) (xy 338.401152 -272.567908) (xy 338.301076 -272.667984) (xy 338.301076 -272.712434)
			(xy 338.501228 -272.712434)
		)
		(stroke
			(width 0)
			(type solid)
		)
		(fill yes)
		(layer "In2.Cu")
		(net "M_C_CPU0_SB_CB<0>")
	)
	(gr_poly
		(pts
			(xy 338.501228 -272.264378) (xy 338.501228 -272.216626) (xy 338.301076 -272.216626) (xy 338.301076 -272.264378)
			(xy 338.401152 -272.3642)
		)
		(stroke
			(width 0)
			(type solid)
		)
		(fill yes)
		(layer "In2.Cu")
		(net "M_C_CPU0_SB_DQS_DP<4>")
	)
	(gr_poly
		(pts
			(xy 338.501228 -271.047718) (xy 338.401152 -270.947896) (xy 338.301076 -271.047718) (xy 338.301076 -271.09547)
			(xy 338.501228 -271.09547)
		)
		(stroke
			(width 0)
			(type solid)
		)
		(fill yes)
		(layer "In2.Cu")
		(net "M_C_CPU0_SB_DQS_DP<9>")
	)
	(gr_poly
		(pts
			(xy 338.501228 -270.644112) (xy 338.501228 -270.599662) (xy 338.301076 -270.599662) (xy 338.301076 -270.644112)
			(xy 338.401152 -270.744188)
		)
		(stroke
			(width 0)
			(type solid)
		)
		(fill yes)
		(layer "In2.Cu")
		(net "M_C_CPU0_SB_CB<7>")
	)
	(gr_poly
		(pts
			(xy 338.501228 -269.42796) (xy 338.401152 -269.327884) (xy 338.301076 -269.42796) (xy 338.301076 -269.47241)
			(xy 338.501228 -269.47241)
		)
		(stroke
			(width 0)
			(type solid)
		)
		(fill yes)
		(layer "In2.Cu")
		(net "M_C_CPU0_SB_CB<4>")
	)
	(gr_poly
		(pts
			(xy 338.501228 -265.784076) (xy 338.501228 -265.739626) (xy 338.301076 -265.739626) (xy 338.301076 -265.784076)
			(xy 338.401152 -265.884152)
		)
		(stroke
			(width 0)
			(type solid)
		)
		(fill yes)
		(layer "In2.Cu")
		(net "M_C_CPU0_SB_CS_N<0>")
	)
	(gr_poly
		(pts
			(xy 338.501228 -264.567924) (xy 338.401152 -264.467848) (xy 338.301076 -264.567924) (xy 338.301076 -264.612374)
			(xy 338.501228 -264.612374)
		)
		(stroke
			(width 0)
			(type solid)
		)
		(fill yes)
		(layer "In2.Cu")
		(net "M_C_CPU0_SB_CA<6>")
	)
	(gr_poly
		(pts
			(xy 338.501228 -264.164064) (xy 338.501228 -264.119614) (xy 338.301076 -264.119614) (xy 338.301076 -264.164064)
			(xy 338.401152 -264.26414)
		)
		(stroke
			(width 0)
			(type solid)
		)
		(fill yes)
		(layer "In2.Cu")
		(net "M_C_CPU0_SB_CA<5>")
	)
	(gr_poly
		(pts
			(xy 338.501228 -262.947912) (xy 338.401152 -262.847836) (xy 338.301076 -262.947912) (xy 338.301076 -262.992362)
			(xy 338.501228 -262.992362)
		)
		(stroke
			(width 0)
			(type solid)
		)
		(fill yes)
		(layer "In2.Cu")
		(net "M_C_CPU0_SB_CA<2>")
	)
	(gr_poly
		(pts
			(xy 338.501228 -262.544052) (xy 338.501228 -262.499602) (xy 338.301076 -262.499602) (xy 338.301076 -262.544052)
			(xy 338.401152 -262.644128)
		)
		(stroke
			(width 0)
			(type solid)
		)
		(fill yes)
		(layer "In2.Cu")
		(net "M_C_CPU0_SB_CA<1>")
	)
	(gr_poly
		(pts
			(xy 338.671154 -256.025904) (xy 338.571078 -255.926082) (xy 338.471002 -256.025904) (xy 338.471002 -256.073656)
			(xy 338.671154 -256.073656)
		)
		(stroke
			(width 0)
			(type solid)
		)
		(fill yes)
		(layer "In2.Cu")
		(net "M_C_CPU0_CLK_DP<0>")
	)
	(gr_poly
		(pts
			(xy 338.671154 -255.622298) (xy 338.671154 -255.577848) (xy 338.471002 -255.577848) (xy 338.471002 -255.622298)
			(xy 338.571078 -255.722374)
		)
		(stroke
			(width 0)
			(type solid)
		)
		(fill yes)
		(layer "In2.Cu")
		(net "M_C_CPU0_SA_PAR")
	)
	(gr_poly
		(pts
			(xy 338.671154 -254.406146) (xy 338.571078 -254.30607) (xy 338.471002 -254.406146) (xy 338.471002 -254.450596)
			(xy 338.671154 -254.450596)
		)
		(stroke
			(width 0)
			(type solid)
		)
		(fill yes)
		(layer "In2.Cu")
		(net "M_C_CPU0_SA_CA<4>")
	)
	(gr_poly
		(pts
			(xy 338.671154 -254.002286) (xy 338.671154 -253.957836) (xy 338.471002 -253.957836) (xy 338.471002 -254.002286)
			(xy 338.571078 -254.102362)
		)
		(stroke
			(width 0)
			(type solid)
		)
		(fill yes)
		(layer "In2.Cu")
		(net "M_C_CPU0_SA_CA<3>")
	)
	(gr_poly
		(pts
			(xy 338.671154 -252.786134) (xy 338.571078 -252.686058) (xy 338.471002 -252.786134) (xy 338.471002 -252.830584)
			(xy 338.671154 -252.830584)
		)
		(stroke
			(width 0)
			(type solid)
		)
		(fill yes)
		(layer "In2.Cu")
		(net "M_C_CPU0_SA_CA<0>")
	)
	(gr_poly
		(pts
			(xy 338.671154 -252.382274) (xy 338.671154 -252.337824) (xy 338.471002 -252.337824) (xy 338.471002 -252.382274)
			(xy 338.571078 -252.48235)
		)
		(stroke
			(width 0)
			(type solid)
		)
		(fill yes)
		(layer "In2.Cu")
		(net "M_C_CPU0_SA_CS_N<1>")
	)
	(gr_poly
		(pts
			(xy 338.671154 -250.762262) (xy 338.671154 -250.717812) (xy 338.471002 -250.717812) (xy 338.471002 -250.762262)
			(xy 338.571078 -250.862338)
		)
		(stroke
			(width 0)
			(type solid)
		)
		(fill yes)
		(layer "In2.Cu")
		(net "M_C_CPU0_RESET_N")
	)
	(gr_poly
		(pts
			(xy 338.671154 -249.14225) (xy 338.671154 -249.0978) (xy 338.471002 -249.0978) (xy 338.471002 -249.14225)
			(xy 338.571078 -249.242326)
		)
		(stroke
			(width 0)
			(type solid)
		)
		(fill yes)
		(layer "In2.Cu")
		(net "M_C_CPU0_SA_CB<7>")
	)
	(gr_poly
		(pts
			(xy 338.671154 -247.926098) (xy 338.571078 -247.826022) (xy 338.471002 -247.926098) (xy 338.471002 -247.970548)
			(xy 338.671154 -247.970548)
		)
		(stroke
			(width 0)
			(type solid)
		)
		(fill yes)
		(layer "In2.Cu")
		(net "M_C_CPU0_SA_CB<4>")
	)
	(gr_poly
		(pts
			(xy 338.671154 -247.522492) (xy 338.671154 -247.47474) (xy 338.471002 -247.47474) (xy 338.471002 -247.522492)
			(xy 338.571078 -247.622314)
		)
		(stroke
			(width 0)
			(type solid)
		)
		(fill yes)
		(layer "In2.Cu")
		(net "M_C_CPU0_SA_DQS_DP<9>")
	)
	(gr_poly
		(pts
			(xy 338.671154 -246.305832) (xy 338.571078 -246.20601) (xy 338.471002 -246.305832) (xy 338.471002 -246.353584)
			(xy 338.671154 -246.353584)
		)
		(stroke
			(width 0)
			(type solid)
		)
		(fill yes)
		(layer "In2.Cu")
		(net "M_C_CPU0_SA_DQS_DP<4>")
	)
	(gr_poly
		(pts
			(xy 338.671154 -245.902226) (xy 338.671154 -245.857776) (xy 338.471002 -245.857776) (xy 338.471002 -245.902226)
			(xy 338.571078 -246.002302)
		)
		(stroke
			(width 0)
			(type solid)
		)
		(fill yes)
		(layer "In2.Cu")
		(net "M_C_CPU0_SA_CB<3>")
	)
	(gr_poly
		(pts
			(xy 338.671154 -244.686074) (xy 338.571078 -244.585998) (xy 338.471002 -244.686074) (xy 338.471002 -244.730524)
			(xy 338.671154 -244.730524)
		)
		(stroke
			(width 0)
			(type solid)
		)
		(fill yes)
		(layer "In2.Cu")
		(net "M_C_CPU0_SA_CB<0>")
	)
	(gr_poly
		(pts
			(xy 338.671154 -244.282214) (xy 338.671154 -244.237764) (xy 338.471002 -244.237764) (xy 338.471002 -244.282214)
			(xy 338.571078 -244.38229)
		)
		(stroke
			(width 0)
			(type solid)
		)
		(fill yes)
		(layer "In2.Cu")
		(net "M_C_CPU0_SA_DQ<31>")
	)
	(gr_poly
		(pts
			(xy 338.671154 -243.066062) (xy 338.571078 -242.965986) (xy 338.471002 -243.066062) (xy 338.471002 -243.110512)
			(xy 338.671154 -243.110512)
		)
		(stroke
			(width 0)
			(type solid)
		)
		(fill yes)
		(layer "In2.Cu")
		(net "M_C_CPU0_SA_DQ<28>")
	)
	(gr_poly
		(pts
			(xy 338.671154 -242.662456) (xy 338.671154 -242.614704) (xy 338.471002 -242.614704) (xy 338.471002 -242.662456)
			(xy 338.571078 -242.762278)
		)
		(stroke
			(width 0)
			(type solid)
		)
		(fill yes)
		(layer "In2.Cu")
		(net "M_C_CPU0_SA_DQS_DP<8>")
	)
	(gr_poly
		(pts
			(xy 338.671154 -241.445796) (xy 338.571078 -241.345974) (xy 338.471002 -241.445796) (xy 338.471002 -241.493548)
			(xy 338.671154 -241.493548)
		)
		(stroke
			(width 0)
			(type solid)
		)
		(fill yes)
		(layer "In2.Cu")
		(net "M_C_CPU0_SA_DQS_DP<3>")
	)
	(gr_poly
		(pts
			(xy 338.671154 -241.04219) (xy 338.671154 -240.99774) (xy 338.471002 -240.99774) (xy 338.471002 -241.04219)
			(xy 338.571078 -241.142266)
		)
		(stroke
			(width 0)
			(type solid)
		)
		(fill yes)
		(layer "In2.Cu")
		(net "M_C_CPU0_SA_DQ<27>")
	)
	(gr_poly
		(pts
			(xy 338.671154 -239.826038) (xy 338.571078 -239.725962) (xy 338.471002 -239.826038) (xy 338.471002 -239.870488)
			(xy 338.671154 -239.870488)
		)
		(stroke
			(width 0)
			(type solid)
		)
		(fill yes)
		(layer "In2.Cu")
		(net "M_C_CPU0_SA_DQ<24>")
	)
	(gr_poly
		(pts
			(xy 338.671154 -239.422178) (xy 338.671154 -239.377728) (xy 338.471002 -239.377728) (xy 338.471002 -239.422178)
			(xy 338.571078 -239.522254)
		)
		(stroke
			(width 0)
			(type solid)
		)
		(fill yes)
		(layer "In2.Cu")
		(net "M_C_CPU0_SA_DQ<23>")
	)
	(gr_poly
		(pts
			(xy 338.671154 -238.206026) (xy 338.571078 -238.10595) (xy 338.471002 -238.206026) (xy 338.471002 -238.250476)
			(xy 338.671154 -238.250476)
		)
		(stroke
			(width 0)
			(type solid)
		)
		(fill yes)
		(layer "In2.Cu")
		(net "M_C_CPU0_SA_DQ<20>")
	)
	(gr_poly
		(pts
			(xy 338.671154 -237.80242) (xy 338.671154 -237.754668) (xy 338.471002 -237.754668) (xy 338.471002 -237.80242)
			(xy 338.571078 -237.902242)
		)
		(stroke
			(width 0)
			(type solid)
		)
		(fill yes)
		(layer "In2.Cu")
		(net "M_C_CPU0_SA_DQS_DP<7>")
	)
	(gr_poly
		(pts
			(xy 338.671154 -236.58576) (xy 338.571078 -236.485938) (xy 338.471002 -236.58576) (xy 338.471002 -236.633512)
			(xy 338.671154 -236.633512)
		)
		(stroke
			(width 0)
			(type solid)
		)
		(fill yes)
		(layer "In2.Cu")
		(net "M_C_CPU0_SA_DQS_DP<2>")
	)
	(gr_poly
		(pts
			(xy 338.671154 -236.182154) (xy 338.671154 -236.137704) (xy 338.471002 -236.137704) (xy 338.471002 -236.182154)
			(xy 338.571078 -236.28223)
		)
		(stroke
			(width 0)
			(type solid)
		)
		(fill yes)
		(layer "In2.Cu")
		(net "M_C_CPU0_SA_DQ<19>")
	)
	(gr_poly
		(pts
			(xy 338.671154 -234.966002) (xy 338.571078 -234.865926) (xy 338.471002 -234.966002) (xy 338.471002 -235.010452)
			(xy 338.671154 -235.010452)
		)
		(stroke
			(width 0)
			(type solid)
		)
		(fill yes)
		(layer "In2.Cu")
		(net "M_C_CPU0_SA_DQ<16>")
	)
	(gr_poly
		(pts
			(xy 338.671154 -234.562142) (xy 338.671154 -234.517692) (xy 338.471002 -234.517692) (xy 338.471002 -234.562142)
			(xy 338.571078 -234.662218)
		)
		(stroke
			(width 0)
			(type solid)
		)
		(fill yes)
		(layer "In2.Cu")
		(net "M_C_CPU0_SA_DQ<15>")
	)
	(gr_poly
		(pts
			(xy 338.671154 -233.34599) (xy 338.571078 -233.245914) (xy 338.471002 -233.34599) (xy 338.471002 -233.39044)
			(xy 338.671154 -233.39044)
		)
		(stroke
			(width 0)
			(type solid)
		)
		(fill yes)
		(layer "In2.Cu")
		(net "M_C_CPU0_SA_DQ<12>")
	)
	(gr_poly
		(pts
			(xy 338.671154 -232.942384) (xy 338.671154 -232.894632) (xy 338.471002 -232.894632) (xy 338.471002 -232.942384)
			(xy 338.571078 -233.042206)
		)
		(stroke
			(width 0)
			(type solid)
		)
		(fill yes)
		(layer "In2.Cu")
		(net "M_C_CPU0_SA_DQS_DP<6>")
	)
	(gr_poly
		(pts
			(xy 338.671154 -231.725724) (xy 338.571078 -231.625902) (xy 338.471002 -231.725724) (xy 338.471002 -231.773476)
			(xy 338.671154 -231.773476)
		)
		(stroke
			(width 0)
			(type solid)
		)
		(fill yes)
		(layer "In2.Cu")
		(net "M_C_CPU0_SA_DQS_DP<1>")
	)
	(gr_poly
		(pts
			(xy 338.671154 -231.322372) (xy 338.671154 -231.277922) (xy 338.471002 -231.277922) (xy 338.471002 -231.322372)
			(xy 338.571078 -231.422448)
		)
		(stroke
			(width 0)
			(type solid)
		)
		(fill yes)
		(layer "In2.Cu")
		(net "M_C_CPU0_SA_DQ<11>")
	)
	(gr_poly
		(pts
			(xy 338.671154 -230.105966) (xy 338.571078 -230.006144) (xy 338.471002 -230.105966) (xy 338.471002 -230.150416)
			(xy 338.671154 -230.150416)
		)
		(stroke
			(width 0)
			(type solid)
		)
		(fill yes)
		(layer "In2.Cu")
		(net "M_C_CPU0_SA_DQ<8>")
	)
	(gr_poly
		(pts
			(xy 338.671154 -229.70236) (xy 338.671154 -229.65791) (xy 338.471002 -229.65791) (xy 338.471002 -229.70236)
			(xy 338.571078 -229.802436)
		)
		(stroke
			(width 0)
			(type solid)
		)
		(fill yes)
		(layer "In2.Cu")
		(net "M_C_CPU0_SA_DQ<7>")
	)
	(gr_poly
		(pts
			(xy 338.671154 -228.486208) (xy 338.571078 -228.386132) (xy 338.471002 -228.486208) (xy 338.471002 -228.530658)
			(xy 338.671154 -228.530658)
		)
		(stroke
			(width 0)
			(type solid)
		)
		(fill yes)
		(layer "In2.Cu")
		(net "M_C_CPU0_SA_DQ<4>")
	)
	(gr_poly
		(pts
			(xy 338.671154 -228.082602) (xy 338.671154 -228.03485) (xy 338.471002 -228.03485) (xy 338.471002 -228.082602)
			(xy 338.571078 -228.182424)
		)
		(stroke
			(width 0)
			(type solid)
		)
		(fill yes)
		(layer "In2.Cu")
		(net "M_C_CPU0_SA_DQS_DP<5>")
	)
	(gr_poly
		(pts
			(xy 338.671154 -226.865942) (xy 338.571078 -226.76612) (xy 338.471002 -226.865942) (xy 338.471002 -226.913694)
			(xy 338.671154 -226.913694)
		)
		(stroke
			(width 0)
			(type solid)
		)
		(fill yes)
		(layer "In2.Cu")
		(net "M_C_CPU0_SA_DQS_DP<0>")
	)
	(gr_poly
		(pts
			(xy 338.671154 -226.462336) (xy 338.671154 -226.417886) (xy 338.471002 -226.417886) (xy 338.471002 -226.462336)
			(xy 338.571078 -226.562412)
		)
		(stroke
			(width 0)
			(type solid)
		)
		(fill yes)
		(layer "In2.Cu")
		(net "M_C_CPU0_SA_DQ<3>")
	)
	(gr_poly
		(pts
			(xy 338.671154 -225.246184) (xy 338.571078 -225.146108) (xy 338.471002 -225.246184) (xy 338.471002 -225.290634)
			(xy 338.671154 -225.290634)
		)
		(stroke
			(width 0)
			(type solid)
		)
		(fill yes)
		(layer "In2.Cu")
		(net "M_C_CPU0_SA_DQ<0>")
	)
	(gr_poly
		(pts
			(xy 338.971128 -292.91788) (xy 338.871052 -292.817804) (xy 338.770976 -292.91788) (xy 338.770976 -292.96233)
			(xy 338.971128 -292.96233)
		)
		(stroke
			(width 0)
			(type solid)
		)
		(fill yes)
		(layer "In2.Cu")
		(net "M_C_CPU0_SB_DQ<29>")
	)
	(gr_poly
		(pts
			(xy 338.971128 -292.51402) (xy 338.971128 -292.46957) (xy 338.770976 -292.46957) (xy 338.770976 -292.51402)
			(xy 338.871052 -292.614096)
		)
		(stroke
			(width 0)
			(type solid)
		)
		(fill yes)
		(layer "In2.Cu")
		(net "M_C_CPU0_SB_DQ<30>")
	)
	(gr_poly
		(pts
			(xy 338.971128 -290.894262) (xy 338.971128 -290.84651) (xy 338.770976 -290.84651) (xy 338.770976 -290.894262)
			(xy 338.871052 -290.994084)
		)
		(stroke
			(width 0)
			(type solid)
		)
		(fill yes)
		(layer "In2.Cu")
		(net "M_C_CPU0_SB_DQS_DN<3>")
	)
	(gr_poly
		(pts
			(xy 338.971128 -289.677856) (xy 338.871052 -289.57778) (xy 338.770976 -289.677856) (xy 338.770976 -289.722306)
			(xy 338.971128 -289.722306)
		)
		(stroke
			(width 0)
			(type solid)
		)
		(fill yes)
		(layer "In2.Cu")
		(net "M_C_CPU0_SB_DQ<25>")
	)
	(gr_poly
		(pts
			(xy 338.971128 -289.273996) (xy 338.971128 -289.229546) (xy 338.770976 -289.229546) (xy 338.770976 -289.273996)
			(xy 338.871052 -289.374072)
		)
		(stroke
			(width 0)
			(type solid)
		)
		(fill yes)
		(layer "In2.Cu")
		(net "M_C_CPU0_SB_DQ<26>")
	)
	(gr_poly
		(pts
			(xy 338.971128 -288.057844) (xy 338.871052 -287.957768) (xy 338.770976 -288.057844) (xy 338.770976 -288.102294)
			(xy 338.971128 -288.102294)
		)
		(stroke
			(width 0)
			(type solid)
		)
		(fill yes)
		(layer "In2.Cu")
		(net "M_C_CPU0_SB_DQ<21>")
	)
	(gr_poly
		(pts
			(xy 338.971128 -287.654238) (xy 338.971128 -287.609788) (xy 338.770976 -287.609788) (xy 338.770976 -287.654238)
			(xy 338.871052 -287.75406)
		)
		(stroke
			(width 0)
			(type solid)
		)
		(fill yes)
		(layer "In2.Cu")
		(net "M_C_CPU0_SB_DQ<22>")
	)
	(gr_poly
		(pts
			(xy 338.971128 -286.437832) (xy 338.871052 -286.337756) (xy 338.770976 -286.437832) (xy 338.770976 -286.485584)
			(xy 338.971128 -286.485584)
		)
		(stroke
			(width 0)
			(type solid)
		)
		(fill yes)
		(layer "In2.Cu")
		(net "M_C_CPU0_SB_DQS_DN<7>")
	)
	(gr_poly
		(pts
			(xy 338.971128 -286.03448) (xy 338.971128 -285.986728) (xy 338.770976 -285.986728) (xy 338.770976 -286.03448)
			(xy 338.871052 -286.134302)
		)
		(stroke
			(width 0)
			(type solid)
		)
		(fill yes)
		(layer "In2.Cu")
		(net "M_C_CPU0_SB_DQS_DN<2>")
	)
	(gr_poly
		(pts
			(xy 338.971128 -284.818074) (xy 338.871052 -284.717998) (xy 338.770976 -284.818074) (xy 338.770976 -284.862524)
			(xy 338.971128 -284.862524)
		)
		(stroke
			(width 0)
			(type solid)
		)
		(fill yes)
		(layer "In2.Cu")
		(net "M_C_CPU0_SB_DQ<17>")
	)
	(gr_poly
		(pts
			(xy 338.971128 -284.414214) (xy 338.971128 -284.369764) (xy 338.770976 -284.369764) (xy 338.770976 -284.414214)
			(xy 338.871052 -284.51429)
		)
		(stroke
			(width 0)
			(type solid)
		)
		(fill yes)
		(layer "In2.Cu")
		(net "M_C_CPU0_SB_DQ<18>")
	)
	(gr_poly
		(pts
			(xy 338.971128 -283.198062) (xy 338.871052 -283.097986) (xy 338.770976 -283.198062) (xy 338.770976 -283.242512)
			(xy 338.971128 -283.242512)
		)
		(stroke
			(width 0)
			(type solid)
		)
		(fill yes)
		(layer "In2.Cu")
		(net "M_C_CPU0_SB_DQ<13>")
	)
	(gr_poly
		(pts
			(xy 338.971128 -282.794202) (xy 338.971128 -282.749752) (xy 338.770976 -282.749752) (xy 338.770976 -282.794202)
			(xy 338.871052 -282.894278)
		)
		(stroke
			(width 0)
			(type solid)
		)
		(fill yes)
		(layer "In2.Cu")
		(net "M_C_CPU0_SB_DQ<14>")
	)
	(gr_poly
		(pts
			(xy 338.971128 -281.577796) (xy 338.871052 -281.477974) (xy 338.770976 -281.577796) (xy 338.770976 -281.625548)
			(xy 338.971128 -281.625548)
		)
		(stroke
			(width 0)
			(type solid)
		)
		(fill yes)
		(layer "In2.Cu")
		(net "M_C_CPU0_SB_DQS_DN<6>")
	)
	(gr_poly
		(pts
			(xy 338.971128 -281.174444) (xy 338.971128 -281.126692) (xy 338.770976 -281.126692) (xy 338.770976 -281.174444)
			(xy 338.871052 -281.274266)
		)
		(stroke
			(width 0)
			(type solid)
		)
		(fill yes)
		(layer "In2.Cu")
		(net "M_C_CPU0_SB_DQS_DN<1>")
	)
	(gr_poly
		(pts
			(xy 338.971128 -279.958038) (xy 338.871052 -279.857962) (xy 338.770976 -279.958038) (xy 338.770976 -280.002488)
			(xy 338.971128 -280.002488)
		)
		(stroke
			(width 0)
			(type solid)
		)
		(fill yes)
		(layer "In2.Cu")
		(net "M_C_CPU0_SB_DQ<9>")
	)
	(gr_poly
		(pts
			(xy 338.971128 -279.554178) (xy 338.971128 -279.509728) (xy 338.770976 -279.509728) (xy 338.770976 -279.554178)
			(xy 338.871052 -279.654254)
		)
		(stroke
			(width 0)
			(type solid)
		)
		(fill yes)
		(layer "In2.Cu")
		(net "M_C_CPU0_SB_DQ<10>")
	)
	(gr_poly
		(pts
			(xy 338.971128 -278.338026) (xy 338.871052 -278.23795) (xy 338.770976 -278.338026) (xy 338.770976 -278.382476)
			(xy 338.971128 -278.382476)
		)
		(stroke
			(width 0)
			(type solid)
		)
		(fill yes)
		(layer "In2.Cu")
		(net "M_C_CPU0_SB_DQ<5>")
	)
	(gr_poly
		(pts
			(xy 338.971128 -277.934166) (xy 338.971128 -277.889716) (xy 338.770976 -277.889716) (xy 338.770976 -277.934166)
			(xy 338.871052 -278.034242)
		)
		(stroke
			(width 0)
			(type solid)
		)
		(fill yes)
		(layer "In2.Cu")
		(net "M_C_CPU0_SB_DQ<6>")
	)
	(gr_poly
		(pts
			(xy 338.971128 -276.71776) (xy 338.871052 -276.617938) (xy 338.770976 -276.71776) (xy 338.770976 -276.765512)
			(xy 338.971128 -276.765512)
		)
		(stroke
			(width 0)
			(type solid)
		)
		(fill yes)
		(layer "In2.Cu")
		(net "M_C_CPU0_SB_DQS_DN<5>")
	)
	(gr_poly
		(pts
			(xy 338.971128 -276.314408) (xy 338.971128 -276.266656) (xy 338.770976 -276.266656) (xy 338.770976 -276.314408)
			(xy 338.871052 -276.41423)
		)
		(stroke
			(width 0)
			(type solid)
		)
		(fill yes)
		(layer "In2.Cu")
		(net "M_C_CPU0_SB_DQS_DN<0>")
	)
	(gr_poly
		(pts
			(xy 338.971128 -275.098002) (xy 338.871052 -274.997926) (xy 338.770976 -275.098002) (xy 338.770976 -275.142452)
			(xy 338.971128 -275.142452)
		)
		(stroke
			(width 0)
			(type solid)
		)
		(fill yes)
		(layer "In2.Cu")
		(net "M_C_CPU0_SB_DQ<1>")
	)
	(gr_poly
		(pts
			(xy 338.971128 -274.694142) (xy 338.971128 -274.649692) (xy 338.770976 -274.649692) (xy 338.770976 -274.694142)
			(xy 338.871052 -274.794218)
		)
		(stroke
			(width 0)
			(type solid)
		)
		(fill yes)
		(layer "In2.Cu")
		(net "M_C_CPU0_SB_DQ<2>")
	)
	(gr_poly
		(pts
			(xy 338.971128 -273.47799) (xy 338.871052 -273.377914) (xy 338.770976 -273.47799) (xy 338.770976 -273.52244)
			(xy 338.971128 -273.52244)
		)
		(stroke
			(width 0)
			(type solid)
		)
		(fill yes)
		(layer "In2.Cu")
		(net "M_C_CPU0_SB_CB<1>")
	)
	(gr_poly
		(pts
			(xy 338.971128 -273.07413) (xy 338.971128 -273.02968) (xy 338.770976 -273.02968) (xy 338.770976 -273.07413)
			(xy 338.871052 -273.174206)
		)
		(stroke
			(width 0)
			(type solid)
		)
		(fill yes)
		(layer "In2.Cu")
		(net "M_C_CPU0_SB_CB<2>")
	)
	(gr_poly
		(pts
			(xy 338.971128 -271.857724) (xy 338.871052 -271.757902) (xy 338.770976 -271.857724) (xy 338.770976 -271.905476)
			(xy 338.971128 -271.905476)
		)
		(stroke
			(width 0)
			(type solid)
		)
		(fill yes)
		(layer "In2.Cu")
		(net "M_C_CPU0_SB_DQS_DN<4>")
	)
	(gr_poly
		(pts
			(xy 338.971128 -271.454372) (xy 338.971128 -271.40662) (xy 338.770976 -271.40662) (xy 338.770976 -271.454372)
			(xy 338.871052 -271.554194)
		)
		(stroke
			(width 0)
			(type solid)
		)
		(fill yes)
		(layer "In2.Cu")
		(net "M_C_CPU0_SB_DQS_DN<9>")
	)
	(gr_poly
		(pts
			(xy 338.971128 -270.237966) (xy 338.871052 -270.13789) (xy 338.770976 -270.237966) (xy 338.770976 -270.282416)
			(xy 338.971128 -270.282416)
		)
		(stroke
			(width 0)
			(type solid)
		)
		(fill yes)
		(layer "In2.Cu")
		(net "M_C_CPU0_SB_CB<5>")
	)
	(gr_poly
		(pts
			(xy 338.971128 -269.834106) (xy 338.971128 -269.789656) (xy 338.770976 -269.789656) (xy 338.770976 -269.834106)
			(xy 338.871052 -269.934182)
		)
		(stroke
			(width 0)
			(type solid)
		)
		(fill yes)
		(layer "In2.Cu")
		(net "M_C_CPU0_SB_CB<6>")
	)
	(gr_poly
		(pts
			(xy 338.971128 -266.594082) (xy 338.971128 -266.549632) (xy 338.770976 -266.549632) (xy 338.770976 -266.594082)
			(xy 338.871052 -266.694158)
		)
		(stroke
			(width 0)
			(type solid)
		)
		(fill yes)
		(layer "In2.Cu")
		(net "M_C_CPU0_SB_CS_N<1>")
	)
	(gr_poly
		(pts
			(xy 338.971128 -264.97407) (xy 338.971128 -264.92962) (xy 338.770976 -264.92962) (xy 338.770976 -264.97407)
			(xy 338.871052 -265.074146)
		)
		(stroke
			(width 0)
			(type solid)
		)
		(fill yes)
		(layer "In2.Cu")
		(net "M_C_CPU0_SB_PAR")
	)
	(gr_poly
		(pts
			(xy 338.971128 -263.757918) (xy 338.871052 -263.657842) (xy 338.770976 -263.757918) (xy 338.770976 -263.802368)
			(xy 338.971128 -263.802368)
		)
		(stroke
			(width 0)
			(type solid)
		)
		(fill yes)
		(layer "In2.Cu")
		(net "M_C_CPU0_SB_CA<4>")
	)
	(gr_poly
		(pts
			(xy 338.971128 -263.354058) (xy 338.971128 -263.309608) (xy 338.770976 -263.309608) (xy 338.770976 -263.354058)
			(xy 338.871052 -263.454134)
		)
		(stroke
			(width 0)
			(type solid)
		)
		(fill yes)
		(layer "In2.Cu")
		(net "M_C_CPU0_SB_CA<3>")
	)
	(gr_poly
		(pts
			(xy 338.971128 -262.137906) (xy 338.871052 -262.03783) (xy 338.770976 -262.137906) (xy 338.770976 -262.182356)
			(xy 338.971128 -262.182356)
		)
		(stroke
			(width 0)
			(type solid)
		)
		(fill yes)
		(layer "In2.Cu")
		(net "M_C_CPU0_SB_CA<0>")
	)
	(gr_poly
		(pts
			(xy 338.977224 -266.991592) (xy 338.877402 -266.891516) (xy 338.777326 -266.991592) (xy 338.777326 -267.036042)
			(xy 338.977224 -267.036042)
		)
		(stroke
			(width 0)
			(type solid)
		)
		(fill yes)
		(layer "In2.Cu")
		(net "M_C_CPU0_SA_RSP<0>")
	)
	(gr_poly
		(pts
			(xy 338.978494 -291.297614) (xy 338.878418 -291.197792) (xy 338.778342 -291.297614) (xy 338.778342 -291.345366)
			(xy 338.978494 -291.345366)
		)
		(stroke
			(width 0)
			(type solid)
		)
		(fill yes)
		(layer "In2.Cu")
		(net "M_C_CPU0_SB_DQS_DN<8>")
	)
	(gr_poly
		(pts
			(xy 339.1408 -246.712232) (xy 339.1408 -246.664734) (xy 338.940902 -246.664734) (xy 338.940902 -246.712232)
			(xy 339.040724 -246.812308)
		)
		(stroke
			(width 0)
			(type solid)
		)
		(fill yes)
		(layer "In2.Cu")
		(net "M_C_CPU0_SA_DQS_DN<4>")
	)
	(gr_poly
		(pts
			(xy 339.141054 -256.432558) (xy 339.141054 -256.384806) (xy 338.940902 -256.384806) (xy 338.940902 -256.432558)
			(xy 339.040978 -256.53238)
		)
		(stroke
			(width 0)
			(type solid)
		)
		(fill yes)
		(layer "In2.Cu")
		(net "M_C_CPU0_CLK_DN<0>")
	)
	(gr_poly
		(pts
			(xy 339.141054 -255.216152) (xy 339.040978 -255.116076) (xy 338.940902 -255.216152) (xy 338.940902 -255.260602)
			(xy 339.141054 -255.260602)
		)
		(stroke
			(width 0)
			(type solid)
		)
		(fill yes)
		(layer "In2.Cu")
		(net "M_C_CPU0_SA_CA<6>")
	)
	(gr_poly
		(pts
			(xy 339.141054 -254.812292) (xy 339.141054 -254.767842) (xy 338.940902 -254.767842) (xy 338.940902 -254.812292)
			(xy 339.040978 -254.912368)
		)
		(stroke
			(width 0)
			(type solid)
		)
		(fill yes)
		(layer "In2.Cu")
		(net "M_C_CPU0_SA_CA<5>")
	)
	(gr_poly
		(pts
			(xy 339.141054 -253.59614) (xy 339.040978 -253.496064) (xy 338.940902 -253.59614) (xy 338.940902 -253.64059)
			(xy 339.141054 -253.64059)
		)
		(stroke
			(width 0)
			(type solid)
		)
		(fill yes)
		(layer "In2.Cu")
		(net "M_C_CPU0_SA_CA<2>")
	)
	(gr_poly
		(pts
			(xy 339.141054 -253.19228) (xy 339.141054 -253.14783) (xy 338.940902 -253.14783) (xy 338.940902 -253.19228)
			(xy 339.040978 -253.292356)
		)
		(stroke
			(width 0)
			(type solid)
		)
		(fill yes)
		(layer "In2.Cu")
		(net "M_C_CPU0_SA_CA<1>")
	)
	(gr_poly
		(pts
			(xy 339.141054 -248.736104) (xy 339.040978 -248.636028) (xy 338.940902 -248.736104) (xy 338.940902 -248.780554)
			(xy 339.141054 -248.780554)
		)
		(stroke
			(width 0)
			(type solid)
		)
		(fill yes)
		(layer "In2.Cu")
		(net "M_C_CPU0_SA_CB<5>")
	)
	(gr_poly
		(pts
			(xy 339.141054 -248.332244) (xy 339.141054 -248.287794) (xy 338.940902 -248.287794) (xy 338.940902 -248.332244)
			(xy 339.040978 -248.43232)
		)
		(stroke
			(width 0)
			(type solid)
		)
		(fill yes)
		(layer "In2.Cu")
		(net "M_C_CPU0_SA_CB<6>")
	)
	(gr_poly
		(pts
			(xy 339.141054 -247.115838) (xy 339.040978 -247.016016) (xy 338.940902 -247.115838) (xy 338.940902 -247.16359)
			(xy 339.141054 -247.16359)
		)
		(stroke
			(width 0)
			(type solid)
		)
		(fill yes)
		(layer "In2.Cu")
		(net "M_C_CPU0_SA_DQS_DN<9>")
	)
	(gr_poly
		(pts
			(xy 339.141054 -245.49608) (xy 339.040978 -245.396004) (xy 338.940902 -245.49608) (xy 338.940902 -245.54053)
			(xy 339.141054 -245.54053)
		)
		(stroke
			(width 0)
			(type solid)
		)
		(fill yes)
		(layer "In2.Cu")
		(net "M_C_CPU0_SA_CB<1>")
	)
	(gr_poly
		(pts
			(xy 339.141054 -245.09222) (xy 339.141054 -245.04777) (xy 338.940902 -245.04777) (xy 338.940902 -245.09222)
			(xy 339.040978 -245.192296)
		)
		(stroke
			(width 0)
			(type solid)
		)
		(fill yes)
		(layer "In2.Cu")
		(net "M_C_CPU0_SA_CB<2>")
	)
	(gr_poly
		(pts
			(xy 339.141054 -243.876068) (xy 339.040978 -243.775992) (xy 338.940902 -243.876068) (xy 338.940902 -243.920518)
			(xy 339.141054 -243.920518)
		)
		(stroke
			(width 0)
			(type solid)
		)
		(fill yes)
		(layer "In2.Cu")
		(net "M_C_CPU0_SA_DQ<29>")
	)
	(gr_poly
		(pts
			(xy 339.141054 -243.472208) (xy 339.141054 -243.427758) (xy 338.940902 -243.427758) (xy 338.940902 -243.472208)
			(xy 339.040978 -243.572284)
		)
		(stroke
			(width 0)
			(type solid)
		)
		(fill yes)
		(layer "In2.Cu")
		(net "M_C_CPU0_SA_DQ<30>")
	)
	(gr_poly
		(pts
			(xy 339.141054 -242.255802) (xy 339.040978 -242.15598) (xy 338.940902 -242.255802) (xy 338.940902 -242.303554)
			(xy 339.141054 -242.303554)
		)
		(stroke
			(width 0)
			(type solid)
		)
		(fill yes)
		(layer "In2.Cu")
		(net "M_C_CPU0_SA_DQS_DN<8>")
	)
	(gr_poly
		(pts
			(xy 339.141054 -241.85245) (xy 339.141054 -241.804698) (xy 338.940902 -241.804698) (xy 338.940902 -241.85245)
			(xy 339.040978 -241.952272)
		)
		(stroke
			(width 0)
			(type solid)
		)
		(fill yes)
		(layer "In2.Cu")
		(net "M_C_CPU0_SA_DQS_DN<3>")
	)
	(gr_poly
		(pts
			(xy 339.141054 -240.636044) (xy 339.040978 -240.535968) (xy 338.940902 -240.636044) (xy 338.940902 -240.680494)
			(xy 339.141054 -240.680494)
		)
		(stroke
			(width 0)
			(type solid)
		)
		(fill yes)
		(layer "In2.Cu")
		(net "M_C_CPU0_SA_DQ<25>")
	)
	(gr_poly
		(pts
			(xy 339.141054 -240.232184) (xy 339.141054 -240.187734) (xy 338.940902 -240.187734) (xy 338.940902 -240.232184)
			(xy 339.040978 -240.33226)
		)
		(stroke
			(width 0)
			(type solid)
		)
		(fill yes)
		(layer "In2.Cu")
		(net "M_C_CPU0_SA_DQ<26>")
	)
	(gr_poly
		(pts
			(xy 339.141054 -239.016032) (xy 339.040978 -238.915956) (xy 338.940902 -239.016032) (xy 338.940902 -239.060482)
			(xy 339.141054 -239.060482)
		)
		(stroke
			(width 0)
			(type solid)
		)
		(fill yes)
		(layer "In2.Cu")
		(net "M_C_CPU0_SA_DQ<21>")
	)
	(gr_poly
		(pts
			(xy 339.141054 -238.612172) (xy 339.141054 -238.567722) (xy 338.940902 -238.567722) (xy 338.940902 -238.612172)
			(xy 339.040978 -238.712248)
		)
		(stroke
			(width 0)
			(type solid)
		)
		(fill yes)
		(layer "In2.Cu")
		(net "M_C_CPU0_SA_DQ<22>")
	)
	(gr_poly
		(pts
			(xy 339.141054 -237.395766) (xy 339.040978 -237.295944) (xy 338.940902 -237.395766) (xy 338.940902 -237.443518)
			(xy 339.141054 -237.443518)
		)
		(stroke
			(width 0)
			(type solid)
		)
		(fill yes)
		(layer "In2.Cu")
		(net "M_C_CPU0_SA_DQS_DN<7>")
	)
	(gr_poly
		(pts
			(xy 339.141054 -236.992414) (xy 339.141054 -236.944662) (xy 338.940902 -236.944662) (xy 338.940902 -236.992414)
			(xy 339.040978 -237.092236)
		)
		(stroke
			(width 0)
			(type solid)
		)
		(fill yes)
		(layer "In2.Cu")
		(net "M_C_CPU0_SA_DQS_DN<2>")
	)
	(gr_poly
		(pts
			(xy 339.141054 -235.776008) (xy 339.040978 -235.675932) (xy 338.940902 -235.776008) (xy 338.940902 -235.820458)
			(xy 339.141054 -235.820458)
		)
		(stroke
			(width 0)
			(type solid)
		)
		(fill yes)
		(layer "In2.Cu")
		(net "M_C_CPU0_SA_DQ<17>")
	)
	(gr_poly
		(pts
			(xy 339.141054 -235.372148) (xy 339.141054 -235.327698) (xy 338.940902 -235.327698) (xy 338.940902 -235.372148)
			(xy 339.040978 -235.472224)
		)
		(stroke
			(width 0)
			(type solid)
		)
		(fill yes)
		(layer "In2.Cu")
		(net "M_C_CPU0_SA_DQ<18>")
	)
	(gr_poly
		(pts
			(xy 339.141054 -234.155996) (xy 339.040978 -234.05592) (xy 338.940902 -234.155996) (xy 338.940902 -234.200446)
			(xy 339.141054 -234.200446)
		)
		(stroke
			(width 0)
			(type solid)
		)
		(fill yes)
		(layer "In2.Cu")
		(net "M_C_CPU0_SA_DQ<13>")
	)
	(gr_poly
		(pts
			(xy 339.141054 -233.752136) (xy 339.141054 -233.707686) (xy 338.940902 -233.707686) (xy 338.940902 -233.752136)
			(xy 339.040978 -233.852212)
		)
		(stroke
			(width 0)
			(type solid)
		)
		(fill yes)
		(layer "In2.Cu")
		(net "M_C_CPU0_SA_DQ<14>")
	)
	(gr_poly
		(pts
			(xy 339.141054 -232.53573) (xy 339.040978 -232.435908) (xy 338.940902 -232.53573) (xy 338.940902 -232.583482)
			(xy 339.141054 -232.583482)
		)
		(stroke
			(width 0)
			(type solid)
		)
		(fill yes)
		(layer "In2.Cu")
		(net "M_C_CPU0_SA_DQS_DN<6>")
	)
	(gr_poly
		(pts
			(xy 339.141054 -232.132378) (xy 339.141054 -232.084626) (xy 338.940902 -232.084626) (xy 338.940902 -232.132378)
			(xy 339.040978 -232.2322)
		)
		(stroke
			(width 0)
			(type solid)
		)
		(fill yes)
		(layer "In2.Cu")
		(net "M_C_CPU0_SA_DQS_DN<1>")
	)
	(gr_poly
		(pts
			(xy 339.141054 -230.915972) (xy 339.040978 -230.815896) (xy 338.940902 -230.915972) (xy 338.940902 -230.960422)
			(xy 339.141054 -230.960422)
		)
		(stroke
			(width 0)
			(type solid)
		)
		(fill yes)
		(layer "In2.Cu")
		(net "M_C_CPU0_SA_DQ<9>")
	)
	(gr_poly
		(pts
			(xy 339.141054 -230.512366) (xy 339.141054 -230.467916) (xy 338.940902 -230.467916) (xy 338.940902 -230.512366)
			(xy 339.040978 -230.612188)
		)
		(stroke
			(width 0)
			(type solid)
		)
		(fill yes)
		(layer "In2.Cu")
		(net "M_C_CPU0_SA_DQ<10>")
	)
	(gr_poly
		(pts
			(xy 339.141054 -229.29596) (xy 339.040978 -229.195884) (xy 338.940902 -229.29596) (xy 338.940902 -229.34041)
			(xy 339.141054 -229.34041)
		)
		(stroke
			(width 0)
			(type solid)
		)
		(fill yes)
		(layer "In2.Cu")
		(net "M_C_CPU0_SA_DQ<5>")
	)
	(gr_poly
		(pts
			(xy 339.141054 -228.892354) (xy 339.141054 -228.847904) (xy 338.940902 -228.847904) (xy 338.940902 -228.892354)
			(xy 339.040978 -228.99243)
		)
		(stroke
			(width 0)
			(type solid)
		)
		(fill yes)
		(layer "In2.Cu")
		(net "M_C_CPU0_SA_DQ<6>")
	)
	(gr_poly
		(pts
			(xy 339.141054 -227.675948) (xy 339.040978 -227.576126) (xy 338.940902 -227.675948) (xy 338.940902 -227.7237)
			(xy 339.141054 -227.7237)
		)
		(stroke
			(width 0)
			(type solid)
		)
		(fill yes)
		(layer "In2.Cu")
		(net "M_C_CPU0_SA_DQS_DN<5>")
	)
	(gr_poly
		(pts
			(xy 339.141054 -227.272596) (xy 339.141054 -227.224844) (xy 338.940902 -227.224844) (xy 338.940902 -227.272596)
			(xy 339.040978 -227.372418)
		)
		(stroke
			(width 0)
			(type solid)
		)
		(fill yes)
		(layer "In2.Cu")
		(net "M_C_CPU0_SA_DQS_DN<0>")
	)
	(gr_poly
		(pts
			(xy 339.141054 -226.05619) (xy 339.040978 -225.956114) (xy 338.940902 -226.05619) (xy 338.940902 -226.10064)
			(xy 339.141054 -226.10064)
		)
		(stroke
			(width 0)
			(type solid)
		)
		(fill yes)
		(layer "In2.Cu")
		(net "M_C_CPU0_SA_DQ<1>")
	)
	(gr_poly
		(pts
			(xy 339.141054 -225.65233) (xy 339.141054 -225.60788) (xy 338.940902 -225.60788) (xy 338.940902 -225.65233)
			(xy 339.040978 -225.752406)
		)
		(stroke
			(width 0)
			(type solid)
		)
		(fill yes)
		(layer "In2.Cu")
		(net "M_C_CPU0_SA_DQ<2>")
	)
	(gr_poly
		(pts
			(xy 339.141308 -251.572268) (xy 339.141308 -251.527818) (xy 338.941156 -251.527818) (xy 338.941156 -251.572268)
			(xy 339.041232 -251.672344)
		)
		(stroke
			(width 0)
			(type solid)
		)
		(fill yes)
		(layer "In2.Cu")
		(net "M_C_CPU0_SA_CS_N<0>")
	)
	(gr_poly
		(pts
			(xy 339.141308 -250.356116) (xy 339.041232 -250.25604) (xy 338.941156 -250.356116) (xy 338.941156 -250.400566)
			(xy 339.141308 -250.400566)
		)
		(stroke
			(width 0)
			(type solid)
		)
		(fill yes)
		(layer "In2.Cu")
		(net "M_C_CPU0_ALERT_R_N")
	)
	(gr_poly
		(pts
			(xy 339.434932 -267.801598) (xy 339.334856 -267.701522) (xy 339.235034 -267.801598) (xy 339.235034 -267.846048)
			(xy 339.434932 -267.846048)
		)
		(stroke
			(width 0)
			(type solid)
		)
		(fill yes)
		(layer "In2.Cu")
		(net "M_C_CPU0_SB_RSP<0>")
	)
	(gr_poly
		(pts
			(xy 339.441028 -291.704268) (xy 339.441028 -291.656516) (xy 339.240876 -291.656516) (xy 339.240876 -291.704268)
			(xy 339.340952 -291.80409)
		)
		(stroke
			(width 0)
			(type solid)
		)
		(fill yes)
		(layer "In2.Cu")
		(net "M_C_CPU0_SB_DQS_DP<8>")
	)
	(gr_poly
		(pts
			(xy 339.441282 -293.324026) (xy 339.441282 -293.279576) (xy 339.24113 -293.279576) (xy 339.24113 -293.324026)
			(xy 339.341206 -293.424102)
		)
		(stroke
			(width 0)
			(type solid)
		)
		(fill yes)
		(layer "In2.Cu")
		(net "M_C_CPU0_SB_DQ<31>")
	)
	(gr_poly
		(pts
			(xy 339.441282 -292.107874) (xy 339.341206 -292.007798) (xy 339.24113 -292.107874) (xy 339.24113 -292.152324)
			(xy 339.441282 -292.152324)
		)
		(stroke
			(width 0)
			(type solid)
		)
		(fill yes)
		(layer "In2.Cu")
		(net "M_C_CPU0_SB_DQ<28>")
	)
	(gr_poly
		(pts
			(xy 339.441282 -290.487608) (xy 339.341206 -290.387786) (xy 339.24113 -290.487608) (xy 339.24113 -290.53536)
			(xy 339.441282 -290.53536)
		)
		(stroke
			(width 0)
			(type solid)
		)
		(fill yes)
		(layer "In2.Cu")
		(net "M_C_CPU0_SB_DQS_DP<3>")
	)
	(gr_poly
		(pts
			(xy 339.441282 -290.084002) (xy 339.441282 -290.039552) (xy 339.24113 -290.039552) (xy 339.24113 -290.084002)
			(xy 339.341206 -290.184078)
		)
		(stroke
			(width 0)
			(type solid)
		)
		(fill yes)
		(layer "In2.Cu")
		(net "M_C_CPU0_SB_DQ<27>")
	)
	(gr_poly
		(pts
			(xy 339.441282 -288.86785) (xy 339.341206 -288.767774) (xy 339.24113 -288.86785) (xy 339.24113 -288.9123)
			(xy 339.441282 -288.9123)
		)
		(stroke
			(width 0)
			(type solid)
		)
		(fill yes)
		(layer "In2.Cu")
		(net "M_C_CPU0_SB_DQ<24>")
	)
	(gr_poly
		(pts
			(xy 339.441282 -288.464244) (xy 339.441282 -288.419794) (xy 339.24113 -288.419794) (xy 339.24113 -288.464244)
			(xy 339.341206 -288.56432)
		)
		(stroke
			(width 0)
			(type solid)
		)
		(fill yes)
		(layer "In2.Cu")
		(net "M_C_CPU0_SB_DQ<23>")
	)
	(gr_poly
		(pts
			(xy 339.441282 -287.247838) (xy 339.341206 -287.148016) (xy 339.24113 -287.247838) (xy 339.24113 -287.292288)
			(xy 339.441282 -287.292288)
		)
		(stroke
			(width 0)
			(type solid)
		)
		(fill yes)
		(layer "In2.Cu")
		(net "M_C_CPU0_SB_DQ<20>")
	)
	(gr_poly
		(pts
			(xy 339.441282 -286.844232) (xy 339.441282 -286.79648) (xy 339.24113 -286.79648) (xy 339.24113 -286.844232)
			(xy 339.341206 -286.944308)
		)
		(stroke
			(width 0)
			(type solid)
		)
		(fill yes)
		(layer "In2.Cu")
		(net "M_C_CPU0_SB_DQS_DP<7>")
	)
	(gr_poly
		(pts
			(xy 339.441282 -285.627826) (xy 339.341206 -285.528004) (xy 339.24113 -285.627826) (xy 339.24113 -285.675578)
			(xy 339.441282 -285.675578)
		)
		(stroke
			(width 0)
			(type solid)
		)
		(fill yes)
		(layer "In2.Cu")
		(net "M_C_CPU0_SB_DQS_DP<2>")
	)
	(gr_poly
		(pts
			(xy 339.441282 -285.22422) (xy 339.441282 -285.17977) (xy 339.24113 -285.17977) (xy 339.24113 -285.22422)
			(xy 339.341206 -285.324296)
		)
		(stroke
			(width 0)
			(type solid)
		)
		(fill yes)
		(layer "In2.Cu")
		(net "M_C_CPU0_SB_DQ<19>")
	)
	(gr_poly
		(pts
			(xy 339.441282 -284.008068) (xy 339.341206 -283.907992) (xy 339.24113 -284.008068) (xy 339.24113 -284.052518)
			(xy 339.441282 -284.052518)
		)
		(stroke
			(width 0)
			(type solid)
		)
		(fill yes)
		(layer "In2.Cu")
		(net "M_C_CPU0_SB_DQ<16>")
	)
	(gr_poly
		(pts
			(xy 339.441282 -283.604208) (xy 339.441282 -283.559758) (xy 339.24113 -283.559758) (xy 339.24113 -283.604208)
			(xy 339.341206 -283.704284)
		)
		(stroke
			(width 0)
			(type solid)
		)
		(fill yes)
		(layer "In2.Cu")
		(net "M_C_CPU0_SB_DQ<15>")
	)
	(gr_poly
		(pts
			(xy 339.441282 -282.388056) (xy 339.341206 -282.28798) (xy 339.24113 -282.388056) (xy 339.24113 -282.432506)
			(xy 339.441282 -282.432506)
		)
		(stroke
			(width 0)
			(type solid)
		)
		(fill yes)
		(layer "In2.Cu")
		(net "M_C_CPU0_SB_DQ<12>")
	)
	(gr_poly
		(pts
			(xy 339.441282 -281.98445) (xy 339.441282 -281.936698) (xy 339.24113 -281.936698) (xy 339.24113 -281.98445)
			(xy 339.341206 -282.084272)
		)
		(stroke
			(width 0)
			(type solid)
		)
		(fill yes)
		(layer "In2.Cu")
		(net "M_C_CPU0_SB_DQS_DP<6>")
	)
	(gr_poly
		(pts
			(xy 339.441282 -280.76779) (xy 339.341206 -280.667968) (xy 339.24113 -280.76779) (xy 339.24113 -280.815542)
			(xy 339.441282 -280.815542)
		)
		(stroke
			(width 0)
			(type solid)
		)
		(fill yes)
		(layer "In2.Cu")
		(net "M_C_CPU0_SB_DQS_DP<1>")
	)
	(gr_poly
		(pts
			(xy 339.441282 -280.364184) (xy 339.441282 -280.319734) (xy 339.24113 -280.319734) (xy 339.24113 -280.364184)
			(xy 339.341206 -280.46426)
		)
		(stroke
			(width 0)
			(type solid)
		)
		(fill yes)
		(layer "In2.Cu")
		(net "M_C_CPU0_SB_DQ<11>")
	)
	(gr_poly
		(pts
			(xy 339.441282 -279.148032) (xy 339.341206 -279.047956) (xy 339.24113 -279.148032) (xy 339.24113 -279.192482)
			(xy 339.441282 -279.192482)
		)
		(stroke
			(width 0)
			(type solid)
		)
		(fill yes)
		(layer "In2.Cu")
		(net "M_C_CPU0_SB_DQ<8>")
	)
	(gr_poly
		(pts
			(xy 339.441282 -278.744172) (xy 339.441282 -278.699722) (xy 339.24113 -278.699722) (xy 339.24113 -278.744172)
			(xy 339.341206 -278.844248)
		)
		(stroke
			(width 0)
			(type solid)
		)
		(fill yes)
		(layer "In2.Cu")
		(net "M_C_CPU0_SB_DQ<7>")
	)
	(gr_poly
		(pts
			(xy 339.441282 -277.52802) (xy 339.341206 -277.427944) (xy 339.24113 -277.52802) (xy 339.24113 -277.57247)
			(xy 339.441282 -277.57247)
		)
		(stroke
			(width 0)
			(type solid)
		)
		(fill yes)
		(layer "In2.Cu")
		(net "M_C_CPU0_SB_DQ<4>")
	)
	(gr_poly
		(pts
			(xy 339.441282 -277.124414) (xy 339.441282 -277.076662) (xy 339.24113 -277.076662) (xy 339.24113 -277.124414)
			(xy 339.341206 -277.224236)
		)
		(stroke
			(width 0)
			(type solid)
		)
		(fill yes)
		(layer "In2.Cu")
		(net "M_C_CPU0_SB_DQS_DP<5>")
	)
	(gr_poly
		(pts
			(xy 339.441282 -275.907754) (xy 339.341206 -275.807932) (xy 339.24113 -275.907754) (xy 339.24113 -275.955506)
			(xy 339.441282 -275.955506)
		)
		(stroke
			(width 0)
			(type solid)
		)
		(fill yes)
		(layer "In2.Cu")
		(net "M_C_CPU0_SB_DQS_DP<0>")
	)
	(gr_poly
		(pts
			(xy 339.441282 -275.504148) (xy 339.441282 -275.459698) (xy 339.24113 -275.459698) (xy 339.24113 -275.504148)
			(xy 339.341206 -275.604224)
		)
		(stroke
			(width 0)
			(type solid)
		)
		(fill yes)
		(layer "In2.Cu")
		(net "M_C_CPU0_SB_DQ<3>")
	)
	(gr_poly
		(pts
			(xy 339.441282 -274.287996) (xy 339.341206 -274.18792) (xy 339.24113 -274.287996) (xy 339.24113 -274.332446)
			(xy 339.441282 -274.332446)
		)
		(stroke
			(width 0)
			(type solid)
		)
		(fill yes)
		(layer "In2.Cu")
		(net "M_C_CPU0_SB_DQ<0>")
	)
	(gr_poly
		(pts
			(xy 339.441282 -273.884136) (xy 339.441282 -273.839686) (xy 339.24113 -273.839686) (xy 339.24113 -273.884136)
			(xy 339.341206 -273.984212)
		)
		(stroke
			(width 0)
			(type solid)
		)
		(fill yes)
		(layer "In2.Cu")
		(net "M_C_CPU0_SB_CB<3>")
	)
	(gr_poly
		(pts
			(xy 339.441282 -272.667984) (xy 339.341206 -272.567908) (xy 339.24113 -272.667984) (xy 339.24113 -272.712434)
			(xy 339.441282 -272.712434)
		)
		(stroke
			(width 0)
			(type solid)
		)
		(fill yes)
		(layer "In2.Cu")
		(net "M_C_CPU0_SB_CB<0>")
	)
	(gr_poly
		(pts
			(xy 339.441282 -272.264378) (xy 339.441282 -272.216626) (xy 339.24113 -272.216626) (xy 339.24113 -272.264378)
			(xy 339.341206 -272.3642)
		)
		(stroke
			(width 0)
			(type solid)
		)
		(fill yes)
		(layer "In2.Cu")
		(net "M_C_CPU0_SB_DQS_DP<4>")
	)
	(gr_poly
		(pts
			(xy 339.441282 -271.047718) (xy 339.341206 -270.947896) (xy 339.24113 -271.047718) (xy 339.24113 -271.09547)
			(xy 339.441282 -271.09547)
		)
		(stroke
			(width 0)
			(type solid)
		)
		(fill yes)
		(layer "In2.Cu")
		(net "M_C_CPU0_SB_DQS_DP<9>")
	)
	(gr_poly
		(pts
			(xy 339.441282 -270.644112) (xy 339.441282 -270.599662) (xy 339.24113 -270.599662) (xy 339.24113 -270.644112)
			(xy 339.341206 -270.744188)
		)
		(stroke
			(width 0)
			(type solid)
		)
		(fill yes)
		(layer "In2.Cu")
		(net "M_C_CPU0_SB_CB<7>")
	)
	(gr_poly
		(pts
			(xy 339.441282 -269.42796) (xy 339.341206 -269.327884) (xy 339.24113 -269.42796) (xy 339.24113 -269.47241)
			(xy 339.441282 -269.47241)
		)
		(stroke
			(width 0)
			(type solid)
		)
		(fill yes)
		(layer "In2.Cu")
		(net "M_C_CPU0_SB_CB<4>")
	)
	(gr_poly
		(pts
			(xy 339.441282 -265.784076) (xy 339.441282 -265.739626) (xy 339.24113 -265.739626) (xy 339.24113 -265.784076)
			(xy 339.341206 -265.884152)
		)
		(stroke
			(width 0)
			(type solid)
		)
		(fill yes)
		(layer "In2.Cu")
		(net "M_C_CPU0_SB_CS_N<0>")
	)
	(gr_poly
		(pts
			(xy 339.441282 -264.567924) (xy 339.341206 -264.467848) (xy 339.24113 -264.567924) (xy 339.24113 -264.612374)
			(xy 339.441282 -264.612374)
		)
		(stroke
			(width 0)
			(type solid)
		)
		(fill yes)
		(layer "In2.Cu")
		(net "M_C_CPU0_SB_CA<6>")
	)
	(gr_poly
		(pts
			(xy 339.441282 -264.164064) (xy 339.441282 -264.119614) (xy 339.24113 -264.119614) (xy 339.24113 -264.164064)
			(xy 339.341206 -264.26414)
		)
		(stroke
			(width 0)
			(type solid)
		)
		(fill yes)
		(layer "In2.Cu")
		(net "M_C_CPU0_SB_CA<5>")
	)
	(gr_poly
		(pts
			(xy 339.441282 -262.947912) (xy 339.341206 -262.847836) (xy 339.24113 -262.947912) (xy 339.24113 -262.992362)
			(xy 339.441282 -262.992362)
		)
		(stroke
			(width 0)
			(type solid)
		)
		(fill yes)
		(layer "In2.Cu")
		(net "M_C_CPU0_SB_CA<2>")
	)
	(gr_poly
		(pts
			(xy 339.441282 -262.544052) (xy 339.441282 -262.499602) (xy 339.24113 -262.499602) (xy 339.24113 -262.544052)
			(xy 339.341206 -262.644128)
		)
		(stroke
			(width 0)
			(type solid)
		)
		(fill yes)
		(layer "In2.Cu")
		(net "M_C_CPU0_SB_CA<1>")
	)
	(gr_poly
		(pts
			(xy 339.611208 -256.025904) (xy 339.511132 -255.926082) (xy 339.411056 -256.025904) (xy 339.411056 -256.073656)
			(xy 339.611208 -256.073656)
		)
		(stroke
			(width 0)
			(type solid)
		)
		(fill yes)
		(layer "In2.Cu")
		(net "M_C_CPU0_CLK_DP<0>")
	)
	(gr_poly
		(pts
			(xy 339.611208 -255.622298) (xy 339.611208 -255.577848) (xy 339.411056 -255.577848) (xy 339.411056 -255.622298)
			(xy 339.511132 -255.722374)
		)
		(stroke
			(width 0)
			(type solid)
		)
		(fill yes)
		(layer "In2.Cu")
		(net "M_C_CPU0_SA_PAR")
	)
	(gr_poly
		(pts
			(xy 339.611208 -254.406146) (xy 339.511132 -254.30607) (xy 339.411056 -254.406146) (xy 339.411056 -254.450596)
			(xy 339.611208 -254.450596)
		)
		(stroke
			(width 0)
			(type solid)
		)
		(fill yes)
		(layer "In2.Cu")
		(net "M_C_CPU0_SA_CA<4>")
	)
	(gr_poly
		(pts
			(xy 339.611208 -254.002286) (xy 339.611208 -253.957836) (xy 339.411056 -253.957836) (xy 339.411056 -254.002286)
			(xy 339.511132 -254.102362)
		)
		(stroke
			(width 0)
			(type solid)
		)
		(fill yes)
		(layer "In2.Cu")
		(net "M_C_CPU0_SA_CA<3>")
	)
	(gr_poly
		(pts
			(xy 339.611208 -252.786134) (xy 339.511132 -252.686058) (xy 339.411056 -252.786134) (xy 339.411056 -252.830584)
			(xy 339.611208 -252.830584)
		)
		(stroke
			(width 0)
			(type solid)
		)
		(fill yes)
		(layer "In2.Cu")
		(net "M_C_CPU0_SA_CA<0>")
	)
	(gr_poly
		(pts
			(xy 339.611208 -252.382274) (xy 339.611208 -252.337824) (xy 339.411056 -252.337824) (xy 339.411056 -252.382274)
			(xy 339.511132 -252.48235)
		)
		(stroke
			(width 0)
			(type solid)
		)
		(fill yes)
		(layer "In2.Cu")
		(net "M_C_CPU0_SA_CS_N<1>")
	)
	(gr_poly
		(pts
			(xy 339.611208 -250.762262) (xy 339.611208 -250.717812) (xy 339.411056 -250.717812) (xy 339.411056 -250.762262)
			(xy 339.511132 -250.862338)
		)
		(stroke
			(width 0)
			(type solid)
		)
		(fill yes)
		(layer "In2.Cu")
		(net "M_C_CPU0_RESET_N")
	)
	(gr_poly
		(pts
			(xy 339.611208 -249.14225) (xy 339.611208 -249.0978) (xy 339.411056 -249.0978) (xy 339.411056 -249.14225)
			(xy 339.511132 -249.242326)
		)
		(stroke
			(width 0)
			(type solid)
		)
		(fill yes)
		(layer "In2.Cu")
		(net "M_C_CPU0_SA_CB<7>")
	)
	(gr_poly
		(pts
			(xy 339.611208 -247.926098) (xy 339.511132 -247.826022) (xy 339.411056 -247.926098) (xy 339.411056 -247.970548)
			(xy 339.611208 -247.970548)
		)
		(stroke
			(width 0)
			(type solid)
		)
		(fill yes)
		(layer "In2.Cu")
		(net "M_C_CPU0_SA_CB<4>")
	)
	(gr_poly
		(pts
			(xy 339.611208 -247.522492) (xy 339.611208 -247.47474) (xy 339.411056 -247.47474) (xy 339.411056 -247.522492)
			(xy 339.511132 -247.622314)
		)
		(stroke
			(width 0)
			(type solid)
		)
		(fill yes)
		(layer "In2.Cu")
		(net "M_C_CPU0_SA_DQS_DP<9>")
	)
	(gr_poly
		(pts
			(xy 339.611208 -246.305832) (xy 339.511132 -246.20601) (xy 339.411056 -246.305832) (xy 339.411056 -246.353584)
			(xy 339.611208 -246.353584)
		)
		(stroke
			(width 0)
			(type solid)
		)
		(fill yes)
		(layer "In2.Cu")
		(net "M_C_CPU0_SA_DQS_DP<4>")
	)
	(gr_poly
		(pts
			(xy 339.611208 -245.902226) (xy 339.611208 -245.857776) (xy 339.411056 -245.857776) (xy 339.411056 -245.902226)
			(xy 339.511132 -246.002302)
		)
		(stroke
			(width 0)
			(type solid)
		)
		(fill yes)
		(layer "In2.Cu")
		(net "M_C_CPU0_SA_CB<3>")
	)
	(gr_poly
		(pts
			(xy 339.611208 -244.686074) (xy 339.511132 -244.585998) (xy 339.411056 -244.686074) (xy 339.411056 -244.730524)
			(xy 339.611208 -244.730524)
		)
		(stroke
			(width 0)
			(type solid)
		)
		(fill yes)
		(layer "In2.Cu")
		(net "M_C_CPU0_SA_CB<0>")
	)
	(gr_poly
		(pts
			(xy 339.611208 -244.282214) (xy 339.611208 -244.237764) (xy 339.411056 -244.237764) (xy 339.411056 -244.282214)
			(xy 339.511132 -244.38229)
		)
		(stroke
			(width 0)
			(type solid)
		)
		(fill yes)
		(layer "In2.Cu")
		(net "M_C_CPU0_SA_DQ<31>")
	)
	(gr_poly
		(pts
			(xy 339.611208 -243.066062) (xy 339.511132 -242.965986) (xy 339.411056 -243.066062) (xy 339.411056 -243.110512)
			(xy 339.611208 -243.110512)
		)
		(stroke
			(width 0)
			(type solid)
		)
		(fill yes)
		(layer "In2.Cu")
		(net "M_C_CPU0_SA_DQ<28>")
	)
	(gr_poly
		(pts
			(xy 339.611208 -242.662456) (xy 339.611208 -242.614704) (xy 339.411056 -242.614704) (xy 339.411056 -242.662456)
			(xy 339.511132 -242.762278)
		)
		(stroke
			(width 0)
			(type solid)
		)
		(fill yes)
		(layer "In2.Cu")
		(net "M_C_CPU0_SA_DQS_DP<8>")
	)
	(gr_poly
		(pts
			(xy 339.611208 -241.445796) (xy 339.511132 -241.345974) (xy 339.411056 -241.445796) (xy 339.411056 -241.493548)
			(xy 339.611208 -241.493548)
		)
		(stroke
			(width 0)
			(type solid)
		)
		(fill yes)
		(layer "In2.Cu")
		(net "M_C_CPU0_SA_DQS_DP<3>")
	)
	(gr_poly
		(pts
			(xy 339.611208 -241.04219) (xy 339.611208 -240.99774) (xy 339.411056 -240.99774) (xy 339.411056 -241.04219)
			(xy 339.511132 -241.142266)
		)
		(stroke
			(width 0)
			(type solid)
		)
		(fill yes)
		(layer "In2.Cu")
		(net "M_C_CPU0_SA_DQ<27>")
	)
	(gr_poly
		(pts
			(xy 339.611208 -239.826038) (xy 339.511132 -239.725962) (xy 339.411056 -239.826038) (xy 339.411056 -239.870488)
			(xy 339.611208 -239.870488)
		)
		(stroke
			(width 0)
			(type solid)
		)
		(fill yes)
		(layer "In2.Cu")
		(net "M_C_CPU0_SA_DQ<24>")
	)
	(gr_poly
		(pts
			(xy 339.611208 -239.422178) (xy 339.611208 -239.377728) (xy 339.411056 -239.377728) (xy 339.411056 -239.422178)
			(xy 339.511132 -239.522254)
		)
		(stroke
			(width 0)
			(type solid)
		)
		(fill yes)
		(layer "In2.Cu")
		(net "M_C_CPU0_SA_DQ<23>")
	)
	(gr_poly
		(pts
			(xy 339.611208 -238.206026) (xy 339.511132 -238.10595) (xy 339.411056 -238.206026) (xy 339.411056 -238.250476)
			(xy 339.611208 -238.250476)
		)
		(stroke
			(width 0)
			(type solid)
		)
		(fill yes)
		(layer "In2.Cu")
		(net "M_C_CPU0_SA_DQ<20>")
	)
	(gr_poly
		(pts
			(xy 339.611208 -237.80242) (xy 339.611208 -237.754668) (xy 339.411056 -237.754668) (xy 339.411056 -237.80242)
			(xy 339.511132 -237.902242)
		)
		(stroke
			(width 0)
			(type solid)
		)
		(fill yes)
		(layer "In2.Cu")
		(net "M_C_CPU0_SA_DQS_DP<7>")
	)
	(gr_poly
		(pts
			(xy 339.611208 -236.58576) (xy 339.511132 -236.485938) (xy 339.411056 -236.58576) (xy 339.411056 -236.633512)
			(xy 339.611208 -236.633512)
		)
		(stroke
			(width 0)
			(type solid)
		)
		(fill yes)
		(layer "In2.Cu")
		(net "M_C_CPU0_SA_DQS_DP<2>")
	)
	(gr_poly
		(pts
			(xy 339.611208 -236.182154) (xy 339.611208 -236.137704) (xy 339.411056 -236.137704) (xy 339.411056 -236.182154)
			(xy 339.511132 -236.28223)
		)
		(stroke
			(width 0)
			(type solid)
		)
		(fill yes)
		(layer "In2.Cu")
		(net "M_C_CPU0_SA_DQ<19>")
	)
	(gr_poly
		(pts
			(xy 339.611208 -234.966002) (xy 339.511132 -234.865926) (xy 339.411056 -234.966002) (xy 339.411056 -235.010452)
			(xy 339.611208 -235.010452)
		)
		(stroke
			(width 0)
			(type solid)
		)
		(fill yes)
		(layer "In2.Cu")
		(net "M_C_CPU0_SA_DQ<16>")
	)
	(gr_poly
		(pts
			(xy 339.611208 -234.562142) (xy 339.611208 -234.517692) (xy 339.411056 -234.517692) (xy 339.411056 -234.562142)
			(xy 339.511132 -234.662218)
		)
		(stroke
			(width 0)
			(type solid)
		)
		(fill yes)
		(layer "In2.Cu")
		(net "M_C_CPU0_SA_DQ<15>")
	)
	(gr_poly
		(pts
			(xy 339.611208 -233.34599) (xy 339.511132 -233.245914) (xy 339.411056 -233.34599) (xy 339.411056 -233.39044)
			(xy 339.611208 -233.39044)
		)
		(stroke
			(width 0)
			(type solid)
		)
		(fill yes)
		(layer "In2.Cu")
		(net "M_C_CPU0_SA_DQ<12>")
	)
	(gr_poly
		(pts
			(xy 339.611208 -232.942384) (xy 339.611208 -232.894632) (xy 339.411056 -232.894632) (xy 339.411056 -232.942384)
			(xy 339.511132 -233.042206)
		)
		(stroke
			(width 0)
			(type solid)
		)
		(fill yes)
		(layer "In2.Cu")
		(net "M_C_CPU0_SA_DQS_DP<6>")
	)
	(gr_poly
		(pts
			(xy 339.611208 -231.725724) (xy 339.511132 -231.625902) (xy 339.411056 -231.725724) (xy 339.411056 -231.773476)
			(xy 339.611208 -231.773476)
		)
		(stroke
			(width 0)
			(type solid)
		)
		(fill yes)
		(layer "In2.Cu")
		(net "M_C_CPU0_SA_DQS_DP<1>")
	)
	(gr_poly
		(pts
			(xy 339.611208 -231.322372) (xy 339.611208 -231.277922) (xy 339.411056 -231.277922) (xy 339.411056 -231.322372)
			(xy 339.511132 -231.422448)
		)
		(stroke
			(width 0)
			(type solid)
		)
		(fill yes)
		(layer "In2.Cu")
		(net "M_C_CPU0_SA_DQ<11>")
	)
	(gr_poly
		(pts
			(xy 339.611208 -230.105966) (xy 339.511132 -230.006144) (xy 339.411056 -230.105966) (xy 339.411056 -230.150416)
			(xy 339.611208 -230.150416)
		)
		(stroke
			(width 0)
			(type solid)
		)
		(fill yes)
		(layer "In2.Cu")
		(net "M_C_CPU0_SA_DQ<8>")
	)
	(gr_poly
		(pts
			(xy 339.611208 -229.70236) (xy 339.611208 -229.65791) (xy 339.411056 -229.65791) (xy 339.411056 -229.70236)
			(xy 339.511132 -229.802436)
		)
		(stroke
			(width 0)
			(type solid)
		)
		(fill yes)
		(layer "In2.Cu")
		(net "M_C_CPU0_SA_DQ<7>")
	)
	(gr_poly
		(pts
			(xy 339.611208 -228.486208) (xy 339.511132 -228.386132) (xy 339.411056 -228.486208) (xy 339.411056 -228.530658)
			(xy 339.611208 -228.530658)
		)
		(stroke
			(width 0)
			(type solid)
		)
		(fill yes)
		(layer "In2.Cu")
		(net "M_C_CPU0_SA_DQ<4>")
	)
	(gr_poly
		(pts
			(xy 339.611208 -228.082602) (xy 339.611208 -228.03485) (xy 339.411056 -228.03485) (xy 339.411056 -228.082602)
			(xy 339.511132 -228.182424)
		)
		(stroke
			(width 0)
			(type solid)
		)
		(fill yes)
		(layer "In2.Cu")
		(net "M_C_CPU0_SA_DQS_DP<5>")
	)
	(gr_poly
		(pts
			(xy 339.611208 -226.865942) (xy 339.511132 -226.76612) (xy 339.411056 -226.865942) (xy 339.411056 -226.913694)
			(xy 339.611208 -226.913694)
		)
		(stroke
			(width 0)
			(type solid)
		)
		(fill yes)
		(layer "In2.Cu")
		(net "M_C_CPU0_SA_DQS_DP<0>")
	)
	(gr_poly
		(pts
			(xy 339.611208 -226.462336) (xy 339.611208 -226.417886) (xy 339.411056 -226.417886) (xy 339.411056 -226.462336)
			(xy 339.511132 -226.562412)
		)
		(stroke
			(width 0)
			(type solid)
		)
		(fill yes)
		(layer "In2.Cu")
		(net "M_C_CPU0_SA_DQ<3>")
	)
	(gr_poly
		(pts
			(xy 339.611208 -225.246184) (xy 339.511132 -225.146108) (xy 339.411056 -225.246184) (xy 339.411056 -225.290634)
			(xy 339.611208 -225.290634)
		)
		(stroke
			(width 0)
			(type solid)
		)
		(fill yes)
		(layer "In2.Cu")
		(net "M_C_CPU0_SA_DQ<0>")
	)
	(gr_poly
		(pts
			(xy 339.911182 -292.91788) (xy 339.811106 -292.817804) (xy 339.71103 -292.91788) (xy 339.71103 -292.96233)
			(xy 339.911182 -292.96233)
		)
		(stroke
			(width 0)
			(type solid)
		)
		(fill yes)
		(layer "In2.Cu")
		(net "M_C_CPU0_SB_DQ<29>")
	)
	(gr_poly
		(pts
			(xy 339.911182 -292.51402) (xy 339.911182 -292.46957) (xy 339.71103 -292.46957) (xy 339.71103 -292.51402)
			(xy 339.811106 -292.614096)
		)
		(stroke
			(width 0)
			(type solid)
		)
		(fill yes)
		(layer "In2.Cu")
		(net "M_C_CPU0_SB_DQ<30>")
	)
	(gr_poly
		(pts
			(xy 339.911182 -291.297614) (xy 339.811106 -291.197792) (xy 339.71103 -291.297614) (xy 339.71103 -291.345366)
			(xy 339.911182 -291.345366)
		)
		(stroke
			(width 0)
			(type solid)
		)
		(fill yes)
		(layer "In2.Cu")
		(net "M_C_CPU0_SB_DQS_DN<8>")
	)
	(gr_poly
		(pts
			(xy 339.911182 -290.894262) (xy 339.911182 -290.84651) (xy 339.71103 -290.84651) (xy 339.71103 -290.894262)
			(xy 339.811106 -290.994084)
		)
		(stroke
			(width 0)
			(type solid)
		)
		(fill yes)
		(layer "In2.Cu")
		(net "M_C_CPU0_SB_DQS_DN<3>")
	)
	(gr_poly
		(pts
			(xy 339.911182 -289.677856) (xy 339.811106 -289.57778) (xy 339.71103 -289.677856) (xy 339.71103 -289.722306)
			(xy 339.911182 -289.722306)
		)
		(stroke
			(width 0)
			(type solid)
		)
		(fill yes)
		(layer "In2.Cu")
		(net "M_C_CPU0_SB_DQ<25>")
	)
	(gr_poly
		(pts
			(xy 339.911182 -289.273996) (xy 339.911182 -289.229546) (xy 339.71103 -289.229546) (xy 339.71103 -289.273996)
			(xy 339.811106 -289.374072)
		)
		(stroke
			(width 0)
			(type solid)
		)
		(fill yes)
		(layer "In2.Cu")
		(net "M_C_CPU0_SB_DQ<26>")
	)
	(gr_poly
		(pts
			(xy 339.911182 -288.057844) (xy 339.811106 -287.957768) (xy 339.71103 -288.057844) (xy 339.71103 -288.102294)
			(xy 339.911182 -288.102294)
		)
		(stroke
			(width 0)
			(type solid)
		)
		(fill yes)
		(layer "In2.Cu")
		(net "M_C_CPU0_SB_DQ<21>")
	)
	(gr_poly
		(pts
			(xy 339.911182 -287.654238) (xy 339.911182 -287.609788) (xy 339.71103 -287.609788) (xy 339.71103 -287.654238)
			(xy 339.811106 -287.75406)
		)
		(stroke
			(width 0)
			(type solid)
		)
		(fill yes)
		(layer "In2.Cu")
		(net "M_C_CPU0_SB_DQ<22>")
	)
	(gr_poly
		(pts
			(xy 339.911182 -286.437832) (xy 339.811106 -286.337756) (xy 339.71103 -286.437832) (xy 339.71103 -286.485584)
			(xy 339.911182 -286.485584)
		)
		(stroke
			(width 0)
			(type solid)
		)
		(fill yes)
		(layer "In2.Cu")
		(net "M_C_CPU0_SB_DQS_DN<7>")
	)
	(gr_poly
		(pts
			(xy 339.911182 -286.03448) (xy 339.911182 -285.986728) (xy 339.71103 -285.986728) (xy 339.71103 -286.03448)
			(xy 339.811106 -286.134302)
		)
		(stroke
			(width 0)
			(type solid)
		)
		(fill yes)
		(layer "In2.Cu")
		(net "M_C_CPU0_SB_DQS_DN<2>")
	)
	(gr_poly
		(pts
			(xy 339.911182 -284.818074) (xy 339.811106 -284.717998) (xy 339.71103 -284.818074) (xy 339.71103 -284.862524)
			(xy 339.911182 -284.862524)
		)
		(stroke
			(width 0)
			(type solid)
		)
		(fill yes)
		(layer "In2.Cu")
		(net "M_C_CPU0_SB_DQ<17>")
	)
	(gr_poly
		(pts
			(xy 339.911182 -284.414214) (xy 339.911182 -284.369764) (xy 339.71103 -284.369764) (xy 339.71103 -284.414214)
			(xy 339.811106 -284.51429)
		)
		(stroke
			(width 0)
			(type solid)
		)
		(fill yes)
		(layer "In2.Cu")
		(net "M_C_CPU0_SB_DQ<18>")
	)
	(gr_poly
		(pts
			(xy 339.911182 -283.198062) (xy 339.811106 -283.097986) (xy 339.71103 -283.198062) (xy 339.71103 -283.242512)
			(xy 339.911182 -283.242512)
		)
		(stroke
			(width 0)
			(type solid)
		)
		(fill yes)
		(layer "In2.Cu")
		(net "M_C_CPU0_SB_DQ<13>")
	)
	(gr_poly
		(pts
			(xy 339.911182 -282.794202) (xy 339.911182 -282.749752) (xy 339.71103 -282.749752) (xy 339.71103 -282.794202)
			(xy 339.811106 -282.894278)
		)
		(stroke
			(width 0)
			(type solid)
		)
		(fill yes)
		(layer "In2.Cu")
		(net "M_C_CPU0_SB_DQ<14>")
	)
	(gr_poly
		(pts
			(xy 339.911182 -281.577796) (xy 339.811106 -281.477974) (xy 339.71103 -281.577796) (xy 339.71103 -281.625548)
			(xy 339.911182 -281.625548)
		)
		(stroke
			(width 0)
			(type solid)
		)
		(fill yes)
		(layer "In2.Cu")
		(net "M_C_CPU0_SB_DQS_DN<6>")
	)
	(gr_poly
		(pts
			(xy 339.911182 -281.174444) (xy 339.911182 -281.126692) (xy 339.71103 -281.126692) (xy 339.71103 -281.174444)
			(xy 339.811106 -281.274266)
		)
		(stroke
			(width 0)
			(type solid)
		)
		(fill yes)
		(layer "In2.Cu")
		(net "M_C_CPU0_SB_DQS_DN<1>")
	)
	(gr_poly
		(pts
			(xy 339.911182 -279.958038) (xy 339.811106 -279.857962) (xy 339.71103 -279.958038) (xy 339.71103 -280.002488)
			(xy 339.911182 -280.002488)
		)
		(stroke
			(width 0)
			(type solid)
		)
		(fill yes)
		(layer "In2.Cu")
		(net "M_C_CPU0_SB_DQ<9>")
	)
	(gr_poly
		(pts
			(xy 339.911182 -279.554178) (xy 339.911182 -279.509728) (xy 339.71103 -279.509728) (xy 339.71103 -279.554178)
			(xy 339.811106 -279.654254)
		)
		(stroke
			(width 0)
			(type solid)
		)
		(fill yes)
		(layer "In2.Cu")
		(net "M_C_CPU0_SB_DQ<10>")
	)
	(gr_poly
		(pts
			(xy 339.911182 -278.338026) (xy 339.811106 -278.23795) (xy 339.71103 -278.338026) (xy 339.71103 -278.382476)
			(xy 339.911182 -278.382476)
		)
		(stroke
			(width 0)
			(type solid)
		)
		(fill yes)
		(layer "In2.Cu")
		(net "M_C_CPU0_SB_DQ<5>")
	)
	(gr_poly
		(pts
			(xy 339.911182 -277.934166) (xy 339.911182 -277.889716) (xy 339.71103 -277.889716) (xy 339.71103 -277.934166)
			(xy 339.811106 -278.034242)
		)
		(stroke
			(width 0)
			(type solid)
		)
		(fill yes)
		(layer "In2.Cu")
		(net "M_C_CPU0_SB_DQ<6>")
	)
	(gr_poly
		(pts
			(xy 339.911182 -276.71776) (xy 339.811106 -276.617938) (xy 339.71103 -276.71776) (xy 339.71103 -276.765512)
			(xy 339.911182 -276.765512)
		)
		(stroke
			(width 0)
			(type solid)
		)
		(fill yes)
		(layer "In2.Cu")
		(net "M_C_CPU0_SB_DQS_DN<5>")
	)
	(gr_poly
		(pts
			(xy 339.911182 -276.314408) (xy 339.911182 -276.266656) (xy 339.71103 -276.266656) (xy 339.71103 -276.314408)
			(xy 339.811106 -276.41423)
		)
		(stroke
			(width 0)
			(type solid)
		)
		(fill yes)
		(layer "In2.Cu")
		(net "M_C_CPU0_SB_DQS_DN<0>")
	)
	(gr_poly
		(pts
			(xy 339.911182 -275.098002) (xy 339.811106 -274.997926) (xy 339.71103 -275.098002) (xy 339.71103 -275.142452)
			(xy 339.911182 -275.142452)
		)
		(stroke
			(width 0)
			(type solid)
		)
		(fill yes)
		(layer "In2.Cu")
		(net "M_C_CPU0_SB_DQ<1>")
	)
	(gr_poly
		(pts
			(xy 339.911182 -274.694142) (xy 339.911182 -274.649692) (xy 339.71103 -274.649692) (xy 339.71103 -274.694142)
			(xy 339.811106 -274.794218)
		)
		(stroke
			(width 0)
			(type solid)
		)
		(fill yes)
		(layer "In2.Cu")
		(net "M_C_CPU0_SB_DQ<2>")
	)
	(gr_poly
		(pts
			(xy 339.911182 -273.47799) (xy 339.811106 -273.377914) (xy 339.71103 -273.47799) (xy 339.71103 -273.52244)
			(xy 339.911182 -273.52244)
		)
		(stroke
			(width 0)
			(type solid)
		)
		(fill yes)
		(layer "In2.Cu")
		(net "M_C_CPU0_SB_CB<1>")
	)
	(gr_poly
		(pts
			(xy 339.911182 -273.07413) (xy 339.911182 -273.02968) (xy 339.71103 -273.02968) (xy 339.71103 -273.07413)
			(xy 339.811106 -273.174206)
		)
		(stroke
			(width 0)
			(type solid)
		)
		(fill yes)
		(layer "In2.Cu")
		(net "M_C_CPU0_SB_CB<2>")
	)
	(gr_poly
		(pts
			(xy 339.911182 -271.857724) (xy 339.811106 -271.757902) (xy 339.71103 -271.857724) (xy 339.71103 -271.905476)
			(xy 339.911182 -271.905476)
		)
		(stroke
			(width 0)
			(type solid)
		)
		(fill yes)
		(layer "In2.Cu")
		(net "M_C_CPU0_SB_DQS_DN<4>")
	)
	(gr_poly
		(pts
			(xy 339.911182 -271.454372) (xy 339.911182 -271.40662) (xy 339.71103 -271.40662) (xy 339.71103 -271.454372)
			(xy 339.811106 -271.554194)
		)
		(stroke
			(width 0)
			(type solid)
		)
		(fill yes)
		(layer "In2.Cu")
		(net "M_C_CPU0_SB_DQS_DN<9>")
	)
	(gr_poly
		(pts
			(xy 339.911182 -270.237966) (xy 339.811106 -270.13789) (xy 339.71103 -270.237966) (xy 339.71103 -270.282416)
			(xy 339.911182 -270.282416)
		)
		(stroke
			(width 0)
			(type solid)
		)
		(fill yes)
		(layer "In2.Cu")
		(net "M_C_CPU0_SB_CB<5>")
	)
	(gr_poly
		(pts
			(xy 339.911182 -269.834106) (xy 339.911182 -269.789656) (xy 339.71103 -269.789656) (xy 339.71103 -269.834106)
			(xy 339.811106 -269.934182)
		)
		(stroke
			(width 0)
			(type solid)
		)
		(fill yes)
		(layer "In2.Cu")
		(net "M_C_CPU0_SB_CB<6>")
	)
	(gr_poly
		(pts
			(xy 339.911182 -266.991592) (xy 339.811106 -266.891516) (xy 339.71103 -266.991592) (xy 339.71103 -267.036042)
			(xy 339.911182 -267.036042)
		)
		(stroke
			(width 0)
			(type solid)
		)
		(fill yes)
		(layer "In2.Cu")
		(net "M_C_CPU0_SA_RSP<0>")
	)
	(gr_poly
		(pts
			(xy 339.911182 -266.594082) (xy 339.911182 -266.549632) (xy 339.71103 -266.549632) (xy 339.71103 -266.594082)
			(xy 339.811106 -266.694158)
		)
		(stroke
			(width 0)
			(type solid)
		)
		(fill yes)
		(layer "In2.Cu")
		(net "M_C_CPU0_SB_CS_N<1>")
	)
	(gr_poly
		(pts
			(xy 339.911182 -264.97407) (xy 339.911182 -264.92962) (xy 339.71103 -264.92962) (xy 339.71103 -264.97407)
			(xy 339.811106 -265.074146)
		)
		(stroke
			(width 0)
			(type solid)
		)
		(fill yes)
		(layer "In2.Cu")
		(net "M_C_CPU0_SB_PAR")
	)
	(gr_poly
		(pts
			(xy 339.911182 -263.757918) (xy 339.811106 -263.657842) (xy 339.71103 -263.757918) (xy 339.71103 -263.802368)
			(xy 339.911182 -263.802368)
		)
		(stroke
			(width 0)
			(type solid)
		)
		(fill yes)
		(layer "In2.Cu")
		(net "M_C_CPU0_SB_CA<4>")
	)
	(gr_poly
		(pts
			(xy 339.911182 -263.354058) (xy 339.911182 -263.309608) (xy 339.71103 -263.309608) (xy 339.71103 -263.354058)
			(xy 339.811106 -263.454134)
		)
		(stroke
			(width 0)
			(type solid)
		)
		(fill yes)
		(layer "In2.Cu")
		(net "M_C_CPU0_SB_CA<3>")
	)
	(gr_poly
		(pts
			(xy 339.911182 -262.137906) (xy 339.811106 -262.03783) (xy 339.71103 -262.137906) (xy 339.71103 -262.182356)
			(xy 339.911182 -262.182356)
		)
		(stroke
			(width 0)
			(type solid)
		)
		(fill yes)
		(layer "In2.Cu")
		(net "M_C_CPU0_SB_CA<0>")
	)
	(gr_poly
		(pts
			(xy 340.080854 -246.712232) (xy 340.080854 -246.664734) (xy 339.880956 -246.664734) (xy 339.880956 -246.712232)
			(xy 339.980778 -246.812308)
		)
		(stroke
			(width 0)
			(type solid)
		)
		(fill yes)
		(layer "In2.Cu")
		(net "M_C_CPU0_SA_DQS_DN<4>")
	)
	(gr_poly
		(pts
			(xy 340.081108 -256.432558) (xy 340.081108 -256.384806) (xy 339.880956 -256.384806) (xy 339.880956 -256.432558)
			(xy 339.981032 -256.53238)
		)
		(stroke
			(width 0)
			(type solid)
		)
		(fill yes)
		(layer "In2.Cu")
		(net "M_C_CPU0_CLK_DN<0>")
	)
	(gr_poly
		(pts
			(xy 340.081108 -255.216152) (xy 339.981032 -255.116076) (xy 339.880956 -255.216152) (xy 339.880956 -255.260602)
			(xy 340.081108 -255.260602)
		)
		(stroke
			(width 0)
			(type solid)
		)
		(fill yes)
		(layer "In2.Cu")
		(net "M_C_CPU0_SA_CA<6>")
	)
	(gr_poly
		(pts
			(xy 340.081108 -254.812292) (xy 340.081108 -254.767842) (xy 339.880956 -254.767842) (xy 339.880956 -254.812292)
			(xy 339.981032 -254.912368)
		)
		(stroke
			(width 0)
			(type solid)
		)
		(fill yes)
		(layer "In2.Cu")
		(net "M_C_CPU0_SA_CA<5>")
	)
	(gr_poly
		(pts
			(xy 340.081108 -253.59614) (xy 339.981032 -253.496064) (xy 339.880956 -253.59614) (xy 339.880956 -253.64059)
			(xy 340.081108 -253.64059)
		)
		(stroke
			(width 0)
			(type solid)
		)
		(fill yes)
		(layer "In2.Cu")
		(net "M_C_CPU0_SA_CA<2>")
	)
	(gr_poly
		(pts
			(xy 340.081108 -253.19228) (xy 340.081108 -253.14783) (xy 339.880956 -253.14783) (xy 339.880956 -253.19228)
			(xy 339.981032 -253.292356)
		)
		(stroke
			(width 0)
			(type solid)
		)
		(fill yes)
		(layer "In2.Cu")
		(net "M_C_CPU0_SA_CA<1>")
	)
	(gr_poly
		(pts
			(xy 340.081108 -251.572268) (xy 340.081108 -251.527818) (xy 339.880956 -251.527818) (xy 339.880956 -251.572268)
			(xy 339.981032 -251.672344)
		)
		(stroke
			(width 0)
			(type solid)
		)
		(fill yes)
		(layer "In2.Cu")
		(net "M_C_CPU0_SA_CS_N<0>")
	)
	(gr_poly
		(pts
			(xy 340.081108 -250.356116) (xy 339.981032 -250.25604) (xy 339.880956 -250.356116) (xy 339.880956 -250.400566)
			(xy 340.081108 -250.400566)
		)
		(stroke
			(width 0)
			(type solid)
		)
		(fill yes)
		(layer "In2.Cu")
		(net "M_C_CPU0_ALERT_R_N")
	)
	(gr_poly
		(pts
			(xy 340.081108 -248.736104) (xy 339.981032 -248.636028) (xy 339.880956 -248.736104) (xy 339.880956 -248.780554)
			(xy 340.081108 -248.780554)
		)
		(stroke
			(width 0)
			(type solid)
		)
		(fill yes)
		(layer "In2.Cu")
		(net "M_C_CPU0_SA_CB<5>")
	)
	(gr_poly
		(pts
			(xy 340.081108 -248.332244) (xy 340.081108 -248.287794) (xy 339.880956 -248.287794) (xy 339.880956 -248.332244)
			(xy 339.981032 -248.43232)
		)
		(stroke
			(width 0)
			(type solid)
		)
		(fill yes)
		(layer "In2.Cu")
		(net "M_C_CPU0_SA_CB<6>")
	)
	(gr_poly
		(pts
			(xy 340.081108 -247.115838) (xy 339.981032 -247.016016) (xy 339.880956 -247.115838) (xy 339.880956 -247.16359)
			(xy 340.081108 -247.16359)
		)
		(stroke
			(width 0)
			(type solid)
		)
		(fill yes)
		(layer "In2.Cu")
		(net "M_C_CPU0_SA_DQS_DN<9>")
	)
	(gr_poly
		(pts
			(xy 340.081108 -245.49608) (xy 339.981032 -245.396004) (xy 339.880956 -245.49608) (xy 339.880956 -245.54053)
			(xy 340.081108 -245.54053)
		)
		(stroke
			(width 0)
			(type solid)
		)
		(fill yes)
		(layer "In2.Cu")
		(net "M_C_CPU0_SA_CB<1>")
	)
	(gr_poly
		(pts
			(xy 340.081108 -245.09222) (xy 340.081108 -245.04777) (xy 339.880956 -245.04777) (xy 339.880956 -245.09222)
			(xy 339.981032 -245.192296)
		)
		(stroke
			(width 0)
			(type solid)
		)
		(fill yes)
		(layer "In2.Cu")
		(net "M_C_CPU0_SA_CB<2>")
	)
	(gr_poly
		(pts
			(xy 340.081108 -243.876068) (xy 339.981032 -243.775992) (xy 339.880956 -243.876068) (xy 339.880956 -243.920518)
			(xy 340.081108 -243.920518)
		)
		(stroke
			(width 0)
			(type solid)
		)
		(fill yes)
		(layer "In2.Cu")
		(net "M_C_CPU0_SA_DQ<29>")
	)
	(gr_poly
		(pts
			(xy 340.081108 -243.472208) (xy 340.081108 -243.427758) (xy 339.880956 -243.427758) (xy 339.880956 -243.472208)
			(xy 339.981032 -243.572284)
		)
		(stroke
			(width 0)
			(type solid)
		)
		(fill yes)
		(layer "In2.Cu")
		(net "M_C_CPU0_SA_DQ<30>")
	)
	(gr_poly
		(pts
			(xy 340.081108 -242.255802) (xy 339.981032 -242.15598) (xy 339.880956 -242.255802) (xy 339.880956 -242.303554)
			(xy 340.081108 -242.303554)
		)
		(stroke
			(width 0)
			(type solid)
		)
		(fill yes)
		(layer "In2.Cu")
		(net "M_C_CPU0_SA_DQS_DN<8>")
	)
	(gr_poly
		(pts
			(xy 340.081108 -241.85245) (xy 340.081108 -241.804698) (xy 339.880956 -241.804698) (xy 339.880956 -241.85245)
			(xy 339.981032 -241.952272)
		)
		(stroke
			(width 0)
			(type solid)
		)
		(fill yes)
		(layer "In2.Cu")
		(net "M_C_CPU0_SA_DQS_DN<3>")
	)
	(gr_poly
		(pts
			(xy 340.081108 -240.636044) (xy 339.981032 -240.535968) (xy 339.880956 -240.636044) (xy 339.880956 -240.680494)
			(xy 340.081108 -240.680494)
		)
		(stroke
			(width 0)
			(type solid)
		)
		(fill yes)
		(layer "In2.Cu")
		(net "M_C_CPU0_SA_DQ<25>")
	)
	(gr_poly
		(pts
			(xy 340.081108 -240.232184) (xy 340.081108 -240.187734) (xy 339.880956 -240.187734) (xy 339.880956 -240.232184)
			(xy 339.981032 -240.33226)
		)
		(stroke
			(width 0)
			(type solid)
		)
		(fill yes)
		(layer "In2.Cu")
		(net "M_C_CPU0_SA_DQ<26>")
	)
	(gr_poly
		(pts
			(xy 340.081108 -239.016032) (xy 339.981032 -238.915956) (xy 339.880956 -239.016032) (xy 339.880956 -239.060482)
			(xy 340.081108 -239.060482)
		)
		(stroke
			(width 0)
			(type solid)
		)
		(fill yes)
		(layer "In2.Cu")
		(net "M_C_CPU0_SA_DQ<21>")
	)
	(gr_poly
		(pts
			(xy 340.081108 -238.612172) (xy 340.081108 -238.567722) (xy 339.880956 -238.567722) (xy 339.880956 -238.612172)
			(xy 339.981032 -238.712248)
		)
		(stroke
			(width 0)
			(type solid)
		)
		(fill yes)
		(layer "In2.Cu")
		(net "M_C_CPU0_SA_DQ<22>")
	)
	(gr_poly
		(pts
			(xy 340.081108 -237.395766) (xy 339.981032 -237.295944) (xy 339.880956 -237.395766) (xy 339.880956 -237.443518)
			(xy 340.081108 -237.443518)
		)
		(stroke
			(width 0)
			(type solid)
		)
		(fill yes)
		(layer "In2.Cu")
		(net "M_C_CPU0_SA_DQS_DN<7>")
	)
	(gr_poly
		(pts
			(xy 340.081108 -236.992414) (xy 340.081108 -236.944662) (xy 339.880956 -236.944662) (xy 339.880956 -236.992414)
			(xy 339.981032 -237.092236)
		)
		(stroke
			(width 0)
			(type solid)
		)
		(fill yes)
		(layer "In2.Cu")
		(net "M_C_CPU0_SA_DQS_DN<2>")
	)
	(gr_poly
		(pts
			(xy 340.081108 -235.776008) (xy 339.981032 -235.675932) (xy 339.880956 -235.776008) (xy 339.880956 -235.820458)
			(xy 340.081108 -235.820458)
		)
		(stroke
			(width 0)
			(type solid)
		)
		(fill yes)
		(layer "In2.Cu")
		(net "M_C_CPU0_SA_DQ<17>")
	)
	(gr_poly
		(pts
			(xy 340.081108 -235.372148) (xy 340.081108 -235.327698) (xy 339.880956 -235.327698) (xy 339.880956 -235.372148)
			(xy 339.981032 -235.472224)
		)
		(stroke
			(width 0)
			(type solid)
		)
		(fill yes)
		(layer "In2.Cu")
		(net "M_C_CPU0_SA_DQ<18>")
	)
	(gr_poly
		(pts
			(xy 340.081108 -234.155996) (xy 339.981032 -234.05592) (xy 339.880956 -234.155996) (xy 339.880956 -234.200446)
			(xy 340.081108 -234.200446)
		)
		(stroke
			(width 0)
			(type solid)
		)
		(fill yes)
		(layer "In2.Cu")
		(net "M_C_CPU0_SA_DQ<13>")
	)
	(gr_poly
		(pts
			(xy 340.081108 -233.752136) (xy 340.081108 -233.707686) (xy 339.880956 -233.707686) (xy 339.880956 -233.752136)
			(xy 339.981032 -233.852212)
		)
		(stroke
			(width 0)
			(type solid)
		)
		(fill yes)
		(layer "In2.Cu")
		(net "M_C_CPU0_SA_DQ<14>")
	)
	(gr_poly
		(pts
			(xy 340.081108 -232.53573) (xy 339.981032 -232.435908) (xy 339.880956 -232.53573) (xy 339.880956 -232.583482)
			(xy 340.081108 -232.583482)
		)
		(stroke
			(width 0)
			(type solid)
		)
		(fill yes)
		(layer "In2.Cu")
		(net "M_C_CPU0_SA_DQS_DN<6>")
	)
	(gr_poly
		(pts
			(xy 340.081108 -232.132378) (xy 340.081108 -232.084626) (xy 339.880956 -232.084626) (xy 339.880956 -232.132378)
			(xy 339.981032 -232.2322)
		)
		(stroke
			(width 0)
			(type solid)
		)
		(fill yes)
		(layer "In2.Cu")
		(net "M_C_CPU0_SA_DQS_DN<1>")
	)
	(gr_poly
		(pts
			(xy 340.081108 -230.915972) (xy 339.981032 -230.815896) (xy 339.880956 -230.915972) (xy 339.880956 -230.960422)
			(xy 340.081108 -230.960422)
		)
		(stroke
			(width 0)
			(type solid)
		)
		(fill yes)
		(layer "In2.Cu")
		(net "M_C_CPU0_SA_DQ<9>")
	)
	(gr_poly
		(pts
			(xy 340.081108 -230.512366) (xy 340.081108 -230.467916) (xy 339.880956 -230.467916) (xy 339.880956 -230.512366)
			(xy 339.981032 -230.612188)
		)
		(stroke
			(width 0)
			(type solid)
		)
		(fill yes)
		(layer "In2.Cu")
		(net "M_C_CPU0_SA_DQ<10>")
	)
	(gr_poly
		(pts
			(xy 340.081108 -229.29596) (xy 339.981032 -229.195884) (xy 339.880956 -229.29596) (xy 339.880956 -229.34041)
			(xy 340.081108 -229.34041)
		)
		(stroke
			(width 0)
			(type solid)
		)
		(fill yes)
		(layer "In2.Cu")
		(net "M_C_CPU0_SA_DQ<5>")
	)
	(gr_poly
		(pts
			(xy 340.081108 -228.892354) (xy 340.081108 -228.847904) (xy 339.880956 -228.847904) (xy 339.880956 -228.892354)
			(xy 339.981032 -228.99243)
		)
		(stroke
			(width 0)
			(type solid)
		)
		(fill yes)
		(layer "In2.Cu")
		(net "M_C_CPU0_SA_DQ<6>")
	)
	(gr_poly
		(pts
			(xy 340.081108 -227.675948) (xy 339.981032 -227.576126) (xy 339.880956 -227.675948) (xy 339.880956 -227.7237)
			(xy 340.081108 -227.7237)
		)
		(stroke
			(width 0)
			(type solid)
		)
		(fill yes)
		(layer "In2.Cu")
		(net "M_C_CPU0_SA_DQS_DN<5>")
	)
	(gr_poly
		(pts
			(xy 340.081108 -227.272596) (xy 340.081108 -227.224844) (xy 339.880956 -227.224844) (xy 339.880956 -227.272596)
			(xy 339.981032 -227.372418)
		)
		(stroke
			(width 0)
			(type solid)
		)
		(fill yes)
		(layer "In2.Cu")
		(net "M_C_CPU0_SA_DQS_DN<0>")
	)
	(gr_poly
		(pts
			(xy 340.081108 -226.05619) (xy 339.981032 -225.956114) (xy 339.880956 -226.05619) (xy 339.880956 -226.10064)
			(xy 340.081108 -226.10064)
		)
		(stroke
			(width 0)
			(type solid)
		)
		(fill yes)
		(layer "In2.Cu")
		(net "M_C_CPU0_SA_DQ<1>")
	)
	(gr_poly
		(pts
			(xy 340.081108 -225.65233) (xy 340.081108 -225.60788) (xy 339.880956 -225.60788) (xy 339.880956 -225.65233)
			(xy 339.981032 -225.752406)
		)
		(stroke
			(width 0)
			(type solid)
		)
		(fill yes)
		(layer "In2.Cu")
		(net "M_C_CPU0_SA_DQ<2>")
	)
	(gr_poly
		(pts
			(xy 340.381082 -293.324026) (xy 340.381082 -293.279576) (xy 340.18093 -293.279576) (xy 340.18093 -293.324026)
			(xy 340.281006 -293.424102)
		)
		(stroke
			(width 0)
			(type solid)
		)
		(fill yes)
		(layer "In2.Cu")
		(net "M_C_CPU0_SB_DQ<31>")
	)
	(gr_poly
		(pts
			(xy 340.381082 -292.107874) (xy 340.281006 -292.007798) (xy 340.18093 -292.107874) (xy 340.18093 -292.152324)
			(xy 340.381082 -292.152324)
		)
		(stroke
			(width 0)
			(type solid)
		)
		(fill yes)
		(layer "In2.Cu")
		(net "M_C_CPU0_SB_DQ<28>")
	)
	(gr_poly
		(pts
			(xy 340.381082 -291.704268) (xy 340.381082 -291.656516) (xy 340.18093 -291.656516) (xy 340.18093 -291.704268)
			(xy 340.281006 -291.80409)
		)
		(stroke
			(width 0)
			(type solid)
		)
		(fill yes)
		(layer "In2.Cu")
		(net "M_C_CPU0_SB_DQS_DP<8>")
	)
	(gr_poly
		(pts
			(xy 340.381082 -290.487608) (xy 340.281006 -290.387786) (xy 340.18093 -290.487608) (xy 340.18093 -290.53536)
			(xy 340.381082 -290.53536)
		)
		(stroke
			(width 0)
			(type solid)
		)
		(fill yes)
		(layer "In2.Cu")
		(net "M_C_CPU0_SB_DQS_DP<3>")
	)
	(gr_poly
		(pts
			(xy 340.381082 -290.084002) (xy 340.381082 -290.039552) (xy 340.18093 -290.039552) (xy 340.18093 -290.084002)
			(xy 340.281006 -290.184078)
		)
		(stroke
			(width 0)
			(type solid)
		)
		(fill yes)
		(layer "In2.Cu")
		(net "M_C_CPU0_SB_DQ<27>")
	)
	(gr_poly
		(pts
			(xy 340.381082 -288.86785) (xy 340.281006 -288.767774) (xy 340.18093 -288.86785) (xy 340.18093 -288.9123)
			(xy 340.381082 -288.9123)
		)
		(stroke
			(width 0)
			(type solid)
		)
		(fill yes)
		(layer "In2.Cu")
		(net "M_C_CPU0_SB_DQ<24>")
	)
	(gr_poly
		(pts
			(xy 340.381082 -288.464244) (xy 340.381082 -288.419794) (xy 340.18093 -288.419794) (xy 340.18093 -288.464244)
			(xy 340.281006 -288.56432)
		)
		(stroke
			(width 0)
			(type solid)
		)
		(fill yes)
		(layer "In2.Cu")
		(net "M_C_CPU0_SB_DQ<23>")
	)
	(gr_poly
		(pts
			(xy 340.381082 -287.247838) (xy 340.281006 -287.148016) (xy 340.18093 -287.247838) (xy 340.18093 -287.292288)
			(xy 340.381082 -287.292288)
		)
		(stroke
			(width 0)
			(type solid)
		)
		(fill yes)
		(layer "In2.Cu")
		(net "M_C_CPU0_SB_DQ<20>")
	)
	(gr_poly
		(pts
			(xy 340.381082 -286.844232) (xy 340.381082 -286.79648) (xy 340.18093 -286.79648) (xy 340.18093 -286.844232)
			(xy 340.281006 -286.944308)
		)
		(stroke
			(width 0)
			(type solid)
		)
		(fill yes)
		(layer "In2.Cu")
		(net "M_C_CPU0_SB_DQS_DP<7>")
	)
	(gr_poly
		(pts
			(xy 340.381082 -285.627826) (xy 340.281006 -285.528004) (xy 340.18093 -285.627826) (xy 340.18093 -285.675578)
			(xy 340.381082 -285.675578)
		)
		(stroke
			(width 0)
			(type solid)
		)
		(fill yes)
		(layer "In2.Cu")
		(net "M_C_CPU0_SB_DQS_DP<2>")
	)
	(gr_poly
		(pts
			(xy 340.381082 -285.22422) (xy 340.381082 -285.17977) (xy 340.18093 -285.17977) (xy 340.18093 -285.22422)
			(xy 340.281006 -285.324296)
		)
		(stroke
			(width 0)
			(type solid)
		)
		(fill yes)
		(layer "In2.Cu")
		(net "M_C_CPU0_SB_DQ<19>")
	)
	(gr_poly
		(pts
			(xy 340.381082 -284.008068) (xy 340.281006 -283.907992) (xy 340.18093 -284.008068) (xy 340.18093 -284.052518)
			(xy 340.381082 -284.052518)
		)
		(stroke
			(width 0)
			(type solid)
		)
		(fill yes)
		(layer "In2.Cu")
		(net "M_C_CPU0_SB_DQ<16>")
	)
	(gr_poly
		(pts
			(xy 340.381082 -283.604208) (xy 340.381082 -283.559758) (xy 340.18093 -283.559758) (xy 340.18093 -283.604208)
			(xy 340.281006 -283.704284)
		)
		(stroke
			(width 0)
			(type solid)
		)
		(fill yes)
		(layer "In2.Cu")
		(net "M_C_CPU0_SB_DQ<15>")
	)
	(gr_poly
		(pts
			(xy 340.381082 -282.388056) (xy 340.281006 -282.28798) (xy 340.18093 -282.388056) (xy 340.18093 -282.432506)
			(xy 340.381082 -282.432506)
		)
		(stroke
			(width 0)
			(type solid)
		)
		(fill yes)
		(layer "In2.Cu")
		(net "M_C_CPU0_SB_DQ<12>")
	)
	(gr_poly
		(pts
			(xy 340.381082 -281.98445) (xy 340.381082 -281.936698) (xy 340.18093 -281.936698) (xy 340.18093 -281.98445)
			(xy 340.281006 -282.084272)
		)
		(stroke
			(width 0)
			(type solid)
		)
		(fill yes)
		(layer "In2.Cu")
		(net "M_C_CPU0_SB_DQS_DP<6>")
	)
	(gr_poly
		(pts
			(xy 340.381082 -280.76779) (xy 340.281006 -280.667968) (xy 340.18093 -280.76779) (xy 340.18093 -280.815542)
			(xy 340.381082 -280.815542)
		)
		(stroke
			(width 0)
			(type solid)
		)
		(fill yes)
		(layer "In2.Cu")
		(net "M_C_CPU0_SB_DQS_DP<1>")
	)
	(gr_poly
		(pts
			(xy 340.381082 -280.364184) (xy 340.381082 -280.319734) (xy 340.18093 -280.319734) (xy 340.18093 -280.364184)
			(xy 340.281006 -280.46426)
		)
		(stroke
			(width 0)
			(type solid)
		)
		(fill yes)
		(layer "In2.Cu")
		(net "M_C_CPU0_SB_DQ<11>")
	)
	(gr_poly
		(pts
			(xy 340.381082 -279.148032) (xy 340.281006 -279.047956) (xy 340.18093 -279.148032) (xy 340.18093 -279.192482)
			(xy 340.381082 -279.192482)
		)
		(stroke
			(width 0)
			(type solid)
		)
		(fill yes)
		(layer "In2.Cu")
		(net "M_C_CPU0_SB_DQ<8>")
	)
	(gr_poly
		(pts
			(xy 340.381082 -278.744172) (xy 340.381082 -278.699722) (xy 340.18093 -278.699722) (xy 340.18093 -278.744172)
			(xy 340.281006 -278.844248)
		)
		(stroke
			(width 0)
			(type solid)
		)
		(fill yes)
		(layer "In2.Cu")
		(net "M_C_CPU0_SB_DQ<7>")
	)
	(gr_poly
		(pts
			(xy 340.381082 -277.52802) (xy 340.281006 -277.427944) (xy 340.18093 -277.52802) (xy 340.18093 -277.57247)
			(xy 340.381082 -277.57247)
		)
		(stroke
			(width 0)
			(type solid)
		)
		(fill yes)
		(layer "In2.Cu")
		(net "M_C_CPU0_SB_DQ<4>")
	)
	(gr_poly
		(pts
			(xy 340.381082 -277.124414) (xy 340.381082 -277.076662) (xy 340.18093 -277.076662) (xy 340.18093 -277.124414)
			(xy 340.281006 -277.224236)
		)
		(stroke
			(width 0)
			(type solid)
		)
		(fill yes)
		(layer "In2.Cu")
		(net "M_C_CPU0_SB_DQS_DP<5>")
	)
	(gr_poly
		(pts
			(xy 340.381082 -275.907754) (xy 340.281006 -275.807932) (xy 340.18093 -275.907754) (xy 340.18093 -275.955506)
			(xy 340.381082 -275.955506)
		)
		(stroke
			(width 0)
			(type solid)
		)
		(fill yes)
		(layer "In2.Cu")
		(net "M_C_CPU0_SB_DQS_DP<0>")
	)
	(gr_poly
		(pts
			(xy 340.381082 -275.504148) (xy 340.381082 -275.459698) (xy 340.18093 -275.459698) (xy 340.18093 -275.504148)
			(xy 340.281006 -275.604224)
		)
		(stroke
			(width 0)
			(type solid)
		)
		(fill yes)
		(layer "In2.Cu")
		(net "M_C_CPU0_SB_DQ<3>")
	)
	(gr_poly
		(pts
			(xy 340.381082 -274.287996) (xy 340.281006 -274.18792) (xy 340.18093 -274.287996) (xy 340.18093 -274.332446)
			(xy 340.381082 -274.332446)
		)
		(stroke
			(width 0)
			(type solid)
		)
		(fill yes)
		(layer "In2.Cu")
		(net "M_C_CPU0_SB_DQ<0>")
	)
	(gr_poly
		(pts
			(xy 340.381082 -273.884136) (xy 340.381082 -273.839686) (xy 340.18093 -273.839686) (xy 340.18093 -273.884136)
			(xy 340.281006 -273.984212)
		)
		(stroke
			(width 0)
			(type solid)
		)
		(fill yes)
		(layer "In2.Cu")
		(net "M_C_CPU0_SB_CB<3>")
	)
	(gr_poly
		(pts
			(xy 340.381082 -272.667984) (xy 340.281006 -272.567908) (xy 340.18093 -272.667984) (xy 340.18093 -272.712434)
			(xy 340.381082 -272.712434)
		)
		(stroke
			(width 0)
			(type solid)
		)
		(fill yes)
		(layer "In2.Cu")
		(net "M_C_CPU0_SB_CB<0>")
	)
	(gr_poly
		(pts
			(xy 340.381082 -272.264378) (xy 340.381082 -272.216626) (xy 340.18093 -272.216626) (xy 340.18093 -272.264378)
			(xy 340.281006 -272.3642)
		)
		(stroke
			(width 0)
			(type solid)
		)
		(fill yes)
		(layer "In2.Cu")
		(net "M_C_CPU0_SB_DQS_DP<4>")
	)
	(gr_poly
		(pts
			(xy 340.381082 -271.047718) (xy 340.281006 -270.947896) (xy 340.18093 -271.047718) (xy 340.18093 -271.09547)
			(xy 340.381082 -271.09547)
		)
		(stroke
			(width 0)
			(type solid)
		)
		(fill yes)
		(layer "In2.Cu")
		(net "M_C_CPU0_SB_DQS_DP<9>")
	)
	(gr_poly
		(pts
			(xy 340.381082 -270.644112) (xy 340.381082 -270.599662) (xy 340.18093 -270.599662) (xy 340.18093 -270.644112)
			(xy 340.281006 -270.744188)
		)
		(stroke
			(width 0)
			(type solid)
		)
		(fill yes)
		(layer "In2.Cu")
		(net "M_C_CPU0_SB_CB<7>")
	)
	(gr_poly
		(pts
			(xy 340.381082 -269.42796) (xy 340.281006 -269.327884) (xy 340.18093 -269.42796) (xy 340.18093 -269.47241)
			(xy 340.381082 -269.47241)
		)
		(stroke
			(width 0)
			(type solid)
		)
		(fill yes)
		(layer "In2.Cu")
		(net "M_C_CPU0_SB_CB<4>")
	)
	(gr_poly
		(pts
			(xy 340.381082 -265.784076) (xy 340.381082 -265.739626) (xy 340.18093 -265.739626) (xy 340.18093 -265.784076)
			(xy 340.281006 -265.884152)
		)
		(stroke
			(width 0)
			(type solid)
		)
		(fill yes)
		(layer "In2.Cu")
		(net "M_C_CPU0_SB_CS_N<0>")
	)
	(gr_poly
		(pts
			(xy 340.381082 -264.567924) (xy 340.281006 -264.467848) (xy 340.18093 -264.567924) (xy 340.18093 -264.612374)
			(xy 340.381082 -264.612374)
		)
		(stroke
			(width 0)
			(type solid)
		)
		(fill yes)
		(layer "In2.Cu")
		(net "M_C_CPU0_SB_CA<6>")
	)
	(gr_poly
		(pts
			(xy 340.381082 -264.164064) (xy 340.381082 -264.119614) (xy 340.18093 -264.119614) (xy 340.18093 -264.164064)
			(xy 340.281006 -264.26414)
		)
		(stroke
			(width 0)
			(type solid)
		)
		(fill yes)
		(layer "In2.Cu")
		(net "M_C_CPU0_SB_CA<5>")
	)
	(gr_poly
		(pts
			(xy 340.381082 -262.947912) (xy 340.281006 -262.847836) (xy 340.18093 -262.947912) (xy 340.18093 -262.992362)
			(xy 340.381082 -262.992362)
		)
		(stroke
			(width 0)
			(type solid)
		)
		(fill yes)
		(layer "In2.Cu")
		(net "M_C_CPU0_SB_CA<2>")
	)
	(gr_poly
		(pts
			(xy 340.381082 -262.544052) (xy 340.381082 -262.499602) (xy 340.18093 -262.499602) (xy 340.18093 -262.544052)
			(xy 340.281006 -262.644128)
		)
		(stroke
			(width 0)
			(type solid)
		)
		(fill yes)
		(layer "In2.Cu")
		(net "M_C_CPU0_SB_CA<1>")
	)
	(gr_poly
		(pts
			(xy 340.387178 -267.801598) (xy 340.287356 -267.701522) (xy 340.18728 -267.801598) (xy 340.18728 -267.846048)
			(xy 340.387178 -267.846048)
		)
		(stroke
			(width 0)
			(type solid)
		)
		(fill yes)
		(layer "In2.Cu")
		(net "M_C_CPU0_SB_RSP<0>")
	)
	(gr_poly
		(pts
			(xy 340.551262 -256.025904) (xy 340.451186 -255.926082) (xy 340.35111 -256.025904) (xy 340.35111 -256.073656)
			(xy 340.551262 -256.073656)
		)
		(stroke
			(width 0)
			(type solid)
		)
		(fill yes)
		(layer "In2.Cu")
		(net "M_C_CPU0_CLK_DP<0>")
	)
	(gr_poly
		(pts
			(xy 340.551262 -255.622298) (xy 340.551262 -255.577848) (xy 340.35111 -255.577848) (xy 340.35111 -255.622298)
			(xy 340.451186 -255.722374)
		)
		(stroke
			(width 0)
			(type solid)
		)
		(fill yes)
		(layer "In2.Cu")
		(net "M_C_CPU0_SA_PAR")
	)
	(gr_poly
		(pts
			(xy 340.551262 -254.406146) (xy 340.451186 -254.30607) (xy 340.35111 -254.406146) (xy 340.35111 -254.450596)
			(xy 340.551262 -254.450596)
		)
		(stroke
			(width 0)
			(type solid)
		)
		(fill yes)
		(layer "In2.Cu")
		(net "M_C_CPU0_SA_CA<4>")
	)
	(gr_poly
		(pts
			(xy 340.551262 -254.002286) (xy 340.551262 -253.957836) (xy 340.35111 -253.957836) (xy 340.35111 -254.002286)
			(xy 340.451186 -254.102362)
		)
		(stroke
			(width 0)
			(type solid)
		)
		(fill yes)
		(layer "In2.Cu")
		(net "M_C_CPU0_SA_CA<3>")
	)
	(gr_poly
		(pts
			(xy 340.551262 -252.786134) (xy 340.451186 -252.686058) (xy 340.35111 -252.786134) (xy 340.35111 -252.830584)
			(xy 340.551262 -252.830584)
		)
		(stroke
			(width 0)
			(type solid)
		)
		(fill yes)
		(layer "In2.Cu")
		(net "M_C_CPU0_SA_CA<0>")
	)
	(gr_poly
		(pts
			(xy 340.551262 -252.382274) (xy 340.551262 -252.337824) (xy 340.35111 -252.337824) (xy 340.35111 -252.382274)
			(xy 340.451186 -252.48235)
		)
		(stroke
			(width 0)
			(type solid)
		)
		(fill yes)
		(layer "In2.Cu")
		(net "M_C_CPU0_SA_CS_N<1>")
	)
	(gr_poly
		(pts
			(xy 340.551262 -250.762262) (xy 340.551262 -250.717812) (xy 340.35111 -250.717812) (xy 340.35111 -250.762262)
			(xy 340.451186 -250.862338)
		)
		(stroke
			(width 0)
			(type solid)
		)
		(fill yes)
		(layer "In2.Cu")
		(net "M_C_CPU0_RESET_N")
	)
	(gr_poly
		(pts
			(xy 340.551262 -249.14225) (xy 340.551262 -249.0978) (xy 340.35111 -249.0978) (xy 340.35111 -249.14225)
			(xy 340.451186 -249.242326)
		)
		(stroke
			(width 0)
			(type solid)
		)
		(fill yes)
		(layer "In2.Cu")
		(net "M_C_CPU0_SA_CB<7>")
	)
	(gr_poly
		(pts
			(xy 340.551262 -247.926098) (xy 340.451186 -247.826022) (xy 340.35111 -247.926098) (xy 340.35111 -247.970548)
			(xy 340.551262 -247.970548)
		)
		(stroke
			(width 0)
			(type solid)
		)
		(fill yes)
		(layer "In2.Cu")
		(net "M_C_CPU0_SA_CB<4>")
	)
	(gr_poly
		(pts
			(xy 340.551262 -247.522492) (xy 340.551262 -247.47474) (xy 340.35111 -247.47474) (xy 340.35111 -247.522492)
			(xy 340.451186 -247.622314)
		)
		(stroke
			(width 0)
			(type solid)
		)
		(fill yes)
		(layer "In2.Cu")
		(net "M_C_CPU0_SA_DQS_DP<9>")
	)
	(gr_poly
		(pts
			(xy 340.551262 -246.305832) (xy 340.451186 -246.20601) (xy 340.35111 -246.305832) (xy 340.35111 -246.353584)
			(xy 340.551262 -246.353584)
		)
		(stroke
			(width 0)
			(type solid)
		)
		(fill yes)
		(layer "In2.Cu")
		(net "M_C_CPU0_SA_DQS_DP<4>")
	)
	(gr_poly
		(pts
			(xy 340.551262 -245.902226) (xy 340.551262 -245.857776) (xy 340.35111 -245.857776) (xy 340.35111 -245.902226)
			(xy 340.451186 -246.002302)
		)
		(stroke
			(width 0)
			(type solid)
		)
		(fill yes)
		(layer "In2.Cu")
		(net "M_C_CPU0_SA_CB<3>")
	)
	(gr_poly
		(pts
			(xy 340.551262 -244.686074) (xy 340.451186 -244.585998) (xy 340.35111 -244.686074) (xy 340.35111 -244.730524)
			(xy 340.551262 -244.730524)
		)
		(stroke
			(width 0)
			(type solid)
		)
		(fill yes)
		(layer "In2.Cu")
		(net "M_C_CPU0_SA_CB<0>")
	)
	(gr_poly
		(pts
			(xy 340.551262 -244.282214) (xy 340.551262 -244.237764) (xy 340.35111 -244.237764) (xy 340.35111 -244.282214)
			(xy 340.451186 -244.38229)
		)
		(stroke
			(width 0)
			(type solid)
		)
		(fill yes)
		(layer "In2.Cu")
		(net "M_C_CPU0_SA_DQ<31>")
	)
	(gr_poly
		(pts
			(xy 340.551262 -243.066062) (xy 340.451186 -242.965986) (xy 340.35111 -243.066062) (xy 340.35111 -243.110512)
			(xy 340.551262 -243.110512)
		)
		(stroke
			(width 0)
			(type solid)
		)
		(fill yes)
		(layer "In2.Cu")
		(net "M_C_CPU0_SA_DQ<28>")
	)
	(gr_poly
		(pts
			(xy 340.551262 -242.662456) (xy 340.551262 -242.614704) (xy 340.35111 -242.614704) (xy 340.35111 -242.662456)
			(xy 340.451186 -242.762278)
		)
		(stroke
			(width 0)
			(type solid)
		)
		(fill yes)
		(layer "In2.Cu")
		(net "M_C_CPU0_SA_DQS_DP<8>")
	)
	(gr_poly
		(pts
			(xy 340.551262 -241.445796) (xy 340.451186 -241.345974) (xy 340.35111 -241.445796) (xy 340.35111 -241.493548)
			(xy 340.551262 -241.493548)
		)
		(stroke
			(width 0)
			(type solid)
		)
		(fill yes)
		(layer "In2.Cu")
		(net "M_C_CPU0_SA_DQS_DP<3>")
	)
	(gr_poly
		(pts
			(xy 340.551262 -241.04219) (xy 340.551262 -240.99774) (xy 340.35111 -240.99774) (xy 340.35111 -241.04219)
			(xy 340.451186 -241.142266)
		)
		(stroke
			(width 0)
			(type solid)
		)
		(fill yes)
		(layer "In2.Cu")
		(net "M_C_CPU0_SA_DQ<27>")
	)
	(gr_poly
		(pts
			(xy 340.551262 -239.826038) (xy 340.451186 -239.725962) (xy 340.35111 -239.826038) (xy 340.35111 -239.870488)
			(xy 340.551262 -239.870488)
		)
		(stroke
			(width 0)
			(type solid)
		)
		(fill yes)
		(layer "In2.Cu")
		(net "M_C_CPU0_SA_DQ<24>")
	)
	(gr_poly
		(pts
			(xy 340.551262 -239.422178) (xy 340.551262 -239.377728) (xy 340.35111 -239.377728) (xy 340.35111 -239.422178)
			(xy 340.451186 -239.522254)
		)
		(stroke
			(width 0)
			(type solid)
		)
		(fill yes)
		(layer "In2.Cu")
		(net "M_C_CPU0_SA_DQ<23>")
	)
	(gr_poly
		(pts
			(xy 340.551262 -238.206026) (xy 340.451186 -238.10595) (xy 340.35111 -238.206026) (xy 340.35111 -238.250476)
			(xy 340.551262 -238.250476)
		)
		(stroke
			(width 0)
			(type solid)
		)
		(fill yes)
		(layer "In2.Cu")
		(net "M_C_CPU0_SA_DQ<20>")
	)
	(gr_poly
		(pts
			(xy 340.551262 -237.80242) (xy 340.551262 -237.754668) (xy 340.35111 -237.754668) (xy 340.35111 -237.80242)
			(xy 340.451186 -237.902242)
		)
		(stroke
			(width 0)
			(type solid)
		)
		(fill yes)
		(layer "In2.Cu")
		(net "M_C_CPU0_SA_DQS_DP<7>")
	)
	(gr_poly
		(pts
			(xy 340.551262 -236.58576) (xy 340.451186 -236.485938) (xy 340.35111 -236.58576) (xy 340.35111 -236.633512)
			(xy 340.551262 -236.633512)
		)
		(stroke
			(width 0)
			(type solid)
		)
		(fill yes)
		(layer "In2.Cu")
		(net "M_C_CPU0_SA_DQS_DP<2>")
	)
	(gr_poly
		(pts
			(xy 340.551262 -236.182154) (xy 340.551262 -236.137704) (xy 340.35111 -236.137704) (xy 340.35111 -236.182154)
			(xy 340.451186 -236.28223)
		)
		(stroke
			(width 0)
			(type solid)
		)
		(fill yes)
		(layer "In2.Cu")
		(net "M_C_CPU0_SA_DQ<19>")
	)
	(gr_poly
		(pts
			(xy 340.551262 -234.966002) (xy 340.451186 -234.865926) (xy 340.35111 -234.966002) (xy 340.35111 -235.010452)
			(xy 340.551262 -235.010452)
		)
		(stroke
			(width 0)
			(type solid)
		)
		(fill yes)
		(layer "In2.Cu")
		(net "M_C_CPU0_SA_DQ<16>")
	)
	(gr_poly
		(pts
			(xy 340.551262 -234.562142) (xy 340.551262 -234.517692) (xy 340.35111 -234.517692) (xy 340.35111 -234.562142)
			(xy 340.451186 -234.662218)
		)
		(stroke
			(width 0)
			(type solid)
		)
		(fill yes)
		(layer "In2.Cu")
		(net "M_C_CPU0_SA_DQ<15>")
	)
	(gr_poly
		(pts
			(xy 340.551262 -233.34599) (xy 340.451186 -233.245914) (xy 340.35111 -233.34599) (xy 340.35111 -233.39044)
			(xy 340.551262 -233.39044)
		)
		(stroke
			(width 0)
			(type solid)
		)
		(fill yes)
		(layer "In2.Cu")
		(net "M_C_CPU0_SA_DQ<12>")
	)
	(gr_poly
		(pts
			(xy 340.551262 -232.942384) (xy 340.551262 -232.894632) (xy 340.35111 -232.894632) (xy 340.35111 -232.942384)
			(xy 340.451186 -233.042206)
		)
		(stroke
			(width 0)
			(type solid)
		)
		(fill yes)
		(layer "In2.Cu")
		(net "M_C_CPU0_SA_DQS_DP<6>")
	)
	(gr_poly
		(pts
			(xy 340.551262 -231.725724) (xy 340.451186 -231.625902) (xy 340.35111 -231.725724) (xy 340.35111 -231.773476)
			(xy 340.551262 -231.773476)
		)
		(stroke
			(width 0)
			(type solid)
		)
		(fill yes)
		(layer "In2.Cu")
		(net "M_C_CPU0_SA_DQS_DP<1>")
	)
	(gr_poly
		(pts
			(xy 340.551262 -231.322372) (xy 340.551262 -231.277922) (xy 340.35111 -231.277922) (xy 340.35111 -231.322372)
			(xy 340.451186 -231.422448)
		)
		(stroke
			(width 0)
			(type solid)
		)
		(fill yes)
		(layer "In2.Cu")
		(net "M_C_CPU0_SA_DQ<11>")
	)
	(gr_poly
		(pts
			(xy 340.551262 -230.105966) (xy 340.451186 -230.006144) (xy 340.35111 -230.105966) (xy 340.35111 -230.150416)
			(xy 340.551262 -230.150416)
		)
		(stroke
			(width 0)
			(type solid)
		)
		(fill yes)
		(layer "In2.Cu")
		(net "M_C_CPU0_SA_DQ<8>")
	)
	(gr_poly
		(pts
			(xy 340.551262 -229.70236) (xy 340.551262 -229.65791) (xy 340.35111 -229.65791) (xy 340.35111 -229.70236)
			(xy 340.451186 -229.802436)
		)
		(stroke
			(width 0)
			(type solid)
		)
		(fill yes)
		(layer "In2.Cu")
		(net "M_C_CPU0_SA_DQ<7>")
	)
	(gr_poly
		(pts
			(xy 340.551262 -228.486208) (xy 340.451186 -228.386132) (xy 340.35111 -228.486208) (xy 340.35111 -228.530658)
			(xy 340.551262 -228.530658)
		)
		(stroke
			(width 0)
			(type solid)
		)
		(fill yes)
		(layer "In2.Cu")
		(net "M_C_CPU0_SA_DQ<4>")
	)
	(gr_poly
		(pts
			(xy 340.551262 -228.082602) (xy 340.551262 -228.03485) (xy 340.35111 -228.03485) (xy 340.35111 -228.082602)
			(xy 340.451186 -228.182424)
		)
		(stroke
			(width 0)
			(type solid)
		)
		(fill yes)
		(layer "In2.Cu")
		(net "M_C_CPU0_SA_DQS_DP<5>")
	)
	(gr_poly
		(pts
			(xy 340.551262 -226.865942) (xy 340.451186 -226.76612) (xy 340.35111 -226.865942) (xy 340.35111 -226.913694)
			(xy 340.551262 -226.913694)
		)
		(stroke
			(width 0)
			(type solid)
		)
		(fill yes)
		(layer "In2.Cu")
		(net "M_C_CPU0_SA_DQS_DP<0>")
	)
	(gr_poly
		(pts
			(xy 340.551262 -226.462336) (xy 340.551262 -226.417886) (xy 340.35111 -226.417886) (xy 340.35111 -226.462336)
			(xy 340.451186 -226.562412)
		)
		(stroke
			(width 0)
			(type solid)
		)
		(fill yes)
		(layer "In2.Cu")
		(net "M_C_CPU0_SA_DQ<3>")
	)
	(gr_poly
		(pts
			(xy 340.551262 -225.246184) (xy 340.451186 -225.146108) (xy 340.35111 -225.246184) (xy 340.35111 -225.290634)
			(xy 340.551262 -225.290634)
		)
		(stroke
			(width 0)
			(type solid)
		)
		(fill yes)
		(layer "In2.Cu")
		(net "M_C_CPU0_SA_DQ<0>")
	)
	(gr_poly
		(pts
			(xy 340.844886 -266.991592) (xy 340.74481 -266.891516) (xy 340.644988 -266.991592) (xy 340.644988 -267.036042)
			(xy 340.844886 -267.036042)
		)
		(stroke
			(width 0)
			(type solid)
		)
		(fill yes)
		(layer "In2.Cu")
		(net "M_C_CPU0_SA_RSP<0>")
	)
	(gr_poly
		(pts
			(xy 340.851236 -292.91788) (xy 340.75116 -292.817804) (xy 340.651084 -292.91788) (xy 340.651084 -292.96233)
			(xy 340.851236 -292.96233)
		)
		(stroke
			(width 0)
			(type solid)
		)
		(fill yes)
		(layer "In2.Cu")
		(net "M_C_CPU0_SB_DQ<29>")
	)
	(gr_poly
		(pts
			(xy 340.851236 -292.51402) (xy 340.851236 -292.46957) (xy 340.651084 -292.46957) (xy 340.651084 -292.51402)
			(xy 340.75116 -292.614096)
		)
		(stroke
			(width 0)
			(type solid)
		)
		(fill yes)
		(layer "In2.Cu")
		(net "M_C_CPU0_SB_DQ<30>")
	)
	(gr_poly
		(pts
			(xy 340.851236 -291.297614) (xy 340.75116 -291.197792) (xy 340.651084 -291.297614) (xy 340.651084 -291.345366)
			(xy 340.851236 -291.345366)
		)
		(stroke
			(width 0)
			(type solid)
		)
		(fill yes)
		(layer "In2.Cu")
		(net "M_C_CPU0_SB_DQS_DN<8>")
	)
	(gr_poly
		(pts
			(xy 340.851236 -290.894262) (xy 340.851236 -290.84651) (xy 340.651084 -290.84651) (xy 340.651084 -290.894262)
			(xy 340.75116 -290.994084)
		)
		(stroke
			(width 0)
			(type solid)
		)
		(fill yes)
		(layer "In2.Cu")
		(net "M_C_CPU0_SB_DQS_DN<3>")
	)
	(gr_poly
		(pts
			(xy 340.851236 -289.677856) (xy 340.75116 -289.57778) (xy 340.651084 -289.677856) (xy 340.651084 -289.722306)
			(xy 340.851236 -289.722306)
		)
		(stroke
			(width 0)
			(type solid)
		)
		(fill yes)
		(layer "In2.Cu")
		(net "M_C_CPU0_SB_DQ<25>")
	)
	(gr_poly
		(pts
			(xy 340.851236 -289.273996) (xy 340.851236 -289.229546) (xy 340.651084 -289.229546) (xy 340.651084 -289.273996)
			(xy 340.75116 -289.374072)
		)
		(stroke
			(width 0)
			(type solid)
		)
		(fill yes)
		(layer "In2.Cu")
		(net "M_C_CPU0_SB_DQ<26>")
	)
	(gr_poly
		(pts
			(xy 340.851236 -288.057844) (xy 340.75116 -287.957768) (xy 340.651084 -288.057844) (xy 340.651084 -288.102294)
			(xy 340.851236 -288.102294)
		)
		(stroke
			(width 0)
			(type solid)
		)
		(fill yes)
		(layer "In2.Cu")
		(net "M_C_CPU0_SB_DQ<21>")
	)
	(gr_poly
		(pts
			(xy 340.851236 -287.654238) (xy 340.851236 -287.609788) (xy 340.651084 -287.609788) (xy 340.651084 -287.654238)
			(xy 340.75116 -287.75406)
		)
		(stroke
			(width 0)
			(type solid)
		)
		(fill yes)
		(layer "In2.Cu")
		(net "M_C_CPU0_SB_DQ<22>")
	)
	(gr_poly
		(pts
			(xy 340.851236 -286.437832) (xy 340.75116 -286.337756) (xy 340.651084 -286.437832) (xy 340.651084 -286.485584)
			(xy 340.851236 -286.485584)
		)
		(stroke
			(width 0)
			(type solid)
		)
		(fill yes)
		(layer "In2.Cu")
		(net "M_C_CPU0_SB_DQS_DN<7>")
	)
	(gr_poly
		(pts
			(xy 340.851236 -286.03448) (xy 340.851236 -285.986728) (xy 340.651084 -285.986728) (xy 340.651084 -286.03448)
			(xy 340.75116 -286.134302)
		)
		(stroke
			(width 0)
			(type solid)
		)
		(fill yes)
		(layer "In2.Cu")
		(net "M_C_CPU0_SB_DQS_DN<2>")
	)
	(gr_poly
		(pts
			(xy 340.851236 -284.818074) (xy 340.75116 -284.717998) (xy 340.651084 -284.818074) (xy 340.651084 -284.862524)
			(xy 340.851236 -284.862524)
		)
		(stroke
			(width 0)
			(type solid)
		)
		(fill yes)
		(layer "In2.Cu")
		(net "M_C_CPU0_SB_DQ<17>")
	)
	(gr_poly
		(pts
			(xy 340.851236 -284.414214) (xy 340.851236 -284.369764) (xy 340.651084 -284.369764) (xy 340.651084 -284.414214)
			(xy 340.75116 -284.51429)
		)
		(stroke
			(width 0)
			(type solid)
		)
		(fill yes)
		(layer "In2.Cu")
		(net "M_C_CPU0_SB_DQ<18>")
	)
	(gr_poly
		(pts
			(xy 340.851236 -283.198062) (xy 340.75116 -283.097986) (xy 340.651084 -283.198062) (xy 340.651084 -283.242512)
			(xy 340.851236 -283.242512)
		)
		(stroke
			(width 0)
			(type solid)
		)
		(fill yes)
		(layer "In2.Cu")
		(net "M_C_CPU0_SB_DQ<13>")
	)
	(gr_poly
		(pts
			(xy 340.851236 -282.794202) (xy 340.851236 -282.749752) (xy 340.651084 -282.749752) (xy 340.651084 -282.794202)
			(xy 340.75116 -282.894278)
		)
		(stroke
			(width 0)
			(type solid)
		)
		(fill yes)
		(layer "In2.Cu")
		(net "M_C_CPU0_SB_DQ<14>")
	)
	(gr_poly
		(pts
			(xy 340.851236 -281.577796) (xy 340.75116 -281.477974) (xy 340.651084 -281.577796) (xy 340.651084 -281.625548)
			(xy 340.851236 -281.625548)
		)
		(stroke
			(width 0)
			(type solid)
		)
		(fill yes)
		(layer "In2.Cu")
		(net "M_C_CPU0_SB_DQS_DN<6>")
	)
	(gr_poly
		(pts
			(xy 340.851236 -281.174444) (xy 340.851236 -281.126692) (xy 340.651084 -281.126692) (xy 340.651084 -281.174444)
			(xy 340.75116 -281.274266)
		)
		(stroke
			(width 0)
			(type solid)
		)
		(fill yes)
		(layer "In2.Cu")
		(net "M_C_CPU0_SB_DQS_DN<1>")
	)
	(gr_poly
		(pts
			(xy 340.851236 -279.958038) (xy 340.75116 -279.857962) (xy 340.651084 -279.958038) (xy 340.651084 -280.002488)
			(xy 340.851236 -280.002488)
		)
		(stroke
			(width 0)
			(type solid)
		)
		(fill yes)
		(layer "In2.Cu")
		(net "M_C_CPU0_SB_DQ<9>")
	)
	(gr_poly
		(pts
			(xy 340.851236 -279.554178) (xy 340.851236 -279.509728) (xy 340.651084 -279.509728) (xy 340.651084 -279.554178)
			(xy 340.75116 -279.654254)
		)
		(stroke
			(width 0)
			(type solid)
		)
		(fill yes)
		(layer "In2.Cu")
		(net "M_C_CPU0_SB_DQ<10>")
	)
	(gr_poly
		(pts
			(xy 340.851236 -278.338026) (xy 340.75116 -278.23795) (xy 340.651084 -278.338026) (xy 340.651084 -278.382476)
			(xy 340.851236 -278.382476)
		)
		(stroke
			(width 0)
			(type solid)
		)
		(fill yes)
		(layer "In2.Cu")
		(net "M_C_CPU0_SB_DQ<5>")
	)
	(gr_poly
		(pts
			(xy 340.851236 -277.934166) (xy 340.851236 -277.889716) (xy 340.651084 -277.889716) (xy 340.651084 -277.934166)
			(xy 340.75116 -278.034242)
		)
		(stroke
			(width 0)
			(type solid)
		)
		(fill yes)
		(layer "In2.Cu")
		(net "M_C_CPU0_SB_DQ<6>")
	)
	(gr_poly
		(pts
			(xy 340.851236 -276.71776) (xy 340.75116 -276.617938) (xy 340.651084 -276.71776) (xy 340.651084 -276.765512)
			(xy 340.851236 -276.765512)
		)
		(stroke
			(width 0)
			(type solid)
		)
		(fill yes)
		(layer "In2.Cu")
		(net "M_C_CPU0_SB_DQS_DN<5>")
	)
	(gr_poly
		(pts
			(xy 340.851236 -276.314408) (xy 340.851236 -276.266656) (xy 340.651084 -276.266656) (xy 340.651084 -276.314408)
			(xy 340.75116 -276.41423)
		)
		(stroke
			(width 0)
			(type solid)
		)
		(fill yes)
		(layer "In2.Cu")
		(net "M_C_CPU0_SB_DQS_DN<0>")
	)
	(gr_poly
		(pts
			(xy 340.851236 -275.098002) (xy 340.75116 -274.997926) (xy 340.651084 -275.098002) (xy 340.651084 -275.142452)
			(xy 340.851236 -275.142452)
		)
		(stroke
			(width 0)
			(type solid)
		)
		(fill yes)
		(layer "In2.Cu")
		(net "M_C_CPU0_SB_DQ<1>")
	)
	(gr_poly
		(pts
			(xy 340.851236 -274.694142) (xy 340.851236 -274.649692) (xy 340.651084 -274.649692) (xy 340.651084 -274.694142)
			(xy 340.75116 -274.794218)
		)
		(stroke
			(width 0)
			(type solid)
		)
		(fill yes)
		(layer "In2.Cu")
		(net "M_C_CPU0_SB_DQ<2>")
	)
	(gr_poly
		(pts
			(xy 340.851236 -273.47799) (xy 340.75116 -273.377914) (xy 340.651084 -273.47799) (xy 340.651084 -273.52244)
			(xy 340.851236 -273.52244)
		)
		(stroke
			(width 0)
			(type solid)
		)
		(fill yes)
		(layer "In2.Cu")
		(net "M_C_CPU0_SB_CB<1>")
	)
	(gr_poly
		(pts
			(xy 340.851236 -273.07413) (xy 340.851236 -273.02968) (xy 340.651084 -273.02968) (xy 340.651084 -273.07413)
			(xy 340.75116 -273.174206)
		)
		(stroke
			(width 0)
			(type solid)
		)
		(fill yes)
		(layer "In2.Cu")
		(net "M_C_CPU0_SB_CB<2>")
	)
	(gr_poly
		(pts
			(xy 340.851236 -271.857724) (xy 340.75116 -271.757902) (xy 340.651084 -271.857724) (xy 340.651084 -271.905476)
			(xy 340.851236 -271.905476)
		)
		(stroke
			(width 0)
			(type solid)
		)
		(fill yes)
		(layer "In2.Cu")
		(net "M_C_CPU0_SB_DQS_DN<4>")
	)
	(gr_poly
		(pts
			(xy 340.851236 -271.454372) (xy 340.851236 -271.40662) (xy 340.651084 -271.40662) (xy 340.651084 -271.454372)
			(xy 340.75116 -271.554194)
		)
		(stroke
			(width 0)
			(type solid)
		)
		(fill yes)
		(layer "In2.Cu")
		(net "M_C_CPU0_SB_DQS_DN<9>")
	)
	(gr_poly
		(pts
			(xy 340.851236 -270.237966) (xy 340.75116 -270.13789) (xy 340.651084 -270.237966) (xy 340.651084 -270.282416)
			(xy 340.851236 -270.282416)
		)
		(stroke
			(width 0)
			(type solid)
		)
		(fill yes)
		(layer "In2.Cu")
		(net "M_C_CPU0_SB_CB<5>")
	)
	(gr_poly
		(pts
			(xy 340.851236 -269.834106) (xy 340.851236 -269.789656) (xy 340.651084 -269.789656) (xy 340.651084 -269.834106)
			(xy 340.75116 -269.934182)
		)
		(stroke
			(width 0)
			(type solid)
		)
		(fill yes)
		(layer "In2.Cu")
		(net "M_C_CPU0_SB_CB<6>")
	)
	(gr_poly
		(pts
			(xy 340.851236 -266.594082) (xy 340.851236 -266.549632) (xy 340.651084 -266.549632) (xy 340.651084 -266.594082)
			(xy 340.75116 -266.694158)
		)
		(stroke
			(width 0)
			(type solid)
		)
		(fill yes)
		(layer "In2.Cu")
		(net "M_C_CPU0_SB_CS_N<1>")
	)
	(gr_poly
		(pts
			(xy 340.851236 -264.97407) (xy 340.851236 -264.92962) (xy 340.651084 -264.92962) (xy 340.651084 -264.97407)
			(xy 340.75116 -265.074146)
		)
		(stroke
			(width 0)
			(type solid)
		)
		(fill yes)
		(layer "In2.Cu")
		(net "M_C_CPU0_SB_PAR")
	)
	(gr_poly
		(pts
			(xy 340.851236 -263.757918) (xy 340.75116 -263.657842) (xy 340.651084 -263.757918) (xy 340.651084 -263.802368)
			(xy 340.851236 -263.802368)
		)
		(stroke
			(width 0)
			(type solid)
		)
		(fill yes)
		(layer "In2.Cu")
		(net "M_C_CPU0_SB_CA<4>")
	)
	(gr_poly
		(pts
			(xy 340.851236 -263.354058) (xy 340.851236 -263.309608) (xy 340.651084 -263.309608) (xy 340.651084 -263.354058)
			(xy 340.75116 -263.454134)
		)
		(stroke
			(width 0)
			(type solid)
		)
		(fill yes)
		(layer "In2.Cu")
		(net "M_C_CPU0_SB_CA<3>")
	)
	(gr_poly
		(pts
			(xy 340.851236 -262.137906) (xy 340.75116 -262.03783) (xy 340.651084 -262.137906) (xy 340.651084 -262.182356)
			(xy 340.851236 -262.182356)
		)
		(stroke
			(width 0)
			(type solid)
		)
		(fill yes)
		(layer "In2.Cu")
		(net "M_C_CPU0_SB_CA<0>")
	)
	(gr_poly
		(pts
			(xy 341.020908 -246.712232) (xy 341.020908 -246.664734) (xy 340.82101 -246.664734) (xy 340.82101 -246.712232)
			(xy 340.920832 -246.812308)
		)
		(stroke
			(width 0)
			(type solid)
		)
		(fill yes)
		(layer "In2.Cu")
		(net "M_C_CPU0_SA_DQS_DN<4>")
	)
	(gr_poly
		(pts
			(xy 341.021162 -256.432558) (xy 341.021162 -256.384806) (xy 340.82101 -256.384806) (xy 340.82101 -256.432558)
			(xy 340.921086 -256.53238)
		)
		(stroke
			(width 0)
			(type solid)
		)
		(fill yes)
		(layer "In2.Cu")
		(net "M_C_CPU0_CLK_DN<0>")
	)
	(gr_poly
		(pts
			(xy 341.021162 -255.216152) (xy 340.921086 -255.116076) (xy 340.82101 -255.216152) (xy 340.82101 -255.260602)
			(xy 341.021162 -255.260602)
		)
		(stroke
			(width 0)
			(type solid)
		)
		(fill yes)
		(layer "In2.Cu")
		(net "M_C_CPU0_SA_CA<6>")
	)
	(gr_poly
		(pts
			(xy 341.021162 -254.812292) (xy 341.021162 -254.767842) (xy 340.82101 -254.767842) (xy 340.82101 -254.812292)
			(xy 340.921086 -254.912368)
		)
		(stroke
			(width 0)
			(type solid)
		)
		(fill yes)
		(layer "In2.Cu")
		(net "M_C_CPU0_SA_CA<5>")
	)
	(gr_poly
		(pts
			(xy 341.021162 -253.59614) (xy 340.921086 -253.496064) (xy 340.82101 -253.59614) (xy 340.82101 -253.64059)
			(xy 341.021162 -253.64059)
		)
		(stroke
			(width 0)
			(type solid)
		)
		(fill yes)
		(layer "In2.Cu")
		(net "M_C_CPU0_SA_CA<2>")
	)
	(gr_poly
		(pts
			(xy 341.021162 -253.19228) (xy 341.021162 -253.14783) (xy 340.82101 -253.14783) (xy 340.82101 -253.19228)
			(xy 340.921086 -253.292356)
		)
		(stroke
			(width 0)
			(type solid)
		)
		(fill yes)
		(layer "In2.Cu")
		(net "M_C_CPU0_SA_CA<1>")
	)
	(gr_poly
		(pts
			(xy 341.021162 -251.572268) (xy 341.021162 -251.527818) (xy 340.82101 -251.527818) (xy 340.82101 -251.572268)
			(xy 340.921086 -251.672344)
		)
		(stroke
			(width 0)
			(type solid)
		)
		(fill yes)
		(layer "In2.Cu")
		(net "M_C_CPU0_SA_CS_N<0>")
	)
	(gr_poly
		(pts
			(xy 341.021162 -250.356116) (xy 340.921086 -250.25604) (xy 340.82101 -250.356116) (xy 340.82101 -250.400566)
			(xy 341.021162 -250.400566)
		)
		(stroke
			(width 0)
			(type solid)
		)
		(fill yes)
		(layer "In2.Cu")
		(net "M_C_CPU0_ALERT_R_N")
	)
	(gr_poly
		(pts
			(xy 341.021162 -248.736104) (xy 340.921086 -248.636028) (xy 340.82101 -248.736104) (xy 340.82101 -248.780554)
			(xy 341.021162 -248.780554)
		)
		(stroke
			(width 0)
			(type solid)
		)
		(fill yes)
		(layer "In2.Cu")
		(net "M_C_CPU0_SA_CB<5>")
	)
	(gr_poly
		(pts
			(xy 341.021162 -248.332244) (xy 341.021162 -248.287794) (xy 340.82101 -248.287794) (xy 340.82101 -248.332244)
			(xy 340.921086 -248.43232)
		)
		(stroke
			(width 0)
			(type solid)
		)
		(fill yes)
		(layer "In2.Cu")
		(net "M_C_CPU0_SA_CB<6>")
	)
	(gr_poly
		(pts
			(xy 341.021162 -247.115838) (xy 340.921086 -247.016016) (xy 340.82101 -247.115838) (xy 340.82101 -247.16359)
			(xy 341.021162 -247.16359)
		)
		(stroke
			(width 0)
			(type solid)
		)
		(fill yes)
		(layer "In2.Cu")
		(net "M_C_CPU0_SA_DQS_DN<9>")
	)
	(gr_poly
		(pts
			(xy 341.021162 -245.49608) (xy 340.921086 -245.396004) (xy 340.82101 -245.49608) (xy 340.82101 -245.54053)
			(xy 341.021162 -245.54053)
		)
		(stroke
			(width 0)
			(type solid)
		)
		(fill yes)
		(layer "In2.Cu")
		(net "M_C_CPU0_SA_CB<1>")
	)
	(gr_poly
		(pts
			(xy 341.021162 -245.09222) (xy 341.021162 -245.04777) (xy 340.82101 -245.04777) (xy 340.82101 -245.09222)
			(xy 340.921086 -245.192296)
		)
		(stroke
			(width 0)
			(type solid)
		)
		(fill yes)
		(layer "In2.Cu")
		(net "M_C_CPU0_SA_CB<2>")
	)
	(gr_poly
		(pts
			(xy 341.021162 -243.876068) (xy 340.921086 -243.775992) (xy 340.82101 -243.876068) (xy 340.82101 -243.920518)
			(xy 341.021162 -243.920518)
		)
		(stroke
			(width 0)
			(type solid)
		)
		(fill yes)
		(layer "In2.Cu")
		(net "M_C_CPU0_SA_DQ<29>")
	)
	(gr_poly
		(pts
			(xy 341.021162 -243.472208) (xy 341.021162 -243.427758) (xy 340.82101 -243.427758) (xy 340.82101 -243.472208)
			(xy 340.921086 -243.572284)
		)
		(stroke
			(width 0)
			(type solid)
		)
		(fill yes)
		(layer "In2.Cu")
		(net "M_C_CPU0_SA_DQ<30>")
	)
	(gr_poly
		(pts
			(xy 341.021162 -242.255802) (xy 340.921086 -242.15598) (xy 340.82101 -242.255802) (xy 340.82101 -242.303554)
			(xy 341.021162 -242.303554)
		)
		(stroke
			(width 0)
			(type solid)
		)
		(fill yes)
		(layer "In2.Cu")
		(net "M_C_CPU0_SA_DQS_DN<8>")
	)
	(gr_poly
		(pts
			(xy 341.021162 -241.85245) (xy 341.021162 -241.804698) (xy 340.82101 -241.804698) (xy 340.82101 -241.85245)
			(xy 340.921086 -241.952272)
		)
		(stroke
			(width 0)
			(type solid)
		)
		(fill yes)
		(layer "In2.Cu")
		(net "M_C_CPU0_SA_DQS_DN<3>")
	)
	(gr_poly
		(pts
			(xy 341.021162 -240.636044) (xy 340.921086 -240.535968) (xy 340.82101 -240.636044) (xy 340.82101 -240.680494)
			(xy 341.021162 -240.680494)
		)
		(stroke
			(width 0)
			(type solid)
		)
		(fill yes)
		(layer "In2.Cu")
		(net "M_C_CPU0_SA_DQ<25>")
	)
	(gr_poly
		(pts
			(xy 341.021162 -240.232184) (xy 341.021162 -240.187734) (xy 340.82101 -240.187734) (xy 340.82101 -240.232184)
			(xy 340.921086 -240.33226)
		)
		(stroke
			(width 0)
			(type solid)
		)
		(fill yes)
		(layer "In2.Cu")
		(net "M_C_CPU0_SA_DQ<26>")
	)
	(gr_poly
		(pts
			(xy 341.021162 -239.016032) (xy 340.921086 -238.915956) (xy 340.82101 -239.016032) (xy 340.82101 -239.060482)
			(xy 341.021162 -239.060482)
		)
		(stroke
			(width 0)
			(type solid)
		)
		(fill yes)
		(layer "In2.Cu")
		(net "M_C_CPU0_SA_DQ<21>")
	)
	(gr_poly
		(pts
			(xy 341.021162 -238.612172) (xy 341.021162 -238.567722) (xy 340.82101 -238.567722) (xy 340.82101 -238.612172)
			(xy 340.921086 -238.712248)
		)
		(stroke
			(width 0)
			(type solid)
		)
		(fill yes)
		(layer "In2.Cu")
		(net "M_C_CPU0_SA_DQ<22>")
	)
	(gr_poly
		(pts
			(xy 341.021162 -237.395766) (xy 340.921086 -237.295944) (xy 340.82101 -237.395766) (xy 340.82101 -237.443518)
			(xy 341.021162 -237.443518)
		)
		(stroke
			(width 0)
			(type solid)
		)
		(fill yes)
		(layer "In2.Cu")
		(net "M_C_CPU0_SA_DQS_DN<7>")
	)
	(gr_poly
		(pts
			(xy 341.021162 -236.992414) (xy 341.021162 -236.944662) (xy 340.82101 -236.944662) (xy 340.82101 -236.992414)
			(xy 340.921086 -237.092236)
		)
		(stroke
			(width 0)
			(type solid)
		)
		(fill yes)
		(layer "In2.Cu")
		(net "M_C_CPU0_SA_DQS_DN<2>")
	)
	(gr_poly
		(pts
			(xy 341.021162 -235.776008) (xy 340.921086 -235.675932) (xy 340.82101 -235.776008) (xy 340.82101 -235.820458)
			(xy 341.021162 -235.820458)
		)
		(stroke
			(width 0)
			(type solid)
		)
		(fill yes)
		(layer "In2.Cu")
		(net "M_C_CPU0_SA_DQ<17>")
	)
	(gr_poly
		(pts
			(xy 341.021162 -235.372148) (xy 341.021162 -235.327698) (xy 340.82101 -235.327698) (xy 340.82101 -235.372148)
			(xy 340.921086 -235.472224)
		)
		(stroke
			(width 0)
			(type solid)
		)
		(fill yes)
		(layer "In2.Cu")
		(net "M_C_CPU0_SA_DQ<18>")
	)
	(gr_poly
		(pts
			(xy 341.021162 -234.155996) (xy 340.921086 -234.05592) (xy 340.82101 -234.155996) (xy 340.82101 -234.200446)
			(xy 341.021162 -234.200446)
		)
		(stroke
			(width 0)
			(type solid)
		)
		(fill yes)
		(layer "In2.Cu")
		(net "M_C_CPU0_SA_DQ<13>")
	)
	(gr_poly
		(pts
			(xy 341.021162 -233.752136) (xy 341.021162 -233.707686) (xy 340.82101 -233.707686) (xy 340.82101 -233.752136)
			(xy 340.921086 -233.852212)
		)
		(stroke
			(width 0)
			(type solid)
		)
		(fill yes)
		(layer "In2.Cu")
		(net "M_C_CPU0_SA_DQ<14>")
	)
	(gr_poly
		(pts
			(xy 341.021162 -232.53573) (xy 340.921086 -232.435908) (xy 340.82101 -232.53573) (xy 340.82101 -232.583482)
			(xy 341.021162 -232.583482)
		)
		(stroke
			(width 0)
			(type solid)
		)
		(fill yes)
		(layer "In2.Cu")
		(net "M_C_CPU0_SA_DQS_DN<6>")
	)
	(gr_poly
		(pts
			(xy 341.021162 -232.132378) (xy 341.021162 -232.084626) (xy 340.82101 -232.084626) (xy 340.82101 -232.132378)
			(xy 340.921086 -232.2322)
		)
		(stroke
			(width 0)
			(type solid)
		)
		(fill yes)
		(layer "In2.Cu")
		(net "M_C_CPU0_SA_DQS_DN<1>")
	)
	(gr_poly
		(pts
			(xy 341.021162 -230.915972) (xy 340.921086 -230.815896) (xy 340.82101 -230.915972) (xy 340.82101 -230.960422)
			(xy 341.021162 -230.960422)
		)
		(stroke
			(width 0)
			(type solid)
		)
		(fill yes)
		(layer "In2.Cu")
		(net "M_C_CPU0_SA_DQ<9>")
	)
	(gr_poly
		(pts
			(xy 341.021162 -230.512366) (xy 341.021162 -230.467916) (xy 340.82101 -230.467916) (xy 340.82101 -230.512366)
			(xy 340.921086 -230.612188)
		)
		(stroke
			(width 0)
			(type solid)
		)
		(fill yes)
		(layer "In2.Cu")
		(net "M_C_CPU0_SA_DQ<10>")
	)
	(gr_poly
		(pts
			(xy 341.021162 -229.29596) (xy 340.921086 -229.195884) (xy 340.82101 -229.29596) (xy 340.82101 -229.34041)
			(xy 341.021162 -229.34041)
		)
		(stroke
			(width 0)
			(type solid)
		)
		(fill yes)
		(layer "In2.Cu")
		(net "M_C_CPU0_SA_DQ<5>")
	)
	(gr_poly
		(pts
			(xy 341.021162 -228.892354) (xy 341.021162 -228.847904) (xy 340.82101 -228.847904) (xy 340.82101 -228.892354)
			(xy 340.921086 -228.99243)
		)
		(stroke
			(width 0)
			(type solid)
		)
		(fill yes)
		(layer "In2.Cu")
		(net "M_C_CPU0_SA_DQ<6>")
	)
	(gr_poly
		(pts
			(xy 341.021162 -227.675948) (xy 340.921086 -227.576126) (xy 340.82101 -227.675948) (xy 340.82101 -227.7237)
			(xy 341.021162 -227.7237)
		)
		(stroke
			(width 0)
			(type solid)
		)
		(fill yes)
		(layer "In2.Cu")
		(net "M_C_CPU0_SA_DQS_DN<5>")
	)
	(gr_poly
		(pts
			(xy 341.021162 -227.272596) (xy 341.021162 -227.224844) (xy 340.82101 -227.224844) (xy 340.82101 -227.272596)
			(xy 340.921086 -227.372418)
		)
		(stroke
			(width 0)
			(type solid)
		)
		(fill yes)
		(layer "In2.Cu")
		(net "M_C_CPU0_SA_DQS_DN<0>")
	)
	(gr_poly
		(pts
			(xy 341.021162 -226.05619) (xy 340.921086 -225.956114) (xy 340.82101 -226.05619) (xy 340.82101 -226.10064)
			(xy 341.021162 -226.10064)
		)
		(stroke
			(width 0)
			(type solid)
		)
		(fill yes)
		(layer "In2.Cu")
		(net "M_C_CPU0_SA_DQ<1>")
	)
	(gr_poly
		(pts
			(xy 341.021162 -225.65233) (xy 341.021162 -225.60788) (xy 340.82101 -225.60788) (xy 340.82101 -225.65233)
			(xy 340.921086 -225.752406)
		)
		(stroke
			(width 0)
			(type solid)
		)
		(fill yes)
		(layer "In2.Cu")
		(net "M_C_CPU0_SA_DQ<2>")
	)
	(gr_poly
		(pts
			(xy 341.321136 -293.324026) (xy 341.321136 -293.279576) (xy 341.120984 -293.279576) (xy 341.120984 -293.324026)
			(xy 341.22106 -293.424102)
		)
		(stroke
			(width 0)
			(type solid)
		)
		(fill yes)
		(layer "In2.Cu")
		(net "M_C_CPU0_SB_DQ<31>")
	)
	(gr_poly
		(pts
			(xy 341.321136 -292.107874) (xy 341.22106 -292.007798) (xy 341.120984 -292.107874) (xy 341.120984 -292.152324)
			(xy 341.321136 -292.152324)
		)
		(stroke
			(width 0)
			(type solid)
		)
		(fill yes)
		(layer "In2.Cu")
		(net "M_C_CPU0_SB_DQ<28>")
	)
	(gr_poly
		(pts
			(xy 341.321136 -291.704268) (xy 341.321136 -291.656516) (xy 341.120984 -291.656516) (xy 341.120984 -291.704268)
			(xy 341.22106 -291.80409)
		)
		(stroke
			(width 0)
			(type solid)
		)
		(fill yes)
		(layer "In2.Cu")
		(net "M_C_CPU0_SB_DQS_DP<8>")
	)
	(gr_poly
		(pts
			(xy 341.321136 -290.487608) (xy 341.22106 -290.387786) (xy 341.120984 -290.487608) (xy 341.120984 -290.53536)
			(xy 341.321136 -290.53536)
		)
		(stroke
			(width 0)
			(type solid)
		)
		(fill yes)
		(layer "In2.Cu")
		(net "M_C_CPU0_SB_DQS_DP<3>")
	)
	(gr_poly
		(pts
			(xy 341.321136 -290.084002) (xy 341.321136 -290.039552) (xy 341.120984 -290.039552) (xy 341.120984 -290.084002)
			(xy 341.22106 -290.184078)
		)
		(stroke
			(width 0)
			(type solid)
		)
		(fill yes)
		(layer "In2.Cu")
		(net "M_C_CPU0_SB_DQ<27>")
	)
	(gr_poly
		(pts
			(xy 341.321136 -288.86785) (xy 341.22106 -288.767774) (xy 341.120984 -288.86785) (xy 341.120984 -288.9123)
			(xy 341.321136 -288.9123)
		)
		(stroke
			(width 0)
			(type solid)
		)
		(fill yes)
		(layer "In2.Cu")
		(net "M_C_CPU0_SB_DQ<24>")
	)
	(gr_poly
		(pts
			(xy 341.321136 -288.464244) (xy 341.321136 -288.419794) (xy 341.120984 -288.419794) (xy 341.120984 -288.464244)
			(xy 341.22106 -288.56432)
		)
		(stroke
			(width 0)
			(type solid)
		)
		(fill yes)
		(layer "In2.Cu")
		(net "M_C_CPU0_SB_DQ<23>")
	)
	(gr_poly
		(pts
			(xy 341.321136 -287.247838) (xy 341.22106 -287.148016) (xy 341.120984 -287.247838) (xy 341.120984 -287.292288)
			(xy 341.321136 -287.292288)
		)
		(stroke
			(width 0)
			(type solid)
		)
		(fill yes)
		(layer "In2.Cu")
		(net "M_C_CPU0_SB_DQ<20>")
	)
	(gr_poly
		(pts
			(xy 341.321136 -286.844232) (xy 341.321136 -286.79648) (xy 341.120984 -286.79648) (xy 341.120984 -286.844232)
			(xy 341.22106 -286.944308)
		)
		(stroke
			(width 0)
			(type solid)
		)
		(fill yes)
		(layer "In2.Cu")
		(net "M_C_CPU0_SB_DQS_DP<7>")
	)
	(gr_poly
		(pts
			(xy 341.321136 -285.627826) (xy 341.22106 -285.528004) (xy 341.120984 -285.627826) (xy 341.120984 -285.675578)
			(xy 341.321136 -285.675578)
		)
		(stroke
			(width 0)
			(type solid)
		)
		(fill yes)
		(layer "In2.Cu")
		(net "M_C_CPU0_SB_DQS_DP<2>")
	)
	(gr_poly
		(pts
			(xy 341.321136 -285.22422) (xy 341.321136 -285.17977) (xy 341.120984 -285.17977) (xy 341.120984 -285.22422)
			(xy 341.22106 -285.324296)
		)
		(stroke
			(width 0)
			(type solid)
		)
		(fill yes)
		(layer "In2.Cu")
		(net "M_C_CPU0_SB_DQ<19>")
	)
	(gr_poly
		(pts
			(xy 341.321136 -284.008068) (xy 341.22106 -283.907992) (xy 341.120984 -284.008068) (xy 341.120984 -284.052518)
			(xy 341.321136 -284.052518)
		)
		(stroke
			(width 0)
			(type solid)
		)
		(fill yes)
		(layer "In2.Cu")
		(net "M_C_CPU0_SB_DQ<16>")
	)
	(gr_poly
		(pts
			(xy 341.321136 -283.604208) (xy 341.321136 -283.559758) (xy 341.120984 -283.559758) (xy 341.120984 -283.604208)
			(xy 341.22106 -283.704284)
		)
		(stroke
			(width 0)
			(type solid)
		)
		(fill yes)
		(layer "In2.Cu")
		(net "M_C_CPU0_SB_DQ<15>")
	)
	(gr_poly
		(pts
			(xy 341.321136 -282.388056) (xy 341.22106 -282.28798) (xy 341.120984 -282.388056) (xy 341.120984 -282.432506)
			(xy 341.321136 -282.432506)
		)
		(stroke
			(width 0)
			(type solid)
		)
		(fill yes)
		(layer "In2.Cu")
		(net "M_C_CPU0_SB_DQ<12>")
	)
	(gr_poly
		(pts
			(xy 341.321136 -281.98445) (xy 341.321136 -281.936698) (xy 341.120984 -281.936698) (xy 341.120984 -281.98445)
			(xy 341.22106 -282.084272)
		)
		(stroke
			(width 0)
			(type solid)
		)
		(fill yes)
		(layer "In2.Cu")
		(net "M_C_CPU0_SB_DQS_DP<6>")
	)
	(gr_poly
		(pts
			(xy 341.321136 -280.76779) (xy 341.22106 -280.667968) (xy 341.120984 -280.76779) (xy 341.120984 -280.815542)
			(xy 341.321136 -280.815542)
		)
		(stroke
			(width 0)
			(type solid)
		)
		(fill yes)
		(layer "In2.Cu")
		(net "M_C_CPU0_SB_DQS_DP<1>")
	)
	(gr_poly
		(pts
			(xy 341.321136 -280.364184) (xy 341.321136 -280.319734) (xy 341.120984 -280.319734) (xy 341.120984 -280.364184)
			(xy 341.22106 -280.46426)
		)
		(stroke
			(width 0)
			(type solid)
		)
		(fill yes)
		(layer "In2.Cu")
		(net "M_C_CPU0_SB_DQ<11>")
	)
	(gr_poly
		(pts
			(xy 341.321136 -279.148032) (xy 341.22106 -279.047956) (xy 341.120984 -279.148032) (xy 341.120984 -279.192482)
			(xy 341.321136 -279.192482)
		)
		(stroke
			(width 0)
			(type solid)
		)
		(fill yes)
		(layer "In2.Cu")
		(net "M_C_CPU0_SB_DQ<8>")
	)
	(gr_poly
		(pts
			(xy 341.321136 -278.744172) (xy 341.321136 -278.699722) (xy 341.120984 -278.699722) (xy 341.120984 -278.744172)
			(xy 341.22106 -278.844248)
		)
		(stroke
			(width 0)
			(type solid)
		)
		(fill yes)
		(layer "In2.Cu")
		(net "M_C_CPU0_SB_DQ<7>")
	)
	(gr_poly
		(pts
			(xy 341.321136 -277.52802) (xy 341.22106 -277.427944) (xy 341.120984 -277.52802) (xy 341.120984 -277.57247)
			(xy 341.321136 -277.57247)
		)
		(stroke
			(width 0)
			(type solid)
		)
		(fill yes)
		(layer "In2.Cu")
		(net "M_C_CPU0_SB_DQ<4>")
	)
	(gr_poly
		(pts
			(xy 341.321136 -277.124414) (xy 341.321136 -277.076662) (xy 341.120984 -277.076662) (xy 341.120984 -277.124414)
			(xy 341.22106 -277.224236)
		)
		(stroke
			(width 0)
			(type solid)
		)
		(fill yes)
		(layer "In2.Cu")
		(net "M_C_CPU0_SB_DQS_DP<5>")
	)
	(gr_poly
		(pts
			(xy 341.321136 -275.907754) (xy 341.22106 -275.807932) (xy 341.120984 -275.907754) (xy 341.120984 -275.955506)
			(xy 341.321136 -275.955506)
		)
		(stroke
			(width 0)
			(type solid)
		)
		(fill yes)
		(layer "In2.Cu")
		(net "M_C_CPU0_SB_DQS_DP<0>")
	)
	(gr_poly
		(pts
			(xy 341.321136 -275.504148) (xy 341.321136 -275.459698) (xy 341.120984 -275.459698) (xy 341.120984 -275.504148)
			(xy 341.22106 -275.604224)
		)
		(stroke
			(width 0)
			(type solid)
		)
		(fill yes)
		(layer "In2.Cu")
		(net "M_C_CPU0_SB_DQ<3>")
	)
	(gr_poly
		(pts
			(xy 341.321136 -274.287996) (xy 341.22106 -274.18792) (xy 341.120984 -274.287996) (xy 341.120984 -274.332446)
			(xy 341.321136 -274.332446)
		)
		(stroke
			(width 0)
			(type solid)
		)
		(fill yes)
		(layer "In2.Cu")
		(net "M_C_CPU0_SB_DQ<0>")
	)
	(gr_poly
		(pts
			(xy 341.321136 -273.884136) (xy 341.321136 -273.839686) (xy 341.120984 -273.839686) (xy 341.120984 -273.884136)
			(xy 341.22106 -273.984212)
		)
		(stroke
			(width 0)
			(type solid)
		)
		(fill yes)
		(layer "In2.Cu")
		(net "M_C_CPU0_SB_CB<3>")
	)
	(gr_poly
		(pts
			(xy 341.321136 -272.667984) (xy 341.22106 -272.567908) (xy 341.120984 -272.667984) (xy 341.120984 -272.712434)
			(xy 341.321136 -272.712434)
		)
		(stroke
			(width 0)
			(type solid)
		)
		(fill yes)
		(layer "In2.Cu")
		(net "M_C_CPU0_SB_CB<0>")
	)
	(gr_poly
		(pts
			(xy 341.321136 -272.264378) (xy 341.321136 -272.216626) (xy 341.120984 -272.216626) (xy 341.120984 -272.264378)
			(xy 341.22106 -272.3642)
		)
		(stroke
			(width 0)
			(type solid)
		)
		(fill yes)
		(layer "In2.Cu")
		(net "M_C_CPU0_SB_DQS_DP<4>")
	)
	(gr_poly
		(pts
			(xy 341.321136 -271.047718) (xy 341.22106 -270.947896) (xy 341.120984 -271.047718) (xy 341.120984 -271.09547)
			(xy 341.321136 -271.09547)
		)
		(stroke
			(width 0)
			(type solid)
		)
		(fill yes)
		(layer "In2.Cu")
		(net "M_C_CPU0_SB_DQS_DP<9>")
	)
	(gr_poly
		(pts
			(xy 341.321136 -270.644112) (xy 341.321136 -270.599662) (xy 341.120984 -270.599662) (xy 341.120984 -270.644112)
			(xy 341.22106 -270.744188)
		)
		(stroke
			(width 0)
			(type solid)
		)
		(fill yes)
		(layer "In2.Cu")
		(net "M_C_CPU0_SB_CB<7>")
	)
	(gr_poly
		(pts
			(xy 341.321136 -269.42796) (xy 341.22106 -269.327884) (xy 341.120984 -269.42796) (xy 341.120984 -269.47241)
			(xy 341.321136 -269.47241)
		)
		(stroke
			(width 0)
			(type solid)
		)
		(fill yes)
		(layer "In2.Cu")
		(net "M_C_CPU0_SB_CB<4>")
	)
	(gr_poly
		(pts
			(xy 341.321136 -265.784076) (xy 341.321136 -265.739626) (xy 341.120984 -265.739626) (xy 341.120984 -265.784076)
			(xy 341.22106 -265.884152)
		)
		(stroke
			(width 0)
			(type solid)
		)
		(fill yes)
		(layer "In2.Cu")
		(net "M_C_CPU0_SB_CS_N<0>")
	)
	(gr_poly
		(pts
			(xy 341.321136 -264.567924) (xy 341.22106 -264.467848) (xy 341.120984 -264.567924) (xy 341.120984 -264.612374)
			(xy 341.321136 -264.612374)
		)
		(stroke
			(width 0)
			(type solid)
		)
		(fill yes)
		(layer "In2.Cu")
		(net "M_C_CPU0_SB_CA<6>")
	)
	(gr_poly
		(pts
			(xy 341.321136 -264.164064) (xy 341.321136 -264.119614) (xy 341.120984 -264.119614) (xy 341.120984 -264.164064)
			(xy 341.22106 -264.26414)
		)
		(stroke
			(width 0)
			(type solid)
		)
		(fill yes)
		(layer "In2.Cu")
		(net "M_C_CPU0_SB_CA<5>")
	)
	(gr_poly
		(pts
			(xy 341.321136 -262.947912) (xy 341.22106 -262.847836) (xy 341.120984 -262.947912) (xy 341.120984 -262.992362)
			(xy 341.321136 -262.992362)
		)
		(stroke
			(width 0)
			(type solid)
		)
		(fill yes)
		(layer "In2.Cu")
		(net "M_C_CPU0_SB_CA<2>")
	)
	(gr_poly
		(pts
			(xy 341.321136 -262.544052) (xy 341.321136 -262.499602) (xy 341.120984 -262.499602) (xy 341.120984 -262.544052)
			(xy 341.22106 -262.644128)
		)
		(stroke
			(width 0)
			(type solid)
		)
		(fill yes)
		(layer "In2.Cu")
		(net "M_C_CPU0_SB_CA<1>")
	)
	(gr_poly
		(pts
			(xy 341.327232 -267.801598) (xy 341.22741 -267.701522) (xy 341.127334 -267.801598) (xy 341.127334 -267.846048)
			(xy 341.327232 -267.846048)
		)
		(stroke
			(width 0)
			(type solid)
		)
		(fill yes)
		(layer "In2.Cu")
		(net "M_C_CPU0_SB_RSP<0>")
	)
	(gr_poly
		(pts
			(xy 341.491062 -256.025904) (xy 341.390986 -255.926082) (xy 341.29091 -256.025904) (xy 341.29091 -256.073656)
			(xy 341.491062 -256.073656)
		)
		(stroke
			(width 0)
			(type solid)
		)
		(fill yes)
		(layer "In2.Cu")
		(net "M_C_CPU0_CLK_DP<0>")
	)
	(gr_poly
		(pts
			(xy 341.491062 -255.622298) (xy 341.491062 -255.577848) (xy 341.29091 -255.577848) (xy 341.29091 -255.622298)
			(xy 341.390986 -255.722374)
		)
		(stroke
			(width 0)
			(type solid)
		)
		(fill yes)
		(layer "In2.Cu")
		(net "M_C_CPU0_SA_PAR")
	)
	(gr_poly
		(pts
			(xy 341.491062 -254.406146) (xy 341.390986 -254.30607) (xy 341.29091 -254.406146) (xy 341.29091 -254.450596)
			(xy 341.491062 -254.450596)
		)
		(stroke
			(width 0)
			(type solid)
		)
		(fill yes)
		(layer "In2.Cu")
		(net "M_C_CPU0_SA_CA<4>")
	)
	(gr_poly
		(pts
			(xy 341.491062 -254.002286) (xy 341.491062 -253.957836) (xy 341.29091 -253.957836) (xy 341.29091 -254.002286)
			(xy 341.390986 -254.102362)
		)
		(stroke
			(width 0)
			(type solid)
		)
		(fill yes)
		(layer "In2.Cu")
		(net "M_C_CPU0_SA_CA<3>")
	)
	(gr_poly
		(pts
			(xy 341.491062 -252.786134) (xy 341.390986 -252.686058) (xy 341.29091 -252.786134) (xy 341.29091 -252.830584)
			(xy 341.491062 -252.830584)
		)
		(stroke
			(width 0)
			(type solid)
		)
		(fill yes)
		(layer "In2.Cu")
		(net "M_C_CPU0_SA_CA<0>")
	)
	(gr_poly
		(pts
			(xy 341.491062 -252.382274) (xy 341.491062 -252.337824) (xy 341.29091 -252.337824) (xy 341.29091 -252.382274)
			(xy 341.390986 -252.48235)
		)
		(stroke
			(width 0)
			(type solid)
		)
		(fill yes)
		(layer "In2.Cu")
		(net "M_C_CPU0_SA_CS_N<1>")
	)
	(gr_poly
		(pts
			(xy 341.491062 -250.762262) (xy 341.491062 -250.717812) (xy 341.29091 -250.717812) (xy 341.29091 -250.762262)
			(xy 341.390986 -250.862338)
		)
		(stroke
			(width 0)
			(type solid)
		)
		(fill yes)
		(layer "In2.Cu")
		(net "M_C_CPU0_RESET_N")
	)
	(gr_poly
		(pts
			(xy 341.491062 -249.14225) (xy 341.491062 -249.0978) (xy 341.29091 -249.0978) (xy 341.29091 -249.14225)
			(xy 341.390986 -249.242326)
		)
		(stroke
			(width 0)
			(type solid)
		)
		(fill yes)
		(layer "In2.Cu")
		(net "M_C_CPU0_SA_CB<7>")
	)
	(gr_poly
		(pts
			(xy 341.491062 -247.926098) (xy 341.390986 -247.826022) (xy 341.29091 -247.926098) (xy 341.29091 -247.970548)
			(xy 341.491062 -247.970548)
		)
		(stroke
			(width 0)
			(type solid)
		)
		(fill yes)
		(layer "In2.Cu")
		(net "M_C_CPU0_SA_CB<4>")
	)
	(gr_poly
		(pts
			(xy 341.491062 -247.522492) (xy 341.491062 -247.47474) (xy 341.29091 -247.47474) (xy 341.29091 -247.522492)
			(xy 341.390986 -247.622314)
		)
		(stroke
			(width 0)
			(type solid)
		)
		(fill yes)
		(layer "In2.Cu")
		(net "M_C_CPU0_SA_DQS_DP<9>")
	)
	(gr_poly
		(pts
			(xy 341.491062 -245.902226) (xy 341.491062 -245.857776) (xy 341.29091 -245.857776) (xy 341.29091 -245.902226)
			(xy 341.390986 -246.002302)
		)
		(stroke
			(width 0)
			(type solid)
		)
		(fill yes)
		(layer "In2.Cu")
		(net "M_C_CPU0_SA_CB<3>")
	)
	(gr_poly
		(pts
			(xy 341.491062 -244.686074) (xy 341.390986 -244.585998) (xy 341.29091 -244.686074) (xy 341.29091 -244.730524)
			(xy 341.491062 -244.730524)
		)
		(stroke
			(width 0)
			(type solid)
		)
		(fill yes)
		(layer "In2.Cu")
		(net "M_C_CPU0_SA_CB<0>")
	)
	(gr_poly
		(pts
			(xy 341.491062 -244.282214) (xy 341.491062 -244.237764) (xy 341.29091 -244.237764) (xy 341.29091 -244.282214)
			(xy 341.390986 -244.38229)
		)
		(stroke
			(width 0)
			(type solid)
		)
		(fill yes)
		(layer "In2.Cu")
		(net "M_C_CPU0_SA_DQ<31>")
	)
	(gr_poly
		(pts
			(xy 341.491062 -243.066062) (xy 341.390986 -242.965986) (xy 341.29091 -243.066062) (xy 341.29091 -243.110512)
			(xy 341.491062 -243.110512)
		)
		(stroke
			(width 0)
			(type solid)
		)
		(fill yes)
		(layer "In2.Cu")
		(net "M_C_CPU0_SA_DQ<28>")
	)
	(gr_poly
		(pts
			(xy 341.491062 -242.662456) (xy 341.491062 -242.614704) (xy 341.29091 -242.614704) (xy 341.29091 -242.662456)
			(xy 341.390986 -242.762278)
		)
		(stroke
			(width 0)
			(type solid)
		)
		(fill yes)
		(layer "In2.Cu")
		(net "M_C_CPU0_SA_DQS_DP<8>")
	)
	(gr_poly
		(pts
			(xy 341.491062 -241.445796) (xy 341.390986 -241.345974) (xy 341.29091 -241.445796) (xy 341.29091 -241.493548)
			(xy 341.491062 -241.493548)
		)
		(stroke
			(width 0)
			(type solid)
		)
		(fill yes)
		(layer "In2.Cu")
		(net "M_C_CPU0_SA_DQS_DP<3>")
	)
	(gr_poly
		(pts
			(xy 341.491062 -241.04219) (xy 341.491062 -240.99774) (xy 341.29091 -240.99774) (xy 341.29091 -241.04219)
			(xy 341.390986 -241.142266)
		)
		(stroke
			(width 0)
			(type solid)
		)
		(fill yes)
		(layer "In2.Cu")
		(net "M_C_CPU0_SA_DQ<27>")
	)
	(gr_poly
		(pts
			(xy 341.491062 -239.826038) (xy 341.390986 -239.725962) (xy 341.29091 -239.826038) (xy 341.29091 -239.870488)
			(xy 341.491062 -239.870488)
		)
		(stroke
			(width 0)
			(type solid)
		)
		(fill yes)
		(layer "In2.Cu")
		(net "M_C_CPU0_SA_DQ<24>")
	)
	(gr_poly
		(pts
			(xy 341.491062 -239.422178) (xy 341.491062 -239.377728) (xy 341.29091 -239.377728) (xy 341.29091 -239.422178)
			(xy 341.390986 -239.522254)
		)
		(stroke
			(width 0)
			(type solid)
		)
		(fill yes)
		(layer "In2.Cu")
		(net "M_C_CPU0_SA_DQ<23>")
	)
	(gr_poly
		(pts
			(xy 341.491062 -238.206026) (xy 341.390986 -238.10595) (xy 341.29091 -238.206026) (xy 341.29091 -238.250476)
			(xy 341.491062 -238.250476)
		)
		(stroke
			(width 0)
			(type solid)
		)
		(fill yes)
		(layer "In2.Cu")
		(net "M_C_CPU0_SA_DQ<20>")
	)
	(gr_poly
		(pts
			(xy 341.491062 -237.80242) (xy 341.491062 -237.754668) (xy 341.29091 -237.754668) (xy 341.29091 -237.80242)
			(xy 341.390986 -237.902242)
		)
		(stroke
			(width 0)
			(type solid)
		)
		(fill yes)
		(layer "In2.Cu")
		(net "M_C_CPU0_SA_DQS_DP<7>")
	)
	(gr_poly
		(pts
			(xy 341.491062 -236.58576) (xy 341.390986 -236.485938) (xy 341.29091 -236.58576) (xy 341.29091 -236.633512)
			(xy 341.491062 -236.633512)
		)
		(stroke
			(width 0)
			(type solid)
		)
		(fill yes)
		(layer "In2.Cu")
		(net "M_C_CPU0_SA_DQS_DP<2>")
	)
	(gr_poly
		(pts
			(xy 341.491062 -236.182154) (xy 341.491062 -236.137704) (xy 341.29091 -236.137704) (xy 341.29091 -236.182154)
			(xy 341.390986 -236.28223)
		)
		(stroke
			(width 0)
			(type solid)
		)
		(fill yes)
		(layer "In2.Cu")
		(net "M_C_CPU0_SA_DQ<19>")
	)
	(gr_poly
		(pts
			(xy 341.491062 -234.966002) (xy 341.390986 -234.865926) (xy 341.29091 -234.966002) (xy 341.29091 -235.010452)
			(xy 341.491062 -235.010452)
		)
		(stroke
			(width 0)
			(type solid)
		)
		(fill yes)
		(layer "In2.Cu")
		(net "M_C_CPU0_SA_DQ<16>")
	)
	(gr_poly
		(pts
			(xy 341.491062 -234.562142) (xy 341.491062 -234.517692) (xy 341.29091 -234.517692) (xy 341.29091 -234.562142)
			(xy 341.390986 -234.662218)
		)
		(stroke
			(width 0)
			(type solid)
		)
		(fill yes)
		(layer "In2.Cu")
		(net "M_C_CPU0_SA_DQ<15>")
	)
	(gr_poly
		(pts
			(xy 341.491062 -233.34599) (xy 341.390986 -233.245914) (xy 341.29091 -233.34599) (xy 341.29091 -233.39044)
			(xy 341.491062 -233.39044)
		)
		(stroke
			(width 0)
			(type solid)
		)
		(fill yes)
		(layer "In2.Cu")
		(net "M_C_CPU0_SA_DQ<12>")
	)
	(gr_poly
		(pts
			(xy 341.491062 -232.942384) (xy 341.491062 -232.894632) (xy 341.29091 -232.894632) (xy 341.29091 -232.942384)
			(xy 341.390986 -233.042206)
		)
		(stroke
			(width 0)
			(type solid)
		)
		(fill yes)
		(layer "In2.Cu")
		(net "M_C_CPU0_SA_DQS_DP<6>")
	)
	(gr_poly
		(pts
			(xy 341.491062 -231.725724) (xy 341.390986 -231.625902) (xy 341.29091 -231.725724) (xy 341.29091 -231.773476)
			(xy 341.491062 -231.773476)
		)
		(stroke
			(width 0)
			(type solid)
		)
		(fill yes)
		(layer "In2.Cu")
		(net "M_C_CPU0_SA_DQS_DP<1>")
	)
	(gr_poly
		(pts
			(xy 341.491062 -231.322372) (xy 341.491062 -231.277922) (xy 341.29091 -231.277922) (xy 341.29091 -231.322372)
			(xy 341.390986 -231.422448)
		)
		(stroke
			(width 0)
			(type solid)
		)
		(fill yes)
		(layer "In2.Cu")
		(net "M_C_CPU0_SA_DQ<11>")
	)
	(gr_poly
		(pts
			(xy 341.491062 -230.105966) (xy 341.390986 -230.006144) (xy 341.29091 -230.105966) (xy 341.29091 -230.150416)
			(xy 341.491062 -230.150416)
		)
		(stroke
			(width 0)
			(type solid)
		)
		(fill yes)
		(layer "In2.Cu")
		(net "M_C_CPU0_SA_DQ<8>")
	)
	(gr_poly
		(pts
			(xy 341.491062 -229.70236) (xy 341.491062 -229.65791) (xy 341.29091 -229.65791) (xy 341.29091 -229.70236)
			(xy 341.390986 -229.802436)
		)
		(stroke
			(width 0)
			(type solid)
		)
		(fill yes)
		(layer "In2.Cu")
		(net "M_C_CPU0_SA_DQ<7>")
	)
	(gr_poly
		(pts
			(xy 341.491062 -228.486208) (xy 341.390986 -228.386132) (xy 341.29091 -228.486208) (xy 341.29091 -228.530658)
			(xy 341.491062 -228.530658)
		)
		(stroke
			(width 0)
			(type solid)
		)
		(fill yes)
		(layer "In2.Cu")
		(net "M_C_CPU0_SA_DQ<4>")
	)
	(gr_poly
		(pts
			(xy 341.491062 -228.082602) (xy 341.491062 -228.03485) (xy 341.29091 -228.03485) (xy 341.29091 -228.082602)
			(xy 341.390986 -228.182424)
		)
		(stroke
			(width 0)
			(type solid)
		)
		(fill yes)
		(layer "In2.Cu")
		(net "M_C_CPU0_SA_DQS_DP<5>")
	)
	(gr_poly
		(pts
			(xy 341.491062 -226.865942) (xy 341.390986 -226.76612) (xy 341.29091 -226.865942) (xy 341.29091 -226.913694)
			(xy 341.491062 -226.913694)
		)
		(stroke
			(width 0)
			(type solid)
		)
		(fill yes)
		(layer "In2.Cu")
		(net "M_C_CPU0_SA_DQS_DP<0>")
	)
	(gr_poly
		(pts
			(xy 341.491062 -226.462336) (xy 341.491062 -226.417886) (xy 341.29091 -226.417886) (xy 341.29091 -226.462336)
			(xy 341.390986 -226.562412)
		)
		(stroke
			(width 0)
			(type solid)
		)
		(fill yes)
		(layer "In2.Cu")
		(net "M_C_CPU0_SA_DQ<3>")
	)
	(gr_poly
		(pts
			(xy 341.491062 -225.246184) (xy 341.390986 -225.146108) (xy 341.29091 -225.246184) (xy 341.29091 -225.290634)
			(xy 341.491062 -225.290634)
		)
		(stroke
			(width 0)
			(type solid)
		)
		(fill yes)
		(layer "In2.Cu")
		(net "M_C_CPU0_SA_DQ<0>")
	)
	(gr_poly
		(pts
			(xy 341.491316 -246.305832) (xy 341.39124 -246.20601) (xy 341.291164 -246.305832) (xy 341.291164 -246.353584)
			(xy 341.491316 -246.353584)
		)
		(stroke
			(width 0)
			(type solid)
		)
		(fill yes)
		(layer "In2.Cu")
		(net "M_C_CPU0_SA_DQS_DP<4>")
	)
	(gr_poly
		(pts
			(xy 341.783924 -291.297614) (xy 341.683848 -291.197792) (xy 341.583772 -291.297614) (xy 341.583772 -291.345366)
			(xy 341.783924 -291.345366)
		)
		(stroke
			(width 0)
			(type solid)
		)
		(fill yes)
		(layer "In2.Cu")
		(net "M_C_CPU0_SB_DQS_DN<8>")
	)
	(gr_poly
		(pts
			(xy 341.78494 -266.991592) (xy 341.684864 -266.891516) (xy 341.585042 -266.991592) (xy 341.585042 -267.036042)
			(xy 341.78494 -267.036042)
		)
		(stroke
			(width 0)
			(type solid)
		)
		(fill yes)
		(layer "In2.Cu")
		(net "M_C_CPU0_SA_RSP<0>")
	)
	(gr_poly
		(pts
			(xy 341.79129 -292.91788) (xy 341.691214 -292.817804) (xy 341.591138 -292.91788) (xy 341.591138 -292.96233)
			(xy 341.79129 -292.96233)
		)
		(stroke
			(width 0)
			(type solid)
		)
		(fill yes)
		(layer "In2.Cu")
		(net "M_C_CPU0_SB_DQ<29>")
	)
	(gr_poly
		(pts
			(xy 341.79129 -292.51402) (xy 341.79129 -292.46957) (xy 341.591138 -292.46957) (xy 341.591138 -292.51402)
			(xy 341.691214 -292.614096)
		)
		(stroke
			(width 0)
			(type solid)
		)
		(fill yes)
		(layer "In2.Cu")
		(net "M_C_CPU0_SB_DQ<30>")
	)
	(gr_poly
		(pts
			(xy 341.79129 -290.894262) (xy 341.79129 -290.84651) (xy 341.591138 -290.84651) (xy 341.591138 -290.894262)
			(xy 341.691214 -290.994084)
		)
		(stroke
			(width 0)
			(type solid)
		)
		(fill yes)
		(layer "In2.Cu")
		(net "M_C_CPU0_SB_DQS_DN<3>")
	)
	(gr_poly
		(pts
			(xy 341.79129 -289.677856) (xy 341.691214 -289.57778) (xy 341.591138 -289.677856) (xy 341.591138 -289.722306)
			(xy 341.79129 -289.722306)
		)
		(stroke
			(width 0)
			(type solid)
		)
		(fill yes)
		(layer "In2.Cu")
		(net "M_C_CPU0_SB_DQ<25>")
	)
	(gr_poly
		(pts
			(xy 341.79129 -289.273996) (xy 341.79129 -289.229546) (xy 341.591138 -289.229546) (xy 341.591138 -289.273996)
			(xy 341.691214 -289.374072)
		)
		(stroke
			(width 0)
			(type solid)
		)
		(fill yes)
		(layer "In2.Cu")
		(net "M_C_CPU0_SB_DQ<26>")
	)
	(gr_poly
		(pts
			(xy 341.79129 -288.057844) (xy 341.691214 -287.957768) (xy 341.591138 -288.057844) (xy 341.591138 -288.102294)
			(xy 341.79129 -288.102294)
		)
		(stroke
			(width 0)
			(type solid)
		)
		(fill yes)
		(layer "In2.Cu")
		(net "M_C_CPU0_SB_DQ<21>")
	)
	(gr_poly
		(pts
			(xy 341.79129 -287.654238) (xy 341.79129 -287.609788) (xy 341.591138 -287.609788) (xy 341.591138 -287.654238)
			(xy 341.691214 -287.75406)
		)
		(stroke
			(width 0)
			(type solid)
		)
		(fill yes)
		(layer "In2.Cu")
		(net "M_C_CPU0_SB_DQ<22>")
	)
	(gr_poly
		(pts
			(xy 341.79129 -286.437832) (xy 341.691214 -286.337756) (xy 341.591138 -286.437832) (xy 341.591138 -286.485584)
			(xy 341.79129 -286.485584)
		)
		(stroke
			(width 0)
			(type solid)
		)
		(fill yes)
		(layer "In2.Cu")
		(net "M_C_CPU0_SB_DQS_DN<7>")
	)
	(gr_poly
		(pts
			(xy 341.79129 -286.03448) (xy 341.79129 -285.986728) (xy 341.591138 -285.986728) (xy 341.591138 -286.03448)
			(xy 341.691214 -286.134302)
		)
		(stroke
			(width 0)
			(type solid)
		)
		(fill yes)
		(layer "In2.Cu")
		(net "M_C_CPU0_SB_DQS_DN<2>")
	)
	(gr_poly
		(pts
			(xy 341.79129 -284.818074) (xy 341.691214 -284.717998) (xy 341.591138 -284.818074) (xy 341.591138 -284.862524)
			(xy 341.79129 -284.862524)
		)
		(stroke
			(width 0)
			(type solid)
		)
		(fill yes)
		(layer "In2.Cu")
		(net "M_C_CPU0_SB_DQ<17>")
	)
	(gr_poly
		(pts
			(xy 341.79129 -284.414214) (xy 341.79129 -284.369764) (xy 341.591138 -284.369764) (xy 341.591138 -284.414214)
			(xy 341.691214 -284.51429)
		)
		(stroke
			(width 0)
			(type solid)
		)
		(fill yes)
		(layer "In2.Cu")
		(net "M_C_CPU0_SB_DQ<18>")
	)
	(gr_poly
		(pts
			(xy 341.79129 -283.198062) (xy 341.691214 -283.097986) (xy 341.591138 -283.198062) (xy 341.591138 -283.242512)
			(xy 341.79129 -283.242512)
		)
		(stroke
			(width 0)
			(type solid)
		)
		(fill yes)
		(layer "In2.Cu")
		(net "M_C_CPU0_SB_DQ<13>")
	)
	(gr_poly
		(pts
			(xy 341.79129 -282.794202) (xy 341.79129 -282.749752) (xy 341.591138 -282.749752) (xy 341.591138 -282.794202)
			(xy 341.691214 -282.894278)
		)
		(stroke
			(width 0)
			(type solid)
		)
		(fill yes)
		(layer "In2.Cu")
		(net "M_C_CPU0_SB_DQ<14>")
	)
	(gr_poly
		(pts
			(xy 341.79129 -281.577796) (xy 341.691214 -281.477974) (xy 341.591138 -281.577796) (xy 341.591138 -281.625548)
			(xy 341.79129 -281.625548)
		)
		(stroke
			(width 0)
			(type solid)
		)
		(fill yes)
		(layer "In2.Cu")
		(net "M_C_CPU0_SB_DQS_DN<6>")
	)
	(gr_poly
		(pts
			(xy 341.79129 -281.174444) (xy 341.79129 -281.126692) (xy 341.591138 -281.126692) (xy 341.591138 -281.174444)
			(xy 341.691214 -281.274266)
		)
		(stroke
			(width 0)
			(type solid)
		)
		(fill yes)
		(layer "In2.Cu")
		(net "M_C_CPU0_SB_DQS_DN<1>")
	)
	(gr_poly
		(pts
			(xy 341.79129 -279.958038) (xy 341.691214 -279.857962) (xy 341.591138 -279.958038) (xy 341.591138 -280.002488)
			(xy 341.79129 -280.002488)
		)
		(stroke
			(width 0)
			(type solid)
		)
		(fill yes)
		(layer "In2.Cu")
		(net "M_C_CPU0_SB_DQ<9>")
	)
	(gr_poly
		(pts
			(xy 341.79129 -279.554178) (xy 341.79129 -279.509728) (xy 341.591138 -279.509728) (xy 341.591138 -279.554178)
			(xy 341.691214 -279.654254)
		)
		(stroke
			(width 0)
			(type solid)
		)
		(fill yes)
		(layer "In2.Cu")
		(net "M_C_CPU0_SB_DQ<10>")
	)
	(gr_poly
		(pts
			(xy 341.79129 -278.338026) (xy 341.691214 -278.23795) (xy 341.591138 -278.338026) (xy 341.591138 -278.382476)
			(xy 341.79129 -278.382476)
		)
		(stroke
			(width 0)
			(type solid)
		)
		(fill yes)
		(layer "In2.Cu")
		(net "M_C_CPU0_SB_DQ<5>")
	)
	(gr_poly
		(pts
			(xy 341.79129 -277.934166) (xy 341.79129 -277.889716) (xy 341.591138 -277.889716) (xy 341.591138 -277.934166)
			(xy 341.691214 -278.034242)
		)
		(stroke
			(width 0)
			(type solid)
		)
		(fill yes)
		(layer "In2.Cu")
		(net "M_C_CPU0_SB_DQ<6>")
	)
	(gr_poly
		(pts
			(xy 341.79129 -276.71776) (xy 341.691214 -276.617938) (xy 341.591138 -276.71776) (xy 341.591138 -276.765512)
			(xy 341.79129 -276.765512)
		)
		(stroke
			(width 0)
			(type solid)
		)
		(fill yes)
		(layer "In2.Cu")
		(net "M_C_CPU0_SB_DQS_DN<5>")
	)
	(gr_poly
		(pts
			(xy 341.79129 -276.314408) (xy 341.79129 -276.266656) (xy 341.591138 -276.266656) (xy 341.591138 -276.314408)
			(xy 341.691214 -276.41423)
		)
		(stroke
			(width 0)
			(type solid)
		)
		(fill yes)
		(layer "In2.Cu")
		(net "M_C_CPU0_SB_DQS_DN<0>")
	)
	(gr_poly
		(pts
			(xy 341.79129 -275.098002) (xy 341.691214 -274.997926) (xy 341.591138 -275.098002) (xy 341.591138 -275.142452)
			(xy 341.79129 -275.142452)
		)
		(stroke
			(width 0)
			(type solid)
		)
		(fill yes)
		(layer "In2.Cu")
		(net "M_C_CPU0_SB_DQ<1>")
	)
	(gr_poly
		(pts
			(xy 341.79129 -274.694142) (xy 341.79129 -274.649692) (xy 341.591138 -274.649692) (xy 341.591138 -274.694142)
			(xy 341.691214 -274.794218)
		)
		(stroke
			(width 0)
			(type solid)
		)
		(fill yes)
		(layer "In2.Cu")
		(net "M_C_CPU0_SB_DQ<2>")
	)
	(gr_poly
		(pts
			(xy 341.79129 -273.47799) (xy 341.691214 -273.377914) (xy 341.591138 -273.47799) (xy 341.591138 -273.52244)
			(xy 341.79129 -273.52244)
		)
		(stroke
			(width 0)
			(type solid)
		)
		(fill yes)
		(layer "In2.Cu")
		(net "M_C_CPU0_SB_CB<1>")
	)
	(gr_poly
		(pts
			(xy 341.79129 -273.07413) (xy 341.79129 -273.02968) (xy 341.591138 -273.02968) (xy 341.591138 -273.07413)
			(xy 341.691214 -273.174206)
		)
		(stroke
			(width 0)
			(type solid)
		)
		(fill yes)
		(layer "In2.Cu")
		(net "M_C_CPU0_SB_CB<2>")
	)
	(gr_poly
		(pts
			(xy 341.79129 -271.857724) (xy 341.691214 -271.757902) (xy 341.591138 -271.857724) (xy 341.591138 -271.905476)
			(xy 341.79129 -271.905476)
		)
		(stroke
			(width 0)
			(type solid)
		)
		(fill yes)
		(layer "In2.Cu")
		(net "M_C_CPU0_SB_DQS_DN<4>")
	)
	(gr_poly
		(pts
			(xy 341.79129 -271.454372) (xy 341.79129 -271.40662) (xy 341.591138 -271.40662) (xy 341.591138 -271.454372)
			(xy 341.691214 -271.554194)
		)
		(stroke
			(width 0)
			(type solid)
		)
		(fill yes)
		(layer "In2.Cu")
		(net "M_C_CPU0_SB_DQS_DN<9>")
	)
	(gr_poly
		(pts
			(xy 341.79129 -270.237966) (xy 341.691214 -270.13789) (xy 341.591138 -270.237966) (xy 341.591138 -270.282416)
			(xy 341.79129 -270.282416)
		)
		(stroke
			(width 0)
			(type solid)
		)
		(fill yes)
		(layer "In2.Cu")
		(net "M_C_CPU0_SB_CB<5>")
	)
	(gr_poly
		(pts
			(xy 341.79129 -269.834106) (xy 341.79129 -269.789656) (xy 341.591138 -269.789656) (xy 341.591138 -269.834106)
			(xy 341.691214 -269.934182)
		)
		(stroke
			(width 0)
			(type solid)
		)
		(fill yes)
		(layer "In2.Cu")
		(net "M_C_CPU0_SB_CB<6>")
	)
	(gr_poly
		(pts
			(xy 341.79129 -266.594082) (xy 341.79129 -266.549632) (xy 341.591138 -266.549632) (xy 341.591138 -266.594082)
			(xy 341.691214 -266.694158)
		)
		(stroke
			(width 0)
			(type solid)
		)
		(fill yes)
		(layer "In2.Cu")
		(net "M_C_CPU0_SB_CS_N<1>")
	)
	(gr_poly
		(pts
			(xy 341.79129 -264.97407) (xy 341.79129 -264.92962) (xy 341.591138 -264.92962) (xy 341.591138 -264.97407)
			(xy 341.691214 -265.074146)
		)
		(stroke
			(width 0)
			(type solid)
		)
		(fill yes)
		(layer "In2.Cu")
		(net "M_C_CPU0_SB_PAR")
	)
	(gr_poly
		(pts
			(xy 341.79129 -263.757918) (xy 341.691214 -263.657842) (xy 341.591138 -263.757918) (xy 341.591138 -263.802368)
			(xy 341.79129 -263.802368)
		)
		(stroke
			(width 0)
			(type solid)
		)
		(fill yes)
		(layer "In2.Cu")
		(net "M_C_CPU0_SB_CA<4>")
	)
	(gr_poly
		(pts
			(xy 341.79129 -263.354058) (xy 341.79129 -263.309608) (xy 341.591138 -263.309608) (xy 341.591138 -263.354058)
			(xy 341.691214 -263.454134)
		)
		(stroke
			(width 0)
			(type solid)
		)
		(fill yes)
		(layer "In2.Cu")
		(net "M_C_CPU0_SB_CA<3>")
	)
	(gr_poly
		(pts
			(xy 341.79129 -262.137906) (xy 341.691214 -262.03783) (xy 341.591138 -262.137906) (xy 341.591138 -262.182356)
			(xy 341.79129 -262.182356)
		)
		(stroke
			(width 0)
			(type solid)
		)
		(fill yes)
		(layer "In2.Cu")
		(net "M_C_CPU0_SB_CA<0>")
	)
	(gr_poly
		(pts
			(xy 341.908638 -256.438908) (xy 341.912956 -256.391664) (xy 341.713566 -256.374138) (xy 341.709502 -256.421636)
			(xy 341.800434 -256.52984)
		)
		(stroke
			(width 0)
			(type solid)
		)
		(fill yes)
		(layer "In2.Cu")
		(net "M_C_CPU0_CLK_DN<0>")
	)
	(gr_poly
		(pts
			(xy 341.908638 -246.718836) (xy 341.912956 -246.671338) (xy 341.713566 -246.653812) (xy 341.709502 -246.70131)
			(xy 341.800434 -246.809768)
		)
		(stroke
			(width 0)
			(type solid)
		)
		(fill yes)
		(layer "In2.Cu")
		(net "M_C_CPU0_SA_DQS_DN<4>")
	)
	(gr_poly
		(pts
			(xy 341.908638 -241.8588) (xy 341.912956 -241.811556) (xy 341.713566 -241.79403) (xy 341.709502 -241.841528)
			(xy 341.800434 -241.949732)
		)
		(stroke
			(width 0)
			(type solid)
		)
		(fill yes)
		(layer "In2.Cu")
		(net "M_C_CPU0_SA_DQS_DN<3>")
	)
	(gr_poly
		(pts
			(xy 341.908638 -236.998764) (xy 341.912956 -236.95152) (xy 341.713566 -236.933994) (xy 341.709502 -236.981492)
			(xy 341.800434 -237.089696)
		)
		(stroke
			(width 0)
			(type solid)
		)
		(fill yes)
		(layer "In2.Cu")
		(net "M_C_CPU0_SA_DQS_DN<2>")
	)
	(gr_poly
		(pts
			(xy 341.908638 -232.138728) (xy 341.912956 -232.091484) (xy 341.713566 -232.073958) (xy 341.709502 -232.121456)
			(xy 341.800434 -232.22966)
		)
		(stroke
			(width 0)
			(type solid)
		)
		(fill yes)
		(layer "In2.Cu")
		(net "M_C_CPU0_SA_DQS_DN<1>")
	)
	(gr_poly
		(pts
			(xy 341.91956 -227.279962) (xy 341.923878 -227.232464) (xy 341.724488 -227.214938) (xy 341.720424 -227.262436)
			(xy 341.811356 -227.370894)
		)
		(stroke
			(width 0)
			(type solid)
		)
		(fill yes)
		(layer "In2.Cu")
		(net "M_C_CPU0_SA_DQS_DN<0>")
	)
	(gr_poly
		(pts
			(xy 341.921592 -254.819912) (xy 341.925402 -254.775462) (xy 341.726266 -254.75819) (xy 341.722456 -254.802386)
			(xy 341.813388 -254.910844)
		)
		(stroke
			(width 0)
			(type solid)
		)
		(fill yes)
		(layer "In2.Cu")
		(net "M_C_CPU0_SA_CA<5>")
	)
	(gr_poly
		(pts
			(xy 341.921592 -253.1999) (xy 341.925402 -253.15545) (xy 341.726266 -253.138178) (xy 341.722456 -253.182374)
			(xy 341.813388 -253.290832)
		)
		(stroke
			(width 0)
			(type solid)
		)
		(fill yes)
		(layer "In2.Cu")
		(net "M_C_CPU0_SA_CA<1>")
	)
	(gr_poly
		(pts
			(xy 341.921592 -251.579888) (xy 341.925402 -251.535438) (xy 341.726266 -251.518166) (xy 341.722456 -251.562362)
			(xy 341.813388 -251.67082)
		)
		(stroke
			(width 0)
			(type solid)
		)
		(fill yes)
		(layer "In2.Cu")
		(net "M_C_CPU0_SA_CS_N<0>")
	)
	(gr_poly
		(pts
			(xy 341.921592 -248.339864) (xy 341.925402 -248.295414) (xy 341.726266 -248.278142) (xy 341.722456 -248.322338)
			(xy 341.813388 -248.430796)
		)
		(stroke
			(width 0)
			(type solid)
		)
		(fill yes)
		(layer "In2.Cu")
		(net "M_C_CPU0_SA_CB<6>")
	)
	(gr_poly
		(pts
			(xy 341.921592 -245.09984) (xy 341.925402 -245.05539) (xy 341.726266 -245.038118) (xy 341.722456 -245.082314)
			(xy 341.813388 -245.190772)
		)
		(stroke
			(width 0)
			(type solid)
		)
		(fill yes)
		(layer "In2.Cu")
		(net "M_C_CPU0_SA_CB<2>")
	)
	(gr_poly
		(pts
			(xy 341.921592 -243.479828) (xy 341.925402 -243.435378) (xy 341.726266 -243.418106) (xy 341.722456 -243.462302)
			(xy 341.813388 -243.57076)
		)
		(stroke
			(width 0)
			(type solid)
		)
		(fill yes)
		(layer "In2.Cu")
		(net "M_C_CPU0_SA_DQ<30>")
	)
	(gr_poly
		(pts
			(xy 341.921592 -240.239804) (xy 341.925402 -240.195354) (xy 341.726266 -240.178082) (xy 341.722456 -240.222278)
			(xy 341.813388 -240.330736)
		)
		(stroke
			(width 0)
			(type solid)
		)
		(fill yes)
		(layer "In2.Cu")
		(net "M_C_CPU0_SA_DQ<26>")
	)
	(gr_poly
		(pts
			(xy 341.921592 -238.619792) (xy 341.925402 -238.575342) (xy 341.726266 -238.55807) (xy 341.722456 -238.602266)
			(xy 341.813388 -238.710724)
		)
		(stroke
			(width 0)
			(type solid)
		)
		(fill yes)
		(layer "In2.Cu")
		(net "M_C_CPU0_SA_DQ<22>")
	)
	(gr_poly
		(pts
			(xy 341.921592 -235.379768) (xy 341.925402 -235.335318) (xy 341.726266 -235.318046) (xy 341.722456 -235.362242)
			(xy 341.813388 -235.4707)
		)
		(stroke
			(width 0)
			(type solid)
		)
		(fill yes)
		(layer "In2.Cu")
		(net "M_C_CPU0_SA_DQ<18>")
	)
	(gr_poly
		(pts
			(xy 341.921592 -233.759756) (xy 341.925402 -233.715306) (xy 341.726266 -233.698034) (xy 341.722456 -233.74223)
			(xy 341.813388 -233.850688)
		)
		(stroke
			(width 0)
			(type solid)
		)
		(fill yes)
		(layer "In2.Cu")
		(net "M_C_CPU0_SA_DQ<14>")
	)
	(gr_poly
		(pts
			(xy 341.921592 -230.519986) (xy 341.925402 -230.475536) (xy 341.726266 -230.458264) (xy 341.722456 -230.50246)
			(xy 341.813388 -230.610664)
		)
		(stroke
			(width 0)
			(type solid)
		)
		(fill yes)
		(layer "In2.Cu")
		(net "M_C_CPU0_SA_DQ<10>")
	)
	(gr_poly
		(pts
			(xy 341.921592 -228.899974) (xy 341.925402 -228.855524) (xy 341.726266 -228.838252) (xy 341.722456 -228.882448)
			(xy 341.813388 -228.990906)
		)
		(stroke
			(width 0)
			(type solid)
		)
		(fill yes)
		(layer "In2.Cu")
		(net "M_C_CPU0_SA_DQ<6>")
	)
	(gr_poly
		(pts
			(xy 341.921592 -225.65995) (xy 341.925402 -225.6155) (xy 341.726266 -225.598228) (xy 341.722456 -225.642424)
			(xy 341.813388 -225.750882)
		)
		(stroke
			(width 0)
			(type solid)
		)
		(fill yes)
		(layer "In2.Cu")
		(net "M_C_CPU0_SA_DQ<2>")
	)
	(gr_poly
		(pts
			(xy 341.961216 -255.216152) (xy 341.86114 -255.116076) (xy 341.761064 -255.216152) (xy 341.761064 -255.260602)
			(xy 341.961216 -255.260602)
		)
		(stroke
			(width 0)
			(type solid)
		)
		(fill yes)
		(layer "In2.Cu")
		(net "M_C_CPU0_SA_CA<6>")
	)
	(gr_poly
		(pts
			(xy 341.961216 -253.59614) (xy 341.86114 -253.496064) (xy 341.761064 -253.59614) (xy 341.761064 -253.64059)
			(xy 341.961216 -253.64059)
		)
		(stroke
			(width 0)
			(type solid)
		)
		(fill yes)
		(layer "In2.Cu")
		(net "M_C_CPU0_SA_CA<2>")
	)
	(gr_poly
		(pts
			(xy 341.961216 -250.356116) (xy 341.86114 -250.25604) (xy 341.761064 -250.356116) (xy 341.761064 -250.400566)
			(xy 341.961216 -250.400566)
		)
		(stroke
			(width 0)
			(type solid)
		)
		(fill yes)
		(layer "In2.Cu")
		(net "M_C_CPU0_ALERT_R_N")
	)
	(gr_poly
		(pts
			(xy 341.961216 -248.736104) (xy 341.86114 -248.636028) (xy 341.761064 -248.736104) (xy 341.761064 -248.780554)
			(xy 341.961216 -248.780554)
		)
		(stroke
			(width 0)
			(type solid)
		)
		(fill yes)
		(layer "In2.Cu")
		(net "M_C_CPU0_SA_CB<5>")
	)
	(gr_poly
		(pts
			(xy 341.961216 -247.115838) (xy 341.86114 -247.016016) (xy 341.761064 -247.115838) (xy 341.761064 -247.16359)
			(xy 341.961216 -247.16359)
		)
		(stroke
			(width 0)
			(type solid)
		)
		(fill yes)
		(layer "In2.Cu")
		(net "M_C_CPU0_SA_DQS_DN<9>")
	)
	(gr_poly
		(pts
			(xy 341.961216 -245.49608) (xy 341.86114 -245.396004) (xy 341.761064 -245.49608) (xy 341.761064 -245.54053)
			(xy 341.961216 -245.54053)
		)
		(stroke
			(width 0)
			(type solid)
		)
		(fill yes)
		(layer "In2.Cu")
		(net "M_C_CPU0_SA_CB<1>")
	)
	(gr_poly
		(pts
			(xy 341.961216 -243.876068) (xy 341.86114 -243.775992) (xy 341.761064 -243.876068) (xy 341.761064 -243.920518)
			(xy 341.961216 -243.920518)
		)
		(stroke
			(width 0)
			(type solid)
		)
		(fill yes)
		(layer "In2.Cu")
		(net "M_C_CPU0_SA_DQ<29>")
	)
	(gr_poly
		(pts
			(xy 341.961216 -242.255802) (xy 341.86114 -242.15598) (xy 341.761064 -242.255802) (xy 341.761064 -242.303554)
			(xy 341.961216 -242.303554)
		)
		(stroke
			(width 0)
			(type solid)
		)
		(fill yes)
		(layer "In2.Cu")
		(net "M_C_CPU0_SA_DQS_DN<8>")
	)
	(gr_poly
		(pts
			(xy 341.961216 -240.636044) (xy 341.86114 -240.535968) (xy 341.761064 -240.636044) (xy 341.761064 -240.680494)
			(xy 341.961216 -240.680494)
		)
		(stroke
			(width 0)
			(type solid)
		)
		(fill yes)
		(layer "In2.Cu")
		(net "M_C_CPU0_SA_DQ<25>")
	)
	(gr_poly
		(pts
			(xy 341.961216 -239.016032) (xy 341.86114 -238.915956) (xy 341.761064 -239.016032) (xy 341.761064 -239.060482)
			(xy 341.961216 -239.060482)
		)
		(stroke
			(width 0)
			(type solid)
		)
		(fill yes)
		(layer "In2.Cu")
		(net "M_C_CPU0_SA_DQ<21>")
	)
	(gr_poly
		(pts
			(xy 341.961216 -237.395766) (xy 341.86114 -237.295944) (xy 341.761064 -237.395766) (xy 341.761064 -237.443518)
			(xy 341.961216 -237.443518)
		)
		(stroke
			(width 0)
			(type solid)
		)
		(fill yes)
		(layer "In2.Cu")
		(net "M_C_CPU0_SA_DQS_DN<7>")
	)
	(gr_poly
		(pts
			(xy 341.961216 -235.776008) (xy 341.86114 -235.675932) (xy 341.761064 -235.776008) (xy 341.761064 -235.820458)
			(xy 341.961216 -235.820458)
		)
		(stroke
			(width 0)
			(type solid)
		)
		(fill yes)
		(layer "In2.Cu")
		(net "M_C_CPU0_SA_DQ<17>")
	)
	(gr_poly
		(pts
			(xy 341.961216 -234.155996) (xy 341.86114 -234.05592) (xy 341.761064 -234.155996) (xy 341.761064 -234.200446)
			(xy 341.961216 -234.200446)
		)
		(stroke
			(width 0)
			(type solid)
		)
		(fill yes)
		(layer "In2.Cu")
		(net "M_C_CPU0_SA_DQ<13>")
	)
	(gr_poly
		(pts
			(xy 341.961216 -232.53573) (xy 341.86114 -232.435908) (xy 341.761064 -232.53573) (xy 341.761064 -232.583482)
			(xy 341.961216 -232.583482)
		)
		(stroke
			(width 0)
			(type solid)
		)
		(fill yes)
		(layer "In2.Cu")
		(net "M_C_CPU0_SA_DQS_DN<6>")
	)
	(gr_poly
		(pts
			(xy 341.961216 -230.915972) (xy 341.86114 -230.815896) (xy 341.761064 -230.915972) (xy 341.761064 -230.960422)
			(xy 341.961216 -230.960422)
		)
		(stroke
			(width 0)
			(type solid)
		)
		(fill yes)
		(layer "In2.Cu")
		(net "M_C_CPU0_SA_DQ<9>")
	)
	(gr_poly
		(pts
			(xy 341.961216 -229.29596) (xy 341.86114 -229.195884) (xy 341.761064 -229.29596) (xy 341.761064 -229.34041)
			(xy 341.961216 -229.34041)
		)
		(stroke
			(width 0)
			(type solid)
		)
		(fill yes)
		(layer "In2.Cu")
		(net "M_C_CPU0_SA_DQ<5>")
	)
	(gr_poly
		(pts
			(xy 341.961216 -227.675948) (xy 341.86114 -227.576126) (xy 341.761064 -227.675948) (xy 341.761064 -227.7237)
			(xy 341.961216 -227.7237)
		)
		(stroke
			(width 0)
			(type solid)
		)
		(fill yes)
		(layer "In2.Cu")
		(net "M_C_CPU0_SA_DQS_DN<5>")
	)
	(gr_poly
		(pts
			(xy 341.961216 -226.05619) (xy 341.86114 -225.956114) (xy 341.761064 -226.05619) (xy 341.761064 -226.10064)
			(xy 341.961216 -226.10064)
		)
		(stroke
			(width 0)
			(type solid)
		)
		(fill yes)
		(layer "In2.Cu")
		(net "M_C_CPU0_SA_DQ<1>")
	)
	(gr_poly
		(pts
			(xy 342.213184 -280.808684) (xy 342.208866 -280.761186) (xy 342.100662 -280.670254) (xy 342.00973 -280.778712)
			(xy 342.013794 -280.825956)
		)
		(stroke
			(width 0)
			(type solid)
		)
		(fill yes)
		(layer "In2.Cu")
		(net "M_C_CPU0_SB_DQS_DP<1>")
	)
	(gr_poly
		(pts
			(xy 342.22309 -267.838428) (xy 342.219026 -267.794232) (xy 342.110822 -267.7033) (xy 342.01989 -267.811758)
			(xy 342.0237 -267.855954)
		)
		(stroke
			(width 0)
			(type solid)
		)
		(fill yes)
		(layer "In2.Cu")
		(net "M_C_CPU0_SB_RSP<0>")
	)
	(gr_poly
		(pts
			(xy 342.223598 -290.52774) (xy 342.219534 -290.480242) (xy 342.11133 -290.38931) (xy 342.020398 -290.497768)
			(xy 342.024462 -290.545012)
		)
		(stroke
			(width 0)
			(type solid)
		)
		(fill yes)
		(layer "In2.Cu")
		(net "M_C_CPU0_SB_DQS_DP<3>")
	)
	(gr_poly
		(pts
			(xy 342.223598 -285.667958) (xy 342.219534 -285.62046) (xy 342.11133 -285.529528) (xy 342.020398 -285.637986)
			(xy 342.024462 -285.685484)
		)
		(stroke
			(width 0)
			(type solid)
		)
		(fill yes)
		(layer "In2.Cu")
		(net "M_C_CPU0_SB_DQS_DP<2>")
	)
	(gr_poly
		(pts
			(xy 342.223598 -275.947886) (xy 342.219534 -275.900388) (xy 342.11133 -275.809456) (xy 342.020398 -275.917914)
			(xy 342.024462 -275.965412)
		)
		(stroke
			(width 0)
			(type solid)
		)
		(fill yes)
		(layer "In2.Cu")
		(net "M_C_CPU0_SB_DQS_DP<0>")
	)
	(gr_poly
		(pts
			(xy 342.223598 -271.08785) (xy 342.219534 -271.040352) (xy 342.11133 -270.94942) (xy 342.020398 -271.057878)
			(xy 342.024462 -271.105376)
		)
		(stroke
			(width 0)
			(type solid)
		)
		(fill yes)
		(layer "In2.Cu")
		(net "M_C_CPU0_SB_DQS_DP<9>")
	)
	(gr_poly
		(pts
			(xy 342.22563 -292.144704) (xy 342.221566 -292.100254) (xy 342.113362 -292.009322) (xy 342.02243 -292.11778)
			(xy 342.02624 -292.161976)
		)
		(stroke
			(width 0)
			(type solid)
		)
		(fill yes)
		(layer "In2.Cu")
		(net "M_C_CPU0_SB_DQ<28>")
	)
	(gr_poly
		(pts
			(xy 342.22563 -288.90468) (xy 342.221566 -288.86023) (xy 342.113362 -288.769298) (xy 342.02243 -288.877756)
			(xy 342.02624 -288.921952)
		)
		(stroke
			(width 0)
			(type solid)
		)
		(fill yes)
		(layer "In2.Cu")
		(net "M_C_CPU0_SB_DQ<24>")
	)
	(gr_poly
		(pts
			(xy 342.22563 -287.284668) (xy 342.221566 -287.240218) (xy 342.113362 -287.14954) (xy 342.02243 -287.257744)
			(xy 342.02624 -287.30194)
		)
		(stroke
			(width 0)
			(type solid)
		)
		(fill yes)
		(layer "In2.Cu")
		(net "M_C_CPU0_SB_DQ<20>")
	)
	(gr_poly
		(pts
			(xy 342.22563 -284.044898) (xy 342.221566 -284.000448) (xy 342.113362 -283.909516) (xy 342.02243 -284.017974)
			(xy 342.02624 -284.06217)
		)
		(stroke
			(width 0)
			(type solid)
		)
		(fill yes)
		(layer "In2.Cu")
		(net "M_C_CPU0_SB_DQ<16>")
	)
	(gr_poly
		(pts
			(xy 342.22563 -282.424886) (xy 342.221566 -282.380436) (xy 342.113362 -282.289504) (xy 342.02243 -282.397962)
			(xy 342.02624 -282.442158)
		)
		(stroke
			(width 0)
			(type solid)
		)
		(fill yes)
		(layer "In2.Cu")
		(net "M_C_CPU0_SB_DQ<12>")
	)
	(gr_poly
		(pts
			(xy 342.22563 -279.184862) (xy 342.221566 -279.140412) (xy 342.113362 -279.04948) (xy 342.02243 -279.157938)
			(xy 342.02624 -279.202134)
		)
		(stroke
			(width 0)
			(type solid)
		)
		(fill yes)
		(layer "In2.Cu")
		(net "M_C_CPU0_SB_DQ<8>")
	)
	(gr_poly
		(pts
			(xy 342.22563 -277.56485) (xy 342.221566 -277.5204) (xy 342.113362 -277.429468) (xy 342.02243 -277.537926)
			(xy 342.02624 -277.582122)
		)
		(stroke
			(width 0)
			(type solid)
		)
		(fill yes)
		(layer "In2.Cu")
		(net "M_C_CPU0_SB_DQ<4>")
	)
	(gr_poly
		(pts
			(xy 342.22563 -274.324826) (xy 342.221566 -274.280376) (xy 342.113362 -274.189444) (xy 342.02243 -274.297902)
			(xy 342.02624 -274.342098)
		)
		(stroke
			(width 0)
			(type solid)
		)
		(fill yes)
		(layer "In2.Cu")
		(net "M_C_CPU0_SB_DQ<0>")
	)
	(gr_poly
		(pts
			(xy 342.22563 -272.704814) (xy 342.221566 -272.660364) (xy 342.113362 -272.569432) (xy 342.02243 -272.67789)
			(xy 342.02624 -272.722086)
		)
		(stroke
			(width 0)
			(type solid)
		)
		(fill yes)
		(layer "In2.Cu")
		(net "M_C_CPU0_SB_CB<0>")
	)
	(gr_poly
		(pts
			(xy 342.22563 -269.46479) (xy 342.221566 -269.42034) (xy 342.113362 -269.329408) (xy 342.02243 -269.437866)
			(xy 342.02624 -269.482062)
		)
		(stroke
			(width 0)
			(type solid)
		)
		(fill yes)
		(layer "In2.Cu")
		(net "M_C_CPU0_SB_CB<4>")
	)
	(gr_poly
		(pts
			(xy 342.22563 -264.604754) (xy 342.221566 -264.560304) (xy 342.113362 -264.469372) (xy 342.02243 -264.57783)
			(xy 342.02624 -264.622026)
		)
		(stroke
			(width 0)
			(type solid)
		)
		(fill yes)
		(layer "In2.Cu")
		(net "M_C_CPU0_SB_CA<6>")
	)
	(gr_poly
		(pts
			(xy 342.22563 -262.984742) (xy 342.221566 -262.940292) (xy 342.113362 -262.84936) (xy 342.02243 -262.957818)
			(xy 342.02624 -263.002014)
		)
		(stroke
			(width 0)
			(type solid)
		)
		(fill yes)
		(layer "In2.Cu")
		(net "M_C_CPU0_SB_CA<2>")
	)
	(gr_poly
		(pts
			(xy 342.26119 -293.324026) (xy 342.26119 -293.279576) (xy 342.061038 -293.279576) (xy 342.061038 -293.324026)
			(xy 342.161114 -293.424102)
		)
		(stroke
			(width 0)
			(type solid)
		)
		(fill yes)
		(layer "In2.Cu")
		(net "M_C_CPU0_SB_DQ<31>")
	)
	(gr_poly
		(pts
			(xy 342.26119 -291.704268) (xy 342.26119 -291.656516) (xy 342.061038 -291.656516) (xy 342.061038 -291.704268)
			(xy 342.161114 -291.80409)
		)
		(stroke
			(width 0)
			(type solid)
		)
		(fill yes)
		(layer "In2.Cu")
		(net "M_C_CPU0_SB_DQS_DP<8>")
	)
	(gr_poly
		(pts
			(xy 342.26119 -290.084002) (xy 342.26119 -290.039552) (xy 342.061038 -290.039552) (xy 342.061038 -290.084002)
			(xy 342.161114 -290.184078)
		)
		(stroke
			(width 0)
			(type solid)
		)
		(fill yes)
		(layer "In2.Cu")
		(net "M_C_CPU0_SB_DQ<27>")
	)
	(gr_poly
		(pts
			(xy 342.26119 -288.464244) (xy 342.26119 -288.419794) (xy 342.061038 -288.419794) (xy 342.061038 -288.464244)
			(xy 342.161114 -288.56432)
		)
		(stroke
			(width 0)
			(type solid)
		)
		(fill yes)
		(layer "In2.Cu")
		(net "M_C_CPU0_SB_DQ<23>")
	)
	(gr_poly
		(pts
			(xy 342.26119 -286.844232) (xy 342.26119 -286.79648) (xy 342.061038 -286.79648) (xy 342.061038 -286.844232)
			(xy 342.161114 -286.944308)
		)
		(stroke
			(width 0)
			(type solid)
		)
		(fill yes)
		(layer "In2.Cu")
		(net "M_C_CPU0_SB_DQS_DP<7>")
	)
	(gr_poly
		(pts
			(xy 342.26119 -285.22422) (xy 342.26119 -285.17977) (xy 342.061038 -285.17977) (xy 342.061038 -285.22422)
			(xy 342.161114 -285.324296)
		)
		(stroke
			(width 0)
			(type solid)
		)
		(fill yes)
		(layer "In2.Cu")
		(net "M_C_CPU0_SB_DQ<19>")
	)
	(gr_poly
		(pts
			(xy 342.26119 -283.604208) (xy 342.26119 -283.559758) (xy 342.061038 -283.559758) (xy 342.061038 -283.604208)
			(xy 342.161114 -283.704284)
		)
		(stroke
			(width 0)
			(type solid)
		)
		(fill yes)
		(layer "In2.Cu")
		(net "M_C_CPU0_SB_DQ<15>")
	)
	(gr_poly
		(pts
			(xy 342.26119 -281.98445) (xy 342.26119 -281.936698) (xy 342.061038 -281.936698) (xy 342.061038 -281.98445)
			(xy 342.161114 -282.084272)
		)
		(stroke
			(width 0)
			(type solid)
		)
		(fill yes)
		(layer "In2.Cu")
		(net "M_C_CPU0_SB_DQS_DP<6>")
	)
	(gr_poly
		(pts
			(xy 342.26119 -280.364184) (xy 342.26119 -280.319734) (xy 342.061038 -280.319734) (xy 342.061038 -280.364184)
			(xy 342.161114 -280.46426)
		)
		(stroke
			(width 0)
			(type solid)
		)
		(fill yes)
		(layer "In2.Cu")
		(net "M_C_CPU0_SB_DQ<11>")
	)
	(gr_poly
		(pts
			(xy 342.26119 -278.744172) (xy 342.26119 -278.699722) (xy 342.061038 -278.699722) (xy 342.061038 -278.744172)
			(xy 342.161114 -278.844248)
		)
		(stroke
			(width 0)
			(type solid)
		)
		(fill yes)
		(layer "In2.Cu")
		(net "M_C_CPU0_SB_DQ<7>")
	)
	(gr_poly
		(pts
			(xy 342.26119 -277.124414) (xy 342.26119 -277.076662) (xy 342.061038 -277.076662) (xy 342.061038 -277.124414)
			(xy 342.161114 -277.224236)
		)
		(stroke
			(width 0)
			(type solid)
		)
		(fill yes)
		(layer "In2.Cu")
		(net "M_C_CPU0_SB_DQS_DP<5>")
	)
	(gr_poly
		(pts
			(xy 342.26119 -275.504148) (xy 342.26119 -275.459698) (xy 342.061038 -275.459698) (xy 342.061038 -275.504148)
			(xy 342.161114 -275.604224)
		)
		(stroke
			(width 0)
			(type solid)
		)
		(fill yes)
		(layer "In2.Cu")
		(net "M_C_CPU0_SB_DQ<3>")
	)
	(gr_poly
		(pts
			(xy 342.26119 -273.884136) (xy 342.26119 -273.839686) (xy 342.061038 -273.839686) (xy 342.061038 -273.884136)
			(xy 342.161114 -273.984212)
		)
		(stroke
			(width 0)
			(type solid)
		)
		(fill yes)
		(layer "In2.Cu")
		(net "M_C_CPU0_SB_CB<3>")
	)
	(gr_poly
		(pts
			(xy 342.26119 -272.264378) (xy 342.26119 -272.216626) (xy 342.061038 -272.216626) (xy 342.061038 -272.264378)
			(xy 342.161114 -272.3642)
		)
		(stroke
			(width 0)
			(type solid)
		)
		(fill yes)
		(layer "In2.Cu")
		(net "M_C_CPU0_SB_DQS_DP<4>")
	)
	(gr_poly
		(pts
			(xy 342.26119 -270.644112) (xy 342.26119 -270.599662) (xy 342.061038 -270.599662) (xy 342.061038 -270.644112)
			(xy 342.161114 -270.744188)
		)
		(stroke
			(width 0)
			(type solid)
		)
		(fill yes)
		(layer "In2.Cu")
		(net "M_C_CPU0_SB_CB<7>")
	)
	(gr_poly
		(pts
			(xy 342.26119 -265.784076) (xy 342.26119 -265.739626) (xy 342.061038 -265.739626) (xy 342.061038 -265.784076)
			(xy 342.161114 -265.884152)
		)
		(stroke
			(width 0)
			(type solid)
		)
		(fill yes)
		(layer "In2.Cu")
		(net "M_C_CPU0_SB_CS_N<0>")
	)
	(gr_poly
		(pts
			(xy 342.26119 -264.164064) (xy 342.26119 -264.119614) (xy 342.061038 -264.119614) (xy 342.061038 -264.164064)
			(xy 342.161114 -264.26414)
		)
		(stroke
			(width 0)
			(type solid)
		)
		(fill yes)
		(layer "In2.Cu")
		(net "M_C_CPU0_SB_CA<5>")
	)
	(gr_poly
		(pts
			(xy 342.26119 -262.544052) (xy 342.26119 -262.499602) (xy 342.061038 -262.499602) (xy 342.061038 -262.544052)
			(xy 342.161114 -262.644128)
		)
		(stroke
			(width 0)
			(type solid)
		)
		(fill yes)
		(layer "In2.Cu")
		(net "M_C_CPU0_SB_CA<1>")
	)
	(gr_poly
		(pts
			(xy 342.431116 -255.622298) (xy 342.431116 -255.577848) (xy 342.230964 -255.577848) (xy 342.230964 -255.622298)
			(xy 342.33104 -255.722374)
		)
		(stroke
			(width 0)
			(type solid)
		)
		(fill yes)
		(layer "In2.Cu")
		(net "M_C_CPU0_SA_PAR")
	)
	(gr_poly
		(pts
			(xy 342.431116 -254.002286) (xy 342.431116 -253.957836) (xy 342.230964 -253.957836) (xy 342.230964 -254.002286)
			(xy 342.33104 -254.102362)
		)
		(stroke
			(width 0)
			(type solid)
		)
		(fill yes)
		(layer "In2.Cu")
		(net "M_C_CPU0_SA_CA<3>")
	)
	(gr_poly
		(pts
			(xy 342.431116 -252.382274) (xy 342.431116 -252.337824) (xy 342.230964 -252.337824) (xy 342.230964 -252.382274)
			(xy 342.33104 -252.48235)
		)
		(stroke
			(width 0)
			(type solid)
		)
		(fill yes)
		(layer "In2.Cu")
		(net "M_C_CPU0_SA_CS_N<1>")
	)
	(gr_poly
		(pts
			(xy 342.431116 -250.762262) (xy 342.431116 -250.717812) (xy 342.230964 -250.717812) (xy 342.230964 -250.762262)
			(xy 342.33104 -250.862338)
		)
		(stroke
			(width 0)
			(type solid)
		)
		(fill yes)
		(layer "In2.Cu")
		(net "M_C_CPU0_RESET_N")
	)
	(gr_poly
		(pts
			(xy 342.431116 -249.14225) (xy 342.431116 -249.0978) (xy 342.230964 -249.0978) (xy 342.230964 -249.14225)
			(xy 342.33104 -249.242326)
		)
		(stroke
			(width 0)
			(type solid)
		)
		(fill yes)
		(layer "In2.Cu")
		(net "M_C_CPU0_SA_CB<7>")
	)
	(gr_poly
		(pts
			(xy 342.431116 -247.522492) (xy 342.431116 -247.47474) (xy 342.230964 -247.47474) (xy 342.230964 -247.522492)
			(xy 342.33104 -247.622314)
		)
		(stroke
			(width 0)
			(type solid)
		)
		(fill yes)
		(layer "In2.Cu")
		(net "M_C_CPU0_SA_DQS_DP<9>")
	)
	(gr_poly
		(pts
			(xy 342.431116 -245.902226) (xy 342.431116 -245.857776) (xy 342.230964 -245.857776) (xy 342.230964 -245.902226)
			(xy 342.33104 -246.002302)
		)
		(stroke
			(width 0)
			(type solid)
		)
		(fill yes)
		(layer "In2.Cu")
		(net "M_C_CPU0_SA_CB<3>")
	)
	(gr_poly
		(pts
			(xy 342.431116 -244.282214) (xy 342.431116 -244.237764) (xy 342.230964 -244.237764) (xy 342.230964 -244.282214)
			(xy 342.33104 -244.38229)
		)
		(stroke
			(width 0)
			(type solid)
		)
		(fill yes)
		(layer "In2.Cu")
		(net "M_C_CPU0_SA_DQ<31>")
	)
	(gr_poly
		(pts
			(xy 342.431116 -242.662456) (xy 342.431116 -242.614704) (xy 342.230964 -242.614704) (xy 342.230964 -242.662456)
			(xy 342.33104 -242.762278)
		)
		(stroke
			(width 0)
			(type solid)
		)
		(fill yes)
		(layer "In2.Cu")
		(net "M_C_CPU0_SA_DQS_DP<8>")
	)
	(gr_poly
		(pts
			(xy 342.431116 -241.04219) (xy 342.431116 -240.99774) (xy 342.230964 -240.99774) (xy 342.230964 -241.04219)
			(xy 342.33104 -241.142266)
		)
		(stroke
			(width 0)
			(type solid)
		)
		(fill yes)
		(layer "In2.Cu")
		(net "M_C_CPU0_SA_DQ<27>")
	)
	(gr_poly
		(pts
			(xy 342.431116 -239.422178) (xy 342.431116 -239.377728) (xy 342.230964 -239.377728) (xy 342.230964 -239.422178)
			(xy 342.33104 -239.522254)
		)
		(stroke
			(width 0)
			(type solid)
		)
		(fill yes)
		(layer "In2.Cu")
		(net "M_C_CPU0_SA_DQ<23>")
	)
	(gr_poly
		(pts
			(xy 342.431116 -237.80242) (xy 342.431116 -237.754668) (xy 342.230964 -237.754668) (xy 342.230964 -237.80242)
			(xy 342.33104 -237.902242)
		)
		(stroke
			(width 0)
			(type solid)
		)
		(fill yes)
		(layer "In2.Cu")
		(net "M_C_CPU0_SA_DQS_DP<7>")
	)
	(gr_poly
		(pts
			(xy 342.431116 -236.182154) (xy 342.431116 -236.137704) (xy 342.230964 -236.137704) (xy 342.230964 -236.182154)
			(xy 342.33104 -236.28223)
		)
		(stroke
			(width 0)
			(type solid)
		)
		(fill yes)
		(layer "In2.Cu")
		(net "M_C_CPU0_SA_DQ<19>")
	)
	(gr_poly
		(pts
			(xy 342.431116 -234.562142) (xy 342.431116 -234.517692) (xy 342.230964 -234.517692) (xy 342.230964 -234.562142)
			(xy 342.33104 -234.662218)
		)
		(stroke
			(width 0)
			(type solid)
		)
		(fill yes)
		(layer "In2.Cu")
		(net "M_C_CPU0_SA_DQ<15>")
	)
	(gr_poly
		(pts
			(xy 342.431116 -232.942384) (xy 342.431116 -232.894632) (xy 342.230964 -232.894632) (xy 342.230964 -232.942384)
			(xy 342.33104 -233.042206)
		)
		(stroke
			(width 0)
			(type solid)
		)
		(fill yes)
		(layer "In2.Cu")
		(net "M_C_CPU0_SA_DQS_DP<6>")
	)
	(gr_poly
		(pts
			(xy 342.431116 -231.322372) (xy 342.431116 -231.277922) (xy 342.230964 -231.277922) (xy 342.230964 -231.322372)
			(xy 342.33104 -231.422448)
		)
		(stroke
			(width 0)
			(type solid)
		)
		(fill yes)
		(layer "In2.Cu")
		(net "M_C_CPU0_SA_DQ<11>")
	)
	(gr_poly
		(pts
			(xy 342.431116 -229.70236) (xy 342.431116 -229.65791) (xy 342.230964 -229.65791) (xy 342.230964 -229.70236)
			(xy 342.33104 -229.802436)
		)
		(stroke
			(width 0)
			(type solid)
		)
		(fill yes)
		(layer "In2.Cu")
		(net "M_C_CPU0_SA_DQ<7>")
	)
	(gr_poly
		(pts
			(xy 342.431116 -228.082602) (xy 342.431116 -228.03485) (xy 342.230964 -228.03485) (xy 342.230964 -228.082602)
			(xy 342.33104 -228.182424)
		)
		(stroke
			(width 0)
			(type solid)
		)
		(fill yes)
		(layer "In2.Cu")
		(net "M_C_CPU0_SA_DQS_DP<5>")
	)
	(gr_poly
		(pts
			(xy 342.431116 -226.462336) (xy 342.431116 -226.417886) (xy 342.230964 -226.417886) (xy 342.230964 -226.462336)
			(xy 342.33104 -226.562412)
		)
		(stroke
			(width 0)
			(type solid)
		)
		(fill yes)
		(layer "In2.Cu")
		(net "M_C_CPU0_SA_DQ<3>")
	)
	(gr_poly
		(pts
			(xy 342.723978 -291.297614) (xy 342.623902 -291.197792) (xy 342.523826 -291.297614) (xy 342.523826 -291.345366)
			(xy 342.723978 -291.345366)
		)
		(stroke
			(width 0)
			(type solid)
		)
		(fill yes)
		(layer "In2.Cu")
		(net "M_C_CPU0_SB_DQS_DN<8>")
	)
	(gr_poly
		(pts
			(xy 342.73109 -292.91788) (xy 342.631014 -292.817804) (xy 342.530938 -292.91788) (xy 342.530938 -292.96233)
			(xy 342.73109 -292.96233)
		)
		(stroke
			(width 0)
			(type solid)
		)
		(fill yes)
		(layer "In2.Cu")
		(net "M_C_CPU0_SB_DQ<29>")
	)
	(gr_poly
		(pts
			(xy 342.73109 -289.677856) (xy 342.631014 -289.57778) (xy 342.530938 -289.677856) (xy 342.530938 -289.722306)
			(xy 342.73109 -289.722306)
		)
		(stroke
			(width 0)
			(type solid)
		)
		(fill yes)
		(layer "In2.Cu")
		(net "M_C_CPU0_SB_DQ<25>")
	)
	(gr_poly
		(pts
			(xy 342.73109 -288.057844) (xy 342.631014 -287.957768) (xy 342.530938 -288.057844) (xy 342.530938 -288.102294)
			(xy 342.73109 -288.102294)
		)
		(stroke
			(width 0)
			(type solid)
		)
		(fill yes)
		(layer "In2.Cu")
		(net "M_C_CPU0_SB_DQ<21>")
	)
	(gr_poly
		(pts
			(xy 342.73109 -286.437832) (xy 342.631014 -286.337756) (xy 342.530938 -286.437832) (xy 342.530938 -286.485584)
			(xy 342.73109 -286.485584)
		)
		(stroke
			(width 0)
			(type solid)
		)
		(fill yes)
		(layer "In2.Cu")
		(net "M_C_CPU0_SB_DQS_DN<7>")
	)
	(gr_poly
		(pts
			(xy 342.73109 -284.818074) (xy 342.631014 -284.717998) (xy 342.530938 -284.818074) (xy 342.530938 -284.862524)
			(xy 342.73109 -284.862524)
		)
		(stroke
			(width 0)
			(type solid)
		)
		(fill yes)
		(layer "In2.Cu")
		(net "M_C_CPU0_SB_DQ<17>")
	)
	(gr_poly
		(pts
			(xy 342.73109 -283.198062) (xy 342.631014 -283.097986) (xy 342.530938 -283.198062) (xy 342.530938 -283.242512)
			(xy 342.73109 -283.242512)
		)
		(stroke
			(width 0)
			(type solid)
		)
		(fill yes)
		(layer "In2.Cu")
		(net "M_C_CPU0_SB_DQ<13>")
	)
	(gr_poly
		(pts
			(xy 342.73109 -281.577796) (xy 342.631014 -281.477974) (xy 342.530938 -281.577796) (xy 342.530938 -281.625548)
			(xy 342.73109 -281.625548)
		)
		(stroke
			(width 0)
			(type solid)
		)
		(fill yes)
		(layer "In2.Cu")
		(net "M_C_CPU0_SB_DQS_DN<6>")
	)
	(gr_poly
		(pts
			(xy 342.73109 -279.958038) (xy 342.631014 -279.857962) (xy 342.530938 -279.958038) (xy 342.530938 -280.002488)
			(xy 342.73109 -280.002488)
		)
		(stroke
			(width 0)
			(type solid)
		)
		(fill yes)
		(layer "In2.Cu")
		(net "M_C_CPU0_SB_DQ<9>")
	)
	(gr_poly
		(pts
			(xy 342.73109 -278.338026) (xy 342.631014 -278.23795) (xy 342.530938 -278.338026) (xy 342.530938 -278.382476)
			(xy 342.73109 -278.382476)
		)
		(stroke
			(width 0)
			(type solid)
		)
		(fill yes)
		(layer "In2.Cu")
		(net "M_C_CPU0_SB_DQ<5>")
	)
	(gr_poly
		(pts
			(xy 342.73109 -276.71776) (xy 342.631014 -276.617938) (xy 342.530938 -276.71776) (xy 342.530938 -276.765512)
			(xy 342.73109 -276.765512)
		)
		(stroke
			(width 0)
			(type solid)
		)
		(fill yes)
		(layer "In2.Cu")
		(net "M_C_CPU0_SB_DQS_DN<5>")
	)
	(gr_poly
		(pts
			(xy 342.73109 -275.098002) (xy 342.631014 -274.997926) (xy 342.530938 -275.098002) (xy 342.530938 -275.142452)
			(xy 342.73109 -275.142452)
		)
		(stroke
			(width 0)
			(type solid)
		)
		(fill yes)
		(layer "In2.Cu")
		(net "M_C_CPU0_SB_DQ<1>")
	)
	(gr_poly
		(pts
			(xy 342.73109 -273.47799) (xy 342.631014 -273.377914) (xy 342.530938 -273.47799) (xy 342.530938 -273.52244)
			(xy 342.73109 -273.52244)
		)
		(stroke
			(width 0)
			(type solid)
		)
		(fill yes)
		(layer "In2.Cu")
		(net "M_C_CPU0_SB_CB<1>")
	)
	(gr_poly
		(pts
			(xy 342.73109 -271.857724) (xy 342.631014 -271.757902) (xy 342.530938 -271.857724) (xy 342.530938 -271.905476)
			(xy 342.73109 -271.905476)
		)
		(stroke
			(width 0)
			(type solid)
		)
		(fill yes)
		(layer "In2.Cu")
		(net "M_C_CPU0_SB_DQS_DN<4>")
	)
	(gr_poly
		(pts
			(xy 342.73109 -270.237966) (xy 342.631014 -270.13789) (xy 342.530938 -270.237966) (xy 342.530938 -270.282416)
			(xy 342.73109 -270.282416)
		)
		(stroke
			(width 0)
			(type solid)
		)
		(fill yes)
		(layer "In2.Cu")
		(net "M_C_CPU0_SB_CB<5>")
	)
	(gr_poly
		(pts
			(xy 342.73109 -263.757918) (xy 342.631014 -263.657842) (xy 342.530938 -263.757918) (xy 342.530938 -263.802368)
			(xy 342.73109 -263.802368)
		)
		(stroke
			(width 0)
			(type solid)
		)
		(fill yes)
		(layer "In2.Cu")
		(net "M_C_CPU0_SB_CA<4>")
	)
	(gr_poly
		(pts
			(xy 342.73109 -262.137906) (xy 342.631014 -262.03783) (xy 342.530938 -262.137906) (xy 342.530938 -262.182356)
			(xy 342.73109 -262.182356)
		)
		(stroke
			(width 0)
			(type solid)
		)
		(fill yes)
		(layer "In2.Cu")
		(net "M_C_CPU0_SB_CA<0>")
	)
	(gr_poly
		(pts
			(xy 342.737186 -266.991592) (xy 342.637364 -266.891516) (xy 342.537288 -266.991592) (xy 342.537288 -267.036042)
			(xy 342.737186 -267.036042)
		)
		(stroke
			(width 0)
			(type solid)
		)
		(fill yes)
		(layer "In2.Cu")
		(net "M_C_CPU0_SA_RSP<0>")
	)
	(gr_poly
		(pts
			(xy 342.90127 -255.216152) (xy 342.801194 -255.116076) (xy 342.701118 -255.216152) (xy 342.701118 -255.260602)
			(xy 342.90127 -255.260602)
		)
		(stroke
			(width 0)
			(type solid)
		)
		(fill yes)
		(layer "In2.Cu")
		(net "M_C_CPU0_SA_CA<6>")
	)
	(gr_poly
		(pts
			(xy 342.90127 -253.59614) (xy 342.801194 -253.496064) (xy 342.701118 -253.59614) (xy 342.701118 -253.64059)
			(xy 342.90127 -253.64059)
		)
		(stroke
			(width 0)
			(type solid)
		)
		(fill yes)
		(layer "In2.Cu")
		(net "M_C_CPU0_SA_CA<2>")
	)
	(gr_poly
		(pts
			(xy 342.90127 -250.356116) (xy 342.801194 -250.25604) (xy 342.701118 -250.356116) (xy 342.701118 -250.400566)
			(xy 342.90127 -250.400566)
		)
		(stroke
			(width 0)
			(type solid)
		)
		(fill yes)
		(layer "In2.Cu")
		(net "M_C_CPU0_ALERT_R_N")
	)
	(gr_poly
		(pts
			(xy 342.90127 -248.736104) (xy 342.801194 -248.636028) (xy 342.701118 -248.736104) (xy 342.701118 -248.780554)
			(xy 342.90127 -248.780554)
		)
		(stroke
			(width 0)
			(type solid)
		)
		(fill yes)
		(layer "In2.Cu")
		(net "M_C_CPU0_SA_CB<5>")
	)
	(gr_poly
		(pts
			(xy 342.90127 -247.115838) (xy 342.801194 -247.016016) (xy 342.701118 -247.115838) (xy 342.701118 -247.16359)
			(xy 342.90127 -247.16359)
		)
		(stroke
			(width 0)
			(type solid)
		)
		(fill yes)
		(layer "In2.Cu")
		(net "M_C_CPU0_SA_DQS_DN<9>")
	)
	(gr_poly
		(pts
			(xy 342.90127 -245.49608) (xy 342.801194 -245.396004) (xy 342.701118 -245.49608) (xy 342.701118 -245.54053)
			(xy 342.90127 -245.54053)
		)
		(stroke
			(width 0)
			(type solid)
		)
		(fill yes)
		(layer "In2.Cu")
		(net "M_C_CPU0_SA_CB<1>")
	)
	(gr_poly
		(pts
			(xy 342.90127 -243.876068) (xy 342.801194 -243.775992) (xy 342.701118 -243.876068) (xy 342.701118 -243.920518)
			(xy 342.90127 -243.920518)
		)
		(stroke
			(width 0)
			(type solid)
		)
		(fill yes)
		(layer "In2.Cu")
		(net "M_C_CPU0_SA_DQ<29>")
	)
	(gr_poly
		(pts
			(xy 342.90127 -242.255802) (xy 342.801194 -242.15598) (xy 342.701118 -242.255802) (xy 342.701118 -242.303554)
			(xy 342.90127 -242.303554)
		)
		(stroke
			(width 0)
			(type solid)
		)
		(fill yes)
		(layer "In2.Cu")
		(net "M_C_CPU0_SA_DQS_DN<8>")
	)
	(gr_poly
		(pts
			(xy 342.90127 -240.636044) (xy 342.801194 -240.535968) (xy 342.701118 -240.636044) (xy 342.701118 -240.680494)
			(xy 342.90127 -240.680494)
		)
		(stroke
			(width 0)
			(type solid)
		)
		(fill yes)
		(layer "In2.Cu")
		(net "M_C_CPU0_SA_DQ<25>")
	)
	(gr_poly
		(pts
			(xy 342.90127 -239.016032) (xy 342.801194 -238.915956) (xy 342.701118 -239.016032) (xy 342.701118 -239.060482)
			(xy 342.90127 -239.060482)
		)
		(stroke
			(width 0)
			(type solid)
		)
		(fill yes)
		(layer "In2.Cu")
		(net "M_C_CPU0_SA_DQ<21>")
	)
	(gr_poly
		(pts
			(xy 342.90127 -237.395766) (xy 342.801194 -237.295944) (xy 342.701118 -237.395766) (xy 342.701118 -237.443518)
			(xy 342.90127 -237.443518)
		)
		(stroke
			(width 0)
			(type solid)
		)
		(fill yes)
		(layer "In2.Cu")
		(net "M_C_CPU0_SA_DQS_DN<7>")
	)
	(gr_poly
		(pts
			(xy 342.90127 -235.776008) (xy 342.801194 -235.675932) (xy 342.701118 -235.776008) (xy 342.701118 -235.820458)
			(xy 342.90127 -235.820458)
		)
		(stroke
			(width 0)
			(type solid)
		)
		(fill yes)
		(layer "In2.Cu")
		(net "M_C_CPU0_SA_DQ<17>")
	)
	(gr_poly
		(pts
			(xy 342.90127 -234.155996) (xy 342.801194 -234.05592) (xy 342.701118 -234.155996) (xy 342.701118 -234.200446)
			(xy 342.90127 -234.200446)
		)
		(stroke
			(width 0)
			(type solid)
		)
		(fill yes)
		(layer "In2.Cu")
		(net "M_C_CPU0_SA_DQ<13>")
	)
	(gr_poly
		(pts
			(xy 342.90127 -232.53573) (xy 342.801194 -232.435908) (xy 342.701118 -232.53573) (xy 342.701118 -232.583482)
			(xy 342.90127 -232.583482)
		)
		(stroke
			(width 0)
			(type solid)
		)
		(fill yes)
		(layer "In2.Cu")
		(net "M_C_CPU0_SA_DQS_DN<6>")
	)
	(gr_poly
		(pts
			(xy 342.90127 -230.915972) (xy 342.801194 -230.815896) (xy 342.701118 -230.915972) (xy 342.701118 -230.960422)
			(xy 342.90127 -230.960422)
		)
		(stroke
			(width 0)
			(type solid)
		)
		(fill yes)
		(layer "In2.Cu")
		(net "M_C_CPU0_SA_DQ<9>")
	)
	(gr_poly
		(pts
			(xy 342.90127 -229.29596) (xy 342.801194 -229.195884) (xy 342.701118 -229.29596) (xy 342.701118 -229.34041)
			(xy 342.90127 -229.34041)
		)
		(stroke
			(width 0)
			(type solid)
		)
		(fill yes)
		(layer "In2.Cu")
		(net "M_C_CPU0_SA_DQ<5>")
	)
	(gr_poly
		(pts
			(xy 342.90127 -227.675948) (xy 342.801194 -227.576126) (xy 342.701118 -227.675948) (xy 342.701118 -227.7237)
			(xy 342.90127 -227.7237)
		)
		(stroke
			(width 0)
			(type solid)
		)
		(fill yes)
		(layer "In2.Cu")
		(net "M_C_CPU0_SA_DQS_DN<5>")
	)
	(gr_poly
		(pts
			(xy 342.90127 -226.05619) (xy 342.801194 -225.956114) (xy 342.701118 -226.05619) (xy 342.701118 -226.10064)
			(xy 342.90127 -226.10064)
		)
		(stroke
			(width 0)
			(type solid)
		)
		(fill yes)
		(layer "In2.Cu")
		(net "M_C_CPU0_SA_DQ<1>")
	)
	(gr_poly
		(pts
			(xy 343.193878 -291.704268) (xy 343.193878 -291.656516) (xy 342.993726 -291.656516) (xy 342.993726 -291.704268)
			(xy 343.093802 -291.80409)
		)
		(stroke
			(width 0)
			(type solid)
		)
		(fill yes)
		(layer "In2.Cu")
		(net "M_C_CPU0_SB_DQS_DP<8>")
	)
	(gr_poly
		(pts
			(xy 343.201244 -293.324026) (xy 343.201244 -293.279576) (xy 343.001092 -293.279576) (xy 343.001092 -293.324026)
			(xy 343.101168 -293.424102)
		)
		(stroke
			(width 0)
			(type solid)
		)
		(fill yes)
		(layer "In2.Cu")
		(net "M_C_CPU0_SB_DQ<31>")
	)
	(gr_poly
		(pts
			(xy 343.201244 -290.084002) (xy 343.201244 -290.039552) (xy 343.001092 -290.039552) (xy 343.001092 -290.084002)
			(xy 343.101168 -290.184078)
		)
		(stroke
			(width 0)
			(type solid)
		)
		(fill yes)
		(layer "In2.Cu")
		(net "M_C_CPU0_SB_DQ<27>")
	)
	(gr_poly
		(pts
			(xy 343.201244 -288.464244) (xy 343.201244 -288.419794) (xy 343.001092 -288.419794) (xy 343.001092 -288.464244)
			(xy 343.101168 -288.56432)
		)
		(stroke
			(width 0)
			(type solid)
		)
		(fill yes)
		(layer "In2.Cu")
		(net "M_C_CPU0_SB_DQ<23>")
	)
	(gr_poly
		(pts
			(xy 343.201244 -286.844232) (xy 343.201244 -286.79648) (xy 343.001092 -286.79648) (xy 343.001092 -286.844232)
			(xy 343.101168 -286.944308)
		)
		(stroke
			(width 0)
			(type solid)
		)
		(fill yes)
		(layer "In2.Cu")
		(net "M_C_CPU0_SB_DQS_DP<7>")
	)
	(gr_poly
		(pts
			(xy 343.201244 -285.22422) (xy 343.201244 -285.17977) (xy 343.001092 -285.17977) (xy 343.001092 -285.22422)
			(xy 343.101168 -285.324296)
		)
		(stroke
			(width 0)
			(type solid)
		)
		(fill yes)
		(layer "In2.Cu")
		(net "M_C_CPU0_SB_DQ<19>")
	)
	(gr_poly
		(pts
			(xy 343.201244 -283.604208) (xy 343.201244 -283.559758) (xy 343.001092 -283.559758) (xy 343.001092 -283.604208)
			(xy 343.101168 -283.704284)
		)
		(stroke
			(width 0)
			(type solid)
		)
		(fill yes)
		(layer "In2.Cu")
		(net "M_C_CPU0_SB_DQ<15>")
	)
	(gr_poly
		(pts
			(xy 343.201244 -281.98445) (xy 343.201244 -281.936698) (xy 343.001092 -281.936698) (xy 343.001092 -281.98445)
			(xy 343.101168 -282.084272)
		)
		(stroke
			(width 0)
			(type solid)
		)
		(fill yes)
		(layer "In2.Cu")
		(net "M_C_CPU0_SB_DQS_DP<6>")
	)
	(gr_poly
		(pts
			(xy 343.201244 -280.364184) (xy 343.201244 -280.319734) (xy 343.001092 -280.319734) (xy 343.001092 -280.364184)
			(xy 343.101168 -280.46426)
		)
		(stroke
			(width 0)
			(type solid)
		)
		(fill yes)
		(layer "In2.Cu")
		(net "M_C_CPU0_SB_DQ<11>")
	)
	(gr_poly
		(pts
			(xy 343.201244 -278.744172) (xy 343.201244 -278.699722) (xy 343.001092 -278.699722) (xy 343.001092 -278.744172)
			(xy 343.101168 -278.844248)
		)
		(stroke
			(width 0)
			(type solid)
		)
		(fill yes)
		(layer "In2.Cu")
		(net "M_C_CPU0_SB_DQ<7>")
	)
	(gr_poly
		(pts
			(xy 343.201244 -277.124414) (xy 343.201244 -277.076662) (xy 343.001092 -277.076662) (xy 343.001092 -277.124414)
			(xy 343.101168 -277.224236)
		)
		(stroke
			(width 0)
			(type solid)
		)
		(fill yes)
		(layer "In2.Cu")
		(net "M_C_CPU0_SB_DQS_DP<5>")
	)
	(gr_poly
		(pts
			(xy 343.201244 -275.504148) (xy 343.201244 -275.459698) (xy 343.001092 -275.459698) (xy 343.001092 -275.504148)
			(xy 343.101168 -275.604224)
		)
		(stroke
			(width 0)
			(type solid)
		)
		(fill yes)
		(layer "In2.Cu")
		(net "M_C_CPU0_SB_DQ<3>")
	)
	(gr_poly
		(pts
			(xy 343.201244 -273.884136) (xy 343.201244 -273.839686) (xy 343.001092 -273.839686) (xy 343.001092 -273.884136)
			(xy 343.101168 -273.984212)
		)
		(stroke
			(width 0)
			(type solid)
		)
		(fill yes)
		(layer "In2.Cu")
		(net "M_C_CPU0_SB_CB<3>")
	)
	(gr_poly
		(pts
			(xy 343.201244 -272.264378) (xy 343.201244 -272.216626) (xy 343.001092 -272.216626) (xy 343.001092 -272.264378)
			(xy 343.101168 -272.3642)
		)
		(stroke
			(width 0)
			(type solid)
		)
		(fill yes)
		(layer "In2.Cu")
		(net "M_C_CPU0_SB_DQS_DP<4>")
	)
	(gr_poly
		(pts
			(xy 343.201244 -270.644112) (xy 343.201244 -270.599662) (xy 343.001092 -270.599662) (xy 343.001092 -270.644112)
			(xy 343.101168 -270.744188)
		)
		(stroke
			(width 0)
			(type solid)
		)
		(fill yes)
		(layer "In2.Cu")
		(net "M_C_CPU0_SB_CB<7>")
	)
	(gr_poly
		(pts
			(xy 343.201244 -265.784076) (xy 343.201244 -265.739626) (xy 343.001092 -265.739626) (xy 343.001092 -265.784076)
			(xy 343.101168 -265.884152)
		)
		(stroke
			(width 0)
			(type solid)
		)
		(fill yes)
		(layer "In2.Cu")
		(net "M_C_CPU0_SB_CS_N<0>")
	)
	(gr_poly
		(pts
			(xy 343.201244 -264.164064) (xy 343.201244 -264.119614) (xy 343.001092 -264.119614) (xy 343.001092 -264.164064)
			(xy 343.101168 -264.26414)
		)
		(stroke
			(width 0)
			(type solid)
		)
		(fill yes)
		(layer "In2.Cu")
		(net "M_C_CPU0_SB_CA<5>")
	)
	(gr_poly
		(pts
			(xy 343.201244 -262.544052) (xy 343.201244 -262.499602) (xy 343.001092 -262.499602) (xy 343.001092 -262.544052)
			(xy 343.101168 -262.644128)
		)
		(stroke
			(width 0)
			(type solid)
		)
		(fill yes)
		(layer "In2.Cu")
		(net "M_C_CPU0_SB_CA<1>")
	)
	(gr_poly
		(pts
			(xy 343.318846 -247.529096) (xy 343.323164 -247.481598) (xy 343.123774 -247.464072) (xy 343.11971 -247.51157)
			(xy 343.210642 -247.620028)
		)
		(stroke
			(width 0)
			(type solid)
		)
		(fill yes)
		(layer "In2.Cu")
		(net "M_C_CPU0_SA_DQS_DP<9>")
	)
	(gr_poly
		(pts
			(xy 343.318846 -242.66906) (xy 343.323164 -242.621562) (xy 343.123774 -242.604036) (xy 343.11971 -242.651534)
			(xy 343.210642 -242.759992)
		)
		(stroke
			(width 0)
			(type solid)
		)
		(fill yes)
		(layer "In2.Cu")
		(net "M_C_CPU0_SA_DQS_DP<8>")
	)
	(gr_poly
		(pts
			(xy 343.318846 -237.809024) (xy 343.323164 -237.761526) (xy 343.123774 -237.744) (xy 343.11971 -237.791498)
			(xy 343.210642 -237.899956)
		)
		(stroke
			(width 0)
			(type solid)
		)
		(fill yes)
		(layer "In2.Cu")
		(net "M_C_CPU0_SA_DQS_DP<7>")
	)
	(gr_poly
		(pts
			(xy 343.318846 -232.948988) (xy 343.323164 -232.90149) (xy 343.123774 -232.883964) (xy 343.11971 -232.931462)
			(xy 343.210642 -233.03992)
		)
		(stroke
			(width 0)
			(type solid)
		)
		(fill yes)
		(layer "In2.Cu")
		(net "M_C_CPU0_SA_DQS_DP<6>")
	)
	(gr_poly
		(pts
			(xy 343.329514 -228.089968) (xy 343.333578 -228.04247) (xy 343.134442 -228.024944) (xy 343.130378 -228.072442)
			(xy 343.22131 -228.1809)
		)
		(stroke
			(width 0)
			(type solid)
		)
		(fill yes)
		(layer "In2.Cu")
		(net "M_C_CPU0_SA_DQS_DP<5>")
	)
	(gr_poly
		(pts
			(xy 343.331546 -255.629918) (xy 343.33561 -255.585468) (xy 343.13622 -255.568196) (xy 343.13241 -255.612392)
			(xy 343.223342 -255.72085)
		)
		(stroke
			(width 0)
			(type solid)
		)
		(fill yes)
		(layer "In2.Cu")
		(net "M_C_CPU0_SA_PAR")
	)
	(gr_poly
		(pts
			(xy 343.331546 -254.009906) (xy 343.33561 -253.965456) (xy 343.13622 -253.948184) (xy 343.13241 -253.99238)
			(xy 343.223342 -254.100838)
		)
		(stroke
			(width 0)
			(type solid)
		)
		(fill yes)
		(layer "In2.Cu")
		(net "M_C_CPU0_SA_CA<3>")
	)
	(gr_poly
		(pts
			(xy 343.331546 -252.389894) (xy 343.33561 -252.345444) (xy 343.13622 -252.328172) (xy 343.13241 -252.372368)
			(xy 343.223342 -252.480826)
		)
		(stroke
			(width 0)
			(type solid)
		)
		(fill yes)
		(layer "In2.Cu")
		(net "M_C_CPU0_SA_CS_N<1>")
	)
	(gr_poly
		(pts
			(xy 343.331546 -250.769882) (xy 343.33561 -250.725432) (xy 343.13622 -250.70816) (xy 343.13241 -250.752356)
			(xy 343.223342 -250.860814)
		)
		(stroke
			(width 0)
			(type solid)
		)
		(fill yes)
		(layer "In2.Cu")
		(net "M_C_CPU0_RESET_N")
	)
	(gr_poly
		(pts
			(xy 343.331546 -249.14987) (xy 343.33561 -249.10542) (xy 343.13622 -249.088148) (xy 343.13241 -249.132344)
			(xy 343.223342 -249.240802)
		)
		(stroke
			(width 0)
			(type solid)
		)
		(fill yes)
		(layer "In2.Cu")
		(net "M_C_CPU0_SA_CB<7>")
	)
	(gr_poly
		(pts
			(xy 343.331546 -245.909846) (xy 343.33561 -245.865396) (xy 343.13622 -245.848124) (xy 343.13241 -245.89232)
			(xy 343.223342 -246.000778)
		)
		(stroke
			(width 0)
			(type solid)
		)
		(fill yes)
		(layer "In2.Cu")
		(net "M_C_CPU0_SA_CB<3>")
	)
	(gr_poly
		(pts
			(xy 343.331546 -244.289834) (xy 343.33561 -244.245384) (xy 343.13622 -244.228112) (xy 343.13241 -244.272308)
			(xy 343.223342 -244.380766)
		)
		(stroke
			(width 0)
			(type solid)
		)
		(fill yes)
		(layer "In2.Cu")
		(net "M_C_CPU0_SA_DQ<31>")
	)
	(gr_poly
		(pts
			(xy 343.331546 -241.04981) (xy 343.33561 -241.00536) (xy 343.13622 -240.988088) (xy 343.13241 -241.032284)
			(xy 343.223342 -241.140742)
		)
		(stroke
			(width 0)
			(type solid)
		)
		(fill yes)
		(layer "In2.Cu")
		(net "M_C_CPU0_SA_DQ<27>")
	)
	(gr_poly
		(pts
			(xy 343.331546 -239.429798) (xy 343.33561 -239.385348) (xy 343.13622 -239.368076) (xy 343.13241 -239.412272)
			(xy 343.223342 -239.52073)
		)
		(stroke
			(width 0)
			(type solid)
		)
		(fill yes)
		(layer "In2.Cu")
		(net "M_C_CPU0_SA_DQ<23>")
	)
	(gr_poly
		(pts
			(xy 343.331546 -236.189774) (xy 343.33561 -236.145324) (xy 343.13622 -236.128052) (xy 343.13241 -236.172248)
			(xy 343.223342 -236.280706)
		)
		(stroke
			(width 0)
			(type solid)
		)
		(fill yes)
		(layer "In2.Cu")
		(net "M_C_CPU0_SA_DQ<19>")
	)
	(gr_poly
		(pts
			(xy 343.331546 -234.569762) (xy 343.33561 -234.525312) (xy 343.13622 -234.50804) (xy 343.13241 -234.552236)
			(xy 343.223342 -234.660694)
		)
		(stroke
			(width 0)
			(type solid)
		)
		(fill yes)
		(layer "In2.Cu")
		(net "M_C_CPU0_SA_DQ<15>")
	)
	(gr_poly
		(pts
			(xy 343.331546 -226.469956) (xy 343.33561 -226.425506) (xy 343.13622 -226.408234) (xy 343.13241 -226.45243)
			(xy 343.223342 -226.560888)
		)
		(stroke
			(width 0)
			(type solid)
		)
		(fill yes)
		(layer "In2.Cu")
		(net "M_C_CPU0_SA_DQ<3>")
	)
	(gr_poly
		(pts
			(xy 343.3318 -231.329738) (xy 343.33561 -231.285542) (xy 343.136474 -231.26827) (xy 343.13241 -231.312466)
			(xy 343.223342 -231.42067)
		)
		(stroke
			(width 0)
			(type solid)
		)
		(fill yes)
		(layer "In2.Cu")
		(net "M_C_CPU0_SA_DQ<11>")
	)
	(gr_poly
		(pts
			(xy 343.3318 -229.70998) (xy 343.33561 -229.66553) (xy 343.136474 -229.648258) (xy 343.13241 -229.692454)
			(xy 343.223342 -229.800658)
		)
		(stroke
			(width 0)
			(type solid)
		)
		(fill yes)
		(layer "In2.Cu")
		(net "M_C_CPU0_SA_DQ<7>")
	)
	(gr_poly
		(pts
			(xy 343.62263 -291.338508) (xy 343.618566 -291.29101) (xy 343.510362 -291.200078) (xy 343.41943 -291.308536)
			(xy 343.423494 -291.35578)
		)
		(stroke
			(width 0)
			(type solid)
		)
		(fill yes)
		(layer "In2.Cu")
		(net "M_C_CPU0_SB_DQS_DN<8>")
	)
	(gr_poly
		(pts
			(xy 343.622884 -271.898618) (xy 343.618566 -271.85112) (xy 343.510362 -271.760188) (xy 343.41943 -271.868646)
			(xy 343.423494 -271.916144)
		)
		(stroke
			(width 0)
			(type solid)
		)
		(fill yes)
		(layer "In2.Cu")
		(net "M_C_CPU0_SB_DQS_DN<4>")
	)
	(gr_poly
		(pts
			(xy 343.633806 -286.477964) (xy 343.629742 -286.430466) (xy 343.521284 -286.339534) (xy 343.430352 -286.447738)
			(xy 343.43467 -286.495236)
		)
		(stroke
			(width 0)
			(type solid)
		)
		(fill yes)
		(layer "In2.Cu")
		(net "M_C_CPU0_SB_DQS_DN<7>")
	)
	(gr_poly
		(pts
			(xy 343.633806 -281.617928) (xy 343.629742 -281.57043) (xy 343.521284 -281.479498) (xy 343.430352 -281.587702)
			(xy 343.43467 -281.6352)
		)
		(stroke
			(width 0)
			(type solid)
		)
		(fill yes)
		(layer "In2.Cu")
		(net "M_C_CPU0_SB_DQS_DN<6>")
	)
	(gr_poly
		(pts
			(xy 343.633806 -276.757892) (xy 343.629742 -276.710394) (xy 343.521284 -276.619462) (xy 343.430352 -276.727666)
			(xy 343.43467 -276.775164)
		)
		(stroke
			(width 0)
			(type solid)
		)
		(fill yes)
		(layer "In2.Cu")
		(net "M_C_CPU0_SB_DQS_DN<5>")
	)
	(gr_poly
		(pts
			(xy 343.63533 -292.95471) (xy 343.63152 -292.91026) (xy 343.523062 -292.819582) (xy 343.43213 -292.927786)
			(xy 343.436194 -292.971982)
		)
		(stroke
			(width 0)
			(type solid)
		)
		(fill yes)
		(layer "In2.Cu")
		(net "M_C_CPU0_SB_DQ<29>")
	)
	(gr_poly
		(pts
			(xy 343.63533 -289.714686) (xy 343.63152 -289.670236) (xy 343.523062 -289.579558) (xy 343.43213 -289.687762)
			(xy 343.436194 -289.731958)
		)
		(stroke
			(width 0)
			(type solid)
		)
		(fill yes)
		(layer "In2.Cu")
		(net "M_C_CPU0_SB_DQ<25>")
	)
	(gr_poly
		(pts
			(xy 343.63533 -284.854904) (xy 343.63152 -284.810708) (xy 343.523062 -284.719776) (xy 343.43213 -284.82798)
			(xy 343.436194 -284.872176)
		)
		(stroke
			(width 0)
			(type solid)
		)
		(fill yes)
		(layer "In2.Cu")
		(net "M_C_CPU0_SB_DQ<17>")
	)
	(gr_poly
		(pts
			(xy 343.63533 -283.234892) (xy 343.63152 -283.190696) (xy 343.523062 -283.099764) (xy 343.43213 -283.207968)
			(xy 343.436194 -283.252164)
		)
		(stroke
			(width 0)
			(type solid)
		)
		(fill yes)
		(layer "In2.Cu")
		(net "M_C_CPU0_SB_DQ<13>")
	)
	(gr_poly
		(pts
			(xy 343.63533 -279.994868) (xy 343.63152 -279.950672) (xy 343.523062 -279.85974) (xy 343.43213 -279.967944)
			(xy 343.436194 -280.01214)
		)
		(stroke
			(width 0)
			(type solid)
		)
		(fill yes)
		(layer "In2.Cu")
		(net "M_C_CPU0_SB_DQ<9>")
	)
	(gr_poly
		(pts
			(xy 343.63533 -278.374856) (xy 343.63152 -278.33066) (xy 343.523062 -278.239728) (xy 343.43213 -278.347932)
			(xy 343.436194 -278.392128)
		)
		(stroke
			(width 0)
			(type solid)
		)
		(fill yes)
		(layer "In2.Cu")
		(net "M_C_CPU0_SB_DQ<5>")
	)
	(gr_poly
		(pts
			(xy 343.63533 -275.134832) (xy 343.63152 -275.090636) (xy 343.523062 -274.999704) (xy 343.43213 -275.107908)
			(xy 343.436194 -275.152104)
		)
		(stroke
			(width 0)
			(type solid)
		)
		(fill yes)
		(layer "In2.Cu")
		(net "M_C_CPU0_SB_DQ<1>")
	)
	(gr_poly
		(pts
			(xy 343.63533 -273.51482) (xy 343.63152 -273.470624) (xy 343.523062 -273.379692) (xy 343.43213 -273.487896)
			(xy 343.436194 -273.532092)
		)
		(stroke
			(width 0)
			(type solid)
		)
		(fill yes)
		(layer "In2.Cu")
		(net "M_C_CPU0_SB_CB<1>")
	)
	(gr_poly
		(pts
			(xy 343.63533 -270.274796) (xy 343.63152 -270.2306) (xy 343.523062 -270.139668) (xy 343.43213 -270.247872)
			(xy 343.436194 -270.292068)
		)
		(stroke
			(width 0)
			(type solid)
		)
		(fill yes)
		(layer "In2.Cu")
		(net "M_C_CPU0_SB_CB<5>")
	)
	(gr_poly
		(pts
			(xy 343.63533 -263.794748) (xy 343.63152 -263.750552) (xy 343.523062 -263.65962) (xy 343.43213 -263.767824)
			(xy 343.436194 -263.81202)
		)
		(stroke
			(width 0)
			(type solid)
		)
		(fill yes)
		(layer "In2.Cu")
		(net "M_C_CPU0_SB_CA<4>")
	)
	(gr_poly
		(pts
			(xy 343.63533 -262.174736) (xy 343.63152 -262.13054) (xy 343.523062 -262.039608) (xy 343.43213 -262.147812)
			(xy 343.436194 -262.192008)
		)
		(stroke
			(width 0)
			(type solid)
		)
		(fill yes)
		(layer "In2.Cu")
		(net "M_C_CPU0_SB_CA<0>")
	)
	(gr_poly
		(pts
			(xy 343.635584 -288.094674) (xy 343.631774 -288.050224) (xy 343.523316 -287.959546) (xy 343.432384 -288.06775)
			(xy 343.436448 -288.111946)
		)
		(stroke
			(width 0)
			(type solid)
		)
		(fill yes)
		(layer "In2.Cu")
		(net "M_C_CPU0_SB_DQ<21>")
	)
	(gr_poly
		(pts
			(xy 343.63914 -267.028168) (xy 343.63533 -266.983718) (xy 343.527126 -266.89304) (xy 343.436194 -267.001244)
			(xy 343.440004 -267.04544)
		)
		(stroke
			(width 0)
			(type solid)
		)
		(fill yes)
		(layer "In2.Cu")
		(net "M_C_CPU0_SA_RSP<0>")
	)
	(gr_poly
		(pts
			(xy 376.30354 -231.312466) (xy 376.299476 -231.26827) (xy 376.10034 -231.285542) (xy 376.10415 -231.329738)
			(xy 376.212608 -231.42067)
		)
		(stroke
			(width 0)
			(type solid)
		)
		(fill yes)
		(layer "In2.Cu")
		(net "M_I_CPU0_SA_DQ<11>")
	)
	(gr_poly
		(pts
			(xy 376.30354 -229.692454) (xy 376.299476 -229.648258) (xy 376.10034 -229.66553) (xy 376.10415 -229.70998)
			(xy 376.212608 -229.800658)
		)
		(stroke
			(width 0)
			(type solid)
		)
		(fill yes)
		(layer "In2.Cu")
		(net "M_I_CPU0_SA_DQ<7>")
	)
	(gr_poly
		(pts
			(xy 376.303794 -255.612392) (xy 376.29973 -255.568196) (xy 376.100594 -255.585468) (xy 376.104404 -255.629664)
			(xy 376.212862 -255.720596)
		)
		(stroke
			(width 0)
			(type solid)
		)
		(fill yes)
		(layer "In2.Cu")
		(net "M_I_CPU0_SA_PAR")
	)
	(gr_poly
		(pts
			(xy 376.303794 -253.99238) (xy 376.29973 -253.948184) (xy 376.100594 -253.965456) (xy 376.104404 -254.009652)
			(xy 376.212862 -254.100584)
		)
		(stroke
			(width 0)
			(type solid)
		)
		(fill yes)
		(layer "In2.Cu")
		(net "M_I_CPU0_SA_CA<3>")
	)
	(gr_poly
		(pts
			(xy 376.303794 -250.752356) (xy 376.29973 -250.70816) (xy 376.100594 -250.725432) (xy 376.104404 -250.769628)
			(xy 376.212862 -250.86056)
		)
		(stroke
			(width 0)
			(type solid)
		)
		(fill yes)
		(layer "In2.Cu")
		(net "M_I_CPU0_RESET_N")
	)
	(gr_poly
		(pts
			(xy 376.303794 -249.132344) (xy 376.29973 -249.088148) (xy 376.100594 -249.10542) (xy 376.104404 -249.14987)
			(xy 376.212862 -249.240548)
		)
		(stroke
			(width 0)
			(type solid)
		)
		(fill yes)
		(layer "In2.Cu")
		(net "M_I_CPU0_SA_CB<7>")
	)
	(gr_poly
		(pts
			(xy 376.303794 -245.89232) (xy 376.29973 -245.848124) (xy 376.100594 -245.865396) (xy 376.104404 -245.909592)
			(xy 376.212862 -246.000524)
		)
		(stroke
			(width 0)
			(type solid)
		)
		(fill yes)
		(layer "In2.Cu")
		(net "M_I_CPU0_SA_CB<3>")
	)
	(gr_poly
		(pts
			(xy 376.303794 -244.272308) (xy 376.29973 -244.228112) (xy 376.100594 -244.245384) (xy 376.104404 -244.289834)
			(xy 376.212862 -244.380512)
		)
		(stroke
			(width 0)
			(type solid)
		)
		(fill yes)
		(layer "In2.Cu")
		(net "M_I_CPU0_SA_DQ<31>")
	)
	(gr_poly
		(pts
			(xy 376.303794 -241.032284) (xy 376.29973 -240.988088) (xy 376.100594 -241.00536) (xy 376.104404 -241.049556)
			(xy 376.212862 -241.140488)
		)
		(stroke
			(width 0)
			(type solid)
		)
		(fill yes)
		(layer "In2.Cu")
		(net "M_I_CPU0_SA_DQ<27>")
	)
	(gr_poly
		(pts
			(xy 376.303794 -239.412272) (xy 376.29973 -239.368076) (xy 376.100594 -239.385348) (xy 376.104404 -239.429544)
			(xy 376.212862 -239.520476)
		)
		(stroke
			(width 0)
			(type solid)
		)
		(fill yes)
		(layer "In2.Cu")
		(net "M_I_CPU0_SA_DQ<23>")
	)
	(gr_poly
		(pts
			(xy 376.303794 -236.172248) (xy 376.29973 -236.128052) (xy 376.100594 -236.145324) (xy 376.104404 -236.18952)
			(xy 376.212862 -236.280452)
		)
		(stroke
			(width 0)
			(type solid)
		)
		(fill yes)
		(layer "In2.Cu")
		(net "M_I_CPU0_SA_DQ<19>")
	)
	(gr_poly
		(pts
			(xy 376.303794 -234.552236) (xy 376.29973 -234.50804) (xy 376.100594 -234.525312) (xy 376.104404 -234.569508)
			(xy 376.212862 -234.66044)
		)
		(stroke
			(width 0)
			(type solid)
		)
		(fill yes)
		(layer "In2.Cu")
		(net "M_I_CPU0_SA_DQ<15>")
	)
	(gr_poly
		(pts
			(xy 376.303794 -226.45243) (xy 376.29973 -226.408234) (xy 376.100594 -226.425506) (xy 376.104404 -226.469702)
			(xy 376.212862 -226.560634)
		)
		(stroke
			(width 0)
			(type solid)
		)
		(fill yes)
		(layer "In2.Cu")
		(net "M_I_CPU0_SA_DQ<3>")
	)
	(gr_poly
		(pts
			(xy 376.316494 -247.51157) (xy 376.31243 -247.464072) (xy 376.11304 -247.481598) (xy 376.117358 -247.529096)
			(xy 376.225562 -247.620028)
		)
		(stroke
			(width 0)
			(type solid)
		)
		(fill yes)
		(layer "In2.Cu")
		(net "M_I_CPU0_SA_DQS_DP<9>")
	)
	(gr_poly
		(pts
			(xy 376.316494 -242.651534) (xy 376.31243 -242.604036) (xy 376.11304 -242.621562) (xy 376.117358 -242.66906)
			(xy 376.225562 -242.759992)
		)
		(stroke
			(width 0)
			(type solid)
		)
		(fill yes)
		(layer "In2.Cu")
		(net "M_I_CPU0_SA_DQS_DP<8>")
	)
	(gr_poly
		(pts
			(xy 376.316494 -237.791498) (xy 376.31243 -237.744) (xy 376.11304 -237.761526) (xy 376.117358 -237.809024)
			(xy 376.225562 -237.899956)
		)
		(stroke
			(width 0)
			(type solid)
		)
		(fill yes)
		(layer "In2.Cu")
		(net "M_I_CPU0_SA_DQS_DP<7>")
	)
	(gr_poly
		(pts
			(xy 376.316494 -232.931462) (xy 376.31243 -232.883964) (xy 376.11304 -232.90149) (xy 376.117358 -232.948988)
			(xy 376.225562 -233.03992)
		)
		(stroke
			(width 0)
			(type solid)
		)
		(fill yes)
		(layer "In2.Cu")
		(net "M_I_CPU0_SA_DQS_DP<6>")
	)
	(gr_poly
		(pts
			(xy 376.316494 -228.07168) (xy 376.31243 -228.024436) (xy 376.11304 -228.041708) (xy 376.117358 -228.089206)
			(xy 376.225562 -228.180138)
		)
		(stroke
			(width 0)
			(type solid)
		)
		(fill yes)
		(layer "In2.Cu")
		(net "M_I_CPU0_SA_DQS_DP<5>")
	)
	(gr_poly
		(pts
			(xy 376.603514 -292.927786) (xy 376.512582 -292.819328) (xy 376.404378 -292.91026) (xy 376.400568 -292.95471)
			(xy 376.599704 -292.971982)
		)
		(stroke
			(width 0)
			(type solid)
		)
		(fill yes)
		(layer "In2.Cu")
		(net "M_I_CPU0_SB_DQ<29>")
	)
	(gr_poly
		(pts
			(xy 376.603514 -289.687762) (xy 376.512582 -289.579304) (xy 376.404378 -289.670236) (xy 376.400568 -289.714686)
			(xy 376.599704 -289.731958)
		)
		(stroke
			(width 0)
			(type solid)
		)
		(fill yes)
		(layer "In2.Cu")
		(net "M_I_CPU0_SB_DQ<25>")
	)
	(gr_poly
		(pts
			(xy 376.603514 -288.06775) (xy 376.512582 -287.959546) (xy 376.404124 -288.050224) (xy 376.400314 -288.094674)
			(xy 376.59945 -288.111946)
		)
		(stroke
			(width 0)
			(type solid)
		)
		(fill yes)
		(layer "In2.Cu")
		(net "M_I_CPU0_SB_DQ<21>")
	)
	(gr_poly
		(pts
			(xy 376.603514 -284.82798) (xy 376.512582 -284.719522) (xy 376.404378 -284.810454) (xy 376.400568 -284.854904)
			(xy 376.599704 -284.872176)
		)
		(stroke
			(width 0)
			(type solid)
		)
		(fill yes)
		(layer "In2.Cu")
		(net "M_I_CPU0_SB_DQ<17>")
	)
	(gr_poly
		(pts
			(xy 376.603514 -283.207968) (xy 376.512582 -283.09951) (xy 376.404378 -283.190442) (xy 376.400568 -283.234892)
			(xy 376.599704 -283.252164)
		)
		(stroke
			(width 0)
			(type solid)
		)
		(fill yes)
		(layer "In2.Cu")
		(net "M_I_CPU0_SB_DQ<13>")
	)
	(gr_poly
		(pts
			(xy 376.603514 -279.967944) (xy 376.512582 -279.859486) (xy 376.404378 -279.950418) (xy 376.400568 -279.994868)
			(xy 376.599704 -280.01214)
		)
		(stroke
			(width 0)
			(type solid)
		)
		(fill yes)
		(layer "In2.Cu")
		(net "M_I_CPU0_SB_DQ<9>")
	)
	(gr_poly
		(pts
			(xy 376.603514 -278.347932) (xy 376.512582 -278.239474) (xy 376.404378 -278.330406) (xy 376.400568 -278.374856)
			(xy 376.599704 -278.392128)
		)
		(stroke
			(width 0)
			(type solid)
		)
		(fill yes)
		(layer "In2.Cu")
		(net "M_I_CPU0_SB_DQ<5>")
	)
	(gr_poly
		(pts
			(xy 376.603514 -275.107908) (xy 376.512582 -274.99945) (xy 376.404378 -275.090382) (xy 376.400568 -275.134832)
			(xy 376.599704 -275.152104)
		)
		(stroke
			(width 0)
			(type solid)
		)
		(fill yes)
		(layer "In2.Cu")
		(net "M_I_CPU0_SB_DQ<1>")
	)
	(gr_poly
		(pts
			(xy 376.603514 -273.487896) (xy 376.512582 -273.379438) (xy 376.404378 -273.47037) (xy 376.400568 -273.51482)
			(xy 376.599704 -273.532092)
		)
		(stroke
			(width 0)
			(type solid)
		)
		(fill yes)
		(layer "In2.Cu")
		(net "M_I_CPU0_SB_CB<1>")
	)
	(gr_poly
		(pts
			(xy 376.603514 -270.247872) (xy 376.512582 -270.139414) (xy 376.404378 -270.230346) (xy 376.400568 -270.274796)
			(xy 376.599704 -270.292068)
		)
		(stroke
			(width 0)
			(type solid)
		)
		(fill yes)
		(layer "In2.Cu")
		(net "M_I_CPU0_SB_CB<5>")
	)
	(gr_poly
		(pts
			(xy 376.603514 -267.007848) (xy 376.512582 -266.89939) (xy 376.404378 -266.990322) (xy 376.400568 -267.034772)
			(xy 376.599704 -267.052044)
		)
		(stroke
			(width 0)
			(type solid)
		)
		(fill yes)
		(layer "In2.Cu")
		(net "M_I_CPU0_SA_RSP<0>")
	)
	(gr_poly
		(pts
			(xy 376.603514 -265.387836) (xy 376.512582 -265.279378) (xy 376.404378 -265.37031) (xy 376.400568 -265.41476)
			(xy 376.599704 -265.432032)
		)
		(stroke
			(width 0)
			(type solid)
		)
		(fill yes)
		(layer "In2.Cu")
		(net "M_I_CPU0_SB_PAR")
	)
	(gr_poly
		(pts
			(xy 376.603514 -263.767824) (xy 376.512582 -263.659366) (xy 376.404378 -263.750298) (xy 376.400568 -263.794748)
			(xy 376.599704 -263.81202)
		)
		(stroke
			(width 0)
			(type solid)
		)
		(fill yes)
		(layer "In2.Cu")
		(net "M_I_CPU0_SB_CA<4>")
	)
	(gr_poly
		(pts
			(xy 376.603514 -262.147812) (xy 376.512582 -262.039354) (xy 376.404378 -262.130286) (xy 376.400568 -262.174736)
			(xy 376.599704 -262.192008)
		)
		(stroke
			(width 0)
			(type solid)
		)
		(fill yes)
		(layer "In2.Cu")
		(net "M_I_CPU0_SB_CA<0>")
	)
	(gr_poly
		(pts
			(xy 376.605546 -291.307774) (xy 376.514614 -291.199316) (xy 376.40641 -291.290248) (xy 376.402346 -291.337746)
			(xy 376.601482 -291.355272)
		)
		(stroke
			(width 0)
			(type solid)
		)
		(fill yes)
		(layer "In2.Cu")
		(net "M_I_CPU0_SB_DQS_DN<8>")
	)
	(gr_poly
		(pts
			(xy 376.605546 -286.447992) (xy 376.514614 -286.339534) (xy 376.40641 -286.430466) (xy 376.402346 -286.477964)
			(xy 376.601482 -286.495236)
		)
		(stroke
			(width 0)
			(type solid)
		)
		(fill yes)
		(layer "In2.Cu")
		(net "M_I_CPU0_SB_DQS_DN<7>")
	)
	(gr_poly
		(pts
			(xy 376.605546 -281.587956) (xy 376.514614 -281.479498) (xy 376.40641 -281.57043) (xy 376.402346 -281.617928)
			(xy 376.601482 -281.6352)
		)
		(stroke
			(width 0)
			(type solid)
		)
		(fill yes)
		(layer "In2.Cu")
		(net "M_I_CPU0_SB_DQS_DN<6>")
	)
	(gr_poly
		(pts
			(xy 376.605546 -271.867884) (xy 376.514614 -271.759426) (xy 376.40641 -271.850358) (xy 376.402346 -271.897856)
			(xy 376.601482 -271.915128)
		)
		(stroke
			(width 0)
			(type solid)
		)
		(fill yes)
		(layer "In2.Cu")
		(net "M_I_CPU0_SB_DQS_DN<4>")
	)
	(gr_poly
		(pts
			(xy 376.616214 -276.728682) (xy 376.525282 -276.620224) (xy 376.417078 -276.711156) (xy 376.41276 -276.758654)
			(xy 376.61215 -276.77618)
		)
		(stroke
			(width 0)
			(type solid)
		)
		(fill yes)
		(layer "In2.Cu")
		(net "M_I_CPU0_SB_DQS_DN<5>")
	)
	(gr_poly
		(pts
			(xy 376.734832 -255.216152) (xy 376.634756 -255.116076) (xy 376.53468 -255.216152) (xy 376.53468 -255.260602)
			(xy 376.734832 -255.260602)
		)
		(stroke
			(width 0)
			(type solid)
		)
		(fill yes)
		(layer "In2.Cu")
		(net "M_I_CPU0_SA_CA<6>")
	)
	(gr_poly
		(pts
			(xy 376.734832 -253.59614) (xy 376.634756 -253.496064) (xy 376.53468 -253.59614) (xy 376.53468 -253.64059)
			(xy 376.734832 -253.64059)
		)
		(stroke
			(width 0)
			(type solid)
		)
		(fill yes)
		(layer "In2.Cu")
		(net "M_I_CPU0_SA_CA<2>")
	)
	(gr_poly
		(pts
			(xy 376.734832 -251.976128) (xy 376.634756 -251.876052) (xy 376.53468 -251.976128) (xy 376.53468 -252.020578)
			(xy 376.734832 -252.020578)
		)
		(stroke
			(width 0)
			(type solid)
		)
		(fill yes)
		(layer "In2.Cu")
		(net "M_I_CPU0_SA_CS_N<1>")
	)
	(gr_poly
		(pts
			(xy 376.734832 -250.356116) (xy 376.634756 -250.25604) (xy 376.53468 -250.356116) (xy 376.53468 -250.400566)
			(xy 376.734832 -250.400566)
		)
		(stroke
			(width 0)
			(type solid)
		)
		(fill yes)
		(layer "In2.Cu")
		(net "M_I_CPU0_ALERT_R_N")
	)
	(gr_poly
		(pts
			(xy 376.734832 -248.736104) (xy 376.634756 -248.636028) (xy 376.53468 -248.736104) (xy 376.53468 -248.780554)
			(xy 376.734832 -248.780554)
		)
		(stroke
			(width 0)
			(type solid)
		)
		(fill yes)
		(layer "In2.Cu")
		(net "M_I_CPU0_SA_CB<5>")
	)
	(gr_poly
		(pts
			(xy 376.734832 -247.115838) (xy 376.634756 -247.016016) (xy 376.53468 -247.115838) (xy 376.53468 -247.16359)
			(xy 376.734832 -247.16359)
		)
		(stroke
			(width 0)
			(type solid)
		)
		(fill yes)
		(layer "In2.Cu")
		(net "M_I_CPU0_SA_DQS_DN<9>")
	)
	(gr_poly
		(pts
			(xy 376.734832 -245.49608) (xy 376.634756 -245.396004) (xy 376.53468 -245.49608) (xy 376.53468 -245.54053)
			(xy 376.734832 -245.54053)
		)
		(stroke
			(width 0)
			(type solid)
		)
		(fill yes)
		(layer "In2.Cu")
		(net "M_I_CPU0_SA_CB<1>")
	)
	(gr_poly
		(pts
			(xy 376.734832 -243.876068) (xy 376.634756 -243.775992) (xy 376.53468 -243.876068) (xy 376.53468 -243.920518)
			(xy 376.734832 -243.920518)
		)
		(stroke
			(width 0)
			(type solid)
		)
		(fill yes)
		(layer "In2.Cu")
		(net "M_I_CPU0_SA_DQ<29>")
	)
	(gr_poly
		(pts
			(xy 376.734832 -242.255802) (xy 376.634756 -242.15598) (xy 376.53468 -242.255802) (xy 376.53468 -242.303554)
			(xy 376.734832 -242.303554)
		)
		(stroke
			(width 0)
			(type solid)
		)
		(fill yes)
		(layer "In2.Cu")
		(net "M_I_CPU0_SA_DQS_DN<8>")
	)
	(gr_poly
		(pts
			(xy 376.734832 -240.636044) (xy 376.634756 -240.535968) (xy 376.53468 -240.636044) (xy 376.53468 -240.680494)
			(xy 376.734832 -240.680494)
		)
		(stroke
			(width 0)
			(type solid)
		)
		(fill yes)
		(layer "In2.Cu")
		(net "M_I_CPU0_SA_DQ<25>")
	)
	(gr_poly
		(pts
			(xy 376.734832 -239.016032) (xy 376.634756 -238.915956) (xy 376.53468 -239.016032) (xy 376.53468 -239.060482)
			(xy 376.734832 -239.060482)
		)
		(stroke
			(width 0)
			(type solid)
		)
		(fill yes)
		(layer "In2.Cu")
		(net "M_I_CPU0_SA_DQ<21>")
	)
	(gr_poly
		(pts
			(xy 376.734832 -237.395766) (xy 376.634756 -237.295944) (xy 376.53468 -237.395766) (xy 376.53468 -237.443518)
			(xy 376.734832 -237.443518)
		)
		(stroke
			(width 0)
			(type solid)
		)
		(fill yes)
		(layer "In2.Cu")
		(net "M_I_CPU0_SA_DQS_DN<7>")
	)
	(gr_poly
		(pts
			(xy 376.734832 -235.776008) (xy 376.634756 -235.675932) (xy 376.53468 -235.776008) (xy 376.53468 -235.820458)
			(xy 376.734832 -235.820458)
		)
		(stroke
			(width 0)
			(type solid)
		)
		(fill yes)
		(layer "In2.Cu")
		(net "M_I_CPU0_SA_DQ<17>")
	)
	(gr_poly
		(pts
			(xy 376.734832 -234.155996) (xy 376.634756 -234.05592) (xy 376.53468 -234.155996) (xy 376.53468 -234.200446)
			(xy 376.734832 -234.200446)
		)
		(stroke
			(width 0)
			(type solid)
		)
		(fill yes)
		(layer "In2.Cu")
		(net "M_I_CPU0_SA_DQ<13>")
	)
	(gr_poly
		(pts
			(xy 376.734832 -232.53573) (xy 376.634756 -232.435908) (xy 376.53468 -232.53573) (xy 376.53468 -232.583482)
			(xy 376.734832 -232.583482)
		)
		(stroke
			(width 0)
			(type solid)
		)
		(fill yes)
		(layer "In2.Cu")
		(net "M_I_CPU0_SA_DQS_DN<6>")
	)
	(gr_poly
		(pts
			(xy 376.734832 -230.915972) (xy 376.634756 -230.815896) (xy 376.53468 -230.915972) (xy 376.53468 -230.960422)
			(xy 376.734832 -230.960422)
		)
		(stroke
			(width 0)
			(type solid)
		)
		(fill yes)
		(layer "In2.Cu")
		(net "M_I_CPU0_SA_DQ<9>")
	)
	(gr_poly
		(pts
			(xy 376.734832 -229.29596) (xy 376.634756 -229.195884) (xy 376.53468 -229.29596) (xy 376.53468 -229.34041)
			(xy 376.734832 -229.34041)
		)
		(stroke
			(width 0)
			(type solid)
		)
		(fill yes)
		(layer "In2.Cu")
		(net "M_I_CPU0_SA_DQ<5>")
	)
	(gr_poly
		(pts
			(xy 376.734832 -227.675948) (xy 376.634756 -227.576126) (xy 376.53468 -227.675948) (xy 376.53468 -227.7237)
			(xy 376.734832 -227.7237)
		)
		(stroke
			(width 0)
			(type solid)
		)
		(fill yes)
		(layer "In2.Cu")
		(net "M_I_CPU0_SA_DQS_DN<5>")
	)
	(gr_poly
		(pts
			(xy 376.734832 -226.05619) (xy 376.634756 -225.956114) (xy 376.53468 -226.05619) (xy 376.53468 -226.10064)
			(xy 376.734832 -226.10064)
		)
		(stroke
			(width 0)
			(type solid)
		)
		(fill yes)
		(layer "In2.Cu")
		(net "M_I_CPU0_SA_DQ<1>")
	)
	(gr_poly
		(pts
			(xy 377.034806 -293.324026) (xy 377.034806 -293.279576) (xy 376.834654 -293.279576) (xy 376.834654 -293.324026)
			(xy 376.93473 -293.424102)
		)
		(stroke
			(width 0)
			(type solid)
		)
		(fill yes)
		(layer "In2.Cu")
		(net "M_I_CPU0_SB_DQ<31>")
	)
	(gr_poly
		(pts
			(xy 377.034806 -291.704268) (xy 377.034806 -291.656516) (xy 376.834654 -291.656516) (xy 376.834654 -291.704268)
			(xy 376.93473 -291.80409)
		)
		(stroke
			(width 0)
			(type solid)
		)
		(fill yes)
		(layer "In2.Cu")
		(net "M_I_CPU0_SB_DQS_DP<8>")
	)
	(gr_poly
		(pts
			(xy 377.034806 -290.084002) (xy 377.034806 -290.039552) (xy 376.834654 -290.039552) (xy 376.834654 -290.084002)
			(xy 376.93473 -290.184078)
		)
		(stroke
			(width 0)
			(type solid)
		)
		(fill yes)
		(layer "In2.Cu")
		(net "M_I_CPU0_SB_DQ<27>")
	)
	(gr_poly
		(pts
			(xy 377.034806 -288.464244) (xy 377.034806 -288.419794) (xy 376.834654 -288.419794) (xy 376.834654 -288.464244)
			(xy 376.93473 -288.56432)
		)
		(stroke
			(width 0)
			(type solid)
		)
		(fill yes)
		(layer "In2.Cu")
		(net "M_I_CPU0_SB_DQ<23>")
	)
	(gr_poly
		(pts
			(xy 377.034806 -286.844232) (xy 377.034806 -286.79648) (xy 376.834654 -286.79648) (xy 376.834654 -286.844232)
			(xy 376.93473 -286.944308)
		)
		(stroke
			(width 0)
			(type solid)
		)
		(fill yes)
		(layer "In2.Cu")
		(net "M_I_CPU0_SB_DQS_DP<7>")
	)
	(gr_poly
		(pts
			(xy 377.034806 -285.22422) (xy 377.034806 -285.17977) (xy 376.834654 -285.17977) (xy 376.834654 -285.22422)
			(xy 376.93473 -285.324296)
		)
		(stroke
			(width 0)
			(type solid)
		)
		(fill yes)
		(layer "In2.Cu")
		(net "M_I_CPU0_SB_DQ<19>")
	)
	(gr_poly
		(pts
			(xy 377.034806 -283.604208) (xy 377.034806 -283.559758) (xy 376.834654 -283.559758) (xy 376.834654 -283.604208)
			(xy 376.93473 -283.704284)
		)
		(stroke
			(width 0)
			(type solid)
		)
		(fill yes)
		(layer "In2.Cu")
		(net "M_I_CPU0_SB_DQ<15>")
	)
	(gr_poly
		(pts
			(xy 377.034806 -281.98445) (xy 377.034806 -281.936698) (xy 376.834654 -281.936698) (xy 376.834654 -281.98445)
			(xy 376.93473 -282.084272)
		)
		(stroke
			(width 0)
			(type solid)
		)
		(fill yes)
		(layer "In2.Cu")
		(net "M_I_CPU0_SB_DQS_DP<6>")
	)
	(gr_poly
		(pts
			(xy 377.034806 -280.364184) (xy 377.034806 -280.319734) (xy 376.834654 -280.319734) (xy 376.834654 -280.364184)
			(xy 376.93473 -280.46426)
		)
		(stroke
			(width 0)
			(type solid)
		)
		(fill yes)
		(layer "In2.Cu")
		(net "M_I_CPU0_SB_DQ<11>")
	)
	(gr_poly
		(pts
			(xy 377.034806 -278.744172) (xy 377.034806 -278.699722) (xy 376.834654 -278.699722) (xy 376.834654 -278.744172)
			(xy 376.93473 -278.844248)
		)
		(stroke
			(width 0)
			(type solid)
		)
		(fill yes)
		(layer "In2.Cu")
		(net "M_I_CPU0_SB_DQ<7>")
	)
	(gr_poly
		(pts
			(xy 377.034806 -277.124414) (xy 377.034806 -277.076662) (xy 376.834654 -277.076662) (xy 376.834654 -277.124414)
			(xy 376.93473 -277.224236)
		)
		(stroke
			(width 0)
			(type solid)
		)
		(fill yes)
		(layer "In2.Cu")
		(net "M_I_CPU0_SB_DQS_DP<5>")
	)
	(gr_poly
		(pts
			(xy 377.034806 -275.504148) (xy 377.034806 -275.459698) (xy 376.834654 -275.459698) (xy 376.834654 -275.504148)
			(xy 376.93473 -275.604224)
		)
		(stroke
			(width 0)
			(type solid)
		)
		(fill yes)
		(layer "In2.Cu")
		(net "M_I_CPU0_SB_DQ<3>")
	)
	(gr_poly
		(pts
			(xy 377.034806 -273.884136) (xy 377.034806 -273.839686) (xy 376.834654 -273.839686) (xy 376.834654 -273.884136)
			(xy 376.93473 -273.984212)
		)
		(stroke
			(width 0)
			(type solid)
		)
		(fill yes)
		(layer "In2.Cu")
		(net "M_I_CPU0_SB_CB<3>")
	)
	(gr_poly
		(pts
			(xy 377.034806 -272.264378) (xy 377.034806 -272.216626) (xy 376.834654 -272.216626) (xy 376.834654 -272.264378)
			(xy 376.93473 -272.3642)
		)
		(stroke
			(width 0)
			(type solid)
		)
		(fill yes)
		(layer "In2.Cu")
		(net "M_I_CPU0_SB_DQS_DP<4>")
	)
	(gr_poly
		(pts
			(xy 377.034806 -270.644112) (xy 377.034806 -270.599662) (xy 376.834654 -270.599662) (xy 376.834654 -270.644112)
			(xy 376.93473 -270.744188)
		)
		(stroke
			(width 0)
			(type solid)
		)
		(fill yes)
		(layer "In2.Cu")
		(net "M_I_CPU0_SB_CB<7>")
	)
	(gr_poly
		(pts
			(xy 377.034806 -265.784076) (xy 377.034806 -265.739626) (xy 376.834654 -265.739626) (xy 376.834654 -265.784076)
			(xy 376.93473 -265.884152)
		)
		(stroke
			(width 0)
			(type solid)
		)
		(fill yes)
		(layer "In2.Cu")
		(net "M_I_CPU0_SB_CS_N<0>")
	)
	(gr_poly
		(pts
			(xy 377.034806 -264.164064) (xy 377.034806 -264.119614) (xy 376.834654 -264.119614) (xy 376.834654 -264.164064)
			(xy 376.93473 -264.26414)
		)
		(stroke
			(width 0)
			(type solid)
		)
		(fill yes)
		(layer "In2.Cu")
		(net "M_I_CPU0_SB_CA<5>")
	)
	(gr_poly
		(pts
			(xy 377.034806 -262.544052) (xy 377.034806 -262.499602) (xy 376.834654 -262.499602) (xy 376.834654 -262.544052)
			(xy 376.93473 -262.644128)
		)
		(stroke
			(width 0)
			(type solid)
		)
		(fill yes)
		(layer "In2.Cu")
		(net "M_I_CPU0_SB_CA<1>")
	)
	(gr_poly
		(pts
			(xy 377.204986 -255.622298) (xy 377.204986 -255.577848) (xy 377.004834 -255.577848) (xy 377.004834 -255.622298)
			(xy 377.10491 -255.722374)
		)
		(stroke
			(width 0)
			(type solid)
		)
		(fill yes)
		(layer "In2.Cu")
		(net "M_I_CPU0_SA_PAR")
	)
	(gr_poly
		(pts
			(xy 377.204986 -254.002286) (xy 377.204986 -253.957836) (xy 377.004834 -253.957836) (xy 377.004834 -254.002286)
			(xy 377.10491 -254.102362)
		)
		(stroke
			(width 0)
			(type solid)
		)
		(fill yes)
		(layer "In2.Cu")
		(net "M_I_CPU0_SA_CA<3>")
	)
	(gr_poly
		(pts
			(xy 377.204986 -250.762262) (xy 377.204986 -250.717812) (xy 377.004834 -250.717812) (xy 377.004834 -250.762262)
			(xy 377.10491 -250.862338)
		)
		(stroke
			(width 0)
			(type solid)
		)
		(fill yes)
		(layer "In2.Cu")
		(net "M_I_CPU0_RESET_N")
	)
	(gr_poly
		(pts
			(xy 377.204986 -249.14225) (xy 377.204986 -249.0978) (xy 377.004834 -249.0978) (xy 377.004834 -249.14225)
			(xy 377.10491 -249.242326)
		)
		(stroke
			(width 0)
			(type solid)
		)
		(fill yes)
		(layer "In2.Cu")
		(net "M_I_CPU0_SA_CB<7>")
	)
	(gr_poly
		(pts
			(xy 377.204986 -247.522492) (xy 377.204986 -247.47474) (xy 377.004834 -247.47474) (xy 377.004834 -247.522492)
			(xy 377.10491 -247.622314)
		)
		(stroke
			(width 0)
			(type solid)
		)
		(fill yes)
		(layer "In2.Cu")
		(net "M_I_CPU0_SA_DQS_DP<9>")
	)
	(gr_poly
		(pts
			(xy 377.204986 -245.902226) (xy 377.204986 -245.857776) (xy 377.004834 -245.857776) (xy 377.004834 -245.902226)
			(xy 377.10491 -246.002302)
		)
		(stroke
			(width 0)
			(type solid)
		)
		(fill yes)
		(layer "In2.Cu")
		(net "M_I_CPU0_SA_CB<3>")
	)
	(gr_poly
		(pts
			(xy 377.204986 -244.282214) (xy 377.204986 -244.237764) (xy 377.004834 -244.237764) (xy 377.004834 -244.282214)
			(xy 377.10491 -244.38229)
		)
		(stroke
			(width 0)
			(type solid)
		)
		(fill yes)
		(layer "In2.Cu")
		(net "M_I_CPU0_SA_DQ<31>")
	)
	(gr_poly
		(pts
			(xy 377.204986 -242.662456) (xy 377.204986 -242.614704) (xy 377.004834 -242.614704) (xy 377.004834 -242.662456)
			(xy 377.10491 -242.762278)
		)
		(stroke
			(width 0)
			(type solid)
		)
		(fill yes)
		(layer "In2.Cu")
		(net "M_I_CPU0_SA_DQS_DP<8>")
	)
	(gr_poly
		(pts
			(xy 377.204986 -241.04219) (xy 377.204986 -240.99774) (xy 377.004834 -240.99774) (xy 377.004834 -241.04219)
			(xy 377.10491 -241.142266)
		)
		(stroke
			(width 0)
			(type solid)
		)
		(fill yes)
		(layer "In2.Cu")
		(net "M_I_CPU0_SA_DQ<27>")
	)
	(gr_poly
		(pts
			(xy 377.204986 -239.422178) (xy 377.204986 -239.377728) (xy 377.004834 -239.377728) (xy 377.004834 -239.422178)
			(xy 377.10491 -239.522254)
		)
		(stroke
			(width 0)
			(type solid)
		)
		(fill yes)
		(layer "In2.Cu")
		(net "M_I_CPU0_SA_DQ<23>")
	)
	(gr_poly
		(pts
			(xy 377.204986 -237.80242) (xy 377.204986 -237.754668) (xy 377.004834 -237.754668) (xy 377.004834 -237.80242)
			(xy 377.10491 -237.902242)
		)
		(stroke
			(width 0)
			(type solid)
		)
		(fill yes)
		(layer "In2.Cu")
		(net "M_I_CPU0_SA_DQS_DP<7>")
	)
	(gr_poly
		(pts
			(xy 377.204986 -236.182154) (xy 377.204986 -236.137704) (xy 377.004834 -236.137704) (xy 377.004834 -236.182154)
			(xy 377.10491 -236.28223)
		)
		(stroke
			(width 0)
			(type solid)
		)
		(fill yes)
		(layer "In2.Cu")
		(net "M_I_CPU0_SA_DQ<19>")
	)
	(gr_poly
		(pts
			(xy 377.204986 -234.562142) (xy 377.204986 -234.517692) (xy 377.004834 -234.517692) (xy 377.004834 -234.562142)
			(xy 377.10491 -234.662218)
		)
		(stroke
			(width 0)
			(type solid)
		)
		(fill yes)
		(layer "In2.Cu")
		(net "M_I_CPU0_SA_DQ<15>")
	)
	(gr_poly
		(pts
			(xy 377.204986 -232.942384) (xy 377.204986 -232.894632) (xy 377.004834 -232.894632) (xy 377.004834 -232.942384)
			(xy 377.10491 -233.042206)
		)
		(stroke
			(width 0)
			(type solid)
		)
		(fill yes)
		(layer "In2.Cu")
		(net "M_I_CPU0_SA_DQS_DP<6>")
	)
	(gr_poly
		(pts
			(xy 377.204986 -231.322372) (xy 377.204986 -231.277922) (xy 377.004834 -231.277922) (xy 377.004834 -231.322372)
			(xy 377.10491 -231.422448)
		)
		(stroke
			(width 0)
			(type solid)
		)
		(fill yes)
		(layer "In2.Cu")
		(net "M_I_CPU0_SA_DQ<11>")
	)
	(gr_poly
		(pts
			(xy 377.204986 -229.70236) (xy 377.204986 -229.65791) (xy 377.004834 -229.65791) (xy 377.004834 -229.70236)
			(xy 377.10491 -229.802436)
		)
		(stroke
			(width 0)
			(type solid)
		)
		(fill yes)
		(layer "In2.Cu")
		(net "M_I_CPU0_SA_DQ<7>")
	)
	(gr_poly
		(pts
			(xy 377.204986 -228.082602) (xy 377.204986 -228.03485) (xy 377.004834 -228.03485) (xy 377.004834 -228.082602)
			(xy 377.10491 -228.182424)
		)
		(stroke
			(width 0)
			(type solid)
		)
		(fill yes)
		(layer "In2.Cu")
		(net "M_I_CPU0_SA_DQS_DP<5>")
	)
	(gr_poly
		(pts
			(xy 377.204986 -226.462336) (xy 377.204986 -226.417886) (xy 377.004834 -226.417886) (xy 377.004834 -226.462336)
			(xy 377.10491 -226.562412)
		)
		(stroke
			(width 0)
			(type solid)
		)
		(fill yes)
		(layer "In2.Cu")
		(net "M_I_CPU0_SA_DQ<3>")
	)
	(gr_poly
		(pts
			(xy 377.50496 -292.91788) (xy 377.404884 -292.817804) (xy 377.304808 -292.91788) (xy 377.304808 -292.96233)
			(xy 377.50496 -292.96233)
		)
		(stroke
			(width 0)
			(type solid)
		)
		(fill yes)
		(layer "In2.Cu")
		(net "M_I_CPU0_SB_DQ<29>")
	)
	(gr_poly
		(pts
			(xy 377.50496 -291.297614) (xy 377.404884 -291.197792) (xy 377.304808 -291.297614) (xy 377.304808 -291.345366)
			(xy 377.50496 -291.345366)
		)
		(stroke
			(width 0)
			(type solid)
		)
		(fill yes)
		(layer "In2.Cu")
		(net "M_I_CPU0_SB_DQS_DN<8>")
	)
	(gr_poly
		(pts
			(xy 377.50496 -289.677856) (xy 377.404884 -289.57778) (xy 377.304808 -289.677856) (xy 377.304808 -289.722306)
			(xy 377.50496 -289.722306)
		)
		(stroke
			(width 0)
			(type solid)
		)
		(fill yes)
		(layer "In2.Cu")
		(net "M_I_CPU0_SB_DQ<25>")
	)
	(gr_poly
		(pts
			(xy 377.50496 -288.057844) (xy 377.404884 -287.957768) (xy 377.304808 -288.057844) (xy 377.304808 -288.102294)
			(xy 377.50496 -288.102294)
		)
		(stroke
			(width 0)
			(type solid)
		)
		(fill yes)
		(layer "In2.Cu")
		(net "M_I_CPU0_SB_DQ<21>")
	)
	(gr_poly
		(pts
			(xy 377.50496 -286.437832) (xy 377.404884 -286.337756) (xy 377.304808 -286.437832) (xy 377.304808 -286.485584)
			(xy 377.50496 -286.485584)
		)
		(stroke
			(width 0)
			(type solid)
		)
		(fill yes)
		(layer "In2.Cu")
		(net "M_I_CPU0_SB_DQS_DN<7>")
	)
	(gr_poly
		(pts
			(xy 377.50496 -284.818074) (xy 377.404884 -284.717998) (xy 377.304808 -284.818074) (xy 377.304808 -284.862524)
			(xy 377.50496 -284.862524)
		)
		(stroke
			(width 0)
			(type solid)
		)
		(fill yes)
		(layer "In2.Cu")
		(net "M_I_CPU0_SB_DQ<17>")
	)
	(gr_poly
		(pts
			(xy 377.50496 -283.198062) (xy 377.404884 -283.097986) (xy 377.304808 -283.198062) (xy 377.304808 -283.242512)
			(xy 377.50496 -283.242512)
		)
		(stroke
			(width 0)
			(type solid)
		)
		(fill yes)
		(layer "In2.Cu")
		(net "M_I_CPU0_SB_DQ<13>")
	)
	(gr_poly
		(pts
			(xy 377.50496 -281.577796) (xy 377.404884 -281.477974) (xy 377.304808 -281.577796) (xy 377.304808 -281.625548)
			(xy 377.50496 -281.625548)
		)
		(stroke
			(width 0)
			(type solid)
		)
		(fill yes)
		(layer "In2.Cu")
		(net "M_I_CPU0_SB_DQS_DN<6>")
	)
	(gr_poly
		(pts
			(xy 377.50496 -279.958038) (xy 377.404884 -279.857962) (xy 377.304808 -279.958038) (xy 377.304808 -280.002488)
			(xy 377.50496 -280.002488)
		)
		(stroke
			(width 0)
			(type solid)
		)
		(fill yes)
		(layer "In2.Cu")
		(net "M_I_CPU0_SB_DQ<9>")
	)
	(gr_poly
		(pts
			(xy 377.50496 -278.338026) (xy 377.404884 -278.23795) (xy 377.304808 -278.338026) (xy 377.304808 -278.382476)
			(xy 377.50496 -278.382476)
		)
		(stroke
			(width 0)
			(type solid)
		)
		(fill yes)
		(layer "In2.Cu")
		(net "M_I_CPU0_SB_DQ<5>")
	)
	(gr_poly
		(pts
			(xy 377.50496 -276.71776) (xy 377.404884 -276.617938) (xy 377.304808 -276.71776) (xy 377.304808 -276.765512)
			(xy 377.50496 -276.765512)
		)
		(stroke
			(width 0)
			(type solid)
		)
		(fill yes)
		(layer "In2.Cu")
		(net "M_I_CPU0_SB_DQS_DN<5>")
	)
	(gr_poly
		(pts
			(xy 377.50496 -275.098002) (xy 377.404884 -274.997926) (xy 377.304808 -275.098002) (xy 377.304808 -275.142452)
			(xy 377.50496 -275.142452)
		)
		(stroke
			(width 0)
			(type solid)
		)
		(fill yes)
		(layer "In2.Cu")
		(net "M_I_CPU0_SB_DQ<1>")
	)
	(gr_poly
		(pts
			(xy 377.50496 -273.47799) (xy 377.404884 -273.377914) (xy 377.304808 -273.47799) (xy 377.304808 -273.52244)
			(xy 377.50496 -273.52244)
		)
		(stroke
			(width 0)
			(type solid)
		)
		(fill yes)
		(layer "In2.Cu")
		(net "M_I_CPU0_SB_CB<1>")
	)
	(gr_poly
		(pts
			(xy 377.50496 -271.857724) (xy 377.404884 -271.757902) (xy 377.304808 -271.857724) (xy 377.304808 -271.905476)
			(xy 377.50496 -271.905476)
		)
		(stroke
			(width 0)
			(type solid)
		)
		(fill yes)
		(layer "In2.Cu")
		(net "M_I_CPU0_SB_DQS_DN<4>")
	)
	(gr_poly
		(pts
			(xy 377.50496 -270.237966) (xy 377.404884 -270.13789) (xy 377.304808 -270.237966) (xy 377.304808 -270.282416)
			(xy 377.50496 -270.282416)
		)
		(stroke
			(width 0)
			(type solid)
		)
		(fill yes)
		(layer "In2.Cu")
		(net "M_I_CPU0_SB_CB<5>")
	)
	(gr_poly
		(pts
			(xy 377.50496 -266.997942) (xy 377.404884 -266.897866) (xy 377.304808 -266.997942) (xy 377.304808 -267.042392)
			(xy 377.50496 -267.042392)
		)
		(stroke
			(width 0)
			(type solid)
		)
		(fill yes)
		(layer "In2.Cu")
		(net "M_I_CPU0_SA_RSP<0>")
	)
	(gr_poly
		(pts
			(xy 377.50496 -265.37793) (xy 377.404884 -265.277854) (xy 377.304808 -265.37793) (xy 377.304808 -265.42238)
			(xy 377.50496 -265.42238)
		)
		(stroke
			(width 0)
			(type solid)
		)
		(fill yes)
		(layer "In2.Cu")
		(net "M_I_CPU0_SB_PAR")
	)
	(gr_poly
		(pts
			(xy 377.50496 -263.757918) (xy 377.404884 -263.657842) (xy 377.304808 -263.757918) (xy 377.304808 -263.802368)
			(xy 377.50496 -263.802368)
		)
		(stroke
			(width 0)
			(type solid)
		)
		(fill yes)
		(layer "In2.Cu")
		(net "M_I_CPU0_SB_CA<4>")
	)
	(gr_poly
		(pts
			(xy 377.50496 -262.137906) (xy 377.404884 -262.03783) (xy 377.304808 -262.137906) (xy 377.304808 -262.182356)
			(xy 377.50496 -262.182356)
		)
		(stroke
			(width 0)
			(type solid)
		)
		(fill yes)
		(layer "In2.Cu")
		(net "M_I_CPU0_SB_CA<0>")
	)
	(gr_poly
		(pts
			(xy 377.674886 -255.216152) (xy 377.57481 -255.116076) (xy 377.474734 -255.216152) (xy 377.474734 -255.260602)
			(xy 377.674886 -255.260602)
		)
		(stroke
			(width 0)
			(type solid)
		)
		(fill yes)
		(layer "In2.Cu")
		(net "M_I_CPU0_SA_CA<6>")
	)
	(gr_poly
		(pts
			(xy 377.674886 -253.59614) (xy 377.57481 -253.496064) (xy 377.474734 -253.59614) (xy 377.474734 -253.64059)
			(xy 377.674886 -253.64059)
		)
		(stroke
			(width 0)
			(type solid)
		)
		(fill yes)
		(layer "In2.Cu")
		(net "M_I_CPU0_SA_CA<2>")
	)
	(gr_poly
		(pts
			(xy 377.674886 -251.976128) (xy 377.57481 -251.876052) (xy 377.474734 -251.976128) (xy 377.474734 -252.020578)
			(xy 377.674886 -252.020578)
		)
		(stroke
			(width 0)
			(type solid)
		)
		(fill yes)
		(layer "In2.Cu")
		(net "M_I_CPU0_SA_CS_N<1>")
	)
	(gr_poly
		(pts
			(xy 377.674886 -250.356116) (xy 377.57481 -250.25604) (xy 377.474734 -250.356116) (xy 377.474734 -250.400566)
			(xy 377.674886 -250.400566)
		)
		(stroke
			(width 0)
			(type solid)
		)
		(fill yes)
		(layer "In2.Cu")
		(net "M_I_CPU0_ALERT_R_N")
	)
	(gr_poly
		(pts
			(xy 377.674886 -248.736104) (xy 377.57481 -248.636028) (xy 377.474734 -248.736104) (xy 377.474734 -248.780554)
			(xy 377.674886 -248.780554)
		)
		(stroke
			(width 0)
			(type solid)
		)
		(fill yes)
		(layer "In2.Cu")
		(net "M_I_CPU0_SA_CB<5>")
	)
	(gr_poly
		(pts
			(xy 377.674886 -247.115838) (xy 377.57481 -247.016016) (xy 377.474734 -247.115838) (xy 377.474734 -247.16359)
			(xy 377.674886 -247.16359)
		)
		(stroke
			(width 0)
			(type solid)
		)
		(fill yes)
		(layer "In2.Cu")
		(net "M_I_CPU0_SA_DQS_DN<9>")
	)
	(gr_poly
		(pts
			(xy 377.674886 -245.49608) (xy 377.57481 -245.396004) (xy 377.474734 -245.49608) (xy 377.474734 -245.54053)
			(xy 377.674886 -245.54053)
		)
		(stroke
			(width 0)
			(type solid)
		)
		(fill yes)
		(layer "In2.Cu")
		(net "M_I_CPU0_SA_CB<1>")
	)
	(gr_poly
		(pts
			(xy 377.674886 -243.876068) (xy 377.57481 -243.775992) (xy 377.474734 -243.876068) (xy 377.474734 -243.920518)
			(xy 377.674886 -243.920518)
		)
		(stroke
			(width 0)
			(type solid)
		)
		(fill yes)
		(layer "In2.Cu")
		(net "M_I_CPU0_SA_DQ<29>")
	)
	(gr_poly
		(pts
			(xy 377.674886 -242.255802) (xy 377.57481 -242.15598) (xy 377.474734 -242.255802) (xy 377.474734 -242.303554)
			(xy 377.674886 -242.303554)
		)
		(stroke
			(width 0)
			(type solid)
		)
		(fill yes)
		(layer "In2.Cu")
		(net "M_I_CPU0_SA_DQS_DN<8>")
	)
	(gr_poly
		(pts
			(xy 377.674886 -240.636044) (xy 377.57481 -240.535968) (xy 377.474734 -240.636044) (xy 377.474734 -240.680494)
			(xy 377.674886 -240.680494)
		)
		(stroke
			(width 0)
			(type solid)
		)
		(fill yes)
		(layer "In2.Cu")
		(net "M_I_CPU0_SA_DQ<25>")
	)
	(gr_poly
		(pts
			(xy 377.674886 -239.016032) (xy 377.57481 -238.915956) (xy 377.474734 -239.016032) (xy 377.474734 -239.060482)
			(xy 377.674886 -239.060482)
		)
		(stroke
			(width 0)
			(type solid)
		)
		(fill yes)
		(layer "In2.Cu")
		(net "M_I_CPU0_SA_DQ<21>")
	)
	(gr_poly
		(pts
			(xy 377.674886 -237.395766) (xy 377.57481 -237.295944) (xy 377.474734 -237.395766) (xy 377.474734 -237.443518)
			(xy 377.674886 -237.443518)
		)
		(stroke
			(width 0)
			(type solid)
		)
		(fill yes)
		(layer "In2.Cu")
		(net "M_I_CPU0_SA_DQS_DN<7>")
	)
	(gr_poly
		(pts
			(xy 377.674886 -235.776008) (xy 377.57481 -235.675932) (xy 377.474734 -235.776008) (xy 377.474734 -235.820458)
			(xy 377.674886 -235.820458)
		)
		(stroke
			(width 0)
			(type solid)
		)
		(fill yes)
		(layer "In2.Cu")
		(net "M_I_CPU0_SA_DQ<17>")
	)
	(gr_poly
		(pts
			(xy 377.674886 -234.155996) (xy 377.57481 -234.05592) (xy 377.474734 -234.155996) (xy 377.474734 -234.200446)
			(xy 377.674886 -234.200446)
		)
		(stroke
			(width 0)
			(type solid)
		)
		(fill yes)
		(layer "In2.Cu")
		(net "M_I_CPU0_SA_DQ<13>")
	)
	(gr_poly
		(pts
			(xy 377.674886 -232.53573) (xy 377.57481 -232.435908) (xy 377.474734 -232.53573) (xy 377.474734 -232.583482)
			(xy 377.674886 -232.583482)
		)
		(stroke
			(width 0)
			(type solid)
		)
		(fill yes)
		(layer "In2.Cu")
		(net "M_I_CPU0_SA_DQS_DN<6>")
	)
	(gr_poly
		(pts
			(xy 377.674886 -230.915972) (xy 377.57481 -230.815896) (xy 377.474734 -230.915972) (xy 377.474734 -230.960422)
			(xy 377.674886 -230.960422)
		)
		(stroke
			(width 0)
			(type solid)
		)
		(fill yes)
		(layer "In2.Cu")
		(net "M_I_CPU0_SA_DQ<9>")
	)
	(gr_poly
		(pts
			(xy 377.674886 -229.29596) (xy 377.57481 -229.195884) (xy 377.474734 -229.29596) (xy 377.474734 -229.34041)
			(xy 377.674886 -229.34041)
		)
		(stroke
			(width 0)
			(type solid)
		)
		(fill yes)
		(layer "In2.Cu")
		(net "M_I_CPU0_SA_DQ<5>")
	)
	(gr_poly
		(pts
			(xy 377.674886 -227.675948) (xy 377.57481 -227.576126) (xy 377.474734 -227.675948) (xy 377.474734 -227.7237)
			(xy 377.674886 -227.7237)
		)
		(stroke
			(width 0)
			(type solid)
		)
		(fill yes)
		(layer "In2.Cu")
		(net "M_I_CPU0_SA_DQS_DN<5>")
	)
	(gr_poly
		(pts
			(xy 377.674886 -226.05619) (xy 377.57481 -225.956114) (xy 377.474734 -226.05619) (xy 377.474734 -226.10064)
			(xy 377.674886 -226.10064)
		)
		(stroke
			(width 0)
			(type solid)
		)
		(fill yes)
		(layer "In2.Cu")
		(net "M_I_CPU0_SA_DQ<1>")
	)
	(gr_poly
		(pts
			(xy 377.713494 -254.802386) (xy 377.709684 -254.75819) (xy 377.510294 -254.775462) (xy 377.514358 -254.819912)
			(xy 377.622562 -254.910844)
		)
		(stroke
			(width 0)
			(type solid)
		)
		(fill yes)
		(layer "In2.Cu")
		(net "M_I_CPU0_SA_CA<5>")
	)
	(gr_poly
		(pts
			(xy 377.713494 -253.182374) (xy 377.709684 -253.138178) (xy 377.510294 -253.15545) (xy 377.514358 -253.1999)
			(xy 377.622562 -253.290832)
		)
		(stroke
			(width 0)
			(type solid)
		)
		(fill yes)
		(layer "In2.Cu")
		(net "M_I_CPU0_SA_CA<1>")
	)
	(gr_poly
		(pts
			(xy 377.713494 -248.322338) (xy 377.709684 -248.278142) (xy 377.510294 -248.295414) (xy 377.514358 -248.339864)
			(xy 377.622562 -248.430796)
		)
		(stroke
			(width 0)
			(type solid)
		)
		(fill yes)
		(layer "In2.Cu")
		(net "M_I_CPU0_SA_CB<6>")
	)
	(gr_poly
		(pts
			(xy 377.713494 -245.082314) (xy 377.709684 -245.038118) (xy 377.510294 -245.05539) (xy 377.514358 -245.09984)
			(xy 377.622562 -245.190772)
		)
		(stroke
			(width 0)
			(type solid)
		)
		(fill yes)
		(layer "In2.Cu")
		(net "M_I_CPU0_SA_CB<2>")
	)
	(gr_poly
		(pts
			(xy 377.713494 -243.462302) (xy 377.709684 -243.418106) (xy 377.510294 -243.435378) (xy 377.514358 -243.479828)
			(xy 377.622562 -243.57076)
		)
		(stroke
			(width 0)
			(type solid)
		)
		(fill yes)
		(layer "In2.Cu")
		(net "M_I_CPU0_SA_DQ<30>")
	)
	(gr_poly
		(pts
			(xy 377.713494 -240.222278) (xy 377.709684 -240.178082) (xy 377.510294 -240.195354) (xy 377.514358 -240.239804)
			(xy 377.622562 -240.330736)
		)
		(stroke
			(width 0)
			(type solid)
		)
		(fill yes)
		(layer "In2.Cu")
		(net "M_I_CPU0_SA_DQ<26>")
	)
	(gr_poly
		(pts
			(xy 377.713494 -238.602266) (xy 377.709684 -238.55807) (xy 377.510294 -238.575342) (xy 377.514358 -238.619792)
			(xy 377.622562 -238.710724)
		)
		(stroke
			(width 0)
			(type solid)
		)
		(fill yes)
		(layer "In2.Cu")
		(net "M_I_CPU0_SA_DQ<22>")
	)
	(gr_poly
		(pts
			(xy 377.713494 -235.362242) (xy 377.709684 -235.318046) (xy 377.510294 -235.335318) (xy 377.514358 -235.379768)
			(xy 377.622562 -235.4707)
		)
		(stroke
			(width 0)
			(type solid)
		)
		(fill yes)
		(layer "In2.Cu")
		(net "M_I_CPU0_SA_DQ<18>")
	)
	(gr_poly
		(pts
			(xy 377.713494 -233.74223) (xy 377.709684 -233.698034) (xy 377.510294 -233.715306) (xy 377.514358 -233.759756)
			(xy 377.622562 -233.850688)
		)
		(stroke
			(width 0)
			(type solid)
		)
		(fill yes)
		(layer "In2.Cu")
		(net "M_I_CPU0_SA_DQ<14>")
	)
	(gr_poly
		(pts
			(xy 377.713494 -230.50246) (xy 377.709684 -230.458264) (xy 377.510294 -230.475536) (xy 377.514358 -230.519986)
			(xy 377.622562 -230.610664)
		)
		(stroke
			(width 0)
			(type solid)
		)
		(fill yes)
		(layer "In2.Cu")
		(net "M_I_CPU0_SA_DQ<10>")
	)
	(gr_poly
		(pts
			(xy 377.713494 -228.882448) (xy 377.709684 -228.838252) (xy 377.510294 -228.855524) (xy 377.514358 -228.899974)
			(xy 377.622562 -228.990906)
		)
		(stroke
			(width 0)
			(type solid)
		)
		(fill yes)
		(layer "In2.Cu")
		(net "M_I_CPU0_SA_DQ<6>")
	)
	(gr_poly
		(pts
			(xy 377.713494 -225.642424) (xy 377.709684 -225.598228) (xy 377.510294 -225.6155) (xy 377.514358 -225.65995)
			(xy 377.622562 -225.750882)
		)
		(stroke
			(width 0)
			(type solid)
		)
		(fill yes)
		(layer "In2.Cu")
		(net "M_I_CPU0_SA_DQ<2>")
	)
	(gr_poly
		(pts
			(xy 377.726194 -256.421636) (xy 377.72213 -256.374138) (xy 377.52274 -256.391664) (xy 377.527058 -256.439162)
			(xy 377.635262 -256.530094)
		)
		(stroke
			(width 0)
			(type solid)
		)
		(fill yes)
		(layer "In2.Cu")
		(net "M_I_CPU0_CLK_DN<0>")
	)
	(gr_poly
		(pts
			(xy 377.726194 -246.701564) (xy 377.72213 -246.65432) (xy 377.52274 -246.671592) (xy 377.527058 -246.71909)
			(xy 377.635262 -246.810022)
		)
		(stroke
			(width 0)
			(type solid)
		)
		(fill yes)
		(layer "In2.Cu")
		(net "M_I_CPU0_SA_DQS_DN<4>")
	)
	(gr_poly
		(pts
			(xy 377.726194 -241.841528) (xy 377.72213 -241.794284) (xy 377.52274 -241.811556) (xy 377.527058 -241.859054)
			(xy 377.635262 -241.949986)
		)
		(stroke
			(width 0)
			(type solid)
		)
		(fill yes)
		(layer "In2.Cu")
		(net "M_I_CPU0_SA_DQS_DN<3>")
	)
	(gr_poly
		(pts
			(xy 377.726194 -236.981492) (xy 377.72213 -236.934248) (xy 377.52274 -236.95152) (xy 377.527058 -236.999018)
			(xy 377.635262 -237.08995)
		)
		(stroke
			(width 0)
			(type solid)
		)
		(fill yes)
		(layer "In2.Cu")
		(net "M_I_CPU0_SA_DQS_DN<2>")
	)
	(gr_poly
		(pts
			(xy 377.726194 -232.121456) (xy 377.72213 -232.074212) (xy 377.52274 -232.091484) (xy 377.527058 -232.138982)
			(xy 377.635262 -232.229914)
		)
		(stroke
			(width 0)
			(type solid)
		)
		(fill yes)
		(layer "In2.Cu")
		(net "M_I_CPU0_SA_DQS_DN<1>")
	)
	(gr_poly
		(pts
			(xy 377.726194 -227.261674) (xy 377.72213 -227.214176) (xy 377.52274 -227.231702) (xy 377.527058 -227.2792)
			(xy 377.635262 -227.370132)
		)
		(stroke
			(width 0)
			(type solid)
		)
		(fill yes)
		(layer "In2.Cu")
		(net "M_I_CPU0_SA_DQS_DN<0>")
	)
	(gr_poly
		(pts
			(xy 377.97486 -293.324026) (xy 377.97486 -293.279576) (xy 377.774708 -293.279576) (xy 377.774708 -293.324026)
			(xy 377.874784 -293.424102)
		)
		(stroke
			(width 0)
			(type solid)
		)
		(fill yes)
		(layer "In2.Cu")
		(net "M_I_CPU0_SB_DQ<31>")
	)
	(gr_poly
		(pts
			(xy 377.97486 -291.704268) (xy 377.97486 -291.656516) (xy 377.774708 -291.656516) (xy 377.774708 -291.704268)
			(xy 377.874784 -291.80409)
		)
		(stroke
			(width 0)
			(type solid)
		)
		(fill yes)
		(layer "In2.Cu")
		(net "M_I_CPU0_SB_DQS_DP<8>")
	)
	(gr_poly
		(pts
			(xy 377.97486 -290.084002) (xy 377.97486 -290.039552) (xy 377.774708 -290.039552) (xy 377.774708 -290.084002)
			(xy 377.874784 -290.184078)
		)
		(stroke
			(width 0)
			(type solid)
		)
		(fill yes)
		(layer "In2.Cu")
		(net "M_I_CPU0_SB_DQ<27>")
	)
	(gr_poly
		(pts
			(xy 377.97486 -288.464244) (xy 377.97486 -288.419794) (xy 377.774708 -288.419794) (xy 377.774708 -288.464244)
			(xy 377.874784 -288.56432)
		)
		(stroke
			(width 0)
			(type solid)
		)
		(fill yes)
		(layer "In2.Cu")
		(net "M_I_CPU0_SB_DQ<23>")
	)
	(gr_poly
		(pts
			(xy 377.97486 -286.844232) (xy 377.97486 -286.79648) (xy 377.774708 -286.79648) (xy 377.774708 -286.844232)
			(xy 377.874784 -286.944308)
		)
		(stroke
			(width 0)
			(type solid)
		)
		(fill yes)
		(layer "In2.Cu")
		(net "M_I_CPU0_SB_DQS_DP<7>")
	)
	(gr_poly
		(pts
			(xy 377.97486 -285.22422) (xy 377.97486 -285.17977) (xy 377.774708 -285.17977) (xy 377.774708 -285.22422)
			(xy 377.874784 -285.324296)
		)
		(stroke
			(width 0)
			(type solid)
		)
		(fill yes)
		(layer "In2.Cu")
		(net "M_I_CPU0_SB_DQ<19>")
	)
	(gr_poly
		(pts
			(xy 377.97486 -283.604208) (xy 377.97486 -283.559758) (xy 377.774708 -283.559758) (xy 377.774708 -283.604208)
			(xy 377.874784 -283.704284)
		)
		(stroke
			(width 0)
			(type solid)
		)
		(fill yes)
		(layer "In2.Cu")
		(net "M_I_CPU0_SB_DQ<15>")
	)
	(gr_poly
		(pts
			(xy 377.97486 -281.98445) (xy 377.97486 -281.936698) (xy 377.774708 -281.936698) (xy 377.774708 -281.98445)
			(xy 377.874784 -282.084272)
		)
		(stroke
			(width 0)
			(type solid)
		)
		(fill yes)
		(layer "In2.Cu")
		(net "M_I_CPU0_SB_DQS_DP<6>")
	)
	(gr_poly
		(pts
			(xy 377.97486 -280.364184) (xy 377.97486 -280.319734) (xy 377.774708 -280.319734) (xy 377.774708 -280.364184)
			(xy 377.874784 -280.46426)
		)
		(stroke
			(width 0)
			(type solid)
		)
		(fill yes)
		(layer "In2.Cu")
		(net "M_I_CPU0_SB_DQ<11>")
	)
	(gr_poly
		(pts
			(xy 377.97486 -278.744172) (xy 377.97486 -278.699722) (xy 377.774708 -278.699722) (xy 377.774708 -278.744172)
			(xy 377.874784 -278.844248)
		)
		(stroke
			(width 0)
			(type solid)
		)
		(fill yes)
		(layer "In2.Cu")
		(net "M_I_CPU0_SB_DQ<7>")
	)
	(gr_poly
		(pts
			(xy 377.97486 -277.124414) (xy 377.97486 -277.076662) (xy 377.774708 -277.076662) (xy 377.774708 -277.124414)
			(xy 377.874784 -277.224236)
		)
		(stroke
			(width 0)
			(type solid)
		)
		(fill yes)
		(layer "In2.Cu")
		(net "M_I_CPU0_SB_DQS_DP<5>")
	)
	(gr_poly
		(pts
			(xy 377.97486 -275.504148) (xy 377.97486 -275.459698) (xy 377.774708 -275.459698) (xy 377.774708 -275.504148)
			(xy 377.874784 -275.604224)
		)
		(stroke
			(width 0)
			(type solid)
		)
		(fill yes)
		(layer "In2.Cu")
		(net "M_I_CPU0_SB_DQ<3>")
	)
	(gr_poly
		(pts
			(xy 377.97486 -273.884136) (xy 377.97486 -273.839686) (xy 377.774708 -273.839686) (xy 377.774708 -273.884136)
			(xy 377.874784 -273.984212)
		)
		(stroke
			(width 0)
			(type solid)
		)
		(fill yes)
		(layer "In2.Cu")
		(net "M_I_CPU0_SB_CB<3>")
	)
	(gr_poly
		(pts
			(xy 377.97486 -272.264378) (xy 377.97486 -272.216626) (xy 377.774708 -272.216626) (xy 377.774708 -272.264378)
			(xy 377.874784 -272.3642)
		)
		(stroke
			(width 0)
			(type solid)
		)
		(fill yes)
		(layer "In2.Cu")
		(net "M_I_CPU0_SB_DQS_DP<4>")
	)
	(gr_poly
		(pts
			(xy 377.97486 -270.644112) (xy 377.97486 -270.599662) (xy 377.774708 -270.599662) (xy 377.774708 -270.644112)
			(xy 377.874784 -270.744188)
		)
		(stroke
			(width 0)
			(type solid)
		)
		(fill yes)
		(layer "In2.Cu")
		(net "M_I_CPU0_SB_CB<7>")
	)
	(gr_poly
		(pts
			(xy 377.97486 -265.784076) (xy 377.97486 -265.739626) (xy 377.774708 -265.739626) (xy 377.774708 -265.784076)
			(xy 377.874784 -265.884152)
		)
		(stroke
			(width 0)
			(type solid)
		)
		(fill yes)
		(layer "In2.Cu")
		(net "M_I_CPU0_SB_CS_N<0>")
	)
	(gr_poly
		(pts
			(xy 377.97486 -264.164064) (xy 377.97486 -264.119614) (xy 377.774708 -264.119614) (xy 377.774708 -264.164064)
			(xy 377.874784 -264.26414)
		)
		(stroke
			(width 0)
			(type solid)
		)
		(fill yes)
		(layer "In2.Cu")
		(net "M_I_CPU0_SB_CA<5>")
	)
	(gr_poly
		(pts
			(xy 377.97486 -262.544052) (xy 377.97486 -262.499602) (xy 377.774708 -262.499602) (xy 377.774708 -262.544052)
			(xy 377.874784 -262.644128)
		)
		(stroke
			(width 0)
			(type solid)
		)
		(fill yes)
		(layer "In2.Cu")
		(net "M_I_CPU0_SB_CA<1>")
	)
	(gr_poly
		(pts
			(xy 378.013468 -292.11778) (xy 377.922536 -292.009322) (xy 377.814332 -292.100254) (xy 377.810522 -292.144704)
			(xy 378.009658 -292.161976)
		)
		(stroke
			(width 0)
			(type solid)
		)
		(fill yes)
		(layer "In2.Cu")
		(net "M_I_CPU0_SB_DQ<28>")
	)
	(gr_poly
		(pts
			(xy 378.013468 -288.877756) (xy 377.922536 -288.769298) (xy 377.814332 -288.86023) (xy 377.810522 -288.90468)
			(xy 378.009658 -288.921952)
		)
		(stroke
			(width 0)
			(type solid)
		)
		(fill yes)
		(layer "In2.Cu")
		(net "M_I_CPU0_SB_DQ<24>")
	)
	(gr_poly
		(pts
			(xy 378.013468 -287.257744) (xy 377.922536 -287.14954) (xy 377.814332 -287.240218) (xy 377.810522 -287.284668)
			(xy 378.009658 -287.30194)
		)
		(stroke
			(width 0)
			(type solid)
		)
		(fill yes)
		(layer "In2.Cu")
		(net "M_I_CPU0_SB_DQ<20>")
	)
	(gr_poly
		(pts
			(xy 378.013468 -284.017974) (xy 377.922536 -283.909516) (xy 377.814332 -284.000448) (xy 377.810522 -284.044898)
			(xy 378.009658 -284.06217)
		)
		(stroke
			(width 0)
			(type solid)
		)
		(fill yes)
		(layer "In2.Cu")
		(net "M_I_CPU0_SB_DQ<16>")
	)
	(gr_poly
		(pts
			(xy 378.013468 -282.397962) (xy 377.922536 -282.289504) (xy 377.814332 -282.380436) (xy 377.810522 -282.424886)
			(xy 378.009658 -282.442158)
		)
		(stroke
			(width 0)
			(type solid)
		)
		(fill yes)
		(layer "In2.Cu")
		(net "M_I_CPU0_SB_DQ<12>")
	)
	(gr_poly
		(pts
			(xy 378.013468 -279.157938) (xy 377.922536 -279.04948) (xy 377.814332 -279.140412) (xy 377.810522 -279.184862)
			(xy 378.009658 -279.202134)
		)
		(stroke
			(width 0)
			(type solid)
		)
		(fill yes)
		(layer "In2.Cu")
		(net "M_I_CPU0_SB_DQ<8>")
	)
	(gr_poly
		(pts
			(xy 378.013468 -277.537926) (xy 377.922536 -277.429468) (xy 377.814332 -277.5204) (xy 377.810522 -277.56485)
			(xy 378.009658 -277.582122)
		)
		(stroke
			(width 0)
			(type solid)
		)
		(fill yes)
		(layer "In2.Cu")
		(net "M_I_CPU0_SB_DQ<4>")
	)
	(gr_poly
		(pts
			(xy 378.013468 -274.297902) (xy 377.922536 -274.189444) (xy 377.814332 -274.280376) (xy 377.810522 -274.324826)
			(xy 378.009658 -274.342098)
		)
		(stroke
			(width 0)
			(type solid)
		)
		(fill yes)
		(layer "In2.Cu")
		(net "M_I_CPU0_SB_DQ<0>")
	)
	(gr_poly
		(pts
			(xy 378.013468 -272.67789) (xy 377.922536 -272.569432) (xy 377.814332 -272.660364) (xy 377.810522 -272.704814)
			(xy 378.009658 -272.722086)
		)
		(stroke
			(width 0)
			(type solid)
		)
		(fill yes)
		(layer "In2.Cu")
		(net "M_I_CPU0_SB_CB<0>")
	)
	(gr_poly
		(pts
			(xy 378.013468 -269.437866) (xy 377.922536 -269.329408) (xy 377.814332 -269.42034) (xy 377.810522 -269.46479)
			(xy 378.009658 -269.482062)
		)
		(stroke
			(width 0)
			(type solid)
		)
		(fill yes)
		(layer "In2.Cu")
		(net "M_I_CPU0_SB_CB<4>")
	)
	(gr_poly
		(pts
			(xy 378.013468 -264.57783) (xy 377.922536 -264.469372) (xy 377.814332 -264.560304) (xy 377.810522 -264.604754)
			(xy 378.009658 -264.622026)
		)
		(stroke
			(width 0)
			(type solid)
		)
		(fill yes)
		(layer "In2.Cu")
		(net "M_I_CPU0_SB_CA<6>")
	)
	(gr_poly
		(pts
			(xy 378.013468 -262.957818) (xy 377.922536 -262.84936) (xy 377.814332 -262.940292) (xy 377.810522 -262.984742)
			(xy 378.009658 -263.002014)
		)
		(stroke
			(width 0)
			(type solid)
		)
		(fill yes)
		(layer "In2.Cu")
		(net "M_I_CPU0_SB_CA<2>")
	)
	(gr_poly
		(pts
			(xy 378.0155 -285.637986) (xy 377.924568 -285.529528) (xy 377.816364 -285.62046) (xy 377.8123 -285.667958)
			(xy 378.011436 -285.685484)
		)
		(stroke
			(width 0)
			(type solid)
		)
		(fill yes)
		(layer "In2.Cu")
		(net "M_I_CPU0_SB_DQS_DP<2>")
	)
	(gr_poly
		(pts
			(xy 378.0155 -280.77795) (xy 377.924568 -280.669492) (xy 377.816364 -280.760424) (xy 377.8123 -280.807922)
			(xy 378.011436 -280.825448)
		)
		(stroke
			(width 0)
			(type solid)
		)
		(fill yes)
		(layer "In2.Cu")
		(net "M_I_CPU0_SB_DQS_DP<1>")
	)
	(gr_poly
		(pts
			(xy 378.0155 -275.917914) (xy 377.924568 -275.809456) (xy 377.816364 -275.900388) (xy 377.8123 -275.947886)
			(xy 378.011436 -275.965412)
		)
		(stroke
			(width 0)
			(type solid)
		)
		(fill yes)
		(layer "In2.Cu")
		(net "M_I_CPU0_SB_DQS_DP<0>")
	)
	(gr_poly
		(pts
			(xy 378.0155 -271.057878) (xy 377.924568 -270.94942) (xy 377.816364 -271.040352) (xy 377.8123 -271.08785)
			(xy 378.011436 -271.105376)
		)
		(stroke
			(width 0)
			(type solid)
		)
		(fill yes)
		(layer "In2.Cu")
		(net "M_I_CPU0_SB_DQS_DP<9>")
	)
	(gr_poly
		(pts
			(xy 378.026422 -290.49853) (xy 377.93549 -290.390326) (xy 377.827286 -290.481004) (xy 377.822968 -290.528502)
			(xy 378.022358 -290.546028)
		)
		(stroke
			(width 0)
			(type solid)
		)
		(fill yes)
		(layer "In2.Cu")
		(net "M_I_CPU0_SB_DQS_DP<3>")
	)
	(gr_poly
		(pts
			(xy 378.144786 -256.025904) (xy 378.04471 -255.926082) (xy 377.944634 -256.025904) (xy 377.944634 -256.073656)
			(xy 378.144786 -256.073656)
		)
		(stroke
			(width 0)
			(type solid)
		)
		(fill yes)
		(layer "In2.Cu")
		(net "M_I_CPU0_CLK_DP<0>")
	)
	(gr_poly
		(pts
			(xy 378.144786 -255.622298) (xy 378.144786 -255.577848) (xy 377.944634 -255.577848) (xy 377.944634 -255.622298)
			(xy 378.04471 -255.722374)
		)
		(stroke
			(width 0)
			(type solid)
		)
		(fill yes)
		(layer "In2.Cu")
		(net "M_I_CPU0_SA_PAR")
	)
	(gr_poly
		(pts
			(xy 378.144786 -254.406146) (xy 378.04471 -254.30607) (xy 377.944634 -254.406146) (xy 377.944634 -254.450596)
			(xy 378.144786 -254.450596)
		)
		(stroke
			(width 0)
			(type solid)
		)
		(fill yes)
		(layer "In2.Cu")
		(net "M_I_CPU0_SA_CA<4>")
	)
	(gr_poly
		(pts
			(xy 378.144786 -254.002286) (xy 378.144786 -253.957836) (xy 377.944634 -253.957836) (xy 377.944634 -254.002286)
			(xy 378.04471 -254.102362)
		)
		(stroke
			(width 0)
			(type solid)
		)
		(fill yes)
		(layer "In2.Cu")
		(net "M_I_CPU0_SA_CA<3>")
	)
	(gr_poly
		(pts
			(xy 378.144786 -252.786134) (xy 378.04471 -252.686058) (xy 377.944634 -252.786134) (xy 377.944634 -252.830584)
			(xy 378.144786 -252.830584)
		)
		(stroke
			(width 0)
			(type solid)
		)
		(fill yes)
		(layer "In2.Cu")
		(net "M_I_CPU0_SA_CA<0>")
	)
	(gr_poly
		(pts
			(xy 378.144786 -251.166122) (xy 378.04471 -251.066046) (xy 377.944634 -251.166122) (xy 377.944634 -251.210572)
			(xy 378.144786 -251.210572)
		)
		(stroke
			(width 0)
			(type solid)
		)
		(fill yes)
		(layer "In2.Cu")
		(net "M_I_CPU0_SA_CS_N<0>")
	)
	(gr_poly
		(pts
			(xy 378.144786 -250.762262) (xy 378.144786 -250.717812) (xy 377.944634 -250.717812) (xy 377.944634 -250.762262)
			(xy 378.04471 -250.862338)
		)
		(stroke
			(width 0)
			(type solid)
		)
		(fill yes)
		(layer "In2.Cu")
		(net "M_I_CPU0_RESET_N")
	)
	(gr_poly
		(pts
			(xy 378.144786 -249.14225) (xy 378.144786 -249.0978) (xy 377.944634 -249.0978) (xy 377.944634 -249.14225)
			(xy 378.04471 -249.242326)
		)
		(stroke
			(width 0)
			(type solid)
		)
		(fill yes)
		(layer "In2.Cu")
		(net "M_I_CPU0_SA_CB<7>")
	)
	(gr_poly
		(pts
			(xy 378.144786 -247.926098) (xy 378.04471 -247.826022) (xy 377.944634 -247.926098) (xy 377.944634 -247.970548)
			(xy 378.144786 -247.970548)
		)
		(stroke
			(width 0)
			(type solid)
		)
		(fill yes)
		(layer "In2.Cu")
		(net "M_I_CPU0_SA_CB<4>")
	)
	(gr_poly
		(pts
			(xy 378.144786 -247.522492) (xy 378.144786 -247.47474) (xy 377.944634 -247.47474) (xy 377.944634 -247.522492)
			(xy 378.04471 -247.622314)
		)
		(stroke
			(width 0)
			(type solid)
		)
		(fill yes)
		(layer "In2.Cu")
		(net "M_I_CPU0_SA_DQS_DP<9>")
	)
	(gr_poly
		(pts
			(xy 378.144786 -246.305832) (xy 378.04471 -246.20601) (xy 377.944634 -246.305832) (xy 377.944634 -246.353584)
			(xy 378.144786 -246.353584)
		)
		(stroke
			(width 0)
			(type solid)
		)
		(fill yes)
		(layer "In2.Cu")
		(net "M_I_CPU0_SA_DQS_DP<4>")
	)
	(gr_poly
		(pts
			(xy 378.144786 -245.902226) (xy 378.144786 -245.857776) (xy 377.944634 -245.857776) (xy 377.944634 -245.902226)
			(xy 378.04471 -246.002302)
		)
		(stroke
			(width 0)
			(type solid)
		)
		(fill yes)
		(layer "In2.Cu")
		(net "M_I_CPU0_SA_CB<3>")
	)
	(gr_poly
		(pts
			(xy 378.144786 -244.686074) (xy 378.04471 -244.585998) (xy 377.944634 -244.686074) (xy 377.944634 -244.730524)
			(xy 378.144786 -244.730524)
		)
		(stroke
			(width 0)
			(type solid)
		)
		(fill yes)
		(layer "In2.Cu")
		(net "M_I_CPU0_SA_CB<0>")
	)
	(gr_poly
		(pts
			(xy 378.144786 -244.282214) (xy 378.144786 -244.237764) (xy 377.944634 -244.237764) (xy 377.944634 -244.282214)
			(xy 378.04471 -244.38229)
		)
		(stroke
			(width 0)
			(type solid)
		)
		(fill yes)
		(layer "In2.Cu")
		(net "M_I_CPU0_SA_DQ<31>")
	)
	(gr_poly
		(pts
			(xy 378.144786 -243.066062) (xy 378.04471 -242.965986) (xy 377.944634 -243.066062) (xy 377.944634 -243.110512)
			(xy 378.144786 -243.110512)
		)
		(stroke
			(width 0)
			(type solid)
		)
		(fill yes)
		(layer "In2.Cu")
		(net "M_I_CPU0_SA_DQ<28>")
	)
	(gr_poly
		(pts
			(xy 378.144786 -242.662456) (xy 378.144786 -242.614704) (xy 377.944634 -242.614704) (xy 377.944634 -242.662456)
			(xy 378.04471 -242.762278)
		)
		(stroke
			(width 0)
			(type solid)
		)
		(fill yes)
		(layer "In2.Cu")
		(net "M_I_CPU0_SA_DQS_DP<8>")
	)
	(gr_poly
		(pts
			(xy 378.144786 -241.445796) (xy 378.04471 -241.345974) (xy 377.944634 -241.445796) (xy 377.944634 -241.493548)
			(xy 378.144786 -241.493548)
		)
		(stroke
			(width 0)
			(type solid)
		)
		(fill yes)
		(layer "In2.Cu")
		(net "M_I_CPU0_SA_DQS_DP<3>")
	)
	(gr_poly
		(pts
			(xy 378.144786 -241.04219) (xy 378.144786 -240.99774) (xy 377.944634 -240.99774) (xy 377.944634 -241.04219)
			(xy 378.04471 -241.142266)
		)
		(stroke
			(width 0)
			(type solid)
		)
		(fill yes)
		(layer "In2.Cu")
		(net "M_I_CPU0_SA_DQ<27>")
	)
	(gr_poly
		(pts
			(xy 378.144786 -239.826038) (xy 378.04471 -239.725962) (xy 377.944634 -239.826038) (xy 377.944634 -239.870488)
			(xy 378.144786 -239.870488)
		)
		(stroke
			(width 0)
			(type solid)
		)
		(fill yes)
		(layer "In2.Cu")
		(net "M_I_CPU0_SA_DQ<24>")
	)
	(gr_poly
		(pts
			(xy 378.144786 -239.422178) (xy 378.144786 -239.377728) (xy 377.944634 -239.377728) (xy 377.944634 -239.422178)
			(xy 378.04471 -239.522254)
		)
		(stroke
			(width 0)
			(type solid)
		)
		(fill yes)
		(layer "In2.Cu")
		(net "M_I_CPU0_SA_DQ<23>")
	)
	(gr_poly
		(pts
			(xy 378.144786 -238.206026) (xy 378.04471 -238.10595) (xy 377.944634 -238.206026) (xy 377.944634 -238.250476)
			(xy 378.144786 -238.250476)
		)
		(stroke
			(width 0)
			(type solid)
		)
		(fill yes)
		(layer "In2.Cu")
		(net "M_I_CPU0_SA_DQ<20>")
	)
	(gr_poly
		(pts
			(xy 378.144786 -237.80242) (xy 378.144786 -237.754668) (xy 377.944634 -237.754668) (xy 377.944634 -237.80242)
			(xy 378.04471 -237.902242)
		)
		(stroke
			(width 0)
			(type solid)
		)
		(fill yes)
		(layer "In2.Cu")
		(net "M_I_CPU0_SA_DQS_DP<7>")
	)
	(gr_poly
		(pts
			(xy 378.144786 -236.58576) (xy 378.04471 -236.485938) (xy 377.944634 -236.58576) (xy 377.944634 -236.633512)
			(xy 378.144786 -236.633512)
		)
		(stroke
			(width 0)
			(type solid)
		)
		(fill yes)
		(layer "In2.Cu")
		(net "M_I_CPU0_SA_DQS_DP<2>")
	)
	(gr_poly
		(pts
			(xy 378.144786 -236.182154) (xy 378.144786 -236.137704) (xy 377.944634 -236.137704) (xy 377.944634 -236.182154)
			(xy 378.04471 -236.28223)
		)
		(stroke
			(width 0)
			(type solid)
		)
		(fill yes)
		(layer "In2.Cu")
		(net "M_I_CPU0_SA_DQ<19>")
	)
	(gr_poly
		(pts
			(xy 378.144786 -234.966002) (xy 378.04471 -234.865926) (xy 377.944634 -234.966002) (xy 377.944634 -235.010452)
			(xy 378.144786 -235.010452)
		)
		(stroke
			(width 0)
			(type solid)
		)
		(fill yes)
		(layer "In2.Cu")
		(net "M_I_CPU0_SA_DQ<16>")
	)
	(gr_poly
		(pts
			(xy 378.144786 -234.562142) (xy 378.144786 -234.517692) (xy 377.944634 -234.517692) (xy 377.944634 -234.562142)
			(xy 378.04471 -234.662218)
		)
		(stroke
			(width 0)
			(type solid)
		)
		(fill yes)
		(layer "In2.Cu")
		(net "M_I_CPU0_SA_DQ<15>")
	)
	(gr_poly
		(pts
			(xy 378.144786 -233.34599) (xy 378.04471 -233.245914) (xy 377.944634 -233.34599) (xy 377.944634 -233.39044)
			(xy 378.144786 -233.39044)
		)
		(stroke
			(width 0)
			(type solid)
		)
		(fill yes)
		(layer "In2.Cu")
		(net "M_I_CPU0_SA_DQ<12>")
	)
	(gr_poly
		(pts
			(xy 378.144786 -232.942384) (xy 378.144786 -232.894632) (xy 377.944634 -232.894632) (xy 377.944634 -232.942384)
			(xy 378.04471 -233.042206)
		)
		(stroke
			(width 0)
			(type solid)
		)
		(fill yes)
		(layer "In2.Cu")
		(net "M_I_CPU0_SA_DQS_DP<6>")
	)
	(gr_poly
		(pts
			(xy 378.144786 -231.725724) (xy 378.04471 -231.625902) (xy 377.944634 -231.725724) (xy 377.944634 -231.773476)
			(xy 378.144786 -231.773476)
		)
		(stroke
			(width 0)
			(type solid)
		)
		(fill yes)
		(layer "In2.Cu")
		(net "M_I_CPU0_SA_DQS_DP<1>")
	)
	(gr_poly
		(pts
			(xy 378.144786 -231.322372) (xy 378.144786 -231.277922) (xy 377.944634 -231.277922) (xy 377.944634 -231.322372)
			(xy 378.04471 -231.422448)
		)
		(stroke
			(width 0)
			(type solid)
		)
		(fill yes)
		(layer "In2.Cu")
		(net "M_I_CPU0_SA_DQ<11>")
	)
	(gr_poly
		(pts
			(xy 378.144786 -230.105966) (xy 378.04471 -230.006144) (xy 377.944634 -230.105966) (xy 377.944634 -230.150416)
			(xy 378.144786 -230.150416)
		)
		(stroke
			(width 0)
			(type solid)
		)
		(fill yes)
		(layer "In2.Cu")
		(net "M_I_CPU0_SA_DQ<8>")
	)
	(gr_poly
		(pts
			(xy 378.144786 -229.70236) (xy 378.144786 -229.65791) (xy 377.944634 -229.65791) (xy 377.944634 -229.70236)
			(xy 378.04471 -229.802436)
		)
		(stroke
			(width 0)
			(type solid)
		)
		(fill yes)
		(layer "In2.Cu")
		(net "M_I_CPU0_SA_DQ<7>")
	)
	(gr_poly
		(pts
			(xy 378.144786 -228.486208) (xy 378.04471 -228.386132) (xy 377.944634 -228.486208) (xy 377.944634 -228.530658)
			(xy 378.144786 -228.530658)
		)
		(stroke
			(width 0)
			(type solid)
		)
		(fill yes)
		(layer "In2.Cu")
		(net "M_I_CPU0_SA_DQ<4>")
	)
	(gr_poly
		(pts
			(xy 378.144786 -228.082602) (xy 378.144786 -228.03485) (xy 377.944634 -228.03485) (xy 377.944634 -228.082602)
			(xy 378.04471 -228.182424)
		)
		(stroke
			(width 0)
			(type solid)
		)
		(fill yes)
		(layer "In2.Cu")
		(net "M_I_CPU0_SA_DQS_DP<5>")
	)
	(gr_poly
		(pts
			(xy 378.144786 -226.865942) (xy 378.04471 -226.76612) (xy 377.944634 -226.865942) (xy 377.944634 -226.913694)
			(xy 378.144786 -226.913694)
		)
		(stroke
			(width 0)
			(type solid)
		)
		(fill yes)
		(layer "In2.Cu")
		(net "M_I_CPU0_SA_DQS_DP<0>")
	)
	(gr_poly
		(pts
			(xy 378.144786 -226.462336) (xy 378.144786 -226.417886) (xy 377.944634 -226.417886) (xy 377.944634 -226.462336)
			(xy 378.04471 -226.562412)
		)
		(stroke
			(width 0)
			(type solid)
		)
		(fill yes)
		(layer "In2.Cu")
		(net "M_I_CPU0_SA_DQ<3>")
	)
	(gr_poly
		(pts
			(xy 378.144786 -225.246184) (xy 378.04471 -225.146108) (xy 377.944634 -225.246184) (xy 377.944634 -225.290634)
			(xy 378.144786 -225.290634)
		)
		(stroke
			(width 0)
			(type solid)
		)
		(fill yes)
		(layer "In2.Cu")
		(net "M_I_CPU0_SA_DQ<0>")
	)
	(gr_poly
		(pts
			(xy 378.445014 -292.91788) (xy 378.344938 -292.817804) (xy 378.244862 -292.91788) (xy 378.244862 -292.96233)
			(xy 378.445014 -292.96233)
		)
		(stroke
			(width 0)
			(type solid)
		)
		(fill yes)
		(layer "In2.Cu")
		(net "M_I_CPU0_SB_DQ<29>")
	)
	(gr_poly
		(pts
			(xy 378.445014 -292.51402) (xy 378.445014 -292.46957) (xy 378.244862 -292.46957) (xy 378.244862 -292.51402)
			(xy 378.344938 -292.614096)
		)
		(stroke
			(width 0)
			(type solid)
		)
		(fill yes)
		(layer "In2.Cu")
		(net "M_I_CPU0_SB_DQ<30>")
	)
	(gr_poly
		(pts
			(xy 378.445014 -291.297614) (xy 378.344938 -291.197792) (xy 378.244862 -291.297614) (xy 378.244862 -291.345366)
			(xy 378.445014 -291.345366)
		)
		(stroke
			(width 0)
			(type solid)
		)
		(fill yes)
		(layer "In2.Cu")
		(net "M_I_CPU0_SB_DQS_DN<8>")
	)
	(gr_poly
		(pts
			(xy 378.445014 -290.894262) (xy 378.445014 -290.84651) (xy 378.244862 -290.84651) (xy 378.244862 -290.894262)
			(xy 378.344938 -290.994084)
		)
		(stroke
			(width 0)
			(type solid)
		)
		(fill yes)
		(layer "In2.Cu")
		(net "M_I_CPU0_SB_DQS_DN<3>")
	)
	(gr_poly
		(pts
			(xy 378.445014 -289.677856) (xy 378.344938 -289.57778) (xy 378.244862 -289.677856) (xy 378.244862 -289.722306)
			(xy 378.445014 -289.722306)
		)
		(stroke
			(width 0)
			(type solid)
		)
		(fill yes)
		(layer "In2.Cu")
		(net "M_I_CPU0_SB_DQ<25>")
	)
	(gr_poly
		(pts
			(xy 378.445014 -289.273996) (xy 378.445014 -289.229546) (xy 378.244862 -289.229546) (xy 378.244862 -289.273996)
			(xy 378.344938 -289.374072)
		)
		(stroke
			(width 0)
			(type solid)
		)
		(fill yes)
		(layer "In2.Cu")
		(net "M_I_CPU0_SB_DQ<26>")
	)
	(gr_poly
		(pts
			(xy 378.445014 -288.057844) (xy 378.344938 -287.957768) (xy 378.244862 -288.057844) (xy 378.244862 -288.102294)
			(xy 378.445014 -288.102294)
		)
		(stroke
			(width 0)
			(type solid)
		)
		(fill yes)
		(layer "In2.Cu")
		(net "M_I_CPU0_SB_DQ<21>")
	)
	(gr_poly
		(pts
			(xy 378.445014 -287.654238) (xy 378.445014 -287.609788) (xy 378.244862 -287.609788) (xy 378.244862 -287.654238)
			(xy 378.344938 -287.75406)
		)
		(stroke
			(width 0)
			(type solid)
		)
		(fill yes)
		(layer "In2.Cu")
		(net "M_I_CPU0_SB_DQ<22>")
	)
	(gr_poly
		(pts
			(xy 378.445014 -286.437832) (xy 378.344938 -286.337756) (xy 378.244862 -286.437832) (xy 378.244862 -286.485584)
			(xy 378.445014 -286.485584)
		)
		(stroke
			(width 0)
			(type solid)
		)
		(fill yes)
		(layer "In2.Cu")
		(net "M_I_CPU0_SB_DQS_DN<7>")
	)
	(gr_poly
		(pts
			(xy 378.445014 -286.03448) (xy 378.445014 -285.986728) (xy 378.244862 -285.986728) (xy 378.244862 -286.03448)
			(xy 378.344938 -286.134302)
		)
		(stroke
			(width 0)
			(type solid)
		)
		(fill yes)
		(layer "In2.Cu")
		(net "M_I_CPU0_SB_DQS_DN<2>")
	)
	(gr_poly
		(pts
			(xy 378.445014 -284.818074) (xy 378.344938 -284.717998) (xy 378.244862 -284.818074) (xy 378.244862 -284.862524)
			(xy 378.445014 -284.862524)
		)
		(stroke
			(width 0)
			(type solid)
		)
		(fill yes)
		(layer "In2.Cu")
		(net "M_I_CPU0_SB_DQ<17>")
	)
	(gr_poly
		(pts
			(xy 378.445014 -284.414214) (xy 378.445014 -284.369764) (xy 378.244862 -284.369764) (xy 378.244862 -284.414214)
			(xy 378.344938 -284.51429)
		)
		(stroke
			(width 0)
			(type solid)
		)
		(fill yes)
		(layer "In2.Cu")
		(net "M_I_CPU0_SB_DQ<18>")
	)
	(gr_poly
		(pts
			(xy 378.445014 -283.198062) (xy 378.344938 -283.097986) (xy 378.244862 -283.198062) (xy 378.244862 -283.242512)
			(xy 378.445014 -283.242512)
		)
		(stroke
			(width 0)
			(type solid)
		)
		(fill yes)
		(layer "In2.Cu")
		(net "M_I_CPU0_SB_DQ<13>")
	)
	(gr_poly
		(pts
			(xy 378.445014 -282.794202) (xy 378.445014 -282.749752) (xy 378.244862 -282.749752) (xy 378.244862 -282.794202)
			(xy 378.344938 -282.894278)
		)
		(stroke
			(width 0)
			(type solid)
		)
		(fill yes)
		(layer "In2.Cu")
		(net "M_I_CPU0_SB_DQ<14>")
	)
	(gr_poly
		(pts
			(xy 378.445014 -281.577796) (xy 378.344938 -281.477974) (xy 378.244862 -281.577796) (xy 378.244862 -281.625548)
			(xy 378.445014 -281.625548)
		)
		(stroke
			(width 0)
			(type solid)
		)
		(fill yes)
		(layer "In2.Cu")
		(net "M_I_CPU0_SB_DQS_DN<6>")
	)
	(gr_poly
		(pts
			(xy 378.445014 -281.174444) (xy 378.445014 -281.126692) (xy 378.244862 -281.126692) (xy 378.244862 -281.174444)
			(xy 378.344938 -281.274266)
		)
		(stroke
			(width 0)
			(type solid)
		)
		(fill yes)
		(layer "In2.Cu")
		(net "M_I_CPU0_SB_DQS_DN<1>")
	)
	(gr_poly
		(pts
			(xy 378.445014 -279.958038) (xy 378.344938 -279.857962) (xy 378.244862 -279.958038) (xy 378.244862 -280.002488)
			(xy 378.445014 -280.002488)
		)
		(stroke
			(width 0)
			(type solid)
		)
		(fill yes)
		(layer "In2.Cu")
		(net "M_I_CPU0_SB_DQ<9>")
	)
	(gr_poly
		(pts
			(xy 378.445014 -279.554178) (xy 378.445014 -279.509728) (xy 378.244862 -279.509728) (xy 378.244862 -279.554178)
			(xy 378.344938 -279.654254)
		)
		(stroke
			(width 0)
			(type solid)
		)
		(fill yes)
		(layer "In2.Cu")
		(net "M_I_CPU0_SB_DQ<10>")
	)
	(gr_poly
		(pts
			(xy 378.445014 -278.338026) (xy 378.344938 -278.23795) (xy 378.244862 -278.338026) (xy 378.244862 -278.382476)
			(xy 378.445014 -278.382476)
		)
		(stroke
			(width 0)
			(type solid)
		)
		(fill yes)
		(layer "In2.Cu")
		(net "M_I_CPU0_SB_DQ<5>")
	)
	(gr_poly
		(pts
			(xy 378.445014 -277.934166) (xy 378.445014 -277.889716) (xy 378.244862 -277.889716) (xy 378.244862 -277.934166)
			(xy 378.344938 -278.034242)
		)
		(stroke
			(width 0)
			(type solid)
		)
		(fill yes)
		(layer "In2.Cu")
		(net "M_I_CPU0_SB_DQ<6>")
	)
	(gr_poly
		(pts
			(xy 378.445014 -276.71776) (xy 378.344938 -276.617938) (xy 378.244862 -276.71776) (xy 378.244862 -276.765512)
			(xy 378.445014 -276.765512)
		)
		(stroke
			(width 0)
			(type solid)
		)
		(fill yes)
		(layer "In2.Cu")
		(net "M_I_CPU0_SB_DQS_DN<5>")
	)
	(gr_poly
		(pts
			(xy 378.445014 -276.314408) (xy 378.445014 -276.266656) (xy 378.244862 -276.266656) (xy 378.244862 -276.314408)
			(xy 378.344938 -276.41423)
		)
		(stroke
			(width 0)
			(type solid)
		)
		(fill yes)
		(layer "In2.Cu")
		(net "M_I_CPU0_SB_DQS_DN<0>")
	)
	(gr_poly
		(pts
			(xy 378.445014 -275.098002) (xy 378.344938 -274.997926) (xy 378.244862 -275.098002) (xy 378.244862 -275.142452)
			(xy 378.445014 -275.142452)
		)
		(stroke
			(width 0)
			(type solid)
		)
		(fill yes)
		(layer "In2.Cu")
		(net "M_I_CPU0_SB_DQ<1>")
	)
	(gr_poly
		(pts
			(xy 378.445014 -274.694142) (xy 378.445014 -274.649692) (xy 378.244862 -274.649692) (xy 378.244862 -274.694142)
			(xy 378.344938 -274.794218)
		)
		(stroke
			(width 0)
			(type solid)
		)
		(fill yes)
		(layer "In2.Cu")
		(net "M_I_CPU0_SB_DQ<2>")
	)
	(gr_poly
		(pts
			(xy 378.445014 -273.47799) (xy 378.344938 -273.377914) (xy 378.244862 -273.47799) (xy 378.244862 -273.52244)
			(xy 378.445014 -273.52244)
		)
		(stroke
			(width 0)
			(type solid)
		)
		(fill yes)
		(layer "In2.Cu")
		(net "M_I_CPU0_SB_CB<1>")
	)
	(gr_poly
		(pts
			(xy 378.445014 -273.07413) (xy 378.445014 -273.02968) (xy 378.244862 -273.02968) (xy 378.244862 -273.07413)
			(xy 378.344938 -273.174206)
		)
		(stroke
			(width 0)
			(type solid)
		)
		(fill yes)
		(layer "In2.Cu")
		(net "M_I_CPU0_SB_CB<2>")
	)
	(gr_poly
		(pts
			(xy 378.445014 -271.857724) (xy 378.344938 -271.757902) (xy 378.244862 -271.857724) (xy 378.244862 -271.905476)
			(xy 378.445014 -271.905476)
		)
		(stroke
			(width 0)
			(type solid)
		)
		(fill yes)
		(layer "In2.Cu")
		(net "M_I_CPU0_SB_DQS_DN<4>")
	)
	(gr_poly
		(pts
			(xy 378.445014 -271.454372) (xy 378.445014 -271.40662) (xy 378.244862 -271.40662) (xy 378.244862 -271.454372)
			(xy 378.344938 -271.554194)
		)
		(stroke
			(width 0)
			(type solid)
		)
		(fill yes)
		(layer "In2.Cu")
		(net "M_I_CPU0_SB_DQS_DN<9>")
	)
	(gr_poly
		(pts
			(xy 378.445014 -270.237966) (xy 378.344938 -270.13789) (xy 378.244862 -270.237966) (xy 378.244862 -270.282416)
			(xy 378.445014 -270.282416)
		)
		(stroke
			(width 0)
			(type solid)
		)
		(fill yes)
		(layer "In2.Cu")
		(net "M_I_CPU0_SB_CB<5>")
	)
	(gr_poly
		(pts
			(xy 378.445014 -269.834106) (xy 378.445014 -269.789656) (xy 378.244862 -269.789656) (xy 378.244862 -269.834106)
			(xy 378.344938 -269.934182)
		)
		(stroke
			(width 0)
			(type solid)
		)
		(fill yes)
		(layer "In2.Cu")
		(net "M_I_CPU0_SB_CB<6>")
	)
	(gr_poly
		(pts
			(xy 378.445014 -266.997942) (xy 378.344938 -266.897866) (xy 378.244862 -266.997942) (xy 378.244862 -267.042392)
			(xy 378.445014 -267.042392)
		)
		(stroke
			(width 0)
			(type solid)
		)
		(fill yes)
		(layer "In2.Cu")
		(net "M_I_CPU0_SA_RSP<0>")
	)
	(gr_poly
		(pts
			(xy 378.445014 -266.594082) (xy 378.445014 -266.549632) (xy 378.244862 -266.549632) (xy 378.244862 -266.594082)
			(xy 378.344938 -266.694158)
		)
		(stroke
			(width 0)
			(type solid)
		)
		(fill yes)
		(layer "In2.Cu")
		(net "M_I_CPU0_SB_CS_N<1>")
	)
	(gr_poly
		(pts
			(xy 378.445014 -265.37793) (xy 378.344938 -265.277854) (xy 378.244862 -265.37793) (xy 378.244862 -265.42238)
			(xy 378.445014 -265.42238)
		)
		(stroke
			(width 0)
			(type solid)
		)
		(fill yes)
		(layer "In2.Cu")
		(net "M_I_CPU0_SB_PAR")
	)
	(gr_poly
		(pts
			(xy 378.445014 -263.757918) (xy 378.344938 -263.657842) (xy 378.244862 -263.757918) (xy 378.244862 -263.802368)
			(xy 378.445014 -263.802368)
		)
		(stroke
			(width 0)
			(type solid)
		)
		(fill yes)
		(layer "In2.Cu")
		(net "M_I_CPU0_SB_CA<4>")
	)
	(gr_poly
		(pts
			(xy 378.445014 -263.354058) (xy 378.445014 -263.309608) (xy 378.244862 -263.309608) (xy 378.244862 -263.354058)
			(xy 378.344938 -263.454134)
		)
		(stroke
			(width 0)
			(type solid)
		)
		(fill yes)
		(layer "In2.Cu")
		(net "M_I_CPU0_SB_CA<3>")
	)
	(gr_poly
		(pts
			(xy 378.445014 -262.137906) (xy 378.344938 -262.03783) (xy 378.244862 -262.137906) (xy 378.244862 -262.182356)
			(xy 378.445014 -262.182356)
		)
		(stroke
			(width 0)
			(type solid)
		)
		(fill yes)
		(layer "In2.Cu")
		(net "M_I_CPU0_SB_CA<0>")
	)
	(gr_poly
		(pts
			(xy 378.61494 -256.432558) (xy 378.61494 -256.384806) (xy 378.414788 -256.384806) (xy 378.414788 -256.432558)
			(xy 378.514864 -256.53238)
		)
		(stroke
			(width 0)
			(type solid)
		)
		(fill yes)
		(layer "In2.Cu")
		(net "M_I_CPU0_CLK_DN<0>")
	)
	(gr_poly
		(pts
			(xy 378.61494 -255.216152) (xy 378.514864 -255.116076) (xy 378.414788 -255.216152) (xy 378.414788 -255.260602)
			(xy 378.61494 -255.260602)
		)
		(stroke
			(width 0)
			(type solid)
		)
		(fill yes)
		(layer "In2.Cu")
		(net "M_I_CPU0_SA_CA<6>")
	)
	(gr_poly
		(pts
			(xy 378.61494 -254.812292) (xy 378.61494 -254.767842) (xy 378.414788 -254.767842) (xy 378.414788 -254.812292)
			(xy 378.514864 -254.912368)
		)
		(stroke
			(width 0)
			(type solid)
		)
		(fill yes)
		(layer "In2.Cu")
		(net "M_I_CPU0_SA_CA<5>")
	)
	(gr_poly
		(pts
			(xy 378.61494 -253.59614) (xy 378.514864 -253.496064) (xy 378.414788 -253.59614) (xy 378.414788 -253.64059)
			(xy 378.61494 -253.64059)
		)
		(stroke
			(width 0)
			(type solid)
		)
		(fill yes)
		(layer "In2.Cu")
		(net "M_I_CPU0_SA_CA<2>")
	)
	(gr_poly
		(pts
			(xy 378.61494 -253.19228) (xy 378.61494 -253.14783) (xy 378.414788 -253.14783) (xy 378.414788 -253.19228)
			(xy 378.514864 -253.292356)
		)
		(stroke
			(width 0)
			(type solid)
		)
		(fill yes)
		(layer "In2.Cu")
		(net "M_I_CPU0_SA_CA<1>")
	)
	(gr_poly
		(pts
			(xy 378.61494 -251.976128) (xy 378.514864 -251.876052) (xy 378.414788 -251.976128) (xy 378.414788 -252.020578)
			(xy 378.61494 -252.020578)
		)
		(stroke
			(width 0)
			(type solid)
		)
		(fill yes)
		(layer "In2.Cu")
		(net "M_I_CPU0_SA_CS_N<1>")
	)
	(gr_poly
		(pts
			(xy 378.61494 -250.356116) (xy 378.514864 -250.25604) (xy 378.414788 -250.356116) (xy 378.414788 -250.400566)
			(xy 378.61494 -250.400566)
		)
		(stroke
			(width 0)
			(type solid)
		)
		(fill yes)
		(layer "In2.Cu")
		(net "M_I_CPU0_ALERT_R_N")
	)
	(gr_poly
		(pts
			(xy 378.61494 -248.736104) (xy 378.514864 -248.636028) (xy 378.414788 -248.736104) (xy 378.414788 -248.780554)
			(xy 378.61494 -248.780554)
		)
		(stroke
			(width 0)
			(type solid)
		)
		(fill yes)
		(layer "In2.Cu")
		(net "M_I_CPU0_SA_CB<5>")
	)
	(gr_poly
		(pts
			(xy 378.61494 -248.332244) (xy 378.61494 -248.287794) (xy 378.414788 -248.287794) (xy 378.414788 -248.332244)
			(xy 378.514864 -248.43232)
		)
		(stroke
			(width 0)
			(type solid)
		)
		(fill yes)
		(layer "In2.Cu")
		(net "M_I_CPU0_SA_CB<6>")
	)
	(gr_poly
		(pts
			(xy 378.61494 -247.115838) (xy 378.514864 -247.016016) (xy 378.414788 -247.115838) (xy 378.414788 -247.16359)
			(xy 378.61494 -247.16359)
		)
		(stroke
			(width 0)
			(type solid)
		)
		(fill yes)
		(layer "In2.Cu")
		(net "M_I_CPU0_SA_DQS_DN<9>")
	)
	(gr_poly
		(pts
			(xy 378.61494 -246.712486) (xy 378.61494 -246.664734) (xy 378.414788 -246.664734) (xy 378.414788 -246.712486)
			(xy 378.514864 -246.812308)
		)
		(stroke
			(width 0)
			(type solid)
		)
		(fill yes)
		(layer "In2.Cu")
		(net "M_I_CPU0_SA_DQS_DN<4>")
	)
	(gr_poly
		(pts
			(xy 378.61494 -245.49608) (xy 378.514864 -245.396004) (xy 378.414788 -245.49608) (xy 378.414788 -245.54053)
			(xy 378.61494 -245.54053)
		)
		(stroke
			(width 0)
			(type solid)
		)
		(fill yes)
		(layer "In2.Cu")
		(net "M_I_CPU0_SA_CB<1>")
	)
	(gr_poly
		(pts
			(xy 378.61494 -245.09222) (xy 378.61494 -245.04777) (xy 378.414788 -245.04777) (xy 378.414788 -245.09222)
			(xy 378.514864 -245.192296)
		)
		(stroke
			(width 0)
			(type solid)
		)
		(fill yes)
		(layer "In2.Cu")
		(net "M_I_CPU0_SA_CB<2>")
	)
	(gr_poly
		(pts
			(xy 378.61494 -243.876068) (xy 378.514864 -243.775992) (xy 378.414788 -243.876068) (xy 378.414788 -243.920518)
			(xy 378.61494 -243.920518)
		)
		(stroke
			(width 0)
			(type solid)
		)
		(fill yes)
		(layer "In2.Cu")
		(net "M_I_CPU0_SA_DQ<29>")
	)
	(gr_poly
		(pts
			(xy 378.61494 -243.472208) (xy 378.61494 -243.427758) (xy 378.414788 -243.427758) (xy 378.414788 -243.472208)
			(xy 378.514864 -243.572284)
		)
		(stroke
			(width 0)
			(type solid)
		)
		(fill yes)
		(layer "In2.Cu")
		(net "M_I_CPU0_SA_DQ<30>")
	)
	(gr_poly
		(pts
			(xy 378.61494 -242.255802) (xy 378.514864 -242.15598) (xy 378.414788 -242.255802) (xy 378.414788 -242.303554)
			(xy 378.61494 -242.303554)
		)
		(stroke
			(width 0)
			(type solid)
		)
		(fill yes)
		(layer "In2.Cu")
		(net "M_I_CPU0_SA_DQS_DN<8>")
	)
	(gr_poly
		(pts
			(xy 378.61494 -241.85245) (xy 378.61494 -241.804698) (xy 378.414788 -241.804698) (xy 378.414788 -241.85245)
			(xy 378.514864 -241.952272)
		)
		(stroke
			(width 0)
			(type solid)
		)
		(fill yes)
		(layer "In2.Cu")
		(net "M_I_CPU0_SA_DQS_DN<3>")
	)
	(gr_poly
		(pts
			(xy 378.61494 -240.636044) (xy 378.514864 -240.535968) (xy 378.414788 -240.636044) (xy 378.414788 -240.680494)
			(xy 378.61494 -240.680494)
		)
		(stroke
			(width 0)
			(type solid)
		)
		(fill yes)
		(layer "In2.Cu")
		(net "M_I_CPU0_SA_DQ<25>")
	)
	(gr_poly
		(pts
			(xy 378.61494 -240.232184) (xy 378.61494 -240.187734) (xy 378.414788 -240.187734) (xy 378.414788 -240.232184)
			(xy 378.514864 -240.33226)
		)
		(stroke
			(width 0)
			(type solid)
		)
		(fill yes)
		(layer "In2.Cu")
		(net "M_I_CPU0_SA_DQ<26>")
	)
	(gr_poly
		(pts
			(xy 378.61494 -239.016032) (xy 378.514864 -238.915956) (xy 378.414788 -239.016032) (xy 378.414788 -239.060482)
			(xy 378.61494 -239.060482)
		)
		(stroke
			(width 0)
			(type solid)
		)
		(fill yes)
		(layer "In2.Cu")
		(net "M_I_CPU0_SA_DQ<21>")
	)
	(gr_poly
		(pts
			(xy 378.61494 -238.612172) (xy 378.61494 -238.567722) (xy 378.414788 -238.567722) (xy 378.414788 -238.612172)
			(xy 378.514864 -238.712248)
		)
		(stroke
			(width 0)
			(type solid)
		)
		(fill yes)
		(layer "In2.Cu")
		(net "M_I_CPU0_SA_DQ<22>")
	)
	(gr_poly
		(pts
			(xy 378.61494 -237.395766) (xy 378.514864 -237.295944) (xy 378.414788 -237.395766) (xy 378.414788 -237.443518)
			(xy 378.61494 -237.443518)
		)
		(stroke
			(width 0)
			(type solid)
		)
		(fill yes)
		(layer "In2.Cu")
		(net "M_I_CPU0_SA_DQS_DN<7>")
	)
	(gr_poly
		(pts
			(xy 378.61494 -236.992414) (xy 378.61494 -236.944662) (xy 378.414788 -236.944662) (xy 378.414788 -236.992414)
			(xy 378.514864 -237.092236)
		)
		(stroke
			(width 0)
			(type solid)
		)
		(fill yes)
		(layer "In2.Cu")
		(net "M_I_CPU0_SA_DQS_DN<2>")
	)
	(gr_poly
		(pts
			(xy 378.61494 -235.776008) (xy 378.514864 -235.675932) (xy 378.414788 -235.776008) (xy 378.414788 -235.820458)
			(xy 378.61494 -235.820458)
		)
		(stroke
			(width 0)
			(type solid)
		)
		(fill yes)
		(layer "In2.Cu")
		(net "M_I_CPU0_SA_DQ<17>")
	)
	(gr_poly
		(pts
			(xy 378.61494 -235.372148) (xy 378.61494 -235.327698) (xy 378.414788 -235.327698) (xy 378.414788 -235.372148)
			(xy 378.514864 -235.472224)
		)
		(stroke
			(width 0)
			(type solid)
		)
		(fill yes)
		(layer "In2.Cu")
		(net "M_I_CPU0_SA_DQ<18>")
	)
	(gr_poly
		(pts
			(xy 378.61494 -234.155996) (xy 378.514864 -234.05592) (xy 378.414788 -234.155996) (xy 378.414788 -234.200446)
			(xy 378.61494 -234.200446)
		)
		(stroke
			(width 0)
			(type solid)
		)
		(fill yes)
		(layer "In2.Cu")
		(net "M_I_CPU0_SA_DQ<13>")
	)
	(gr_poly
		(pts
			(xy 378.61494 -233.752136) (xy 378.61494 -233.707686) (xy 378.414788 -233.707686) (xy 378.414788 -233.752136)
			(xy 378.514864 -233.852212)
		)
		(stroke
			(width 0)
			(type solid)
		)
		(fill yes)
		(layer "In2.Cu")
		(net "M_I_CPU0_SA_DQ<14>")
	)
	(gr_poly
		(pts
			(xy 378.61494 -232.53573) (xy 378.514864 -232.435908) (xy 378.414788 -232.53573) (xy 378.414788 -232.583482)
			(xy 378.61494 -232.583482)
		)
		(stroke
			(width 0)
			(type solid)
		)
		(fill yes)
		(layer "In2.Cu")
		(net "M_I_CPU0_SA_DQS_DN<6>")
	)
	(gr_poly
		(pts
			(xy 378.61494 -232.132378) (xy 378.61494 -232.084626) (xy 378.414788 -232.084626) (xy 378.414788 -232.132378)
			(xy 378.514864 -232.2322)
		)
		(stroke
			(width 0)
			(type solid)
		)
		(fill yes)
		(layer "In2.Cu")
		(net "M_I_CPU0_SA_DQS_DN<1>")
	)
	(gr_poly
		(pts
			(xy 378.61494 -230.915972) (xy 378.514864 -230.815896) (xy 378.414788 -230.915972) (xy 378.414788 -230.960422)
			(xy 378.61494 -230.960422)
		)
		(stroke
			(width 0)
			(type solid)
		)
		(fill yes)
		(layer "In2.Cu")
		(net "M_I_CPU0_SA_DQ<9>")
	)
	(gr_poly
		(pts
			(xy 378.61494 -230.512366) (xy 378.61494 -230.467916) (xy 378.414788 -230.467916) (xy 378.414788 -230.512366)
			(xy 378.514864 -230.612188)
		)
		(stroke
			(width 0)
			(type solid)
		)
		(fill yes)
		(layer "In2.Cu")
		(net "M_I_CPU0_SA_DQ<10>")
	)
	(gr_poly
		(pts
			(xy 378.61494 -229.29596) (xy 378.514864 -229.195884) (xy 378.414788 -229.29596) (xy 378.414788 -229.34041)
			(xy 378.61494 -229.34041)
		)
		(stroke
			(width 0)
			(type solid)
		)
		(fill yes)
		(layer "In2.Cu")
		(net "M_I_CPU0_SA_DQ<5>")
	)
	(gr_poly
		(pts
			(xy 378.61494 -228.892354) (xy 378.61494 -228.847904) (xy 378.414788 -228.847904) (xy 378.414788 -228.892354)
			(xy 378.514864 -228.99243)
		)
		(stroke
			(width 0)
			(type solid)
		)
		(fill yes)
		(layer "In2.Cu")
		(net "M_I_CPU0_SA_DQ<6>")
	)
	(gr_poly
		(pts
			(xy 378.61494 -227.675948) (xy 378.514864 -227.576126) (xy 378.414788 -227.675948) (xy 378.414788 -227.7237)
			(xy 378.61494 -227.7237)
		)
		(stroke
			(width 0)
			(type solid)
		)
		(fill yes)
		(layer "In2.Cu")
		(net "M_I_CPU0_SA_DQS_DN<5>")
	)
	(gr_poly
		(pts
			(xy 378.61494 -227.272596) (xy 378.61494 -227.224844) (xy 378.414788 -227.224844) (xy 378.414788 -227.272596)
			(xy 378.514864 -227.372418)
		)
		(stroke
			(width 0)
			(type solid)
		)
		(fill yes)
		(layer "In2.Cu")
		(net "M_I_CPU0_SA_DQS_DN<0>")
	)
	(gr_poly
		(pts
			(xy 378.61494 -226.05619) (xy 378.514864 -225.956114) (xy 378.414788 -226.05619) (xy 378.414788 -226.10064)
			(xy 378.61494 -226.10064)
		)
		(stroke
			(width 0)
			(type solid)
		)
		(fill yes)
		(layer "In2.Cu")
		(net "M_I_CPU0_SA_DQ<1>")
	)
	(gr_poly
		(pts
			(xy 378.61494 -225.65233) (xy 378.61494 -225.60788) (xy 378.414788 -225.60788) (xy 378.414788 -225.65233)
			(xy 378.514864 -225.752406)
		)
		(stroke
			(width 0)
			(type solid)
		)
		(fill yes)
		(layer "In2.Cu")
		(net "M_I_CPU0_SA_DQ<2>")
	)
	(gr_poly
		(pts
			(xy 378.914914 -293.324026) (xy 378.914914 -293.279576) (xy 378.714762 -293.279576) (xy 378.714762 -293.324026)
			(xy 378.814838 -293.424102)
		)
		(stroke
			(width 0)
			(type solid)
		)
		(fill yes)
		(layer "In2.Cu")
		(net "M_I_CPU0_SB_DQ<31>")
	)
	(gr_poly
		(pts
			(xy 378.914914 -292.107874) (xy 378.814838 -292.007798) (xy 378.714762 -292.107874) (xy 378.714762 -292.152324)
			(xy 378.914914 -292.152324)
		)
		(stroke
			(width 0)
			(type solid)
		)
		(fill yes)
		(layer "In2.Cu")
		(net "M_I_CPU0_SB_DQ<28>")
	)
	(gr_poly
		(pts
			(xy 378.914914 -291.704268) (xy 378.914914 -291.656516) (xy 378.714762 -291.656516) (xy 378.714762 -291.704268)
			(xy 378.814838 -291.80409)
		)
		(stroke
			(width 0)
			(type solid)
		)
		(fill yes)
		(layer "In2.Cu")
		(net "M_I_CPU0_SB_DQS_DP<8>")
	)
	(gr_poly
		(pts
			(xy 378.914914 -290.487608) (xy 378.814838 -290.387786) (xy 378.714762 -290.487608) (xy 378.714762 -290.53536)
			(xy 378.914914 -290.53536)
		)
		(stroke
			(width 0)
			(type solid)
		)
		(fill yes)
		(layer "In2.Cu")
		(net "M_I_CPU0_SB_DQS_DP<3>")
	)
	(gr_poly
		(pts
			(xy 378.914914 -290.084002) (xy 378.914914 -290.039552) (xy 378.714762 -290.039552) (xy 378.714762 -290.084002)
			(xy 378.814838 -290.184078)
		)
		(stroke
			(width 0)
			(type solid)
		)
		(fill yes)
		(layer "In2.Cu")
		(net "M_I_CPU0_SB_DQ<27>")
	)
	(gr_poly
		(pts
			(xy 378.914914 -288.86785) (xy 378.814838 -288.767774) (xy 378.714762 -288.86785) (xy 378.714762 -288.9123)
			(xy 378.914914 -288.9123)
		)
		(stroke
			(width 0)
			(type solid)
		)
		(fill yes)
		(layer "In2.Cu")
		(net "M_I_CPU0_SB_DQ<24>")
	)
	(gr_poly
		(pts
			(xy 378.914914 -288.464244) (xy 378.914914 -288.419794) (xy 378.714762 -288.419794) (xy 378.714762 -288.464244)
			(xy 378.814838 -288.56432)
		)
		(stroke
			(width 0)
			(type solid)
		)
		(fill yes)
		(layer "In2.Cu")
		(net "M_I_CPU0_SB_DQ<23>")
	)
	(gr_poly
		(pts
			(xy 378.914914 -287.247838) (xy 378.814838 -287.148016) (xy 378.714762 -287.247838) (xy 378.714762 -287.292288)
			(xy 378.914914 -287.292288)
		)
		(stroke
			(width 0)
			(type solid)
		)
		(fill yes)
		(layer "In2.Cu")
		(net "M_I_CPU0_SB_DQ<20>")
	)
	(gr_poly
		(pts
			(xy 378.914914 -286.844232) (xy 378.914914 -286.79648) (xy 378.714762 -286.79648) (xy 378.714762 -286.844232)
			(xy 378.814838 -286.944308)
		)
		(stroke
			(width 0)
			(type solid)
		)
		(fill yes)
		(layer "In2.Cu")
		(net "M_I_CPU0_SB_DQS_DP<7>")
	)
	(gr_poly
		(pts
			(xy 378.914914 -285.627826) (xy 378.814838 -285.528004) (xy 378.714762 -285.627826) (xy 378.714762 -285.675578)
			(xy 378.914914 -285.675578)
		)
		(stroke
			(width 0)
			(type solid)
		)
		(fill yes)
		(layer "In2.Cu")
		(net "M_I_CPU0_SB_DQS_DP<2>")
	)
	(gr_poly
		(pts
			(xy 378.914914 -285.22422) (xy 378.914914 -285.17977) (xy 378.714762 -285.17977) (xy 378.714762 -285.22422)
			(xy 378.814838 -285.324296)
		)
		(stroke
			(width 0)
			(type solid)
		)
		(fill yes)
		(layer "In2.Cu")
		(net "M_I_CPU0_SB_DQ<19>")
	)
	(gr_poly
		(pts
			(xy 378.914914 -284.008068) (xy 378.814838 -283.907992) (xy 378.714762 -284.008068) (xy 378.714762 -284.052518)
			(xy 378.914914 -284.052518)
		)
		(stroke
			(width 0)
			(type solid)
		)
		(fill yes)
		(layer "In2.Cu")
		(net "M_I_CPU0_SB_DQ<16>")
	)
	(gr_poly
		(pts
			(xy 378.914914 -283.604208) (xy 378.914914 -283.559758) (xy 378.714762 -283.559758) (xy 378.714762 -283.604208)
			(xy 378.814838 -283.704284)
		)
		(stroke
			(width 0)
			(type solid)
		)
		(fill yes)
		(layer "In2.Cu")
		(net "M_I_CPU0_SB_DQ<15>")
	)
	(gr_poly
		(pts
			(xy 378.914914 -282.388056) (xy 378.814838 -282.28798) (xy 378.714762 -282.388056) (xy 378.714762 -282.432506)
			(xy 378.914914 -282.432506)
		)
		(stroke
			(width 0)
			(type solid)
		)
		(fill yes)
		(layer "In2.Cu")
		(net "M_I_CPU0_SB_DQ<12>")
	)
	(gr_poly
		(pts
			(xy 378.914914 -281.98445) (xy 378.914914 -281.936698) (xy 378.714762 -281.936698) (xy 378.714762 -281.98445)
			(xy 378.814838 -282.084272)
		)
		(stroke
			(width 0)
			(type solid)
		)
		(fill yes)
		(layer "In2.Cu")
		(net "M_I_CPU0_SB_DQS_DP<6>")
	)
	(gr_poly
		(pts
			(xy 378.914914 -280.76779) (xy 378.814838 -280.667968) (xy 378.714762 -280.76779) (xy 378.714762 -280.815542)
			(xy 378.914914 -280.815542)
		)
		(stroke
			(width 0)
			(type solid)
		)
		(fill yes)
		(layer "In2.Cu")
		(net "M_I_CPU0_SB_DQS_DP<1>")
	)
	(gr_poly
		(pts
			(xy 378.914914 -280.364184) (xy 378.914914 -280.319734) (xy 378.714762 -280.319734) (xy 378.714762 -280.364184)
			(xy 378.814838 -280.46426)
		)
		(stroke
			(width 0)
			(type solid)
		)
		(fill yes)
		(layer "In2.Cu")
		(net "M_I_CPU0_SB_DQ<11>")
	)
	(gr_poly
		(pts
			(xy 378.914914 -279.148032) (xy 378.814838 -279.047956) (xy 378.714762 -279.148032) (xy 378.714762 -279.192482)
			(xy 378.914914 -279.192482)
		)
		(stroke
			(width 0)
			(type solid)
		)
		(fill yes)
		(layer "In2.Cu")
		(net "M_I_CPU0_SB_DQ<8>")
	)
	(gr_poly
		(pts
			(xy 378.914914 -278.744172) (xy 378.914914 -278.699722) (xy 378.714762 -278.699722) (xy 378.714762 -278.744172)
			(xy 378.814838 -278.844248)
		)
		(stroke
			(width 0)
			(type solid)
		)
		(fill yes)
		(layer "In2.Cu")
		(net "M_I_CPU0_SB_DQ<7>")
	)
	(gr_poly
		(pts
			(xy 378.914914 -277.52802) (xy 378.814838 -277.427944) (xy 378.714762 -277.52802) (xy 378.714762 -277.57247)
			(xy 378.914914 -277.57247)
		)
		(stroke
			(width 0)
			(type solid)
		)
		(fill yes)
		(layer "In2.Cu")
		(net "M_I_CPU0_SB_DQ<4>")
	)
	(gr_poly
		(pts
			(xy 378.914914 -277.124414) (xy 378.914914 -277.076662) (xy 378.714762 -277.076662) (xy 378.714762 -277.124414)
			(xy 378.814838 -277.224236)
		)
		(stroke
			(width 0)
			(type solid)
		)
		(fill yes)
		(layer "In2.Cu")
		(net "M_I_CPU0_SB_DQS_DP<5>")
	)
	(gr_poly
		(pts
			(xy 378.914914 -275.907754) (xy 378.814838 -275.807932) (xy 378.714762 -275.907754) (xy 378.714762 -275.955506)
			(xy 378.914914 -275.955506)
		)
		(stroke
			(width 0)
			(type solid)
		)
		(fill yes)
		(layer "In2.Cu")
		(net "M_I_CPU0_SB_DQS_DP<0>")
	)
	(gr_poly
		(pts
			(xy 378.914914 -275.504148) (xy 378.914914 -275.459698) (xy 378.714762 -275.459698) (xy 378.714762 -275.504148)
			(xy 378.814838 -275.604224)
		)
		(stroke
			(width 0)
			(type solid)
		)
		(fill yes)
		(layer "In2.Cu")
		(net "M_I_CPU0_SB_DQ<3>")
	)
	(gr_poly
		(pts
			(xy 378.914914 -274.287996) (xy 378.814838 -274.18792) (xy 378.714762 -274.287996) (xy 378.714762 -274.332446)
			(xy 378.914914 -274.332446)
		)
		(stroke
			(width 0)
			(type solid)
		)
		(fill yes)
		(layer "In2.Cu")
		(net "M_I_CPU0_SB_DQ<0>")
	)
	(gr_poly
		(pts
			(xy 378.914914 -273.884136) (xy 378.914914 -273.839686) (xy 378.714762 -273.839686) (xy 378.714762 -273.884136)
			(xy 378.814838 -273.984212)
		)
		(stroke
			(width 0)
			(type solid)
		)
		(fill yes)
		(layer "In2.Cu")
		(net "M_I_CPU0_SB_CB<3>")
	)
	(gr_poly
		(pts
			(xy 378.914914 -272.667984) (xy 378.814838 -272.567908) (xy 378.714762 -272.667984) (xy 378.714762 -272.712434)
			(xy 378.914914 -272.712434)
		)
		(stroke
			(width 0)
			(type solid)
		)
		(fill yes)
		(layer "In2.Cu")
		(net "M_I_CPU0_SB_CB<0>")
	)
	(gr_poly
		(pts
			(xy 378.914914 -272.264378) (xy 378.914914 -272.216626) (xy 378.714762 -272.216626) (xy 378.714762 -272.264378)
			(xy 378.814838 -272.3642)
		)
		(stroke
			(width 0)
			(type solid)
		)
		(fill yes)
		(layer "In2.Cu")
		(net "M_I_CPU0_SB_DQS_DP<4>")
	)
	(gr_poly
		(pts
			(xy 378.914914 -271.047718) (xy 378.814838 -270.947896) (xy 378.714762 -271.047718) (xy 378.714762 -271.09547)
			(xy 378.914914 -271.09547)
		)
		(stroke
			(width 0)
			(type solid)
		)
		(fill yes)
		(layer "In2.Cu")
		(net "M_I_CPU0_SB_DQS_DP<9>")
	)
	(gr_poly
		(pts
			(xy 378.914914 -270.644112) (xy 378.914914 -270.599662) (xy 378.714762 -270.599662) (xy 378.714762 -270.644112)
			(xy 378.814838 -270.744188)
		)
		(stroke
			(width 0)
			(type solid)
		)
		(fill yes)
		(layer "In2.Cu")
		(net "M_I_CPU0_SB_CB<7>")
	)
	(gr_poly
		(pts
			(xy 378.914914 -269.42796) (xy 378.814838 -269.327884) (xy 378.714762 -269.42796) (xy 378.714762 -269.47241)
			(xy 378.914914 -269.47241)
		)
		(stroke
			(width 0)
			(type solid)
		)
		(fill yes)
		(layer "In2.Cu")
		(net "M_I_CPU0_SB_CB<4>")
	)
	(gr_poly
		(pts
			(xy 378.914914 -267.404088) (xy 378.914914 -267.359638) (xy 378.714762 -267.359638) (xy 378.714762 -267.404088)
			(xy 378.814838 -267.504164)
		)
		(stroke
			(width 0)
			(type solid)
		)
		(fill yes)
		(layer "In2.Cu")
		(net "M_I_CPU0_SB_RSP<0>")
	)
	(gr_poly
		(pts
			(xy 378.914914 -265.784076) (xy 378.914914 -265.739626) (xy 378.714762 -265.739626) (xy 378.714762 -265.784076)
			(xy 378.814838 -265.884152)
		)
		(stroke
			(width 0)
			(type solid)
		)
		(fill yes)
		(layer "In2.Cu")
		(net "M_I_CPU0_SB_CS_N<0>")
	)
	(gr_poly
		(pts
			(xy 378.914914 -264.567924) (xy 378.814838 -264.467848) (xy 378.714762 -264.567924) (xy 378.714762 -264.612374)
			(xy 378.914914 -264.612374)
		)
		(stroke
			(width 0)
			(type solid)
		)
		(fill yes)
		(layer "In2.Cu")
		(net "M_I_CPU0_SB_CA<6>")
	)
	(gr_poly
		(pts
			(xy 378.914914 -264.164064) (xy 378.914914 -264.119614) (xy 378.714762 -264.119614) (xy 378.714762 -264.164064)
			(xy 378.814838 -264.26414)
		)
		(stroke
			(width 0)
			(type solid)
		)
		(fill yes)
		(layer "In2.Cu")
		(net "M_I_CPU0_SB_CA<5>")
	)
	(gr_poly
		(pts
			(xy 378.914914 -262.947912) (xy 378.814838 -262.847836) (xy 378.714762 -262.947912) (xy 378.714762 -262.992362)
			(xy 378.914914 -262.992362)
		)
		(stroke
			(width 0)
			(type solid)
		)
		(fill yes)
		(layer "In2.Cu")
		(net "M_I_CPU0_SB_CA<2>")
	)
	(gr_poly
		(pts
			(xy 378.914914 -262.544052) (xy 378.914914 -262.499602) (xy 378.714762 -262.499602) (xy 378.714762 -262.544052)
			(xy 378.814838 -262.644128)
		)
		(stroke
			(width 0)
			(type solid)
		)
		(fill yes)
		(layer "In2.Cu")
		(net "M_I_CPU0_SB_CA<1>")
	)
	(gr_poly
		(pts
			(xy 379.08484 -256.025904) (xy 378.984764 -255.926082) (xy 378.884688 -256.025904) (xy 378.884688 -256.073656)
			(xy 379.08484 -256.073656)
		)
		(stroke
			(width 0)
			(type solid)
		)
		(fill yes)
		(layer "In2.Cu")
		(net "M_I_CPU0_CLK_DP<0>")
	)
	(gr_poly
		(pts
			(xy 379.08484 -255.622298) (xy 379.08484 -255.577848) (xy 378.884688 -255.577848) (xy 378.884688 -255.622298)
			(xy 378.984764 -255.722374)
		)
		(stroke
			(width 0)
			(type solid)
		)
		(fill yes)
		(layer "In2.Cu")
		(net "M_I_CPU0_SA_PAR")
	)
	(gr_poly
		(pts
			(xy 379.08484 -254.406146) (xy 378.984764 -254.30607) (xy 378.884688 -254.406146) (xy 378.884688 -254.450596)
			(xy 379.08484 -254.450596)
		)
		(stroke
			(width 0)
			(type solid)
		)
		(fill yes)
		(layer "In2.Cu")
		(net "M_I_CPU0_SA_CA<4>")
	)
	(gr_poly
		(pts
			(xy 379.08484 -254.002286) (xy 379.08484 -253.957836) (xy 378.884688 -253.957836) (xy 378.884688 -254.002286)
			(xy 378.984764 -254.102362)
		)
		(stroke
			(width 0)
			(type solid)
		)
		(fill yes)
		(layer "In2.Cu")
		(net "M_I_CPU0_SA_CA<3>")
	)
	(gr_poly
		(pts
			(xy 379.08484 -252.786134) (xy 378.984764 -252.686058) (xy 378.884688 -252.786134) (xy 378.884688 -252.830584)
			(xy 379.08484 -252.830584)
		)
		(stroke
			(width 0)
			(type solid)
		)
		(fill yes)
		(layer "In2.Cu")
		(net "M_I_CPU0_SA_CA<0>")
	)
	(gr_poly
		(pts
			(xy 379.08484 -251.166122) (xy 378.984764 -251.066046) (xy 378.884688 -251.166122) (xy 378.884688 -251.210572)
			(xy 379.08484 -251.210572)
		)
		(stroke
			(width 0)
			(type solid)
		)
		(fill yes)
		(layer "In2.Cu")
		(net "M_I_CPU0_SA_CS_N<0>")
	)
	(gr_poly
		(pts
			(xy 379.08484 -250.762262) (xy 379.08484 -250.717812) (xy 378.884688 -250.717812) (xy 378.884688 -250.762262)
			(xy 378.984764 -250.862338)
		)
		(stroke
			(width 0)
			(type solid)
		)
		(fill yes)
		(layer "In2.Cu")
		(net "M_I_CPU0_RESET_N")
	)
	(gr_poly
		(pts
			(xy 379.08484 -249.14225) (xy 379.08484 -249.0978) (xy 378.884688 -249.0978) (xy 378.884688 -249.14225)
			(xy 378.984764 -249.242326)
		)
		(stroke
			(width 0)
			(type solid)
		)
		(fill yes)
		(layer "In2.Cu")
		(net "M_I_CPU0_SA_CB<7>")
	)
	(gr_poly
		(pts
			(xy 379.08484 -247.926098) (xy 378.984764 -247.826022) (xy 378.884688 -247.926098) (xy 378.884688 -247.970548)
			(xy 379.08484 -247.970548)
		)
		(stroke
			(width 0)
			(type solid)
		)
		(fill yes)
		(layer "In2.Cu")
		(net "M_I_CPU0_SA_CB<4>")
	)
	(gr_poly
		(pts
			(xy 379.08484 -247.522492) (xy 379.08484 -247.47474) (xy 378.884688 -247.47474) (xy 378.884688 -247.522492)
			(xy 378.984764 -247.622314)
		)
		(stroke
			(width 0)
			(type solid)
		)
		(fill yes)
		(layer "In2.Cu")
		(net "M_I_CPU0_SA_DQS_DP<9>")
	)
	(gr_poly
		(pts
			(xy 379.08484 -246.305832) (xy 378.984764 -246.20601) (xy 378.884688 -246.305832) (xy 378.884688 -246.353584)
			(xy 379.08484 -246.353584)
		)
		(stroke
			(width 0)
			(type solid)
		)
		(fill yes)
		(layer "In2.Cu")
		(net "M_I_CPU0_SA_DQS_DP<4>")
	)
	(gr_poly
		(pts
			(xy 379.08484 -245.902226) (xy 379.08484 -245.857776) (xy 378.884688 -245.857776) (xy 378.884688 -245.902226)
			(xy 378.984764 -246.002302)
		)
		(stroke
			(width 0)
			(type solid)
		)
		(fill yes)
		(layer "In2.Cu")
		(net "M_I_CPU0_SA_CB<3>")
	)
	(gr_poly
		(pts
			(xy 379.08484 -244.686074) (xy 378.984764 -244.585998) (xy 378.884688 -244.686074) (xy 378.884688 -244.730524)
			(xy 379.08484 -244.730524)
		)
		(stroke
			(width 0)
			(type solid)
		)
		(fill yes)
		(layer "In2.Cu")
		(net "M_I_CPU0_SA_CB<0>")
	)
	(gr_poly
		(pts
			(xy 379.08484 -244.282214) (xy 379.08484 -244.237764) (xy 378.884688 -244.237764) (xy 378.884688 -244.282214)
			(xy 378.984764 -244.38229)
		)
		(stroke
			(width 0)
			(type solid)
		)
		(fill yes)
		(layer "In2.Cu")
		(net "M_I_CPU0_SA_DQ<31>")
	)
	(gr_poly
		(pts
			(xy 379.08484 -243.066062) (xy 378.984764 -242.965986) (xy 378.884688 -243.066062) (xy 378.884688 -243.110512)
			(xy 379.08484 -243.110512)
		)
		(stroke
			(width 0)
			(type solid)
		)
		(fill yes)
		(layer "In2.Cu")
		(net "M_I_CPU0_SA_DQ<28>")
	)
	(gr_poly
		(pts
			(xy 379.08484 -242.662456) (xy 379.08484 -242.614704) (xy 378.884688 -242.614704) (xy 378.884688 -242.662456)
			(xy 378.984764 -242.762278)
		)
		(stroke
			(width 0)
			(type solid)
		)
		(fill yes)
		(layer "In2.Cu")
		(net "M_I_CPU0_SA_DQS_DP<8>")
	)
	(gr_poly
		(pts
			(xy 379.08484 -241.445796) (xy 378.984764 -241.345974) (xy 378.884688 -241.445796) (xy 378.884688 -241.493548)
			(xy 379.08484 -241.493548)
		)
		(stroke
			(width 0)
			(type solid)
		)
		(fill yes)
		(layer "In2.Cu")
		(net "M_I_CPU0_SA_DQS_DP<3>")
	)
	(gr_poly
		(pts
			(xy 379.08484 -241.04219) (xy 379.08484 -240.99774) (xy 378.884688 -240.99774) (xy 378.884688 -241.04219)
			(xy 378.984764 -241.142266)
		)
		(stroke
			(width 0)
			(type solid)
		)
		(fill yes)
		(layer "In2.Cu")
		(net "M_I_CPU0_SA_DQ<27>")
	)
	(gr_poly
		(pts
			(xy 379.08484 -239.826038) (xy 378.984764 -239.725962) (xy 378.884688 -239.826038) (xy 378.884688 -239.870488)
			(xy 379.08484 -239.870488)
		)
		(stroke
			(width 0)
			(type solid)
		)
		(fill yes)
		(layer "In2.Cu")
		(net "M_I_CPU0_SA_DQ<24>")
	)
	(gr_poly
		(pts
			(xy 379.08484 -239.422178) (xy 379.08484 -239.377728) (xy 378.884688 -239.377728) (xy 378.884688 -239.422178)
			(xy 378.984764 -239.522254)
		)
		(stroke
			(width 0)
			(type solid)
		)
		(fill yes)
		(layer "In2.Cu")
		(net "M_I_CPU0_SA_DQ<23>")
	)
	(gr_poly
		(pts
			(xy 379.08484 -238.206026) (xy 378.984764 -238.10595) (xy 378.884688 -238.206026) (xy 378.884688 -238.250476)
			(xy 379.08484 -238.250476)
		)
		(stroke
			(width 0)
			(type solid)
		)
		(fill yes)
		(layer "In2.Cu")
		(net "M_I_CPU0_SA_DQ<20>")
	)
	(gr_poly
		(pts
			(xy 379.08484 -237.80242) (xy 379.08484 -237.754668) (xy 378.884688 -237.754668) (xy 378.884688 -237.80242)
			(xy 378.984764 -237.902242)
		)
		(stroke
			(width 0)
			(type solid)
		)
		(fill yes)
		(layer "In2.Cu")
		(net "M_I_CPU0_SA_DQS_DP<7>")
	)
	(gr_poly
		(pts
			(xy 379.08484 -236.58576) (xy 378.984764 -236.485938) (xy 378.884688 -236.58576) (xy 378.884688 -236.633512)
			(xy 379.08484 -236.633512)
		)
		(stroke
			(width 0)
			(type solid)
		)
		(fill yes)
		(layer "In2.Cu")
		(net "M_I_CPU0_SA_DQS_DP<2>")
	)
	(gr_poly
		(pts
			(xy 379.08484 -236.182154) (xy 379.08484 -236.137704) (xy 378.884688 -236.137704) (xy 378.884688 -236.182154)
			(xy 378.984764 -236.28223)
		)
		(stroke
			(width 0)
			(type solid)
		)
		(fill yes)
		(layer "In2.Cu")
		(net "M_I_CPU0_SA_DQ<19>")
	)
	(gr_poly
		(pts
			(xy 379.08484 -234.966002) (xy 378.984764 -234.865926) (xy 378.884688 -234.966002) (xy 378.884688 -235.010452)
			(xy 379.08484 -235.010452)
		)
		(stroke
			(width 0)
			(type solid)
		)
		(fill yes)
		(layer "In2.Cu")
		(net "M_I_CPU0_SA_DQ<16>")
	)
	(gr_poly
		(pts
			(xy 379.08484 -234.562142) (xy 379.08484 -234.517692) (xy 378.884688 -234.517692) (xy 378.884688 -234.562142)
			(xy 378.984764 -234.662218)
		)
		(stroke
			(width 0)
			(type solid)
		)
		(fill yes)
		(layer "In2.Cu")
		(net "M_I_CPU0_SA_DQ<15>")
	)
	(gr_poly
		(pts
			(xy 379.08484 -233.34599) (xy 378.984764 -233.245914) (xy 378.884688 -233.34599) (xy 378.884688 -233.39044)
			(xy 379.08484 -233.39044)
		)
		(stroke
			(width 0)
			(type solid)
		)
		(fill yes)
		(layer "In2.Cu")
		(net "M_I_CPU0_SA_DQ<12>")
	)
	(gr_poly
		(pts
			(xy 379.08484 -232.942384) (xy 379.08484 -232.894632) (xy 378.884688 -232.894632) (xy 378.884688 -232.942384)
			(xy 378.984764 -233.042206)
		)
		(stroke
			(width 0)
			(type solid)
		)
		(fill yes)
		(layer "In2.Cu")
		(net "M_I_CPU0_SA_DQS_DP<6>")
	)
	(gr_poly
		(pts
			(xy 379.08484 -231.725724) (xy 378.984764 -231.625902) (xy 378.884688 -231.725724) (xy 378.884688 -231.773476)
			(xy 379.08484 -231.773476)
		)
		(stroke
			(width 0)
			(type solid)
		)
		(fill yes)
		(layer "In2.Cu")
		(net "M_I_CPU0_SA_DQS_DP<1>")
	)
	(gr_poly
		(pts
			(xy 379.08484 -231.322372) (xy 379.08484 -231.277922) (xy 378.884688 -231.277922) (xy 378.884688 -231.322372)
			(xy 378.984764 -231.422448)
		)
		(stroke
			(width 0)
			(type solid)
		)
		(fill yes)
		(layer "In2.Cu")
		(net "M_I_CPU0_SA_DQ<11>")
	)
	(gr_poly
		(pts
			(xy 379.08484 -230.105966) (xy 378.984764 -230.006144) (xy 378.884688 -230.105966) (xy 378.884688 -230.150416)
			(xy 379.08484 -230.150416)
		)
		(stroke
			(width 0)
			(type solid)
		)
		(fill yes)
		(layer "In2.Cu")
		(net "M_I_CPU0_SA_DQ<8>")
	)
	(gr_poly
		(pts
			(xy 379.08484 -229.70236) (xy 379.08484 -229.65791) (xy 378.884688 -229.65791) (xy 378.884688 -229.70236)
			(xy 378.984764 -229.802436)
		)
		(stroke
			(width 0)
			(type solid)
		)
		(fill yes)
		(layer "In2.Cu")
		(net "M_I_CPU0_SA_DQ<7>")
	)
	(gr_poly
		(pts
			(xy 379.08484 -228.486208) (xy 378.984764 -228.386132) (xy 378.884688 -228.486208) (xy 378.884688 -228.530658)
			(xy 379.08484 -228.530658)
		)
		(stroke
			(width 0)
			(type solid)
		)
		(fill yes)
		(layer "In2.Cu")
		(net "M_I_CPU0_SA_DQ<4>")
	)
	(gr_poly
		(pts
			(xy 379.08484 -228.082602) (xy 379.08484 -228.03485) (xy 378.884688 -228.03485) (xy 378.884688 -228.082602)
			(xy 378.984764 -228.182424)
		)
		(stroke
			(width 0)
			(type solid)
		)
		(fill yes)
		(layer "In2.Cu")
		(net "M_I_CPU0_SA_DQS_DP<5>")
	)
	(gr_poly
		(pts
			(xy 379.08484 -226.865942) (xy 378.984764 -226.76612) (xy 378.884688 -226.865942) (xy 378.884688 -226.913694)
			(xy 379.08484 -226.913694)
		)
		(stroke
			(width 0)
			(type solid)
		)
		(fill yes)
		(layer "In2.Cu")
		(net "M_I_CPU0_SA_DQS_DP<0>")
	)
	(gr_poly
		(pts
			(xy 379.08484 -226.462336) (xy 379.08484 -226.417886) (xy 378.884688 -226.417886) (xy 378.884688 -226.462336)
			(xy 378.984764 -226.562412)
		)
		(stroke
			(width 0)
			(type solid)
		)
		(fill yes)
		(layer "In2.Cu")
		(net "M_I_CPU0_SA_DQ<3>")
	)
	(gr_poly
		(pts
			(xy 379.08484 -225.246184) (xy 378.984764 -225.146108) (xy 378.884688 -225.246184) (xy 378.884688 -225.290634)
			(xy 379.08484 -225.290634)
		)
		(stroke
			(width 0)
			(type solid)
		)
		(fill yes)
		(layer "In2.Cu")
		(net "M_I_CPU0_SA_DQ<0>")
	)
	(gr_poly
		(pts
			(xy 379.384814 -292.91788) (xy 379.284738 -292.817804) (xy 379.184662 -292.91788) (xy 379.184662 -292.96233)
			(xy 379.384814 -292.96233)
		)
		(stroke
			(width 0)
			(type solid)
		)
		(fill yes)
		(layer "In2.Cu")
		(net "M_I_CPU0_SB_DQ<29>")
	)
	(gr_poly
		(pts
			(xy 379.384814 -292.51402) (xy 379.384814 -292.46957) (xy 379.184662 -292.46957) (xy 379.184662 -292.51402)
			(xy 379.284738 -292.614096)
		)
		(stroke
			(width 0)
			(type solid)
		)
		(fill yes)
		(layer "In2.Cu")
		(net "M_I_CPU0_SB_DQ<30>")
	)
	(gr_poly
		(pts
			(xy 379.384814 -291.297614) (xy 379.284738 -291.197792) (xy 379.184662 -291.297614) (xy 379.184662 -291.345366)
			(xy 379.384814 -291.345366)
		)
		(stroke
			(width 0)
			(type solid)
		)
		(fill yes)
		(layer "In2.Cu")
		(net "M_I_CPU0_SB_DQS_DN<8>")
	)
	(gr_poly
		(pts
			(xy 379.384814 -290.894262) (xy 379.384814 -290.84651) (xy 379.184662 -290.84651) (xy 379.184662 -290.894262)
			(xy 379.284738 -290.994084)
		)
		(stroke
			(width 0)
			(type solid)
		)
		(fill yes)
		(layer "In2.Cu")
		(net "M_I_CPU0_SB_DQS_DN<3>")
	)
	(gr_poly
		(pts
			(xy 379.384814 -289.677856) (xy 379.284738 -289.57778) (xy 379.184662 -289.677856) (xy 379.184662 -289.722306)
			(xy 379.384814 -289.722306)
		)
		(stroke
			(width 0)
			(type solid)
		)
		(fill yes)
		(layer "In2.Cu")
		(net "M_I_CPU0_SB_DQ<25>")
	)
	(gr_poly
		(pts
			(xy 379.384814 -289.273996) (xy 379.384814 -289.229546) (xy 379.184662 -289.229546) (xy 379.184662 -289.273996)
			(xy 379.284738 -289.374072)
		)
		(stroke
			(width 0)
			(type solid)
		)
		(fill yes)
		(layer "In2.Cu")
		(net "M_I_CPU0_SB_DQ<26>")
	)
	(gr_poly
		(pts
			(xy 379.384814 -288.057844) (xy 379.284738 -287.957768) (xy 379.184662 -288.057844) (xy 379.184662 -288.102294)
			(xy 379.384814 -288.102294)
		)
		(stroke
			(width 0)
			(type solid)
		)
		(fill yes)
		(layer "In2.Cu")
		(net "M_I_CPU0_SB_DQ<21>")
	)
	(gr_poly
		(pts
			(xy 379.384814 -287.654238) (xy 379.384814 -287.609788) (xy 379.184662 -287.609788) (xy 379.184662 -287.654238)
			(xy 379.284738 -287.75406)
		)
		(stroke
			(width 0)
			(type solid)
		)
		(fill yes)
		(layer "In2.Cu")
		(net "M_I_CPU0_SB_DQ<22>")
	)
	(gr_poly
		(pts
			(xy 379.384814 -286.437832) (xy 379.284738 -286.337756) (xy 379.184662 -286.437832) (xy 379.184662 -286.485584)
			(xy 379.384814 -286.485584)
		)
		(stroke
			(width 0)
			(type solid)
		)
		(fill yes)
		(layer "In2.Cu")
		(net "M_I_CPU0_SB_DQS_DN<7>")
	)
	(gr_poly
		(pts
			(xy 379.384814 -286.03448) (xy 379.384814 -285.986728) (xy 379.184662 -285.986728) (xy 379.184662 -286.03448)
			(xy 379.284738 -286.134302)
		)
		(stroke
			(width 0)
			(type solid)
		)
		(fill yes)
		(layer "In2.Cu")
		(net "M_I_CPU0_SB_DQS_DN<2>")
	)
	(gr_poly
		(pts
			(xy 379.384814 -284.818074) (xy 379.284738 -284.717998) (xy 379.184662 -284.818074) (xy 379.184662 -284.862524)
			(xy 379.384814 -284.862524)
		)
		(stroke
			(width 0)
			(type solid)
		)
		(fill yes)
		(layer "In2.Cu")
		(net "M_I_CPU0_SB_DQ<17>")
	)
	(gr_poly
		(pts
			(xy 379.384814 -284.414214) (xy 379.384814 -284.369764) (xy 379.184662 -284.369764) (xy 379.184662 -284.414214)
			(xy 379.284738 -284.51429)
		)
		(stroke
			(width 0)
			(type solid)
		)
		(fill yes)
		(layer "In2.Cu")
		(net "M_I_CPU0_SB_DQ<18>")
	)
	(gr_poly
		(pts
			(xy 379.384814 -283.198062) (xy 379.284738 -283.097986) (xy 379.184662 -283.198062) (xy 379.184662 -283.242512)
			(xy 379.384814 -283.242512)
		)
		(stroke
			(width 0)
			(type solid)
		)
		(fill yes)
		(layer "In2.Cu")
		(net "M_I_CPU0_SB_DQ<13>")
	)
	(gr_poly
		(pts
			(xy 379.384814 -282.794202) (xy 379.384814 -282.749752) (xy 379.184662 -282.749752) (xy 379.184662 -282.794202)
			(xy 379.284738 -282.894278)
		)
		(stroke
			(width 0)
			(type solid)
		)
		(fill yes)
		(layer "In2.Cu")
		(net "M_I_CPU0_SB_DQ<14>")
	)
	(gr_poly
		(pts
			(xy 379.384814 -281.577796) (xy 379.284738 -281.477974) (xy 379.184662 -281.577796) (xy 379.184662 -281.625548)
			(xy 379.384814 -281.625548)
		)
		(stroke
			(width 0)
			(type solid)
		)
		(fill yes)
		(layer "In2.Cu")
		(net "M_I_CPU0_SB_DQS_DN<6>")
	)
	(gr_poly
		(pts
			(xy 379.384814 -281.174444) (xy 379.384814 -281.126692) (xy 379.184662 -281.126692) (xy 379.184662 -281.174444)
			(xy 379.284738 -281.274266)
		)
		(stroke
			(width 0)
			(type solid)
		)
		(fill yes)
		(layer "In2.Cu")
		(net "M_I_CPU0_SB_DQS_DN<1>")
	)
	(gr_poly
		(pts
			(xy 379.384814 -279.958038) (xy 379.284738 -279.857962) (xy 379.184662 -279.958038) (xy 379.184662 -280.002488)
			(xy 379.384814 -280.002488)
		)
		(stroke
			(width 0)
			(type solid)
		)
		(fill yes)
		(layer "In2.Cu")
		(net "M_I_CPU0_SB_DQ<9>")
	)
	(gr_poly
		(pts
			(xy 379.384814 -279.554178) (xy 379.384814 -279.509728) (xy 379.184662 -279.509728) (xy 379.184662 -279.554178)
			(xy 379.284738 -279.654254)
		)
		(stroke
			(width 0)
			(type solid)
		)
		(fill yes)
		(layer "In2.Cu")
		(net "M_I_CPU0_SB_DQ<10>")
	)
	(gr_poly
		(pts
			(xy 379.384814 -278.338026) (xy 379.284738 -278.23795) (xy 379.184662 -278.338026) (xy 379.184662 -278.382476)
			(xy 379.384814 -278.382476)
		)
		(stroke
			(width 0)
			(type solid)
		)
		(fill yes)
		(layer "In2.Cu")
		(net "M_I_CPU0_SB_DQ<5>")
	)
	(gr_poly
		(pts
			(xy 379.384814 -277.934166) (xy 379.384814 -277.889716) (xy 379.184662 -277.889716) (xy 379.184662 -277.934166)
			(xy 379.284738 -278.034242)
		)
		(stroke
			(width 0)
			(type solid)
		)
		(fill yes)
		(layer "In2.Cu")
		(net "M_I_CPU0_SB_DQ<6>")
	)
	(gr_poly
		(pts
			(xy 379.384814 -276.71776) (xy 379.284738 -276.617938) (xy 379.184662 -276.71776) (xy 379.184662 -276.765512)
			(xy 379.384814 -276.765512)
		)
		(stroke
			(width 0)
			(type solid)
		)
		(fill yes)
		(layer "In2.Cu")
		(net "M_I_CPU0_SB_DQS_DN<5>")
	)
	(gr_poly
		(pts
			(xy 379.384814 -276.314408) (xy 379.384814 -276.266656) (xy 379.184662 -276.266656) (xy 379.184662 -276.314408)
			(xy 379.284738 -276.41423)
		)
		(stroke
			(width 0)
			(type solid)
		)
		(fill yes)
		(layer "In2.Cu")
		(net "M_I_CPU0_SB_DQS_DN<0>")
	)
	(gr_poly
		(pts
			(xy 379.384814 -275.098002) (xy 379.284738 -274.997926) (xy 379.184662 -275.098002) (xy 379.184662 -275.142452)
			(xy 379.384814 -275.142452)
		)
		(stroke
			(width 0)
			(type solid)
		)
		(fill yes)
		(layer "In2.Cu")
		(net "M_I_CPU0_SB_DQ<1>")
	)
	(gr_poly
		(pts
			(xy 379.384814 -274.694142) (xy 379.384814 -274.649692) (xy 379.184662 -274.649692) (xy 379.184662 -274.694142)
			(xy 379.284738 -274.794218)
		)
		(stroke
			(width 0)
			(type solid)
		)
		(fill yes)
		(layer "In2.Cu")
		(net "M_I_CPU0_SB_DQ<2>")
	)
	(gr_poly
		(pts
			(xy 379.384814 -273.47799) (xy 379.284738 -273.377914) (xy 379.184662 -273.47799) (xy 379.184662 -273.52244)
			(xy 379.384814 -273.52244)
		)
		(stroke
			(width 0)
			(type solid)
		)
		(fill yes)
		(layer "In2.Cu")
		(net "M_I_CPU0_SB_CB<1>")
	)
	(gr_poly
		(pts
			(xy 379.384814 -273.07413) (xy 379.384814 -273.02968) (xy 379.184662 -273.02968) (xy 379.184662 -273.07413)
			(xy 379.284738 -273.174206)
		)
		(stroke
			(width 0)
			(type solid)
		)
		(fill yes)
		(layer "In2.Cu")
		(net "M_I_CPU0_SB_CB<2>")
	)
	(gr_poly
		(pts
			(xy 379.384814 -271.857724) (xy 379.284738 -271.757902) (xy 379.184662 -271.857724) (xy 379.184662 -271.905476)
			(xy 379.384814 -271.905476)
		)
		(stroke
			(width 0)
			(type solid)
		)
		(fill yes)
		(layer "In2.Cu")
		(net "M_I_CPU0_SB_DQS_DN<4>")
	)
	(gr_poly
		(pts
			(xy 379.384814 -271.454372) (xy 379.384814 -271.40662) (xy 379.184662 -271.40662) (xy 379.184662 -271.454372)
			(xy 379.284738 -271.554194)
		)
		(stroke
			(width 0)
			(type solid)
		)
		(fill yes)
		(layer "In2.Cu")
		(net "M_I_CPU0_SB_DQS_DN<9>")
	)
	(gr_poly
		(pts
			(xy 379.384814 -270.237966) (xy 379.284738 -270.13789) (xy 379.184662 -270.237966) (xy 379.184662 -270.282416)
			(xy 379.384814 -270.282416)
		)
		(stroke
			(width 0)
			(type solid)
		)
		(fill yes)
		(layer "In2.Cu")
		(net "M_I_CPU0_SB_CB<5>")
	)
	(gr_poly
		(pts
			(xy 379.384814 -269.834106) (xy 379.384814 -269.789656) (xy 379.184662 -269.789656) (xy 379.184662 -269.834106)
			(xy 379.284738 -269.934182)
		)
		(stroke
			(width 0)
			(type solid)
		)
		(fill yes)
		(layer "In2.Cu")
		(net "M_I_CPU0_SB_CB<6>")
	)
	(gr_poly
		(pts
			(xy 379.384814 -266.997942) (xy 379.284738 -266.897866) (xy 379.184662 -266.997942) (xy 379.184662 -267.042392)
			(xy 379.384814 -267.042392)
		)
		(stroke
			(width 0)
			(type solid)
		)
		(fill yes)
		(layer "In2.Cu")
		(net "M_I_CPU0_SA_RSP<0>")
	)
	(gr_poly
		(pts
			(xy 379.384814 -266.594082) (xy 379.384814 -266.549632) (xy 379.184662 -266.549632) (xy 379.184662 -266.594082)
			(xy 379.284738 -266.694158)
		)
		(stroke
			(width 0)
			(type solid)
		)
		(fill yes)
		(layer "In2.Cu")
		(net "M_I_CPU0_SB_CS_N<1>")
	)
	(gr_poly
		(pts
			(xy 379.384814 -265.37793) (xy 379.284738 -265.277854) (xy 379.184662 -265.37793) (xy 379.184662 -265.42238)
			(xy 379.384814 -265.42238)
		)
		(stroke
			(width 0)
			(type solid)
		)
		(fill yes)
		(layer "In2.Cu")
		(net "M_I_CPU0_SB_PAR")
	)
	(gr_poly
		(pts
			(xy 379.384814 -263.757918) (xy 379.284738 -263.657842) (xy 379.184662 -263.757918) (xy 379.184662 -263.802368)
			(xy 379.384814 -263.802368)
		)
		(stroke
			(width 0)
			(type solid)
		)
		(fill yes)
		(layer "In2.Cu")
		(net "M_I_CPU0_SB_CA<4>")
	)
	(gr_poly
		(pts
			(xy 379.384814 -263.354058) (xy 379.384814 -263.309608) (xy 379.184662 -263.309608) (xy 379.184662 -263.354058)
			(xy 379.284738 -263.454134)
		)
		(stroke
			(width 0)
			(type solid)
		)
		(fill yes)
		(layer "In2.Cu")
		(net "M_I_CPU0_SB_CA<3>")
	)
	(gr_poly
		(pts
			(xy 379.384814 -262.137906) (xy 379.284738 -262.03783) (xy 379.184662 -262.137906) (xy 379.184662 -262.182356)
			(xy 379.384814 -262.182356)
		)
		(stroke
			(width 0)
			(type solid)
		)
		(fill yes)
		(layer "In2.Cu")
		(net "M_I_CPU0_SB_CA<0>")
	)
	(gr_poly
		(pts
			(xy 379.554994 -256.432558) (xy 379.554994 -256.384806) (xy 379.354842 -256.384806) (xy 379.354842 -256.432558)
			(xy 379.454918 -256.53238)
		)
		(stroke
			(width 0)
			(type solid)
		)
		(fill yes)
		(layer "In2.Cu")
		(net "M_I_CPU0_CLK_DN<0>")
	)
	(gr_poly
		(pts
			(xy 379.554994 -255.216152) (xy 379.454918 -255.116076) (xy 379.354842 -255.216152) (xy 379.354842 -255.260602)
			(xy 379.554994 -255.260602)
		)
		(stroke
			(width 0)
			(type solid)
		)
		(fill yes)
		(layer "In2.Cu")
		(net "M_I_CPU0_SA_CA<6>")
	)
	(gr_poly
		(pts
			(xy 379.554994 -254.812292) (xy 379.554994 -254.767842) (xy 379.354842 -254.767842) (xy 379.354842 -254.812292)
			(xy 379.454918 -254.912368)
		)
		(stroke
			(width 0)
			(type solid)
		)
		(fill yes)
		(layer "In2.Cu")
		(net "M_I_CPU0_SA_CA<5>")
	)
	(gr_poly
		(pts
			(xy 379.554994 -253.59614) (xy 379.454918 -253.496064) (xy 379.354842 -253.59614) (xy 379.354842 -253.64059)
			(xy 379.554994 -253.64059)
		)
		(stroke
			(width 0)
			(type solid)
		)
		(fill yes)
		(layer "In2.Cu")
		(net "M_I_CPU0_SA_CA<2>")
	)
	(gr_poly
		(pts
			(xy 379.554994 -253.19228) (xy 379.554994 -253.14783) (xy 379.354842 -253.14783) (xy 379.354842 -253.19228)
			(xy 379.454918 -253.292356)
		)
		(stroke
			(width 0)
			(type solid)
		)
		(fill yes)
		(layer "In2.Cu")
		(net "M_I_CPU0_SA_CA<1>")
	)
	(gr_poly
		(pts
			(xy 379.554994 -251.976128) (xy 379.454918 -251.876052) (xy 379.354842 -251.976128) (xy 379.354842 -252.020578)
			(xy 379.554994 -252.020578)
		)
		(stroke
			(width 0)
			(type solid)
		)
		(fill yes)
		(layer "In2.Cu")
		(net "M_I_CPU0_SA_CS_N<1>")
	)
	(gr_poly
		(pts
			(xy 379.554994 -250.356116) (xy 379.454918 -250.25604) (xy 379.354842 -250.356116) (xy 379.354842 -250.400566)
			(xy 379.554994 -250.400566)
		)
		(stroke
			(width 0)
			(type solid)
		)
		(fill yes)
		(layer "In2.Cu")
		(net "M_I_CPU0_ALERT_R_N")
	)
	(gr_poly
		(pts
			(xy 379.554994 -248.736104) (xy 379.454918 -248.636028) (xy 379.354842 -248.736104) (xy 379.354842 -248.780554)
			(xy 379.554994 -248.780554)
		)
		(stroke
			(width 0)
			(type solid)
		)
		(fill yes)
		(layer "In2.Cu")
		(net "M_I_CPU0_SA_CB<5>")
	)
	(gr_poly
		(pts
			(xy 379.554994 -248.332244) (xy 379.554994 -248.287794) (xy 379.354842 -248.287794) (xy 379.354842 -248.332244)
			(xy 379.454918 -248.43232)
		)
		(stroke
			(width 0)
			(type solid)
		)
		(fill yes)
		(layer "In2.Cu")
		(net "M_I_CPU0_SA_CB<6>")
	)
	(gr_poly
		(pts
			(xy 379.554994 -247.115838) (xy 379.454918 -247.016016) (xy 379.354842 -247.115838) (xy 379.354842 -247.16359)
			(xy 379.554994 -247.16359)
		)
		(stroke
			(width 0)
			(type solid)
		)
		(fill yes)
		(layer "In2.Cu")
		(net "M_I_CPU0_SA_DQS_DN<9>")
	)
	(gr_poly
		(pts
			(xy 379.554994 -246.712486) (xy 379.554994 -246.664734) (xy 379.354842 -246.664734) (xy 379.354842 -246.712486)
			(xy 379.454918 -246.812308)
		)
		(stroke
			(width 0)
			(type solid)
		)
		(fill yes)
		(layer "In2.Cu")
		(net "M_I_CPU0_SA_DQS_DN<4>")
	)
	(gr_poly
		(pts
			(xy 379.554994 -245.49608) (xy 379.454918 -245.396004) (xy 379.354842 -245.49608) (xy 379.354842 -245.54053)
			(xy 379.554994 -245.54053)
		)
		(stroke
			(width 0)
			(type solid)
		)
		(fill yes)
		(layer "In2.Cu")
		(net "M_I_CPU0_SA_CB<1>")
	)
	(gr_poly
		(pts
			(xy 379.554994 -245.09222) (xy 379.554994 -245.04777) (xy 379.354842 -245.04777) (xy 379.354842 -245.09222)
			(xy 379.454918 -245.192296)
		)
		(stroke
			(width 0)
			(type solid)
		)
		(fill yes)
		(layer "In2.Cu")
		(net "M_I_CPU0_SA_CB<2>")
	)
	(gr_poly
		(pts
			(xy 379.554994 -243.876068) (xy 379.454918 -243.775992) (xy 379.354842 -243.876068) (xy 379.354842 -243.920518)
			(xy 379.554994 -243.920518)
		)
		(stroke
			(width 0)
			(type solid)
		)
		(fill yes)
		(layer "In2.Cu")
		(net "M_I_CPU0_SA_DQ<29>")
	)
	(gr_poly
		(pts
			(xy 379.554994 -243.472208) (xy 379.554994 -243.427758) (xy 379.354842 -243.427758) (xy 379.354842 -243.472208)
			(xy 379.454918 -243.572284)
		)
		(stroke
			(width 0)
			(type solid)
		)
		(fill yes)
		(layer "In2.Cu")
		(net "M_I_CPU0_SA_DQ<30>")
	)
	(gr_poly
		(pts
			(xy 379.554994 -242.255802) (xy 379.454918 -242.15598) (xy 379.354842 -242.255802) (xy 379.354842 -242.303554)
			(xy 379.554994 -242.303554)
		)
		(stroke
			(width 0)
			(type solid)
		)
		(fill yes)
		(layer "In2.Cu")
		(net "M_I_CPU0_SA_DQS_DN<8>")
	)
	(gr_poly
		(pts
			(xy 379.554994 -241.85245) (xy 379.554994 -241.804698) (xy 379.354842 -241.804698) (xy 379.354842 -241.85245)
			(xy 379.454918 -241.952272)
		)
		(stroke
			(width 0)
			(type solid)
		)
		(fill yes)
		(layer "In2.Cu")
		(net "M_I_CPU0_SA_DQS_DN<3>")
	)
	(gr_poly
		(pts
			(xy 379.554994 -240.636044) (xy 379.454918 -240.535968) (xy 379.354842 -240.636044) (xy 379.354842 -240.680494)
			(xy 379.554994 -240.680494)
		)
		(stroke
			(width 0)
			(type solid)
		)
		(fill yes)
		(layer "In2.Cu")
		(net "M_I_CPU0_SA_DQ<25>")
	)
	(gr_poly
		(pts
			(xy 379.554994 -240.232184) (xy 379.554994 -240.187734) (xy 379.354842 -240.187734) (xy 379.354842 -240.232184)
			(xy 379.454918 -240.33226)
		)
		(stroke
			(width 0)
			(type solid)
		)
		(fill yes)
		(layer "In2.Cu")
		(net "M_I_CPU0_SA_DQ<26>")
	)
	(gr_poly
		(pts
			(xy 379.554994 -239.016032) (xy 379.454918 -238.915956) (xy 379.354842 -239.016032) (xy 379.354842 -239.060482)
			(xy 379.554994 -239.060482)
		)
		(stroke
			(width 0)
			(type solid)
		)
		(fill yes)
		(layer "In2.Cu")
		(net "M_I_CPU0_SA_DQ<21>")
	)
	(gr_poly
		(pts
			(xy 379.554994 -238.612172) (xy 379.554994 -238.567722) (xy 379.354842 -238.567722) (xy 379.354842 -238.612172)
			(xy 379.454918 -238.712248)
		)
		(stroke
			(width 0)
			(type solid)
		)
		(fill yes)
		(layer "In2.Cu")
		(net "M_I_CPU0_SA_DQ<22>")
	)
	(gr_poly
		(pts
			(xy 379.554994 -237.395766) (xy 379.454918 -237.295944) (xy 379.354842 -237.395766) (xy 379.354842 -237.443518)
			(xy 379.554994 -237.443518)
		)
		(stroke
			(width 0)
			(type solid)
		)
		(fill yes)
		(layer "In2.Cu")
		(net "M_I_CPU0_SA_DQS_DN<7>")
	)
	(gr_poly
		(pts
			(xy 379.554994 -236.992414) (xy 379.554994 -236.944662) (xy 379.354842 -236.944662) (xy 379.354842 -236.992414)
			(xy 379.454918 -237.092236)
		)
		(stroke
			(width 0)
			(type solid)
		)
		(fill yes)
		(layer "In2.Cu")
		(net "M_I_CPU0_SA_DQS_DN<2>")
	)
	(gr_poly
		(pts
			(xy 379.554994 -235.776008) (xy 379.454918 -235.675932) (xy 379.354842 -235.776008) (xy 379.354842 -235.820458)
			(xy 379.554994 -235.820458)
		)
		(stroke
			(width 0)
			(type solid)
		)
		(fill yes)
		(layer "In2.Cu")
		(net "M_I_CPU0_SA_DQ<17>")
	)
	(gr_poly
		(pts
			(xy 379.554994 -235.372148) (xy 379.554994 -235.327698) (xy 379.354842 -235.327698) (xy 379.354842 -235.372148)
			(xy 379.454918 -235.472224)
		)
		(stroke
			(width 0)
			(type solid)
		)
		(fill yes)
		(layer "In2.Cu")
		(net "M_I_CPU0_SA_DQ<18>")
	)
	(gr_poly
		(pts
			(xy 379.554994 -234.155996) (xy 379.454918 -234.05592) (xy 379.354842 -234.155996) (xy 379.354842 -234.200446)
			(xy 379.554994 -234.200446)
		)
		(stroke
			(width 0)
			(type solid)
		)
		(fill yes)
		(layer "In2.Cu")
		(net "M_I_CPU0_SA_DQ<13>")
	)
	(gr_poly
		(pts
			(xy 379.554994 -233.752136) (xy 379.554994 -233.707686) (xy 379.354842 -233.707686) (xy 379.354842 -233.752136)
			(xy 379.454918 -233.852212)
		)
		(stroke
			(width 0)
			(type solid)
		)
		(fill yes)
		(layer "In2.Cu")
		(net "M_I_CPU0_SA_DQ<14>")
	)
	(gr_poly
		(pts
			(xy 379.554994 -232.53573) (xy 379.454918 -232.435908) (xy 379.354842 -232.53573) (xy 379.354842 -232.583482)
			(xy 379.554994 -232.583482)
		)
		(stroke
			(width 0)
			(type solid)
		)
		(fill yes)
		(layer "In2.Cu")
		(net "M_I_CPU0_SA_DQS_DN<6>")
	)
	(gr_poly
		(pts
			(xy 379.554994 -232.132378) (xy 379.554994 -232.084626) (xy 379.354842 -232.084626) (xy 379.354842 -232.132378)
			(xy 379.454918 -232.2322)
		)
		(stroke
			(width 0)
			(type solid)
		)
		(fill yes)
		(layer "In2.Cu")
		(net "M_I_CPU0_SA_DQS_DN<1>")
	)
	(gr_poly
		(pts
			(xy 379.554994 -230.915972) (xy 379.454918 -230.815896) (xy 379.354842 -230.915972) (xy 379.354842 -230.960422)
			(xy 379.554994 -230.960422)
		)
		(stroke
			(width 0)
			(type solid)
		)
		(fill yes)
		(layer "In2.Cu")
		(net "M_I_CPU0_SA_DQ<9>")
	)
	(gr_poly
		(pts
			(xy 379.554994 -230.512366) (xy 379.554994 -230.467916) (xy 379.354842 -230.467916) (xy 379.354842 -230.512366)
			(xy 379.454918 -230.612188)
		)
		(stroke
			(width 0)
			(type solid)
		)
		(fill yes)
		(layer "In2.Cu")
		(net "M_I_CPU0_SA_DQ<10>")
	)
	(gr_poly
		(pts
			(xy 379.554994 -229.29596) (xy 379.454918 -229.195884) (xy 379.354842 -229.29596) (xy 379.354842 -229.34041)
			(xy 379.554994 -229.34041)
		)
		(stroke
			(width 0)
			(type solid)
		)
		(fill yes)
		(layer "In2.Cu")
		(net "M_I_CPU0_SA_DQ<5>")
	)
	(gr_poly
		(pts
			(xy 379.554994 -228.892354) (xy 379.554994 -228.847904) (xy 379.354842 -228.847904) (xy 379.354842 -228.892354)
			(xy 379.454918 -228.99243)
		)
		(stroke
			(width 0)
			(type solid)
		)
		(fill yes)
		(layer "In2.Cu")
		(net "M_I_CPU0_SA_DQ<6>")
	)
	(gr_poly
		(pts
			(xy 379.554994 -227.675948) (xy 379.454918 -227.576126) (xy 379.354842 -227.675948) (xy 379.354842 -227.7237)
			(xy 379.554994 -227.7237)
		)
		(stroke
			(width 0)
			(type solid)
		)
		(fill yes)
		(layer "In2.Cu")
		(net "M_I_CPU0_SA_DQS_DN<5>")
	)
	(gr_poly
		(pts
			(xy 379.554994 -227.272596) (xy 379.554994 -227.224844) (xy 379.354842 -227.224844) (xy 379.354842 -227.272596)
			(xy 379.454918 -227.372418)
		)
		(stroke
			(width 0)
			(type solid)
		)
		(fill yes)
		(layer "In2.Cu")
		(net "M_I_CPU0_SA_DQS_DN<0>")
	)
	(gr_poly
		(pts
			(xy 379.554994 -226.05619) (xy 379.454918 -225.956114) (xy 379.354842 -226.05619) (xy 379.354842 -226.10064)
			(xy 379.554994 -226.10064)
		)
		(stroke
			(width 0)
			(type solid)
		)
		(fill yes)
		(layer "In2.Cu")
		(net "M_I_CPU0_SA_DQ<1>")
	)
	(gr_poly
		(pts
			(xy 379.554994 -225.65233) (xy 379.554994 -225.60788) (xy 379.354842 -225.60788) (xy 379.354842 -225.65233)
			(xy 379.454918 -225.752406)
		)
		(stroke
			(width 0)
			(type solid)
		)
		(fill yes)
		(layer "In2.Cu")
		(net "M_I_CPU0_SA_DQ<2>")
	)
	(gr_poly
		(pts
			(xy 379.854968 -293.324026) (xy 379.854968 -293.279576) (xy 379.654816 -293.279576) (xy 379.654816 -293.324026)
			(xy 379.754892 -293.424102)
		)
		(stroke
			(width 0)
			(type solid)
		)
		(fill yes)
		(layer "In2.Cu")
		(net "M_I_CPU0_SB_DQ<31>")
	)
	(gr_poly
		(pts
			(xy 379.854968 -292.107874) (xy 379.754892 -292.007798) (xy 379.654816 -292.107874) (xy 379.654816 -292.152324)
			(xy 379.854968 -292.152324)
		)
		(stroke
			(width 0)
			(type solid)
		)
		(fill yes)
		(layer "In2.Cu")
		(net "M_I_CPU0_SB_DQ<28>")
	)
	(gr_poly
		(pts
			(xy 379.854968 -291.704268) (xy 379.854968 -291.656516) (xy 379.654816 -291.656516) (xy 379.654816 -291.704268)
			(xy 379.754892 -291.80409)
		)
		(stroke
			(width 0)
			(type solid)
		)
		(fill yes)
		(layer "In2.Cu")
		(net "M_I_CPU0_SB_DQS_DP<8>")
	)
	(gr_poly
		(pts
			(xy 379.854968 -290.487608) (xy 379.754892 -290.387786) (xy 379.654816 -290.487608) (xy 379.654816 -290.53536)
			(xy 379.854968 -290.53536)
		)
		(stroke
			(width 0)
			(type solid)
		)
		(fill yes)
		(layer "In2.Cu")
		(net "M_I_CPU0_SB_DQS_DP<3>")
	)
	(gr_poly
		(pts
			(xy 379.854968 -290.084002) (xy 379.854968 -290.039552) (xy 379.654816 -290.039552) (xy 379.654816 -290.084002)
			(xy 379.754892 -290.184078)
		)
		(stroke
			(width 0)
			(type solid)
		)
		(fill yes)
		(layer "In2.Cu")
		(net "M_I_CPU0_SB_DQ<27>")
	)
	(gr_poly
		(pts
			(xy 379.854968 -288.86785) (xy 379.754892 -288.767774) (xy 379.654816 -288.86785) (xy 379.654816 -288.9123)
			(xy 379.854968 -288.9123)
		)
		(stroke
			(width 0)
			(type solid)
		)
		(fill yes)
		(layer "In2.Cu")
		(net "M_I_CPU0_SB_DQ<24>")
	)
	(gr_poly
		(pts
			(xy 379.854968 -288.464244) (xy 379.854968 -288.419794) (xy 379.654816 -288.419794) (xy 379.654816 -288.464244)
			(xy 379.754892 -288.56432)
		)
		(stroke
			(width 0)
			(type solid)
		)
		(fill yes)
		(layer "In2.Cu")
		(net "M_I_CPU0_SB_DQ<23>")
	)
	(gr_poly
		(pts
			(xy 379.854968 -287.247838) (xy 379.754892 -287.148016) (xy 379.654816 -287.247838) (xy 379.654816 -287.292288)
			(xy 379.854968 -287.292288)
		)
		(stroke
			(width 0)
			(type solid)
		)
		(fill yes)
		(layer "In2.Cu")
		(net "M_I_CPU0_SB_DQ<20>")
	)
	(gr_poly
		(pts
			(xy 379.854968 -286.844232) (xy 379.854968 -286.79648) (xy 379.654816 -286.79648) (xy 379.654816 -286.844232)
			(xy 379.754892 -286.944308)
		)
		(stroke
			(width 0)
			(type solid)
		)
		(fill yes)
		(layer "In2.Cu")
		(net "M_I_CPU0_SB_DQS_DP<7>")
	)
	(gr_poly
		(pts
			(xy 379.854968 -285.627826) (xy 379.754892 -285.528004) (xy 379.654816 -285.627826) (xy 379.654816 -285.675578)
			(xy 379.854968 -285.675578)
		)
		(stroke
			(width 0)
			(type solid)
		)
		(fill yes)
		(layer "In2.Cu")
		(net "M_I_CPU0_SB_DQS_DP<2>")
	)
	(gr_poly
		(pts
			(xy 379.854968 -285.22422) (xy 379.854968 -285.17977) (xy 379.654816 -285.17977) (xy 379.654816 -285.22422)
			(xy 379.754892 -285.324296)
		)
		(stroke
			(width 0)
			(type solid)
		)
		(fill yes)
		(layer "In2.Cu")
		(net "M_I_CPU0_SB_DQ<19>")
	)
	(gr_poly
		(pts
			(xy 379.854968 -284.008068) (xy 379.754892 -283.907992) (xy 379.654816 -284.008068) (xy 379.654816 -284.052518)
			(xy 379.854968 -284.052518)
		)
		(stroke
			(width 0)
			(type solid)
		)
		(fill yes)
		(layer "In2.Cu")
		(net "M_I_CPU0_SB_DQ<16>")
	)
	(gr_poly
		(pts
			(xy 379.854968 -283.604208) (xy 379.854968 -283.559758) (xy 379.654816 -283.559758) (xy 379.654816 -283.604208)
			(xy 379.754892 -283.704284)
		)
		(stroke
			(width 0)
			(type solid)
		)
		(fill yes)
		(layer "In2.Cu")
		(net "M_I_CPU0_SB_DQ<15>")
	)
	(gr_poly
		(pts
			(xy 379.854968 -282.388056) (xy 379.754892 -282.28798) (xy 379.654816 -282.388056) (xy 379.654816 -282.432506)
			(xy 379.854968 -282.432506)
		)
		(stroke
			(width 0)
			(type solid)
		)
		(fill yes)
		(layer "In2.Cu")
		(net "M_I_CPU0_SB_DQ<12>")
	)
	(gr_poly
		(pts
			(xy 379.854968 -281.98445) (xy 379.854968 -281.936698) (xy 379.654816 -281.936698) (xy 379.654816 -281.98445)
			(xy 379.754892 -282.084272)
		)
		(stroke
			(width 0)
			(type solid)
		)
		(fill yes)
		(layer "In2.Cu")
		(net "M_I_CPU0_SB_DQS_DP<6>")
	)
	(gr_poly
		(pts
			(xy 379.854968 -280.76779) (xy 379.754892 -280.667968) (xy 379.654816 -280.76779) (xy 379.654816 -280.815542)
			(xy 379.854968 -280.815542)
		)
		(stroke
			(width 0)
			(type solid)
		)
		(fill yes)
		(layer "In2.Cu")
		(net "M_I_CPU0_SB_DQS_DP<1>")
	)
	(gr_poly
		(pts
			(xy 379.854968 -280.364184) (xy 379.854968 -280.319734) (xy 379.654816 -280.319734) (xy 379.654816 -280.364184)
			(xy 379.754892 -280.46426)
		)
		(stroke
			(width 0)
			(type solid)
		)
		(fill yes)
		(layer "In2.Cu")
		(net "M_I_CPU0_SB_DQ<11>")
	)
	(gr_poly
		(pts
			(xy 379.854968 -279.148032) (xy 379.754892 -279.047956) (xy 379.654816 -279.148032) (xy 379.654816 -279.192482)
			(xy 379.854968 -279.192482)
		)
		(stroke
			(width 0)
			(type solid)
		)
		(fill yes)
		(layer "In2.Cu")
		(net "M_I_CPU0_SB_DQ<8>")
	)
	(gr_poly
		(pts
			(xy 379.854968 -278.744172) (xy 379.854968 -278.699722) (xy 379.654816 -278.699722) (xy 379.654816 -278.744172)
			(xy 379.754892 -278.844248)
		)
		(stroke
			(width 0)
			(type solid)
		)
		(fill yes)
		(layer "In2.Cu")
		(net "M_I_CPU0_SB_DQ<7>")
	)
	(gr_poly
		(pts
			(xy 379.854968 -277.52802) (xy 379.754892 -277.427944) (xy 379.654816 -277.52802) (xy 379.654816 -277.57247)
			(xy 379.854968 -277.57247)
		)
		(stroke
			(width 0)
			(type solid)
		)
		(fill yes)
		(layer "In2.Cu")
		(net "M_I_CPU0_SB_DQ<4>")
	)
	(gr_poly
		(pts
			(xy 379.854968 -277.124414) (xy 379.854968 -277.076662) (xy 379.654816 -277.076662) (xy 379.654816 -277.124414)
			(xy 379.754892 -277.224236)
		)
		(stroke
			(width 0)
			(type solid)
		)
		(fill yes)
		(layer "In2.Cu")
		(net "M_I_CPU0_SB_DQS_DP<5>")
	)
	(gr_poly
		(pts
			(xy 379.854968 -275.907754) (xy 379.754892 -275.807932) (xy 379.654816 -275.907754) (xy 379.654816 -275.955506)
			(xy 379.854968 -275.955506)
		)
		(stroke
			(width 0)
			(type solid)
		)
		(fill yes)
		(layer "In2.Cu")
		(net "M_I_CPU0_SB_DQS_DP<0>")
	)
	(gr_poly
		(pts
			(xy 379.854968 -275.504148) (xy 379.854968 -275.459698) (xy 379.654816 -275.459698) (xy 379.654816 -275.504148)
			(xy 379.754892 -275.604224)
		)
		(stroke
			(width 0)
			(type solid)
		)
		(fill yes)
		(layer "In2.Cu")
		(net "M_I_CPU0_SB_DQ<3>")
	)
	(gr_poly
		(pts
			(xy 379.854968 -274.287996) (xy 379.754892 -274.18792) (xy 379.654816 -274.287996) (xy 379.654816 -274.332446)
			(xy 379.854968 -274.332446)
		)
		(stroke
			(width 0)
			(type solid)
		)
		(fill yes)
		(layer "In2.Cu")
		(net "M_I_CPU0_SB_DQ<0>")
	)
	(gr_poly
		(pts
			(xy 379.854968 -273.884136) (xy 379.854968 -273.839686) (xy 379.654816 -273.839686) (xy 379.654816 -273.884136)
			(xy 379.754892 -273.984212)
		)
		(stroke
			(width 0)
			(type solid)
		)
		(fill yes)
		(layer "In2.Cu")
		(net "M_I_CPU0_SB_CB<3>")
	)
	(gr_poly
		(pts
			(xy 379.854968 -272.667984) (xy 379.754892 -272.567908) (xy 379.654816 -272.667984) (xy 379.654816 -272.712434)
			(xy 379.854968 -272.712434)
		)
		(stroke
			(width 0)
			(type solid)
		)
		(fill yes)
		(layer "In2.Cu")
		(net "M_I_CPU0_SB_CB<0>")
	)
	(gr_poly
		(pts
			(xy 379.854968 -272.264378) (xy 379.854968 -272.216626) (xy 379.654816 -272.216626) (xy 379.654816 -272.264378)
			(xy 379.754892 -272.3642)
		)
		(stroke
			(width 0)
			(type solid)
		)
		(fill yes)
		(layer "In2.Cu")
		(net "M_I_CPU0_SB_DQS_DP<4>")
	)
	(gr_poly
		(pts
			(xy 379.854968 -271.047718) (xy 379.754892 -270.947896) (xy 379.654816 -271.047718) (xy 379.654816 -271.09547)
			(xy 379.854968 -271.09547)
		)
		(stroke
			(width 0)
			(type solid)
		)
		(fill yes)
		(layer "In2.Cu")
		(net "M_I_CPU0_SB_DQS_DP<9>")
	)
	(gr_poly
		(pts
			(xy 379.854968 -270.644112) (xy 379.854968 -270.599662) (xy 379.654816 -270.599662) (xy 379.654816 -270.644112)
			(xy 379.754892 -270.744188)
		)
		(stroke
			(width 0)
			(type solid)
		)
		(fill yes)
		(layer "In2.Cu")
		(net "M_I_CPU0_SB_CB<7>")
	)
	(gr_poly
		(pts
			(xy 379.854968 -269.42796) (xy 379.754892 -269.327884) (xy 379.654816 -269.42796) (xy 379.654816 -269.47241)
			(xy 379.854968 -269.47241)
		)
		(stroke
			(width 0)
			(type solid)
		)
		(fill yes)
		(layer "In2.Cu")
		(net "M_I_CPU0_SB_CB<4>")
	)
	(gr_poly
		(pts
			(xy 379.854968 -267.404088) (xy 379.854968 -267.359638) (xy 379.654816 -267.359638) (xy 379.654816 -267.404088)
			(xy 379.754892 -267.504164)
		)
		(stroke
			(width 0)
			(type solid)
		)
		(fill yes)
		(layer "In2.Cu")
		(net "M_I_CPU0_SB_RSP<0>")
	)
	(gr_poly
		(pts
			(xy 379.854968 -265.784076) (xy 379.854968 -265.739626) (xy 379.654816 -265.739626) (xy 379.654816 -265.784076)
			(xy 379.754892 -265.884152)
		)
		(stroke
			(width 0)
			(type solid)
		)
		(fill yes)
		(layer "In2.Cu")
		(net "M_I_CPU0_SB_CS_N<0>")
	)
	(gr_poly
		(pts
			(xy 379.854968 -264.567924) (xy 379.754892 -264.467848) (xy 379.654816 -264.567924) (xy 379.654816 -264.612374)
			(xy 379.854968 -264.612374)
		)
		(stroke
			(width 0)
			(type solid)
		)
		(fill yes)
		(layer "In2.Cu")
		(net "M_I_CPU0_SB_CA<6>")
	)
	(gr_poly
		(pts
			(xy 379.854968 -264.164064) (xy 379.854968 -264.119614) (xy 379.654816 -264.119614) (xy 379.654816 -264.164064)
			(xy 379.754892 -264.26414)
		)
		(stroke
			(width 0)
			(type solid)
		)
		(fill yes)
		(layer "In2.Cu")
		(net "M_I_CPU0_SB_CA<5>")
	)
	(gr_poly
		(pts
			(xy 379.854968 -262.947912) (xy 379.754892 -262.847836) (xy 379.654816 -262.947912) (xy 379.654816 -262.992362)
			(xy 379.854968 -262.992362)
		)
		(stroke
			(width 0)
			(type solid)
		)
		(fill yes)
		(layer "In2.Cu")
		(net "M_I_CPU0_SB_CA<2>")
	)
	(gr_poly
		(pts
			(xy 379.854968 -262.544052) (xy 379.854968 -262.499602) (xy 379.654816 -262.499602) (xy 379.654816 -262.544052)
			(xy 379.754892 -262.644128)
		)
		(stroke
			(width 0)
			(type solid)
		)
		(fill yes)
		(layer "In2.Cu")
		(net "M_I_CPU0_SB_CA<1>")
	)
	(gr_poly
		(pts
			(xy 380.024894 -256.025904) (xy 379.924818 -255.926082) (xy 379.824742 -256.025904) (xy 379.824742 -256.073656)
			(xy 380.024894 -256.073656)
		)
		(stroke
			(width 0)
			(type solid)
		)
		(fill yes)
		(layer "In2.Cu")
		(net "M_I_CPU0_CLK_DP<0>")
	)
	(gr_poly
		(pts
			(xy 380.024894 -255.622298) (xy 380.024894 -255.577848) (xy 379.824742 -255.577848) (xy 379.824742 -255.622298)
			(xy 379.924818 -255.722374)
		)
		(stroke
			(width 0)
			(type solid)
		)
		(fill yes)
		(layer "In2.Cu")
		(net "M_I_CPU0_SA_PAR")
	)
	(gr_poly
		(pts
			(xy 380.024894 -254.406146) (xy 379.924818 -254.30607) (xy 379.824742 -254.406146) (xy 379.824742 -254.450596)
			(xy 380.024894 -254.450596)
		)
		(stroke
			(width 0)
			(type solid)
		)
		(fill yes)
		(layer "In2.Cu")
		(net "M_I_CPU0_SA_CA<4>")
	)
	(gr_poly
		(pts
			(xy 380.024894 -254.002286) (xy 380.024894 -253.957836) (xy 379.824742 -253.957836) (xy 379.824742 -254.002286)
			(xy 379.924818 -254.102362)
		)
		(stroke
			(width 0)
			(type solid)
		)
		(fill yes)
		(layer "In2.Cu")
		(net "M_I_CPU0_SA_CA<3>")
	)
	(gr_poly
		(pts
			(xy 380.024894 -252.786134) (xy 379.924818 -252.686058) (xy 379.824742 -252.786134) (xy 379.824742 -252.830584)
			(xy 380.024894 -252.830584)
		)
		(stroke
			(width 0)
			(type solid)
		)
		(fill yes)
		(layer "In2.Cu")
		(net "M_I_CPU0_SA_CA<0>")
	)
	(gr_poly
		(pts
			(xy 380.024894 -251.166122) (xy 379.924818 -251.066046) (xy 379.824742 -251.166122) (xy 379.824742 -251.210572)
			(xy 380.024894 -251.210572)
		)
		(stroke
			(width 0)
			(type solid)
		)
		(fill yes)
		(layer "In2.Cu")
		(net "M_I_CPU0_SA_CS_N<0>")
	)
	(gr_poly
		(pts
			(xy 380.024894 -250.762262) (xy 380.024894 -250.717812) (xy 379.824742 -250.717812) (xy 379.824742 -250.762262)
			(xy 379.924818 -250.862338)
		)
		(stroke
			(width 0)
			(type solid)
		)
		(fill yes)
		(layer "In2.Cu")
		(net "M_I_CPU0_RESET_N")
	)
	(gr_poly
		(pts
			(xy 380.024894 -249.14225) (xy 380.024894 -249.0978) (xy 379.824742 -249.0978) (xy 379.824742 -249.14225)
			(xy 379.924818 -249.242326)
		)
		(stroke
			(width 0)
			(type solid)
		)
		(fill yes)
		(layer "In2.Cu")
		(net "M_I_CPU0_SA_CB<7>")
	)
	(gr_poly
		(pts
			(xy 380.024894 -247.926098) (xy 379.924818 -247.826022) (xy 379.824742 -247.926098) (xy 379.824742 -247.970548)
			(xy 380.024894 -247.970548)
		)
		(stroke
			(width 0)
			(type solid)
		)
		(fill yes)
		(layer "In2.Cu")
		(net "M_I_CPU0_SA_CB<4>")
	)
	(gr_poly
		(pts
			(xy 380.024894 -247.522492) (xy 380.024894 -247.47474) (xy 379.824742 -247.47474) (xy 379.824742 -247.522492)
			(xy 379.924818 -247.622314)
		)
		(stroke
			(width 0)
			(type solid)
		)
		(fill yes)
		(layer "In2.Cu")
		(net "M_I_CPU0_SA_DQS_DP<9>")
	)
	(gr_poly
		(pts
			(xy 380.024894 -246.305832) (xy 379.924818 -246.20601) (xy 379.824742 -246.305832) (xy 379.824742 -246.353584)
			(xy 380.024894 -246.353584)
		)
		(stroke
			(width 0)
			(type solid)
		)
		(fill yes)
		(layer "In2.Cu")
		(net "M_I_CPU0_SA_DQS_DP<4>")
	)
	(gr_poly
		(pts
			(xy 380.024894 -245.902226) (xy 380.024894 -245.857776) (xy 379.824742 -245.857776) (xy 379.824742 -245.902226)
			(xy 379.924818 -246.002302)
		)
		(stroke
			(width 0)
			(type solid)
		)
		(fill yes)
		(layer "In2.Cu")
		(net "M_I_CPU0_SA_CB<3>")
	)
	(gr_poly
		(pts
			(xy 380.024894 -244.686074) (xy 379.924818 -244.585998) (xy 379.824742 -244.686074) (xy 379.824742 -244.730524)
			(xy 380.024894 -244.730524)
		)
		(stroke
			(width 0)
			(type solid)
		)
		(fill yes)
		(layer "In2.Cu")
		(net "M_I_CPU0_SA_CB<0>")
	)
	(gr_poly
		(pts
			(xy 380.024894 -244.282214) (xy 380.024894 -244.237764) (xy 379.824742 -244.237764) (xy 379.824742 -244.282214)
			(xy 379.924818 -244.38229)
		)
		(stroke
			(width 0)
			(type solid)
		)
		(fill yes)
		(layer "In2.Cu")
		(net "M_I_CPU0_SA_DQ<31>")
	)
	(gr_poly
		(pts
			(xy 380.024894 -243.066062) (xy 379.924818 -242.965986) (xy 379.824742 -243.066062) (xy 379.824742 -243.110512)
			(xy 380.024894 -243.110512)
		)
		(stroke
			(width 0)
			(type solid)
		)
		(fill yes)
		(layer "In2.Cu")
		(net "M_I_CPU0_SA_DQ<28>")
	)
	(gr_poly
		(pts
			(xy 380.024894 -242.662456) (xy 380.024894 -242.614704) (xy 379.824742 -242.614704) (xy 379.824742 -242.662456)
			(xy 379.924818 -242.762278)
		)
		(stroke
			(width 0)
			(type solid)
		)
		(fill yes)
		(layer "In2.Cu")
		(net "M_I_CPU0_SA_DQS_DP<8>")
	)
	(gr_poly
		(pts
			(xy 380.024894 -241.445796) (xy 379.924818 -241.345974) (xy 379.824742 -241.445796) (xy 379.824742 -241.493548)
			(xy 380.024894 -241.493548)
		)
		(stroke
			(width 0)
			(type solid)
		)
		(fill yes)
		(layer "In2.Cu")
		(net "M_I_CPU0_SA_DQS_DP<3>")
	)
	(gr_poly
		(pts
			(xy 380.024894 -241.04219) (xy 380.024894 -240.99774) (xy 379.824742 -240.99774) (xy 379.824742 -241.04219)
			(xy 379.924818 -241.142266)
		)
		(stroke
			(width 0)
			(type solid)
		)
		(fill yes)
		(layer "In2.Cu")
		(net "M_I_CPU0_SA_DQ<27>")
	)
	(gr_poly
		(pts
			(xy 380.024894 -239.826038) (xy 379.924818 -239.725962) (xy 379.824742 -239.826038) (xy 379.824742 -239.870488)
			(xy 380.024894 -239.870488)
		)
		(stroke
			(width 0)
			(type solid)
		)
		(fill yes)
		(layer "In2.Cu")
		(net "M_I_CPU0_SA_DQ<24>")
	)
	(gr_poly
		(pts
			(xy 380.024894 -239.422178) (xy 380.024894 -239.377728) (xy 379.824742 -239.377728) (xy 379.824742 -239.422178)
			(xy 379.924818 -239.522254)
		)
		(stroke
			(width 0)
			(type solid)
		)
		(fill yes)
		(layer "In2.Cu")
		(net "M_I_CPU0_SA_DQ<23>")
	)
	(gr_poly
		(pts
			(xy 380.024894 -238.206026) (xy 379.924818 -238.10595) (xy 379.824742 -238.206026) (xy 379.824742 -238.250476)
			(xy 380.024894 -238.250476)
		)
		(stroke
			(width 0)
			(type solid)
		)
		(fill yes)
		(layer "In2.Cu")
		(net "M_I_CPU0_SA_DQ<20>")
	)
	(gr_poly
		(pts
			(xy 380.024894 -237.80242) (xy 380.024894 -237.754668) (xy 379.824742 -237.754668) (xy 379.824742 -237.80242)
			(xy 379.924818 -237.902242)
		)
		(stroke
			(width 0)
			(type solid)
		)
		(fill yes)
		(layer "In2.Cu")
		(net "M_I_CPU0_SA_DQS_DP<7>")
	)
	(gr_poly
		(pts
			(xy 380.024894 -236.58576) (xy 379.924818 -236.485938) (xy 379.824742 -236.58576) (xy 379.824742 -236.633512)
			(xy 380.024894 -236.633512)
		)
		(stroke
			(width 0)
			(type solid)
		)
		(fill yes)
		(layer "In2.Cu")
		(net "M_I_CPU0_SA_DQS_DP<2>")
	)
	(gr_poly
		(pts
			(xy 380.024894 -236.182154) (xy 380.024894 -236.137704) (xy 379.824742 -236.137704) (xy 379.824742 -236.182154)
			(xy 379.924818 -236.28223)
		)
		(stroke
			(width 0)
			(type solid)
		)
		(fill yes)
		(layer "In2.Cu")
		(net "M_I_CPU0_SA_DQ<19>")
	)
	(gr_poly
		(pts
			(xy 380.024894 -234.966002) (xy 379.924818 -234.865926) (xy 379.824742 -234.966002) (xy 379.824742 -235.010452)
			(xy 380.024894 -235.010452)
		)
		(stroke
			(width 0)
			(type solid)
		)
		(fill yes)
		(layer "In2.Cu")
		(net "M_I_CPU0_SA_DQ<16>")
	)
	(gr_poly
		(pts
			(xy 380.024894 -234.562142) (xy 380.024894 -234.517692) (xy 379.824742 -234.517692) (xy 379.824742 -234.562142)
			(xy 379.924818 -234.662218)
		)
		(stroke
			(width 0)
			(type solid)
		)
		(fill yes)
		(layer "In2.Cu")
		(net "M_I_CPU0_SA_DQ<15>")
	)
	(gr_poly
		(pts
			(xy 380.024894 -233.34599) (xy 379.924818 -233.245914) (xy 379.824742 -233.34599) (xy 379.824742 -233.39044)
			(xy 380.024894 -233.39044)
		)
		(stroke
			(width 0)
			(type solid)
		)
		(fill yes)
		(layer "In2.Cu")
		(net "M_I_CPU0_SA_DQ<12>")
	)
	(gr_poly
		(pts
			(xy 380.024894 -232.942384) (xy 380.024894 -232.894632) (xy 379.824742 -232.894632) (xy 379.824742 -232.942384)
			(xy 379.924818 -233.042206)
		)
		(stroke
			(width 0)
			(type solid)
		)
		(fill yes)
		(layer "In2.Cu")
		(net "M_I_CPU0_SA_DQS_DP<6>")
	)
	(gr_poly
		(pts
			(xy 380.024894 -231.725724) (xy 379.924818 -231.625902) (xy 379.824742 -231.725724) (xy 379.824742 -231.773476)
			(xy 380.024894 -231.773476)
		)
		(stroke
			(width 0)
			(type solid)
		)
		(fill yes)
		(layer "In2.Cu")
		(net "M_I_CPU0_SA_DQS_DP<1>")
	)
	(gr_poly
		(pts
			(xy 380.024894 -231.322372) (xy 380.024894 -231.277922) (xy 379.824742 -231.277922) (xy 379.824742 -231.322372)
			(xy 379.924818 -231.422448)
		)
		(stroke
			(width 0)
			(type solid)
		)
		(fill yes)
		(layer "In2.Cu")
		(net "M_I_CPU0_SA_DQ<11>")
	)
	(gr_poly
		(pts
			(xy 380.024894 -230.105966) (xy 379.924818 -230.006144) (xy 379.824742 -230.105966) (xy 379.824742 -230.150416)
			(xy 380.024894 -230.150416)
		)
		(stroke
			(width 0)
			(type solid)
		)
		(fill yes)
		(layer "In2.Cu")
		(net "M_I_CPU0_SA_DQ<8>")
	)
	(gr_poly
		(pts
			(xy 380.024894 -229.70236) (xy 380.024894 -229.65791) (xy 379.824742 -229.65791) (xy 379.824742 -229.70236)
			(xy 379.924818 -229.802436)
		)
		(stroke
			(width 0)
			(type solid)
		)
		(fill yes)
		(layer "In2.Cu")
		(net "M_I_CPU0_SA_DQ<7>")
	)
	(gr_poly
		(pts
			(xy 380.024894 -228.486208) (xy 379.924818 -228.386132) (xy 379.824742 -228.486208) (xy 379.824742 -228.530658)
			(xy 380.024894 -228.530658)
		)
		(stroke
			(width 0)
			(type solid)
		)
		(fill yes)
		(layer "In2.Cu")
		(net "M_I_CPU0_SA_DQ<4>")
	)
	(gr_poly
		(pts
			(xy 380.024894 -228.082602) (xy 380.024894 -228.03485) (xy 379.824742 -228.03485) (xy 379.824742 -228.082602)
			(xy 379.924818 -228.182424)
		)
		(stroke
			(width 0)
			(type solid)
		)
		(fill yes)
		(layer "In2.Cu")
		(net "M_I_CPU0_SA_DQS_DP<5>")
	)
	(gr_poly
		(pts
			(xy 380.024894 -226.865942) (xy 379.924818 -226.76612) (xy 379.824742 -226.865942) (xy 379.824742 -226.913694)
			(xy 380.024894 -226.913694)
		)
		(stroke
			(width 0)
			(type solid)
		)
		(fill yes)
		(layer "In2.Cu")
		(net "M_I_CPU0_SA_DQS_DP<0>")
	)
	(gr_poly
		(pts
			(xy 380.024894 -226.462336) (xy 380.024894 -226.417886) (xy 379.824742 -226.417886) (xy 379.824742 -226.462336)
			(xy 379.924818 -226.562412)
		)
		(stroke
			(width 0)
			(type solid)
		)
		(fill yes)
		(layer "In2.Cu")
		(net "M_I_CPU0_SA_DQ<3>")
	)
	(gr_poly
		(pts
			(xy 380.024894 -225.246184) (xy 379.924818 -225.146108) (xy 379.824742 -225.246184) (xy 379.824742 -225.290634)
			(xy 380.024894 -225.290634)
		)
		(stroke
			(width 0)
			(type solid)
		)
		(fill yes)
		(layer "In2.Cu")
		(net "M_I_CPU0_SA_DQ<0>")
	)
	(gr_poly
		(pts
			(xy 380.324868 -292.91788) (xy 380.224792 -292.817804) (xy 380.124716 -292.91788) (xy 380.124716 -292.96233)
			(xy 380.324868 -292.96233)
		)
		(stroke
			(width 0)
			(type solid)
		)
		(fill yes)
		(layer "In2.Cu")
		(net "M_I_CPU0_SB_DQ<29>")
	)
	(gr_poly
		(pts
			(xy 380.324868 -292.51402) (xy 380.324868 -292.46957) (xy 380.124716 -292.46957) (xy 380.124716 -292.51402)
			(xy 380.224792 -292.614096)
		)
		(stroke
			(width 0)
			(type solid)
		)
		(fill yes)
		(layer "In2.Cu")
		(net "M_I_CPU0_SB_DQ<30>")
	)
	(gr_poly
		(pts
			(xy 380.324868 -291.297614) (xy 380.224792 -291.197792) (xy 380.124716 -291.297614) (xy 380.124716 -291.345366)
			(xy 380.324868 -291.345366)
		)
		(stroke
			(width 0)
			(type solid)
		)
		(fill yes)
		(layer "In2.Cu")
		(net "M_I_CPU0_SB_DQS_DN<8>")
	)
	(gr_poly
		(pts
			(xy 380.324868 -290.894262) (xy 380.324868 -290.84651) (xy 380.124716 -290.84651) (xy 380.124716 -290.894262)
			(xy 380.224792 -290.994084)
		)
		(stroke
			(width 0)
			(type solid)
		)
		(fill yes)
		(layer "In2.Cu")
		(net "M_I_CPU0_SB_DQS_DN<3>")
	)
	(gr_poly
		(pts
			(xy 380.324868 -289.677856) (xy 380.224792 -289.57778) (xy 380.124716 -289.677856) (xy 380.124716 -289.722306)
			(xy 380.324868 -289.722306)
		)
		(stroke
			(width 0)
			(type solid)
		)
		(fill yes)
		(layer "In2.Cu")
		(net "M_I_CPU0_SB_DQ<25>")
	)
	(gr_poly
		(pts
			(xy 380.324868 -289.273996) (xy 380.324868 -289.229546) (xy 380.124716 -289.229546) (xy 380.124716 -289.273996)
			(xy 380.224792 -289.374072)
		)
		(stroke
			(width 0)
			(type solid)
		)
		(fill yes)
		(layer "In2.Cu")
		(net "M_I_CPU0_SB_DQ<26>")
	)
	(gr_poly
		(pts
			(xy 380.324868 -288.057844) (xy 380.224792 -287.957768) (xy 380.124716 -288.057844) (xy 380.124716 -288.102294)
			(xy 380.324868 -288.102294)
		)
		(stroke
			(width 0)
			(type solid)
		)
		(fill yes)
		(layer "In2.Cu")
		(net "M_I_CPU0_SB_DQ<21>")
	)
	(gr_poly
		(pts
			(xy 380.324868 -287.654238) (xy 380.324868 -287.609788) (xy 380.124716 -287.609788) (xy 380.124716 -287.654238)
			(xy 380.224792 -287.75406)
		)
		(stroke
			(width 0)
			(type solid)
		)
		(fill yes)
		(layer "In2.Cu")
		(net "M_I_CPU0_SB_DQ<22>")
	)
	(gr_poly
		(pts
			(xy 380.324868 -286.437832) (xy 380.224792 -286.337756) (xy 380.124716 -286.437832) (xy 380.124716 -286.485584)
			(xy 380.324868 -286.485584)
		)
		(stroke
			(width 0)
			(type solid)
		)
		(fill yes)
		(layer "In2.Cu")
		(net "M_I_CPU0_SB_DQS_DN<7>")
	)
	(gr_poly
		(pts
			(xy 380.324868 -286.03448) (xy 380.324868 -285.986728) (xy 380.124716 -285.986728) (xy 380.124716 -286.03448)
			(xy 380.224792 -286.134302)
		)
		(stroke
			(width 0)
			(type solid)
		)
		(fill yes)
		(layer "In2.Cu")
		(net "M_I_CPU0_SB_DQS_DN<2>")
	)
	(gr_poly
		(pts
			(xy 380.324868 -284.818074) (xy 380.224792 -284.717998) (xy 380.124716 -284.818074) (xy 380.124716 -284.862524)
			(xy 380.324868 -284.862524)
		)
		(stroke
			(width 0)
			(type solid)
		)
		(fill yes)
		(layer "In2.Cu")
		(net "M_I_CPU0_SB_DQ<17>")
	)
	(gr_poly
		(pts
			(xy 380.324868 -284.414214) (xy 380.324868 -284.369764) (xy 380.124716 -284.369764) (xy 380.124716 -284.414214)
			(xy 380.224792 -284.51429)
		)
		(stroke
			(width 0)
			(type solid)
		)
		(fill yes)
		(layer "In2.Cu")
		(net "M_I_CPU0_SB_DQ<18>")
	)
	(gr_poly
		(pts
			(xy 380.324868 -283.198062) (xy 380.224792 -283.097986) (xy 380.124716 -283.198062) (xy 380.124716 -283.242512)
			(xy 380.324868 -283.242512)
		)
		(stroke
			(width 0)
			(type solid)
		)
		(fill yes)
		(layer "In2.Cu")
		(net "M_I_CPU0_SB_DQ<13>")
	)
	(gr_poly
		(pts
			(xy 380.324868 -282.794202) (xy 380.324868 -282.749752) (xy 380.124716 -282.749752) (xy 380.124716 -282.794202)
			(xy 380.224792 -282.894278)
		)
		(stroke
			(width 0)
			(type solid)
		)
		(fill yes)
		(layer "In2.Cu")
		(net "M_I_CPU0_SB_DQ<14>")
	)
	(gr_poly
		(pts
			(xy 380.324868 -281.577796) (xy 380.224792 -281.477974) (xy 380.124716 -281.577796) (xy 380.124716 -281.625548)
			(xy 380.324868 -281.625548)
		)
		(stroke
			(width 0)
			(type solid)
		)
		(fill yes)
		(layer "In2.Cu")
		(net "M_I_CPU0_SB_DQS_DN<6>")
	)
	(gr_poly
		(pts
			(xy 380.324868 -281.174444) (xy 380.324868 -281.126692) (xy 380.124716 -281.126692) (xy 380.124716 -281.174444)
			(xy 380.224792 -281.274266)
		)
		(stroke
			(width 0)
			(type solid)
		)
		(fill yes)
		(layer "In2.Cu")
		(net "M_I_CPU0_SB_DQS_DN<1>")
	)
	(gr_poly
		(pts
			(xy 380.324868 -279.958038) (xy 380.224792 -279.857962) (xy 380.124716 -279.958038) (xy 380.124716 -280.002488)
			(xy 380.324868 -280.002488)
		)
		(stroke
			(width 0)
			(type solid)
		)
		(fill yes)
		(layer "In2.Cu")
		(net "M_I_CPU0_SB_DQ<9>")
	)
	(gr_poly
		(pts
			(xy 380.324868 -279.554178) (xy 380.324868 -279.509728) (xy 380.124716 -279.509728) (xy 380.124716 -279.554178)
			(xy 380.224792 -279.654254)
		)
		(stroke
			(width 0)
			(type solid)
		)
		(fill yes)
		(layer "In2.Cu")
		(net "M_I_CPU0_SB_DQ<10>")
	)
	(gr_poly
		(pts
			(xy 380.324868 -278.338026) (xy 380.224792 -278.23795) (xy 380.124716 -278.338026) (xy 380.124716 -278.382476)
			(xy 380.324868 -278.382476)
		)
		(stroke
			(width 0)
			(type solid)
		)
		(fill yes)
		(layer "In2.Cu")
		(net "M_I_CPU0_SB_DQ<5>")
	)
	(gr_poly
		(pts
			(xy 380.324868 -277.934166) (xy 380.324868 -277.889716) (xy 380.124716 -277.889716) (xy 380.124716 -277.934166)
			(xy 380.224792 -278.034242)
		)
		(stroke
			(width 0)
			(type solid)
		)
		(fill yes)
		(layer "In2.Cu")
		(net "M_I_CPU0_SB_DQ<6>")
	)
	(gr_poly
		(pts
			(xy 380.324868 -276.71776) (xy 380.224792 -276.617938) (xy 380.124716 -276.71776) (xy 380.124716 -276.765512)
			(xy 380.324868 -276.765512)
		)
		(stroke
			(width 0)
			(type solid)
		)
		(fill yes)
		(layer "In2.Cu")
		(net "M_I_CPU0_SB_DQS_DN<5>")
	)
	(gr_poly
		(pts
			(xy 380.324868 -276.314408) (xy 380.324868 -276.266656) (xy 380.124716 -276.266656) (xy 380.124716 -276.314408)
			(xy 380.224792 -276.41423)
		)
		(stroke
			(width 0)
			(type solid)
		)
		(fill yes)
		(layer "In2.Cu")
		(net "M_I_CPU0_SB_DQS_DN<0>")
	)
	(gr_poly
		(pts
			(xy 380.324868 -275.098002) (xy 380.224792 -274.997926) (xy 380.124716 -275.098002) (xy 380.124716 -275.142452)
			(xy 380.324868 -275.142452)
		)
		(stroke
			(width 0)
			(type solid)
		)
		(fill yes)
		(layer "In2.Cu")
		(net "M_I_CPU0_SB_DQ<1>")
	)
	(gr_poly
		(pts
			(xy 380.324868 -274.694142) (xy 380.324868 -274.649692) (xy 380.124716 -274.649692) (xy 380.124716 -274.694142)
			(xy 380.224792 -274.794218)
		)
		(stroke
			(width 0)
			(type solid)
		)
		(fill yes)
		(layer "In2.Cu")
		(net "M_I_CPU0_SB_DQ<2>")
	)
	(gr_poly
		(pts
			(xy 380.324868 -273.47799) (xy 380.224792 -273.377914) (xy 380.124716 -273.47799) (xy 380.124716 -273.52244)
			(xy 380.324868 -273.52244)
		)
		(stroke
			(width 0)
			(type solid)
		)
		(fill yes)
		(layer "In2.Cu")
		(net "M_I_CPU0_SB_CB<1>")
	)
	(gr_poly
		(pts
			(xy 380.324868 -273.07413) (xy 380.324868 -273.02968) (xy 380.124716 -273.02968) (xy 380.124716 -273.07413)
			(xy 380.224792 -273.174206)
		)
		(stroke
			(width 0)
			(type solid)
		)
		(fill yes)
		(layer "In2.Cu")
		(net "M_I_CPU0_SB_CB<2>")
	)
	(gr_poly
		(pts
			(xy 380.324868 -271.857724) (xy 380.224792 -271.757902) (xy 380.124716 -271.857724) (xy 380.124716 -271.905476)
			(xy 380.324868 -271.905476)
		)
		(stroke
			(width 0)
			(type solid)
		)
		(fill yes)
		(layer "In2.Cu")
		(net "M_I_CPU0_SB_DQS_DN<4>")
	)
	(gr_poly
		(pts
			(xy 380.324868 -271.454372) (xy 380.324868 -271.40662) (xy 380.124716 -271.40662) (xy 380.124716 -271.454372)
			(xy 380.224792 -271.554194)
		)
		(stroke
			(width 0)
			(type solid)
		)
		(fill yes)
		(layer "In2.Cu")
		(net "M_I_CPU0_SB_DQS_DN<9>")
	)
	(gr_poly
		(pts
			(xy 380.324868 -270.237966) (xy 380.224792 -270.13789) (xy 380.124716 -270.237966) (xy 380.124716 -270.282416)
			(xy 380.324868 -270.282416)
		)
		(stroke
			(width 0)
			(type solid)
		)
		(fill yes)
		(layer "In2.Cu")
		(net "M_I_CPU0_SB_CB<5>")
	)
	(gr_poly
		(pts
			(xy 380.324868 -269.834106) (xy 380.324868 -269.789656) (xy 380.124716 -269.789656) (xy 380.124716 -269.834106)
			(xy 380.224792 -269.934182)
		)
		(stroke
			(width 0)
			(type solid)
		)
		(fill yes)
		(layer "In2.Cu")
		(net "M_I_CPU0_SB_CB<6>")
	)
	(gr_poly
		(pts
			(xy 380.324868 -266.997942) (xy 380.224792 -266.897866) (xy 380.124716 -266.997942) (xy 380.124716 -267.042392)
			(xy 380.324868 -267.042392)
		)
		(stroke
			(width 0)
			(type solid)
		)
		(fill yes)
		(layer "In2.Cu")
		(net "M_I_CPU0_SA_RSP<0>")
	)
	(gr_poly
		(pts
			(xy 380.324868 -266.594082) (xy 380.324868 -266.549632) (xy 380.124716 -266.549632) (xy 380.124716 -266.594082)
			(xy 380.224792 -266.694158)
		)
		(stroke
			(width 0)
			(type solid)
		)
		(fill yes)
		(layer "In2.Cu")
		(net "M_I_CPU0_SB_CS_N<1>")
	)
	(gr_poly
		(pts
			(xy 380.324868 -265.37793) (xy 380.224792 -265.277854) (xy 380.124716 -265.37793) (xy 380.124716 -265.42238)
			(xy 380.324868 -265.42238)
		)
		(stroke
			(width 0)
			(type solid)
		)
		(fill yes)
		(layer "In2.Cu")
		(net "M_I_CPU0_SB_PAR")
	)
	(gr_poly
		(pts
			(xy 380.324868 -263.757918) (xy 380.224792 -263.657842) (xy 380.124716 -263.757918) (xy 380.124716 -263.802368)
			(xy 380.324868 -263.802368)
		)
		(stroke
			(width 0)
			(type solid)
		)
		(fill yes)
		(layer "In2.Cu")
		(net "M_I_CPU0_SB_CA<4>")
	)
	(gr_poly
		(pts
			(xy 380.324868 -263.354058) (xy 380.324868 -263.309608) (xy 380.124716 -263.309608) (xy 380.124716 -263.354058)
			(xy 380.224792 -263.454134)
		)
		(stroke
			(width 0)
			(type solid)
		)
		(fill yes)
		(layer "In2.Cu")
		(net "M_I_CPU0_SB_CA<3>")
	)
	(gr_poly
		(pts
			(xy 380.324868 -262.137906) (xy 380.224792 -262.03783) (xy 380.124716 -262.137906) (xy 380.124716 -262.182356)
			(xy 380.324868 -262.182356)
		)
		(stroke
			(width 0)
			(type solid)
		)
		(fill yes)
		(layer "In2.Cu")
		(net "M_I_CPU0_SB_CA<0>")
	)
	(gr_poly
		(pts
			(xy 380.494794 -256.432558) (xy 380.494794 -256.384806) (xy 380.294642 -256.384806) (xy 380.294642 -256.432558)
			(xy 380.394718 -256.53238)
		)
		(stroke
			(width 0)
			(type solid)
		)
		(fill yes)
		(layer "In2.Cu")
		(net "M_I_CPU0_CLK_DN<0>")
	)
	(gr_poly
		(pts
			(xy 380.494794 -255.216152) (xy 380.394718 -255.116076) (xy 380.294642 -255.216152) (xy 380.294642 -255.260602)
			(xy 380.494794 -255.260602)
		)
		(stroke
			(width 0)
			(type solid)
		)
		(fill yes)
		(layer "In2.Cu")
		(net "M_I_CPU0_SA_CA<6>")
	)
	(gr_poly
		(pts
			(xy 380.494794 -254.812292) (xy 380.494794 -254.767842) (xy 380.294642 -254.767842) (xy 380.294642 -254.812292)
			(xy 380.394718 -254.912368)
		)
		(stroke
			(width 0)
			(type solid)
		)
		(fill yes)
		(layer "In2.Cu")
		(net "M_I_CPU0_SA_CA<5>")
	)
	(gr_poly
		(pts
			(xy 380.494794 -253.59614) (xy 380.394718 -253.496064) (xy 380.294642 -253.59614) (xy 380.294642 -253.64059)
			(xy 380.494794 -253.64059)
		)
		(stroke
			(width 0)
			(type solid)
		)
		(fill yes)
		(layer "In2.Cu")
		(net "M_I_CPU0_SA_CA<2>")
	)
	(gr_poly
		(pts
			(xy 380.494794 -253.19228) (xy 380.494794 -253.14783) (xy 380.294642 -253.14783) (xy 380.294642 -253.19228)
			(xy 380.394718 -253.292356)
		)
		(stroke
			(width 0)
			(type solid)
		)
		(fill yes)
		(layer "In2.Cu")
		(net "M_I_CPU0_SA_CA<1>")
	)
	(gr_poly
		(pts
			(xy 380.494794 -251.976128) (xy 380.394718 -251.876052) (xy 380.294642 -251.976128) (xy 380.294642 -252.020578)
			(xy 380.494794 -252.020578)
		)
		(stroke
			(width 0)
			(type solid)
		)
		(fill yes)
		(layer "In2.Cu")
		(net "M_I_CPU0_SA_CS_N<1>")
	)
	(gr_poly
		(pts
			(xy 380.494794 -250.356116) (xy 380.394718 -250.25604) (xy 380.294642 -250.356116) (xy 380.294642 -250.400566)
			(xy 380.494794 -250.400566)
		)
		(stroke
			(width 0)
			(type solid)
		)
		(fill yes)
		(layer "In2.Cu")
		(net "M_I_CPU0_ALERT_R_N")
	)
	(gr_poly
		(pts
			(xy 380.494794 -248.736104) (xy 380.394718 -248.636028) (xy 380.294642 -248.736104) (xy 380.294642 -248.780554)
			(xy 380.494794 -248.780554)
		)
		(stroke
			(width 0)
			(type solid)
		)
		(fill yes)
		(layer "In2.Cu")
		(net "M_I_CPU0_SA_CB<5>")
	)
	(gr_poly
		(pts
			(xy 380.494794 -248.332244) (xy 380.494794 -248.287794) (xy 380.294642 -248.287794) (xy 380.294642 -248.332244)
			(xy 380.394718 -248.43232)
		)
		(stroke
			(width 0)
			(type solid)
		)
		(fill yes)
		(layer "In2.Cu")
		(net "M_I_CPU0_SA_CB<6>")
	)
	(gr_poly
		(pts
			(xy 380.494794 -247.115838) (xy 380.394718 -247.016016) (xy 380.294642 -247.115838) (xy 380.294642 -247.16359)
			(xy 380.494794 -247.16359)
		)
		(stroke
			(width 0)
			(type solid)
		)
		(fill yes)
		(layer "In2.Cu")
		(net "M_I_CPU0_SA_DQS_DN<9>")
	)
	(gr_poly
		(pts
			(xy 380.494794 -246.712486) (xy 380.494794 -246.664734) (xy 380.294642 -246.664734) (xy 380.294642 -246.712486)
			(xy 380.394718 -246.812308)
		)
		(stroke
			(width 0)
			(type solid)
		)
		(fill yes)
		(layer "In2.Cu")
		(net "M_I_CPU0_SA_DQS_DN<4>")
	)
	(gr_poly
		(pts
			(xy 380.494794 -245.49608) (xy 380.394718 -245.396004) (xy 380.294642 -245.49608) (xy 380.294642 -245.54053)
			(xy 380.494794 -245.54053)
		)
		(stroke
			(width 0)
			(type solid)
		)
		(fill yes)
		(layer "In2.Cu")
		(net "M_I_CPU0_SA_CB<1>")
	)
	(gr_poly
		(pts
			(xy 380.494794 -245.09222) (xy 380.494794 -245.04777) (xy 380.294642 -245.04777) (xy 380.294642 -245.09222)
			(xy 380.394718 -245.192296)
		)
		(stroke
			(width 0)
			(type solid)
		)
		(fill yes)
		(layer "In2.Cu")
		(net "M_I_CPU0_SA_CB<2>")
	)
	(gr_poly
		(pts
			(xy 380.494794 -243.876068) (xy 380.394718 -243.775992) (xy 380.294642 -243.876068) (xy 380.294642 -243.920518)
			(xy 380.494794 -243.920518)
		)
		(stroke
			(width 0)
			(type solid)
		)
		(fill yes)
		(layer "In2.Cu")
		(net "M_I_CPU0_SA_DQ<29>")
	)
	(gr_poly
		(pts
			(xy 380.494794 -243.472208) (xy 380.494794 -243.427758) (xy 380.294642 -243.427758) (xy 380.294642 -243.472208)
			(xy 380.394718 -243.572284)
		)
		(stroke
			(width 0)
			(type solid)
		)
		(fill yes)
		(layer "In2.Cu")
		(net "M_I_CPU0_SA_DQ<30>")
	)
	(gr_poly
		(pts
			(xy 380.494794 -242.255802) (xy 380.394718 -242.15598) (xy 380.294642 -242.255802) (xy 380.294642 -242.303554)
			(xy 380.494794 -242.303554)
		)
		(stroke
			(width 0)
			(type solid)
		)
		(fill yes)
		(layer "In2.Cu")
		(net "M_I_CPU0_SA_DQS_DN<8>")
	)
	(gr_poly
		(pts
			(xy 380.494794 -241.85245) (xy 380.494794 -241.804698) (xy 380.294642 -241.804698) (xy 380.294642 -241.85245)
			(xy 380.394718 -241.952272)
		)
		(stroke
			(width 0)
			(type solid)
		)
		(fill yes)
		(layer "In2.Cu")
		(net "M_I_CPU0_SA_DQS_DN<3>")
	)
	(gr_poly
		(pts
			(xy 380.494794 -240.636044) (xy 380.394718 -240.535968) (xy 380.294642 -240.636044) (xy 380.294642 -240.680494)
			(xy 380.494794 -240.680494)
		)
		(stroke
			(width 0)
			(type solid)
		)
		(fill yes)
		(layer "In2.Cu")
		(net "M_I_CPU0_SA_DQ<25>")
	)
	(gr_poly
		(pts
			(xy 380.494794 -240.232184) (xy 380.494794 -240.187734) (xy 380.294642 -240.187734) (xy 380.294642 -240.232184)
			(xy 380.394718 -240.33226)
		)
		(stroke
			(width 0)
			(type solid)
		)
		(fill yes)
		(layer "In2.Cu")
		(net "M_I_CPU0_SA_DQ<26>")
	)
	(gr_poly
		(pts
			(xy 380.494794 -239.016032) (xy 380.394718 -238.915956) (xy 380.294642 -239.016032) (xy 380.294642 -239.060482)
			(xy 380.494794 -239.060482)
		)
		(stroke
			(width 0)
			(type solid)
		)
		(fill yes)
		(layer "In2.Cu")
		(net "M_I_CPU0_SA_DQ<21>")
	)
	(gr_poly
		(pts
			(xy 380.494794 -238.612172) (xy 380.494794 -238.567722) (xy 380.294642 -238.567722) (xy 380.294642 -238.612172)
			(xy 380.394718 -238.712248)
		)
		(stroke
			(width 0)
			(type solid)
		)
		(fill yes)
		(layer "In2.Cu")
		(net "M_I_CPU0_SA_DQ<22>")
	)
	(gr_poly
		(pts
			(xy 380.494794 -237.395766) (xy 380.394718 -237.295944) (xy 380.294642 -237.395766) (xy 380.294642 -237.443518)
			(xy 380.494794 -237.443518)
		)
		(stroke
			(width 0)
			(type solid)
		)
		(fill yes)
		(layer "In2.Cu")
		(net "M_I_CPU0_SA_DQS_DN<7>")
	)
	(gr_poly
		(pts
			(xy 380.494794 -236.992414) (xy 380.494794 -236.944662) (xy 380.294642 -236.944662) (xy 380.294642 -236.992414)
			(xy 380.394718 -237.092236)
		)
		(stroke
			(width 0)
			(type solid)
		)
		(fill yes)
		(layer "In2.Cu")
		(net "M_I_CPU0_SA_DQS_DN<2>")
	)
	(gr_poly
		(pts
			(xy 380.494794 -235.776008) (xy 380.394718 -235.675932) (xy 380.294642 -235.776008) (xy 380.294642 -235.820458)
			(xy 380.494794 -235.820458)
		)
		(stroke
			(width 0)
			(type solid)
		)
		(fill yes)
		(layer "In2.Cu")
		(net "M_I_CPU0_SA_DQ<17>")
	)
	(gr_poly
		(pts
			(xy 380.494794 -235.372148) (xy 380.494794 -235.327698) (xy 380.294642 -235.327698) (xy 380.294642 -235.372148)
			(xy 380.394718 -235.472224)
		)
		(stroke
			(width 0)
			(type solid)
		)
		(fill yes)
		(layer "In2.Cu")
		(net "M_I_CPU0_SA_DQ<18>")
	)
	(gr_poly
		(pts
			(xy 380.494794 -234.155996) (xy 380.394718 -234.05592) (xy 380.294642 -234.155996) (xy 380.294642 -234.200446)
			(xy 380.494794 -234.200446)
		)
		(stroke
			(width 0)
			(type solid)
		)
		(fill yes)
		(layer "In2.Cu")
		(net "M_I_CPU0_SA_DQ<13>")
	)
	(gr_poly
		(pts
			(xy 380.494794 -233.752136) (xy 380.494794 -233.707686) (xy 380.294642 -233.707686) (xy 380.294642 -233.752136)
			(xy 380.394718 -233.852212)
		)
		(stroke
			(width 0)
			(type solid)
		)
		(fill yes)
		(layer "In2.Cu")
		(net "M_I_CPU0_SA_DQ<14>")
	)
	(gr_poly
		(pts
			(xy 380.494794 -232.53573) (xy 380.394718 -232.435908) (xy 380.294642 -232.53573) (xy 380.294642 -232.583482)
			(xy 380.494794 -232.583482)
		)
		(stroke
			(width 0)
			(type solid)
		)
		(fill yes)
		(layer "In2.Cu")
		(net "M_I_CPU0_SA_DQS_DN<6>")
	)
	(gr_poly
		(pts
			(xy 380.494794 -232.132378) (xy 380.494794 -232.084626) (xy 380.294642 -232.084626) (xy 380.294642 -232.132378)
			(xy 380.394718 -232.2322)
		)
		(stroke
			(width 0)
			(type solid)
		)
		(fill yes)
		(layer "In2.Cu")
		(net "M_I_CPU0_SA_DQS_DN<1>")
	)
	(gr_poly
		(pts
			(xy 380.494794 -230.915972) (xy 380.394718 -230.815896) (xy 380.294642 -230.915972) (xy 380.294642 -230.960422)
			(xy 380.494794 -230.960422)
		)
		(stroke
			(width 0)
			(type solid)
		)
		(fill yes)
		(layer "In2.Cu")
		(net "M_I_CPU0_SA_DQ<9>")
	)
	(gr_poly
		(pts
			(xy 380.494794 -230.512366) (xy 380.494794 -230.467916) (xy 380.294642 -230.467916) (xy 380.294642 -230.512366)
			(xy 380.394718 -230.612188)
		)
		(stroke
			(width 0)
			(type solid)
		)
		(fill yes)
		(layer "In2.Cu")
		(net "M_I_CPU0_SA_DQ<10>")
	)
	(gr_poly
		(pts
			(xy 380.494794 -229.29596) (xy 380.394718 -229.195884) (xy 380.294642 -229.29596) (xy 380.294642 -229.34041)
			(xy 380.494794 -229.34041)
		)
		(stroke
			(width 0)
			(type solid)
		)
		(fill yes)
		(layer "In2.Cu")
		(net "M_I_CPU0_SA_DQ<5>")
	)
	(gr_poly
		(pts
			(xy 380.494794 -228.892354) (xy 380.494794 -228.847904) (xy 380.294642 -228.847904) (xy 380.294642 -228.892354)
			(xy 380.394718 -228.99243)
		)
		(stroke
			(width 0)
			(type solid)
		)
		(fill yes)
		(layer "In2.Cu")
		(net "M_I_CPU0_SA_DQ<6>")
	)
	(gr_poly
		(pts
			(xy 380.494794 -227.675948) (xy 380.394718 -227.576126) (xy 380.294642 -227.675948) (xy 380.294642 -227.7237)
			(xy 380.494794 -227.7237)
		)
		(stroke
			(width 0)
			(type solid)
		)
		(fill yes)
		(layer "In2.Cu")
		(net "M_I_CPU0_SA_DQS_DN<5>")
	)
	(gr_poly
		(pts
			(xy 380.494794 -227.272596) (xy 380.494794 -227.224844) (xy 380.294642 -227.224844) (xy 380.294642 -227.272596)
			(xy 380.394718 -227.372418)
		)
		(stroke
			(width 0)
			(type solid)
		)
		(fill yes)
		(layer "In2.Cu")
		(net "M_I_CPU0_SA_DQS_DN<0>")
	)
	(gr_poly
		(pts
			(xy 380.494794 -226.05619) (xy 380.394718 -225.956114) (xy 380.294642 -226.05619) (xy 380.294642 -226.10064)
			(xy 380.494794 -226.10064)
		)
		(stroke
			(width 0)
			(type solid)
		)
		(fill yes)
		(layer "In2.Cu")
		(net "M_I_CPU0_SA_DQ<1>")
	)
	(gr_poly
		(pts
			(xy 380.494794 -225.65233) (xy 380.494794 -225.60788) (xy 380.294642 -225.60788) (xy 380.294642 -225.65233)
			(xy 380.394718 -225.752406)
		)
		(stroke
			(width 0)
			(type solid)
		)
		(fill yes)
		(layer "In2.Cu")
		(net "M_I_CPU0_SA_DQ<2>")
	)
	(gr_poly
		(pts
			(xy 380.794768 -262.544052) (xy 380.794768 -262.499602) (xy 380.594616 -262.499602) (xy 380.594616 -262.544052)
			(xy 380.694692 -262.644128)
		)
		(stroke
			(width 0)
			(type solid)
		)
		(fill yes)
		(layer "In2.Cu")
		(net "M_I_CPU0_SB_CA<1>")
	)
	(gr_poly
		(pts
			(xy 380.795022 -293.324026) (xy 380.795022 -293.279576) (xy 380.59487 -293.279576) (xy 380.59487 -293.324026)
			(xy 380.694946 -293.424102)
		)
		(stroke
			(width 0)
			(type solid)
		)
		(fill yes)
		(layer "In2.Cu")
		(net "M_I_CPU0_SB_DQ<31>")
	)
	(gr_poly
		(pts
			(xy 380.795022 -292.107874) (xy 380.694946 -292.007798) (xy 380.59487 -292.107874) (xy 380.59487 -292.152324)
			(xy 380.795022 -292.152324)
		)
		(stroke
			(width 0)
			(type solid)
		)
		(fill yes)
		(layer "In2.Cu")
		(net "M_I_CPU0_SB_DQ<28>")
	)
	(gr_poly
		(pts
			(xy 380.795022 -291.704268) (xy 380.795022 -291.656516) (xy 380.59487 -291.656516) (xy 380.59487 -291.704268)
			(xy 380.694946 -291.80409)
		)
		(stroke
			(width 0)
			(type solid)
		)
		(fill yes)
		(layer "In2.Cu")
		(net "M_I_CPU0_SB_DQS_DP<8>")
	)
	(gr_poly
		(pts
			(xy 380.795022 -290.487608) (xy 380.694946 -290.387786) (xy 380.59487 -290.487608) (xy 380.59487 -290.53536)
			(xy 380.795022 -290.53536)
		)
		(stroke
			(width 0)
			(type solid)
		)
		(fill yes)
		(layer "In2.Cu")
		(net "M_I_CPU0_SB_DQS_DP<3>")
	)
	(gr_poly
		(pts
			(xy 380.795022 -290.084002) (xy 380.795022 -290.039552) (xy 380.59487 -290.039552) (xy 380.59487 -290.084002)
			(xy 380.694946 -290.184078)
		)
		(stroke
			(width 0)
			(type solid)
		)
		(fill yes)
		(layer "In2.Cu")
		(net "M_I_CPU0_SB_DQ<27>")
	)
	(gr_poly
		(pts
			(xy 380.795022 -288.86785) (xy 380.694946 -288.767774) (xy 380.59487 -288.86785) (xy 380.59487 -288.9123)
			(xy 380.795022 -288.9123)
		)
		(stroke
			(width 0)
			(type solid)
		)
		(fill yes)
		(layer "In2.Cu")
		(net "M_I_CPU0_SB_DQ<24>")
	)
	(gr_poly
		(pts
			(xy 380.795022 -288.464244) (xy 380.795022 -288.419794) (xy 380.59487 -288.419794) (xy 380.59487 -288.464244)
			(xy 380.694946 -288.56432)
		)
		(stroke
			(width 0)
			(type solid)
		)
		(fill yes)
		(layer "In2.Cu")
		(net "M_I_CPU0_SB_DQ<23>")
	)
	(gr_poly
		(pts
			(xy 380.795022 -287.247838) (xy 380.694946 -287.148016) (xy 380.59487 -287.247838) (xy 380.59487 -287.292288)
			(xy 380.795022 -287.292288)
		)
		(stroke
			(width 0)
			(type solid)
		)
		(fill yes)
		(layer "In2.Cu")
		(net "M_I_CPU0_SB_DQ<20>")
	)
	(gr_poly
		(pts
			(xy 380.795022 -286.844232) (xy 380.795022 -286.79648) (xy 380.59487 -286.79648) (xy 380.59487 -286.844232)
			(xy 380.694946 -286.944308)
		)
		(stroke
			(width 0)
			(type solid)
		)
		(fill yes)
		(layer "In2.Cu")
		(net "M_I_CPU0_SB_DQS_DP<7>")
	)
	(gr_poly
		(pts
			(xy 380.795022 -285.627826) (xy 380.694946 -285.528004) (xy 380.59487 -285.627826) (xy 380.59487 -285.675578)
			(xy 380.795022 -285.675578)
		)
		(stroke
			(width 0)
			(type solid)
		)
		(fill yes)
		(layer "In2.Cu")
		(net "M_I_CPU0_SB_DQS_DP<2>")
	)
	(gr_poly
		(pts
			(xy 380.795022 -285.22422) (xy 380.795022 -285.17977) (xy 380.59487 -285.17977) (xy 380.59487 -285.22422)
			(xy 380.694946 -285.324296)
		)
		(stroke
			(width 0)
			(type solid)
		)
		(fill yes)
		(layer "In2.Cu")
		(net "M_I_CPU0_SB_DQ<19>")
	)
	(gr_poly
		(pts
			(xy 380.795022 -284.008068) (xy 380.694946 -283.907992) (xy 380.59487 -284.008068) (xy 380.59487 -284.052518)
			(xy 380.795022 -284.052518)
		)
		(stroke
			(width 0)
			(type solid)
		)
		(fill yes)
		(layer "In2.Cu")
		(net "M_I_CPU0_SB_DQ<16>")
	)
	(gr_poly
		(pts
			(xy 380.795022 -283.604208) (xy 380.795022 -283.559758) (xy 380.59487 -283.559758) (xy 380.59487 -283.604208)
			(xy 380.694946 -283.704284)
		)
		(stroke
			(width 0)
			(type solid)
		)
		(fill yes)
		(layer "In2.Cu")
		(net "M_I_CPU0_SB_DQ<15>")
	)
	(gr_poly
		(pts
			(xy 380.795022 -282.388056) (xy 380.694946 -282.28798) (xy 380.59487 -282.388056) (xy 380.59487 -282.432506)
			(xy 380.795022 -282.432506)
		)
		(stroke
			(width 0)
			(type solid)
		)
		(fill yes)
		(layer "In2.Cu")
		(net "M_I_CPU0_SB_DQ<12>")
	)
	(gr_poly
		(pts
			(xy 380.795022 -281.98445) (xy 380.795022 -281.936698) (xy 380.59487 -281.936698) (xy 380.59487 -281.98445)
			(xy 380.694946 -282.084272)
		)
		(stroke
			(width 0)
			(type solid)
		)
		(fill yes)
		(layer "In2.Cu")
		(net "M_I_CPU0_SB_DQS_DP<6>")
	)
	(gr_poly
		(pts
			(xy 380.795022 -280.76779) (xy 380.694946 -280.667968) (xy 380.59487 -280.76779) (xy 380.59487 -280.815542)
			(xy 380.795022 -280.815542)
		)
		(stroke
			(width 0)
			(type solid)
		)
		(fill yes)
		(layer "In2.Cu")
		(net "M_I_CPU0_SB_DQS_DP<1>")
	)
	(gr_poly
		(pts
			(xy 380.795022 -280.364184) (xy 380.795022 -280.319734) (xy 380.59487 -280.319734) (xy 380.59487 -280.364184)
			(xy 380.694946 -280.46426)
		)
		(stroke
			(width 0)
			(type solid)
		)
		(fill yes)
		(layer "In2.Cu")
		(net "M_I_CPU0_SB_DQ<11>")
	)
	(gr_poly
		(pts
			(xy 380.795022 -279.148032) (xy 380.694946 -279.047956) (xy 380.59487 -279.148032) (xy 380.59487 -279.192482)
			(xy 380.795022 -279.192482)
		)
		(stroke
			(width 0)
			(type solid)
		)
		(fill yes)
		(layer "In2.Cu")
		(net "M_I_CPU0_SB_DQ<8>")
	)
	(gr_poly
		(pts
			(xy 380.795022 -278.744172) (xy 380.795022 -278.699722) (xy 380.59487 -278.699722) (xy 380.59487 -278.744172)
			(xy 380.694946 -278.844248)
		)
		(stroke
			(width 0)
			(type solid)
		)
		(fill yes)
		(layer "In2.Cu")
		(net "M_I_CPU0_SB_DQ<7>")
	)
	(gr_poly
		(pts
			(xy 380.795022 -277.52802) (xy 380.694946 -277.427944) (xy 380.59487 -277.52802) (xy 380.59487 -277.57247)
			(xy 380.795022 -277.57247)
		)
		(stroke
			(width 0)
			(type solid)
		)
		(fill yes)
		(layer "In2.Cu")
		(net "M_I_CPU0_SB_DQ<4>")
	)
	(gr_poly
		(pts
			(xy 380.795022 -277.124414) (xy 380.795022 -277.076662) (xy 380.59487 -277.076662) (xy 380.59487 -277.124414)
			(xy 380.694946 -277.224236)
		)
		(stroke
			(width 0)
			(type solid)
		)
		(fill yes)
		(layer "In2.Cu")
		(net "M_I_CPU0_SB_DQS_DP<5>")
	)
	(gr_poly
		(pts
			(xy 380.795022 -275.907754) (xy 380.694946 -275.807932) (xy 380.59487 -275.907754) (xy 380.59487 -275.955506)
			(xy 380.795022 -275.955506)
		)
		(stroke
			(width 0)
			(type solid)
		)
		(fill yes)
		(layer "In2.Cu")
		(net "M_I_CPU0_SB_DQS_DP<0>")
	)
	(gr_poly
		(pts
			(xy 380.795022 -275.504148) (xy 380.795022 -275.459698) (xy 380.59487 -275.459698) (xy 380.59487 -275.504148)
			(xy 380.694946 -275.604224)
		)
		(stroke
			(width 0)
			(type solid)
		)
		(fill yes)
		(layer "In2.Cu")
		(net "M_I_CPU0_SB_DQ<3>")
	)
	(gr_poly
		(pts
			(xy 380.795022 -274.287996) (xy 380.694946 -274.18792) (xy 380.59487 -274.287996) (xy 380.59487 -274.332446)
			(xy 380.795022 -274.332446)
		)
		(stroke
			(width 0)
			(type solid)
		)
		(fill yes)
		(layer "In2.Cu")
		(net "M_I_CPU0_SB_DQ<0>")
	)
	(gr_poly
		(pts
			(xy 380.795022 -273.884136) (xy 380.795022 -273.839686) (xy 380.59487 -273.839686) (xy 380.59487 -273.884136)
			(xy 380.694946 -273.984212)
		)
		(stroke
			(width 0)
			(type solid)
		)
		(fill yes)
		(layer "In2.Cu")
		(net "M_I_CPU0_SB_CB<3>")
	)
	(gr_poly
		(pts
			(xy 380.795022 -272.667984) (xy 380.694946 -272.567908) (xy 380.59487 -272.667984) (xy 380.59487 -272.712434)
			(xy 380.795022 -272.712434)
		)
		(stroke
			(width 0)
			(type solid)
		)
		(fill yes)
		(layer "In2.Cu")
		(net "M_I_CPU0_SB_CB<0>")
	)
	(gr_poly
		(pts
			(xy 380.795022 -272.264378) (xy 380.795022 -272.216626) (xy 380.59487 -272.216626) (xy 380.59487 -272.264378)
			(xy 380.694946 -272.3642)
		)
		(stroke
			(width 0)
			(type solid)
		)
		(fill yes)
		(layer "In2.Cu")
		(net "M_I_CPU0_SB_DQS_DP<4>")
	)
	(gr_poly
		(pts
			(xy 380.795022 -271.047718) (xy 380.694946 -270.947896) (xy 380.59487 -271.047718) (xy 380.59487 -271.09547)
			(xy 380.795022 -271.09547)
		)
		(stroke
			(width 0)
			(type solid)
		)
		(fill yes)
		(layer "In2.Cu")
		(net "M_I_CPU0_SB_DQS_DP<9>")
	)
	(gr_poly
		(pts
			(xy 380.795022 -270.644112) (xy 380.795022 -270.599662) (xy 380.59487 -270.599662) (xy 380.59487 -270.644112)
			(xy 380.694946 -270.744188)
		)
		(stroke
			(width 0)
			(type solid)
		)
		(fill yes)
		(layer "In2.Cu")
		(net "M_I_CPU0_SB_CB<7>")
	)
	(gr_poly
		(pts
			(xy 380.795022 -269.42796) (xy 380.694946 -269.327884) (xy 380.59487 -269.42796) (xy 380.59487 -269.47241)
			(xy 380.795022 -269.47241)
		)
		(stroke
			(width 0)
			(type solid)
		)
		(fill yes)
		(layer "In2.Cu")
		(net "M_I_CPU0_SB_CB<4>")
	)
	(gr_poly
		(pts
			(xy 380.795022 -267.404088) (xy 380.795022 -267.359638) (xy 380.59487 -267.359638) (xy 380.59487 -267.404088)
			(xy 380.694946 -267.504164)
		)
		(stroke
			(width 0)
			(type solid)
		)
		(fill yes)
		(layer "In2.Cu")
		(net "M_I_CPU0_SB_RSP<0>")
	)
	(gr_poly
		(pts
			(xy 380.795022 -265.784076) (xy 380.795022 -265.739626) (xy 380.59487 -265.739626) (xy 380.59487 -265.784076)
			(xy 380.694946 -265.884152)
		)
		(stroke
			(width 0)
			(type solid)
		)
		(fill yes)
		(layer "In2.Cu")
		(net "M_I_CPU0_SB_CS_N<0>")
	)
	(gr_poly
		(pts
			(xy 380.795022 -264.567924) (xy 380.694946 -264.467848) (xy 380.59487 -264.567924) (xy 380.59487 -264.612374)
			(xy 380.795022 -264.612374)
		)
		(stroke
			(width 0)
			(type solid)
		)
		(fill yes)
		(layer "In2.Cu")
		(net "M_I_CPU0_SB_CA<6>")
	)
	(gr_poly
		(pts
			(xy 380.795022 -264.164064) (xy 380.795022 -264.119614) (xy 380.59487 -264.119614) (xy 380.59487 -264.164064)
			(xy 380.694946 -264.26414)
		)
		(stroke
			(width 0)
			(type solid)
		)
		(fill yes)
		(layer "In2.Cu")
		(net "M_I_CPU0_SB_CA<5>")
	)
	(gr_poly
		(pts
			(xy 380.795022 -262.947912) (xy 380.694946 -262.847836) (xy 380.59487 -262.947912) (xy 380.59487 -262.992362)
			(xy 380.795022 -262.992362)
		)
		(stroke
			(width 0)
			(type solid)
		)
		(fill yes)
		(layer "In2.Cu")
		(net "M_I_CPU0_SB_CA<2>")
	)
	(gr_poly
		(pts
			(xy 380.964948 -256.025904) (xy 380.864872 -255.926082) (xy 380.764796 -256.025904) (xy 380.764796 -256.073656)
			(xy 380.964948 -256.073656)
		)
		(stroke
			(width 0)
			(type solid)
		)
		(fill yes)
		(layer "In2.Cu")
		(net "M_I_CPU0_CLK_DP<0>")
	)
	(gr_poly
		(pts
			(xy 380.964948 -255.622298) (xy 380.964948 -255.577848) (xy 380.764796 -255.577848) (xy 380.764796 -255.622298)
			(xy 380.864872 -255.722374)
		)
		(stroke
			(width 0)
			(type solid)
		)
		(fill yes)
		(layer "In2.Cu")
		(net "M_I_CPU0_SA_PAR")
	)
	(gr_poly
		(pts
			(xy 380.964948 -254.406146) (xy 380.864872 -254.30607) (xy 380.764796 -254.406146) (xy 380.764796 -254.450596)
			(xy 380.964948 -254.450596)
		)
		(stroke
			(width 0)
			(type solid)
		)
		(fill yes)
		(layer "In2.Cu")
		(net "M_I_CPU0_SA_CA<4>")
	)
	(gr_poly
		(pts
			(xy 380.964948 -254.002286) (xy 380.964948 -253.957836) (xy 380.764796 -253.957836) (xy 380.764796 -254.002286)
			(xy 380.864872 -254.102362)
		)
		(stroke
			(width 0)
			(type solid)
		)
		(fill yes)
		(layer "In2.Cu")
		(net "M_I_CPU0_SA_CA<3>")
	)
	(gr_poly
		(pts
			(xy 380.964948 -252.786134) (xy 380.864872 -252.686058) (xy 380.764796 -252.786134) (xy 380.764796 -252.830584)
			(xy 380.964948 -252.830584)
		)
		(stroke
			(width 0)
			(type solid)
		)
		(fill yes)
		(layer "In2.Cu")
		(net "M_I_CPU0_SA_CA<0>")
	)
	(gr_poly
		(pts
			(xy 380.964948 -251.166122) (xy 380.864872 -251.066046) (xy 380.764796 -251.166122) (xy 380.764796 -251.210572)
			(xy 380.964948 -251.210572)
		)
		(stroke
			(width 0)
			(type solid)
		)
		(fill yes)
		(layer "In2.Cu")
		(net "M_I_CPU0_SA_CS_N<0>")
	)
	(gr_poly
		(pts
			(xy 380.964948 -250.762262) (xy 380.964948 -250.717812) (xy 380.764796 -250.717812) (xy 380.764796 -250.762262)
			(xy 380.864872 -250.862338)
		)
		(stroke
			(width 0)
			(type solid)
		)
		(fill yes)
		(layer "In2.Cu")
		(net "M_I_CPU0_RESET_N")
	)
	(gr_poly
		(pts
			(xy 380.964948 -249.14225) (xy 380.964948 -249.0978) (xy 380.764796 -249.0978) (xy 380.764796 -249.14225)
			(xy 380.864872 -249.242326)
		)
		(stroke
			(width 0)
			(type solid)
		)
		(fill yes)
		(layer "In2.Cu")
		(net "M_I_CPU0_SA_CB<7>")
	)
	(gr_poly
		(pts
			(xy 380.964948 -247.926098) (xy 380.864872 -247.826022) (xy 380.764796 -247.926098) (xy 380.764796 -247.970548)
			(xy 380.964948 -247.970548)
		)
		(stroke
			(width 0)
			(type solid)
		)
		(fill yes)
		(layer "In2.Cu")
		(net "M_I_CPU0_SA_CB<4>")
	)
	(gr_poly
		(pts
			(xy 380.964948 -247.522492) (xy 380.964948 -247.47474) (xy 380.764796 -247.47474) (xy 380.764796 -247.522492)
			(xy 380.864872 -247.622314)
		)
		(stroke
			(width 0)
			(type solid)
		)
		(fill yes)
		(layer "In2.Cu")
		(net "M_I_CPU0_SA_DQS_DP<9>")
	)
	(gr_poly
		(pts
			(xy 380.964948 -246.305832) (xy 380.864872 -246.20601) (xy 380.764796 -246.305832) (xy 380.764796 -246.353584)
			(xy 380.964948 -246.353584)
		)
		(stroke
			(width 0)
			(type solid)
		)
		(fill yes)
		(layer "In2.Cu")
		(net "M_I_CPU0_SA_DQS_DP<4>")
	)
	(gr_poly
		(pts
			(xy 380.964948 -245.902226) (xy 380.964948 -245.857776) (xy 380.764796 -245.857776) (xy 380.764796 -245.902226)
			(xy 380.864872 -246.002302)
		)
		(stroke
			(width 0)
			(type solid)
		)
		(fill yes)
		(layer "In2.Cu")
		(net "M_I_CPU0_SA_CB<3>")
	)
	(gr_poly
		(pts
			(xy 380.964948 -244.686074) (xy 380.864872 -244.585998) (xy 380.764796 -244.686074) (xy 380.764796 -244.730524)
			(xy 380.964948 -244.730524)
		)
		(stroke
			(width 0)
			(type solid)
		)
		(fill yes)
		(layer "In2.Cu")
		(net "M_I_CPU0_SA_CB<0>")
	)
	(gr_poly
		(pts
			(xy 380.964948 -244.282214) (xy 380.964948 -244.237764) (xy 380.764796 -244.237764) (xy 380.764796 -244.282214)
			(xy 380.864872 -244.38229)
		)
		(stroke
			(width 0)
			(type solid)
		)
		(fill yes)
		(layer "In2.Cu")
		(net "M_I_CPU0_SA_DQ<31>")
	)
	(gr_poly
		(pts
			(xy 380.964948 -243.066062) (xy 380.864872 -242.965986) (xy 380.764796 -243.066062) (xy 380.764796 -243.110512)
			(xy 380.964948 -243.110512)
		)
		(stroke
			(width 0)
			(type solid)
		)
		(fill yes)
		(layer "In2.Cu")
		(net "M_I_CPU0_SA_DQ<28>")
	)
	(gr_poly
		(pts
			(xy 380.964948 -242.662456) (xy 380.964948 -242.614704) (xy 380.764796 -242.614704) (xy 380.764796 -242.662456)
			(xy 380.864872 -242.762278)
		)
		(stroke
			(width 0)
			(type solid)
		)
		(fill yes)
		(layer "In2.Cu")
		(net "M_I_CPU0_SA_DQS_DP<8>")
	)
	(gr_poly
		(pts
			(xy 380.964948 -241.445796) (xy 380.864872 -241.345974) (xy 380.764796 -241.445796) (xy 380.764796 -241.493548)
			(xy 380.964948 -241.493548)
		)
		(stroke
			(width 0)
			(type solid)
		)
		(fill yes)
		(layer "In2.Cu")
		(net "M_I_CPU0_SA_DQS_DP<3>")
	)
	(gr_poly
		(pts
			(xy 380.964948 -241.04219) (xy 380.964948 -240.99774) (xy 380.764796 -240.99774) (xy 380.764796 -241.04219)
			(xy 380.864872 -241.142266)
		)
		(stroke
			(width 0)
			(type solid)
		)
		(fill yes)
		(layer "In2.Cu")
		(net "M_I_CPU0_SA_DQ<27>")
	)
	(gr_poly
		(pts
			(xy 380.964948 -239.826038) (xy 380.864872 -239.725962) (xy 380.764796 -239.826038) (xy 380.764796 -239.870488)
			(xy 380.964948 -239.870488)
		)
		(stroke
			(width 0)
			(type solid)
		)
		(fill yes)
		(layer "In2.Cu")
		(net "M_I_CPU0_SA_DQ<24>")
	)
	(gr_poly
		(pts
			(xy 380.964948 -239.422178) (xy 380.964948 -239.377728) (xy 380.764796 -239.377728) (xy 380.764796 -239.422178)
			(xy 380.864872 -239.522254)
		)
		(stroke
			(width 0)
			(type solid)
		)
		(fill yes)
		(layer "In2.Cu")
		(net "M_I_CPU0_SA_DQ<23>")
	)
	(gr_poly
		(pts
			(xy 380.964948 -238.206026) (xy 380.864872 -238.10595) (xy 380.764796 -238.206026) (xy 380.764796 -238.250476)
			(xy 380.964948 -238.250476)
		)
		(stroke
			(width 0)
			(type solid)
		)
		(fill yes)
		(layer "In2.Cu")
		(net "M_I_CPU0_SA_DQ<20>")
	)
	(gr_poly
		(pts
			(xy 380.964948 -237.80242) (xy 380.964948 -237.754668) (xy 380.764796 -237.754668) (xy 380.764796 -237.80242)
			(xy 380.864872 -237.902242)
		)
		(stroke
			(width 0)
			(type solid)
		)
		(fill yes)
		(layer "In2.Cu")
		(net "M_I_CPU0_SA_DQS_DP<7>")
	)
	(gr_poly
		(pts
			(xy 380.964948 -236.58576) (xy 380.864872 -236.485938) (xy 380.764796 -236.58576) (xy 380.764796 -236.633512)
			(xy 380.964948 -236.633512)
		)
		(stroke
			(width 0)
			(type solid)
		)
		(fill yes)
		(layer "In2.Cu")
		(net "M_I_CPU0_SA_DQS_DP<2>")
	)
	(gr_poly
		(pts
			(xy 380.964948 -236.182154) (xy 380.964948 -236.137704) (xy 380.764796 -236.137704) (xy 380.764796 -236.182154)
			(xy 380.864872 -236.28223)
		)
		(stroke
			(width 0)
			(type solid)
		)
		(fill yes)
		(layer "In2.Cu")
		(net "M_I_CPU0_SA_DQ<19>")
	)
	(gr_poly
		(pts
			(xy 380.964948 -234.966002) (xy 380.864872 -234.865926) (xy 380.764796 -234.966002) (xy 380.764796 -235.010452)
			(xy 380.964948 -235.010452)
		)
		(stroke
			(width 0)
			(type solid)
		)
		(fill yes)
		(layer "In2.Cu")
		(net "M_I_CPU0_SA_DQ<16>")
	)
	(gr_poly
		(pts
			(xy 380.964948 -234.562142) (xy 380.964948 -234.517692) (xy 380.764796 -234.517692) (xy 380.764796 -234.562142)
			(xy 380.864872 -234.662218)
		)
		(stroke
			(width 0)
			(type solid)
		)
		(fill yes)
		(layer "In2.Cu")
		(net "M_I_CPU0_SA_DQ<15>")
	)
	(gr_poly
		(pts
			(xy 380.964948 -233.34599) (xy 380.864872 -233.245914) (xy 380.764796 -233.34599) (xy 380.764796 -233.39044)
			(xy 380.964948 -233.39044)
		)
		(stroke
			(width 0)
			(type solid)
		)
		(fill yes)
		(layer "In2.Cu")
		(net "M_I_CPU0_SA_DQ<12>")
	)
	(gr_poly
		(pts
			(xy 380.964948 -232.942384) (xy 380.964948 -232.894632) (xy 380.764796 -232.894632) (xy 380.764796 -232.942384)
			(xy 380.864872 -233.042206)
		)
		(stroke
			(width 0)
			(type solid)
		)
		(fill yes)
		(layer "In2.Cu")
		(net "M_I_CPU0_SA_DQS_DP<6>")
	)
	(gr_poly
		(pts
			(xy 380.964948 -231.725724) (xy 380.864872 -231.625902) (xy 380.764796 -231.725724) (xy 380.764796 -231.773476)
			(xy 380.964948 -231.773476)
		)
		(stroke
			(width 0)
			(type solid)
		)
		(fill yes)
		(layer "In2.Cu")
		(net "M_I_CPU0_SA_DQS_DP<1>")
	)
	(gr_poly
		(pts
			(xy 380.964948 -231.322372) (xy 380.964948 -231.277922) (xy 380.764796 -231.277922) (xy 380.764796 -231.322372)
			(xy 380.864872 -231.422448)
		)
		(stroke
			(width 0)
			(type solid)
		)
		(fill yes)
		(layer "In2.Cu")
		(net "M_I_CPU0_SA_DQ<11>")
	)
	(gr_poly
		(pts
			(xy 380.964948 -230.105966) (xy 380.864872 -230.006144) (xy 380.764796 -230.105966) (xy 380.764796 -230.150416)
			(xy 380.964948 -230.150416)
		)
		(stroke
			(width 0)
			(type solid)
		)
		(fill yes)
		(layer "In2.Cu")
		(net "M_I_CPU0_SA_DQ<8>")
	)
	(gr_poly
		(pts
			(xy 380.964948 -229.70236) (xy 380.964948 -229.65791) (xy 380.764796 -229.65791) (xy 380.764796 -229.70236)
			(xy 380.864872 -229.802436)
		)
		(stroke
			(width 0)
			(type solid)
		)
		(fill yes)
		(layer "In2.Cu")
		(net "M_I_CPU0_SA_DQ<7>")
	)
	(gr_poly
		(pts
			(xy 380.964948 -228.486208) (xy 380.864872 -228.386132) (xy 380.764796 -228.486208) (xy 380.764796 -228.530658)
			(xy 380.964948 -228.530658)
		)
		(stroke
			(width 0)
			(type solid)
		)
		(fill yes)
		(layer "In2.Cu")
		(net "M_I_CPU0_SA_DQ<4>")
	)
	(gr_poly
		(pts
			(xy 380.964948 -228.082602) (xy 380.964948 -228.03485) (xy 380.764796 -228.03485) (xy 380.764796 -228.082602)
			(xy 380.864872 -228.182424)
		)
		(stroke
			(width 0)
			(type solid)
		)
		(fill yes)
		(layer "In2.Cu")
		(net "M_I_CPU0_SA_DQS_DP<5>")
	)
	(gr_poly
		(pts
			(xy 380.964948 -226.865942) (xy 380.864872 -226.76612) (xy 380.764796 -226.865942) (xy 380.764796 -226.913694)
			(xy 380.964948 -226.913694)
		)
		(stroke
			(width 0)
			(type solid)
		)
		(fill yes)
		(layer "In2.Cu")
		(net "M_I_CPU0_SA_DQS_DP<0>")
	)
	(gr_poly
		(pts
			(xy 380.964948 -226.462336) (xy 380.964948 -226.417886) (xy 380.764796 -226.417886) (xy 380.764796 -226.462336)
			(xy 380.864872 -226.562412)
		)
		(stroke
			(width 0)
			(type solid)
		)
		(fill yes)
		(layer "In2.Cu")
		(net "M_I_CPU0_SA_DQ<3>")
	)
	(gr_poly
		(pts
			(xy 380.964948 -225.246184) (xy 380.864872 -225.146108) (xy 380.764796 -225.246184) (xy 380.764796 -225.290634)
			(xy 380.964948 -225.290634)
		)
		(stroke
			(width 0)
			(type solid)
		)
		(fill yes)
		(layer "In2.Cu")
		(net "M_I_CPU0_SA_DQ<0>")
	)
	(gr_poly
		(pts
			(xy 381.264922 -292.91788) (xy 381.164846 -292.817804) (xy 381.06477 -292.91788) (xy 381.06477 -292.96233)
			(xy 381.264922 -292.96233)
		)
		(stroke
			(width 0)
			(type solid)
		)
		(fill yes)
		(layer "In2.Cu")
		(net "M_I_CPU0_SB_DQ<29>")
	)
	(gr_poly
		(pts
			(xy 381.264922 -292.51402) (xy 381.264922 -292.46957) (xy 381.06477 -292.46957) (xy 381.06477 -292.51402)
			(xy 381.164846 -292.614096)
		)
		(stroke
			(width 0)
			(type solid)
		)
		(fill yes)
		(layer "In2.Cu")
		(net "M_I_CPU0_SB_DQ<30>")
	)
	(gr_poly
		(pts
			(xy 381.264922 -291.297614) (xy 381.164846 -291.197792) (xy 381.06477 -291.297614) (xy 381.06477 -291.345366)
			(xy 381.264922 -291.345366)
		)
		(stroke
			(width 0)
			(type solid)
		)
		(fill yes)
		(layer "In2.Cu")
		(net "M_I_CPU0_SB_DQS_DN<8>")
	)
	(gr_poly
		(pts
			(xy 381.264922 -290.894262) (xy 381.264922 -290.84651) (xy 381.06477 -290.84651) (xy 381.06477 -290.894262)
			(xy 381.164846 -290.994084)
		)
		(stroke
			(width 0)
			(type solid)
		)
		(fill yes)
		(layer "In2.Cu")
		(net "M_I_CPU0_SB_DQS_DN<3>")
	)
	(gr_poly
		(pts
			(xy 381.264922 -289.677856) (xy 381.164846 -289.57778) (xy 381.06477 -289.677856) (xy 381.06477 -289.722306)
			(xy 381.264922 -289.722306)
		)
		(stroke
			(width 0)
			(type solid)
		)
		(fill yes)
		(layer "In2.Cu")
		(net "M_I_CPU0_SB_DQ<25>")
	)
	(gr_poly
		(pts
			(xy 381.264922 -289.273996) (xy 381.264922 -289.229546) (xy 381.06477 -289.229546) (xy 381.06477 -289.273996)
			(xy 381.164846 -289.374072)
		)
		(stroke
			(width 0)
			(type solid)
		)
		(fill yes)
		(layer "In2.Cu")
		(net "M_I_CPU0_SB_DQ<26>")
	)
	(gr_poly
		(pts
			(xy 381.264922 -288.057844) (xy 381.164846 -287.957768) (xy 381.06477 -288.057844) (xy 381.06477 -288.102294)
			(xy 381.264922 -288.102294)
		)
		(stroke
			(width 0)
			(type solid)
		)
		(fill yes)
		(layer "In2.Cu")
		(net "M_I_CPU0_SB_DQ<21>")
	)
	(gr_poly
		(pts
			(xy 381.264922 -287.654238) (xy 381.264922 -287.609788) (xy 381.06477 -287.609788) (xy 381.06477 -287.654238)
			(xy 381.164846 -287.75406)
		)
		(stroke
			(width 0)
			(type solid)
		)
		(fill yes)
		(layer "In2.Cu")
		(net "M_I_CPU0_SB_DQ<22>")
	)
	(gr_poly
		(pts
			(xy 381.264922 -286.437832) (xy 381.164846 -286.337756) (xy 381.06477 -286.437832) (xy 381.06477 -286.485584)
			(xy 381.264922 -286.485584)
		)
		(stroke
			(width 0)
			(type solid)
		)
		(fill yes)
		(layer "In2.Cu")
		(net "M_I_CPU0_SB_DQS_DN<7>")
	)
	(gr_poly
		(pts
			(xy 381.264922 -286.03448) (xy 381.264922 -285.986728) (xy 381.06477 -285.986728) (xy 381.06477 -286.03448)
			(xy 381.164846 -286.134302)
		)
		(stroke
			(width 0)
			(type solid)
		)
		(fill yes)
		(layer "In2.Cu")
		(net "M_I_CPU0_SB_DQS_DN<2>")
	)
	(gr_poly
		(pts
			(xy 381.264922 -284.818074) (xy 381.164846 -284.717998) (xy 381.06477 -284.818074) (xy 381.06477 -284.862524)
			(xy 381.264922 -284.862524)
		)
		(stroke
			(width 0)
			(type solid)
		)
		(fill yes)
		(layer "In2.Cu")
		(net "M_I_CPU0_SB_DQ<17>")
	)
	(gr_poly
		(pts
			(xy 381.264922 -284.414214) (xy 381.264922 -284.369764) (xy 381.06477 -284.369764) (xy 381.06477 -284.414214)
			(xy 381.164846 -284.51429)
		)
		(stroke
			(width 0)
			(type solid)
		)
		(fill yes)
		(layer "In2.Cu")
		(net "M_I_CPU0_SB_DQ<18>")
	)
	(gr_poly
		(pts
			(xy 381.264922 -283.198062) (xy 381.164846 -283.097986) (xy 381.06477 -283.198062) (xy 381.06477 -283.242512)
			(xy 381.264922 -283.242512)
		)
		(stroke
			(width 0)
			(type solid)
		)
		(fill yes)
		(layer "In2.Cu")
		(net "M_I_CPU0_SB_DQ<13>")
	)
	(gr_poly
		(pts
			(xy 381.264922 -282.794202) (xy 381.264922 -282.749752) (xy 381.06477 -282.749752) (xy 381.06477 -282.794202)
			(xy 381.164846 -282.894278)
		)
		(stroke
			(width 0)
			(type solid)
		)
		(fill yes)
		(layer "In2.Cu")
		(net "M_I_CPU0_SB_DQ<14>")
	)
	(gr_poly
		(pts
			(xy 381.264922 -281.577796) (xy 381.164846 -281.477974) (xy 381.06477 -281.577796) (xy 381.06477 -281.625548)
			(xy 381.264922 -281.625548)
		)
		(stroke
			(width 0)
			(type solid)
		)
		(fill yes)
		(layer "In2.Cu")
		(net "M_I_CPU0_SB_DQS_DN<6>")
	)
	(gr_poly
		(pts
			(xy 381.264922 -281.174444) (xy 381.264922 -281.126692) (xy 381.06477 -281.126692) (xy 381.06477 -281.174444)
			(xy 381.164846 -281.274266)
		)
		(stroke
			(width 0)
			(type solid)
		)
		(fill yes)
		(layer "In2.Cu")
		(net "M_I_CPU0_SB_DQS_DN<1>")
	)
	(gr_poly
		(pts
			(xy 381.264922 -279.958038) (xy 381.164846 -279.857962) (xy 381.06477 -279.958038) (xy 381.06477 -280.002488)
			(xy 381.264922 -280.002488)
		)
		(stroke
			(width 0)
			(type solid)
		)
		(fill yes)
		(layer "In2.Cu")
		(net "M_I_CPU0_SB_DQ<9>")
	)
	(gr_poly
		(pts
			(xy 381.264922 -279.554178) (xy 381.264922 -279.509728) (xy 381.06477 -279.509728) (xy 381.06477 -279.554178)
			(xy 381.164846 -279.654254)
		)
		(stroke
			(width 0)
			(type solid)
		)
		(fill yes)
		(layer "In2.Cu")
		(net "M_I_CPU0_SB_DQ<10>")
	)
	(gr_poly
		(pts
			(xy 381.264922 -278.338026) (xy 381.164846 -278.23795) (xy 381.06477 -278.338026) (xy 381.06477 -278.382476)
			(xy 381.264922 -278.382476)
		)
		(stroke
			(width 0)
			(type solid)
		)
		(fill yes)
		(layer "In2.Cu")
		(net "M_I_CPU0_SB_DQ<5>")
	)
	(gr_poly
		(pts
			(xy 381.264922 -277.934166) (xy 381.264922 -277.889716) (xy 381.06477 -277.889716) (xy 381.06477 -277.934166)
			(xy 381.164846 -278.034242)
		)
		(stroke
			(width 0)
			(type solid)
		)
		(fill yes)
		(layer "In2.Cu")
		(net "M_I_CPU0_SB_DQ<6>")
	)
	(gr_poly
		(pts
			(xy 381.264922 -276.71776) (xy 381.164846 -276.617938) (xy 381.06477 -276.71776) (xy 381.06477 -276.765512)
			(xy 381.264922 -276.765512)
		)
		(stroke
			(width 0)
			(type solid)
		)
		(fill yes)
		(layer "In2.Cu")
		(net "M_I_CPU0_SB_DQS_DN<5>")
	)
	(gr_poly
		(pts
			(xy 381.264922 -276.314408) (xy 381.264922 -276.266656) (xy 381.06477 -276.266656) (xy 381.06477 -276.314408)
			(xy 381.164846 -276.41423)
		)
		(stroke
			(width 0)
			(type solid)
		)
		(fill yes)
		(layer "In2.Cu")
		(net "M_I_CPU0_SB_DQS_DN<0>")
	)
	(gr_poly
		(pts
			(xy 381.264922 -275.098002) (xy 381.164846 -274.997926) (xy 381.06477 -275.098002) (xy 381.06477 -275.142452)
			(xy 381.264922 -275.142452)
		)
		(stroke
			(width 0)
			(type solid)
		)
		(fill yes)
		(layer "In2.Cu")
		(net "M_I_CPU0_SB_DQ<1>")
	)
	(gr_poly
		(pts
			(xy 381.264922 -274.694142) (xy 381.264922 -274.649692) (xy 381.06477 -274.649692) (xy 381.06477 -274.694142)
			(xy 381.164846 -274.794218)
		)
		(stroke
			(width 0)
			(type solid)
		)
		(fill yes)
		(layer "In2.Cu")
		(net "M_I_CPU0_SB_DQ<2>")
	)
	(gr_poly
		(pts
			(xy 381.264922 -273.47799) (xy 381.164846 -273.377914) (xy 381.06477 -273.47799) (xy 381.06477 -273.52244)
			(xy 381.264922 -273.52244)
		)
		(stroke
			(width 0)
			(type solid)
		)
		(fill yes)
		(layer "In2.Cu")
		(net "M_I_CPU0_SB_CB<1>")
	)
	(gr_poly
		(pts
			(xy 381.264922 -273.07413) (xy 381.264922 -273.02968) (xy 381.06477 -273.02968) (xy 381.06477 -273.07413)
			(xy 381.164846 -273.174206)
		)
		(stroke
			(width 0)
			(type solid)
		)
		(fill yes)
		(layer "In2.Cu")
		(net "M_I_CPU0_SB_CB<2>")
	)
	(gr_poly
		(pts
			(xy 381.264922 -271.857724) (xy 381.164846 -271.757902) (xy 381.06477 -271.857724) (xy 381.06477 -271.905476)
			(xy 381.264922 -271.905476)
		)
		(stroke
			(width 0)
			(type solid)
		)
		(fill yes)
		(layer "In2.Cu")
		(net "M_I_CPU0_SB_DQS_DN<4>")
	)
	(gr_poly
		(pts
			(xy 381.264922 -271.454372) (xy 381.264922 -271.40662) (xy 381.06477 -271.40662) (xy 381.06477 -271.454372)
			(xy 381.164846 -271.554194)
		)
		(stroke
			(width 0)
			(type solid)
		)
		(fill yes)
		(layer "In2.Cu")
		(net "M_I_CPU0_SB_DQS_DN<9>")
	)
	(gr_poly
		(pts
			(xy 381.264922 -270.237966) (xy 381.164846 -270.13789) (xy 381.06477 -270.237966) (xy 381.06477 -270.282416)
			(xy 381.264922 -270.282416)
		)
		(stroke
			(width 0)
			(type solid)
		)
		(fill yes)
		(layer "In2.Cu")
		(net "M_I_CPU0_SB_CB<5>")
	)
	(gr_poly
		(pts
			(xy 381.264922 -269.834106) (xy 381.264922 -269.789656) (xy 381.06477 -269.789656) (xy 381.06477 -269.834106)
			(xy 381.164846 -269.934182)
		)
		(stroke
			(width 0)
			(type solid)
		)
		(fill yes)
		(layer "In2.Cu")
		(net "M_I_CPU0_SB_CB<6>")
	)
	(gr_poly
		(pts
			(xy 381.264922 -266.997942) (xy 381.164846 -266.897866) (xy 381.06477 -266.997942) (xy 381.06477 -267.042392)
			(xy 381.264922 -267.042392)
		)
		(stroke
			(width 0)
			(type solid)
		)
		(fill yes)
		(layer "In2.Cu")
		(net "M_I_CPU0_SA_RSP<0>")
	)
	(gr_poly
		(pts
			(xy 381.264922 -266.594082) (xy 381.264922 -266.549632) (xy 381.06477 -266.549632) (xy 381.06477 -266.594082)
			(xy 381.164846 -266.694158)
		)
		(stroke
			(width 0)
			(type solid)
		)
		(fill yes)
		(layer "In2.Cu")
		(net "M_I_CPU0_SB_CS_N<1>")
	)
	(gr_poly
		(pts
			(xy 381.264922 -265.37793) (xy 381.164846 -265.277854) (xy 381.06477 -265.37793) (xy 381.06477 -265.42238)
			(xy 381.264922 -265.42238)
		)
		(stroke
			(width 0)
			(type solid)
		)
		(fill yes)
		(layer "In2.Cu")
		(net "M_I_CPU0_SB_PAR")
	)
	(gr_poly
		(pts
			(xy 381.264922 -263.757918) (xy 381.164846 -263.657842) (xy 381.06477 -263.757918) (xy 381.06477 -263.802368)
			(xy 381.264922 -263.802368)
		)
		(stroke
			(width 0)
			(type solid)
		)
		(fill yes)
		(layer "In2.Cu")
		(net "M_I_CPU0_SB_CA<4>")
	)
	(gr_poly
		(pts
			(xy 381.264922 -263.354058) (xy 381.264922 -263.309608) (xy 381.06477 -263.309608) (xy 381.06477 -263.354058)
			(xy 381.164846 -263.454134)
		)
		(stroke
			(width 0)
			(type solid)
		)
		(fill yes)
		(layer "In2.Cu")
		(net "M_I_CPU0_SB_CA<3>")
	)
	(gr_poly
		(pts
			(xy 381.264922 -262.137906) (xy 381.164846 -262.03783) (xy 381.06477 -262.137906) (xy 381.06477 -262.182356)
			(xy 381.264922 -262.182356)
		)
		(stroke
			(width 0)
			(type solid)
		)
		(fill yes)
		(layer "In2.Cu")
		(net "M_I_CPU0_SB_CA<0>")
	)
	(gr_poly
		(pts
			(xy 381.434848 -256.432558) (xy 381.434848 -256.384806) (xy 381.234696 -256.384806) (xy 381.234696 -256.432558)
			(xy 381.334772 -256.53238)
		)
		(stroke
			(width 0)
			(type solid)
		)
		(fill yes)
		(layer "In2.Cu")
		(net "M_I_CPU0_CLK_DN<0>")
	)
	(gr_poly
		(pts
			(xy 381.434848 -255.216152) (xy 381.334772 -255.116076) (xy 381.234696 -255.216152) (xy 381.234696 -255.260602)
			(xy 381.434848 -255.260602)
		)
		(stroke
			(width 0)
			(type solid)
		)
		(fill yes)
		(layer "In2.Cu")
		(net "M_I_CPU0_SA_CA<6>")
	)
	(gr_poly
		(pts
			(xy 381.434848 -254.812292) (xy 381.434848 -254.767842) (xy 381.234696 -254.767842) (xy 381.234696 -254.812292)
			(xy 381.334772 -254.912368)
		)
		(stroke
			(width 0)
			(type solid)
		)
		(fill yes)
		(layer "In2.Cu")
		(net "M_I_CPU0_SA_CA<5>")
	)
	(gr_poly
		(pts
			(xy 381.434848 -253.59614) (xy 381.334772 -253.496064) (xy 381.234696 -253.59614) (xy 381.234696 -253.64059)
			(xy 381.434848 -253.64059)
		)
		(stroke
			(width 0)
			(type solid)
		)
		(fill yes)
		(layer "In2.Cu")
		(net "M_I_CPU0_SA_CA<2>")
	)
	(gr_poly
		(pts
			(xy 381.434848 -253.19228) (xy 381.434848 -253.14783) (xy 381.234696 -253.14783) (xy 381.234696 -253.19228)
			(xy 381.334772 -253.292356)
		)
		(stroke
			(width 0)
			(type solid)
		)
		(fill yes)
		(layer "In2.Cu")
		(net "M_I_CPU0_SA_CA<1>")
	)
	(gr_poly
		(pts
			(xy 381.434848 -251.976128) (xy 381.334772 -251.876052) (xy 381.234696 -251.976128) (xy 381.234696 -252.020578)
			(xy 381.434848 -252.020578)
		)
		(stroke
			(width 0)
			(type solid)
		)
		(fill yes)
		(layer "In2.Cu")
		(net "M_I_CPU0_SA_CS_N<1>")
	)
	(gr_poly
		(pts
			(xy 381.434848 -250.356116) (xy 381.334772 -250.25604) (xy 381.234696 -250.356116) (xy 381.234696 -250.400566)
			(xy 381.434848 -250.400566)
		)
		(stroke
			(width 0)
			(type solid)
		)
		(fill yes)
		(layer "In2.Cu")
		(net "M_I_CPU0_ALERT_R_N")
	)
	(gr_poly
		(pts
			(xy 381.434848 -248.736104) (xy 381.334772 -248.636028) (xy 381.234696 -248.736104) (xy 381.234696 -248.780554)
			(xy 381.434848 -248.780554)
		)
		(stroke
			(width 0)
			(type solid)
		)
		(fill yes)
		(layer "In2.Cu")
		(net "M_I_CPU0_SA_CB<5>")
	)
	(gr_poly
		(pts
			(xy 381.434848 -248.332244) (xy 381.434848 -248.287794) (xy 381.234696 -248.287794) (xy 381.234696 -248.332244)
			(xy 381.334772 -248.43232)
		)
		(stroke
			(width 0)
			(type solid)
		)
		(fill yes)
		(layer "In2.Cu")
		(net "M_I_CPU0_SA_CB<6>")
	)
	(gr_poly
		(pts
			(xy 381.434848 -247.115838) (xy 381.334772 -247.016016) (xy 381.234696 -247.115838) (xy 381.234696 -247.16359)
			(xy 381.434848 -247.16359)
		)
		(stroke
			(width 0)
			(type solid)
		)
		(fill yes)
		(layer "In2.Cu")
		(net "M_I_CPU0_SA_DQS_DN<9>")
	)
	(gr_poly
		(pts
			(xy 381.434848 -246.712486) (xy 381.434848 -246.664734) (xy 381.234696 -246.664734) (xy 381.234696 -246.712486)
			(xy 381.334772 -246.812308)
		)
		(stroke
			(width 0)
			(type solid)
		)
		(fill yes)
		(layer "In2.Cu")
		(net "M_I_CPU0_SA_DQS_DN<4>")
	)
	(gr_poly
		(pts
			(xy 381.434848 -245.49608) (xy 381.334772 -245.396004) (xy 381.234696 -245.49608) (xy 381.234696 -245.54053)
			(xy 381.434848 -245.54053)
		)
		(stroke
			(width 0)
			(type solid)
		)
		(fill yes)
		(layer "In2.Cu")
		(net "M_I_CPU0_SA_CB<1>")
	)
	(gr_poly
		(pts
			(xy 381.434848 -245.09222) (xy 381.434848 -245.04777) (xy 381.234696 -245.04777) (xy 381.234696 -245.09222)
			(xy 381.334772 -245.192296)
		)
		(stroke
			(width 0)
			(type solid)
		)
		(fill yes)
		(layer "In2.Cu")
		(net "M_I_CPU0_SA_CB<2>")
	)
	(gr_poly
		(pts
			(xy 381.434848 -243.876068) (xy 381.334772 -243.775992) (xy 381.234696 -243.876068) (xy 381.234696 -243.920518)
			(xy 381.434848 -243.920518)
		)
		(stroke
			(width 0)
			(type solid)
		)
		(fill yes)
		(layer "In2.Cu")
		(net "M_I_CPU0_SA_DQ<29>")
	)
	(gr_poly
		(pts
			(xy 381.434848 -243.472208) (xy 381.434848 -243.427758) (xy 381.234696 -243.427758) (xy 381.234696 -243.472208)
			(xy 381.334772 -243.572284)
		)
		(stroke
			(width 0)
			(type solid)
		)
		(fill yes)
		(layer "In2.Cu")
		(net "M_I_CPU0_SA_DQ<30>")
	)
	(gr_poly
		(pts
			(xy 381.434848 -242.255802) (xy 381.334772 -242.15598) (xy 381.234696 -242.255802) (xy 381.234696 -242.303554)
			(xy 381.434848 -242.303554)
		)
		(stroke
			(width 0)
			(type solid)
		)
		(fill yes)
		(layer "In2.Cu")
		(net "M_I_CPU0_SA_DQS_DN<8>")
	)
	(gr_poly
		(pts
			(xy 381.434848 -241.85245) (xy 381.434848 -241.804698) (xy 381.234696 -241.804698) (xy 381.234696 -241.85245)
			(xy 381.334772 -241.952272)
		)
		(stroke
			(width 0)
			(type solid)
		)
		(fill yes)
		(layer "In2.Cu")
		(net "M_I_CPU0_SA_DQS_DN<3>")
	)
	(gr_poly
		(pts
			(xy 381.434848 -240.636044) (xy 381.334772 -240.535968) (xy 381.234696 -240.636044) (xy 381.234696 -240.680494)
			(xy 381.434848 -240.680494)
		)
		(stroke
			(width 0)
			(type solid)
		)
		(fill yes)
		(layer "In2.Cu")
		(net "M_I_CPU0_SA_DQ<25>")
	)
	(gr_poly
		(pts
			(xy 381.434848 -240.232184) (xy 381.434848 -240.187734) (xy 381.234696 -240.187734) (xy 381.234696 -240.232184)
			(xy 381.334772 -240.33226)
		)
		(stroke
			(width 0)
			(type solid)
		)
		(fill yes)
		(layer "In2.Cu")
		(net "M_I_CPU0_SA_DQ<26>")
	)
	(gr_poly
		(pts
			(xy 381.434848 -239.016032) (xy 381.334772 -238.915956) (xy 381.234696 -239.016032) (xy 381.234696 -239.060482)
			(xy 381.434848 -239.060482)
		)
		(stroke
			(width 0)
			(type solid)
		)
		(fill yes)
		(layer "In2.Cu")
		(net "M_I_CPU0_SA_DQ<21>")
	)
	(gr_poly
		(pts
			(xy 381.434848 -238.612172) (xy 381.434848 -238.567722) (xy 381.234696 -238.567722) (xy 381.234696 -238.612172)
			(xy 381.334772 -238.712248)
		)
		(stroke
			(width 0)
			(type solid)
		)
		(fill yes)
		(layer "In2.Cu")
		(net "M_I_CPU0_SA_DQ<22>")
	)
	(gr_poly
		(pts
			(xy 381.434848 -237.395766) (xy 381.334772 -237.295944) (xy 381.234696 -237.395766) (xy 381.234696 -237.443518)
			(xy 381.434848 -237.443518)
		)
		(stroke
			(width 0)
			(type solid)
		)
		(fill yes)
		(layer "In2.Cu")
		(net "M_I_CPU0_SA_DQS_DN<7>")
	)
	(gr_poly
		(pts
			(xy 381.434848 -236.992414) (xy 381.434848 -236.944662) (xy 381.234696 -236.944662) (xy 381.234696 -236.992414)
			(xy 381.334772 -237.092236)
		)
		(stroke
			(width 0)
			(type solid)
		)
		(fill yes)
		(layer "In2.Cu")
		(net "M_I_CPU0_SA_DQS_DN<2>")
	)
	(gr_poly
		(pts
			(xy 381.434848 -235.776008) (xy 381.334772 -235.675932) (xy 381.234696 -235.776008) (xy 381.234696 -235.820458)
			(xy 381.434848 -235.820458)
		)
		(stroke
			(width 0)
			(type solid)
		)
		(fill yes)
		(layer "In2.Cu")
		(net "M_I_CPU0_SA_DQ<17>")
	)
	(gr_poly
		(pts
			(xy 381.434848 -235.372148) (xy 381.434848 -235.327698) (xy 381.234696 -235.327698) (xy 381.234696 -235.372148)
			(xy 381.334772 -235.472224)
		)
		(stroke
			(width 0)
			(type solid)
		)
		(fill yes)
		(layer "In2.Cu")
		(net "M_I_CPU0_SA_DQ<18>")
	)
	(gr_poly
		(pts
			(xy 381.434848 -234.155996) (xy 381.334772 -234.05592) (xy 381.234696 -234.155996) (xy 381.234696 -234.200446)
			(xy 381.434848 -234.200446)
		)
		(stroke
			(width 0)
			(type solid)
		)
		(fill yes)
		(layer "In2.Cu")
		(net "M_I_CPU0_SA_DQ<13>")
	)
	(gr_poly
		(pts
			(xy 381.434848 -233.752136) (xy 381.434848 -233.707686) (xy 381.234696 -233.707686) (xy 381.234696 -233.752136)
			(xy 381.334772 -233.852212)
		)
		(stroke
			(width 0)
			(type solid)
		)
		(fill yes)
		(layer "In2.Cu")
		(net "M_I_CPU0_SA_DQ<14>")
	)
	(gr_poly
		(pts
			(xy 381.434848 -232.53573) (xy 381.334772 -232.435908) (xy 381.234696 -232.53573) (xy 381.234696 -232.583482)
			(xy 381.434848 -232.583482)
		)
		(stroke
			(width 0)
			(type solid)
		)
		(fill yes)
		(layer "In2.Cu")
		(net "M_I_CPU0_SA_DQS_DN<6>")
	)
	(gr_poly
		(pts
			(xy 381.434848 -232.132378) (xy 381.434848 -232.084626) (xy 381.234696 -232.084626) (xy 381.234696 -232.132378)
			(xy 381.334772 -232.2322)
		)
		(stroke
			(width 0)
			(type solid)
		)
		(fill yes)
		(layer "In2.Cu")
		(net "M_I_CPU0_SA_DQS_DN<1>")
	)
	(gr_poly
		(pts
			(xy 381.434848 -230.915972) (xy 381.334772 -230.815896) (xy 381.234696 -230.915972) (xy 381.234696 -230.960422)
			(xy 381.434848 -230.960422)
		)
		(stroke
			(width 0)
			(type solid)
		)
		(fill yes)
		(layer "In2.Cu")
		(net "M_I_CPU0_SA_DQ<9>")
	)
	(gr_poly
		(pts
			(xy 381.434848 -230.512366) (xy 381.434848 -230.467916) (xy 381.234696 -230.467916) (xy 381.234696 -230.512366)
			(xy 381.334772 -230.612188)
		)
		(stroke
			(width 0)
			(type solid)
		)
		(fill yes)
		(layer "In2.Cu")
		(net "M_I_CPU0_SA_DQ<10>")
	)
	(gr_poly
		(pts
			(xy 381.434848 -229.29596) (xy 381.334772 -229.195884) (xy 381.234696 -229.29596) (xy 381.234696 -229.34041)
			(xy 381.434848 -229.34041)
		)
		(stroke
			(width 0)
			(type solid)
		)
		(fill yes)
		(layer "In2.Cu")
		(net "M_I_CPU0_SA_DQ<5>")
	)
	(gr_poly
		(pts
			(xy 381.434848 -228.892354) (xy 381.434848 -228.847904) (xy 381.234696 -228.847904) (xy 381.234696 -228.892354)
			(xy 381.334772 -228.99243)
		)
		(stroke
			(width 0)
			(type solid)
		)
		(fill yes)
		(layer "In2.Cu")
		(net "M_I_CPU0_SA_DQ<6>")
	)
	(gr_poly
		(pts
			(xy 381.434848 -227.675948) (xy 381.334772 -227.576126) (xy 381.234696 -227.675948) (xy 381.234696 -227.7237)
			(xy 381.434848 -227.7237)
		)
		(stroke
			(width 0)
			(type solid)
		)
		(fill yes)
		(layer "In2.Cu")
		(net "M_I_CPU0_SA_DQS_DN<5>")
	)
	(gr_poly
		(pts
			(xy 381.434848 -227.272596) (xy 381.434848 -227.224844) (xy 381.234696 -227.224844) (xy 381.234696 -227.272596)
			(xy 381.334772 -227.372418)
		)
		(stroke
			(width 0)
			(type solid)
		)
		(fill yes)
		(layer "In2.Cu")
		(net "M_I_CPU0_SA_DQS_DN<0>")
	)
	(gr_poly
		(pts
			(xy 381.434848 -226.05619) (xy 381.334772 -225.956114) (xy 381.234696 -226.05619) (xy 381.234696 -226.10064)
			(xy 381.434848 -226.10064)
		)
		(stroke
			(width 0)
			(type solid)
		)
		(fill yes)
		(layer "In2.Cu")
		(net "M_I_CPU0_SA_DQ<1>")
	)
	(gr_poly
		(pts
			(xy 381.434848 -225.65233) (xy 381.434848 -225.60788) (xy 381.234696 -225.60788) (xy 381.234696 -225.65233)
			(xy 381.334772 -225.752406)
		)
		(stroke
			(width 0)
			(type solid)
		)
		(fill yes)
		(layer "In2.Cu")
		(net "M_I_CPU0_SA_DQ<2>")
	)
	(gr_poly
		(pts
			(xy 381.734822 -293.324026) (xy 381.734822 -293.279576) (xy 381.53467 -293.279576) (xy 381.53467 -293.324026)
			(xy 381.634746 -293.424102)
		)
		(stroke
			(width 0)
			(type solid)
		)
		(fill yes)
		(layer "In2.Cu")
		(net "M_I_CPU0_SB_DQ<31>")
	)
	(gr_poly
		(pts
			(xy 381.734822 -292.107874) (xy 381.634746 -292.007798) (xy 381.53467 -292.107874) (xy 381.53467 -292.152324)
			(xy 381.734822 -292.152324)
		)
		(stroke
			(width 0)
			(type solid)
		)
		(fill yes)
		(layer "In2.Cu")
		(net "M_I_CPU0_SB_DQ<28>")
	)
	(gr_poly
		(pts
			(xy 381.734822 -291.704268) (xy 381.734822 -291.656516) (xy 381.53467 -291.656516) (xy 381.53467 -291.704268)
			(xy 381.634746 -291.80409)
		)
		(stroke
			(width 0)
			(type solid)
		)
		(fill yes)
		(layer "In2.Cu")
		(net "M_I_CPU0_SB_DQS_DP<8>")
	)
	(gr_poly
		(pts
			(xy 381.734822 -290.487608) (xy 381.634746 -290.387786) (xy 381.53467 -290.487608) (xy 381.53467 -290.53536)
			(xy 381.734822 -290.53536)
		)
		(stroke
			(width 0)
			(type solid)
		)
		(fill yes)
		(layer "In2.Cu")
		(net "M_I_CPU0_SB_DQS_DP<3>")
	)
	(gr_poly
		(pts
			(xy 381.734822 -290.084002) (xy 381.734822 -290.039552) (xy 381.53467 -290.039552) (xy 381.53467 -290.084002)
			(xy 381.634746 -290.184078)
		)
		(stroke
			(width 0)
			(type solid)
		)
		(fill yes)
		(layer "In2.Cu")
		(net "M_I_CPU0_SB_DQ<27>")
	)
	(gr_poly
		(pts
			(xy 381.734822 -288.86785) (xy 381.634746 -288.767774) (xy 381.53467 -288.86785) (xy 381.53467 -288.9123)
			(xy 381.734822 -288.9123)
		)
		(stroke
			(width 0)
			(type solid)
		)
		(fill yes)
		(layer "In2.Cu")
		(net "M_I_CPU0_SB_DQ<24>")
	)
	(gr_poly
		(pts
			(xy 381.734822 -288.464244) (xy 381.734822 -288.419794) (xy 381.53467 -288.419794) (xy 381.53467 -288.464244)
			(xy 381.634746 -288.56432)
		)
		(stroke
			(width 0)
			(type solid)
		)
		(fill yes)
		(layer "In2.Cu")
		(net "M_I_CPU0_SB_DQ<23>")
	)
	(gr_poly
		(pts
			(xy 381.734822 -287.247838) (xy 381.634746 -287.148016) (xy 381.53467 -287.247838) (xy 381.53467 -287.292288)
			(xy 381.734822 -287.292288)
		)
		(stroke
			(width 0)
			(type solid)
		)
		(fill yes)
		(layer "In2.Cu")
		(net "M_I_CPU0_SB_DQ<20>")
	)
	(gr_poly
		(pts
			(xy 381.734822 -286.844232) (xy 381.734822 -286.79648) (xy 381.53467 -286.79648) (xy 381.53467 -286.844232)
			(xy 381.634746 -286.944308)
		)
		(stroke
			(width 0)
			(type solid)
		)
		(fill yes)
		(layer "In2.Cu")
		(net "M_I_CPU0_SB_DQS_DP<7>")
	)
	(gr_poly
		(pts
			(xy 381.734822 -285.627826) (xy 381.634746 -285.528004) (xy 381.53467 -285.627826) (xy 381.53467 -285.675578)
			(xy 381.734822 -285.675578)
		)
		(stroke
			(width 0)
			(type solid)
		)
		(fill yes)
		(layer "In2.Cu")
		(net "M_I_CPU0_SB_DQS_DP<2>")
	)
	(gr_poly
		(pts
			(xy 381.734822 -285.22422) (xy 381.734822 -285.17977) (xy 381.53467 -285.17977) (xy 381.53467 -285.22422)
			(xy 381.634746 -285.324296)
		)
		(stroke
			(width 0)
			(type solid)
		)
		(fill yes)
		(layer "In2.Cu")
		(net "M_I_CPU0_SB_DQ<19>")
	)
	(gr_poly
		(pts
			(xy 381.734822 -284.008068) (xy 381.634746 -283.907992) (xy 381.53467 -284.008068) (xy 381.53467 -284.052518)
			(xy 381.734822 -284.052518)
		)
		(stroke
			(width 0)
			(type solid)
		)
		(fill yes)
		(layer "In2.Cu")
		(net "M_I_CPU0_SB_DQ<16>")
	)
	(gr_poly
		(pts
			(xy 381.734822 -283.604208) (xy 381.734822 -283.559758) (xy 381.53467 -283.559758) (xy 381.53467 -283.604208)
			(xy 381.634746 -283.704284)
		)
		(stroke
			(width 0)
			(type solid)
		)
		(fill yes)
		(layer "In2.Cu")
		(net "M_I_CPU0_SB_DQ<15>")
	)
	(gr_poly
		(pts
			(xy 381.734822 -282.388056) (xy 381.634746 -282.28798) (xy 381.53467 -282.388056) (xy 381.53467 -282.432506)
			(xy 381.734822 -282.432506)
		)
		(stroke
			(width 0)
			(type solid)
		)
		(fill yes)
		(layer "In2.Cu")
		(net "M_I_CPU0_SB_DQ<12>")
	)
	(gr_poly
		(pts
			(xy 381.734822 -281.98445) (xy 381.734822 -281.936698) (xy 381.53467 -281.936698) (xy 381.53467 -281.98445)
			(xy 381.634746 -282.084272)
		)
		(stroke
			(width 0)
			(type solid)
		)
		(fill yes)
		(layer "In2.Cu")
		(net "M_I_CPU0_SB_DQS_DP<6>")
	)
	(gr_poly
		(pts
			(xy 381.734822 -280.76779) (xy 381.634746 -280.667968) (xy 381.53467 -280.76779) (xy 381.53467 -280.815542)
			(xy 381.734822 -280.815542)
		)
		(stroke
			(width 0)
			(type solid)
		)
		(fill yes)
		(layer "In2.Cu")
		(net "M_I_CPU0_SB_DQS_DP<1>")
	)
	(gr_poly
		(pts
			(xy 381.734822 -280.364184) (xy 381.734822 -280.319734) (xy 381.53467 -280.319734) (xy 381.53467 -280.364184)
			(xy 381.634746 -280.46426)
		)
		(stroke
			(width 0)
			(type solid)
		)
		(fill yes)
		(layer "In2.Cu")
		(net "M_I_CPU0_SB_DQ<11>")
	)
	(gr_poly
		(pts
			(xy 381.734822 -279.148032) (xy 381.634746 -279.047956) (xy 381.53467 -279.148032) (xy 381.53467 -279.192482)
			(xy 381.734822 -279.192482)
		)
		(stroke
			(width 0)
			(type solid)
		)
		(fill yes)
		(layer "In2.Cu")
		(net "M_I_CPU0_SB_DQ<8>")
	)
	(gr_poly
		(pts
			(xy 381.734822 -278.744172) (xy 381.734822 -278.699722) (xy 381.53467 -278.699722) (xy 381.53467 -278.744172)
			(xy 381.634746 -278.844248)
		)
		(stroke
			(width 0)
			(type solid)
		)
		(fill yes)
		(layer "In2.Cu")
		(net "M_I_CPU0_SB_DQ<7>")
	)
	(gr_poly
		(pts
			(xy 381.734822 -277.52802) (xy 381.634746 -277.427944) (xy 381.53467 -277.52802) (xy 381.53467 -277.57247)
			(xy 381.734822 -277.57247)
		)
		(stroke
			(width 0)
			(type solid)
		)
		(fill yes)
		(layer "In2.Cu")
		(net "M_I_CPU0_SB_DQ<4>")
	)
	(gr_poly
		(pts
			(xy 381.734822 -277.124414) (xy 381.734822 -277.076662) (xy 381.53467 -277.076662) (xy 381.53467 -277.124414)
			(xy 381.634746 -277.224236)
		)
		(stroke
			(width 0)
			(type solid)
		)
		(fill yes)
		(layer "In2.Cu")
		(net "M_I_CPU0_SB_DQS_DP<5>")
	)
	(gr_poly
		(pts
			(xy 381.734822 -275.907754) (xy 381.634746 -275.807932) (xy 381.53467 -275.907754) (xy 381.53467 -275.955506)
			(xy 381.734822 -275.955506)
		)
		(stroke
			(width 0)
			(type solid)
		)
		(fill yes)
		(layer "In2.Cu")
		(net "M_I_CPU0_SB_DQS_DP<0>")
	)
	(gr_poly
		(pts
			(xy 381.734822 -275.504148) (xy 381.734822 -275.459698) (xy 381.53467 -275.459698) (xy 381.53467 -275.504148)
			(xy 381.634746 -275.604224)
		)
		(stroke
			(width 0)
			(type solid)
		)
		(fill yes)
		(layer "In2.Cu")
		(net "M_I_CPU0_SB_DQ<3>")
	)
	(gr_poly
		(pts
			(xy 381.734822 -274.287996) (xy 381.634746 -274.18792) (xy 381.53467 -274.287996) (xy 381.53467 -274.332446)
			(xy 381.734822 -274.332446)
		)
		(stroke
			(width 0)
			(type solid)
		)
		(fill yes)
		(layer "In2.Cu")
		(net "M_I_CPU0_SB_DQ<0>")
	)
	(gr_poly
		(pts
			(xy 381.734822 -273.884136) (xy 381.734822 -273.839686) (xy 381.53467 -273.839686) (xy 381.53467 -273.884136)
			(xy 381.634746 -273.984212)
		)
		(stroke
			(width 0)
			(type solid)
		)
		(fill yes)
		(layer "In2.Cu")
		(net "M_I_CPU0_SB_CB<3>")
	)
	(gr_poly
		(pts
			(xy 381.734822 -272.667984) (xy 381.634746 -272.567908) (xy 381.53467 -272.667984) (xy 381.53467 -272.712434)
			(xy 381.734822 -272.712434)
		)
		(stroke
			(width 0)
			(type solid)
		)
		(fill yes)
		(layer "In2.Cu")
		(net "M_I_CPU0_SB_CB<0>")
	)
	(gr_poly
		(pts
			(xy 381.734822 -272.264378) (xy 381.734822 -272.216626) (xy 381.53467 -272.216626) (xy 381.53467 -272.264378)
			(xy 381.634746 -272.3642)
		)
		(stroke
			(width 0)
			(type solid)
		)
		(fill yes)
		(layer "In2.Cu")
		(net "M_I_CPU0_SB_DQS_DP<4>")
	)
	(gr_poly
		(pts
			(xy 381.734822 -271.047718) (xy 381.634746 -270.947896) (xy 381.53467 -271.047718) (xy 381.53467 -271.09547)
			(xy 381.734822 -271.09547)
		)
		(stroke
			(width 0)
			(type solid)
		)
		(fill yes)
		(layer "In2.Cu")
		(net "M_I_CPU0_SB_DQS_DP<9>")
	)
	(gr_poly
		(pts
			(xy 381.734822 -270.644112) (xy 381.734822 -270.599662) (xy 381.53467 -270.599662) (xy 381.53467 -270.644112)
			(xy 381.634746 -270.744188)
		)
		(stroke
			(width 0)
			(type solid)
		)
		(fill yes)
		(layer "In2.Cu")
		(net "M_I_CPU0_SB_CB<7>")
	)
	(gr_poly
		(pts
			(xy 381.734822 -269.42796) (xy 381.634746 -269.327884) (xy 381.53467 -269.42796) (xy 381.53467 -269.47241)
			(xy 381.734822 -269.47241)
		)
		(stroke
			(width 0)
			(type solid)
		)
		(fill yes)
		(layer "In2.Cu")
		(net "M_I_CPU0_SB_CB<4>")
	)
	(gr_poly
		(pts
			(xy 381.734822 -267.404088) (xy 381.734822 -267.359638) (xy 381.53467 -267.359638) (xy 381.53467 -267.404088)
			(xy 381.634746 -267.504164)
		)
		(stroke
			(width 0)
			(type solid)
		)
		(fill yes)
		(layer "In2.Cu")
		(net "M_I_CPU0_SB_RSP<0>")
	)
	(gr_poly
		(pts
			(xy 381.734822 -265.784076) (xy 381.734822 -265.739626) (xy 381.53467 -265.739626) (xy 381.53467 -265.784076)
			(xy 381.634746 -265.884152)
		)
		(stroke
			(width 0)
			(type solid)
		)
		(fill yes)
		(layer "In2.Cu")
		(net "M_I_CPU0_SB_CS_N<0>")
	)
	(gr_poly
		(pts
			(xy 381.734822 -264.567924) (xy 381.634746 -264.467848) (xy 381.53467 -264.567924) (xy 381.53467 -264.612374)
			(xy 381.734822 -264.612374)
		)
		(stroke
			(width 0)
			(type solid)
		)
		(fill yes)
		(layer "In2.Cu")
		(net "M_I_CPU0_SB_CA<6>")
	)
	(gr_poly
		(pts
			(xy 381.734822 -264.164064) (xy 381.734822 -264.119614) (xy 381.53467 -264.119614) (xy 381.53467 -264.164064)
			(xy 381.634746 -264.26414)
		)
		(stroke
			(width 0)
			(type solid)
		)
		(fill yes)
		(layer "In2.Cu")
		(net "M_I_CPU0_SB_CA<5>")
	)
	(gr_poly
		(pts
			(xy 381.734822 -262.947912) (xy 381.634746 -262.847836) (xy 381.53467 -262.947912) (xy 381.53467 -262.992362)
			(xy 381.734822 -262.992362)
		)
		(stroke
			(width 0)
			(type solid)
		)
		(fill yes)
		(layer "In2.Cu")
		(net "M_I_CPU0_SB_CA<2>")
	)
	(gr_poly
		(pts
			(xy 381.734822 -262.544052) (xy 381.734822 -262.499602) (xy 381.53467 -262.499602) (xy 381.53467 -262.544052)
			(xy 381.634746 -262.644128)
		)
		(stroke
			(width 0)
			(type solid)
		)
		(fill yes)
		(layer "In2.Cu")
		(net "M_I_CPU0_SB_CA<1>")
	)
	(gr_poly
		(pts
			(xy 381.905002 -256.025904) (xy 381.804926 -255.926082) (xy 381.70485 -256.025904) (xy 381.70485 -256.073656)
			(xy 381.905002 -256.073656)
		)
		(stroke
			(width 0)
			(type solid)
		)
		(fill yes)
		(layer "In2.Cu")
		(net "M_I_CPU0_CLK_DP<0>")
	)
	(gr_poly
		(pts
			(xy 381.905002 -255.622298) (xy 381.905002 -255.577848) (xy 381.70485 -255.577848) (xy 381.70485 -255.622298)
			(xy 381.804926 -255.722374)
		)
		(stroke
			(width 0)
			(type solid)
		)
		(fill yes)
		(layer "In2.Cu")
		(net "M_I_CPU0_SA_PAR")
	)
	(gr_poly
		(pts
			(xy 381.905002 -254.406146) (xy 381.804926 -254.30607) (xy 381.70485 -254.406146) (xy 381.70485 -254.450596)
			(xy 381.905002 -254.450596)
		)
		(stroke
			(width 0)
			(type solid)
		)
		(fill yes)
		(layer "In2.Cu")
		(net "M_I_CPU0_SA_CA<4>")
	)
	(gr_poly
		(pts
			(xy 381.905002 -254.002286) (xy 381.905002 -253.957836) (xy 381.70485 -253.957836) (xy 381.70485 -254.002286)
			(xy 381.804926 -254.102362)
		)
		(stroke
			(width 0)
			(type solid)
		)
		(fill yes)
		(layer "In2.Cu")
		(net "M_I_CPU0_SA_CA<3>")
	)
	(gr_poly
		(pts
			(xy 381.905002 -252.786134) (xy 381.804926 -252.686058) (xy 381.70485 -252.786134) (xy 381.70485 -252.830584)
			(xy 381.905002 -252.830584)
		)
		(stroke
			(width 0)
			(type solid)
		)
		(fill yes)
		(layer "In2.Cu")
		(net "M_I_CPU0_SA_CA<0>")
	)
	(gr_poly
		(pts
			(xy 381.905002 -251.166122) (xy 381.804926 -251.066046) (xy 381.70485 -251.166122) (xy 381.70485 -251.210572)
			(xy 381.905002 -251.210572)
		)
		(stroke
			(width 0)
			(type solid)
		)
		(fill yes)
		(layer "In2.Cu")
		(net "M_I_CPU0_SA_CS_N<0>")
	)
	(gr_poly
		(pts
			(xy 381.905002 -250.762262) (xy 381.905002 -250.717812) (xy 381.70485 -250.717812) (xy 381.70485 -250.762262)
			(xy 381.804926 -250.862338)
		)
		(stroke
			(width 0)
			(type solid)
		)
		(fill yes)
		(layer "In2.Cu")
		(net "M_I_CPU0_RESET_N")
	)
	(gr_poly
		(pts
			(xy 381.905002 -249.14225) (xy 381.905002 -249.0978) (xy 381.70485 -249.0978) (xy 381.70485 -249.14225)
			(xy 381.804926 -249.242326)
		)
		(stroke
			(width 0)
			(type solid)
		)
		(fill yes)
		(layer "In2.Cu")
		(net "M_I_CPU0_SA_CB<7>")
	)
	(gr_poly
		(pts
			(xy 381.905002 -247.926098) (xy 381.804926 -247.826022) (xy 381.70485 -247.926098) (xy 381.70485 -247.970548)
			(xy 381.905002 -247.970548)
		)
		(stroke
			(width 0)
			(type solid)
		)
		(fill yes)
		(layer "In2.Cu")
		(net "M_I_CPU0_SA_CB<4>")
	)
	(gr_poly
		(pts
			(xy 381.905002 -247.522492) (xy 381.905002 -247.47474) (xy 381.70485 -247.47474) (xy 381.70485 -247.522492)
			(xy 381.804926 -247.622314)
		)
		(stroke
			(width 0)
			(type solid)
		)
		(fill yes)
		(layer "In2.Cu")
		(net "M_I_CPU0_SA_DQS_DP<9>")
	)
	(gr_poly
		(pts
			(xy 381.905002 -246.305832) (xy 381.804926 -246.20601) (xy 381.70485 -246.305832) (xy 381.70485 -246.353584)
			(xy 381.905002 -246.353584)
		)
		(stroke
			(width 0)
			(type solid)
		)
		(fill yes)
		(layer "In2.Cu")
		(net "M_I_CPU0_SA_DQS_DP<4>")
	)
	(gr_poly
		(pts
			(xy 381.905002 -245.902226) (xy 381.905002 -245.857776) (xy 381.70485 -245.857776) (xy 381.70485 -245.902226)
			(xy 381.804926 -246.002302)
		)
		(stroke
			(width 0)
			(type solid)
		)
		(fill yes)
		(layer "In2.Cu")
		(net "M_I_CPU0_SA_CB<3>")
	)
	(gr_poly
		(pts
			(xy 381.905002 -244.686074) (xy 381.804926 -244.585998) (xy 381.70485 -244.686074) (xy 381.70485 -244.730524)
			(xy 381.905002 -244.730524)
		)
		(stroke
			(width 0)
			(type solid)
		)
		(fill yes)
		(layer "In2.Cu")
		(net "M_I_CPU0_SA_CB<0>")
	)
	(gr_poly
		(pts
			(xy 381.905002 -244.282214) (xy 381.905002 -244.237764) (xy 381.70485 -244.237764) (xy 381.70485 -244.282214)
			(xy 381.804926 -244.38229)
		)
		(stroke
			(width 0)
			(type solid)
		)
		(fill yes)
		(layer "In2.Cu")
		(net "M_I_CPU0_SA_DQ<31>")
	)
	(gr_poly
		(pts
			(xy 381.905002 -243.066062) (xy 381.804926 -242.965986) (xy 381.70485 -243.066062) (xy 381.70485 -243.110512)
			(xy 381.905002 -243.110512)
		)
		(stroke
			(width 0)
			(type solid)
		)
		(fill yes)
		(layer "In2.Cu")
		(net "M_I_CPU0_SA_DQ<28>")
	)
	(gr_poly
		(pts
			(xy 381.905002 -242.662456) (xy 381.905002 -242.614704) (xy 381.70485 -242.614704) (xy 381.70485 -242.662456)
			(xy 381.804926 -242.762278)
		)
		(stroke
			(width 0)
			(type solid)
		)
		(fill yes)
		(layer "In2.Cu")
		(net "M_I_CPU0_SA_DQS_DP<8>")
	)
	(gr_poly
		(pts
			(xy 381.905002 -241.445796) (xy 381.804926 -241.345974) (xy 381.70485 -241.445796) (xy 381.70485 -241.493548)
			(xy 381.905002 -241.493548)
		)
		(stroke
			(width 0)
			(type solid)
		)
		(fill yes)
		(layer "In2.Cu")
		(net "M_I_CPU0_SA_DQS_DP<3>")
	)
	(gr_poly
		(pts
			(xy 381.905002 -241.04219) (xy 381.905002 -240.99774) (xy 381.70485 -240.99774) (xy 381.70485 -241.04219)
			(xy 381.804926 -241.142266)
		)
		(stroke
			(width 0)
			(type solid)
		)
		(fill yes)
		(layer "In2.Cu")
		(net "M_I_CPU0_SA_DQ<27>")
	)
	(gr_poly
		(pts
			(xy 381.905002 -239.826038) (xy 381.804926 -239.725962) (xy 381.70485 -239.826038) (xy 381.70485 -239.870488)
			(xy 381.905002 -239.870488)
		)
		(stroke
			(width 0)
			(type solid)
		)
		(fill yes)
		(layer "In2.Cu")
		(net "M_I_CPU0_SA_DQ<24>")
	)
	(gr_poly
		(pts
			(xy 381.905002 -239.422178) (xy 381.905002 -239.377728) (xy 381.70485 -239.377728) (xy 381.70485 -239.422178)
			(xy 381.804926 -239.522254)
		)
		(stroke
			(width 0)
			(type solid)
		)
		(fill yes)
		(layer "In2.Cu")
		(net "M_I_CPU0_SA_DQ<23>")
	)
	(gr_poly
		(pts
			(xy 381.905002 -238.206026) (xy 381.804926 -238.10595) (xy 381.70485 -238.206026) (xy 381.70485 -238.250476)
			(xy 381.905002 -238.250476)
		)
		(stroke
			(width 0)
			(type solid)
		)
		(fill yes)
		(layer "In2.Cu")
		(net "M_I_CPU0_SA_DQ<20>")
	)
	(gr_poly
		(pts
			(xy 381.905002 -237.80242) (xy 381.905002 -237.754668) (xy 381.70485 -237.754668) (xy 381.70485 -237.80242)
			(xy 381.804926 -237.902242)
		)
		(stroke
			(width 0)
			(type solid)
		)
		(fill yes)
		(layer "In2.Cu")
		(net "M_I_CPU0_SA_DQS_DP<7>")
	)
	(gr_poly
		(pts
			(xy 381.905002 -236.58576) (xy 381.804926 -236.485938) (xy 381.70485 -236.58576) (xy 381.70485 -236.633512)
			(xy 381.905002 -236.633512)
		)
		(stroke
			(width 0)
			(type solid)
		)
		(fill yes)
		(layer "In2.Cu")
		(net "M_I_CPU0_SA_DQS_DP<2>")
	)
	(gr_poly
		(pts
			(xy 381.905002 -236.182154) (xy 381.905002 -236.137704) (xy 381.70485 -236.137704) (xy 381.70485 -236.182154)
			(xy 381.804926 -236.28223)
		)
		(stroke
			(width 0)
			(type solid)
		)
		(fill yes)
		(layer "In2.Cu")
		(net "M_I_CPU0_SA_DQ<19>")
	)
	(gr_poly
		(pts
			(xy 381.905002 -234.966002) (xy 381.804926 -234.865926) (xy 381.70485 -234.966002) (xy 381.70485 -235.010452)
			(xy 381.905002 -235.010452)
		)
		(stroke
			(width 0)
			(type solid)
		)
		(fill yes)
		(layer "In2.Cu")
		(net "M_I_CPU0_SA_DQ<16>")
	)
	(gr_poly
		(pts
			(xy 381.905002 -234.562142) (xy 381.905002 -234.517692) (xy 381.70485 -234.517692) (xy 381.70485 -234.562142)
			(xy 381.804926 -234.662218)
		)
		(stroke
			(width 0)
			(type solid)
		)
		(fill yes)
		(layer "In2.Cu")
		(net "M_I_CPU0_SA_DQ<15>")
	)
	(gr_poly
		(pts
			(xy 381.905002 -233.34599) (xy 381.804926 -233.245914) (xy 381.70485 -233.34599) (xy 381.70485 -233.39044)
			(xy 381.905002 -233.39044)
		)
		(stroke
			(width 0)
			(type solid)
		)
		(fill yes)
		(layer "In2.Cu")
		(net "M_I_CPU0_SA_DQ<12>")
	)
	(gr_poly
		(pts
			(xy 381.905002 -232.942384) (xy 381.905002 -232.894632) (xy 381.70485 -232.894632) (xy 381.70485 -232.942384)
			(xy 381.804926 -233.042206)
		)
		(stroke
			(width 0)
			(type solid)
		)
		(fill yes)
		(layer "In2.Cu")
		(net "M_I_CPU0_SA_DQS_DP<6>")
	)
	(gr_poly
		(pts
			(xy 381.905002 -231.725724) (xy 381.804926 -231.625902) (xy 381.70485 -231.725724) (xy 381.70485 -231.773476)
			(xy 381.905002 -231.773476)
		)
		(stroke
			(width 0)
			(type solid)
		)
		(fill yes)
		(layer "In2.Cu")
		(net "M_I_CPU0_SA_DQS_DP<1>")
	)
	(gr_poly
		(pts
			(xy 381.905002 -231.322372) (xy 381.905002 -231.277922) (xy 381.70485 -231.277922) (xy 381.70485 -231.322372)
			(xy 381.804926 -231.422448)
		)
		(stroke
			(width 0)
			(type solid)
		)
		(fill yes)
		(layer "In2.Cu")
		(net "M_I_CPU0_SA_DQ<11>")
	)
	(gr_poly
		(pts
			(xy 381.905002 -230.105966) (xy 381.804926 -230.006144) (xy 381.70485 -230.105966) (xy 381.70485 -230.150416)
			(xy 381.905002 -230.150416)
		)
		(stroke
			(width 0)
			(type solid)
		)
		(fill yes)
		(layer "In2.Cu")
		(net "M_I_CPU0_SA_DQ<8>")
	)
	(gr_poly
		(pts
			(xy 381.905002 -229.70236) (xy 381.905002 -229.65791) (xy 381.70485 -229.65791) (xy 381.70485 -229.70236)
			(xy 381.804926 -229.802436)
		)
		(stroke
			(width 0)
			(type solid)
		)
		(fill yes)
		(layer "In2.Cu")
		(net "M_I_CPU0_SA_DQ<7>")
	)
	(gr_poly
		(pts
			(xy 381.905002 -228.486208) (xy 381.804926 -228.386132) (xy 381.70485 -228.486208) (xy 381.70485 -228.530658)
			(xy 381.905002 -228.530658)
		)
		(stroke
			(width 0)
			(type solid)
		)
		(fill yes)
		(layer "In2.Cu")
		(net "M_I_CPU0_SA_DQ<4>")
	)
	(gr_poly
		(pts
			(xy 381.905002 -228.082602) (xy 381.905002 -228.03485) (xy 381.70485 -228.03485) (xy 381.70485 -228.082602)
			(xy 381.804926 -228.182424)
		)
		(stroke
			(width 0)
			(type solid)
		)
		(fill yes)
		(layer "In2.Cu")
		(net "M_I_CPU0_SA_DQS_DP<5>")
	)
	(gr_poly
		(pts
			(xy 381.905002 -226.865942) (xy 381.804926 -226.76612) (xy 381.70485 -226.865942) (xy 381.70485 -226.913694)
			(xy 381.905002 -226.913694)
		)
		(stroke
			(width 0)
			(type solid)
		)
		(fill yes)
		(layer "In2.Cu")
		(net "M_I_CPU0_SA_DQS_DP<0>")
	)
	(gr_poly
		(pts
			(xy 381.905002 -226.462336) (xy 381.905002 -226.417886) (xy 381.70485 -226.417886) (xy 381.70485 -226.462336)
			(xy 381.804926 -226.562412)
		)
		(stroke
			(width 0)
			(type solid)
		)
		(fill yes)
		(layer "In2.Cu")
		(net "M_I_CPU0_SA_DQ<3>")
	)
	(gr_poly
		(pts
			(xy 381.905002 -225.246184) (xy 381.804926 -225.146108) (xy 381.70485 -225.246184) (xy 381.70485 -225.290634)
			(xy 381.905002 -225.290634)
		)
		(stroke
			(width 0)
			(type solid)
		)
		(fill yes)
		(layer "In2.Cu")
		(net "M_I_CPU0_SA_DQ<0>")
	)
	(gr_poly
		(pts
			(xy 382.204976 -292.91788) (xy 382.1049 -292.817804) (xy 382.004824 -292.91788) (xy 382.004824 -292.96233)
			(xy 382.204976 -292.96233)
		)
		(stroke
			(width 0)
			(type solid)
		)
		(fill yes)
		(layer "In2.Cu")
		(net "M_I_CPU0_SB_DQ<29>")
	)
	(gr_poly
		(pts
			(xy 382.204976 -292.51402) (xy 382.204976 -292.46957) (xy 382.004824 -292.46957) (xy 382.004824 -292.51402)
			(xy 382.1049 -292.614096)
		)
		(stroke
			(width 0)
			(type solid)
		)
		(fill yes)
		(layer "In2.Cu")
		(net "M_I_CPU0_SB_DQ<30>")
	)
	(gr_poly
		(pts
			(xy 382.204976 -291.297614) (xy 382.1049 -291.197792) (xy 382.004824 -291.297614) (xy 382.004824 -291.345366)
			(xy 382.204976 -291.345366)
		)
		(stroke
			(width 0)
			(type solid)
		)
		(fill yes)
		(layer "In2.Cu")
		(net "M_I_CPU0_SB_DQS_DN<8>")
	)
	(gr_poly
		(pts
			(xy 382.204976 -290.894262) (xy 382.204976 -290.84651) (xy 382.004824 -290.84651) (xy 382.004824 -290.894262)
			(xy 382.1049 -290.994084)
		)
		(stroke
			(width 0)
			(type solid)
		)
		(fill yes)
		(layer "In2.Cu")
		(net "M_I_CPU0_SB_DQS_DN<3>")
	)
	(gr_poly
		(pts
			(xy 382.204976 -289.677856) (xy 382.1049 -289.57778) (xy 382.004824 -289.677856) (xy 382.004824 -289.722306)
			(xy 382.204976 -289.722306)
		)
		(stroke
			(width 0)
			(type solid)
		)
		(fill yes)
		(layer "In2.Cu")
		(net "M_I_CPU0_SB_DQ<25>")
	)
	(gr_poly
		(pts
			(xy 382.204976 -289.273996) (xy 382.204976 -289.229546) (xy 382.004824 -289.229546) (xy 382.004824 -289.273996)
			(xy 382.1049 -289.374072)
		)
		(stroke
			(width 0)
			(type solid)
		)
		(fill yes)
		(layer "In2.Cu")
		(net "M_I_CPU0_SB_DQ<26>")
	)
	(gr_poly
		(pts
			(xy 382.204976 -288.057844) (xy 382.1049 -287.957768) (xy 382.004824 -288.057844) (xy 382.004824 -288.102294)
			(xy 382.204976 -288.102294)
		)
		(stroke
			(width 0)
			(type solid)
		)
		(fill yes)
		(layer "In2.Cu")
		(net "M_I_CPU0_SB_DQ<21>")
	)
	(gr_poly
		(pts
			(xy 382.204976 -287.654238) (xy 382.204976 -287.609788) (xy 382.004824 -287.609788) (xy 382.004824 -287.654238)
			(xy 382.1049 -287.75406)
		)
		(stroke
			(width 0)
			(type solid)
		)
		(fill yes)
		(layer "In2.Cu")
		(net "M_I_CPU0_SB_DQ<22>")
	)
	(gr_poly
		(pts
			(xy 382.204976 -286.437832) (xy 382.1049 -286.337756) (xy 382.004824 -286.437832) (xy 382.004824 -286.485584)
			(xy 382.204976 -286.485584)
		)
		(stroke
			(width 0)
			(type solid)
		)
		(fill yes)
		(layer "In2.Cu")
		(net "M_I_CPU0_SB_DQS_DN<7>")
	)
	(gr_poly
		(pts
			(xy 382.204976 -286.03448) (xy 382.204976 -285.986728) (xy 382.004824 -285.986728) (xy 382.004824 -286.03448)
			(xy 382.1049 -286.134302)
		)
		(stroke
			(width 0)
			(type solid)
		)
		(fill yes)
		(layer "In2.Cu")
		(net "M_I_CPU0_SB_DQS_DN<2>")
	)
	(gr_poly
		(pts
			(xy 382.204976 -284.818074) (xy 382.1049 -284.717998) (xy 382.004824 -284.818074) (xy 382.004824 -284.862524)
			(xy 382.204976 -284.862524)
		)
		(stroke
			(width 0)
			(type solid)
		)
		(fill yes)
		(layer "In2.Cu")
		(net "M_I_CPU0_SB_DQ<17>")
	)
	(gr_poly
		(pts
			(xy 382.204976 -284.414214) (xy 382.204976 -284.369764) (xy 382.004824 -284.369764) (xy 382.004824 -284.414214)
			(xy 382.1049 -284.51429)
		)
		(stroke
			(width 0)
			(type solid)
		)
		(fill yes)
		(layer "In2.Cu")
		(net "M_I_CPU0_SB_DQ<18>")
	)
	(gr_poly
		(pts
			(xy 382.204976 -283.198062) (xy 382.1049 -283.097986) (xy 382.004824 -283.198062) (xy 382.004824 -283.242512)
			(xy 382.204976 -283.242512)
		)
		(stroke
			(width 0)
			(type solid)
		)
		(fill yes)
		(layer "In2.Cu")
		(net "M_I_CPU0_SB_DQ<13>")
	)
	(gr_poly
		(pts
			(xy 382.204976 -282.794202) (xy 382.204976 -282.749752) (xy 382.004824 -282.749752) (xy 382.004824 -282.794202)
			(xy 382.1049 -282.894278)
		)
		(stroke
			(width 0)
			(type solid)
		)
		(fill yes)
		(layer "In2.Cu")
		(net "M_I_CPU0_SB_DQ<14>")
	)
	(gr_poly
		(pts
			(xy 382.204976 -281.577796) (xy 382.1049 -281.477974) (xy 382.004824 -281.577796) (xy 382.004824 -281.625548)
			(xy 382.204976 -281.625548)
		)
		(stroke
			(width 0)
			(type solid)
		)
		(fill yes)
		(layer "In2.Cu")
		(net "M_I_CPU0_SB_DQS_DN<6>")
	)
	(gr_poly
		(pts
			(xy 382.204976 -281.174444) (xy 382.204976 -281.126692) (xy 382.004824 -281.126692) (xy 382.004824 -281.174444)
			(xy 382.1049 -281.274266)
		)
		(stroke
			(width 0)
			(type solid)
		)
		(fill yes)
		(layer "In2.Cu")
		(net "M_I_CPU0_SB_DQS_DN<1>")
	)
	(gr_poly
		(pts
			(xy 382.204976 -279.958038) (xy 382.1049 -279.857962) (xy 382.004824 -279.958038) (xy 382.004824 -280.002488)
			(xy 382.204976 -280.002488)
		)
		(stroke
			(width 0)
			(type solid)
		)
		(fill yes)
		(layer "In2.Cu")
		(net "M_I_CPU0_SB_DQ<9>")
	)
	(gr_poly
		(pts
			(xy 382.204976 -279.554178) (xy 382.204976 -279.509728) (xy 382.004824 -279.509728) (xy 382.004824 -279.554178)
			(xy 382.1049 -279.654254)
		)
		(stroke
			(width 0)
			(type solid)
		)
		(fill yes)
		(layer "In2.Cu")
		(net "M_I_CPU0_SB_DQ<10>")
	)
	(gr_poly
		(pts
			(xy 382.204976 -278.338026) (xy 382.1049 -278.23795) (xy 382.004824 -278.338026) (xy 382.004824 -278.382476)
			(xy 382.204976 -278.382476)
		)
		(stroke
			(width 0)
			(type solid)
		)
		(fill yes)
		(layer "In2.Cu")
		(net "M_I_CPU0_SB_DQ<5>")
	)
	(gr_poly
		(pts
			(xy 382.204976 -277.934166) (xy 382.204976 -277.889716) (xy 382.004824 -277.889716) (xy 382.004824 -277.934166)
			(xy 382.1049 -278.034242)
		)
		(stroke
			(width 0)
			(type solid)
		)
		(fill yes)
		(layer "In2.Cu")
		(net "M_I_CPU0_SB_DQ<6>")
	)
	(gr_poly
		(pts
			(xy 382.204976 -276.71776) (xy 382.1049 -276.617938) (xy 382.004824 -276.71776) (xy 382.004824 -276.765512)
			(xy 382.204976 -276.765512)
		)
		(stroke
			(width 0)
			(type solid)
		)
		(fill yes)
		(layer "In2.Cu")
		(net "M_I_CPU0_SB_DQS_DN<5>")
	)
	(gr_poly
		(pts
			(xy 382.204976 -276.314408) (xy 382.204976 -276.266656) (xy 382.004824 -276.266656) (xy 382.004824 -276.314408)
			(xy 382.1049 -276.41423)
		)
		(stroke
			(width 0)
			(type solid)
		)
		(fill yes)
		(layer "In2.Cu")
		(net "M_I_CPU0_SB_DQS_DN<0>")
	)
	(gr_poly
		(pts
			(xy 382.204976 -275.098002) (xy 382.1049 -274.997926) (xy 382.004824 -275.098002) (xy 382.004824 -275.142452)
			(xy 382.204976 -275.142452)
		)
		(stroke
			(width 0)
			(type solid)
		)
		(fill yes)
		(layer "In2.Cu")
		(net "M_I_CPU0_SB_DQ<1>")
	)
	(gr_poly
		(pts
			(xy 382.204976 -274.694142) (xy 382.204976 -274.649692) (xy 382.004824 -274.649692) (xy 382.004824 -274.694142)
			(xy 382.1049 -274.794218)
		)
		(stroke
			(width 0)
			(type solid)
		)
		(fill yes)
		(layer "In2.Cu")
		(net "M_I_CPU0_SB_DQ<2>")
	)
	(gr_poly
		(pts
			(xy 382.204976 -273.47799) (xy 382.1049 -273.377914) (xy 382.004824 -273.47799) (xy 382.004824 -273.52244)
			(xy 382.204976 -273.52244)
		)
		(stroke
			(width 0)
			(type solid)
		)
		(fill yes)
		(layer "In2.Cu")
		(net "M_I_CPU0_SB_CB<1>")
	)
	(gr_poly
		(pts
			(xy 382.204976 -273.07413) (xy 382.204976 -273.02968) (xy 382.004824 -273.02968) (xy 382.004824 -273.07413)
			(xy 382.1049 -273.174206)
		)
		(stroke
			(width 0)
			(type solid)
		)
		(fill yes)
		(layer "In2.Cu")
		(net "M_I_CPU0_SB_CB<2>")
	)
	(gr_poly
		(pts
			(xy 382.204976 -271.857724) (xy 382.1049 -271.757902) (xy 382.004824 -271.857724) (xy 382.004824 -271.905476)
			(xy 382.204976 -271.905476)
		)
		(stroke
			(width 0)
			(type solid)
		)
		(fill yes)
		(layer "In2.Cu")
		(net "M_I_CPU0_SB_DQS_DN<4>")
	)
	(gr_poly
		(pts
			(xy 382.204976 -271.454372) (xy 382.204976 -271.40662) (xy 382.004824 -271.40662) (xy 382.004824 -271.454372)
			(xy 382.1049 -271.554194)
		)
		(stroke
			(width 0)
			(type solid)
		)
		(fill yes)
		(layer "In2.Cu")
		(net "M_I_CPU0_SB_DQS_DN<9>")
	)
	(gr_poly
		(pts
			(xy 382.204976 -270.237966) (xy 382.1049 -270.13789) (xy 382.004824 -270.237966) (xy 382.004824 -270.282416)
			(xy 382.204976 -270.282416)
		)
		(stroke
			(width 0)
			(type solid)
		)
		(fill yes)
		(layer "In2.Cu")
		(net "M_I_CPU0_SB_CB<5>")
	)
	(gr_poly
		(pts
			(xy 382.204976 -269.834106) (xy 382.204976 -269.789656) (xy 382.004824 -269.789656) (xy 382.004824 -269.834106)
			(xy 382.1049 -269.934182)
		)
		(stroke
			(width 0)
			(type solid)
		)
		(fill yes)
		(layer "In2.Cu")
		(net "M_I_CPU0_SB_CB<6>")
	)
	(gr_poly
		(pts
			(xy 382.204976 -266.997942) (xy 382.1049 -266.897866) (xy 382.004824 -266.997942) (xy 382.004824 -267.042392)
			(xy 382.204976 -267.042392)
		)
		(stroke
			(width 0)
			(type solid)
		)
		(fill yes)
		(layer "In2.Cu")
		(net "M_I_CPU0_SA_RSP<0>")
	)
	(gr_poly
		(pts
			(xy 382.204976 -266.594082) (xy 382.204976 -266.549632) (xy 382.004824 -266.549632) (xy 382.004824 -266.594082)
			(xy 382.1049 -266.694158)
		)
		(stroke
			(width 0)
			(type solid)
		)
		(fill yes)
		(layer "In2.Cu")
		(net "M_I_CPU0_SB_CS_N<1>")
	)
	(gr_poly
		(pts
			(xy 382.204976 -265.37793) (xy 382.1049 -265.277854) (xy 382.004824 -265.37793) (xy 382.004824 -265.42238)
			(xy 382.204976 -265.42238)
		)
		(stroke
			(width 0)
			(type solid)
		)
		(fill yes)
		(layer "In2.Cu")
		(net "M_I_CPU0_SB_PAR")
	)
	(gr_poly
		(pts
			(xy 382.204976 -263.757918) (xy 382.1049 -263.657842) (xy 382.004824 -263.757918) (xy 382.004824 -263.802368)
			(xy 382.204976 -263.802368)
		)
		(stroke
			(width 0)
			(type solid)
		)
		(fill yes)
		(layer "In2.Cu")
		(net "M_I_CPU0_SB_CA<4>")
	)
	(gr_poly
		(pts
			(xy 382.204976 -263.354058) (xy 382.204976 -263.309608) (xy 382.004824 -263.309608) (xy 382.004824 -263.354058)
			(xy 382.1049 -263.454134)
		)
		(stroke
			(width 0)
			(type solid)
		)
		(fill yes)
		(layer "In2.Cu")
		(net "M_I_CPU0_SB_CA<3>")
	)
	(gr_poly
		(pts
			(xy 382.204976 -262.137906) (xy 382.1049 -262.03783) (xy 382.004824 -262.137906) (xy 382.004824 -262.182356)
			(xy 382.204976 -262.182356)
		)
		(stroke
			(width 0)
			(type solid)
		)
		(fill yes)
		(layer "In2.Cu")
		(net "M_I_CPU0_SB_CA<0>")
	)
	(gr_poly
		(pts
			(xy 382.374902 -256.432558) (xy 382.374902 -256.384806) (xy 382.17475 -256.384806) (xy 382.17475 -256.432558)
			(xy 382.274826 -256.53238)
		)
		(stroke
			(width 0)
			(type solid)
		)
		(fill yes)
		(layer "In2.Cu")
		(net "M_I_CPU0_CLK_DN<0>")
	)
	(gr_poly
		(pts
			(xy 382.374902 -255.216152) (xy 382.274826 -255.116076) (xy 382.17475 -255.216152) (xy 382.17475 -255.260602)
			(xy 382.374902 -255.260602)
		)
		(stroke
			(width 0)
			(type solid)
		)
		(fill yes)
		(layer "In2.Cu")
		(net "M_I_CPU0_SA_CA<6>")
	)
	(gr_poly
		(pts
			(xy 382.374902 -254.812292) (xy 382.374902 -254.767842) (xy 382.17475 -254.767842) (xy 382.17475 -254.812292)
			(xy 382.274826 -254.912368)
		)
		(stroke
			(width 0)
			(type solid)
		)
		(fill yes)
		(layer "In2.Cu")
		(net "M_I_CPU0_SA_CA<5>")
	)
	(gr_poly
		(pts
			(xy 382.374902 -253.59614) (xy 382.274826 -253.496064) (xy 382.17475 -253.59614) (xy 382.17475 -253.64059)
			(xy 382.374902 -253.64059)
		)
		(stroke
			(width 0)
			(type solid)
		)
		(fill yes)
		(layer "In2.Cu")
		(net "M_I_CPU0_SA_CA<2>")
	)
	(gr_poly
		(pts
			(xy 382.374902 -253.19228) (xy 382.374902 -253.14783) (xy 382.17475 -253.14783) (xy 382.17475 -253.19228)
			(xy 382.274826 -253.292356)
		)
		(stroke
			(width 0)
			(type solid)
		)
		(fill yes)
		(layer "In2.Cu")
		(net "M_I_CPU0_SA_CA<1>")
	)
	(gr_poly
		(pts
			(xy 382.374902 -251.976128) (xy 382.274826 -251.876052) (xy 382.17475 -251.976128) (xy 382.17475 -252.020578)
			(xy 382.374902 -252.020578)
		)
		(stroke
			(width 0)
			(type solid)
		)
		(fill yes)
		(layer "In2.Cu")
		(net "M_I_CPU0_SA_CS_N<1>")
	)
	(gr_poly
		(pts
			(xy 382.374902 -250.356116) (xy 382.274826 -250.25604) (xy 382.17475 -250.356116) (xy 382.17475 -250.400566)
			(xy 382.374902 -250.400566)
		)
		(stroke
			(width 0)
			(type solid)
		)
		(fill yes)
		(layer "In2.Cu")
		(net "M_I_CPU0_ALERT_R_N")
	)
	(gr_poly
		(pts
			(xy 382.374902 -248.736104) (xy 382.274826 -248.636028) (xy 382.17475 -248.736104) (xy 382.17475 -248.780554)
			(xy 382.374902 -248.780554)
		)
		(stroke
			(width 0)
			(type solid)
		)
		(fill yes)
		(layer "In2.Cu")
		(net "M_I_CPU0_SA_CB<5>")
	)
	(gr_poly
		(pts
			(xy 382.374902 -248.332244) (xy 382.374902 -248.287794) (xy 382.17475 -248.287794) (xy 382.17475 -248.332244)
			(xy 382.274826 -248.43232)
		)
		(stroke
			(width 0)
			(type solid)
		)
		(fill yes)
		(layer "In2.Cu")
		(net "M_I_CPU0_SA_CB<6>")
	)
	(gr_poly
		(pts
			(xy 382.374902 -247.115838) (xy 382.274826 -247.016016) (xy 382.17475 -247.115838) (xy 382.17475 -247.16359)
			(xy 382.374902 -247.16359)
		)
		(stroke
			(width 0)
			(type solid)
		)
		(fill yes)
		(layer "In2.Cu")
		(net "M_I_CPU0_SA_DQS_DN<9>")
	)
	(gr_poly
		(pts
			(xy 382.374902 -246.712486) (xy 382.374902 -246.664734) (xy 382.17475 -246.664734) (xy 382.17475 -246.712486)
			(xy 382.274826 -246.812308)
		)
		(stroke
			(width 0)
			(type solid)
		)
		(fill yes)
		(layer "In2.Cu")
		(net "M_I_CPU0_SA_DQS_DN<4>")
	)
	(gr_poly
		(pts
			(xy 382.374902 -245.49608) (xy 382.274826 -245.396004) (xy 382.17475 -245.49608) (xy 382.17475 -245.54053)
			(xy 382.374902 -245.54053)
		)
		(stroke
			(width 0)
			(type solid)
		)
		(fill yes)
		(layer "In2.Cu")
		(net "M_I_CPU0_SA_CB<1>")
	)
	(gr_poly
		(pts
			(xy 382.374902 -245.09222) (xy 382.374902 -245.04777) (xy 382.17475 -245.04777) (xy 382.17475 -245.09222)
			(xy 382.274826 -245.192296)
		)
		(stroke
			(width 0)
			(type solid)
		)
		(fill yes)
		(layer "In2.Cu")
		(net "M_I_CPU0_SA_CB<2>")
	)
	(gr_poly
		(pts
			(xy 382.374902 -243.876068) (xy 382.274826 -243.775992) (xy 382.17475 -243.876068) (xy 382.17475 -243.920518)
			(xy 382.374902 -243.920518)
		)
		(stroke
			(width 0)
			(type solid)
		)
		(fill yes)
		(layer "In2.Cu")
		(net "M_I_CPU0_SA_DQ<29>")
	)
	(gr_poly
		(pts
			(xy 382.374902 -243.472208) (xy 382.374902 -243.427758) (xy 382.17475 -243.427758) (xy 382.17475 -243.472208)
			(xy 382.274826 -243.572284)
		)
		(stroke
			(width 0)
			(type solid)
		)
		(fill yes)
		(layer "In2.Cu")
		(net "M_I_CPU0_SA_DQ<30>")
	)
	(gr_poly
		(pts
			(xy 382.374902 -242.255802) (xy 382.274826 -242.15598) (xy 382.17475 -242.255802) (xy 382.17475 -242.303554)
			(xy 382.374902 -242.303554)
		)
		(stroke
			(width 0)
			(type solid)
		)
		(fill yes)
		(layer "In2.Cu")
		(net "M_I_CPU0_SA_DQS_DN<8>")
	)
	(gr_poly
		(pts
			(xy 382.374902 -241.85245) (xy 382.374902 -241.804698) (xy 382.17475 -241.804698) (xy 382.17475 -241.85245)
			(xy 382.274826 -241.952272)
		)
		(stroke
			(width 0)
			(type solid)
		)
		(fill yes)
		(layer "In2.Cu")
		(net "M_I_CPU0_SA_DQS_DN<3>")
	)
	(gr_poly
		(pts
			(xy 382.374902 -240.636044) (xy 382.274826 -240.535968) (xy 382.17475 -240.636044) (xy 382.17475 -240.680494)
			(xy 382.374902 -240.680494)
		)
		(stroke
			(width 0)
			(type solid)
		)
		(fill yes)
		(layer "In2.Cu")
		(net "M_I_CPU0_SA_DQ<25>")
	)
	(gr_poly
		(pts
			(xy 382.374902 -240.232184) (xy 382.374902 -240.187734) (xy 382.17475 -240.187734) (xy 382.17475 -240.232184)
			(xy 382.274826 -240.33226)
		)
		(stroke
			(width 0)
			(type solid)
		)
		(fill yes)
		(layer "In2.Cu")
		(net "M_I_CPU0_SA_DQ<26>")
	)
	(gr_poly
		(pts
			(xy 382.374902 -239.016032) (xy 382.274826 -238.915956) (xy 382.17475 -239.016032) (xy 382.17475 -239.060482)
			(xy 382.374902 -239.060482)
		)
		(stroke
			(width 0)
			(type solid)
		)
		(fill yes)
		(layer "In2.Cu")
		(net "M_I_CPU0_SA_DQ<21>")
	)
	(gr_poly
		(pts
			(xy 382.374902 -238.612172) (xy 382.374902 -238.567722) (xy 382.17475 -238.567722) (xy 382.17475 -238.612172)
			(xy 382.274826 -238.712248)
		)
		(stroke
			(width 0)
			(type solid)
		)
		(fill yes)
		(layer "In2.Cu")
		(net "M_I_CPU0_SA_DQ<22>")
	)
	(gr_poly
		(pts
			(xy 382.374902 -237.395766) (xy 382.274826 -237.295944) (xy 382.17475 -237.395766) (xy 382.17475 -237.443518)
			(xy 382.374902 -237.443518)
		)
		(stroke
			(width 0)
			(type solid)
		)
		(fill yes)
		(layer "In2.Cu")
		(net "M_I_CPU0_SA_DQS_DN<7>")
	)
	(gr_poly
		(pts
			(xy 382.374902 -236.992414) (xy 382.374902 -236.944662) (xy 382.17475 -236.944662) (xy 382.17475 -236.992414)
			(xy 382.274826 -237.092236)
		)
		(stroke
			(width 0)
			(type solid)
		)
		(fill yes)
		(layer "In2.Cu")
		(net "M_I_CPU0_SA_DQS_DN<2>")
	)
	(gr_poly
		(pts
			(xy 382.374902 -235.776008) (xy 382.274826 -235.675932) (xy 382.17475 -235.776008) (xy 382.17475 -235.820458)
			(xy 382.374902 -235.820458)
		)
		(stroke
			(width 0)
			(type solid)
		)
		(fill yes)
		(layer "In2.Cu")
		(net "M_I_CPU0_SA_DQ<17>")
	)
	(gr_poly
		(pts
			(xy 382.374902 -235.372148) (xy 382.374902 -235.327698) (xy 382.17475 -235.327698) (xy 382.17475 -235.372148)
			(xy 382.274826 -235.472224)
		)
		(stroke
			(width 0)
			(type solid)
		)
		(fill yes)
		(layer "In2.Cu")
		(net "M_I_CPU0_SA_DQ<18>")
	)
	(gr_poly
		(pts
			(xy 382.374902 -234.155996) (xy 382.274826 -234.05592) (xy 382.17475 -234.155996) (xy 382.17475 -234.200446)
			(xy 382.374902 -234.200446)
		)
		(stroke
			(width 0)
			(type solid)
		)
		(fill yes)
		(layer "In2.Cu")
		(net "M_I_CPU0_SA_DQ<13>")
	)
	(gr_poly
		(pts
			(xy 382.374902 -233.752136) (xy 382.374902 -233.707686) (xy 382.17475 -233.707686) (xy 382.17475 -233.752136)
			(xy 382.274826 -233.852212)
		)
		(stroke
			(width 0)
			(type solid)
		)
		(fill yes)
		(layer "In2.Cu")
		(net "M_I_CPU0_SA_DQ<14>")
	)
	(gr_poly
		(pts
			(xy 382.374902 -232.53573) (xy 382.274826 -232.435908) (xy 382.17475 -232.53573) (xy 382.17475 -232.583482)
			(xy 382.374902 -232.583482)
		)
		(stroke
			(width 0)
			(type solid)
		)
		(fill yes)
		(layer "In2.Cu")
		(net "M_I_CPU0_SA_DQS_DN<6>")
	)
	(gr_poly
		(pts
			(xy 382.374902 -232.132378) (xy 382.374902 -232.084626) (xy 382.17475 -232.084626) (xy 382.17475 -232.132378)
			(xy 382.274826 -232.2322)
		)
		(stroke
			(width 0)
			(type solid)
		)
		(fill yes)
		(layer "In2.Cu")
		(net "M_I_CPU0_SA_DQS_DN<1>")
	)
	(gr_poly
		(pts
			(xy 382.374902 -230.915972) (xy 382.274826 -230.815896) (xy 382.17475 -230.915972) (xy 382.17475 -230.960422)
			(xy 382.374902 -230.960422)
		)
		(stroke
			(width 0)
			(type solid)
		)
		(fill yes)
		(layer "In2.Cu")
		(net "M_I_CPU0_SA_DQ<9>")
	)
	(gr_poly
		(pts
			(xy 382.374902 -230.512366) (xy 382.374902 -230.467916) (xy 382.17475 -230.467916) (xy 382.17475 -230.512366)
			(xy 382.274826 -230.612188)
		)
		(stroke
			(width 0)
			(type solid)
		)
		(fill yes)
		(layer "In2.Cu")
		(net "M_I_CPU0_SA_DQ<10>")
	)
	(gr_poly
		(pts
			(xy 382.374902 -229.29596) (xy 382.274826 -229.195884) (xy 382.17475 -229.29596) (xy 382.17475 -229.34041)
			(xy 382.374902 -229.34041)
		)
		(stroke
			(width 0)
			(type solid)
		)
		(fill yes)
		(layer "In2.Cu")
		(net "M_I_CPU0_SA_DQ<5>")
	)
	(gr_poly
		(pts
			(xy 382.374902 -228.892354) (xy 382.374902 -228.847904) (xy 382.17475 -228.847904) (xy 382.17475 -228.892354)
			(xy 382.274826 -228.99243)
		)
		(stroke
			(width 0)
			(type solid)
		)
		(fill yes)
		(layer "In2.Cu")
		(net "M_I_CPU0_SA_DQ<6>")
	)
	(gr_poly
		(pts
			(xy 382.374902 -227.675948) (xy 382.274826 -227.576126) (xy 382.17475 -227.675948) (xy 382.17475 -227.7237)
			(xy 382.374902 -227.7237)
		)
		(stroke
			(width 0)
			(type solid)
		)
		(fill yes)
		(layer "In2.Cu")
		(net "M_I_CPU0_SA_DQS_DN<5>")
	)
	(gr_poly
		(pts
			(xy 382.374902 -227.272596) (xy 382.374902 -227.224844) (xy 382.17475 -227.224844) (xy 382.17475 -227.272596)
			(xy 382.274826 -227.372418)
		)
		(stroke
			(width 0)
			(type solid)
		)
		(fill yes)
		(layer "In2.Cu")
		(net "M_I_CPU0_SA_DQS_DN<0>")
	)
	(gr_poly
		(pts
			(xy 382.374902 -226.05619) (xy 382.274826 -225.956114) (xy 382.17475 -226.05619) (xy 382.17475 -226.10064)
			(xy 382.374902 -226.10064)
		)
		(stroke
			(width 0)
			(type solid)
		)
		(fill yes)
		(layer "In2.Cu")
		(net "M_I_CPU0_SA_DQ<1>")
	)
	(gr_poly
		(pts
			(xy 382.374902 -225.65233) (xy 382.374902 -225.60788) (xy 382.17475 -225.60788) (xy 382.17475 -225.65233)
			(xy 382.274826 -225.752406)
		)
		(stroke
			(width 0)
			(type solid)
		)
		(fill yes)
		(layer "In2.Cu")
		(net "M_I_CPU0_SA_DQ<2>")
	)
	(gr_poly
		(pts
			(xy 382.674876 -293.324026) (xy 382.674876 -293.279576) (xy 382.474724 -293.279576) (xy 382.474724 -293.324026)
			(xy 382.5748 -293.424102)
		)
		(stroke
			(width 0)
			(type solid)
		)
		(fill yes)
		(layer "In2.Cu")
		(net "M_I_CPU0_SB_DQ<31>")
	)
	(gr_poly
		(pts
			(xy 382.674876 -292.107874) (xy 382.5748 -292.007798) (xy 382.474724 -292.107874) (xy 382.474724 -292.152324)
			(xy 382.674876 -292.152324)
		)
		(stroke
			(width 0)
			(type solid)
		)
		(fill yes)
		(layer "In2.Cu")
		(net "M_I_CPU0_SB_DQ<28>")
	)
	(gr_poly
		(pts
			(xy 382.674876 -291.704268) (xy 382.674876 -291.656516) (xy 382.474724 -291.656516) (xy 382.474724 -291.704268)
			(xy 382.5748 -291.80409)
		)
		(stroke
			(width 0)
			(type solid)
		)
		(fill yes)
		(layer "In2.Cu")
		(net "M_I_CPU0_SB_DQS_DP<8>")
	)
	(gr_poly
		(pts
			(xy 382.674876 -290.487608) (xy 382.5748 -290.387786) (xy 382.474724 -290.487608) (xy 382.474724 -290.53536)
			(xy 382.674876 -290.53536)
		)
		(stroke
			(width 0)
			(type solid)
		)
		(fill yes)
		(layer "In2.Cu")
		(net "M_I_CPU0_SB_DQS_DP<3>")
	)
	(gr_poly
		(pts
			(xy 382.674876 -290.084002) (xy 382.674876 -290.039552) (xy 382.474724 -290.039552) (xy 382.474724 -290.084002)
			(xy 382.5748 -290.184078)
		)
		(stroke
			(width 0)
			(type solid)
		)
		(fill yes)
		(layer "In2.Cu")
		(net "M_I_CPU0_SB_DQ<27>")
	)
	(gr_poly
		(pts
			(xy 382.674876 -288.86785) (xy 382.5748 -288.767774) (xy 382.474724 -288.86785) (xy 382.474724 -288.9123)
			(xy 382.674876 -288.9123)
		)
		(stroke
			(width 0)
			(type solid)
		)
		(fill yes)
		(layer "In2.Cu")
		(net "M_I_CPU0_SB_DQ<24>")
	)
	(gr_poly
		(pts
			(xy 382.674876 -288.464244) (xy 382.674876 -288.419794) (xy 382.474724 -288.419794) (xy 382.474724 -288.464244)
			(xy 382.5748 -288.56432)
		)
		(stroke
			(width 0)
			(type solid)
		)
		(fill yes)
		(layer "In2.Cu")
		(net "M_I_CPU0_SB_DQ<23>")
	)
	(gr_poly
		(pts
			(xy 382.674876 -287.247838) (xy 382.5748 -287.148016) (xy 382.474724 -287.247838) (xy 382.474724 -287.292288)
			(xy 382.674876 -287.292288)
		)
		(stroke
			(width 0)
			(type solid)
		)
		(fill yes)
		(layer "In2.Cu")
		(net "M_I_CPU0_SB_DQ<20>")
	)
	(gr_poly
		(pts
			(xy 382.674876 -286.844232) (xy 382.674876 -286.79648) (xy 382.474724 -286.79648) (xy 382.474724 -286.844232)
			(xy 382.5748 -286.944308)
		)
		(stroke
			(width 0)
			(type solid)
		)
		(fill yes)
		(layer "In2.Cu")
		(net "M_I_CPU0_SB_DQS_DP<7>")
	)
	(gr_poly
		(pts
			(xy 382.674876 -285.627826) (xy 382.5748 -285.528004) (xy 382.474724 -285.627826) (xy 382.474724 -285.675578)
			(xy 382.674876 -285.675578)
		)
		(stroke
			(width 0)
			(type solid)
		)
		(fill yes)
		(layer "In2.Cu")
		(net "M_I_CPU0_SB_DQS_DP<2>")
	)
	(gr_poly
		(pts
			(xy 382.674876 -285.22422) (xy 382.674876 -285.17977) (xy 382.474724 -285.17977) (xy 382.474724 -285.22422)
			(xy 382.5748 -285.324296)
		)
		(stroke
			(width 0)
			(type solid)
		)
		(fill yes)
		(layer "In2.Cu")
		(net "M_I_CPU0_SB_DQ<19>")
	)
	(gr_poly
		(pts
			(xy 382.674876 -284.008068) (xy 382.5748 -283.907992) (xy 382.474724 -284.008068) (xy 382.474724 -284.052518)
			(xy 382.674876 -284.052518)
		)
		(stroke
			(width 0)
			(type solid)
		)
		(fill yes)
		(layer "In2.Cu")
		(net "M_I_CPU0_SB_DQ<16>")
	)
	(gr_poly
		(pts
			(xy 382.674876 -283.604208) (xy 382.674876 -283.559758) (xy 382.474724 -283.559758) (xy 382.474724 -283.604208)
			(xy 382.5748 -283.704284)
		)
		(stroke
			(width 0)
			(type solid)
		)
		(fill yes)
		(layer "In2.Cu")
		(net "M_I_CPU0_SB_DQ<15>")
	)
	(gr_poly
		(pts
			(xy 382.674876 -282.388056) (xy 382.5748 -282.28798) (xy 382.474724 -282.388056) (xy 382.474724 -282.432506)
			(xy 382.674876 -282.432506)
		)
		(stroke
			(width 0)
			(type solid)
		)
		(fill yes)
		(layer "In2.Cu")
		(net "M_I_CPU0_SB_DQ<12>")
	)
	(gr_poly
		(pts
			(xy 382.674876 -281.98445) (xy 382.674876 -281.936698) (xy 382.474724 -281.936698) (xy 382.474724 -281.98445)
			(xy 382.5748 -282.084272)
		)
		(stroke
			(width 0)
			(type solid)
		)
		(fill yes)
		(layer "In2.Cu")
		(net "M_I_CPU0_SB_DQS_DP<6>")
	)
	(gr_poly
		(pts
			(xy 382.674876 -280.76779) (xy 382.5748 -280.667968) (xy 382.474724 -280.76779) (xy 382.474724 -280.815542)
			(xy 382.674876 -280.815542)
		)
		(stroke
			(width 0)
			(type solid)
		)
		(fill yes)
		(layer "In2.Cu")
		(net "M_I_CPU0_SB_DQS_DP<1>")
	)
	(gr_poly
		(pts
			(xy 382.674876 -280.364184) (xy 382.674876 -280.319734) (xy 382.474724 -280.319734) (xy 382.474724 -280.364184)
			(xy 382.5748 -280.46426)
		)
		(stroke
			(width 0)
			(type solid)
		)
		(fill yes)
		(layer "In2.Cu")
		(net "M_I_CPU0_SB_DQ<11>")
	)
	(gr_poly
		(pts
			(xy 382.674876 -279.148032) (xy 382.5748 -279.047956) (xy 382.474724 -279.148032) (xy 382.474724 -279.192482)
			(xy 382.674876 -279.192482)
		)
		(stroke
			(width 0)
			(type solid)
		)
		(fill yes)
		(layer "In2.Cu")
		(net "M_I_CPU0_SB_DQ<8>")
	)
	(gr_poly
		(pts
			(xy 382.674876 -278.744172) (xy 382.674876 -278.699722) (xy 382.474724 -278.699722) (xy 382.474724 -278.744172)
			(xy 382.5748 -278.844248)
		)
		(stroke
			(width 0)
			(type solid)
		)
		(fill yes)
		(layer "In2.Cu")
		(net "M_I_CPU0_SB_DQ<7>")
	)
	(gr_poly
		(pts
			(xy 382.674876 -277.52802) (xy 382.5748 -277.427944) (xy 382.474724 -277.52802) (xy 382.474724 -277.57247)
			(xy 382.674876 -277.57247)
		)
		(stroke
			(width 0)
			(type solid)
		)
		(fill yes)
		(layer "In2.Cu")
		(net "M_I_CPU0_SB_DQ<4>")
	)
	(gr_poly
		(pts
			(xy 382.674876 -277.124414) (xy 382.674876 -277.076662) (xy 382.474724 -277.076662) (xy 382.474724 -277.124414)
			(xy 382.5748 -277.224236)
		)
		(stroke
			(width 0)
			(type solid)
		)
		(fill yes)
		(layer "In2.Cu")
		(net "M_I_CPU0_SB_DQS_DP<5>")
	)
	(gr_poly
		(pts
			(xy 382.674876 -275.907754) (xy 382.5748 -275.807932) (xy 382.474724 -275.907754) (xy 382.474724 -275.955506)
			(xy 382.674876 -275.955506)
		)
		(stroke
			(width 0)
			(type solid)
		)
		(fill yes)
		(layer "In2.Cu")
		(net "M_I_CPU0_SB_DQS_DP<0>")
	)
	(gr_poly
		(pts
			(xy 382.674876 -275.504148) (xy 382.674876 -275.459698) (xy 382.474724 -275.459698) (xy 382.474724 -275.504148)
			(xy 382.5748 -275.604224)
		)
		(stroke
			(width 0)
			(type solid)
		)
		(fill yes)
		(layer "In2.Cu")
		(net "M_I_CPU0_SB_DQ<3>")
	)
	(gr_poly
		(pts
			(xy 382.674876 -274.287996) (xy 382.5748 -274.18792) (xy 382.474724 -274.287996) (xy 382.474724 -274.332446)
			(xy 382.674876 -274.332446)
		)
		(stroke
			(width 0)
			(type solid)
		)
		(fill yes)
		(layer "In2.Cu")
		(net "M_I_CPU0_SB_DQ<0>")
	)
	(gr_poly
		(pts
			(xy 382.674876 -273.884136) (xy 382.674876 -273.839686) (xy 382.474724 -273.839686) (xy 382.474724 -273.884136)
			(xy 382.5748 -273.984212)
		)
		(stroke
			(width 0)
			(type solid)
		)
		(fill yes)
		(layer "In2.Cu")
		(net "M_I_CPU0_SB_CB<3>")
	)
	(gr_poly
		(pts
			(xy 382.674876 -272.667984) (xy 382.5748 -272.567908) (xy 382.474724 -272.667984) (xy 382.474724 -272.712434)
			(xy 382.674876 -272.712434)
		)
		(stroke
			(width 0)
			(type solid)
		)
		(fill yes)
		(layer "In2.Cu")
		(net "M_I_CPU0_SB_CB<0>")
	)
	(gr_poly
		(pts
			(xy 382.674876 -272.264378) (xy 382.674876 -272.216626) (xy 382.474724 -272.216626) (xy 382.474724 -272.264378)
			(xy 382.5748 -272.3642)
		)
		(stroke
			(width 0)
			(type solid)
		)
		(fill yes)
		(layer "In2.Cu")
		(net "M_I_CPU0_SB_DQS_DP<4>")
	)
	(gr_poly
		(pts
			(xy 382.674876 -271.047718) (xy 382.5748 -270.947896) (xy 382.474724 -271.047718) (xy 382.474724 -271.09547)
			(xy 382.674876 -271.09547)
		)
		(stroke
			(width 0)
			(type solid)
		)
		(fill yes)
		(layer "In2.Cu")
		(net "M_I_CPU0_SB_DQS_DP<9>")
	)
	(gr_poly
		(pts
			(xy 382.674876 -270.644112) (xy 382.674876 -270.599662) (xy 382.474724 -270.599662) (xy 382.474724 -270.644112)
			(xy 382.5748 -270.744188)
		)
		(stroke
			(width 0)
			(type solid)
		)
		(fill yes)
		(layer "In2.Cu")
		(net "M_I_CPU0_SB_CB<7>")
	)
	(gr_poly
		(pts
			(xy 382.674876 -269.42796) (xy 382.5748 -269.327884) (xy 382.474724 -269.42796) (xy 382.474724 -269.47241)
			(xy 382.674876 -269.47241)
		)
		(stroke
			(width 0)
			(type solid)
		)
		(fill yes)
		(layer "In2.Cu")
		(net "M_I_CPU0_SB_CB<4>")
	)
	(gr_poly
		(pts
			(xy 382.674876 -267.404088) (xy 382.674876 -267.359638) (xy 382.474724 -267.359638) (xy 382.474724 -267.404088)
			(xy 382.5748 -267.504164)
		)
		(stroke
			(width 0)
			(type solid)
		)
		(fill yes)
		(layer "In2.Cu")
		(net "M_I_CPU0_SB_RSP<0>")
	)
	(gr_poly
		(pts
			(xy 382.674876 -265.784076) (xy 382.674876 -265.739626) (xy 382.474724 -265.739626) (xy 382.474724 -265.784076)
			(xy 382.5748 -265.884152)
		)
		(stroke
			(width 0)
			(type solid)
		)
		(fill yes)
		(layer "In2.Cu")
		(net "M_I_CPU0_SB_CS_N<0>")
	)
	(gr_poly
		(pts
			(xy 382.674876 -264.567924) (xy 382.5748 -264.467848) (xy 382.474724 -264.567924) (xy 382.474724 -264.612374)
			(xy 382.674876 -264.612374)
		)
		(stroke
			(width 0)
			(type solid)
		)
		(fill yes)
		(layer "In2.Cu")
		(net "M_I_CPU0_SB_CA<6>")
	)
	(gr_poly
		(pts
			(xy 382.674876 -264.164064) (xy 382.674876 -264.119614) (xy 382.474724 -264.119614) (xy 382.474724 -264.164064)
			(xy 382.5748 -264.26414)
		)
		(stroke
			(width 0)
			(type solid)
		)
		(fill yes)
		(layer "In2.Cu")
		(net "M_I_CPU0_SB_CA<5>")
	)
	(gr_poly
		(pts
			(xy 382.674876 -262.947912) (xy 382.5748 -262.847836) (xy 382.474724 -262.947912) (xy 382.474724 -262.992362)
			(xy 382.674876 -262.992362)
		)
		(stroke
			(width 0)
			(type solid)
		)
		(fill yes)
		(layer "In2.Cu")
		(net "M_I_CPU0_SB_CA<2>")
	)
	(gr_poly
		(pts
			(xy 382.674876 -262.544052) (xy 382.674876 -262.499602) (xy 382.474724 -262.499602) (xy 382.474724 -262.544052)
			(xy 382.5748 -262.644128)
		)
		(stroke
			(width 0)
			(type solid)
		)
		(fill yes)
		(layer "In2.Cu")
		(net "M_I_CPU0_SB_CA<1>")
	)
	(gr_poly
		(pts
			(xy 382.844802 -256.025904) (xy 382.744726 -255.926082) (xy 382.64465 -256.025904) (xy 382.64465 -256.073656)
			(xy 382.844802 -256.073656)
		)
		(stroke
			(width 0)
			(type solid)
		)
		(fill yes)
		(layer "In2.Cu")
		(net "M_I_CPU0_CLK_DP<0>")
	)
	(gr_poly
		(pts
			(xy 382.844802 -255.622298) (xy 382.844802 -255.577848) (xy 382.64465 -255.577848) (xy 382.64465 -255.622298)
			(xy 382.744726 -255.722374)
		)
		(stroke
			(width 0)
			(type solid)
		)
		(fill yes)
		(layer "In2.Cu")
		(net "M_I_CPU0_SA_PAR")
	)
	(gr_poly
		(pts
			(xy 382.844802 -254.406146) (xy 382.744726 -254.30607) (xy 382.64465 -254.406146) (xy 382.64465 -254.450596)
			(xy 382.844802 -254.450596)
		)
		(stroke
			(width 0)
			(type solid)
		)
		(fill yes)
		(layer "In2.Cu")
		(net "M_I_CPU0_SA_CA<4>")
	)
	(gr_poly
		(pts
			(xy 382.844802 -254.002286) (xy 382.844802 -253.957836) (xy 382.64465 -253.957836) (xy 382.64465 -254.002286)
			(xy 382.744726 -254.102362)
		)
		(stroke
			(width 0)
			(type solid)
		)
		(fill yes)
		(layer "In2.Cu")
		(net "M_I_CPU0_SA_CA<3>")
	)
	(gr_poly
		(pts
			(xy 382.844802 -252.786134) (xy 382.744726 -252.686058) (xy 382.64465 -252.786134) (xy 382.64465 -252.830584)
			(xy 382.844802 -252.830584)
		)
		(stroke
			(width 0)
			(type solid)
		)
		(fill yes)
		(layer "In2.Cu")
		(net "M_I_CPU0_SA_CA<0>")
	)
	(gr_poly
		(pts
			(xy 382.844802 -251.166122) (xy 382.744726 -251.066046) (xy 382.64465 -251.166122) (xy 382.64465 -251.210572)
			(xy 382.844802 -251.210572)
		)
		(stroke
			(width 0)
			(type solid)
		)
		(fill yes)
		(layer "In2.Cu")
		(net "M_I_CPU0_SA_CS_N<0>")
	)
	(gr_poly
		(pts
			(xy 382.844802 -250.762262) (xy 382.844802 -250.717812) (xy 382.64465 -250.717812) (xy 382.64465 -250.762262)
			(xy 382.744726 -250.862338)
		)
		(stroke
			(width 0)
			(type solid)
		)
		(fill yes)
		(layer "In2.Cu")
		(net "M_I_CPU0_RESET_N")
	)
	(gr_poly
		(pts
			(xy 382.844802 -249.14225) (xy 382.844802 -249.0978) (xy 382.64465 -249.0978) (xy 382.64465 -249.14225)
			(xy 382.744726 -249.242326)
		)
		(stroke
			(width 0)
			(type solid)
		)
		(fill yes)
		(layer "In2.Cu")
		(net "M_I_CPU0_SA_CB<7>")
	)
	(gr_poly
		(pts
			(xy 382.844802 -247.926098) (xy 382.744726 -247.826022) (xy 382.64465 -247.926098) (xy 382.64465 -247.970548)
			(xy 382.844802 -247.970548)
		)
		(stroke
			(width 0)
			(type solid)
		)
		(fill yes)
		(layer "In2.Cu")
		(net "M_I_CPU0_SA_CB<4>")
	)
	(gr_poly
		(pts
			(xy 382.844802 -247.522492) (xy 382.844802 -247.47474) (xy 382.64465 -247.47474) (xy 382.64465 -247.522492)
			(xy 382.744726 -247.622314)
		)
		(stroke
			(width 0)
			(type solid)
		)
		(fill yes)
		(layer "In2.Cu")
		(net "M_I_CPU0_SA_DQS_DP<9>")
	)
	(gr_poly
		(pts
			(xy 382.844802 -246.305832) (xy 382.744726 -246.20601) (xy 382.64465 -246.305832) (xy 382.64465 -246.353584)
			(xy 382.844802 -246.353584)
		)
		(stroke
			(width 0)
			(type solid)
		)
		(fill yes)
		(layer "In2.Cu")
		(net "M_I_CPU0_SA_DQS_DP<4>")
	)
	(gr_poly
		(pts
			(xy 382.844802 -245.902226) (xy 382.844802 -245.857776) (xy 382.64465 -245.857776) (xy 382.64465 -245.902226)
			(xy 382.744726 -246.002302)
		)
		(stroke
			(width 0)
			(type solid)
		)
		(fill yes)
		(layer "In2.Cu")
		(net "M_I_CPU0_SA_CB<3>")
	)
	(gr_poly
		(pts
			(xy 382.844802 -244.686074) (xy 382.744726 -244.585998) (xy 382.64465 -244.686074) (xy 382.64465 -244.730524)
			(xy 382.844802 -244.730524)
		)
		(stroke
			(width 0)
			(type solid)
		)
		(fill yes)
		(layer "In2.Cu")
		(net "M_I_CPU0_SA_CB<0>")
	)
	(gr_poly
		(pts
			(xy 382.844802 -244.282214) (xy 382.844802 -244.237764) (xy 382.64465 -244.237764) (xy 382.64465 -244.282214)
			(xy 382.744726 -244.38229)
		)
		(stroke
			(width 0)
			(type solid)
		)
		(fill yes)
		(layer "In2.Cu")
		(net "M_I_CPU0_SA_DQ<31>")
	)
	(gr_poly
		(pts
			(xy 382.844802 -243.066062) (xy 382.744726 -242.965986) (xy 382.64465 -243.066062) (xy 382.64465 -243.110512)
			(xy 382.844802 -243.110512)
		)
		(stroke
			(width 0)
			(type solid)
		)
		(fill yes)
		(layer "In2.Cu")
		(net "M_I_CPU0_SA_DQ<28>")
	)
	(gr_poly
		(pts
			(xy 382.844802 -242.662456) (xy 382.844802 -242.614704) (xy 382.64465 -242.614704) (xy 382.64465 -242.662456)
			(xy 382.744726 -242.762278)
		)
		(stroke
			(width 0)
			(type solid)
		)
		(fill yes)
		(layer "In2.Cu")
		(net "M_I_CPU0_SA_DQS_DP<8>")
	)
	(gr_poly
		(pts
			(xy 382.844802 -241.445796) (xy 382.744726 -241.345974) (xy 382.64465 -241.445796) (xy 382.64465 -241.493548)
			(xy 382.844802 -241.493548)
		)
		(stroke
			(width 0)
			(type solid)
		)
		(fill yes)
		(layer "In2.Cu")
		(net "M_I_CPU0_SA_DQS_DP<3>")
	)
	(gr_poly
		(pts
			(xy 382.844802 -241.04219) (xy 382.844802 -240.99774) (xy 382.64465 -240.99774) (xy 382.64465 -241.04219)
			(xy 382.744726 -241.142266)
		)
		(stroke
			(width 0)
			(type solid)
		)
		(fill yes)
		(layer "In2.Cu")
		(net "M_I_CPU0_SA_DQ<27>")
	)
	(gr_poly
		(pts
			(xy 382.844802 -239.826038) (xy 382.744726 -239.725962) (xy 382.64465 -239.826038) (xy 382.64465 -239.870488)
			(xy 382.844802 -239.870488)
		)
		(stroke
			(width 0)
			(type solid)
		)
		(fill yes)
		(layer "In2.Cu")
		(net "M_I_CPU0_SA_DQ<24>")
	)
	(gr_poly
		(pts
			(xy 382.844802 -239.422178) (xy 382.844802 -239.377728) (xy 382.64465 -239.377728) (xy 382.64465 -239.422178)
			(xy 382.744726 -239.522254)
		)
		(stroke
			(width 0)
			(type solid)
		)
		(fill yes)
		(layer "In2.Cu")
		(net "M_I_CPU0_SA_DQ<23>")
	)
	(gr_poly
		(pts
			(xy 382.844802 -238.206026) (xy 382.744726 -238.10595) (xy 382.64465 -238.206026) (xy 382.64465 -238.250476)
			(xy 382.844802 -238.250476)
		)
		(stroke
			(width 0)
			(type solid)
		)
		(fill yes)
		(layer "In2.Cu")
		(net "M_I_CPU0_SA_DQ<20>")
	)
	(gr_poly
		(pts
			(xy 382.844802 -237.80242) (xy 382.844802 -237.754668) (xy 382.64465 -237.754668) (xy 382.64465 -237.80242)
			(xy 382.744726 -237.902242)
		)
		(stroke
			(width 0)
			(type solid)
		)
		(fill yes)
		(layer "In2.Cu")
		(net "M_I_CPU0_SA_DQS_DP<7>")
	)
	(gr_poly
		(pts
			(xy 382.844802 -236.58576) (xy 382.744726 -236.485938) (xy 382.64465 -236.58576) (xy 382.64465 -236.633512)
			(xy 382.844802 -236.633512)
		)
		(stroke
			(width 0)
			(type solid)
		)
		(fill yes)
		(layer "In2.Cu")
		(net "M_I_CPU0_SA_DQS_DP<2>")
	)
	(gr_poly
		(pts
			(xy 382.844802 -236.182154) (xy 382.844802 -236.137704) (xy 382.64465 -236.137704) (xy 382.64465 -236.182154)
			(xy 382.744726 -236.28223)
		)
		(stroke
			(width 0)
			(type solid)
		)
		(fill yes)
		(layer "In2.Cu")
		(net "M_I_CPU0_SA_DQ<19>")
	)
	(gr_poly
		(pts
			(xy 382.844802 -234.966002) (xy 382.744726 -234.865926) (xy 382.64465 -234.966002) (xy 382.64465 -235.010452)
			(xy 382.844802 -235.010452)
		)
		(stroke
			(width 0)
			(type solid)
		)
		(fill yes)
		(layer "In2.Cu")
		(net "M_I_CPU0_SA_DQ<16>")
	)
	(gr_poly
		(pts
			(xy 382.844802 -234.562142) (xy 382.844802 -234.517692) (xy 382.64465 -234.517692) (xy 382.64465 -234.562142)
			(xy 382.744726 -234.662218)
		)
		(stroke
			(width 0)
			(type solid)
		)
		(fill yes)
		(layer "In2.Cu")
		(net "M_I_CPU0_SA_DQ<15>")
	)
	(gr_poly
		(pts
			(xy 382.844802 -233.34599) (xy 382.744726 -233.245914) (xy 382.64465 -233.34599) (xy 382.64465 -233.39044)
			(xy 382.844802 -233.39044)
		)
		(stroke
			(width 0)
			(type solid)
		)
		(fill yes)
		(layer "In2.Cu")
		(net "M_I_CPU0_SA_DQ<12>")
	)
	(gr_poly
		(pts
			(xy 382.844802 -232.942384) (xy 382.844802 -232.894632) (xy 382.64465 -232.894632) (xy 382.64465 -232.942384)
			(xy 382.744726 -233.042206)
		)
		(stroke
			(width 0)
			(type solid)
		)
		(fill yes)
		(layer "In2.Cu")
		(net "M_I_CPU0_SA_DQS_DP<6>")
	)
	(gr_poly
		(pts
			(xy 382.844802 -231.725724) (xy 382.744726 -231.625902) (xy 382.64465 -231.725724) (xy 382.64465 -231.773476)
			(xy 382.844802 -231.773476)
		)
		(stroke
			(width 0)
			(type solid)
		)
		(fill yes)
		(layer "In2.Cu")
		(net "M_I_CPU0_SA_DQS_DP<1>")
	)
	(gr_poly
		(pts
			(xy 382.844802 -231.322372) (xy 382.844802 -231.277922) (xy 382.64465 -231.277922) (xy 382.64465 -231.322372)
			(xy 382.744726 -231.422448)
		)
		(stroke
			(width 0)
			(type solid)
		)
		(fill yes)
		(layer "In2.Cu")
		(net "M_I_CPU0_SA_DQ<11>")
	)
	(gr_poly
		(pts
			(xy 382.844802 -230.105966) (xy 382.744726 -230.006144) (xy 382.64465 -230.105966) (xy 382.64465 -230.150416)
			(xy 382.844802 -230.150416)
		)
		(stroke
			(width 0)
			(type solid)
		)
		(fill yes)
		(layer "In2.Cu")
		(net "M_I_CPU0_SA_DQ<8>")
	)
	(gr_poly
		(pts
			(xy 382.844802 -229.70236) (xy 382.844802 -229.65791) (xy 382.64465 -229.65791) (xy 382.64465 -229.70236)
			(xy 382.744726 -229.802436)
		)
		(stroke
			(width 0)
			(type solid)
		)
		(fill yes)
		(layer "In2.Cu")
		(net "M_I_CPU0_SA_DQ<7>")
	)
	(gr_poly
		(pts
			(xy 382.844802 -228.486208) (xy 382.744726 -228.386132) (xy 382.64465 -228.486208) (xy 382.64465 -228.530658)
			(xy 382.844802 -228.530658)
		)
		(stroke
			(width 0)
			(type solid)
		)
		(fill yes)
		(layer "In2.Cu")
		(net "M_I_CPU0_SA_DQ<4>")
	)
	(gr_poly
		(pts
			(xy 382.844802 -228.082602) (xy 382.844802 -228.03485) (xy 382.64465 -228.03485) (xy 382.64465 -228.082602)
			(xy 382.744726 -228.182424)
		)
		(stroke
			(width 0)
			(type solid)
		)
		(fill yes)
		(layer "In2.Cu")
		(net "M_I_CPU0_SA_DQS_DP<5>")
	)
	(gr_poly
		(pts
			(xy 382.844802 -226.865942) (xy 382.744726 -226.76612) (xy 382.64465 -226.865942) (xy 382.64465 -226.913694)
			(xy 382.844802 -226.913694)
		)
		(stroke
			(width 0)
			(type solid)
		)
		(fill yes)
		(layer "In2.Cu")
		(net "M_I_CPU0_SA_DQS_DP<0>")
	)
	(gr_poly
		(pts
			(xy 382.844802 -226.462336) (xy 382.844802 -226.417886) (xy 382.64465 -226.417886) (xy 382.64465 -226.462336)
			(xy 382.744726 -226.562412)
		)
		(stroke
			(width 0)
			(type solid)
		)
		(fill yes)
		(layer "In2.Cu")
		(net "M_I_CPU0_SA_DQ<3>")
	)
	(gr_poly
		(pts
			(xy 382.844802 -225.246184) (xy 382.744726 -225.146108) (xy 382.64465 -225.246184) (xy 382.64465 -225.290634)
			(xy 382.844802 -225.290634)
		)
		(stroke
			(width 0)
			(type solid)
		)
		(fill yes)
		(layer "In2.Cu")
		(net "M_I_CPU0_SA_DQ<0>")
	)
	(gr_poly
		(pts
			(xy 383.144776 -292.91788) (xy 383.0447 -292.817804) (xy 382.944624 -292.91788) (xy 382.944624 -292.96233)
			(xy 383.144776 -292.96233)
		)
		(stroke
			(width 0)
			(type solid)
		)
		(fill yes)
		(layer "In2.Cu")
		(net "M_I_CPU0_SB_DQ<29>")
	)
	(gr_poly
		(pts
			(xy 383.144776 -292.51402) (xy 383.144776 -292.46957) (xy 382.944624 -292.46957) (xy 382.944624 -292.51402)
			(xy 383.0447 -292.614096)
		)
		(stroke
			(width 0)
			(type solid)
		)
		(fill yes)
		(layer "In2.Cu")
		(net "M_I_CPU0_SB_DQ<30>")
	)
	(gr_poly
		(pts
			(xy 383.144776 -291.297614) (xy 383.0447 -291.197792) (xy 382.944624 -291.297614) (xy 382.944624 -291.345366)
			(xy 383.144776 -291.345366)
		)
		(stroke
			(width 0)
			(type solid)
		)
		(fill yes)
		(layer "In2.Cu")
		(net "M_I_CPU0_SB_DQS_DN<8>")
	)
	(gr_poly
		(pts
			(xy 383.144776 -290.894262) (xy 383.144776 -290.84651) (xy 382.944624 -290.84651) (xy 382.944624 -290.894262)
			(xy 383.0447 -290.994084)
		)
		(stroke
			(width 0)
			(type solid)
		)
		(fill yes)
		(layer "In2.Cu")
		(net "M_I_CPU0_SB_DQS_DN<3>")
	)
	(gr_poly
		(pts
			(xy 383.144776 -289.677856) (xy 383.0447 -289.57778) (xy 382.944624 -289.677856) (xy 382.944624 -289.722306)
			(xy 383.144776 -289.722306)
		)
		(stroke
			(width 0)
			(type solid)
		)
		(fill yes)
		(layer "In2.Cu")
		(net "M_I_CPU0_SB_DQ<25>")
	)
	(gr_poly
		(pts
			(xy 383.144776 -289.273996) (xy 383.144776 -289.229546) (xy 382.944624 -289.229546) (xy 382.944624 -289.273996)
			(xy 383.0447 -289.374072)
		)
		(stroke
			(width 0)
			(type solid)
		)
		(fill yes)
		(layer "In2.Cu")
		(net "M_I_CPU0_SB_DQ<26>")
	)
	(gr_poly
		(pts
			(xy 383.144776 -288.057844) (xy 383.0447 -287.957768) (xy 382.944624 -288.057844) (xy 382.944624 -288.102294)
			(xy 383.144776 -288.102294)
		)
		(stroke
			(width 0)
			(type solid)
		)
		(fill yes)
		(layer "In2.Cu")
		(net "M_I_CPU0_SB_DQ<21>")
	)
	(gr_poly
		(pts
			(xy 383.144776 -287.654238) (xy 383.144776 -287.609788) (xy 382.944624 -287.609788) (xy 382.944624 -287.654238)
			(xy 383.0447 -287.75406)
		)
		(stroke
			(width 0)
			(type solid)
		)
		(fill yes)
		(layer "In2.Cu")
		(net "M_I_CPU0_SB_DQ<22>")
	)
	(gr_poly
		(pts
			(xy 383.144776 -286.437832) (xy 383.0447 -286.337756) (xy 382.944624 -286.437832) (xy 382.944624 -286.485584)
			(xy 383.144776 -286.485584)
		)
		(stroke
			(width 0)
			(type solid)
		)
		(fill yes)
		(layer "In2.Cu")
		(net "M_I_CPU0_SB_DQS_DN<7>")
	)
	(gr_poly
		(pts
			(xy 383.144776 -286.03448) (xy 383.144776 -285.986728) (xy 382.944624 -285.986728) (xy 382.944624 -286.03448)
			(xy 383.0447 -286.134302)
		)
		(stroke
			(width 0)
			(type solid)
		)
		(fill yes)
		(layer "In2.Cu")
		(net "M_I_CPU0_SB_DQS_DN<2>")
	)
	(gr_poly
		(pts
			(xy 383.144776 -284.818074) (xy 383.0447 -284.717998) (xy 382.944624 -284.818074) (xy 382.944624 -284.862524)
			(xy 383.144776 -284.862524)
		)
		(stroke
			(width 0)
			(type solid)
		)
		(fill yes)
		(layer "In2.Cu")
		(net "M_I_CPU0_SB_DQ<17>")
	)
	(gr_poly
		(pts
			(xy 383.144776 -284.414214) (xy 383.144776 -284.369764) (xy 382.944624 -284.369764) (xy 382.944624 -284.414214)
			(xy 383.0447 -284.51429)
		)
		(stroke
			(width 0)
			(type solid)
		)
		(fill yes)
		(layer "In2.Cu")
		(net "M_I_CPU0_SB_DQ<18>")
	)
	(gr_poly
		(pts
			(xy 383.144776 -283.198062) (xy 383.0447 -283.097986) (xy 382.944624 -283.198062) (xy 382.944624 -283.242512)
			(xy 383.144776 -283.242512)
		)
		(stroke
			(width 0)
			(type solid)
		)
		(fill yes)
		(layer "In2.Cu")
		(net "M_I_CPU0_SB_DQ<13>")
	)
	(gr_poly
		(pts
			(xy 383.144776 -282.794202) (xy 383.144776 -282.749752) (xy 382.944624 -282.749752) (xy 382.944624 -282.794202)
			(xy 383.0447 -282.894278)
		)
		(stroke
			(width 0)
			(type solid)
		)
		(fill yes)
		(layer "In2.Cu")
		(net "M_I_CPU0_SB_DQ<14>")
	)
	(gr_poly
		(pts
			(xy 383.144776 -281.577796) (xy 383.0447 -281.477974) (xy 382.944624 -281.577796) (xy 382.944624 -281.625548)
			(xy 383.144776 -281.625548)
		)
		(stroke
			(width 0)
			(type solid)
		)
		(fill yes)
		(layer "In2.Cu")
		(net "M_I_CPU0_SB_DQS_DN<6>")
	)
	(gr_poly
		(pts
			(xy 383.144776 -281.174444) (xy 383.144776 -281.126692) (xy 382.944624 -281.126692) (xy 382.944624 -281.174444)
			(xy 383.0447 -281.274266)
		)
		(stroke
			(width 0)
			(type solid)
		)
		(fill yes)
		(layer "In2.Cu")
		(net "M_I_CPU0_SB_DQS_DN<1>")
	)
	(gr_poly
		(pts
			(xy 383.144776 -279.958038) (xy 383.0447 -279.857962) (xy 382.944624 -279.958038) (xy 382.944624 -280.002488)
			(xy 383.144776 -280.002488)
		)
		(stroke
			(width 0)
			(type solid)
		)
		(fill yes)
		(layer "In2.Cu")
		(net "M_I_CPU0_SB_DQ<9>")
	)
	(gr_poly
		(pts
			(xy 383.144776 -279.554178) (xy 383.144776 -279.509728) (xy 382.944624 -279.509728) (xy 382.944624 -279.554178)
			(xy 383.0447 -279.654254)
		)
		(stroke
			(width 0)
			(type solid)
		)
		(fill yes)
		(layer "In2.Cu")
		(net "M_I_CPU0_SB_DQ<10>")
	)
	(gr_poly
		(pts
			(xy 383.144776 -278.338026) (xy 383.0447 -278.23795) (xy 382.944624 -278.338026) (xy 382.944624 -278.382476)
			(xy 383.144776 -278.382476)
		)
		(stroke
			(width 0)
			(type solid)
		)
		(fill yes)
		(layer "In2.Cu")
		(net "M_I_CPU0_SB_DQ<5>")
	)
	(gr_poly
		(pts
			(xy 383.144776 -277.934166) (xy 383.144776 -277.889716) (xy 382.944624 -277.889716) (xy 382.944624 -277.934166)
			(xy 383.0447 -278.034242)
		)
		(stroke
			(width 0)
			(type solid)
		)
		(fill yes)
		(layer "In2.Cu")
		(net "M_I_CPU0_SB_DQ<6>")
	)
	(gr_poly
		(pts
			(xy 383.144776 -276.71776) (xy 383.0447 -276.617938) (xy 382.944624 -276.71776) (xy 382.944624 -276.765512)
			(xy 383.144776 -276.765512)
		)
		(stroke
			(width 0)
			(type solid)
		)
		(fill yes)
		(layer "In2.Cu")
		(net "M_I_CPU0_SB_DQS_DN<5>")
	)
	(gr_poly
		(pts
			(xy 383.144776 -276.314408) (xy 383.144776 -276.266656) (xy 382.944624 -276.266656) (xy 382.944624 -276.314408)
			(xy 383.0447 -276.41423)
		)
		(stroke
			(width 0)
			(type solid)
		)
		(fill yes)
		(layer "In2.Cu")
		(net "M_I_CPU0_SB_DQS_DN<0>")
	)
	(gr_poly
		(pts
			(xy 383.144776 -275.098002) (xy 383.0447 -274.997926) (xy 382.944624 -275.098002) (xy 382.944624 -275.142452)
			(xy 383.144776 -275.142452)
		)
		(stroke
			(width 0)
			(type solid)
		)
		(fill yes)
		(layer "In2.Cu")
		(net "M_I_CPU0_SB_DQ<1>")
	)
	(gr_poly
		(pts
			(xy 383.144776 -274.694142) (xy 383.144776 -274.649692) (xy 382.944624 -274.649692) (xy 382.944624 -274.694142)
			(xy 383.0447 -274.794218)
		)
		(stroke
			(width 0)
			(type solid)
		)
		(fill yes)
		(layer "In2.Cu")
		(net "M_I_CPU0_SB_DQ<2>")
	)
	(gr_poly
		(pts
			(xy 383.144776 -273.47799) (xy 383.0447 -273.377914) (xy 382.944624 -273.47799) (xy 382.944624 -273.52244)
			(xy 383.144776 -273.52244)
		)
		(stroke
			(width 0)
			(type solid)
		)
		(fill yes)
		(layer "In2.Cu")
		(net "M_I_CPU0_SB_CB<1>")
	)
	(gr_poly
		(pts
			(xy 383.144776 -273.07413) (xy 383.144776 -273.02968) (xy 382.944624 -273.02968) (xy 382.944624 -273.07413)
			(xy 383.0447 -273.174206)
		)
		(stroke
			(width 0)
			(type solid)
		)
		(fill yes)
		(layer "In2.Cu")
		(net "M_I_CPU0_SB_CB<2>")
	)
	(gr_poly
		(pts
			(xy 383.144776 -271.857724) (xy 383.0447 -271.757902) (xy 382.944624 -271.857724) (xy 382.944624 -271.905476)
			(xy 383.144776 -271.905476)
		)
		(stroke
			(width 0)
			(type solid)
		)
		(fill yes)
		(layer "In2.Cu")
		(net "M_I_CPU0_SB_DQS_DN<4>")
	)
	(gr_poly
		(pts
			(xy 383.144776 -271.454372) (xy 383.144776 -271.40662) (xy 382.944624 -271.40662) (xy 382.944624 -271.454372)
			(xy 383.0447 -271.554194)
		)
		(stroke
			(width 0)
			(type solid)
		)
		(fill yes)
		(layer "In2.Cu")
		(net "M_I_CPU0_SB_DQS_DN<9>")
	)
	(gr_poly
		(pts
			(xy 383.144776 -270.237966) (xy 383.0447 -270.13789) (xy 382.944624 -270.237966) (xy 382.944624 -270.282416)
			(xy 383.144776 -270.282416)
		)
		(stroke
			(width 0)
			(type solid)
		)
		(fill yes)
		(layer "In2.Cu")
		(net "M_I_CPU0_SB_CB<5>")
	)
	(gr_poly
		(pts
			(xy 383.144776 -269.834106) (xy 383.144776 -269.789656) (xy 382.944624 -269.789656) (xy 382.944624 -269.834106)
			(xy 383.0447 -269.934182)
		)
		(stroke
			(width 0)
			(type solid)
		)
		(fill yes)
		(layer "In2.Cu")
		(net "M_I_CPU0_SB_CB<6>")
	)
	(gr_poly
		(pts
			(xy 383.144776 -266.997942) (xy 383.0447 -266.897866) (xy 382.944624 -266.997942) (xy 382.944624 -267.042392)
			(xy 383.144776 -267.042392)
		)
		(stroke
			(width 0)
			(type solid)
		)
		(fill yes)
		(layer "In2.Cu")
		(net "M_I_CPU0_SA_RSP<0>")
	)
	(gr_poly
		(pts
			(xy 383.144776 -266.594082) (xy 383.144776 -266.549632) (xy 382.944624 -266.549632) (xy 382.944624 -266.594082)
			(xy 383.0447 -266.694158)
		)
		(stroke
			(width 0)
			(type solid)
		)
		(fill yes)
		(layer "In2.Cu")
		(net "M_I_CPU0_SB_CS_N<1>")
	)
	(gr_poly
		(pts
			(xy 383.144776 -265.37793) (xy 383.0447 -265.277854) (xy 382.944624 -265.37793) (xy 382.944624 -265.42238)
			(xy 383.144776 -265.42238)
		)
		(stroke
			(width 0)
			(type solid)
		)
		(fill yes)
		(layer "In2.Cu")
		(net "M_I_CPU0_SB_PAR")
	)
	(gr_poly
		(pts
			(xy 383.144776 -263.757918) (xy 383.0447 -263.657842) (xy 382.944624 -263.757918) (xy 382.944624 -263.802368)
			(xy 383.144776 -263.802368)
		)
		(stroke
			(width 0)
			(type solid)
		)
		(fill yes)
		(layer "In2.Cu")
		(net "M_I_CPU0_SB_CA<4>")
	)
	(gr_poly
		(pts
			(xy 383.144776 -263.354058) (xy 383.144776 -263.309608) (xy 382.944624 -263.309608) (xy 382.944624 -263.354058)
			(xy 383.0447 -263.454134)
		)
		(stroke
			(width 0)
			(type solid)
		)
		(fill yes)
		(layer "In2.Cu")
		(net "M_I_CPU0_SB_CA<3>")
	)
	(gr_poly
		(pts
			(xy 383.144776 -262.137906) (xy 383.0447 -262.03783) (xy 382.944624 -262.137906) (xy 382.944624 -262.182356)
			(xy 383.144776 -262.182356)
		)
		(stroke
			(width 0)
			(type solid)
		)
		(fill yes)
		(layer "In2.Cu")
		(net "M_I_CPU0_SB_CA<0>")
	)
	(gr_poly
		(pts
			(xy 383.314956 -256.432558) (xy 383.314956 -256.384806) (xy 383.114804 -256.384806) (xy 383.114804 -256.432558)
			(xy 383.21488 -256.53238)
		)
		(stroke
			(width 0)
			(type solid)
		)
		(fill yes)
		(layer "In2.Cu")
		(net "M_I_CPU0_CLK_DN<0>")
	)
	(gr_poly
		(pts
			(xy 383.314956 -255.216152) (xy 383.21488 -255.116076) (xy 383.114804 -255.216152) (xy 383.114804 -255.260602)
			(xy 383.314956 -255.260602)
		)
		(stroke
			(width 0)
			(type solid)
		)
		(fill yes)
		(layer "In2.Cu")
		(net "M_I_CPU0_SA_CA<6>")
	)
	(gr_poly
		(pts
			(xy 383.314956 -254.812292) (xy 383.314956 -254.767842) (xy 383.114804 -254.767842) (xy 383.114804 -254.812292)
			(xy 383.21488 -254.912368)
		)
		(stroke
			(width 0)
			(type solid)
		)
		(fill yes)
		(layer "In2.Cu")
		(net "M_I_CPU0_SA_CA<5>")
	)
	(gr_poly
		(pts
			(xy 383.314956 -253.59614) (xy 383.21488 -253.496064) (xy 383.114804 -253.59614) (xy 383.114804 -253.64059)
			(xy 383.314956 -253.64059)
		)
		(stroke
			(width 0)
			(type solid)
		)
		(fill yes)
		(layer "In2.Cu")
		(net "M_I_CPU0_SA_CA<2>")
	)
	(gr_poly
		(pts
			(xy 383.314956 -253.19228) (xy 383.314956 -253.14783) (xy 383.114804 -253.14783) (xy 383.114804 -253.19228)
			(xy 383.21488 -253.292356)
		)
		(stroke
			(width 0)
			(type solid)
		)
		(fill yes)
		(layer "In2.Cu")
		(net "M_I_CPU0_SA_CA<1>")
	)
	(gr_poly
		(pts
			(xy 383.314956 -251.976128) (xy 383.21488 -251.876052) (xy 383.114804 -251.976128) (xy 383.114804 -252.020578)
			(xy 383.314956 -252.020578)
		)
		(stroke
			(width 0)
			(type solid)
		)
		(fill yes)
		(layer "In2.Cu")
		(net "M_I_CPU0_SA_CS_N<1>")
	)
	(gr_poly
		(pts
			(xy 383.314956 -250.356116) (xy 383.21488 -250.25604) (xy 383.114804 -250.356116) (xy 383.114804 -250.400566)
			(xy 383.314956 -250.400566)
		)
		(stroke
			(width 0)
			(type solid)
		)
		(fill yes)
		(layer "In2.Cu")
		(net "M_I_CPU0_ALERT_R_N")
	)
	(gr_poly
		(pts
			(xy 383.314956 -248.736104) (xy 383.21488 -248.636028) (xy 383.114804 -248.736104) (xy 383.114804 -248.780554)
			(xy 383.314956 -248.780554)
		)
		(stroke
			(width 0)
			(type solid)
		)
		(fill yes)
		(layer "In2.Cu")
		(net "M_I_CPU0_SA_CB<5>")
	)
	(gr_poly
		(pts
			(xy 383.314956 -248.332244) (xy 383.314956 -248.287794) (xy 383.114804 -248.287794) (xy 383.114804 -248.332244)
			(xy 383.21488 -248.43232)
		)
		(stroke
			(width 0)
			(type solid)
		)
		(fill yes)
		(layer "In2.Cu")
		(net "M_I_CPU0_SA_CB<6>")
	)
	(gr_poly
		(pts
			(xy 383.314956 -247.115838) (xy 383.21488 -247.016016) (xy 383.114804 -247.115838) (xy 383.114804 -247.16359)
			(xy 383.314956 -247.16359)
		)
		(stroke
			(width 0)
			(type solid)
		)
		(fill yes)
		(layer "In2.Cu")
		(net "M_I_CPU0_SA_DQS_DN<9>")
	)
	(gr_poly
		(pts
			(xy 383.314956 -246.712486) (xy 383.314956 -246.664734) (xy 383.114804 -246.664734) (xy 383.114804 -246.712486)
			(xy 383.21488 -246.812308)
		)
		(stroke
			(width 0)
			(type solid)
		)
		(fill yes)
		(layer "In2.Cu")
		(net "M_I_CPU0_SA_DQS_DN<4>")
	)
	(gr_poly
		(pts
			(xy 383.314956 -245.49608) (xy 383.21488 -245.396004) (xy 383.114804 -245.49608) (xy 383.114804 -245.54053)
			(xy 383.314956 -245.54053)
		)
		(stroke
			(width 0)
			(type solid)
		)
		(fill yes)
		(layer "In2.Cu")
		(net "M_I_CPU0_SA_CB<1>")
	)
	(gr_poly
		(pts
			(xy 383.314956 -245.09222) (xy 383.314956 -245.04777) (xy 383.114804 -245.04777) (xy 383.114804 -245.09222)
			(xy 383.21488 -245.192296)
		)
		(stroke
			(width 0)
			(type solid)
		)
		(fill yes)
		(layer "In2.Cu")
		(net "M_I_CPU0_SA_CB<2>")
	)
	(gr_poly
		(pts
			(xy 383.314956 -243.876068) (xy 383.21488 -243.775992) (xy 383.114804 -243.876068) (xy 383.114804 -243.920518)
			(xy 383.314956 -243.920518)
		)
		(stroke
			(width 0)
			(type solid)
		)
		(fill yes)
		(layer "In2.Cu")
		(net "M_I_CPU0_SA_DQ<29>")
	)
	(gr_poly
		(pts
			(xy 383.314956 -243.472208) (xy 383.314956 -243.427758) (xy 383.114804 -243.427758) (xy 383.114804 -243.472208)
			(xy 383.21488 -243.572284)
		)
		(stroke
			(width 0)
			(type solid)
		)
		(fill yes)
		(layer "In2.Cu")
		(net "M_I_CPU0_SA_DQ<30>")
	)
	(gr_poly
		(pts
			(xy 383.314956 -242.255802) (xy 383.21488 -242.15598) (xy 383.114804 -242.255802) (xy 383.114804 -242.303554)
			(xy 383.314956 -242.303554)
		)
		(stroke
			(width 0)
			(type solid)
		)
		(fill yes)
		(layer "In2.Cu")
		(net "M_I_CPU0_SA_DQS_DN<8>")
	)
	(gr_poly
		(pts
			(xy 383.314956 -241.85245) (xy 383.314956 -241.804698) (xy 383.114804 -241.804698) (xy 383.114804 -241.85245)
			(xy 383.21488 -241.952272)
		)
		(stroke
			(width 0)
			(type solid)
		)
		(fill yes)
		(layer "In2.Cu")
		(net "M_I_CPU0_SA_DQS_DN<3>")
	)
	(gr_poly
		(pts
			(xy 383.314956 -240.636044) (xy 383.21488 -240.535968) (xy 383.114804 -240.636044) (xy 383.114804 -240.680494)
			(xy 383.314956 -240.680494)
		)
		(stroke
			(width 0)
			(type solid)
		)
		(fill yes)
		(layer "In2.Cu")
		(net "M_I_CPU0_SA_DQ<25>")
	)
	(gr_poly
		(pts
			(xy 383.314956 -240.232184) (xy 383.314956 -240.187734) (xy 383.114804 -240.187734) (xy 383.114804 -240.232184)
			(xy 383.21488 -240.33226)
		)
		(stroke
			(width 0)
			(type solid)
		)
		(fill yes)
		(layer "In2.Cu")
		(net "M_I_CPU0_SA_DQ<26>")
	)
	(gr_poly
		(pts
			(xy 383.314956 -239.016032) (xy 383.21488 -238.915956) (xy 383.114804 -239.016032) (xy 383.114804 -239.060482)
			(xy 383.314956 -239.060482)
		)
		(stroke
			(width 0)
			(type solid)
		)
		(fill yes)
		(layer "In2.Cu")
		(net "M_I_CPU0_SA_DQ<21>")
	)
	(gr_poly
		(pts
			(xy 383.314956 -238.612172) (xy 383.314956 -238.567722) (xy 383.114804 -238.567722) (xy 383.114804 -238.612172)
			(xy 383.21488 -238.712248)
		)
		(stroke
			(width 0)
			(type solid)
		)
		(fill yes)
		(layer "In2.Cu")
		(net "M_I_CPU0_SA_DQ<22>")
	)
	(gr_poly
		(pts
			(xy 383.314956 -237.395766) (xy 383.21488 -237.295944) (xy 383.114804 -237.395766) (xy 383.114804 -237.443518)
			(xy 383.314956 -237.443518)
		)
		(stroke
			(width 0)
			(type solid)
		)
		(fill yes)
		(layer "In2.Cu")
		(net "M_I_CPU0_SA_DQS_DN<7>")
	)
	(gr_poly
		(pts
			(xy 383.314956 -236.992414) (xy 383.314956 -236.944662) (xy 383.114804 -236.944662) (xy 383.114804 -236.992414)
			(xy 383.21488 -237.092236)
		)
		(stroke
			(width 0)
			(type solid)
		)
		(fill yes)
		(layer "In2.Cu")
		(net "M_I_CPU0_SA_DQS_DN<2>")
	)
	(gr_poly
		(pts
			(xy 383.314956 -235.776008) (xy 383.21488 -235.675932) (xy 383.114804 -235.776008) (xy 383.114804 -235.820458)
			(xy 383.314956 -235.820458)
		)
		(stroke
			(width 0)
			(type solid)
		)
		(fill yes)
		(layer "In2.Cu")
		(net "M_I_CPU0_SA_DQ<17>")
	)
	(gr_poly
		(pts
			(xy 383.314956 -235.372148) (xy 383.314956 -235.327698) (xy 383.114804 -235.327698) (xy 383.114804 -235.372148)
			(xy 383.21488 -235.472224)
		)
		(stroke
			(width 0)
			(type solid)
		)
		(fill yes)
		(layer "In2.Cu")
		(net "M_I_CPU0_SA_DQ<18>")
	)
	(gr_poly
		(pts
			(xy 383.314956 -234.155996) (xy 383.21488 -234.05592) (xy 383.114804 -234.155996) (xy 383.114804 -234.200446)
			(xy 383.314956 -234.200446)
		)
		(stroke
			(width 0)
			(type solid)
		)
		(fill yes)
		(layer "In2.Cu")
		(net "M_I_CPU0_SA_DQ<13>")
	)
	(gr_poly
		(pts
			(xy 383.314956 -233.752136) (xy 383.314956 -233.707686) (xy 383.114804 -233.707686) (xy 383.114804 -233.752136)
			(xy 383.21488 -233.852212)
		)
		(stroke
			(width 0)
			(type solid)
		)
		(fill yes)
		(layer "In2.Cu")
		(net "M_I_CPU0_SA_DQ<14>")
	)
	(gr_poly
		(pts
			(xy 383.314956 -232.53573) (xy 383.21488 -232.435908) (xy 383.114804 -232.53573) (xy 383.114804 -232.583482)
			(xy 383.314956 -232.583482)
		)
		(stroke
			(width 0)
			(type solid)
		)
		(fill yes)
		(layer "In2.Cu")
		(net "M_I_CPU0_SA_DQS_DN<6>")
	)
	(gr_poly
		(pts
			(xy 383.314956 -232.132378) (xy 383.314956 -232.084626) (xy 383.114804 -232.084626) (xy 383.114804 -232.132378)
			(xy 383.21488 -232.2322)
		)
		(stroke
			(width 0)
			(type solid)
		)
		(fill yes)
		(layer "In2.Cu")
		(net "M_I_CPU0_SA_DQS_DN<1>")
	)
	(gr_poly
		(pts
			(xy 383.314956 -230.915972) (xy 383.21488 -230.815896) (xy 383.114804 -230.915972) (xy 383.114804 -230.960422)
			(xy 383.314956 -230.960422)
		)
		(stroke
			(width 0)
			(type solid)
		)
		(fill yes)
		(layer "In2.Cu")
		(net "M_I_CPU0_SA_DQ<9>")
	)
	(gr_poly
		(pts
			(xy 383.314956 -230.512366) (xy 383.314956 -230.467916) (xy 383.114804 -230.467916) (xy 383.114804 -230.512366)
			(xy 383.21488 -230.612188)
		)
		(stroke
			(width 0)
			(type solid)
		)
		(fill yes)
		(layer "In2.Cu")
		(net "M_I_CPU0_SA_DQ<10>")
	)
	(gr_poly
		(pts
			(xy 383.314956 -229.29596) (xy 383.21488 -229.195884) (xy 383.114804 -229.29596) (xy 383.114804 -229.34041)
			(xy 383.314956 -229.34041)
		)
		(stroke
			(width 0)
			(type solid)
		)
		(fill yes)
		(layer "In2.Cu")
		(net "M_I_CPU0_SA_DQ<5>")
	)
	(gr_poly
		(pts
			(xy 383.314956 -228.892354) (xy 383.314956 -228.847904) (xy 383.114804 -228.847904) (xy 383.114804 -228.892354)
			(xy 383.21488 -228.99243)
		)
		(stroke
			(width 0)
			(type solid)
		)
		(fill yes)
		(layer "In2.Cu")
		(net "M_I_CPU0_SA_DQ<6>")
	)
	(gr_poly
		(pts
			(xy 383.314956 -227.675948) (xy 383.21488 -227.576126) (xy 383.114804 -227.675948) (xy 383.114804 -227.7237)
			(xy 383.314956 -227.7237)
		)
		(stroke
			(width 0)
			(type solid)
		)
		(fill yes)
		(layer "In2.Cu")
		(net "M_I_CPU0_SA_DQS_DN<5>")
	)
	(gr_poly
		(pts
			(xy 383.314956 -227.272596) (xy 383.314956 -227.224844) (xy 383.114804 -227.224844) (xy 383.114804 -227.272596)
			(xy 383.21488 -227.372418)
		)
		(stroke
			(width 0)
			(type solid)
		)
		(fill yes)
		(layer "In2.Cu")
		(net "M_I_CPU0_SA_DQS_DN<0>")
	)
	(gr_poly
		(pts
			(xy 383.314956 -226.05619) (xy 383.21488 -225.956114) (xy 383.114804 -226.05619) (xy 383.114804 -226.10064)
			(xy 383.314956 -226.10064)
		)
		(stroke
			(width 0)
			(type solid)
		)
		(fill yes)
		(layer "In2.Cu")
		(net "M_I_CPU0_SA_DQ<1>")
	)
	(gr_poly
		(pts
			(xy 383.314956 -225.65233) (xy 383.314956 -225.60788) (xy 383.114804 -225.60788) (xy 383.114804 -225.65233)
			(xy 383.21488 -225.752406)
		)
		(stroke
			(width 0)
			(type solid)
		)
		(fill yes)
		(layer "In2.Cu")
		(net "M_I_CPU0_SA_DQ<2>")
	)
	(gr_poly
		(pts
			(xy 383.61493 -293.324026) (xy 383.61493 -293.279576) (xy 383.414778 -293.279576) (xy 383.414778 -293.324026)
			(xy 383.514854 -293.424102)
		)
		(stroke
			(width 0)
			(type solid)
		)
		(fill yes)
		(layer "In2.Cu")
		(net "M_I_CPU0_SB_DQ<31>")
	)
	(gr_poly
		(pts
			(xy 383.61493 -292.107874) (xy 383.514854 -292.007798) (xy 383.414778 -292.107874) (xy 383.414778 -292.152324)
			(xy 383.61493 -292.152324)
		)
		(stroke
			(width 0)
			(type solid)
		)
		(fill yes)
		(layer "In2.Cu")
		(net "M_I_CPU0_SB_DQ<28>")
	)
	(gr_poly
		(pts
			(xy 383.61493 -291.704268) (xy 383.61493 -291.656516) (xy 383.414778 -291.656516) (xy 383.414778 -291.704268)
			(xy 383.514854 -291.80409)
		)
		(stroke
			(width 0)
			(type solid)
		)
		(fill yes)
		(layer "In2.Cu")
		(net "M_I_CPU0_SB_DQS_DP<8>")
	)
	(gr_poly
		(pts
			(xy 383.61493 -290.487608) (xy 383.514854 -290.387786) (xy 383.414778 -290.487608) (xy 383.414778 -290.53536)
			(xy 383.61493 -290.53536)
		)
		(stroke
			(width 0)
			(type solid)
		)
		(fill yes)
		(layer "In2.Cu")
		(net "M_I_CPU0_SB_DQS_DP<3>")
	)
	(gr_poly
		(pts
			(xy 383.61493 -290.084002) (xy 383.61493 -290.039552) (xy 383.414778 -290.039552) (xy 383.414778 -290.084002)
			(xy 383.514854 -290.184078)
		)
		(stroke
			(width 0)
			(type solid)
		)
		(fill yes)
		(layer "In2.Cu")
		(net "M_I_CPU0_SB_DQ<27>")
	)
	(gr_poly
		(pts
			(xy 383.61493 -288.86785) (xy 383.514854 -288.767774) (xy 383.414778 -288.86785) (xy 383.414778 -288.9123)
			(xy 383.61493 -288.9123)
		)
		(stroke
			(width 0)
			(type solid)
		)
		(fill yes)
		(layer "In2.Cu")
		(net "M_I_CPU0_SB_DQ<24>")
	)
	(gr_poly
		(pts
			(xy 383.61493 -288.464244) (xy 383.61493 -288.419794) (xy 383.414778 -288.419794) (xy 383.414778 -288.464244)
			(xy 383.514854 -288.56432)
		)
		(stroke
			(width 0)
			(type solid)
		)
		(fill yes)
		(layer "In2.Cu")
		(net "M_I_CPU0_SB_DQ<23>")
	)
	(gr_poly
		(pts
			(xy 383.61493 -287.247838) (xy 383.514854 -287.148016) (xy 383.414778 -287.247838) (xy 383.414778 -287.292288)
			(xy 383.61493 -287.292288)
		)
		(stroke
			(width 0)
			(type solid)
		)
		(fill yes)
		(layer "In2.Cu")
		(net "M_I_CPU0_SB_DQ<20>")
	)
	(gr_poly
		(pts
			(xy 383.61493 -286.844232) (xy 383.61493 -286.79648) (xy 383.414778 -286.79648) (xy 383.414778 -286.844232)
			(xy 383.514854 -286.944308)
		)
		(stroke
			(width 0)
			(type solid)
		)
		(fill yes)
		(layer "In2.Cu")
		(net "M_I_CPU0_SB_DQS_DP<7>")
	)
	(gr_poly
		(pts
			(xy 383.61493 -285.627826) (xy 383.514854 -285.528004) (xy 383.414778 -285.627826) (xy 383.414778 -285.675578)
			(xy 383.61493 -285.675578)
		)
		(stroke
			(width 0)
			(type solid)
		)
		(fill yes)
		(layer "In2.Cu")
		(net "M_I_CPU0_SB_DQS_DP<2>")
	)
	(gr_poly
		(pts
			(xy 383.61493 -285.22422) (xy 383.61493 -285.17977) (xy 383.414778 -285.17977) (xy 383.414778 -285.22422)
			(xy 383.514854 -285.324296)
		)
		(stroke
			(width 0)
			(type solid)
		)
		(fill yes)
		(layer "In2.Cu")
		(net "M_I_CPU0_SB_DQ<19>")
	)
	(gr_poly
		(pts
			(xy 383.61493 -284.008068) (xy 383.514854 -283.907992) (xy 383.414778 -284.008068) (xy 383.414778 -284.052518)
			(xy 383.61493 -284.052518)
		)
		(stroke
			(width 0)
			(type solid)
		)
		(fill yes)
		(layer "In2.Cu")
		(net "M_I_CPU0_SB_DQ<16>")
	)
	(gr_poly
		(pts
			(xy 383.61493 -283.604208) (xy 383.61493 -283.559758) (xy 383.414778 -283.559758) (xy 383.414778 -283.604208)
			(xy 383.514854 -283.704284)
		)
		(stroke
			(width 0)
			(type solid)
		)
		(fill yes)
		(layer "In2.Cu")
		(net "M_I_CPU0_SB_DQ<15>")
	)
	(gr_poly
		(pts
			(xy 383.61493 -282.388056) (xy 383.514854 -282.28798) (xy 383.414778 -282.388056) (xy 383.414778 -282.432506)
			(xy 383.61493 -282.432506)
		)
		(stroke
			(width 0)
			(type solid)
		)
		(fill yes)
		(layer "In2.Cu")
		(net "M_I_CPU0_SB_DQ<12>")
	)
	(gr_poly
		(pts
			(xy 383.61493 -281.98445) (xy 383.61493 -281.936698) (xy 383.414778 -281.936698) (xy 383.414778 -281.98445)
			(xy 383.514854 -282.084272)
		)
		(stroke
			(width 0)
			(type solid)
		)
		(fill yes)
		(layer "In2.Cu")
		(net "M_I_CPU0_SB_DQS_DP<6>")
	)
	(gr_poly
		(pts
			(xy 383.61493 -280.76779) (xy 383.514854 -280.667968) (xy 383.414778 -280.76779) (xy 383.414778 -280.815542)
			(xy 383.61493 -280.815542)
		)
		(stroke
			(width 0)
			(type solid)
		)
		(fill yes)
		(layer "In2.Cu")
		(net "M_I_CPU0_SB_DQS_DP<1>")
	)
	(gr_poly
		(pts
			(xy 383.61493 -280.364184) (xy 383.61493 -280.319734) (xy 383.414778 -280.319734) (xy 383.414778 -280.364184)
			(xy 383.514854 -280.46426)
		)
		(stroke
			(width 0)
			(type solid)
		)
		(fill yes)
		(layer "In2.Cu")
		(net "M_I_CPU0_SB_DQ<11>")
	)
	(gr_poly
		(pts
			(xy 383.61493 -279.148032) (xy 383.514854 -279.047956) (xy 383.414778 -279.148032) (xy 383.414778 -279.192482)
			(xy 383.61493 -279.192482)
		)
		(stroke
			(width 0)
			(type solid)
		)
		(fill yes)
		(layer "In2.Cu")
		(net "M_I_CPU0_SB_DQ<8>")
	)
	(gr_poly
		(pts
			(xy 383.61493 -278.744172) (xy 383.61493 -278.699722) (xy 383.414778 -278.699722) (xy 383.414778 -278.744172)
			(xy 383.514854 -278.844248)
		)
		(stroke
			(width 0)
			(type solid)
		)
		(fill yes)
		(layer "In2.Cu")
		(net "M_I_CPU0_SB_DQ<7>")
	)
	(gr_poly
		(pts
			(xy 383.61493 -277.52802) (xy 383.514854 -277.427944) (xy 383.414778 -277.52802) (xy 383.414778 -277.57247)
			(xy 383.61493 -277.57247)
		)
		(stroke
			(width 0)
			(type solid)
		)
		(fill yes)
		(layer "In2.Cu")
		(net "M_I_CPU0_SB_DQ<4>")
	)
	(gr_poly
		(pts
			(xy 383.61493 -277.124414) (xy 383.61493 -277.076662) (xy 383.414778 -277.076662) (xy 383.414778 -277.124414)
			(xy 383.514854 -277.224236)
		)
		(stroke
			(width 0)
			(type solid)
		)
		(fill yes)
		(layer "In2.Cu")
		(net "M_I_CPU0_SB_DQS_DP<5>")
	)
	(gr_poly
		(pts
			(xy 383.61493 -275.907754) (xy 383.514854 -275.807932) (xy 383.414778 -275.907754) (xy 383.414778 -275.955506)
			(xy 383.61493 -275.955506)
		)
		(stroke
			(width 0)
			(type solid)
		)
		(fill yes)
		(layer "In2.Cu")
		(net "M_I_CPU0_SB_DQS_DP<0>")
	)
	(gr_poly
		(pts
			(xy 383.61493 -275.504148) (xy 383.61493 -275.459698) (xy 383.414778 -275.459698) (xy 383.414778 -275.504148)
			(xy 383.514854 -275.604224)
		)
		(stroke
			(width 0)
			(type solid)
		)
		(fill yes)
		(layer "In2.Cu")
		(net "M_I_CPU0_SB_DQ<3>")
	)
	(gr_poly
		(pts
			(xy 383.61493 -274.287996) (xy 383.514854 -274.18792) (xy 383.414778 -274.287996) (xy 383.414778 -274.332446)
			(xy 383.61493 -274.332446)
		)
		(stroke
			(width 0)
			(type solid)
		)
		(fill yes)
		(layer "In2.Cu")
		(net "M_I_CPU0_SB_DQ<0>")
	)
	(gr_poly
		(pts
			(xy 383.61493 -273.884136) (xy 383.61493 -273.839686) (xy 383.414778 -273.839686) (xy 383.414778 -273.884136)
			(xy 383.514854 -273.984212)
		)
		(stroke
			(width 0)
			(type solid)
		)
		(fill yes)
		(layer "In2.Cu")
		(net "M_I_CPU0_SB_CB<3>")
	)
	(gr_poly
		(pts
			(xy 383.61493 -272.667984) (xy 383.514854 -272.567908) (xy 383.414778 -272.667984) (xy 383.414778 -272.712434)
			(xy 383.61493 -272.712434)
		)
		(stroke
			(width 0)
			(type solid)
		)
		(fill yes)
		(layer "In2.Cu")
		(net "M_I_CPU0_SB_CB<0>")
	)
	(gr_poly
		(pts
			(xy 383.61493 -272.264378) (xy 383.61493 -272.216626) (xy 383.414778 -272.216626) (xy 383.414778 -272.264378)
			(xy 383.514854 -272.3642)
		)
		(stroke
			(width 0)
			(type solid)
		)
		(fill yes)
		(layer "In2.Cu")
		(net "M_I_CPU0_SB_DQS_DP<4>")
	)
	(gr_poly
		(pts
			(xy 383.61493 -271.047718) (xy 383.514854 -270.947896) (xy 383.414778 -271.047718) (xy 383.414778 -271.09547)
			(xy 383.61493 -271.09547)
		)
		(stroke
			(width 0)
			(type solid)
		)
		(fill yes)
		(layer "In2.Cu")
		(net "M_I_CPU0_SB_DQS_DP<9>")
	)
	(gr_poly
		(pts
			(xy 383.61493 -270.644112) (xy 383.61493 -270.599662) (xy 383.414778 -270.599662) (xy 383.414778 -270.644112)
			(xy 383.514854 -270.744188)
		)
		(stroke
			(width 0)
			(type solid)
		)
		(fill yes)
		(layer "In2.Cu")
		(net "M_I_CPU0_SB_CB<7>")
	)
	(gr_poly
		(pts
			(xy 383.61493 -269.42796) (xy 383.514854 -269.327884) (xy 383.414778 -269.42796) (xy 383.414778 -269.47241)
			(xy 383.61493 -269.47241)
		)
		(stroke
			(width 0)
			(type solid)
		)
		(fill yes)
		(layer "In2.Cu")
		(net "M_I_CPU0_SB_CB<4>")
	)
	(gr_poly
		(pts
			(xy 383.61493 -267.404088) (xy 383.61493 -267.359638) (xy 383.414778 -267.359638) (xy 383.414778 -267.404088)
			(xy 383.514854 -267.504164)
		)
		(stroke
			(width 0)
			(type solid)
		)
		(fill yes)
		(layer "In2.Cu")
		(net "M_I_CPU0_SB_RSP<0>")
	)
	(gr_poly
		(pts
			(xy 383.61493 -265.784076) (xy 383.61493 -265.739626) (xy 383.414778 -265.739626) (xy 383.414778 -265.784076)
			(xy 383.514854 -265.884152)
		)
		(stroke
			(width 0)
			(type solid)
		)
		(fill yes)
		(layer "In2.Cu")
		(net "M_I_CPU0_SB_CS_N<0>")
	)
	(gr_poly
		(pts
			(xy 383.61493 -264.567924) (xy 383.514854 -264.467848) (xy 383.414778 -264.567924) (xy 383.414778 -264.612374)
			(xy 383.61493 -264.612374)
		)
		(stroke
			(width 0)
			(type solid)
		)
		(fill yes)
		(layer "In2.Cu")
		(net "M_I_CPU0_SB_CA<6>")
	)
	(gr_poly
		(pts
			(xy 383.61493 -264.164064) (xy 383.61493 -264.119614) (xy 383.414778 -264.119614) (xy 383.414778 -264.164064)
			(xy 383.514854 -264.26414)
		)
		(stroke
			(width 0)
			(type solid)
		)
		(fill yes)
		(layer "In2.Cu")
		(net "M_I_CPU0_SB_CA<5>")
	)
	(gr_poly
		(pts
			(xy 383.61493 -262.947912) (xy 383.514854 -262.847836) (xy 383.414778 -262.947912) (xy 383.414778 -262.992362)
			(xy 383.61493 -262.992362)
		)
		(stroke
			(width 0)
			(type solid)
		)
		(fill yes)
		(layer "In2.Cu")
		(net "M_I_CPU0_SB_CA<2>")
	)
	(gr_poly
		(pts
			(xy 383.61493 -262.544052) (xy 383.61493 -262.499602) (xy 383.414778 -262.499602) (xy 383.414778 -262.544052)
			(xy 383.514854 -262.644128)
		)
		(stroke
			(width 0)
			(type solid)
		)
		(fill yes)
		(layer "In2.Cu")
		(net "M_I_CPU0_SB_CA<1>")
	)
	(gr_poly
		(pts
			(xy 383.784856 -256.025904) (xy 383.68478 -255.926082) (xy 383.584704 -256.025904) (xy 383.584704 -256.073656)
			(xy 383.784856 -256.073656)
		)
		(stroke
			(width 0)
			(type solid)
		)
		(fill yes)
		(layer "In2.Cu")
		(net "M_I_CPU0_CLK_DP<0>")
	)
	(gr_poly
		(pts
			(xy 383.784856 -255.622298) (xy 383.784856 -255.577848) (xy 383.584704 -255.577848) (xy 383.584704 -255.622298)
			(xy 383.68478 -255.722374)
		)
		(stroke
			(width 0)
			(type solid)
		)
		(fill yes)
		(layer "In2.Cu")
		(net "M_I_CPU0_SA_PAR")
	)
	(gr_poly
		(pts
			(xy 383.784856 -254.406146) (xy 383.68478 -254.30607) (xy 383.584704 -254.406146) (xy 383.584704 -254.450596)
			(xy 383.784856 -254.450596)
		)
		(stroke
			(width 0)
			(type solid)
		)
		(fill yes)
		(layer "In2.Cu")
		(net "M_I_CPU0_SA_CA<4>")
	)
	(gr_poly
		(pts
			(xy 383.784856 -254.002286) (xy 383.784856 -253.957836) (xy 383.584704 -253.957836) (xy 383.584704 -254.002286)
			(xy 383.68478 -254.102362)
		)
		(stroke
			(width 0)
			(type solid)
		)
		(fill yes)
		(layer "In2.Cu")
		(net "M_I_CPU0_SA_CA<3>")
	)
	(gr_poly
		(pts
			(xy 383.784856 -252.786134) (xy 383.68478 -252.686058) (xy 383.584704 -252.786134) (xy 383.584704 -252.830584)
			(xy 383.784856 -252.830584)
		)
		(stroke
			(width 0)
			(type solid)
		)
		(fill yes)
		(layer "In2.Cu")
		(net "M_I_CPU0_SA_CA<0>")
	)
	(gr_poly
		(pts
			(xy 383.784856 -251.166122) (xy 383.68478 -251.066046) (xy 383.584704 -251.166122) (xy 383.584704 -251.210572)
			(xy 383.784856 -251.210572)
		)
		(stroke
			(width 0)
			(type solid)
		)
		(fill yes)
		(layer "In2.Cu")
		(net "M_I_CPU0_SA_CS_N<0>")
	)
	(gr_poly
		(pts
			(xy 383.784856 -250.762262) (xy 383.784856 -250.717812) (xy 383.584704 -250.717812) (xy 383.584704 -250.762262)
			(xy 383.68478 -250.862338)
		)
		(stroke
			(width 0)
			(type solid)
		)
		(fill yes)
		(layer "In2.Cu")
		(net "M_I_CPU0_RESET_N")
	)
	(gr_poly
		(pts
			(xy 383.784856 -249.14225) (xy 383.784856 -249.0978) (xy 383.584704 -249.0978) (xy 383.584704 -249.14225)
			(xy 383.68478 -249.242326)
		)
		(stroke
			(width 0)
			(type solid)
		)
		(fill yes)
		(layer "In2.Cu")
		(net "M_I_CPU0_SA_CB<7>")
	)
	(gr_poly
		(pts
			(xy 383.784856 -247.926098) (xy 383.68478 -247.826022) (xy 383.584704 -247.926098) (xy 383.584704 -247.970548)
			(xy 383.784856 -247.970548)
		)
		(stroke
			(width 0)
			(type solid)
		)
		(fill yes)
		(layer "In2.Cu")
		(net "M_I_CPU0_SA_CB<4>")
	)
	(gr_poly
		(pts
			(xy 383.784856 -247.522492) (xy 383.784856 -247.47474) (xy 383.584704 -247.47474) (xy 383.584704 -247.522492)
			(xy 383.68478 -247.622314)
		)
		(stroke
			(width 0)
			(type solid)
		)
		(fill yes)
		(layer "In2.Cu")
		(net "M_I_CPU0_SA_DQS_DP<9>")
	)
	(gr_poly
		(pts
			(xy 383.784856 -246.305832) (xy 383.68478 -246.20601) (xy 383.584704 -246.305832) (xy 383.584704 -246.353584)
			(xy 383.784856 -246.353584)
		)
		(stroke
			(width 0)
			(type solid)
		)
		(fill yes)
		(layer "In2.Cu")
		(net "M_I_CPU0_SA_DQS_DP<4>")
	)
	(gr_poly
		(pts
			(xy 383.784856 -245.902226) (xy 383.784856 -245.857776) (xy 383.584704 -245.857776) (xy 383.584704 -245.902226)
			(xy 383.68478 -246.002302)
		)
		(stroke
			(width 0)
			(type solid)
		)
		(fill yes)
		(layer "In2.Cu")
		(net "M_I_CPU0_SA_CB<3>")
	)
	(gr_poly
		(pts
			(xy 383.784856 -244.686074) (xy 383.68478 -244.585998) (xy 383.584704 -244.686074) (xy 383.584704 -244.730524)
			(xy 383.784856 -244.730524)
		)
		(stroke
			(width 0)
			(type solid)
		)
		(fill yes)
		(layer "In2.Cu")
		(net "M_I_CPU0_SA_CB<0>")
	)
	(gr_poly
		(pts
			(xy 383.784856 -244.282214) (xy 383.784856 -244.237764) (xy 383.584704 -244.237764) (xy 383.584704 -244.282214)
			(xy 383.68478 -244.38229)
		)
		(stroke
			(width 0)
			(type solid)
		)
		(fill yes)
		(layer "In2.Cu")
		(net "M_I_CPU0_SA_DQ<31>")
	)
	(gr_poly
		(pts
			(xy 383.784856 -243.066062) (xy 383.68478 -242.965986) (xy 383.584704 -243.066062) (xy 383.584704 -243.110512)
			(xy 383.784856 -243.110512)
		)
		(stroke
			(width 0)
			(type solid)
		)
		(fill yes)
		(layer "In2.Cu")
		(net "M_I_CPU0_SA_DQ<28>")
	)
	(gr_poly
		(pts
			(xy 383.784856 -242.662456) (xy 383.784856 -242.614704) (xy 383.584704 -242.614704) (xy 383.584704 -242.662456)
			(xy 383.68478 -242.762278)
		)
		(stroke
			(width 0)
			(type solid)
		)
		(fill yes)
		(layer "In2.Cu")
		(net "M_I_CPU0_SA_DQS_DP<8>")
	)
	(gr_poly
		(pts
			(xy 383.784856 -241.445796) (xy 383.68478 -241.345974) (xy 383.584704 -241.445796) (xy 383.584704 -241.493548)
			(xy 383.784856 -241.493548)
		)
		(stroke
			(width 0)
			(type solid)
		)
		(fill yes)
		(layer "In2.Cu")
		(net "M_I_CPU0_SA_DQS_DP<3>")
	)
	(gr_poly
		(pts
			(xy 383.784856 -241.04219) (xy 383.784856 -240.99774) (xy 383.584704 -240.99774) (xy 383.584704 -241.04219)
			(xy 383.68478 -241.142266)
		)
		(stroke
			(width 0)
			(type solid)
		)
		(fill yes)
		(layer "In2.Cu")
		(net "M_I_CPU0_SA_DQ<27>")
	)
	(gr_poly
		(pts
			(xy 383.784856 -239.826038) (xy 383.68478 -239.725962) (xy 383.584704 -239.826038) (xy 383.584704 -239.870488)
			(xy 383.784856 -239.870488)
		)
		(stroke
			(width 0)
			(type solid)
		)
		(fill yes)
		(layer "In2.Cu")
		(net "M_I_CPU0_SA_DQ<24>")
	)
	(gr_poly
		(pts
			(xy 383.784856 -239.422178) (xy 383.784856 -239.377728) (xy 383.584704 -239.377728) (xy 383.584704 -239.422178)
			(xy 383.68478 -239.522254)
		)
		(stroke
			(width 0)
			(type solid)
		)
		(fill yes)
		(layer "In2.Cu")
		(net "M_I_CPU0_SA_DQ<23>")
	)
	(gr_poly
		(pts
			(xy 383.784856 -238.206026) (xy 383.68478 -238.10595) (xy 383.584704 -238.206026) (xy 383.584704 -238.250476)
			(xy 383.784856 -238.250476)
		)
		(stroke
			(width 0)
			(type solid)
		)
		(fill yes)
		(layer "In2.Cu")
		(net "M_I_CPU0_SA_DQ<20>")
	)
	(gr_poly
		(pts
			(xy 383.784856 -237.80242) (xy 383.784856 -237.754668) (xy 383.584704 -237.754668) (xy 383.584704 -237.80242)
			(xy 383.68478 -237.902242)
		)
		(stroke
			(width 0)
			(type solid)
		)
		(fill yes)
		(layer "In2.Cu")
		(net "M_I_CPU0_SA_DQS_DP<7>")
	)
	(gr_poly
		(pts
			(xy 383.784856 -236.58576) (xy 383.68478 -236.485938) (xy 383.584704 -236.58576) (xy 383.584704 -236.633512)
			(xy 383.784856 -236.633512)
		)
		(stroke
			(width 0)
			(type solid)
		)
		(fill yes)
		(layer "In2.Cu")
		(net "M_I_CPU0_SA_DQS_DP<2>")
	)
	(gr_poly
		(pts
			(xy 383.784856 -236.182154) (xy 383.784856 -236.137704) (xy 383.584704 -236.137704) (xy 383.584704 -236.182154)
			(xy 383.68478 -236.28223)
		)
		(stroke
			(width 0)
			(type solid)
		)
		(fill yes)
		(layer "In2.Cu")
		(net "M_I_CPU0_SA_DQ<19>")
	)
	(gr_poly
		(pts
			(xy 383.784856 -234.966002) (xy 383.68478 -234.865926) (xy 383.584704 -234.966002) (xy 383.584704 -235.010452)
			(xy 383.784856 -235.010452)
		)
		(stroke
			(width 0)
			(type solid)
		)
		(fill yes)
		(layer "In2.Cu")
		(net "M_I_CPU0_SA_DQ<16>")
	)
	(gr_poly
		(pts
			(xy 383.784856 -234.562142) (xy 383.784856 -234.517692) (xy 383.584704 -234.517692) (xy 383.584704 -234.562142)
			(xy 383.68478 -234.662218)
		)
		(stroke
			(width 0)
			(type solid)
		)
		(fill yes)
		(layer "In2.Cu")
		(net "M_I_CPU0_SA_DQ<15>")
	)
	(gr_poly
		(pts
			(xy 383.784856 -233.34599) (xy 383.68478 -233.245914) (xy 383.584704 -233.34599) (xy 383.584704 -233.39044)
			(xy 383.784856 -233.39044)
		)
		(stroke
			(width 0)
			(type solid)
		)
		(fill yes)
		(layer "In2.Cu")
		(net "M_I_CPU0_SA_DQ<12>")
	)
	(gr_poly
		(pts
			(xy 383.784856 -232.942384) (xy 383.784856 -232.894632) (xy 383.584704 -232.894632) (xy 383.584704 -232.942384)
			(xy 383.68478 -233.042206)
		)
		(stroke
			(width 0)
			(type solid)
		)
		(fill yes)
		(layer "In2.Cu")
		(net "M_I_CPU0_SA_DQS_DP<6>")
	)
	(gr_poly
		(pts
			(xy 383.784856 -231.725724) (xy 383.68478 -231.625902) (xy 383.584704 -231.725724) (xy 383.584704 -231.773476)
			(xy 383.784856 -231.773476)
		)
		(stroke
			(width 0)
			(type solid)
		)
		(fill yes)
		(layer "In2.Cu")
		(net "M_I_CPU0_SA_DQS_DP<1>")
	)
	(gr_poly
		(pts
			(xy 383.784856 -231.322372) (xy 383.784856 -231.277922) (xy 383.584704 -231.277922) (xy 383.584704 -231.322372)
			(xy 383.68478 -231.422448)
		)
		(stroke
			(width 0)
			(type solid)
		)
		(fill yes)
		(layer "In2.Cu")
		(net "M_I_CPU0_SA_DQ<11>")
	)
	(gr_poly
		(pts
			(xy 383.784856 -230.105966) (xy 383.68478 -230.006144) (xy 383.584704 -230.105966) (xy 383.584704 -230.150416)
			(xy 383.784856 -230.150416)
		)
		(stroke
			(width 0)
			(type solid)
		)
		(fill yes)
		(layer "In2.Cu")
		(net "M_I_CPU0_SA_DQ<8>")
	)
	(gr_poly
		(pts
			(xy 383.784856 -229.70236) (xy 383.784856 -229.65791) (xy 383.584704 -229.65791) (xy 383.584704 -229.70236)
			(xy 383.68478 -229.802436)
		)
		(stroke
			(width 0)
			(type solid)
		)
		(fill yes)
		(layer "In2.Cu")
		(net "M_I_CPU0_SA_DQ<7>")
	)
	(gr_poly
		(pts
			(xy 383.784856 -228.486208) (xy 383.68478 -228.386132) (xy 383.584704 -228.486208) (xy 383.584704 -228.530658)
			(xy 383.784856 -228.530658)
		)
		(stroke
			(width 0)
			(type solid)
		)
		(fill yes)
		(layer "In2.Cu")
		(net "M_I_CPU0_SA_DQ<4>")
	)
	(gr_poly
		(pts
			(xy 383.784856 -228.082602) (xy 383.784856 -228.03485) (xy 383.584704 -228.03485) (xy 383.584704 -228.082602)
			(xy 383.68478 -228.182424)
		)
		(stroke
			(width 0)
			(type solid)
		)
		(fill yes)
		(layer "In2.Cu")
		(net "M_I_CPU0_SA_DQS_DP<5>")
	)
	(gr_poly
		(pts
			(xy 383.784856 -226.865942) (xy 383.68478 -226.76612) (xy 383.584704 -226.865942) (xy 383.584704 -226.913694)
			(xy 383.784856 -226.913694)
		)
		(stroke
			(width 0)
			(type solid)
		)
		(fill yes)
		(layer "In2.Cu")
		(net "M_I_CPU0_SA_DQS_DP<0>")
	)
	(gr_poly
		(pts
			(xy 383.784856 -226.462336) (xy 383.784856 -226.417886) (xy 383.584704 -226.417886) (xy 383.584704 -226.462336)
			(xy 383.68478 -226.562412)
		)
		(stroke
			(width 0)
			(type solid)
		)
		(fill yes)
		(layer "In2.Cu")
		(net "M_I_CPU0_SA_DQ<3>")
	)
	(gr_poly
		(pts
			(xy 383.784856 -225.246184) (xy 383.68478 -225.146108) (xy 383.584704 -225.246184) (xy 383.584704 -225.290634)
			(xy 383.784856 -225.290634)
		)
		(stroke
			(width 0)
			(type solid)
		)
		(fill yes)
		(layer "In2.Cu")
		(net "M_I_CPU0_SA_DQ<0>")
	)
	(gr_poly
		(pts
			(xy 384.08483 -292.91788) (xy 383.984754 -292.817804) (xy 383.884678 -292.91788) (xy 383.884678 -292.96233)
			(xy 384.08483 -292.96233)
		)
		(stroke
			(width 0)
			(type solid)
		)
		(fill yes)
		(layer "In2.Cu")
		(net "M_I_CPU0_SB_DQ<29>")
	)
	(gr_poly
		(pts
			(xy 384.08483 -292.51402) (xy 384.08483 -292.46957) (xy 383.884678 -292.46957) (xy 383.884678 -292.51402)
			(xy 383.984754 -292.614096)
		)
		(stroke
			(width 0)
			(type solid)
		)
		(fill yes)
		(layer "In2.Cu")
		(net "M_I_CPU0_SB_DQ<30>")
	)
	(gr_poly
		(pts
			(xy 384.08483 -291.297614) (xy 383.984754 -291.197792) (xy 383.884678 -291.297614) (xy 383.884678 -291.345366)
			(xy 384.08483 -291.345366)
		)
		(stroke
			(width 0)
			(type solid)
		)
		(fill yes)
		(layer "In2.Cu")
		(net "M_I_CPU0_SB_DQS_DN<8>")
	)
	(gr_poly
		(pts
			(xy 384.08483 -290.894262) (xy 384.08483 -290.84651) (xy 383.884678 -290.84651) (xy 383.884678 -290.894262)
			(xy 383.984754 -290.994084)
		)
		(stroke
			(width 0)
			(type solid)
		)
		(fill yes)
		(layer "In2.Cu")
		(net "M_I_CPU0_SB_DQS_DN<3>")
	)
	(gr_poly
		(pts
			(xy 384.08483 -289.677856) (xy 383.984754 -289.57778) (xy 383.884678 -289.677856) (xy 383.884678 -289.722306)
			(xy 384.08483 -289.722306)
		)
		(stroke
			(width 0)
			(type solid)
		)
		(fill yes)
		(layer "In2.Cu")
		(net "M_I_CPU0_SB_DQ<25>")
	)
	(gr_poly
		(pts
			(xy 384.08483 -289.273996) (xy 384.08483 -289.229546) (xy 383.884678 -289.229546) (xy 383.884678 -289.273996)
			(xy 383.984754 -289.374072)
		)
		(stroke
			(width 0)
			(type solid)
		)
		(fill yes)
		(layer "In2.Cu")
		(net "M_I_CPU0_SB_DQ<26>")
	)
	(gr_poly
		(pts
			(xy 384.08483 -288.057844) (xy 383.984754 -287.957768) (xy 383.884678 -288.057844) (xy 383.884678 -288.102294)
			(xy 384.08483 -288.102294)
		)
		(stroke
			(width 0)
			(type solid)
		)
		(fill yes)
		(layer "In2.Cu")
		(net "M_I_CPU0_SB_DQ<21>")
	)
	(gr_poly
		(pts
			(xy 384.08483 -287.654238) (xy 384.08483 -287.609788) (xy 383.884678 -287.609788) (xy 383.884678 -287.654238)
			(xy 383.984754 -287.75406)
		)
		(stroke
			(width 0)
			(type solid)
		)
		(fill yes)
		(layer "In2.Cu")
		(net "M_I_CPU0_SB_DQ<22>")
	)
	(gr_poly
		(pts
			(xy 384.08483 -286.437832) (xy 383.984754 -286.337756) (xy 383.884678 -286.437832) (xy 383.884678 -286.485584)
			(xy 384.08483 -286.485584)
		)
		(stroke
			(width 0)
			(type solid)
		)
		(fill yes)
		(layer "In2.Cu")
		(net "M_I_CPU0_SB_DQS_DN<7>")
	)
	(gr_poly
		(pts
			(xy 384.08483 -286.03448) (xy 384.08483 -285.986728) (xy 383.884678 -285.986728) (xy 383.884678 -286.03448)
			(xy 383.984754 -286.134302)
		)
		(stroke
			(width 0)
			(type solid)
		)
		(fill yes)
		(layer "In2.Cu")
		(net "M_I_CPU0_SB_DQS_DN<2>")
	)
	(gr_poly
		(pts
			(xy 384.08483 -284.818074) (xy 383.984754 -284.717998) (xy 383.884678 -284.818074) (xy 383.884678 -284.862524)
			(xy 384.08483 -284.862524)
		)
		(stroke
			(width 0)
			(type solid)
		)
		(fill yes)
		(layer "In2.Cu")
		(net "M_I_CPU0_SB_DQ<17>")
	)
	(gr_poly
		(pts
			(xy 384.08483 -284.414214) (xy 384.08483 -284.369764) (xy 383.884678 -284.369764) (xy 383.884678 -284.414214)
			(xy 383.984754 -284.51429)
		)
		(stroke
			(width 0)
			(type solid)
		)
		(fill yes)
		(layer "In2.Cu")
		(net "M_I_CPU0_SB_DQ<18>")
	)
	(gr_poly
		(pts
			(xy 384.08483 -283.198062) (xy 383.984754 -283.097986) (xy 383.884678 -283.198062) (xy 383.884678 -283.242512)
			(xy 384.08483 -283.242512)
		)
		(stroke
			(width 0)
			(type solid)
		)
		(fill yes)
		(layer "In2.Cu")
		(net "M_I_CPU0_SB_DQ<13>")
	)
	(gr_poly
		(pts
			(xy 384.08483 -282.794202) (xy 384.08483 -282.749752) (xy 383.884678 -282.749752) (xy 383.884678 -282.794202)
			(xy 383.984754 -282.894278)
		)
		(stroke
			(width 0)
			(type solid)
		)
		(fill yes)
		(layer "In2.Cu")
		(net "M_I_CPU0_SB_DQ<14>")
	)
	(gr_poly
		(pts
			(xy 384.08483 -281.577796) (xy 383.984754 -281.477974) (xy 383.884678 -281.577796) (xy 383.884678 -281.625548)
			(xy 384.08483 -281.625548)
		)
		(stroke
			(width 0)
			(type solid)
		)
		(fill yes)
		(layer "In2.Cu")
		(net "M_I_CPU0_SB_DQS_DN<6>")
	)
	(gr_poly
		(pts
			(xy 384.08483 -281.174444) (xy 384.08483 -281.126692) (xy 383.884678 -281.126692) (xy 383.884678 -281.174444)
			(xy 383.984754 -281.274266)
		)
		(stroke
			(width 0)
			(type solid)
		)
		(fill yes)
		(layer "In2.Cu")
		(net "M_I_CPU0_SB_DQS_DN<1>")
	)
	(gr_poly
		(pts
			(xy 384.08483 -279.958038) (xy 383.984754 -279.857962) (xy 383.884678 -279.958038) (xy 383.884678 -280.002488)
			(xy 384.08483 -280.002488)
		)
		(stroke
			(width 0)
			(type solid)
		)
		(fill yes)
		(layer "In2.Cu")
		(net "M_I_CPU0_SB_DQ<9>")
	)
	(gr_poly
		(pts
			(xy 384.08483 -279.554178) (xy 384.08483 -279.509728) (xy 383.884678 -279.509728) (xy 383.884678 -279.554178)
			(xy 383.984754 -279.654254)
		)
		(stroke
			(width 0)
			(type solid)
		)
		(fill yes)
		(layer "In2.Cu")
		(net "M_I_CPU0_SB_DQ<10>")
	)
	(gr_poly
		(pts
			(xy 384.08483 -278.338026) (xy 383.984754 -278.23795) (xy 383.884678 -278.338026) (xy 383.884678 -278.382476)
			(xy 384.08483 -278.382476)
		)
		(stroke
			(width 0)
			(type solid)
		)
		(fill yes)
		(layer "In2.Cu")
		(net "M_I_CPU0_SB_DQ<5>")
	)
	(gr_poly
		(pts
			(xy 384.08483 -277.934166) (xy 384.08483 -277.889716) (xy 383.884678 -277.889716) (xy 383.884678 -277.934166)
			(xy 383.984754 -278.034242)
		)
		(stroke
			(width 0)
			(type solid)
		)
		(fill yes)
		(layer "In2.Cu")
		(net "M_I_CPU0_SB_DQ<6>")
	)
	(gr_poly
		(pts
			(xy 384.08483 -276.71776) (xy 383.984754 -276.617938) (xy 383.884678 -276.71776) (xy 383.884678 -276.765512)
			(xy 384.08483 -276.765512)
		)
		(stroke
			(width 0)
			(type solid)
		)
		(fill yes)
		(layer "In2.Cu")
		(net "M_I_CPU0_SB_DQS_DN<5>")
	)
	(gr_poly
		(pts
			(xy 384.08483 -276.314408) (xy 384.08483 -276.266656) (xy 383.884678 -276.266656) (xy 383.884678 -276.314408)
			(xy 383.984754 -276.41423)
		)
		(stroke
			(width 0)
			(type solid)
		)
		(fill yes)
		(layer "In2.Cu")
		(net "M_I_CPU0_SB_DQS_DN<0>")
	)
	(gr_poly
		(pts
			(xy 384.08483 -275.098002) (xy 383.984754 -274.997926) (xy 383.884678 -275.098002) (xy 383.884678 -275.142452)
			(xy 384.08483 -275.142452)
		)
		(stroke
			(width 0)
			(type solid)
		)
		(fill yes)
		(layer "In2.Cu")
		(net "M_I_CPU0_SB_DQ<1>")
	)
	(gr_poly
		(pts
			(xy 384.08483 -274.694142) (xy 384.08483 -274.649692) (xy 383.884678 -274.649692) (xy 383.884678 -274.694142)
			(xy 383.984754 -274.794218)
		)
		(stroke
			(width 0)
			(type solid)
		)
		(fill yes)
		(layer "In2.Cu")
		(net "M_I_CPU0_SB_DQ<2>")
	)
	(gr_poly
		(pts
			(xy 384.08483 -273.47799) (xy 383.984754 -273.377914) (xy 383.884678 -273.47799) (xy 383.884678 -273.52244)
			(xy 384.08483 -273.52244)
		)
		(stroke
			(width 0)
			(type solid)
		)
		(fill yes)
		(layer "In2.Cu")
		(net "M_I_CPU0_SB_CB<1>")
	)
	(gr_poly
		(pts
			(xy 384.08483 -273.07413) (xy 384.08483 -273.02968) (xy 383.884678 -273.02968) (xy 383.884678 -273.07413)
			(xy 383.984754 -273.174206)
		)
		(stroke
			(width 0)
			(type solid)
		)
		(fill yes)
		(layer "In2.Cu")
		(net "M_I_CPU0_SB_CB<2>")
	)
	(gr_poly
		(pts
			(xy 384.08483 -271.857724) (xy 383.984754 -271.757902) (xy 383.884678 -271.857724) (xy 383.884678 -271.905476)
			(xy 384.08483 -271.905476)
		)
		(stroke
			(width 0)
			(type solid)
		)
		(fill yes)
		(layer "In2.Cu")
		(net "M_I_CPU0_SB_DQS_DN<4>")
	)
	(gr_poly
		(pts
			(xy 384.08483 -271.454372) (xy 384.08483 -271.40662) (xy 383.884678 -271.40662) (xy 383.884678 -271.454372)
			(xy 383.984754 -271.554194)
		)
		(stroke
			(width 0)
			(type solid)
		)
		(fill yes)
		(layer "In2.Cu")
		(net "M_I_CPU0_SB_DQS_DN<9>")
	)
	(gr_poly
		(pts
			(xy 384.08483 -270.237966) (xy 383.984754 -270.13789) (xy 383.884678 -270.237966) (xy 383.884678 -270.282416)
			(xy 384.08483 -270.282416)
		)
		(stroke
			(width 0)
			(type solid)
		)
		(fill yes)
		(layer "In2.Cu")
		(net "M_I_CPU0_SB_CB<5>")
	)
	(gr_poly
		(pts
			(xy 384.08483 -269.834106) (xy 384.08483 -269.789656) (xy 383.884678 -269.789656) (xy 383.884678 -269.834106)
			(xy 383.984754 -269.934182)
		)
		(stroke
			(width 0)
			(type solid)
		)
		(fill yes)
		(layer "In2.Cu")
		(net "M_I_CPU0_SB_CB<6>")
	)
	(gr_poly
		(pts
			(xy 384.08483 -266.997942) (xy 383.984754 -266.897866) (xy 383.884678 -266.997942) (xy 383.884678 -267.042392)
			(xy 384.08483 -267.042392)
		)
		(stroke
			(width 0)
			(type solid)
		)
		(fill yes)
		(layer "In2.Cu")
		(net "M_I_CPU0_SA_RSP<0>")
	)
	(gr_poly
		(pts
			(xy 384.08483 -266.594082) (xy 384.08483 -266.549632) (xy 383.884678 -266.549632) (xy 383.884678 -266.594082)
			(xy 383.984754 -266.694158)
		)
		(stroke
			(width 0)
			(type solid)
		)
		(fill yes)
		(layer "In2.Cu")
		(net "M_I_CPU0_SB_CS_N<1>")
	)
	(gr_poly
		(pts
			(xy 384.08483 -265.37793) (xy 383.984754 -265.277854) (xy 383.884678 -265.37793) (xy 383.884678 -265.42238)
			(xy 384.08483 -265.42238)
		)
		(stroke
			(width 0)
			(type solid)
		)
		(fill yes)
		(layer "In2.Cu")
		(net "M_I_CPU0_SB_PAR")
	)
	(gr_poly
		(pts
			(xy 384.08483 -263.757918) (xy 383.984754 -263.657842) (xy 383.884678 -263.757918) (xy 383.884678 -263.802368)
			(xy 384.08483 -263.802368)
		)
		(stroke
			(width 0)
			(type solid)
		)
		(fill yes)
		(layer "In2.Cu")
		(net "M_I_CPU0_SB_CA<4>")
	)
	(gr_poly
		(pts
			(xy 384.08483 -263.354058) (xy 384.08483 -263.309608) (xy 383.884678 -263.309608) (xy 383.884678 -263.354058)
			(xy 383.984754 -263.454134)
		)
		(stroke
			(width 0)
			(type solid)
		)
		(fill yes)
		(layer "In2.Cu")
		(net "M_I_CPU0_SB_CA<3>")
	)
	(gr_poly
		(pts
			(xy 384.08483 -262.137906) (xy 383.984754 -262.03783) (xy 383.884678 -262.137906) (xy 383.884678 -262.182356)
			(xy 384.08483 -262.182356)
		)
		(stroke
			(width 0)
			(type solid)
		)
		(fill yes)
		(layer "In2.Cu")
		(net "M_I_CPU0_SB_CA<0>")
	)
	(gr_poly
		(pts
			(xy 384.25501 -256.432558) (xy 384.25501 -256.384806) (xy 384.054858 -256.384806) (xy 384.054858 -256.432558)
			(xy 384.154934 -256.53238)
		)
		(stroke
			(width 0)
			(type solid)
		)
		(fill yes)
		(layer "In2.Cu")
		(net "M_I_CPU0_CLK_DN<0>")
	)
	(gr_poly
		(pts
			(xy 384.25501 -255.216152) (xy 384.154934 -255.116076) (xy 384.054858 -255.216152) (xy 384.054858 -255.260602)
			(xy 384.25501 -255.260602)
		)
		(stroke
			(width 0)
			(type solid)
		)
		(fill yes)
		(layer "In2.Cu")
		(net "M_I_CPU0_SA_CA<6>")
	)
	(gr_poly
		(pts
			(xy 384.25501 -254.812292) (xy 384.25501 -254.767842) (xy 384.054858 -254.767842) (xy 384.054858 -254.812292)
			(xy 384.154934 -254.912368)
		)
		(stroke
			(width 0)
			(type solid)
		)
		(fill yes)
		(layer "In2.Cu")
		(net "M_I_CPU0_SA_CA<5>")
	)
	(gr_poly
		(pts
			(xy 384.25501 -253.59614) (xy 384.154934 -253.496064) (xy 384.054858 -253.59614) (xy 384.054858 -253.64059)
			(xy 384.25501 -253.64059)
		)
		(stroke
			(width 0)
			(type solid)
		)
		(fill yes)
		(layer "In2.Cu")
		(net "M_I_CPU0_SA_CA<2>")
	)
	(gr_poly
		(pts
			(xy 384.25501 -253.19228) (xy 384.25501 -253.14783) (xy 384.054858 -253.14783) (xy 384.054858 -253.19228)
			(xy 384.154934 -253.292356)
		)
		(stroke
			(width 0)
			(type solid)
		)
		(fill yes)
		(layer "In2.Cu")
		(net "M_I_CPU0_SA_CA<1>")
	)
	(gr_poly
		(pts
			(xy 384.25501 -251.976128) (xy 384.154934 -251.876052) (xy 384.054858 -251.976128) (xy 384.054858 -252.020578)
			(xy 384.25501 -252.020578)
		)
		(stroke
			(width 0)
			(type solid)
		)
		(fill yes)
		(layer "In2.Cu")
		(net "M_I_CPU0_SA_CS_N<1>")
	)
	(gr_poly
		(pts
			(xy 384.25501 -250.356116) (xy 384.154934 -250.25604) (xy 384.054858 -250.356116) (xy 384.054858 -250.400566)
			(xy 384.25501 -250.400566)
		)
		(stroke
			(width 0)
			(type solid)
		)
		(fill yes)
		(layer "In2.Cu")
		(net "M_I_CPU0_ALERT_R_N")
	)
	(gr_poly
		(pts
			(xy 384.25501 -248.736104) (xy 384.154934 -248.636028) (xy 384.054858 -248.736104) (xy 384.054858 -248.780554)
			(xy 384.25501 -248.780554)
		)
		(stroke
			(width 0)
			(type solid)
		)
		(fill yes)
		(layer "In2.Cu")
		(net "M_I_CPU0_SA_CB<5>")
	)
	(gr_poly
		(pts
			(xy 384.25501 -248.332244) (xy 384.25501 -248.287794) (xy 384.054858 -248.287794) (xy 384.054858 -248.332244)
			(xy 384.154934 -248.43232)
		)
		(stroke
			(width 0)
			(type solid)
		)
		(fill yes)
		(layer "In2.Cu")
		(net "M_I_CPU0_SA_CB<6>")
	)
	(gr_poly
		(pts
			(xy 384.25501 -247.115838) (xy 384.154934 -247.016016) (xy 384.054858 -247.115838) (xy 384.054858 -247.16359)
			(xy 384.25501 -247.16359)
		)
		(stroke
			(width 0)
			(type solid)
		)
		(fill yes)
		(layer "In2.Cu")
		(net "M_I_CPU0_SA_DQS_DN<9>")
	)
	(gr_poly
		(pts
			(xy 384.25501 -246.712486) (xy 384.25501 -246.664734) (xy 384.054858 -246.664734) (xy 384.054858 -246.712486)
			(xy 384.154934 -246.812308)
		)
		(stroke
			(width 0)
			(type solid)
		)
		(fill yes)
		(layer "In2.Cu")
		(net "M_I_CPU0_SA_DQS_DN<4>")
	)
	(gr_poly
		(pts
			(xy 384.25501 -245.49608) (xy 384.154934 -245.396004) (xy 384.054858 -245.49608) (xy 384.054858 -245.54053)
			(xy 384.25501 -245.54053)
		)
		(stroke
			(width 0)
			(type solid)
		)
		(fill yes)
		(layer "In2.Cu")
		(net "M_I_CPU0_SA_CB<1>")
	)
	(gr_poly
		(pts
			(xy 384.25501 -245.09222) (xy 384.25501 -245.04777) (xy 384.054858 -245.04777) (xy 384.054858 -245.09222)
			(xy 384.154934 -245.192296)
		)
		(stroke
			(width 0)
			(type solid)
		)
		(fill yes)
		(layer "In2.Cu")
		(net "M_I_CPU0_SA_CB<2>")
	)
	(gr_poly
		(pts
			(xy 384.25501 -243.876068) (xy 384.154934 -243.775992) (xy 384.054858 -243.876068) (xy 384.054858 -243.920518)
			(xy 384.25501 -243.920518)
		)
		(stroke
			(width 0)
			(type solid)
		)
		(fill yes)
		(layer "In2.Cu")
		(net "M_I_CPU0_SA_DQ<29>")
	)
	(gr_poly
		(pts
			(xy 384.25501 -243.472208) (xy 384.25501 -243.427758) (xy 384.054858 -243.427758) (xy 384.054858 -243.472208)
			(xy 384.154934 -243.572284)
		)
		(stroke
			(width 0)
			(type solid)
		)
		(fill yes)
		(layer "In2.Cu")
		(net "M_I_CPU0_SA_DQ<30>")
	)
	(gr_poly
		(pts
			(xy 384.25501 -242.255802) (xy 384.154934 -242.15598) (xy 384.054858 -242.255802) (xy 384.054858 -242.303554)
			(xy 384.25501 -242.303554)
		)
		(stroke
			(width 0)
			(type solid)
		)
		(fill yes)
		(layer "In2.Cu")
		(net "M_I_CPU0_SA_DQS_DN<8>")
	)
	(gr_poly
		(pts
			(xy 384.25501 -241.85245) (xy 384.25501 -241.804698) (xy 384.054858 -241.804698) (xy 384.054858 -241.85245)
			(xy 384.154934 -241.952272)
		)
		(stroke
			(width 0)
			(type solid)
		)
		(fill yes)
		(layer "In2.Cu")
		(net "M_I_CPU0_SA_DQS_DN<3>")
	)
	(gr_poly
		(pts
			(xy 384.25501 -240.636044) (xy 384.154934 -240.535968) (xy 384.054858 -240.636044) (xy 384.054858 -240.680494)
			(xy 384.25501 -240.680494)
		)
		(stroke
			(width 0)
			(type solid)
		)
		(fill yes)
		(layer "In2.Cu")
		(net "M_I_CPU0_SA_DQ<25>")
	)
	(gr_poly
		(pts
			(xy 384.25501 -240.232184) (xy 384.25501 -240.187734) (xy 384.054858 -240.187734) (xy 384.054858 -240.232184)
			(xy 384.154934 -240.33226)
		)
		(stroke
			(width 0)
			(type solid)
		)
		(fill yes)
		(layer "In2.Cu")
		(net "M_I_CPU0_SA_DQ<26>")
	)
	(gr_poly
		(pts
			(xy 384.25501 -239.016032) (xy 384.154934 -238.915956) (xy 384.054858 -239.016032) (xy 384.054858 -239.060482)
			(xy 384.25501 -239.060482)
		)
		(stroke
			(width 0)
			(type solid)
		)
		(fill yes)
		(layer "In2.Cu")
		(net "M_I_CPU0_SA_DQ<21>")
	)
	(gr_poly
		(pts
			(xy 384.25501 -238.612172) (xy 384.25501 -238.567722) (xy 384.054858 -238.567722) (xy 384.054858 -238.612172)
			(xy 384.154934 -238.712248)
		)
		(stroke
			(width 0)
			(type solid)
		)
		(fill yes)
		(layer "In2.Cu")
		(net "M_I_CPU0_SA_DQ<22>")
	)
	(gr_poly
		(pts
			(xy 384.25501 -237.395766) (xy 384.154934 -237.295944) (xy 384.054858 -237.395766) (xy 384.054858 -237.443518)
			(xy 384.25501 -237.443518)
		)
		(stroke
			(width 0)
			(type solid)
		)
		(fill yes)
		(layer "In2.Cu")
		(net "M_I_CPU0_SA_DQS_DN<7>")
	)
	(gr_poly
		(pts
			(xy 384.25501 -236.992414) (xy 384.25501 -236.944662) (xy 384.054858 -236.944662) (xy 384.054858 -236.992414)
			(xy 384.154934 -237.092236)
		)
		(stroke
			(width 0)
			(type solid)
		)
		(fill yes)
		(layer "In2.Cu")
		(net "M_I_CPU0_SA_DQS_DN<2>")
	)
	(gr_poly
		(pts
			(xy 384.25501 -235.776008) (xy 384.154934 -235.675932) (xy 384.054858 -235.776008) (xy 384.054858 -235.820458)
			(xy 384.25501 -235.820458)
		)
		(stroke
			(width 0)
			(type solid)
		)
		(fill yes)
		(layer "In2.Cu")
		(net "M_I_CPU0_SA_DQ<17>")
	)
	(gr_poly
		(pts
			(xy 384.25501 -235.372148) (xy 384.25501 -235.327698) (xy 384.054858 -235.327698) (xy 384.054858 -235.372148)
			(xy 384.154934 -235.472224)
		)
		(stroke
			(width 0)
			(type solid)
		)
		(fill yes)
		(layer "In2.Cu")
		(net "M_I_CPU0_SA_DQ<18>")
	)
	(gr_poly
		(pts
			(xy 384.25501 -234.155996) (xy 384.154934 -234.05592) (xy 384.054858 -234.155996) (xy 384.054858 -234.200446)
			(xy 384.25501 -234.200446)
		)
		(stroke
			(width 0)
			(type solid)
		)
		(fill yes)
		(layer "In2.Cu")
		(net "M_I_CPU0_SA_DQ<13>")
	)
	(gr_poly
		(pts
			(xy 384.25501 -233.752136) (xy 384.25501 -233.707686) (xy 384.054858 -233.707686) (xy 384.054858 -233.752136)
			(xy 384.154934 -233.852212)
		)
		(stroke
			(width 0)
			(type solid)
		)
		(fill yes)
		(layer "In2.Cu")
		(net "M_I_CPU0_SA_DQ<14>")
	)
	(gr_poly
		(pts
			(xy 384.25501 -232.53573) (xy 384.154934 -232.435908) (xy 384.054858 -232.53573) (xy 384.054858 -232.583482)
			(xy 384.25501 -232.583482)
		)
		(stroke
			(width 0)
			(type solid)
		)
		(fill yes)
		(layer "In2.Cu")
		(net "M_I_CPU0_SA_DQS_DN<6>")
	)
	(gr_poly
		(pts
			(xy 384.25501 -232.132378) (xy 384.25501 -232.084626) (xy 384.054858 -232.084626) (xy 384.054858 -232.132378)
			(xy 384.154934 -232.2322)
		)
		(stroke
			(width 0)
			(type solid)
		)
		(fill yes)
		(layer "In2.Cu")
		(net "M_I_CPU0_SA_DQS_DN<1>")
	)
	(gr_poly
		(pts
			(xy 384.25501 -230.915972) (xy 384.154934 -230.815896) (xy 384.054858 -230.915972) (xy 384.054858 -230.960422)
			(xy 384.25501 -230.960422)
		)
		(stroke
			(width 0)
			(type solid)
		)
		(fill yes)
		(layer "In2.Cu")
		(net "M_I_CPU0_SA_DQ<9>")
	)
	(gr_poly
		(pts
			(xy 384.25501 -230.512366) (xy 384.25501 -230.467916) (xy 384.054858 -230.467916) (xy 384.054858 -230.512366)
			(xy 384.154934 -230.612188)
		)
		(stroke
			(width 0)
			(type solid)
		)
		(fill yes)
		(layer "In2.Cu")
		(net "M_I_CPU0_SA_DQ<10>")
	)
	(gr_poly
		(pts
			(xy 384.25501 -229.29596) (xy 384.154934 -229.195884) (xy 384.054858 -229.29596) (xy 384.054858 -229.34041)
			(xy 384.25501 -229.34041)
		)
		(stroke
			(width 0)
			(type solid)
		)
		(fill yes)
		(layer "In2.Cu")
		(net "M_I_CPU0_SA_DQ<5>")
	)
	(gr_poly
		(pts
			(xy 384.25501 -228.892354) (xy 384.25501 -228.847904) (xy 384.054858 -228.847904) (xy 384.054858 -228.892354)
			(xy 384.154934 -228.99243)
		)
		(stroke
			(width 0)
			(type solid)
		)
		(fill yes)
		(layer "In2.Cu")
		(net "M_I_CPU0_SA_DQ<6>")
	)
	(gr_poly
		(pts
			(xy 384.25501 -227.675948) (xy 384.154934 -227.576126) (xy 384.054858 -227.675948) (xy 384.054858 -227.7237)
			(xy 384.25501 -227.7237)
		)
		(stroke
			(width 0)
			(type solid)
		)
		(fill yes)
		(layer "In2.Cu")
		(net "M_I_CPU0_SA_DQS_DN<5>")
	)
	(gr_poly
		(pts
			(xy 384.25501 -227.272596) (xy 384.25501 -227.224844) (xy 384.054858 -227.224844) (xy 384.054858 -227.272596)
			(xy 384.154934 -227.372418)
		)
		(stroke
			(width 0)
			(type solid)
		)
		(fill yes)
		(layer "In2.Cu")
		(net "M_I_CPU0_SA_DQS_DN<0>")
	)
	(gr_poly
		(pts
			(xy 384.25501 -226.05619) (xy 384.154934 -225.956114) (xy 384.054858 -226.05619) (xy 384.054858 -226.10064)
			(xy 384.25501 -226.10064)
		)
		(stroke
			(width 0)
			(type solid)
		)
		(fill yes)
		(layer "In2.Cu")
		(net "M_I_CPU0_SA_DQ<1>")
	)
	(gr_poly
		(pts
			(xy 384.25501 -225.65233) (xy 384.25501 -225.60788) (xy 384.054858 -225.60788) (xy 384.054858 -225.65233)
			(xy 384.154934 -225.752406)
		)
		(stroke
			(width 0)
			(type solid)
		)
		(fill yes)
		(layer "In2.Cu")
		(net "M_I_CPU0_SA_DQ<2>")
	)
	(gr_poly
		(pts
			(xy 384.554984 -293.324026) (xy 384.554984 -293.279576) (xy 384.354832 -293.279576) (xy 384.354832 -293.324026)
			(xy 384.454908 -293.424102)
		)
		(stroke
			(width 0)
			(type solid)
		)
		(fill yes)
		(layer "In2.Cu")
		(net "M_I_CPU0_SB_DQ<31>")
	)
	(gr_poly
		(pts
			(xy 384.554984 -292.107874) (xy 384.454908 -292.007798) (xy 384.354832 -292.107874) (xy 384.354832 -292.152324)
			(xy 384.554984 -292.152324)
		)
		(stroke
			(width 0)
			(type solid)
		)
		(fill yes)
		(layer "In2.Cu")
		(net "M_I_CPU0_SB_DQ<28>")
	)
	(gr_poly
		(pts
			(xy 384.554984 -291.704268) (xy 384.554984 -291.656516) (xy 384.354832 -291.656516) (xy 384.354832 -291.704268)
			(xy 384.454908 -291.80409)
		)
		(stroke
			(width 0)
			(type solid)
		)
		(fill yes)
		(layer "In2.Cu")
		(net "M_I_CPU0_SB_DQS_DP<8>")
	)
	(gr_poly
		(pts
			(xy 384.554984 -290.487608) (xy 384.454908 -290.387786) (xy 384.354832 -290.487608) (xy 384.354832 -290.53536)
			(xy 384.554984 -290.53536)
		)
		(stroke
			(width 0)
			(type solid)
		)
		(fill yes)
		(layer "In2.Cu")
		(net "M_I_CPU0_SB_DQS_DP<3>")
	)
	(gr_poly
		(pts
			(xy 384.554984 -290.084002) (xy 384.554984 -290.039552) (xy 384.354832 -290.039552) (xy 384.354832 -290.084002)
			(xy 384.454908 -290.184078)
		)
		(stroke
			(width 0)
			(type solid)
		)
		(fill yes)
		(layer "In2.Cu")
		(net "M_I_CPU0_SB_DQ<27>")
	)
	(gr_poly
		(pts
			(xy 384.554984 -288.86785) (xy 384.454908 -288.767774) (xy 384.354832 -288.86785) (xy 384.354832 -288.9123)
			(xy 384.554984 -288.9123)
		)
		(stroke
			(width 0)
			(type solid)
		)
		(fill yes)
		(layer "In2.Cu")
		(net "M_I_CPU0_SB_DQ<24>")
	)
	(gr_poly
		(pts
			(xy 384.554984 -288.464244) (xy 384.554984 -288.419794) (xy 384.354832 -288.419794) (xy 384.354832 -288.464244)
			(xy 384.454908 -288.56432)
		)
		(stroke
			(width 0)
			(type solid)
		)
		(fill yes)
		(layer "In2.Cu")
		(net "M_I_CPU0_SB_DQ<23>")
	)
	(gr_poly
		(pts
			(xy 384.554984 -287.247838) (xy 384.454908 -287.148016) (xy 384.354832 -287.247838) (xy 384.354832 -287.292288)
			(xy 384.554984 -287.292288)
		)
		(stroke
			(width 0)
			(type solid)
		)
		(fill yes)
		(layer "In2.Cu")
		(net "M_I_CPU0_SB_DQ<20>")
	)
	(gr_poly
		(pts
			(xy 384.554984 -286.844232) (xy 384.554984 -286.79648) (xy 384.354832 -286.79648) (xy 384.354832 -286.844232)
			(xy 384.454908 -286.944308)
		)
		(stroke
			(width 0)
			(type solid)
		)
		(fill yes)
		(layer "In2.Cu")
		(net "M_I_CPU0_SB_DQS_DP<7>")
	)
	(gr_poly
		(pts
			(xy 384.554984 -285.627826) (xy 384.454908 -285.528004) (xy 384.354832 -285.627826) (xy 384.354832 -285.675578)
			(xy 384.554984 -285.675578)
		)
		(stroke
			(width 0)
			(type solid)
		)
		(fill yes)
		(layer "In2.Cu")
		(net "M_I_CPU0_SB_DQS_DP<2>")
	)
	(gr_poly
		(pts
			(xy 384.554984 -285.22422) (xy 384.554984 -285.17977) (xy 384.354832 -285.17977) (xy 384.354832 -285.22422)
			(xy 384.454908 -285.324296)
		)
		(stroke
			(width 0)
			(type solid)
		)
		(fill yes)
		(layer "In2.Cu")
		(net "M_I_CPU0_SB_DQ<19>")
	)
	(gr_poly
		(pts
			(xy 384.554984 -284.008068) (xy 384.454908 -283.907992) (xy 384.354832 -284.008068) (xy 384.354832 -284.052518)
			(xy 384.554984 -284.052518)
		)
		(stroke
			(width 0)
			(type solid)
		)
		(fill yes)
		(layer "In2.Cu")
		(net "M_I_CPU0_SB_DQ<16>")
	)
	(gr_poly
		(pts
			(xy 384.554984 -283.604208) (xy 384.554984 -283.559758) (xy 384.354832 -283.559758) (xy 384.354832 -283.604208)
			(xy 384.454908 -283.704284)
		)
		(stroke
			(width 0)
			(type solid)
		)
		(fill yes)
		(layer "In2.Cu")
		(net "M_I_CPU0_SB_DQ<15>")
	)
	(gr_poly
		(pts
			(xy 384.554984 -282.388056) (xy 384.454908 -282.28798) (xy 384.354832 -282.388056) (xy 384.354832 -282.432506)
			(xy 384.554984 -282.432506)
		)
		(stroke
			(width 0)
			(type solid)
		)
		(fill yes)
		(layer "In2.Cu")
		(net "M_I_CPU0_SB_DQ<12>")
	)
	(gr_poly
		(pts
			(xy 384.554984 -281.98445) (xy 384.554984 -281.936698) (xy 384.354832 -281.936698) (xy 384.354832 -281.98445)
			(xy 384.454908 -282.084272)
		)
		(stroke
			(width 0)
			(type solid)
		)
		(fill yes)
		(layer "In2.Cu")
		(net "M_I_CPU0_SB_DQS_DP<6>")
	)
	(gr_poly
		(pts
			(xy 384.554984 -280.76779) (xy 384.454908 -280.667968) (xy 384.354832 -280.76779) (xy 384.354832 -280.815542)
			(xy 384.554984 -280.815542)
		)
		(stroke
			(width 0)
			(type solid)
		)
		(fill yes)
		(layer "In2.Cu")
		(net "M_I_CPU0_SB_DQS_DP<1>")
	)
	(gr_poly
		(pts
			(xy 384.554984 -280.364184) (xy 384.554984 -280.319734) (xy 384.354832 -280.319734) (xy 384.354832 -280.364184)
			(xy 384.454908 -280.46426)
		)
		(stroke
			(width 0)
			(type solid)
		)
		(fill yes)
		(layer "In2.Cu")
		(net "M_I_CPU0_SB_DQ<11>")
	)
	(gr_poly
		(pts
			(xy 384.554984 -279.148032) (xy 384.454908 -279.047956) (xy 384.354832 -279.148032) (xy 384.354832 -279.192482)
			(xy 384.554984 -279.192482)
		)
		(stroke
			(width 0)
			(type solid)
		)
		(fill yes)
		(layer "In2.Cu")
		(net "M_I_CPU0_SB_DQ<8>")
	)
	(gr_poly
		(pts
			(xy 384.554984 -278.744172) (xy 384.554984 -278.699722) (xy 384.354832 -278.699722) (xy 384.354832 -278.744172)
			(xy 384.454908 -278.844248)
		)
		(stroke
			(width 0)
			(type solid)
		)
		(fill yes)
		(layer "In2.Cu")
		(net "M_I_CPU0_SB_DQ<7>")
	)
	(gr_poly
		(pts
			(xy 384.554984 -277.52802) (xy 384.454908 -277.427944) (xy 384.354832 -277.52802) (xy 384.354832 -277.57247)
			(xy 384.554984 -277.57247)
		)
		(stroke
			(width 0)
			(type solid)
		)
		(fill yes)
		(layer "In2.Cu")
		(net "M_I_CPU0_SB_DQ<4>")
	)
	(gr_poly
		(pts
			(xy 384.554984 -277.124414) (xy 384.554984 -277.076662) (xy 384.354832 -277.076662) (xy 384.354832 -277.124414)
			(xy 384.454908 -277.224236)
		)
		(stroke
			(width 0)
			(type solid)
		)
		(fill yes)
		(layer "In2.Cu")
		(net "M_I_CPU0_SB_DQS_DP<5>")
	)
	(gr_poly
		(pts
			(xy 384.554984 -275.907754) (xy 384.454908 -275.807932) (xy 384.354832 -275.907754) (xy 384.354832 -275.955506)
			(xy 384.554984 -275.955506)
		)
		(stroke
			(width 0)
			(type solid)
		)
		(fill yes)
		(layer "In2.Cu")
		(net "M_I_CPU0_SB_DQS_DP<0>")
	)
	(gr_poly
		(pts
			(xy 384.554984 -275.504148) (xy 384.554984 -275.459698) (xy 384.354832 -275.459698) (xy 384.354832 -275.504148)
			(xy 384.454908 -275.604224)
		)
		(stroke
			(width 0)
			(type solid)
		)
		(fill yes)
		(layer "In2.Cu")
		(net "M_I_CPU0_SB_DQ<3>")
	)
	(gr_poly
		(pts
			(xy 384.554984 -274.287996) (xy 384.454908 -274.18792) (xy 384.354832 -274.287996) (xy 384.354832 -274.332446)
			(xy 384.554984 -274.332446)
		)
		(stroke
			(width 0)
			(type solid)
		)
		(fill yes)
		(layer "In2.Cu")
		(net "M_I_CPU0_SB_DQ<0>")
	)
	(gr_poly
		(pts
			(xy 384.554984 -273.884136) (xy 384.554984 -273.839686) (xy 384.354832 -273.839686) (xy 384.354832 -273.884136)
			(xy 384.454908 -273.984212)
		)
		(stroke
			(width 0)
			(type solid)
		)
		(fill yes)
		(layer "In2.Cu")
		(net "M_I_CPU0_SB_CB<3>")
	)
	(gr_poly
		(pts
			(xy 384.554984 -272.667984) (xy 384.454908 -272.567908) (xy 384.354832 -272.667984) (xy 384.354832 -272.712434)
			(xy 384.554984 -272.712434)
		)
		(stroke
			(width 0)
			(type solid)
		)
		(fill yes)
		(layer "In2.Cu")
		(net "M_I_CPU0_SB_CB<0>")
	)
	(gr_poly
		(pts
			(xy 384.554984 -272.264378) (xy 384.554984 -272.216626) (xy 384.354832 -272.216626) (xy 384.354832 -272.264378)
			(xy 384.454908 -272.3642)
		)
		(stroke
			(width 0)
			(type solid)
		)
		(fill yes)
		(layer "In2.Cu")
		(net "M_I_CPU0_SB_DQS_DP<4>")
	)
	(gr_poly
		(pts
			(xy 384.554984 -271.047718) (xy 384.454908 -270.947896) (xy 384.354832 -271.047718) (xy 384.354832 -271.09547)
			(xy 384.554984 -271.09547)
		)
		(stroke
			(width 0)
			(type solid)
		)
		(fill yes)
		(layer "In2.Cu")
		(net "M_I_CPU0_SB_DQS_DP<9>")
	)
	(gr_poly
		(pts
			(xy 384.554984 -270.644112) (xy 384.554984 -270.599662) (xy 384.354832 -270.599662) (xy 384.354832 -270.644112)
			(xy 384.454908 -270.744188)
		)
		(stroke
			(width 0)
			(type solid)
		)
		(fill yes)
		(layer "In2.Cu")
		(net "M_I_CPU0_SB_CB<7>")
	)
	(gr_poly
		(pts
			(xy 384.554984 -269.42796) (xy 384.454908 -269.327884) (xy 384.354832 -269.42796) (xy 384.354832 -269.47241)
			(xy 384.554984 -269.47241)
		)
		(stroke
			(width 0)
			(type solid)
		)
		(fill yes)
		(layer "In2.Cu")
		(net "M_I_CPU0_SB_CB<4>")
	)
	(gr_poly
		(pts
			(xy 384.554984 -267.404088) (xy 384.554984 -267.359638) (xy 384.354832 -267.359638) (xy 384.354832 -267.404088)
			(xy 384.454908 -267.504164)
		)
		(stroke
			(width 0)
			(type solid)
		)
		(fill yes)
		(layer "In2.Cu")
		(net "M_I_CPU0_SB_RSP<0>")
	)
	(gr_poly
		(pts
			(xy 384.554984 -265.784076) (xy 384.554984 -265.739626) (xy 384.354832 -265.739626) (xy 384.354832 -265.784076)
			(xy 384.454908 -265.884152)
		)
		(stroke
			(width 0)
			(type solid)
		)
		(fill yes)
		(layer "In2.Cu")
		(net "M_I_CPU0_SB_CS_N<0>")
	)
	(gr_poly
		(pts
			(xy 384.554984 -264.567924) (xy 384.454908 -264.467848) (xy 384.354832 -264.567924) (xy 384.354832 -264.612374)
			(xy 384.554984 -264.612374)
		)
		(stroke
			(width 0)
			(type solid)
		)
		(fill yes)
		(layer "In2.Cu")
		(net "M_I_CPU0_SB_CA<6>")
	)
	(gr_poly
		(pts
			(xy 384.554984 -264.164064) (xy 384.554984 -264.119614) (xy 384.354832 -264.119614) (xy 384.354832 -264.164064)
			(xy 384.454908 -264.26414)
		)
		(stroke
			(width 0)
			(type solid)
		)
		(fill yes)
		(layer "In2.Cu")
		(net "M_I_CPU0_SB_CA<5>")
	)
	(gr_poly
		(pts
			(xy 384.554984 -262.947912) (xy 384.454908 -262.847836) (xy 384.354832 -262.947912) (xy 384.354832 -262.992362)
			(xy 384.554984 -262.992362)
		)
		(stroke
			(width 0)
			(type solid)
		)
		(fill yes)
		(layer "In2.Cu")
		(net "M_I_CPU0_SB_CA<2>")
	)
	(gr_poly
		(pts
			(xy 384.554984 -262.544052) (xy 384.554984 -262.499602) (xy 384.354832 -262.499602) (xy 384.354832 -262.544052)
			(xy 384.454908 -262.644128)
		)
		(stroke
			(width 0)
			(type solid)
		)
		(fill yes)
		(layer "In2.Cu")
		(net "M_I_CPU0_SB_CA<1>")
	)
	(gr_poly
		(pts
			(xy 384.72491 -256.025904) (xy 384.624834 -255.926082) (xy 384.524758 -256.025904) (xy 384.524758 -256.073656)
			(xy 384.72491 -256.073656)
		)
		(stroke
			(width 0)
			(type solid)
		)
		(fill yes)
		(layer "In2.Cu")
		(net "M_I_CPU0_CLK_DP<0>")
	)
	(gr_poly
		(pts
			(xy 384.72491 -255.622298) (xy 384.72491 -255.577848) (xy 384.524758 -255.577848) (xy 384.524758 -255.622298)
			(xy 384.624834 -255.722374)
		)
		(stroke
			(width 0)
			(type solid)
		)
		(fill yes)
		(layer "In2.Cu")
		(net "M_I_CPU0_SA_PAR")
	)
	(gr_poly
		(pts
			(xy 384.72491 -254.406146) (xy 384.624834 -254.30607) (xy 384.524758 -254.406146) (xy 384.524758 -254.450596)
			(xy 384.72491 -254.450596)
		)
		(stroke
			(width 0)
			(type solid)
		)
		(fill yes)
		(layer "In2.Cu")
		(net "M_I_CPU0_SA_CA<4>")
	)
	(gr_poly
		(pts
			(xy 384.72491 -254.002286) (xy 384.72491 -253.957836) (xy 384.524758 -253.957836) (xy 384.524758 -254.002286)
			(xy 384.624834 -254.102362)
		)
		(stroke
			(width 0)
			(type solid)
		)
		(fill yes)
		(layer "In2.Cu")
		(net "M_I_CPU0_SA_CA<3>")
	)
	(gr_poly
		(pts
			(xy 384.72491 -252.786134) (xy 384.624834 -252.686058) (xy 384.524758 -252.786134) (xy 384.524758 -252.830584)
			(xy 384.72491 -252.830584)
		)
		(stroke
			(width 0)
			(type solid)
		)
		(fill yes)
		(layer "In2.Cu")
		(net "M_I_CPU0_SA_CA<0>")
	)
	(gr_poly
		(pts
			(xy 384.72491 -251.166122) (xy 384.624834 -251.066046) (xy 384.524758 -251.166122) (xy 384.524758 -251.210572)
			(xy 384.72491 -251.210572)
		)
		(stroke
			(width 0)
			(type solid)
		)
		(fill yes)
		(layer "In2.Cu")
		(net "M_I_CPU0_SA_CS_N<0>")
	)
	(gr_poly
		(pts
			(xy 384.72491 -250.762262) (xy 384.72491 -250.717812) (xy 384.524758 -250.717812) (xy 384.524758 -250.762262)
			(xy 384.624834 -250.862338)
		)
		(stroke
			(width 0)
			(type solid)
		)
		(fill yes)
		(layer "In2.Cu")
		(net "M_I_CPU0_RESET_N")
	)
	(gr_poly
		(pts
			(xy 384.72491 -249.14225) (xy 384.72491 -249.0978) (xy 384.524758 -249.0978) (xy 384.524758 -249.14225)
			(xy 384.624834 -249.242326)
		)
		(stroke
			(width 0)
			(type solid)
		)
		(fill yes)
		(layer "In2.Cu")
		(net "M_I_CPU0_SA_CB<7>")
	)
	(gr_poly
		(pts
			(xy 384.72491 -247.926098) (xy 384.624834 -247.826022) (xy 384.524758 -247.926098) (xy 384.524758 -247.970548)
			(xy 384.72491 -247.970548)
		)
		(stroke
			(width 0)
			(type solid)
		)
		(fill yes)
		(layer "In2.Cu")
		(net "M_I_CPU0_SA_CB<4>")
	)
	(gr_poly
		(pts
			(xy 384.72491 -247.522492) (xy 384.72491 -247.47474) (xy 384.524758 -247.47474) (xy 384.524758 -247.522492)
			(xy 384.624834 -247.622314)
		)
		(stroke
			(width 0)
			(type solid)
		)
		(fill yes)
		(layer "In2.Cu")
		(net "M_I_CPU0_SA_DQS_DP<9>")
	)
	(gr_poly
		(pts
			(xy 384.72491 -246.305832) (xy 384.624834 -246.20601) (xy 384.524758 -246.305832) (xy 384.524758 -246.353584)
			(xy 384.72491 -246.353584)
		)
		(stroke
			(width 0)
			(type solid)
		)
		(fill yes)
		(layer "In2.Cu")
		(net "M_I_CPU0_SA_DQS_DP<4>")
	)
	(gr_poly
		(pts
			(xy 384.72491 -245.902226) (xy 384.72491 -245.857776) (xy 384.524758 -245.857776) (xy 384.524758 -245.902226)
			(xy 384.624834 -246.002302)
		)
		(stroke
			(width 0)
			(type solid)
		)
		(fill yes)
		(layer "In2.Cu")
		(net "M_I_CPU0_SA_CB<3>")
	)
	(gr_poly
		(pts
			(xy 384.72491 -244.686074) (xy 384.624834 -244.585998) (xy 384.524758 -244.686074) (xy 384.524758 -244.730524)
			(xy 384.72491 -244.730524)
		)
		(stroke
			(width 0)
			(type solid)
		)
		(fill yes)
		(layer "In2.Cu")
		(net "M_I_CPU0_SA_CB<0>")
	)
	(gr_poly
		(pts
			(xy 384.72491 -244.282214) (xy 384.72491 -244.237764) (xy 384.524758 -244.237764) (xy 384.524758 -244.282214)
			(xy 384.624834 -244.38229)
		)
		(stroke
			(width 0)
			(type solid)
		)
		(fill yes)
		(layer "In2.Cu")
		(net "M_I_CPU0_SA_DQ<31>")
	)
	(gr_poly
		(pts
			(xy 384.72491 -243.066062) (xy 384.624834 -242.965986) (xy 384.524758 -243.066062) (xy 384.524758 -243.110512)
			(xy 384.72491 -243.110512)
		)
		(stroke
			(width 0)
			(type solid)
		)
		(fill yes)
		(layer "In2.Cu")
		(net "M_I_CPU0_SA_DQ<28>")
	)
	(gr_poly
		(pts
			(xy 384.72491 -242.662456) (xy 384.72491 -242.614704) (xy 384.524758 -242.614704) (xy 384.524758 -242.662456)
			(xy 384.624834 -242.762278)
		)
		(stroke
			(width 0)
			(type solid)
		)
		(fill yes)
		(layer "In2.Cu")
		(net "M_I_CPU0_SA_DQS_DP<8>")
	)
	(gr_poly
		(pts
			(xy 384.72491 -241.445796) (xy 384.624834 -241.345974) (xy 384.524758 -241.445796) (xy 384.524758 -241.493548)
			(xy 384.72491 -241.493548)
		)
		(stroke
			(width 0)
			(type solid)
		)
		(fill yes)
		(layer "In2.Cu")
		(net "M_I_CPU0_SA_DQS_DP<3>")
	)
	(gr_poly
		(pts
			(xy 384.72491 -241.04219) (xy 384.72491 -240.99774) (xy 384.524758 -240.99774) (xy 384.524758 -241.04219)
			(xy 384.624834 -241.142266)
		)
		(stroke
			(width 0)
			(type solid)
		)
		(fill yes)
		(layer "In2.Cu")
		(net "M_I_CPU0_SA_DQ<27>")
	)
	(gr_poly
		(pts
			(xy 384.72491 -239.826038) (xy 384.624834 -239.725962) (xy 384.524758 -239.826038) (xy 384.524758 -239.870488)
			(xy 384.72491 -239.870488)
		)
		(stroke
			(width 0)
			(type solid)
		)
		(fill yes)
		(layer "In2.Cu")
		(net "M_I_CPU0_SA_DQ<24>")
	)
	(gr_poly
		(pts
			(xy 384.72491 -239.422178) (xy 384.72491 -239.377728) (xy 384.524758 -239.377728) (xy 384.524758 -239.422178)
			(xy 384.624834 -239.522254)
		)
		(stroke
			(width 0)
			(type solid)
		)
		(fill yes)
		(layer "In2.Cu")
		(net "M_I_CPU0_SA_DQ<23>")
	)
	(gr_poly
		(pts
			(xy 384.72491 -238.206026) (xy 384.624834 -238.10595) (xy 384.524758 -238.206026) (xy 384.524758 -238.250476)
			(xy 384.72491 -238.250476)
		)
		(stroke
			(width 0)
			(type solid)
		)
		(fill yes)
		(layer "In2.Cu")
		(net "M_I_CPU0_SA_DQ<20>")
	)
	(gr_poly
		(pts
			(xy 384.72491 -237.80242) (xy 384.72491 -237.754668) (xy 384.524758 -237.754668) (xy 384.524758 -237.80242)
			(xy 384.624834 -237.902242)
		)
		(stroke
			(width 0)
			(type solid)
		)
		(fill yes)
		(layer "In2.Cu")
		(net "M_I_CPU0_SA_DQS_DP<7>")
	)
	(gr_poly
		(pts
			(xy 384.72491 -236.58576) (xy 384.624834 -236.485938) (xy 384.524758 -236.58576) (xy 384.524758 -236.633512)
			(xy 384.72491 -236.633512)
		)
		(stroke
			(width 0)
			(type solid)
		)
		(fill yes)
		(layer "In2.Cu")
		(net "M_I_CPU0_SA_DQS_DP<2>")
	)
	(gr_poly
		(pts
			(xy 384.72491 -236.182154) (xy 384.72491 -236.137704) (xy 384.524758 -236.137704) (xy 384.524758 -236.182154)
			(xy 384.624834 -236.28223)
		)
		(stroke
			(width 0)
			(type solid)
		)
		(fill yes)
		(layer "In2.Cu")
		(net "M_I_CPU0_SA_DQ<19>")
	)
	(gr_poly
		(pts
			(xy 384.72491 -234.966002) (xy 384.624834 -234.865926) (xy 384.524758 -234.966002) (xy 384.524758 -235.010452)
			(xy 384.72491 -235.010452)
		)
		(stroke
			(width 0)
			(type solid)
		)
		(fill yes)
		(layer "In2.Cu")
		(net "M_I_CPU0_SA_DQ<16>")
	)
	(gr_poly
		(pts
			(xy 384.72491 -234.562142) (xy 384.72491 -234.517692) (xy 384.524758 -234.517692) (xy 384.524758 -234.562142)
			(xy 384.624834 -234.662218)
		)
		(stroke
			(width 0)
			(type solid)
		)
		(fill yes)
		(layer "In2.Cu")
		(net "M_I_CPU0_SA_DQ<15>")
	)
	(gr_poly
		(pts
			(xy 384.72491 -233.34599) (xy 384.624834 -233.245914) (xy 384.524758 -233.34599) (xy 384.524758 -233.39044)
			(xy 384.72491 -233.39044)
		)
		(stroke
			(width 0)
			(type solid)
		)
		(fill yes)
		(layer "In2.Cu")
		(net "M_I_CPU0_SA_DQ<12>")
	)
	(gr_poly
		(pts
			(xy 384.72491 -232.942384) (xy 384.72491 -232.894632) (xy 384.524758 -232.894632) (xy 384.524758 -232.942384)
			(xy 384.624834 -233.042206)
		)
		(stroke
			(width 0)
			(type solid)
		)
		(fill yes)
		(layer "In2.Cu")
		(net "M_I_CPU0_SA_DQS_DP<6>")
	)
	(gr_poly
		(pts
			(xy 384.72491 -231.725724) (xy 384.624834 -231.625902) (xy 384.524758 -231.725724) (xy 384.524758 -231.773476)
			(xy 384.72491 -231.773476)
		)
		(stroke
			(width 0)
			(type solid)
		)
		(fill yes)
		(layer "In2.Cu")
		(net "M_I_CPU0_SA_DQS_DP<1>")
	)
	(gr_poly
		(pts
			(xy 384.72491 -231.322372) (xy 384.72491 -231.277922) (xy 384.524758 -231.277922) (xy 384.524758 -231.322372)
			(xy 384.624834 -231.422448)
		)
		(stroke
			(width 0)
			(type solid)
		)
		(fill yes)
		(layer "In2.Cu")
		(net "M_I_CPU0_SA_DQ<11>")
	)
	(gr_poly
		(pts
			(xy 384.72491 -230.105966) (xy 384.624834 -230.006144) (xy 384.524758 -230.105966) (xy 384.524758 -230.150416)
			(xy 384.72491 -230.150416)
		)
		(stroke
			(width 0)
			(type solid)
		)
		(fill yes)
		(layer "In2.Cu")
		(net "M_I_CPU0_SA_DQ<8>")
	)
	(gr_poly
		(pts
			(xy 384.72491 -229.70236) (xy 384.72491 -229.65791) (xy 384.524758 -229.65791) (xy 384.524758 -229.70236)
			(xy 384.624834 -229.802436)
		)
		(stroke
			(width 0)
			(type solid)
		)
		(fill yes)
		(layer "In2.Cu")
		(net "M_I_CPU0_SA_DQ<7>")
	)
	(gr_poly
		(pts
			(xy 384.72491 -228.486208) (xy 384.624834 -228.386132) (xy 384.524758 -228.486208) (xy 384.524758 -228.530658)
			(xy 384.72491 -228.530658)
		)
		(stroke
			(width 0)
			(type solid)
		)
		(fill yes)
		(layer "In2.Cu")
		(net "M_I_CPU0_SA_DQ<4>")
	)
	(gr_poly
		(pts
			(xy 384.72491 -228.082602) (xy 384.72491 -228.03485) (xy 384.524758 -228.03485) (xy 384.524758 -228.082602)
			(xy 384.624834 -228.182424)
		)
		(stroke
			(width 0)
			(type solid)
		)
		(fill yes)
		(layer "In2.Cu")
		(net "M_I_CPU0_SA_DQS_DP<5>")
	)
	(gr_poly
		(pts
			(xy 384.72491 -226.865942) (xy 384.624834 -226.76612) (xy 384.524758 -226.865942) (xy 384.524758 -226.913694)
			(xy 384.72491 -226.913694)
		)
		(stroke
			(width 0)
			(type solid)
		)
		(fill yes)
		(layer "In2.Cu")
		(net "M_I_CPU0_SA_DQS_DP<0>")
	)
	(gr_poly
		(pts
			(xy 384.72491 -226.462336) (xy 384.72491 -226.417886) (xy 384.524758 -226.417886) (xy 384.524758 -226.462336)
			(xy 384.624834 -226.562412)
		)
		(stroke
			(width 0)
			(type solid)
		)
		(fill yes)
		(layer "In2.Cu")
		(net "M_I_CPU0_SA_DQ<3>")
	)
	(gr_poly
		(pts
			(xy 384.72491 -225.246184) (xy 384.624834 -225.146108) (xy 384.524758 -225.246184) (xy 384.524758 -225.290634)
			(xy 384.72491 -225.290634)
		)
		(stroke
			(width 0)
			(type solid)
		)
		(fill yes)
		(layer "In2.Cu")
		(net "M_I_CPU0_SA_DQ<0>")
	)
	(gr_poly
		(pts
			(xy 385.024884 -292.91788) (xy 384.924808 -292.817804) (xy 384.824732 -292.91788) (xy 384.824732 -292.96233)
			(xy 385.024884 -292.96233)
		)
		(stroke
			(width 0)
			(type solid)
		)
		(fill yes)
		(layer "In2.Cu")
		(net "M_I_CPU0_SB_DQ<29>")
	)
	(gr_poly
		(pts
			(xy 385.024884 -292.51402) (xy 385.024884 -292.46957) (xy 384.824732 -292.46957) (xy 384.824732 -292.51402)
			(xy 384.924808 -292.614096)
		)
		(stroke
			(width 0)
			(type solid)
		)
		(fill yes)
		(layer "In2.Cu")
		(net "M_I_CPU0_SB_DQ<30>")
	)
	(gr_poly
		(pts
			(xy 385.024884 -291.297614) (xy 384.924808 -291.197792) (xy 384.824732 -291.297614) (xy 384.824732 -291.345366)
			(xy 385.024884 -291.345366)
		)
		(stroke
			(width 0)
			(type solid)
		)
		(fill yes)
		(layer "In2.Cu")
		(net "M_I_CPU0_SB_DQS_DN<8>")
	)
	(gr_poly
		(pts
			(xy 385.024884 -290.894262) (xy 385.024884 -290.84651) (xy 384.824732 -290.84651) (xy 384.824732 -290.894262)
			(xy 384.924808 -290.994084)
		)
		(stroke
			(width 0)
			(type solid)
		)
		(fill yes)
		(layer "In2.Cu")
		(net "M_I_CPU0_SB_DQS_DN<3>")
	)
	(gr_poly
		(pts
			(xy 385.024884 -289.677856) (xy 384.924808 -289.57778) (xy 384.824732 -289.677856) (xy 384.824732 -289.722306)
			(xy 385.024884 -289.722306)
		)
		(stroke
			(width 0)
			(type solid)
		)
		(fill yes)
		(layer "In2.Cu")
		(net "M_I_CPU0_SB_DQ<25>")
	)
	(gr_poly
		(pts
			(xy 385.024884 -289.273996) (xy 385.024884 -289.229546) (xy 384.824732 -289.229546) (xy 384.824732 -289.273996)
			(xy 384.924808 -289.374072)
		)
		(stroke
			(width 0)
			(type solid)
		)
		(fill yes)
		(layer "In2.Cu")
		(net "M_I_CPU0_SB_DQ<26>")
	)
	(gr_poly
		(pts
			(xy 385.024884 -288.057844) (xy 384.924808 -287.957768) (xy 384.824732 -288.057844) (xy 384.824732 -288.102294)
			(xy 385.024884 -288.102294)
		)
		(stroke
			(width 0)
			(type solid)
		)
		(fill yes)
		(layer "In2.Cu")
		(net "M_I_CPU0_SB_DQ<21>")
	)
	(gr_poly
		(pts
			(xy 385.024884 -287.654238) (xy 385.024884 -287.609788) (xy 384.824732 -287.609788) (xy 384.824732 -287.654238)
			(xy 384.924808 -287.75406)
		)
		(stroke
			(width 0)
			(type solid)
		)
		(fill yes)
		(layer "In2.Cu")
		(net "M_I_CPU0_SB_DQ<22>")
	)
	(gr_poly
		(pts
			(xy 385.024884 -286.437832) (xy 384.924808 -286.337756) (xy 384.824732 -286.437832) (xy 384.824732 -286.485584)
			(xy 385.024884 -286.485584)
		)
		(stroke
			(width 0)
			(type solid)
		)
		(fill yes)
		(layer "In2.Cu")
		(net "M_I_CPU0_SB_DQS_DN<7>")
	)
	(gr_poly
		(pts
			(xy 385.024884 -286.03448) (xy 385.024884 -285.986728) (xy 384.824732 -285.986728) (xy 384.824732 -286.03448)
			(xy 384.924808 -286.134302)
		)
		(stroke
			(width 0)
			(type solid)
		)
		(fill yes)
		(layer "In2.Cu")
		(net "M_I_CPU0_SB_DQS_DN<2>")
	)
	(gr_poly
		(pts
			(xy 385.024884 -284.818074) (xy 384.924808 -284.717998) (xy 384.824732 -284.818074) (xy 384.824732 -284.862524)
			(xy 385.024884 -284.862524)
		)
		(stroke
			(width 0)
			(type solid)
		)
		(fill yes)
		(layer "In2.Cu")
		(net "M_I_CPU0_SB_DQ<17>")
	)
	(gr_poly
		(pts
			(xy 385.024884 -284.414214) (xy 385.024884 -284.369764) (xy 384.824732 -284.369764) (xy 384.824732 -284.414214)
			(xy 384.924808 -284.51429)
		)
		(stroke
			(width 0)
			(type solid)
		)
		(fill yes)
		(layer "In2.Cu")
		(net "M_I_CPU0_SB_DQ<18>")
	)
	(gr_poly
		(pts
			(xy 385.024884 -283.198062) (xy 384.924808 -283.097986) (xy 384.824732 -283.198062) (xy 384.824732 -283.242512)
			(xy 385.024884 -283.242512)
		)
		(stroke
			(width 0)
			(type solid)
		)
		(fill yes)
		(layer "In2.Cu")
		(net "M_I_CPU0_SB_DQ<13>")
	)
	(gr_poly
		(pts
			(xy 385.024884 -282.794202) (xy 385.024884 -282.749752) (xy 384.824732 -282.749752) (xy 384.824732 -282.794202)
			(xy 384.924808 -282.894278)
		)
		(stroke
			(width 0)
			(type solid)
		)
		(fill yes)
		(layer "In2.Cu")
		(net "M_I_CPU0_SB_DQ<14>")
	)
	(gr_poly
		(pts
			(xy 385.024884 -281.577796) (xy 384.924808 -281.477974) (xy 384.824732 -281.577796) (xy 384.824732 -281.625548)
			(xy 385.024884 -281.625548)
		)
		(stroke
			(width 0)
			(type solid)
		)
		(fill yes)
		(layer "In2.Cu")
		(net "M_I_CPU0_SB_DQS_DN<6>")
	)
	(gr_poly
		(pts
			(xy 385.024884 -281.174444) (xy 385.024884 -281.126692) (xy 384.824732 -281.126692) (xy 384.824732 -281.174444)
			(xy 384.924808 -281.274266)
		)
		(stroke
			(width 0)
			(type solid)
		)
		(fill yes)
		(layer "In2.Cu")
		(net "M_I_CPU0_SB_DQS_DN<1>")
	)
	(gr_poly
		(pts
			(xy 385.024884 -279.958038) (xy 384.924808 -279.857962) (xy 384.824732 -279.958038) (xy 384.824732 -280.002488)
			(xy 385.024884 -280.002488)
		)
		(stroke
			(width 0)
			(type solid)
		)
		(fill yes)
		(layer "In2.Cu")
		(net "M_I_CPU0_SB_DQ<9>")
	)
	(gr_poly
		(pts
			(xy 385.024884 -279.554178) (xy 385.024884 -279.509728) (xy 384.824732 -279.509728) (xy 384.824732 -279.554178)
			(xy 384.924808 -279.654254)
		)
		(stroke
			(width 0)
			(type solid)
		)
		(fill yes)
		(layer "In2.Cu")
		(net "M_I_CPU0_SB_DQ<10>")
	)
	(gr_poly
		(pts
			(xy 385.024884 -278.338026) (xy 384.924808 -278.23795) (xy 384.824732 -278.338026) (xy 384.824732 -278.382476)
			(xy 385.024884 -278.382476)
		)
		(stroke
			(width 0)
			(type solid)
		)
		(fill yes)
		(layer "In2.Cu")
		(net "M_I_CPU0_SB_DQ<5>")
	)
	(gr_poly
		(pts
			(xy 385.024884 -277.934166) (xy 385.024884 -277.889716) (xy 384.824732 -277.889716) (xy 384.824732 -277.934166)
			(xy 384.924808 -278.034242)
		)
		(stroke
			(width 0)
			(type solid)
		)
		(fill yes)
		(layer "In2.Cu")
		(net "M_I_CPU0_SB_DQ<6>")
	)
	(gr_poly
		(pts
			(xy 385.024884 -276.71776) (xy 384.924808 -276.617938) (xy 384.824732 -276.71776) (xy 384.824732 -276.765512)
			(xy 385.024884 -276.765512)
		)
		(stroke
			(width 0)
			(type solid)
		)
		(fill yes)
		(layer "In2.Cu")
		(net "M_I_CPU0_SB_DQS_DN<5>")
	)
	(gr_poly
		(pts
			(xy 385.024884 -276.314408) (xy 385.024884 -276.266656) (xy 384.824732 -276.266656) (xy 384.824732 -276.314408)
			(xy 384.924808 -276.41423)
		)
		(stroke
			(width 0)
			(type solid)
		)
		(fill yes)
		(layer "In2.Cu")
		(net "M_I_CPU0_SB_DQS_DN<0>")
	)
	(gr_poly
		(pts
			(xy 385.024884 -275.098002) (xy 384.924808 -274.997926) (xy 384.824732 -275.098002) (xy 384.824732 -275.142452)
			(xy 385.024884 -275.142452)
		)
		(stroke
			(width 0)
			(type solid)
		)
		(fill yes)
		(layer "In2.Cu")
		(net "M_I_CPU0_SB_DQ<1>")
	)
	(gr_poly
		(pts
			(xy 385.024884 -274.694142) (xy 385.024884 -274.649692) (xy 384.824732 -274.649692) (xy 384.824732 -274.694142)
			(xy 384.924808 -274.794218)
		)
		(stroke
			(width 0)
			(type solid)
		)
		(fill yes)
		(layer "In2.Cu")
		(net "M_I_CPU0_SB_DQ<2>")
	)
	(gr_poly
		(pts
			(xy 385.024884 -273.47799) (xy 384.924808 -273.377914) (xy 384.824732 -273.47799) (xy 384.824732 -273.52244)
			(xy 385.024884 -273.52244)
		)
		(stroke
			(width 0)
			(type solid)
		)
		(fill yes)
		(layer "In2.Cu")
		(net "M_I_CPU0_SB_CB<1>")
	)
	(gr_poly
		(pts
			(xy 385.024884 -273.07413) (xy 385.024884 -273.02968) (xy 384.824732 -273.02968) (xy 384.824732 -273.07413)
			(xy 384.924808 -273.174206)
		)
		(stroke
			(width 0)
			(type solid)
		)
		(fill yes)
		(layer "In2.Cu")
		(net "M_I_CPU0_SB_CB<2>")
	)
	(gr_poly
		(pts
			(xy 385.024884 -271.857724) (xy 384.924808 -271.757902) (xy 384.824732 -271.857724) (xy 384.824732 -271.905476)
			(xy 385.024884 -271.905476)
		)
		(stroke
			(width 0)
			(type solid)
		)
		(fill yes)
		(layer "In2.Cu")
		(net "M_I_CPU0_SB_DQS_DN<4>")
	)
	(gr_poly
		(pts
			(xy 385.024884 -271.454372) (xy 385.024884 -271.40662) (xy 384.824732 -271.40662) (xy 384.824732 -271.454372)
			(xy 384.924808 -271.554194)
		)
		(stroke
			(width 0)
			(type solid)
		)
		(fill yes)
		(layer "In2.Cu")
		(net "M_I_CPU0_SB_DQS_DN<9>")
	)
	(gr_poly
		(pts
			(xy 385.024884 -270.237966) (xy 384.924808 -270.13789) (xy 384.824732 -270.237966) (xy 384.824732 -270.282416)
			(xy 385.024884 -270.282416)
		)
		(stroke
			(width 0)
			(type solid)
		)
		(fill yes)
		(layer "In2.Cu")
		(net "M_I_CPU0_SB_CB<5>")
	)
	(gr_poly
		(pts
			(xy 385.024884 -269.834106) (xy 385.024884 -269.789656) (xy 384.824732 -269.789656) (xy 384.824732 -269.834106)
			(xy 384.924808 -269.934182)
		)
		(stroke
			(width 0)
			(type solid)
		)
		(fill yes)
		(layer "In2.Cu")
		(net "M_I_CPU0_SB_CB<6>")
	)
	(gr_poly
		(pts
			(xy 385.024884 -266.997942) (xy 384.924808 -266.897866) (xy 384.824732 -266.997942) (xy 384.824732 -267.042392)
			(xy 385.024884 -267.042392)
		)
		(stroke
			(width 0)
			(type solid)
		)
		(fill yes)
		(layer "In2.Cu")
		(net "M_I_CPU0_SA_RSP<0>")
	)
	(gr_poly
		(pts
			(xy 385.024884 -266.594082) (xy 385.024884 -266.549632) (xy 384.824732 -266.549632) (xy 384.824732 -266.594082)
			(xy 384.924808 -266.694158)
		)
		(stroke
			(width 0)
			(type solid)
		)
		(fill yes)
		(layer "In2.Cu")
		(net "M_I_CPU0_SB_CS_N<1>")
	)
	(gr_poly
		(pts
			(xy 385.024884 -265.37793) (xy 384.924808 -265.277854) (xy 384.824732 -265.37793) (xy 384.824732 -265.42238)
			(xy 385.024884 -265.42238)
		)
		(stroke
			(width 0)
			(type solid)
		)
		(fill yes)
		(layer "In2.Cu")
		(net "M_I_CPU0_SB_PAR")
	)
	(gr_poly
		(pts
			(xy 385.024884 -263.757918) (xy 384.924808 -263.657842) (xy 384.824732 -263.757918) (xy 384.824732 -263.802368)
			(xy 385.024884 -263.802368)
		)
		(stroke
			(width 0)
			(type solid)
		)
		(fill yes)
		(layer "In2.Cu")
		(net "M_I_CPU0_SB_CA<4>")
	)
	(gr_poly
		(pts
			(xy 385.024884 -263.354058) (xy 385.024884 -263.309608) (xy 384.824732 -263.309608) (xy 384.824732 -263.354058)
			(xy 384.924808 -263.454134)
		)
		(stroke
			(width 0)
			(type solid)
		)
		(fill yes)
		(layer "In2.Cu")
		(net "M_I_CPU0_SB_CA<3>")
	)
	(gr_poly
		(pts
			(xy 385.024884 -262.137906) (xy 384.924808 -262.03783) (xy 384.824732 -262.137906) (xy 384.824732 -262.182356)
			(xy 385.024884 -262.182356)
		)
		(stroke
			(width 0)
			(type solid)
		)
		(fill yes)
		(layer "In2.Cu")
		(net "M_I_CPU0_SB_CA<0>")
	)
	(gr_poly
		(pts
			(xy 385.19481 -256.432558) (xy 385.19481 -256.384806) (xy 384.994658 -256.384806) (xy 384.994658 -256.432558)
			(xy 385.094734 -256.53238)
		)
		(stroke
			(width 0)
			(type solid)
		)
		(fill yes)
		(layer "In2.Cu")
		(net "M_I_CPU0_CLK_DN<0>")
	)
	(gr_poly
		(pts
			(xy 385.19481 -255.216152) (xy 385.094734 -255.116076) (xy 384.994658 -255.216152) (xy 384.994658 -255.260602)
			(xy 385.19481 -255.260602)
		)
		(stroke
			(width 0)
			(type solid)
		)
		(fill yes)
		(layer "In2.Cu")
		(net "M_I_CPU0_SA_CA<6>")
	)
	(gr_poly
		(pts
			(xy 385.19481 -254.812292) (xy 385.19481 -254.767842) (xy 384.994658 -254.767842) (xy 384.994658 -254.812292)
			(xy 385.094734 -254.912368)
		)
		(stroke
			(width 0)
			(type solid)
		)
		(fill yes)
		(layer "In2.Cu")
		(net "M_I_CPU0_SA_CA<5>")
	)
	(gr_poly
		(pts
			(xy 385.19481 -253.59614) (xy 385.094734 -253.496064) (xy 384.994658 -253.59614) (xy 384.994658 -253.64059)
			(xy 385.19481 -253.64059)
		)
		(stroke
			(width 0)
			(type solid)
		)
		(fill yes)
		(layer "In2.Cu")
		(net "M_I_CPU0_SA_CA<2>")
	)
	(gr_poly
		(pts
			(xy 385.19481 -253.19228) (xy 385.19481 -253.14783) (xy 384.994658 -253.14783) (xy 384.994658 -253.19228)
			(xy 385.094734 -253.292356)
		)
		(stroke
			(width 0)
			(type solid)
		)
		(fill yes)
		(layer "In2.Cu")
		(net "M_I_CPU0_SA_CA<1>")
	)
	(gr_poly
		(pts
			(xy 385.19481 -251.976128) (xy 385.094734 -251.876052) (xy 384.994658 -251.976128) (xy 384.994658 -252.020578)
			(xy 385.19481 -252.020578)
		)
		(stroke
			(width 0)
			(type solid)
		)
		(fill yes)
		(layer "In2.Cu")
		(net "M_I_CPU0_SA_CS_N<1>")
	)
	(gr_poly
		(pts
			(xy 385.19481 -250.356116) (xy 385.094734 -250.25604) (xy 384.994658 -250.356116) (xy 384.994658 -250.400566)
			(xy 385.19481 -250.400566)
		)
		(stroke
			(width 0)
			(type solid)
		)
		(fill yes)
		(layer "In2.Cu")
		(net "M_I_CPU0_ALERT_R_N")
	)
	(gr_poly
		(pts
			(xy 385.19481 -248.736104) (xy 385.094734 -248.636028) (xy 384.994658 -248.736104) (xy 384.994658 -248.780554)
			(xy 385.19481 -248.780554)
		)
		(stroke
			(width 0)
			(type solid)
		)
		(fill yes)
		(layer "In2.Cu")
		(net "M_I_CPU0_SA_CB<5>")
	)
	(gr_poly
		(pts
			(xy 385.19481 -248.332244) (xy 385.19481 -248.287794) (xy 384.994658 -248.287794) (xy 384.994658 -248.332244)
			(xy 385.094734 -248.43232)
		)
		(stroke
			(width 0)
			(type solid)
		)
		(fill yes)
		(layer "In2.Cu")
		(net "M_I_CPU0_SA_CB<6>")
	)
	(gr_poly
		(pts
			(xy 385.19481 -247.115838) (xy 385.094734 -247.016016) (xy 384.994658 -247.115838) (xy 384.994658 -247.16359)
			(xy 385.19481 -247.16359)
		)
		(stroke
			(width 0)
			(type solid)
		)
		(fill yes)
		(layer "In2.Cu")
		(net "M_I_CPU0_SA_DQS_DN<9>")
	)
	(gr_poly
		(pts
			(xy 385.19481 -246.712486) (xy 385.19481 -246.664734) (xy 384.994658 -246.664734) (xy 384.994658 -246.712486)
			(xy 385.094734 -246.812308)
		)
		(stroke
			(width 0)
			(type solid)
		)
		(fill yes)
		(layer "In2.Cu")
		(net "M_I_CPU0_SA_DQS_DN<4>")
	)
	(gr_poly
		(pts
			(xy 385.19481 -245.49608) (xy 385.094734 -245.396004) (xy 384.994658 -245.49608) (xy 384.994658 -245.54053)
			(xy 385.19481 -245.54053)
		)
		(stroke
			(width 0)
			(type solid)
		)
		(fill yes)
		(layer "In2.Cu")
		(net "M_I_CPU0_SA_CB<1>")
	)
	(gr_poly
		(pts
			(xy 385.19481 -245.09222) (xy 385.19481 -245.04777) (xy 384.994658 -245.04777) (xy 384.994658 -245.09222)
			(xy 385.094734 -245.192296)
		)
		(stroke
			(width 0)
			(type solid)
		)
		(fill yes)
		(layer "In2.Cu")
		(net "M_I_CPU0_SA_CB<2>")
	)
	(gr_poly
		(pts
			(xy 385.19481 -243.876068) (xy 385.094734 -243.775992) (xy 384.994658 -243.876068) (xy 384.994658 -243.920518)
			(xy 385.19481 -243.920518)
		)
		(stroke
			(width 0)
			(type solid)
		)
		(fill yes)
		(layer "In2.Cu")
		(net "M_I_CPU0_SA_DQ<29>")
	)
	(gr_poly
		(pts
			(xy 385.19481 -243.472208) (xy 385.19481 -243.427758) (xy 384.994658 -243.427758) (xy 384.994658 -243.472208)
			(xy 385.094734 -243.572284)
		)
		(stroke
			(width 0)
			(type solid)
		)
		(fill yes)
		(layer "In2.Cu")
		(net "M_I_CPU0_SA_DQ<30>")
	)
	(gr_poly
		(pts
			(xy 385.19481 -242.255802) (xy 385.094734 -242.15598) (xy 384.994658 -242.255802) (xy 384.994658 -242.303554)
			(xy 385.19481 -242.303554)
		)
		(stroke
			(width 0)
			(type solid)
		)
		(fill yes)
		(layer "In2.Cu")
		(net "M_I_CPU0_SA_DQS_DN<8>")
	)
	(gr_poly
		(pts
			(xy 385.19481 -241.85245) (xy 385.19481 -241.804698) (xy 384.994658 -241.804698) (xy 384.994658 -241.85245)
			(xy 385.094734 -241.952272)
		)
		(stroke
			(width 0)
			(type solid)
		)
		(fill yes)
		(layer "In2.Cu")
		(net "M_I_CPU0_SA_DQS_DN<3>")
	)
	(gr_poly
		(pts
			(xy 385.19481 -240.636044) (xy 385.094734 -240.535968) (xy 384.994658 -240.636044) (xy 384.994658 -240.680494)
			(xy 385.19481 -240.680494)
		)
		(stroke
			(width 0)
			(type solid)
		)
		(fill yes)
		(layer "In2.Cu")
		(net "M_I_CPU0_SA_DQ<25>")
	)
	(gr_poly
		(pts
			(xy 385.19481 -240.232184) (xy 385.19481 -240.187734) (xy 384.994658 -240.187734) (xy 384.994658 -240.232184)
			(xy 385.094734 -240.33226)
		)
		(stroke
			(width 0)
			(type solid)
		)
		(fill yes)
		(layer "In2.Cu")
		(net "M_I_CPU0_SA_DQ<26>")
	)
	(gr_poly
		(pts
			(xy 385.19481 -239.016032) (xy 385.094734 -238.915956) (xy 384.994658 -239.016032) (xy 384.994658 -239.060482)
			(xy 385.19481 -239.060482)
		)
		(stroke
			(width 0)
			(type solid)
		)
		(fill yes)
		(layer "In2.Cu")
		(net "M_I_CPU0_SA_DQ<21>")
	)
	(gr_poly
		(pts
			(xy 385.19481 -238.612172) (xy 385.19481 -238.567722) (xy 384.994658 -238.567722) (xy 384.994658 -238.612172)
			(xy 385.094734 -238.712248)
		)
		(stroke
			(width 0)
			(type solid)
		)
		(fill yes)
		(layer "In2.Cu")
		(net "M_I_CPU0_SA_DQ<22>")
	)
	(gr_poly
		(pts
			(xy 385.19481 -237.395766) (xy 385.094734 -237.295944) (xy 384.994658 -237.395766) (xy 384.994658 -237.443518)
			(xy 385.19481 -237.443518)
		)
		(stroke
			(width 0)
			(type solid)
		)
		(fill yes)
		(layer "In2.Cu")
		(net "M_I_CPU0_SA_DQS_DN<7>")
	)
	(gr_poly
		(pts
			(xy 385.19481 -236.992414) (xy 385.19481 -236.944662) (xy 384.994658 -236.944662) (xy 384.994658 -236.992414)
			(xy 385.094734 -237.092236)
		)
		(stroke
			(width 0)
			(type solid)
		)
		(fill yes)
		(layer "In2.Cu")
		(net "M_I_CPU0_SA_DQS_DN<2>")
	)
	(gr_poly
		(pts
			(xy 385.19481 -235.776008) (xy 385.094734 -235.675932) (xy 384.994658 -235.776008) (xy 384.994658 -235.820458)
			(xy 385.19481 -235.820458)
		)
		(stroke
			(width 0)
			(type solid)
		)
		(fill yes)
		(layer "In2.Cu")
		(net "M_I_CPU0_SA_DQ<17>")
	)
	(gr_poly
		(pts
			(xy 385.19481 -235.372148) (xy 385.19481 -235.327698) (xy 384.994658 -235.327698) (xy 384.994658 -235.372148)
			(xy 385.094734 -235.472224)
		)
		(stroke
			(width 0)
			(type solid)
		)
		(fill yes)
		(layer "In2.Cu")
		(net "M_I_CPU0_SA_DQ<18>")
	)
	(gr_poly
		(pts
			(xy 385.19481 -234.155996) (xy 385.094734 -234.05592) (xy 384.994658 -234.155996) (xy 384.994658 -234.200446)
			(xy 385.19481 -234.200446)
		)
		(stroke
			(width 0)
			(type solid)
		)
		(fill yes)
		(layer "In2.Cu")
		(net "M_I_CPU0_SA_DQ<13>")
	)
	(gr_poly
		(pts
			(xy 385.19481 -233.752136) (xy 385.19481 -233.707686) (xy 384.994658 -233.707686) (xy 384.994658 -233.752136)
			(xy 385.094734 -233.852212)
		)
		(stroke
			(width 0)
			(type solid)
		)
		(fill yes)
		(layer "In2.Cu")
		(net "M_I_CPU0_SA_DQ<14>")
	)
	(gr_poly
		(pts
			(xy 385.19481 -232.53573) (xy 385.094734 -232.435908) (xy 384.994658 -232.53573) (xy 384.994658 -232.583482)
			(xy 385.19481 -232.583482)
		)
		(stroke
			(width 0)
			(type solid)
		)
		(fill yes)
		(layer "In2.Cu")
		(net "M_I_CPU0_SA_DQS_DN<6>")
	)
	(gr_poly
		(pts
			(xy 385.19481 -232.132378) (xy 385.19481 -232.084626) (xy 384.994658 -232.084626) (xy 384.994658 -232.132378)
			(xy 385.094734 -232.2322)
		)
		(stroke
			(width 0)
			(type solid)
		)
		(fill yes)
		(layer "In2.Cu")
		(net "M_I_CPU0_SA_DQS_DN<1>")
	)
	(gr_poly
		(pts
			(xy 385.19481 -230.915972) (xy 385.094734 -230.815896) (xy 384.994658 -230.915972) (xy 384.994658 -230.960422)
			(xy 385.19481 -230.960422)
		)
		(stroke
			(width 0)
			(type solid)
		)
		(fill yes)
		(layer "In2.Cu")
		(net "M_I_CPU0_SA_DQ<9>")
	)
	(gr_poly
		(pts
			(xy 385.19481 -230.512366) (xy 385.19481 -230.467916) (xy 384.994658 -230.467916) (xy 384.994658 -230.512366)
			(xy 385.094734 -230.612188)
		)
		(stroke
			(width 0)
			(type solid)
		)
		(fill yes)
		(layer "In2.Cu")
		(net "M_I_CPU0_SA_DQ<10>")
	)
	(gr_poly
		(pts
			(xy 385.19481 -229.29596) (xy 385.094734 -229.195884) (xy 384.994658 -229.29596) (xy 384.994658 -229.34041)
			(xy 385.19481 -229.34041)
		)
		(stroke
			(width 0)
			(type solid)
		)
		(fill yes)
		(layer "In2.Cu")
		(net "M_I_CPU0_SA_DQ<5>")
	)
	(gr_poly
		(pts
			(xy 385.19481 -228.892354) (xy 385.19481 -228.847904) (xy 384.994658 -228.847904) (xy 384.994658 -228.892354)
			(xy 385.094734 -228.99243)
		)
		(stroke
			(width 0)
			(type solid)
		)
		(fill yes)
		(layer "In2.Cu")
		(net "M_I_CPU0_SA_DQ<6>")
	)
	(gr_poly
		(pts
			(xy 385.19481 -227.675948) (xy 385.094734 -227.576126) (xy 384.994658 -227.675948) (xy 384.994658 -227.7237)
			(xy 385.19481 -227.7237)
		)
		(stroke
			(width 0)
			(type solid)
		)
		(fill yes)
		(layer "In2.Cu")
		(net "M_I_CPU0_SA_DQS_DN<5>")
	)
	(gr_poly
		(pts
			(xy 385.19481 -227.272596) (xy 385.19481 -227.224844) (xy 384.994658 -227.224844) (xy 384.994658 -227.272596)
			(xy 385.094734 -227.372418)
		)
		(stroke
			(width 0)
			(type solid)
		)
		(fill yes)
		(layer "In2.Cu")
		(net "M_I_CPU0_SA_DQS_DN<0>")
	)
	(gr_poly
		(pts
			(xy 385.19481 -226.05619) (xy 385.094734 -225.956114) (xy 384.994658 -226.05619) (xy 384.994658 -226.10064)
			(xy 385.19481 -226.10064)
		)
		(stroke
			(width 0)
			(type solid)
		)
		(fill yes)
		(layer "In2.Cu")
		(net "M_I_CPU0_SA_DQ<1>")
	)
	(gr_poly
		(pts
			(xy 385.19481 -225.65233) (xy 385.19481 -225.60788) (xy 384.994658 -225.60788) (xy 384.994658 -225.65233)
			(xy 385.094734 -225.752406)
		)
		(stroke
			(width 0)
			(type solid)
		)
		(fill yes)
		(layer "In2.Cu")
		(net "M_I_CPU0_SA_DQ<2>")
	)
	(gr_poly
		(pts
			(xy 385.494784 -293.324026) (xy 385.494784 -293.279576) (xy 385.294632 -293.279576) (xy 385.294632 -293.324026)
			(xy 385.394708 -293.424102)
		)
		(stroke
			(width 0)
			(type solid)
		)
		(fill yes)
		(layer "In2.Cu")
		(net "M_I_CPU0_SB_DQ<31>")
	)
	(gr_poly
		(pts
			(xy 385.494784 -292.107874) (xy 385.394708 -292.007798) (xy 385.294632 -292.107874) (xy 385.294632 -292.152324)
			(xy 385.494784 -292.152324)
		)
		(stroke
			(width 0)
			(type solid)
		)
		(fill yes)
		(layer "In2.Cu")
		(net "M_I_CPU0_SB_DQ<28>")
	)
	(gr_poly
		(pts
			(xy 385.494784 -291.704268) (xy 385.494784 -291.656516) (xy 385.294632 -291.656516) (xy 385.294632 -291.704268)
			(xy 385.394708 -291.80409)
		)
		(stroke
			(width 0)
			(type solid)
		)
		(fill yes)
		(layer "In2.Cu")
		(net "M_I_CPU0_SB_DQS_DP<8>")
	)
	(gr_poly
		(pts
			(xy 385.494784 -290.487608) (xy 385.394708 -290.387786) (xy 385.294632 -290.487608) (xy 385.294632 -290.53536)
			(xy 385.494784 -290.53536)
		)
		(stroke
			(width 0)
			(type solid)
		)
		(fill yes)
		(layer "In2.Cu")
		(net "M_I_CPU0_SB_DQS_DP<3>")
	)
	(gr_poly
		(pts
			(xy 385.494784 -290.084002) (xy 385.494784 -290.039552) (xy 385.294632 -290.039552) (xy 385.294632 -290.084002)
			(xy 385.394708 -290.184078)
		)
		(stroke
			(width 0)
			(type solid)
		)
		(fill yes)
		(layer "In2.Cu")
		(net "M_I_CPU0_SB_DQ<27>")
	)
	(gr_poly
		(pts
			(xy 385.494784 -288.86785) (xy 385.394708 -288.767774) (xy 385.294632 -288.86785) (xy 385.294632 -288.9123)
			(xy 385.494784 -288.9123)
		)
		(stroke
			(width 0)
			(type solid)
		)
		(fill yes)
		(layer "In2.Cu")
		(net "M_I_CPU0_SB_DQ<24>")
	)
	(gr_poly
		(pts
			(xy 385.494784 -288.464244) (xy 385.494784 -288.419794) (xy 385.294632 -288.419794) (xy 385.294632 -288.464244)
			(xy 385.394708 -288.56432)
		)
		(stroke
			(width 0)
			(type solid)
		)
		(fill yes)
		(layer "In2.Cu")
		(net "M_I_CPU0_SB_DQ<23>")
	)
	(gr_poly
		(pts
			(xy 385.494784 -287.247838) (xy 385.394708 -287.148016) (xy 385.294632 -287.247838) (xy 385.294632 -287.292288)
			(xy 385.494784 -287.292288)
		)
		(stroke
			(width 0)
			(type solid)
		)
		(fill yes)
		(layer "In2.Cu")
		(net "M_I_CPU0_SB_DQ<20>")
	)
	(gr_poly
		(pts
			(xy 385.494784 -286.844232) (xy 385.494784 -286.79648) (xy 385.294632 -286.79648) (xy 385.294632 -286.844232)
			(xy 385.394708 -286.944308)
		)
		(stroke
			(width 0)
			(type solid)
		)
		(fill yes)
		(layer "In2.Cu")
		(net "M_I_CPU0_SB_DQS_DP<7>")
	)
	(gr_poly
		(pts
			(xy 385.494784 -285.627826) (xy 385.394708 -285.528004) (xy 385.294632 -285.627826) (xy 385.294632 -285.675578)
			(xy 385.494784 -285.675578)
		)
		(stroke
			(width 0)
			(type solid)
		)
		(fill yes)
		(layer "In2.Cu")
		(net "M_I_CPU0_SB_DQS_DP<2>")
	)
	(gr_poly
		(pts
			(xy 385.494784 -285.22422) (xy 385.494784 -285.17977) (xy 385.294632 -285.17977) (xy 385.294632 -285.22422)
			(xy 385.394708 -285.324296)
		)
		(stroke
			(width 0)
			(type solid)
		)
		(fill yes)
		(layer "In2.Cu")
		(net "M_I_CPU0_SB_DQ<19>")
	)
	(gr_poly
		(pts
			(xy 385.494784 -284.008068) (xy 385.394708 -283.907992) (xy 385.294632 -284.008068) (xy 385.294632 -284.052518)
			(xy 385.494784 -284.052518)
		)
		(stroke
			(width 0)
			(type solid)
		)
		(fill yes)
		(layer "In2.Cu")
		(net "M_I_CPU0_SB_DQ<16>")
	)
	(gr_poly
		(pts
			(xy 385.494784 -283.604208) (xy 385.494784 -283.559758) (xy 385.294632 -283.559758) (xy 385.294632 -283.604208)
			(xy 385.394708 -283.704284)
		)
		(stroke
			(width 0)
			(type solid)
		)
		(fill yes)
		(layer "In2.Cu")
		(net "M_I_CPU0_SB_DQ<15>")
	)
	(gr_poly
		(pts
			(xy 385.494784 -282.388056) (xy 385.394708 -282.28798) (xy 385.294632 -282.388056) (xy 385.294632 -282.432506)
			(xy 385.494784 -282.432506)
		)
		(stroke
			(width 0)
			(type solid)
		)
		(fill yes)
		(layer "In2.Cu")
		(net "M_I_CPU0_SB_DQ<12>")
	)
	(gr_poly
		(pts
			(xy 385.494784 -281.98445) (xy 385.494784 -281.936698) (xy 385.294632 -281.936698) (xy 385.294632 -281.98445)
			(xy 385.394708 -282.084272)
		)
		(stroke
			(width 0)
			(type solid)
		)
		(fill yes)
		(layer "In2.Cu")
		(net "M_I_CPU0_SB_DQS_DP<6>")
	)
	(gr_poly
		(pts
			(xy 385.494784 -280.76779) (xy 385.394708 -280.667968) (xy 385.294632 -280.76779) (xy 385.294632 -280.815542)
			(xy 385.494784 -280.815542)
		)
		(stroke
			(width 0)
			(type solid)
		)
		(fill yes)
		(layer "In2.Cu")
		(net "M_I_CPU0_SB_DQS_DP<1>")
	)
	(gr_poly
		(pts
			(xy 385.494784 -280.364184) (xy 385.494784 -280.319734) (xy 385.294632 -280.319734) (xy 385.294632 -280.364184)
			(xy 385.394708 -280.46426)
		)
		(stroke
			(width 0)
			(type solid)
		)
		(fill yes)
		(layer "In2.Cu")
		(net "M_I_CPU0_SB_DQ<11>")
	)
	(gr_poly
		(pts
			(xy 385.494784 -279.148032) (xy 385.394708 -279.047956) (xy 385.294632 -279.148032) (xy 385.294632 -279.192482)
			(xy 385.494784 -279.192482)
		)
		(stroke
			(width 0)
			(type solid)
		)
		(fill yes)
		(layer "In2.Cu")
		(net "M_I_CPU0_SB_DQ<8>")
	)
	(gr_poly
		(pts
			(xy 385.494784 -278.744172) (xy 385.494784 -278.699722) (xy 385.294632 -278.699722) (xy 385.294632 -278.744172)
			(xy 385.394708 -278.844248)
		)
		(stroke
			(width 0)
			(type solid)
		)
		(fill yes)
		(layer "In2.Cu")
		(net "M_I_CPU0_SB_DQ<7>")
	)
	(gr_poly
		(pts
			(xy 385.494784 -277.52802) (xy 385.394708 -277.427944) (xy 385.294632 -277.52802) (xy 385.294632 -277.57247)
			(xy 385.494784 -277.57247)
		)
		(stroke
			(width 0)
			(type solid)
		)
		(fill yes)
		(layer "In2.Cu")
		(net "M_I_CPU0_SB_DQ<4>")
	)
	(gr_poly
		(pts
			(xy 385.494784 -277.124414) (xy 385.494784 -277.076662) (xy 385.294632 -277.076662) (xy 385.294632 -277.124414)
			(xy 385.394708 -277.224236)
		)
		(stroke
			(width 0)
			(type solid)
		)
		(fill yes)
		(layer "In2.Cu")
		(net "M_I_CPU0_SB_DQS_DP<5>")
	)
	(gr_poly
		(pts
			(xy 385.494784 -275.907754) (xy 385.394708 -275.807932) (xy 385.294632 -275.907754) (xy 385.294632 -275.955506)
			(xy 385.494784 -275.955506)
		)
		(stroke
			(width 0)
			(type solid)
		)
		(fill yes)
		(layer "In2.Cu")
		(net "M_I_CPU0_SB_DQS_DP<0>")
	)
	(gr_poly
		(pts
			(xy 385.494784 -275.504148) (xy 385.494784 -275.459698) (xy 385.294632 -275.459698) (xy 385.294632 -275.504148)
			(xy 385.394708 -275.604224)
		)
		(stroke
			(width 0)
			(type solid)
		)
		(fill yes)
		(layer "In2.Cu")
		(net "M_I_CPU0_SB_DQ<3>")
	)
	(gr_poly
		(pts
			(xy 385.494784 -274.287996) (xy 385.394708 -274.18792) (xy 385.294632 -274.287996) (xy 385.294632 -274.332446)
			(xy 385.494784 -274.332446)
		)
		(stroke
			(width 0)
			(type solid)
		)
		(fill yes)
		(layer "In2.Cu")
		(net "M_I_CPU0_SB_DQ<0>")
	)
	(gr_poly
		(pts
			(xy 385.494784 -273.884136) (xy 385.494784 -273.839686) (xy 385.294632 -273.839686) (xy 385.294632 -273.884136)
			(xy 385.394708 -273.984212)
		)
		(stroke
			(width 0)
			(type solid)
		)
		(fill yes)
		(layer "In2.Cu")
		(net "M_I_CPU0_SB_CB<3>")
	)
	(gr_poly
		(pts
			(xy 385.494784 -272.667984) (xy 385.394708 -272.567908) (xy 385.294632 -272.667984) (xy 385.294632 -272.712434)
			(xy 385.494784 -272.712434)
		)
		(stroke
			(width 0)
			(type solid)
		)
		(fill yes)
		(layer "In2.Cu")
		(net "M_I_CPU0_SB_CB<0>")
	)
	(gr_poly
		(pts
			(xy 385.494784 -272.264378) (xy 385.494784 -272.216626) (xy 385.294632 -272.216626) (xy 385.294632 -272.264378)
			(xy 385.394708 -272.3642)
		)
		(stroke
			(width 0)
			(type solid)
		)
		(fill yes)
		(layer "In2.Cu")
		(net "M_I_CPU0_SB_DQS_DP<4>")
	)
	(gr_poly
		(pts
			(xy 385.494784 -271.047718) (xy 385.394708 -270.947896) (xy 385.294632 -271.047718) (xy 385.294632 -271.09547)
			(xy 385.494784 -271.09547)
		)
		(stroke
			(width 0)
			(type solid)
		)
		(fill yes)
		(layer "In2.Cu")
		(net "M_I_CPU0_SB_DQS_DP<9>")
	)
	(gr_poly
		(pts
			(xy 385.494784 -270.644112) (xy 385.494784 -270.599662) (xy 385.294632 -270.599662) (xy 385.294632 -270.644112)
			(xy 385.394708 -270.744188)
		)
		(stroke
			(width 0)
			(type solid)
		)
		(fill yes)
		(layer "In2.Cu")
		(net "M_I_CPU0_SB_CB<7>")
	)
	(gr_poly
		(pts
			(xy 385.494784 -269.42796) (xy 385.394708 -269.327884) (xy 385.294632 -269.42796) (xy 385.294632 -269.47241)
			(xy 385.494784 -269.47241)
		)
		(stroke
			(width 0)
			(type solid)
		)
		(fill yes)
		(layer "In2.Cu")
		(net "M_I_CPU0_SB_CB<4>")
	)
	(gr_poly
		(pts
			(xy 385.494784 -267.404088) (xy 385.494784 -267.359638) (xy 385.294632 -267.359638) (xy 385.294632 -267.404088)
			(xy 385.394708 -267.504164)
		)
		(stroke
			(width 0)
			(type solid)
		)
		(fill yes)
		(layer "In2.Cu")
		(net "M_I_CPU0_SB_RSP<0>")
	)
	(gr_poly
		(pts
			(xy 385.494784 -265.784076) (xy 385.494784 -265.739626) (xy 385.294632 -265.739626) (xy 385.294632 -265.784076)
			(xy 385.394708 -265.884152)
		)
		(stroke
			(width 0)
			(type solid)
		)
		(fill yes)
		(layer "In2.Cu")
		(net "M_I_CPU0_SB_CS_N<0>")
	)
	(gr_poly
		(pts
			(xy 385.494784 -264.567924) (xy 385.394708 -264.467848) (xy 385.294632 -264.567924) (xy 385.294632 -264.612374)
			(xy 385.494784 -264.612374)
		)
		(stroke
			(width 0)
			(type solid)
		)
		(fill yes)
		(layer "In2.Cu")
		(net "M_I_CPU0_SB_CA<6>")
	)
	(gr_poly
		(pts
			(xy 385.494784 -264.164064) (xy 385.494784 -264.119614) (xy 385.294632 -264.119614) (xy 385.294632 -264.164064)
			(xy 385.394708 -264.26414)
		)
		(stroke
			(width 0)
			(type solid)
		)
		(fill yes)
		(layer "In2.Cu")
		(net "M_I_CPU0_SB_CA<5>")
	)
	(gr_poly
		(pts
			(xy 385.494784 -262.947912) (xy 385.394708 -262.847836) (xy 385.294632 -262.947912) (xy 385.294632 -262.992362)
			(xy 385.494784 -262.992362)
		)
		(stroke
			(width 0)
			(type solid)
		)
		(fill yes)
		(layer "In2.Cu")
		(net "M_I_CPU0_SB_CA<2>")
	)
	(gr_poly
		(pts
			(xy 385.494784 -262.544052) (xy 385.494784 -262.499602) (xy 385.294632 -262.499602) (xy 385.294632 -262.544052)
			(xy 385.394708 -262.644128)
		)
		(stroke
			(width 0)
			(type solid)
		)
		(fill yes)
		(layer "In2.Cu")
		(net "M_I_CPU0_SB_CA<1>")
	)
	(gr_poly
		(pts
			(xy 385.664964 -256.025904) (xy 385.564888 -255.926082) (xy 385.464812 -256.025904) (xy 385.464812 -256.073656)
			(xy 385.664964 -256.073656)
		)
		(stroke
			(width 0)
			(type solid)
		)
		(fill yes)
		(layer "In2.Cu")
		(net "M_I_CPU0_CLK_DP<0>")
	)
	(gr_poly
		(pts
			(xy 385.664964 -255.622298) (xy 385.664964 -255.577848) (xy 385.464812 -255.577848) (xy 385.464812 -255.622298)
			(xy 385.564888 -255.722374)
		)
		(stroke
			(width 0)
			(type solid)
		)
		(fill yes)
		(layer "In2.Cu")
		(net "M_I_CPU0_SA_PAR")
	)
	(gr_poly
		(pts
			(xy 385.664964 -254.406146) (xy 385.564888 -254.30607) (xy 385.464812 -254.406146) (xy 385.464812 -254.450596)
			(xy 385.664964 -254.450596)
		)
		(stroke
			(width 0)
			(type solid)
		)
		(fill yes)
		(layer "In2.Cu")
		(net "M_I_CPU0_SA_CA<4>")
	)
	(gr_poly
		(pts
			(xy 385.664964 -254.002286) (xy 385.664964 -253.957836) (xy 385.464812 -253.957836) (xy 385.464812 -254.002286)
			(xy 385.564888 -254.102362)
		)
		(stroke
			(width 0)
			(type solid)
		)
		(fill yes)
		(layer "In2.Cu")
		(net "M_I_CPU0_SA_CA<3>")
	)
	(gr_poly
		(pts
			(xy 385.664964 -252.786134) (xy 385.564888 -252.686058) (xy 385.464812 -252.786134) (xy 385.464812 -252.830584)
			(xy 385.664964 -252.830584)
		)
		(stroke
			(width 0)
			(type solid)
		)
		(fill yes)
		(layer "In2.Cu")
		(net "M_I_CPU0_SA_CA<0>")
	)
	(gr_poly
		(pts
			(xy 385.664964 -251.166122) (xy 385.564888 -251.066046) (xy 385.464812 -251.166122) (xy 385.464812 -251.210572)
			(xy 385.664964 -251.210572)
		)
		(stroke
			(width 0)
			(type solid)
		)
		(fill yes)
		(layer "In2.Cu")
		(net "M_I_CPU0_SA_CS_N<0>")
	)
	(gr_poly
		(pts
			(xy 385.664964 -250.762262) (xy 385.664964 -250.717812) (xy 385.464812 -250.717812) (xy 385.464812 -250.762262)
			(xy 385.564888 -250.862338)
		)
		(stroke
			(width 0)
			(type solid)
		)
		(fill yes)
		(layer "In2.Cu")
		(net "M_I_CPU0_RESET_N")
	)
	(gr_poly
		(pts
			(xy 385.664964 -249.14225) (xy 385.664964 -249.0978) (xy 385.464812 -249.0978) (xy 385.464812 -249.14225)
			(xy 385.564888 -249.242326)
		)
		(stroke
			(width 0)
			(type solid)
		)
		(fill yes)
		(layer "In2.Cu")
		(net "M_I_CPU0_SA_CB<7>")
	)
	(gr_poly
		(pts
			(xy 385.664964 -247.926098) (xy 385.564888 -247.826022) (xy 385.464812 -247.926098) (xy 385.464812 -247.970548)
			(xy 385.664964 -247.970548)
		)
		(stroke
			(width 0)
			(type solid)
		)
		(fill yes)
		(layer "In2.Cu")
		(net "M_I_CPU0_SA_CB<4>")
	)
	(gr_poly
		(pts
			(xy 385.664964 -247.522492) (xy 385.664964 -247.47474) (xy 385.464812 -247.47474) (xy 385.464812 -247.522492)
			(xy 385.564888 -247.622314)
		)
		(stroke
			(width 0)
			(type solid)
		)
		(fill yes)
		(layer "In2.Cu")
		(net "M_I_CPU0_SA_DQS_DP<9>")
	)
	(gr_poly
		(pts
			(xy 385.664964 -246.305832) (xy 385.564888 -246.20601) (xy 385.464812 -246.305832) (xy 385.464812 -246.353584)
			(xy 385.664964 -246.353584)
		)
		(stroke
			(width 0)
			(type solid)
		)
		(fill yes)
		(layer "In2.Cu")
		(net "M_I_CPU0_SA_DQS_DP<4>")
	)
	(gr_poly
		(pts
			(xy 385.664964 -245.902226) (xy 385.664964 -245.857776) (xy 385.464812 -245.857776) (xy 385.464812 -245.902226)
			(xy 385.564888 -246.002302)
		)
		(stroke
			(width 0)
			(type solid)
		)
		(fill yes)
		(layer "In2.Cu")
		(net "M_I_CPU0_SA_CB<3>")
	)
	(gr_poly
		(pts
			(xy 385.664964 -244.686074) (xy 385.564888 -244.585998) (xy 385.464812 -244.686074) (xy 385.464812 -244.730524)
			(xy 385.664964 -244.730524)
		)
		(stroke
			(width 0)
			(type solid)
		)
		(fill yes)
		(layer "In2.Cu")
		(net "M_I_CPU0_SA_CB<0>")
	)
	(gr_poly
		(pts
			(xy 385.664964 -244.282214) (xy 385.664964 -244.237764) (xy 385.464812 -244.237764) (xy 385.464812 -244.282214)
			(xy 385.564888 -244.38229)
		)
		(stroke
			(width 0)
			(type solid)
		)
		(fill yes)
		(layer "In2.Cu")
		(net "M_I_CPU0_SA_DQ<31>")
	)
	(gr_poly
		(pts
			(xy 385.664964 -243.066062) (xy 385.564888 -242.965986) (xy 385.464812 -243.066062) (xy 385.464812 -243.110512)
			(xy 385.664964 -243.110512)
		)
		(stroke
			(width 0)
			(type solid)
		)
		(fill yes)
		(layer "In2.Cu")
		(net "M_I_CPU0_SA_DQ<28>")
	)
	(gr_poly
		(pts
			(xy 385.664964 -242.662456) (xy 385.664964 -242.614704) (xy 385.464812 -242.614704) (xy 385.464812 -242.662456)
			(xy 385.564888 -242.762278)
		)
		(stroke
			(width 0)
			(type solid)
		)
		(fill yes)
		(layer "In2.Cu")
		(net "M_I_CPU0_SA_DQS_DP<8>")
	)
	(gr_poly
		(pts
			(xy 385.664964 -241.445796) (xy 385.564888 -241.345974) (xy 385.464812 -241.445796) (xy 385.464812 -241.493548)
			(xy 385.664964 -241.493548)
		)
		(stroke
			(width 0)
			(type solid)
		)
		(fill yes)
		(layer "In2.Cu")
		(net "M_I_CPU0_SA_DQS_DP<3>")
	)
	(gr_poly
		(pts
			(xy 385.664964 -241.04219) (xy 385.664964 -240.99774) (xy 385.464812 -240.99774) (xy 385.464812 -241.04219)
			(xy 385.564888 -241.142266)
		)
		(stroke
			(width 0)
			(type solid)
		)
		(fill yes)
		(layer "In2.Cu")
		(net "M_I_CPU0_SA_DQ<27>")
	)
	(gr_poly
		(pts
			(xy 385.664964 -239.826038) (xy 385.564888 -239.725962) (xy 385.464812 -239.826038) (xy 385.464812 -239.870488)
			(xy 385.664964 -239.870488)
		)
		(stroke
			(width 0)
			(type solid)
		)
		(fill yes)
		(layer "In2.Cu")
		(net "M_I_CPU0_SA_DQ<24>")
	)
	(gr_poly
		(pts
			(xy 385.664964 -239.422178) (xy 385.664964 -239.377728) (xy 385.464812 -239.377728) (xy 385.464812 -239.422178)
			(xy 385.564888 -239.522254)
		)
		(stroke
			(width 0)
			(type solid)
		)
		(fill yes)
		(layer "In2.Cu")
		(net "M_I_CPU0_SA_DQ<23>")
	)
	(gr_poly
		(pts
			(xy 385.664964 -238.206026) (xy 385.564888 -238.10595) (xy 385.464812 -238.206026) (xy 385.464812 -238.250476)
			(xy 385.664964 -238.250476)
		)
		(stroke
			(width 0)
			(type solid)
		)
		(fill yes)
		(layer "In2.Cu")
		(net "M_I_CPU0_SA_DQ<20>")
	)
	(gr_poly
		(pts
			(xy 385.664964 -237.80242) (xy 385.664964 -237.754668) (xy 385.464812 -237.754668) (xy 385.464812 -237.80242)
			(xy 385.564888 -237.902242)
		)
		(stroke
			(width 0)
			(type solid)
		)
		(fill yes)
		(layer "In2.Cu")
		(net "M_I_CPU0_SA_DQS_DP<7>")
	)
	(gr_poly
		(pts
			(xy 385.664964 -236.58576) (xy 385.564888 -236.485938) (xy 385.464812 -236.58576) (xy 385.464812 -236.633512)
			(xy 385.664964 -236.633512)
		)
		(stroke
			(width 0)
			(type solid)
		)
		(fill yes)
		(layer "In2.Cu")
		(net "M_I_CPU0_SA_DQS_DP<2>")
	)
	(gr_poly
		(pts
			(xy 385.664964 -236.182154) (xy 385.664964 -236.137704) (xy 385.464812 -236.137704) (xy 385.464812 -236.182154)
			(xy 385.564888 -236.28223)
		)
		(stroke
			(width 0)
			(type solid)
		)
		(fill yes)
		(layer "In2.Cu")
		(net "M_I_CPU0_SA_DQ<19>")
	)
	(gr_poly
		(pts
			(xy 385.664964 -234.966002) (xy 385.564888 -234.865926) (xy 385.464812 -234.966002) (xy 385.464812 -235.010452)
			(xy 385.664964 -235.010452)
		)
		(stroke
			(width 0)
			(type solid)
		)
		(fill yes)
		(layer "In2.Cu")
		(net "M_I_CPU0_SA_DQ<16>")
	)
	(gr_poly
		(pts
			(xy 385.664964 -234.562142) (xy 385.664964 -234.517692) (xy 385.464812 -234.517692) (xy 385.464812 -234.562142)
			(xy 385.564888 -234.662218)
		)
		(stroke
			(width 0)
			(type solid)
		)
		(fill yes)
		(layer "In2.Cu")
		(net "M_I_CPU0_SA_DQ<15>")
	)
	(gr_poly
		(pts
			(xy 385.664964 -233.34599) (xy 385.564888 -233.245914) (xy 385.464812 -233.34599) (xy 385.464812 -233.39044)
			(xy 385.664964 -233.39044)
		)
		(stroke
			(width 0)
			(type solid)
		)
		(fill yes)
		(layer "In2.Cu")
		(net "M_I_CPU0_SA_DQ<12>")
	)
	(gr_poly
		(pts
			(xy 385.664964 -232.942384) (xy 385.664964 -232.894632) (xy 385.464812 -232.894632) (xy 385.464812 -232.942384)
			(xy 385.564888 -233.042206)
		)
		(stroke
			(width 0)
			(type solid)
		)
		(fill yes)
		(layer "In2.Cu")
		(net "M_I_CPU0_SA_DQS_DP<6>")
	)
	(gr_poly
		(pts
			(xy 385.664964 -231.725724) (xy 385.564888 -231.625902) (xy 385.464812 -231.725724) (xy 385.464812 -231.773476)
			(xy 385.664964 -231.773476)
		)
		(stroke
			(width 0)
			(type solid)
		)
		(fill yes)
		(layer "In2.Cu")
		(net "M_I_CPU0_SA_DQS_DP<1>")
	)
	(gr_poly
		(pts
			(xy 385.664964 -231.322372) (xy 385.664964 -231.277922) (xy 385.464812 -231.277922) (xy 385.464812 -231.322372)
			(xy 385.564888 -231.422448)
		)
		(stroke
			(width 0)
			(type solid)
		)
		(fill yes)
		(layer "In2.Cu")
		(net "M_I_CPU0_SA_DQ<11>")
	)
	(gr_poly
		(pts
			(xy 385.664964 -230.105966) (xy 385.564888 -230.006144) (xy 385.464812 -230.105966) (xy 385.464812 -230.150416)
			(xy 385.664964 -230.150416)
		)
		(stroke
			(width 0)
			(type solid)
		)
		(fill yes)
		(layer "In2.Cu")
		(net "M_I_CPU0_SA_DQ<8>")
	)
	(gr_poly
		(pts
			(xy 385.664964 -229.70236) (xy 385.664964 -229.65791) (xy 385.464812 -229.65791) (xy 385.464812 -229.70236)
			(xy 385.564888 -229.802436)
		)
		(stroke
			(width 0)
			(type solid)
		)
		(fill yes)
		(layer "In2.Cu")
		(net "M_I_CPU0_SA_DQ<7>")
	)
	(gr_poly
		(pts
			(xy 385.664964 -228.486208) (xy 385.564888 -228.386132) (xy 385.464812 -228.486208) (xy 385.464812 -228.530658)
			(xy 385.664964 -228.530658)
		)
		(stroke
			(width 0)
			(type solid)
		)
		(fill yes)
		(layer "In2.Cu")
		(net "M_I_CPU0_SA_DQ<4>")
	)
	(gr_poly
		(pts
			(xy 385.664964 -228.082602) (xy 385.664964 -228.03485) (xy 385.464812 -228.03485) (xy 385.464812 -228.082602)
			(xy 385.564888 -228.182424)
		)
		(stroke
			(width 0)
			(type solid)
		)
		(fill yes)
		(layer "In2.Cu")
		(net "M_I_CPU0_SA_DQS_DP<5>")
	)
	(gr_poly
		(pts
			(xy 385.664964 -226.865942) (xy 385.564888 -226.76612) (xy 385.464812 -226.865942) (xy 385.464812 -226.913694)
			(xy 385.664964 -226.913694)
		)
		(stroke
			(width 0)
			(type solid)
		)
		(fill yes)
		(layer "In2.Cu")
		(net "M_I_CPU0_SA_DQS_DP<0>")
	)
	(gr_poly
		(pts
			(xy 385.664964 -226.462336) (xy 385.664964 -226.417886) (xy 385.464812 -226.417886) (xy 385.464812 -226.462336)
			(xy 385.564888 -226.562412)
		)
		(stroke
			(width 0)
			(type solid)
		)
		(fill yes)
		(layer "In2.Cu")
		(net "M_I_CPU0_SA_DQ<3>")
	)
	(gr_poly
		(pts
			(xy 385.664964 -225.246184) (xy 385.564888 -225.146108) (xy 385.464812 -225.246184) (xy 385.464812 -225.290634)
			(xy 385.664964 -225.290634)
		)
		(stroke
			(width 0)
			(type solid)
		)
		(fill yes)
		(layer "In2.Cu")
		(net "M_I_CPU0_SA_DQ<0>")
	)
	(gr_poly
		(pts
			(xy 385.964938 -292.91788) (xy 385.864862 -292.817804) (xy 385.764786 -292.91788) (xy 385.764786 -292.96233)
			(xy 385.964938 -292.96233)
		)
		(stroke
			(width 0)
			(type solid)
		)
		(fill yes)
		(layer "In2.Cu")
		(net "M_I_CPU0_SB_DQ<29>")
	)
	(gr_poly
		(pts
			(xy 385.964938 -292.51402) (xy 385.964938 -292.46957) (xy 385.764786 -292.46957) (xy 385.764786 -292.51402)
			(xy 385.864862 -292.614096)
		)
		(stroke
			(width 0)
			(type solid)
		)
		(fill yes)
		(layer "In2.Cu")
		(net "M_I_CPU0_SB_DQ<30>")
	)
	(gr_poly
		(pts
			(xy 385.964938 -291.297614) (xy 385.864862 -291.197792) (xy 385.764786 -291.297614) (xy 385.764786 -291.345366)
			(xy 385.964938 -291.345366)
		)
		(stroke
			(width 0)
			(type solid)
		)
		(fill yes)
		(layer "In2.Cu")
		(net "M_I_CPU0_SB_DQS_DN<8>")
	)
	(gr_poly
		(pts
			(xy 385.964938 -290.894262) (xy 385.964938 -290.84651) (xy 385.764786 -290.84651) (xy 385.764786 -290.894262)
			(xy 385.864862 -290.994084)
		)
		(stroke
			(width 0)
			(type solid)
		)
		(fill yes)
		(layer "In2.Cu")
		(net "M_I_CPU0_SB_DQS_DN<3>")
	)
	(gr_poly
		(pts
			(xy 385.964938 -289.677856) (xy 385.864862 -289.57778) (xy 385.764786 -289.677856) (xy 385.764786 -289.722306)
			(xy 385.964938 -289.722306)
		)
		(stroke
			(width 0)
			(type solid)
		)
		(fill yes)
		(layer "In2.Cu")
		(net "M_I_CPU0_SB_DQ<25>")
	)
	(gr_poly
		(pts
			(xy 385.964938 -289.273996) (xy 385.964938 -289.229546) (xy 385.764786 -289.229546) (xy 385.764786 -289.273996)
			(xy 385.864862 -289.374072)
		)
		(stroke
			(width 0)
			(type solid)
		)
		(fill yes)
		(layer "In2.Cu")
		(net "M_I_CPU0_SB_DQ<26>")
	)
	(gr_poly
		(pts
			(xy 385.964938 -288.057844) (xy 385.864862 -287.957768) (xy 385.764786 -288.057844) (xy 385.764786 -288.102294)
			(xy 385.964938 -288.102294)
		)
		(stroke
			(width 0)
			(type solid)
		)
		(fill yes)
		(layer "In2.Cu")
		(net "M_I_CPU0_SB_DQ<21>")
	)
	(gr_poly
		(pts
			(xy 385.964938 -287.654238) (xy 385.964938 -287.609788) (xy 385.764786 -287.609788) (xy 385.764786 -287.654238)
			(xy 385.864862 -287.75406)
		)
		(stroke
			(width 0)
			(type solid)
		)
		(fill yes)
		(layer "In2.Cu")
		(net "M_I_CPU0_SB_DQ<22>")
	)
	(gr_poly
		(pts
			(xy 385.964938 -286.437832) (xy 385.864862 -286.337756) (xy 385.764786 -286.437832) (xy 385.764786 -286.485584)
			(xy 385.964938 -286.485584)
		)
		(stroke
			(width 0)
			(type solid)
		)
		(fill yes)
		(layer "In2.Cu")
		(net "M_I_CPU0_SB_DQS_DN<7>")
	)
	(gr_poly
		(pts
			(xy 385.964938 -286.03448) (xy 385.964938 -285.986728) (xy 385.764786 -285.986728) (xy 385.764786 -286.03448)
			(xy 385.864862 -286.134302)
		)
		(stroke
			(width 0)
			(type solid)
		)
		(fill yes)
		(layer "In2.Cu")
		(net "M_I_CPU0_SB_DQS_DN<2>")
	)
	(gr_poly
		(pts
			(xy 385.964938 -284.818074) (xy 385.864862 -284.717998) (xy 385.764786 -284.818074) (xy 385.764786 -284.862524)
			(xy 385.964938 -284.862524)
		)
		(stroke
			(width 0)
			(type solid)
		)
		(fill yes)
		(layer "In2.Cu")
		(net "M_I_CPU0_SB_DQ<17>")
	)
	(gr_poly
		(pts
			(xy 385.964938 -284.414214) (xy 385.964938 -284.369764) (xy 385.764786 -284.369764) (xy 385.764786 -284.414214)
			(xy 385.864862 -284.51429)
		)
		(stroke
			(width 0)
			(type solid)
		)
		(fill yes)
		(layer "In2.Cu")
		(net "M_I_CPU0_SB_DQ<18>")
	)
	(gr_poly
		(pts
			(xy 385.964938 -283.198062) (xy 385.864862 -283.097986) (xy 385.764786 -283.198062) (xy 385.764786 -283.242512)
			(xy 385.964938 -283.242512)
		)
		(stroke
			(width 0)
			(type solid)
		)
		(fill yes)
		(layer "In2.Cu")
		(net "M_I_CPU0_SB_DQ<13>")
	)
	(gr_poly
		(pts
			(xy 385.964938 -282.794202) (xy 385.964938 -282.749752) (xy 385.764786 -282.749752) (xy 385.764786 -282.794202)
			(xy 385.864862 -282.894278)
		)
		(stroke
			(width 0)
			(type solid)
		)
		(fill yes)
		(layer "In2.Cu")
		(net "M_I_CPU0_SB_DQ<14>")
	)
	(gr_poly
		(pts
			(xy 385.964938 -281.577796) (xy 385.864862 -281.477974) (xy 385.764786 -281.577796) (xy 385.764786 -281.625548)
			(xy 385.964938 -281.625548)
		)
		(stroke
			(width 0)
			(type solid)
		)
		(fill yes)
		(layer "In2.Cu")
		(net "M_I_CPU0_SB_DQS_DN<6>")
	)
	(gr_poly
		(pts
			(xy 385.964938 -281.174444) (xy 385.964938 -281.126692) (xy 385.764786 -281.126692) (xy 385.764786 -281.174444)
			(xy 385.864862 -281.274266)
		)
		(stroke
			(width 0)
			(type solid)
		)
		(fill yes)
		(layer "In2.Cu")
		(net "M_I_CPU0_SB_DQS_DN<1>")
	)
	(gr_poly
		(pts
			(xy 385.964938 -279.958038) (xy 385.864862 -279.857962) (xy 385.764786 -279.958038) (xy 385.764786 -280.002488)
			(xy 385.964938 -280.002488)
		)
		(stroke
			(width 0)
			(type solid)
		)
		(fill yes)
		(layer "In2.Cu")
		(net "M_I_CPU0_SB_DQ<9>")
	)
	(gr_poly
		(pts
			(xy 385.964938 -279.554178) (xy 385.964938 -279.509728) (xy 385.764786 -279.509728) (xy 385.764786 -279.554178)
			(xy 385.864862 -279.654254)
		)
		(stroke
			(width 0)
			(type solid)
		)
		(fill yes)
		(layer "In2.Cu")
		(net "M_I_CPU0_SB_DQ<10>")
	)
	(gr_poly
		(pts
			(xy 385.964938 -278.338026) (xy 385.864862 -278.23795) (xy 385.764786 -278.338026) (xy 385.764786 -278.382476)
			(xy 385.964938 -278.382476)
		)
		(stroke
			(width 0)
			(type solid)
		)
		(fill yes)
		(layer "In2.Cu")
		(net "M_I_CPU0_SB_DQ<5>")
	)
	(gr_poly
		(pts
			(xy 385.964938 -277.934166) (xy 385.964938 -277.889716) (xy 385.764786 -277.889716) (xy 385.764786 -277.934166)
			(xy 385.864862 -278.034242)
		)
		(stroke
			(width 0)
			(type solid)
		)
		(fill yes)
		(layer "In2.Cu")
		(net "M_I_CPU0_SB_DQ<6>")
	)
	(gr_poly
		(pts
			(xy 385.964938 -276.71776) (xy 385.864862 -276.617938) (xy 385.764786 -276.71776) (xy 385.764786 -276.765512)
			(xy 385.964938 -276.765512)
		)
		(stroke
			(width 0)
			(type solid)
		)
		(fill yes)
		(layer "In2.Cu")
		(net "M_I_CPU0_SB_DQS_DN<5>")
	)
	(gr_poly
		(pts
			(xy 385.964938 -276.314408) (xy 385.964938 -276.266656) (xy 385.764786 -276.266656) (xy 385.764786 -276.314408)
			(xy 385.864862 -276.41423)
		)
		(stroke
			(width 0)
			(type solid)
		)
		(fill yes)
		(layer "In2.Cu")
		(net "M_I_CPU0_SB_DQS_DN<0>")
	)
	(gr_poly
		(pts
			(xy 385.964938 -275.098002) (xy 385.864862 -274.997926) (xy 385.764786 -275.098002) (xy 385.764786 -275.142452)
			(xy 385.964938 -275.142452)
		)
		(stroke
			(width 0)
			(type solid)
		)
		(fill yes)
		(layer "In2.Cu")
		(net "M_I_CPU0_SB_DQ<1>")
	)
	(gr_poly
		(pts
			(xy 385.964938 -274.694142) (xy 385.964938 -274.649692) (xy 385.764786 -274.649692) (xy 385.764786 -274.694142)
			(xy 385.864862 -274.794218)
		)
		(stroke
			(width 0)
			(type solid)
		)
		(fill yes)
		(layer "In2.Cu")
		(net "M_I_CPU0_SB_DQ<2>")
	)
	(gr_poly
		(pts
			(xy 385.964938 -273.47799) (xy 385.864862 -273.377914) (xy 385.764786 -273.47799) (xy 385.764786 -273.52244)
			(xy 385.964938 -273.52244)
		)
		(stroke
			(width 0)
			(type solid)
		)
		(fill yes)
		(layer "In2.Cu")
		(net "M_I_CPU0_SB_CB<1>")
	)
	(gr_poly
		(pts
			(xy 385.964938 -273.07413) (xy 385.964938 -273.02968) (xy 385.764786 -273.02968) (xy 385.764786 -273.07413)
			(xy 385.864862 -273.174206)
		)
		(stroke
			(width 0)
			(type solid)
		)
		(fill yes)
		(layer "In2.Cu")
		(net "M_I_CPU0_SB_CB<2>")
	)
	(gr_poly
		(pts
			(xy 385.964938 -271.857724) (xy 385.864862 -271.757902) (xy 385.764786 -271.857724) (xy 385.764786 -271.905476)
			(xy 385.964938 -271.905476)
		)
		(stroke
			(width 0)
			(type solid)
		)
		(fill yes)
		(layer "In2.Cu")
		(net "M_I_CPU0_SB_DQS_DN<4>")
	)
	(gr_poly
		(pts
			(xy 385.964938 -271.454372) (xy 385.964938 -271.40662) (xy 385.764786 -271.40662) (xy 385.764786 -271.454372)
			(xy 385.864862 -271.554194)
		)
		(stroke
			(width 0)
			(type solid)
		)
		(fill yes)
		(layer "In2.Cu")
		(net "M_I_CPU0_SB_DQS_DN<9>")
	)
	(gr_poly
		(pts
			(xy 385.964938 -270.237966) (xy 385.864862 -270.13789) (xy 385.764786 -270.237966) (xy 385.764786 -270.282416)
			(xy 385.964938 -270.282416)
		)
		(stroke
			(width 0)
			(type solid)
		)
		(fill yes)
		(layer "In2.Cu")
		(net "M_I_CPU0_SB_CB<5>")
	)
	(gr_poly
		(pts
			(xy 385.964938 -269.834106) (xy 385.964938 -269.789656) (xy 385.764786 -269.789656) (xy 385.764786 -269.834106)
			(xy 385.864862 -269.934182)
		)
		(stroke
			(width 0)
			(type solid)
		)
		(fill yes)
		(layer "In2.Cu")
		(net "M_I_CPU0_SB_CB<6>")
	)
	(gr_poly
		(pts
			(xy 385.964938 -266.997942) (xy 385.864862 -266.897866) (xy 385.764786 -266.997942) (xy 385.764786 -267.042392)
			(xy 385.964938 -267.042392)
		)
		(stroke
			(width 0)
			(type solid)
		)
		(fill yes)
		(layer "In2.Cu")
		(net "M_I_CPU0_SA_RSP<0>")
	)
	(gr_poly
		(pts
			(xy 385.964938 -266.594082) (xy 385.964938 -266.549632) (xy 385.764786 -266.549632) (xy 385.764786 -266.594082)
			(xy 385.864862 -266.694158)
		)
		(stroke
			(width 0)
			(type solid)
		)
		(fill yes)
		(layer "In2.Cu")
		(net "M_I_CPU0_SB_CS_N<1>")
	)
	(gr_poly
		(pts
			(xy 385.964938 -265.37793) (xy 385.864862 -265.277854) (xy 385.764786 -265.37793) (xy 385.764786 -265.42238)
			(xy 385.964938 -265.42238)
		)
		(stroke
			(width 0)
			(type solid)
		)
		(fill yes)
		(layer "In2.Cu")
		(net "M_I_CPU0_SB_PAR")
	)
	(gr_poly
		(pts
			(xy 385.964938 -263.757918) (xy 385.864862 -263.657842) (xy 385.764786 -263.757918) (xy 385.764786 -263.802368)
			(xy 385.964938 -263.802368)
		)
		(stroke
			(width 0)
			(type solid)
		)
		(fill yes)
		(layer "In2.Cu")
		(net "M_I_CPU0_SB_CA<4>")
	)
	(gr_poly
		(pts
			(xy 385.964938 -263.354058) (xy 385.964938 -263.309608) (xy 385.764786 -263.309608) (xy 385.764786 -263.354058)
			(xy 385.864862 -263.454134)
		)
		(stroke
			(width 0)
			(type solid)
		)
		(fill yes)
		(layer "In2.Cu")
		(net "M_I_CPU0_SB_CA<3>")
	)
	(gr_poly
		(pts
			(xy 385.964938 -262.137906) (xy 385.864862 -262.03783) (xy 385.764786 -262.137906) (xy 385.764786 -262.182356)
			(xy 385.964938 -262.182356)
		)
		(stroke
			(width 0)
			(type solid)
		)
		(fill yes)
		(layer "In2.Cu")
		(net "M_I_CPU0_SB_CA<0>")
	)
	(gr_poly
		(pts
			(xy 386.134864 -256.432558) (xy 386.134864 -256.384806) (xy 385.934712 -256.384806) (xy 385.934712 -256.432558)
			(xy 386.034788 -256.53238)
		)
		(stroke
			(width 0)
			(type solid)
		)
		(fill yes)
		(layer "In2.Cu")
		(net "M_I_CPU0_CLK_DN<0>")
	)
	(gr_poly
		(pts
			(xy 386.134864 -255.216152) (xy 386.034788 -255.116076) (xy 385.934712 -255.216152) (xy 385.934712 -255.260602)
			(xy 386.134864 -255.260602)
		)
		(stroke
			(width 0)
			(type solid)
		)
		(fill yes)
		(layer "In2.Cu")
		(net "M_I_CPU0_SA_CA<6>")
	)
	(gr_poly
		(pts
			(xy 386.134864 -254.812292) (xy 386.134864 -254.767842) (xy 385.934712 -254.767842) (xy 385.934712 -254.812292)
			(xy 386.034788 -254.912368)
		)
		(stroke
			(width 0)
			(type solid)
		)
		(fill yes)
		(layer "In2.Cu")
		(net "M_I_CPU0_SA_CA<5>")
	)
	(gr_poly
		(pts
			(xy 386.134864 -253.59614) (xy 386.034788 -253.496064) (xy 385.934712 -253.59614) (xy 385.934712 -253.64059)
			(xy 386.134864 -253.64059)
		)
		(stroke
			(width 0)
			(type solid)
		)
		(fill yes)
		(layer "In2.Cu")
		(net "M_I_CPU0_SA_CA<2>")
	)
	(gr_poly
		(pts
			(xy 386.134864 -253.19228) (xy 386.134864 -253.14783) (xy 385.934712 -253.14783) (xy 385.934712 -253.19228)
			(xy 386.034788 -253.292356)
		)
		(stroke
			(width 0)
			(type solid)
		)
		(fill yes)
		(layer "In2.Cu")
		(net "M_I_CPU0_SA_CA<1>")
	)
	(gr_poly
		(pts
			(xy 386.134864 -251.976128) (xy 386.034788 -251.876052) (xy 385.934712 -251.976128) (xy 385.934712 -252.020578)
			(xy 386.134864 -252.020578)
		)
		(stroke
			(width 0)
			(type solid)
		)
		(fill yes)
		(layer "In2.Cu")
		(net "M_I_CPU0_SA_CS_N<1>")
	)
	(gr_poly
		(pts
			(xy 386.134864 -250.356116) (xy 386.034788 -250.25604) (xy 385.934712 -250.356116) (xy 385.934712 -250.400566)
			(xy 386.134864 -250.400566)
		)
		(stroke
			(width 0)
			(type solid)
		)
		(fill yes)
		(layer "In2.Cu")
		(net "M_I_CPU0_ALERT_R_N")
	)
	(gr_poly
		(pts
			(xy 386.134864 -248.736104) (xy 386.034788 -248.636028) (xy 385.934712 -248.736104) (xy 385.934712 -248.780554)
			(xy 386.134864 -248.780554)
		)
		(stroke
			(width 0)
			(type solid)
		)
		(fill yes)
		(layer "In2.Cu")
		(net "M_I_CPU0_SA_CB<5>")
	)
	(gr_poly
		(pts
			(xy 386.134864 -248.332244) (xy 386.134864 -248.287794) (xy 385.934712 -248.287794) (xy 385.934712 -248.332244)
			(xy 386.034788 -248.43232)
		)
		(stroke
			(width 0)
			(type solid)
		)
		(fill yes)
		(layer "In2.Cu")
		(net "M_I_CPU0_SA_CB<6>")
	)
	(gr_poly
		(pts
			(xy 386.134864 -247.115838) (xy 386.034788 -247.016016) (xy 385.934712 -247.115838) (xy 385.934712 -247.16359)
			(xy 386.134864 -247.16359)
		)
		(stroke
			(width 0)
			(type solid)
		)
		(fill yes)
		(layer "In2.Cu")
		(net "M_I_CPU0_SA_DQS_DN<9>")
	)
	(gr_poly
		(pts
			(xy 386.134864 -246.712486) (xy 386.134864 -246.664734) (xy 385.934712 -246.664734) (xy 385.934712 -246.712486)
			(xy 386.034788 -246.812308)
		)
		(stroke
			(width 0)
			(type solid)
		)
		(fill yes)
		(layer "In2.Cu")
		(net "M_I_CPU0_SA_DQS_DN<4>")
	)
	(gr_poly
		(pts
			(xy 386.134864 -245.49608) (xy 386.034788 -245.396004) (xy 385.934712 -245.49608) (xy 385.934712 -245.54053)
			(xy 386.134864 -245.54053)
		)
		(stroke
			(width 0)
			(type solid)
		)
		(fill yes)
		(layer "In2.Cu")
		(net "M_I_CPU0_SA_CB<1>")
	)
	(gr_poly
		(pts
			(xy 386.134864 -245.09222) (xy 386.134864 -245.04777) (xy 385.934712 -245.04777) (xy 385.934712 -245.09222)
			(xy 386.034788 -245.192296)
		)
		(stroke
			(width 0)
			(type solid)
		)
		(fill yes)
		(layer "In2.Cu")
		(net "M_I_CPU0_SA_CB<2>")
	)
	(gr_poly
		(pts
			(xy 386.134864 -243.876068) (xy 386.034788 -243.775992) (xy 385.934712 -243.876068) (xy 385.934712 -243.920518)
			(xy 386.134864 -243.920518)
		)
		(stroke
			(width 0)
			(type solid)
		)
		(fill yes)
		(layer "In2.Cu")
		(net "M_I_CPU0_SA_DQ<29>")
	)
	(gr_poly
		(pts
			(xy 386.134864 -243.472208) (xy 386.134864 -243.427758) (xy 385.934712 -243.427758) (xy 385.934712 -243.472208)
			(xy 386.034788 -243.572284)
		)
		(stroke
			(width 0)
			(type solid)
		)
		(fill yes)
		(layer "In2.Cu")
		(net "M_I_CPU0_SA_DQ<30>")
	)
	(gr_poly
		(pts
			(xy 386.134864 -242.255802) (xy 386.034788 -242.15598) (xy 385.934712 -242.255802) (xy 385.934712 -242.303554)
			(xy 386.134864 -242.303554)
		)
		(stroke
			(width 0)
			(type solid)
		)
		(fill yes)
		(layer "In2.Cu")
		(net "M_I_CPU0_SA_DQS_DN<8>")
	)
	(gr_poly
		(pts
			(xy 386.134864 -241.85245) (xy 386.134864 -241.804698) (xy 385.934712 -241.804698) (xy 385.934712 -241.85245)
			(xy 386.034788 -241.952272)
		)
		(stroke
			(width 0)
			(type solid)
		)
		(fill yes)
		(layer "In2.Cu")
		(net "M_I_CPU0_SA_DQS_DN<3>")
	)
	(gr_poly
		(pts
			(xy 386.134864 -240.636044) (xy 386.034788 -240.535968) (xy 385.934712 -240.636044) (xy 385.934712 -240.680494)
			(xy 386.134864 -240.680494)
		)
		(stroke
			(width 0)
			(type solid)
		)
		(fill yes)
		(layer "In2.Cu")
		(net "M_I_CPU0_SA_DQ<25>")
	)
	(gr_poly
		(pts
			(xy 386.134864 -240.232184) (xy 386.134864 -240.187734) (xy 385.934712 -240.187734) (xy 385.934712 -240.232184)
			(xy 386.034788 -240.33226)
		)
		(stroke
			(width 0)
			(type solid)
		)
		(fill yes)
		(layer "In2.Cu")
		(net "M_I_CPU0_SA_DQ<26>")
	)
	(gr_poly
		(pts
			(xy 386.134864 -239.016032) (xy 386.034788 -238.915956) (xy 385.934712 -239.016032) (xy 385.934712 -239.060482)
			(xy 386.134864 -239.060482)
		)
		(stroke
			(width 0)
			(type solid)
		)
		(fill yes)
		(layer "In2.Cu")
		(net "M_I_CPU0_SA_DQ<21>")
	)
	(gr_poly
		(pts
			(xy 386.134864 -238.612172) (xy 386.134864 -238.567722) (xy 385.934712 -238.567722) (xy 385.934712 -238.612172)
			(xy 386.034788 -238.712248)
		)
		(stroke
			(width 0)
			(type solid)
		)
		(fill yes)
		(layer "In2.Cu")
		(net "M_I_CPU0_SA_DQ<22>")
	)
	(gr_poly
		(pts
			(xy 386.134864 -237.395766) (xy 386.034788 -237.295944) (xy 385.934712 -237.395766) (xy 385.934712 -237.443518)
			(xy 386.134864 -237.443518)
		)
		(stroke
			(width 0)
			(type solid)
		)
		(fill yes)
		(layer "In2.Cu")
		(net "M_I_CPU0_SA_DQS_DN<7>")
	)
	(gr_poly
		(pts
			(xy 386.134864 -236.992414) (xy 386.134864 -236.944662) (xy 385.934712 -236.944662) (xy 385.934712 -236.992414)
			(xy 386.034788 -237.092236)
		)
		(stroke
			(width 0)
			(type solid)
		)
		(fill yes)
		(layer "In2.Cu")
		(net "M_I_CPU0_SA_DQS_DN<2>")
	)
	(gr_poly
		(pts
			(xy 386.134864 -235.776008) (xy 386.034788 -235.675932) (xy 385.934712 -235.776008) (xy 385.934712 -235.820458)
			(xy 386.134864 -235.820458)
		)
		(stroke
			(width 0)
			(type solid)
		)
		(fill yes)
		(layer "In2.Cu")
		(net "M_I_CPU0_SA_DQ<17>")
	)
	(gr_poly
		(pts
			(xy 386.134864 -235.372148) (xy 386.134864 -235.327698) (xy 385.934712 -235.327698) (xy 385.934712 -235.372148)
			(xy 386.034788 -235.472224)
		)
		(stroke
			(width 0)
			(type solid)
		)
		(fill yes)
		(layer "In2.Cu")
		(net "M_I_CPU0_SA_DQ<18>")
	)
	(gr_poly
		(pts
			(xy 386.134864 -234.155996) (xy 386.034788 -234.05592) (xy 385.934712 -234.155996) (xy 385.934712 -234.200446)
			(xy 386.134864 -234.200446)
		)
		(stroke
			(width 0)
			(type solid)
		)
		(fill yes)
		(layer "In2.Cu")
		(net "M_I_CPU0_SA_DQ<13>")
	)
	(gr_poly
		(pts
			(xy 386.134864 -233.752136) (xy 386.134864 -233.707686) (xy 385.934712 -233.707686) (xy 385.934712 -233.752136)
			(xy 386.034788 -233.852212)
		)
		(stroke
			(width 0)
			(type solid)
		)
		(fill yes)
		(layer "In2.Cu")
		(net "M_I_CPU0_SA_DQ<14>")
	)
	(gr_poly
		(pts
			(xy 386.134864 -232.53573) (xy 386.034788 -232.435908) (xy 385.934712 -232.53573) (xy 385.934712 -232.583482)
			(xy 386.134864 -232.583482)
		)
		(stroke
			(width 0)
			(type solid)
		)
		(fill yes)
		(layer "In2.Cu")
		(net "M_I_CPU0_SA_DQS_DN<6>")
	)
	(gr_poly
		(pts
			(xy 386.134864 -232.132378) (xy 386.134864 -232.084626) (xy 385.934712 -232.084626) (xy 385.934712 -232.132378)
			(xy 386.034788 -232.2322)
		)
		(stroke
			(width 0)
			(type solid)
		)
		(fill yes)
		(layer "In2.Cu")
		(net "M_I_CPU0_SA_DQS_DN<1>")
	)
	(gr_poly
		(pts
			(xy 386.134864 -230.915972) (xy 386.034788 -230.815896) (xy 385.934712 -230.915972) (xy 385.934712 -230.960422)
			(xy 386.134864 -230.960422)
		)
		(stroke
			(width 0)
			(type solid)
		)
		(fill yes)
		(layer "In2.Cu")
		(net "M_I_CPU0_SA_DQ<9>")
	)
	(gr_poly
		(pts
			(xy 386.134864 -230.512366) (xy 386.134864 -230.467916) (xy 385.934712 -230.467916) (xy 385.934712 -230.512366)
			(xy 386.034788 -230.612188)
		)
		(stroke
			(width 0)
			(type solid)
		)
		(fill yes)
		(layer "In2.Cu")
		(net "M_I_CPU0_SA_DQ<10>")
	)
	(gr_poly
		(pts
			(xy 386.134864 -229.29596) (xy 386.034788 -229.195884) (xy 385.934712 -229.29596) (xy 385.934712 -229.34041)
			(xy 386.134864 -229.34041)
		)
		(stroke
			(width 0)
			(type solid)
		)
		(fill yes)
		(layer "In2.Cu")
		(net "M_I_CPU0_SA_DQ<5>")
	)
	(gr_poly
		(pts
			(xy 386.134864 -228.892354) (xy 386.134864 -228.847904) (xy 385.934712 -228.847904) (xy 385.934712 -228.892354)
			(xy 386.034788 -228.99243)
		)
		(stroke
			(width 0)
			(type solid)
		)
		(fill yes)
		(layer "In2.Cu")
		(net "M_I_CPU0_SA_DQ<6>")
	)
	(gr_poly
		(pts
			(xy 386.134864 -227.675948) (xy 386.034788 -227.576126) (xy 385.934712 -227.675948) (xy 385.934712 -227.7237)
			(xy 386.134864 -227.7237)
		)
		(stroke
			(width 0)
			(type solid)
		)
		(fill yes)
		(layer "In2.Cu")
		(net "M_I_CPU0_SA_DQS_DN<5>")
	)
	(gr_poly
		(pts
			(xy 386.134864 -227.272596) (xy 386.134864 -227.224844) (xy 385.934712 -227.224844) (xy 385.934712 -227.272596)
			(xy 386.034788 -227.372418)
		)
		(stroke
			(width 0)
			(type solid)
		)
		(fill yes)
		(layer "In2.Cu")
		(net "M_I_CPU0_SA_DQS_DN<0>")
	)
	(gr_poly
		(pts
			(xy 386.134864 -226.05619) (xy 386.034788 -225.956114) (xy 385.934712 -226.05619) (xy 385.934712 -226.10064)
			(xy 386.134864 -226.10064)
		)
		(stroke
			(width 0)
			(type solid)
		)
		(fill yes)
		(layer "In2.Cu")
		(net "M_I_CPU0_SA_DQ<1>")
	)
	(gr_poly
		(pts
			(xy 386.134864 -225.65233) (xy 386.134864 -225.60788) (xy 385.934712 -225.60788) (xy 385.934712 -225.65233)
			(xy 386.034788 -225.752406)
		)
		(stroke
			(width 0)
			(type solid)
		)
		(fill yes)
		(layer "In2.Cu")
		(net "M_I_CPU0_SA_DQ<2>")
	)
	(gr_poly
		(pts
			(xy 386.434838 -293.324026) (xy 386.434838 -293.279576) (xy 386.234686 -293.279576) (xy 386.234686 -293.324026)
			(xy 386.334762 -293.424102)
		)
		(stroke
			(width 0)
			(type solid)
		)
		(fill yes)
		(layer "In2.Cu")
		(net "M_I_CPU0_SB_DQ<31>")
	)
	(gr_poly
		(pts
			(xy 386.434838 -292.107874) (xy 386.334762 -292.007798) (xy 386.234686 -292.107874) (xy 386.234686 -292.152324)
			(xy 386.434838 -292.152324)
		)
		(stroke
			(width 0)
			(type solid)
		)
		(fill yes)
		(layer "In2.Cu")
		(net "M_I_CPU0_SB_DQ<28>")
	)
	(gr_poly
		(pts
			(xy 386.434838 -291.704268) (xy 386.434838 -291.656516) (xy 386.234686 -291.656516) (xy 386.234686 -291.704268)
			(xy 386.334762 -291.80409)
		)
		(stroke
			(width 0)
			(type solid)
		)
		(fill yes)
		(layer "In2.Cu")
		(net "M_I_CPU0_SB_DQS_DP<8>")
	)
	(gr_poly
		(pts
			(xy 386.434838 -290.487608) (xy 386.334762 -290.387786) (xy 386.234686 -290.487608) (xy 386.234686 -290.53536)
			(xy 386.434838 -290.53536)
		)
		(stroke
			(width 0)
			(type solid)
		)
		(fill yes)
		(layer "In2.Cu")
		(net "M_I_CPU0_SB_DQS_DP<3>")
	)
	(gr_poly
		(pts
			(xy 386.434838 -290.084002) (xy 386.434838 -290.039552) (xy 386.234686 -290.039552) (xy 386.234686 -290.084002)
			(xy 386.334762 -290.184078)
		)
		(stroke
			(width 0)
			(type solid)
		)
		(fill yes)
		(layer "In2.Cu")
		(net "M_I_CPU0_SB_DQ<27>")
	)
	(gr_poly
		(pts
			(xy 386.434838 -288.86785) (xy 386.334762 -288.767774) (xy 386.234686 -288.86785) (xy 386.234686 -288.9123)
			(xy 386.434838 -288.9123)
		)
		(stroke
			(width 0)
			(type solid)
		)
		(fill yes)
		(layer "In2.Cu")
		(net "M_I_CPU0_SB_DQ<24>")
	)
	(gr_poly
		(pts
			(xy 386.434838 -288.464244) (xy 386.434838 -288.419794) (xy 386.234686 -288.419794) (xy 386.234686 -288.464244)
			(xy 386.334762 -288.56432)
		)
		(stroke
			(width 0)
			(type solid)
		)
		(fill yes)
		(layer "In2.Cu")
		(net "M_I_CPU0_SB_DQ<23>")
	)
	(gr_poly
		(pts
			(xy 386.434838 -287.247838) (xy 386.334762 -287.148016) (xy 386.234686 -287.247838) (xy 386.234686 -287.292288)
			(xy 386.434838 -287.292288)
		)
		(stroke
			(width 0)
			(type solid)
		)
		(fill yes)
		(layer "In2.Cu")
		(net "M_I_CPU0_SB_DQ<20>")
	)
	(gr_poly
		(pts
			(xy 386.434838 -286.844232) (xy 386.434838 -286.79648) (xy 386.234686 -286.79648) (xy 386.234686 -286.844232)
			(xy 386.334762 -286.944308)
		)
		(stroke
			(width 0)
			(type solid)
		)
		(fill yes)
		(layer "In2.Cu")
		(net "M_I_CPU0_SB_DQS_DP<7>")
	)
	(gr_poly
		(pts
			(xy 386.434838 -285.627826) (xy 386.334762 -285.528004) (xy 386.234686 -285.627826) (xy 386.234686 -285.675578)
			(xy 386.434838 -285.675578)
		)
		(stroke
			(width 0)
			(type solid)
		)
		(fill yes)
		(layer "In2.Cu")
		(net "M_I_CPU0_SB_DQS_DP<2>")
	)
	(gr_poly
		(pts
			(xy 386.434838 -285.22422) (xy 386.434838 -285.17977) (xy 386.234686 -285.17977) (xy 386.234686 -285.22422)
			(xy 386.334762 -285.324296)
		)
		(stroke
			(width 0)
			(type solid)
		)
		(fill yes)
		(layer "In2.Cu")
		(net "M_I_CPU0_SB_DQ<19>")
	)
	(gr_poly
		(pts
			(xy 386.434838 -284.008068) (xy 386.334762 -283.907992) (xy 386.234686 -284.008068) (xy 386.234686 -284.052518)
			(xy 386.434838 -284.052518)
		)
		(stroke
			(width 0)
			(type solid)
		)
		(fill yes)
		(layer "In2.Cu")
		(net "M_I_CPU0_SB_DQ<16>")
	)
	(gr_poly
		(pts
			(xy 386.434838 -283.604208) (xy 386.434838 -283.559758) (xy 386.234686 -283.559758) (xy 386.234686 -283.604208)
			(xy 386.334762 -283.704284)
		)
		(stroke
			(width 0)
			(type solid)
		)
		(fill yes)
		(layer "In2.Cu")
		(net "M_I_CPU0_SB_DQ<15>")
	)
	(gr_poly
		(pts
			(xy 386.434838 -282.388056) (xy 386.334762 -282.28798) (xy 386.234686 -282.388056) (xy 386.234686 -282.432506)
			(xy 386.434838 -282.432506)
		)
		(stroke
			(width 0)
			(type solid)
		)
		(fill yes)
		(layer "In2.Cu")
		(net "M_I_CPU0_SB_DQ<12>")
	)
	(gr_poly
		(pts
			(xy 386.434838 -281.98445) (xy 386.434838 -281.936698) (xy 386.234686 -281.936698) (xy 386.234686 -281.98445)
			(xy 386.334762 -282.084272)
		)
		(stroke
			(width 0)
			(type solid)
		)
		(fill yes)
		(layer "In2.Cu")
		(net "M_I_CPU0_SB_DQS_DP<6>")
	)
	(gr_poly
		(pts
			(xy 386.434838 -280.76779) (xy 386.334762 -280.667968) (xy 386.234686 -280.76779) (xy 386.234686 -280.815542)
			(xy 386.434838 -280.815542)
		)
		(stroke
			(width 0)
			(type solid)
		)
		(fill yes)
		(layer "In2.Cu")
		(net "M_I_CPU0_SB_DQS_DP<1>")
	)
	(gr_poly
		(pts
			(xy 386.434838 -280.364184) (xy 386.434838 -280.319734) (xy 386.234686 -280.319734) (xy 386.234686 -280.364184)
			(xy 386.334762 -280.46426)
		)
		(stroke
			(width 0)
			(type solid)
		)
		(fill yes)
		(layer "In2.Cu")
		(net "M_I_CPU0_SB_DQ<11>")
	)
	(gr_poly
		(pts
			(xy 386.434838 -279.148032) (xy 386.334762 -279.047956) (xy 386.234686 -279.148032) (xy 386.234686 -279.192482)
			(xy 386.434838 -279.192482)
		)
		(stroke
			(width 0)
			(type solid)
		)
		(fill yes)
		(layer "In2.Cu")
		(net "M_I_CPU0_SB_DQ<8>")
	)
	(gr_poly
		(pts
			(xy 386.434838 -278.744172) (xy 386.434838 -278.699722) (xy 386.234686 -278.699722) (xy 386.234686 -278.744172)
			(xy 386.334762 -278.844248)
		)
		(stroke
			(width 0)
			(type solid)
		)
		(fill yes)
		(layer "In2.Cu")
		(net "M_I_CPU0_SB_DQ<7>")
	)
	(gr_poly
		(pts
			(xy 386.434838 -277.52802) (xy 386.334762 -277.427944) (xy 386.234686 -277.52802) (xy 386.234686 -277.57247)
			(xy 386.434838 -277.57247)
		)
		(stroke
			(width 0)
			(type solid)
		)
		(fill yes)
		(layer "In2.Cu")
		(net "M_I_CPU0_SB_DQ<4>")
	)
	(gr_poly
		(pts
			(xy 386.434838 -277.124414) (xy 386.434838 -277.076662) (xy 386.234686 -277.076662) (xy 386.234686 -277.124414)
			(xy 386.334762 -277.224236)
		)
		(stroke
			(width 0)
			(type solid)
		)
		(fill yes)
		(layer "In2.Cu")
		(net "M_I_CPU0_SB_DQS_DP<5>")
	)
	(gr_poly
		(pts
			(xy 386.434838 -275.907754) (xy 386.334762 -275.807932) (xy 386.234686 -275.907754) (xy 386.234686 -275.955506)
			(xy 386.434838 -275.955506)
		)
		(stroke
			(width 0)
			(type solid)
		)
		(fill yes)
		(layer "In2.Cu")
		(net "M_I_CPU0_SB_DQS_DP<0>")
	)
	(gr_poly
		(pts
			(xy 386.434838 -275.504148) (xy 386.434838 -275.459698) (xy 386.234686 -275.459698) (xy 386.234686 -275.504148)
			(xy 386.334762 -275.604224)
		)
		(stroke
			(width 0)
			(type solid)
		)
		(fill yes)
		(layer "In2.Cu")
		(net "M_I_CPU0_SB_DQ<3>")
	)
	(gr_poly
		(pts
			(xy 386.434838 -274.287996) (xy 386.334762 -274.18792) (xy 386.234686 -274.287996) (xy 386.234686 -274.332446)
			(xy 386.434838 -274.332446)
		)
		(stroke
			(width 0)
			(type solid)
		)
		(fill yes)
		(layer "In2.Cu")
		(net "M_I_CPU0_SB_DQ<0>")
	)
	(gr_poly
		(pts
			(xy 386.434838 -273.884136) (xy 386.434838 -273.839686) (xy 386.234686 -273.839686) (xy 386.234686 -273.884136)
			(xy 386.334762 -273.984212)
		)
		(stroke
			(width 0)
			(type solid)
		)
		(fill yes)
		(layer "In2.Cu")
		(net "M_I_CPU0_SB_CB<3>")
	)
	(gr_poly
		(pts
			(xy 386.434838 -272.667984) (xy 386.334762 -272.567908) (xy 386.234686 -272.667984) (xy 386.234686 -272.712434)
			(xy 386.434838 -272.712434)
		)
		(stroke
			(width 0)
			(type solid)
		)
		(fill yes)
		(layer "In2.Cu")
		(net "M_I_CPU0_SB_CB<0>")
	)
	(gr_poly
		(pts
			(xy 386.434838 -272.264378) (xy 386.434838 -272.216626) (xy 386.234686 -272.216626) (xy 386.234686 -272.264378)
			(xy 386.334762 -272.3642)
		)
		(stroke
			(width 0)
			(type solid)
		)
		(fill yes)
		(layer "In2.Cu")
		(net "M_I_CPU0_SB_DQS_DP<4>")
	)
	(gr_poly
		(pts
			(xy 386.434838 -271.047718) (xy 386.334762 -270.947896) (xy 386.234686 -271.047718) (xy 386.234686 -271.09547)
			(xy 386.434838 -271.09547)
		)
		(stroke
			(width 0)
			(type solid)
		)
		(fill yes)
		(layer "In2.Cu")
		(net "M_I_CPU0_SB_DQS_DP<9>")
	)
	(gr_poly
		(pts
			(xy 386.434838 -270.644112) (xy 386.434838 -270.599662) (xy 386.234686 -270.599662) (xy 386.234686 -270.644112)
			(xy 386.334762 -270.744188)
		)
		(stroke
			(width 0)
			(type solid)
		)
		(fill yes)
		(layer "In2.Cu")
		(net "M_I_CPU0_SB_CB<7>")
	)
	(gr_poly
		(pts
			(xy 386.434838 -269.42796) (xy 386.334762 -269.327884) (xy 386.234686 -269.42796) (xy 386.234686 -269.47241)
			(xy 386.434838 -269.47241)
		)
		(stroke
			(width 0)
			(type solid)
		)
		(fill yes)
		(layer "In2.Cu")
		(net "M_I_CPU0_SB_CB<4>")
	)
	(gr_poly
		(pts
			(xy 386.434838 -267.404088) (xy 386.434838 -267.359638) (xy 386.234686 -267.359638) (xy 386.234686 -267.404088)
			(xy 386.334762 -267.504164)
		)
		(stroke
			(width 0)
			(type solid)
		)
		(fill yes)
		(layer "In2.Cu")
		(net "M_I_CPU0_SB_RSP<0>")
	)
	(gr_poly
		(pts
			(xy 386.434838 -265.784076) (xy 386.434838 -265.739626) (xy 386.234686 -265.739626) (xy 386.234686 -265.784076)
			(xy 386.334762 -265.884152)
		)
		(stroke
			(width 0)
			(type solid)
		)
		(fill yes)
		(layer "In2.Cu")
		(net "M_I_CPU0_SB_CS_N<0>")
	)
	(gr_poly
		(pts
			(xy 386.434838 -264.567924) (xy 386.334762 -264.467848) (xy 386.234686 -264.567924) (xy 386.234686 -264.612374)
			(xy 386.434838 -264.612374)
		)
		(stroke
			(width 0)
			(type solid)
		)
		(fill yes)
		(layer "In2.Cu")
		(net "M_I_CPU0_SB_CA<6>")
	)
	(gr_poly
		(pts
			(xy 386.434838 -264.164064) (xy 386.434838 -264.119614) (xy 386.234686 -264.119614) (xy 386.234686 -264.164064)
			(xy 386.334762 -264.26414)
		)
		(stroke
			(width 0)
			(type solid)
		)
		(fill yes)
		(layer "In2.Cu")
		(net "M_I_CPU0_SB_CA<5>")
	)
	(gr_poly
		(pts
			(xy 386.434838 -262.947912) (xy 386.334762 -262.847836) (xy 386.234686 -262.947912) (xy 386.234686 -262.992362)
			(xy 386.434838 -262.992362)
		)
		(stroke
			(width 0)
			(type solid)
		)
		(fill yes)
		(layer "In2.Cu")
		(net "M_I_CPU0_SB_CA<2>")
	)
	(gr_poly
		(pts
			(xy 386.434838 -262.544052) (xy 386.434838 -262.499602) (xy 386.234686 -262.499602) (xy 386.234686 -262.544052)
			(xy 386.334762 -262.644128)
		)
		(stroke
			(width 0)
			(type solid)
		)
		(fill yes)
		(layer "In2.Cu")
		(net "M_I_CPU0_SB_CA<1>")
	)
	(gr_poly
		(pts
			(xy 386.605018 -256.025904) (xy 386.504942 -255.926082) (xy 386.404866 -256.025904) (xy 386.404866 -256.073656)
			(xy 386.605018 -256.073656)
		)
		(stroke
			(width 0)
			(type solid)
		)
		(fill yes)
		(layer "In2.Cu")
		(net "M_I_CPU0_CLK_DP<0>")
	)
	(gr_poly
		(pts
			(xy 386.605018 -255.622298) (xy 386.605018 -255.577848) (xy 386.404866 -255.577848) (xy 386.404866 -255.622298)
			(xy 386.504942 -255.722374)
		)
		(stroke
			(width 0)
			(type solid)
		)
		(fill yes)
		(layer "In2.Cu")
		(net "M_I_CPU0_SA_PAR")
	)
	(gr_poly
		(pts
			(xy 386.605018 -254.406146) (xy 386.504942 -254.30607) (xy 386.404866 -254.406146) (xy 386.404866 -254.450596)
			(xy 386.605018 -254.450596)
		)
		(stroke
			(width 0)
			(type solid)
		)
		(fill yes)
		(layer "In2.Cu")
		(net "M_I_CPU0_SA_CA<4>")
	)
	(gr_poly
		(pts
			(xy 386.605018 -254.002286) (xy 386.605018 -253.957836) (xy 386.404866 -253.957836) (xy 386.404866 -254.002286)
			(xy 386.504942 -254.102362)
		)
		(stroke
			(width 0)
			(type solid)
		)
		(fill yes)
		(layer "In2.Cu")
		(net "M_I_CPU0_SA_CA<3>")
	)
	(gr_poly
		(pts
			(xy 386.605018 -252.786134) (xy 386.504942 -252.686058) (xy 386.404866 -252.786134) (xy 386.404866 -252.830584)
			(xy 386.605018 -252.830584)
		)
		(stroke
			(width 0)
			(type solid)
		)
		(fill yes)
		(layer "In2.Cu")
		(net "M_I_CPU0_SA_CA<0>")
	)
	(gr_poly
		(pts
			(xy 386.605018 -251.166122) (xy 386.504942 -251.066046) (xy 386.404866 -251.166122) (xy 386.404866 -251.210572)
			(xy 386.605018 -251.210572)
		)
		(stroke
			(width 0)
			(type solid)
		)
		(fill yes)
		(layer "In2.Cu")
		(net "M_I_CPU0_SA_CS_N<0>")
	)
	(gr_poly
		(pts
			(xy 386.605018 -250.762262) (xy 386.605018 -250.717812) (xy 386.404866 -250.717812) (xy 386.404866 -250.762262)
			(xy 386.504942 -250.862338)
		)
		(stroke
			(width 0)
			(type solid)
		)
		(fill yes)
		(layer "In2.Cu")
		(net "M_I_CPU0_RESET_N")
	)
	(gr_poly
		(pts
			(xy 386.605018 -249.14225) (xy 386.605018 -249.0978) (xy 386.404866 -249.0978) (xy 386.404866 -249.14225)
			(xy 386.504942 -249.242326)
		)
		(stroke
			(width 0)
			(type solid)
		)
		(fill yes)
		(layer "In2.Cu")
		(net "M_I_CPU0_SA_CB<7>")
	)
	(gr_poly
		(pts
			(xy 386.605018 -247.926098) (xy 386.504942 -247.826022) (xy 386.404866 -247.926098) (xy 386.404866 -247.970548)
			(xy 386.605018 -247.970548)
		)
		(stroke
			(width 0)
			(type solid)
		)
		(fill yes)
		(layer "In2.Cu")
		(net "M_I_CPU0_SA_CB<4>")
	)
	(gr_poly
		(pts
			(xy 386.605018 -247.522492) (xy 386.605018 -247.47474) (xy 386.404866 -247.47474) (xy 386.404866 -247.522492)
			(xy 386.504942 -247.622314)
		)
		(stroke
			(width 0)
			(type solid)
		)
		(fill yes)
		(layer "In2.Cu")
		(net "M_I_CPU0_SA_DQS_DP<9>")
	)
	(gr_poly
		(pts
			(xy 386.605018 -246.305832) (xy 386.504942 -246.20601) (xy 386.404866 -246.305832) (xy 386.404866 -246.353584)
			(xy 386.605018 -246.353584)
		)
		(stroke
			(width 0)
			(type solid)
		)
		(fill yes)
		(layer "In2.Cu")
		(net "M_I_CPU0_SA_DQS_DP<4>")
	)
	(gr_poly
		(pts
			(xy 386.605018 -245.902226) (xy 386.605018 -245.857776) (xy 386.404866 -245.857776) (xy 386.404866 -245.902226)
			(xy 386.504942 -246.002302)
		)
		(stroke
			(width 0)
			(type solid)
		)
		(fill yes)
		(layer "In2.Cu")
		(net "M_I_CPU0_SA_CB<3>")
	)
	(gr_poly
		(pts
			(xy 386.605018 -244.686074) (xy 386.504942 -244.585998) (xy 386.404866 -244.686074) (xy 386.404866 -244.730524)
			(xy 386.605018 -244.730524)
		)
		(stroke
			(width 0)
			(type solid)
		)
		(fill yes)
		(layer "In2.Cu")
		(net "M_I_CPU0_SA_CB<0>")
	)
	(gr_poly
		(pts
			(xy 386.605018 -244.282214) (xy 386.605018 -244.237764) (xy 386.404866 -244.237764) (xy 386.404866 -244.282214)
			(xy 386.504942 -244.38229)
		)
		(stroke
			(width 0)
			(type solid)
		)
		(fill yes)
		(layer "In2.Cu")
		(net "M_I_CPU0_SA_DQ<31>")
	)
	(gr_poly
		(pts
			(xy 386.605018 -243.066062) (xy 386.504942 -242.965986) (xy 386.404866 -243.066062) (xy 386.404866 -243.110512)
			(xy 386.605018 -243.110512)
		)
		(stroke
			(width 0)
			(type solid)
		)
		(fill yes)
		(layer "In2.Cu")
		(net "M_I_CPU0_SA_DQ<28>")
	)
	(gr_poly
		(pts
			(xy 386.605018 -242.662456) (xy 386.605018 -242.614704) (xy 386.404866 -242.614704) (xy 386.404866 -242.662456)
			(xy 386.504942 -242.762278)
		)
		(stroke
			(width 0)
			(type solid)
		)
		(fill yes)
		(layer "In2.Cu")
		(net "M_I_CPU0_SA_DQS_DP<8>")
	)
	(gr_poly
		(pts
			(xy 386.605018 -241.445796) (xy 386.504942 -241.345974) (xy 386.404866 -241.445796) (xy 386.404866 -241.493548)
			(xy 386.605018 -241.493548)
		)
		(stroke
			(width 0)
			(type solid)
		)
		(fill yes)
		(layer "In2.Cu")
		(net "M_I_CPU0_SA_DQS_DP<3>")
	)
	(gr_poly
		(pts
			(xy 386.605018 -241.04219) (xy 386.605018 -240.99774) (xy 386.404866 -240.99774) (xy 386.404866 -241.04219)
			(xy 386.504942 -241.142266)
		)
		(stroke
			(width 0)
			(type solid)
		)
		(fill yes)
		(layer "In2.Cu")
		(net "M_I_CPU0_SA_DQ<27>")
	)
	(gr_poly
		(pts
			(xy 386.605018 -239.826038) (xy 386.504942 -239.725962) (xy 386.404866 -239.826038) (xy 386.404866 -239.870488)
			(xy 386.605018 -239.870488)
		)
		(stroke
			(width 0)
			(type solid)
		)
		(fill yes)
		(layer "In2.Cu")
		(net "M_I_CPU0_SA_DQ<24>")
	)
	(gr_poly
		(pts
			(xy 386.605018 -239.422178) (xy 386.605018 -239.377728) (xy 386.404866 -239.377728) (xy 386.404866 -239.422178)
			(xy 386.504942 -239.522254)
		)
		(stroke
			(width 0)
			(type solid)
		)
		(fill yes)
		(layer "In2.Cu")
		(net "M_I_CPU0_SA_DQ<23>")
	)
	(gr_poly
		(pts
			(xy 386.605018 -238.206026) (xy 386.504942 -238.10595) (xy 386.404866 -238.206026) (xy 386.404866 -238.250476)
			(xy 386.605018 -238.250476)
		)
		(stroke
			(width 0)
			(type solid)
		)
		(fill yes)
		(layer "In2.Cu")
		(net "M_I_CPU0_SA_DQ<20>")
	)
	(gr_poly
		(pts
			(xy 386.605018 -237.80242) (xy 386.605018 -237.754668) (xy 386.404866 -237.754668) (xy 386.404866 -237.80242)
			(xy 386.504942 -237.902242)
		)
		(stroke
			(width 0)
			(type solid)
		)
		(fill yes)
		(layer "In2.Cu")
		(net "M_I_CPU0_SA_DQS_DP<7>")
	)
	(gr_poly
		(pts
			(xy 386.605018 -236.58576) (xy 386.504942 -236.485938) (xy 386.404866 -236.58576) (xy 386.404866 -236.633512)
			(xy 386.605018 -236.633512)
		)
		(stroke
			(width 0)
			(type solid)
		)
		(fill yes)
		(layer "In2.Cu")
		(net "M_I_CPU0_SA_DQS_DP<2>")
	)
	(gr_poly
		(pts
			(xy 386.605018 -236.182154) (xy 386.605018 -236.137704) (xy 386.404866 -236.137704) (xy 386.404866 -236.182154)
			(xy 386.504942 -236.28223)
		)
		(stroke
			(width 0)
			(type solid)
		)
		(fill yes)
		(layer "In2.Cu")
		(net "M_I_CPU0_SA_DQ<19>")
	)
	(gr_poly
		(pts
			(xy 386.605018 -234.966002) (xy 386.504942 -234.865926) (xy 386.404866 -234.966002) (xy 386.404866 -235.010452)
			(xy 386.605018 -235.010452)
		)
		(stroke
			(width 0)
			(type solid)
		)
		(fill yes)
		(layer "In2.Cu")
		(net "M_I_CPU0_SA_DQ<16>")
	)
	(gr_poly
		(pts
			(xy 386.605018 -234.562142) (xy 386.605018 -234.517692) (xy 386.404866 -234.517692) (xy 386.404866 -234.562142)
			(xy 386.504942 -234.662218)
		)
		(stroke
			(width 0)
			(type solid)
		)
		(fill yes)
		(layer "In2.Cu")
		(net "M_I_CPU0_SA_DQ<15>")
	)
	(gr_poly
		(pts
			(xy 386.605018 -233.34599) (xy 386.504942 -233.245914) (xy 386.404866 -233.34599) (xy 386.404866 -233.39044)
			(xy 386.605018 -233.39044)
		)
		(stroke
			(width 0)
			(type solid)
		)
		(fill yes)
		(layer "In2.Cu")
		(net "M_I_CPU0_SA_DQ<12>")
	)
	(gr_poly
		(pts
			(xy 386.605018 -232.942384) (xy 386.605018 -232.894632) (xy 386.404866 -232.894632) (xy 386.404866 -232.942384)
			(xy 386.504942 -233.042206)
		)
		(stroke
			(width 0)
			(type solid)
		)
		(fill yes)
		(layer "In2.Cu")
		(net "M_I_CPU0_SA_DQS_DP<6>")
	)
	(gr_poly
		(pts
			(xy 386.605018 -231.725724) (xy 386.504942 -231.625902) (xy 386.404866 -231.725724) (xy 386.404866 -231.773476)
			(xy 386.605018 -231.773476)
		)
		(stroke
			(width 0)
			(type solid)
		)
		(fill yes)
		(layer "In2.Cu")
		(net "M_I_CPU0_SA_DQS_DP<1>")
	)
	(gr_poly
		(pts
			(xy 386.605018 -231.322372) (xy 386.605018 -231.277922) (xy 386.404866 -231.277922) (xy 386.404866 -231.322372)
			(xy 386.504942 -231.422448)
		)
		(stroke
			(width 0)
			(type solid)
		)
		(fill yes)
		(layer "In2.Cu")
		(net "M_I_CPU0_SA_DQ<11>")
	)
	(gr_poly
		(pts
			(xy 386.605018 -230.105966) (xy 386.504942 -230.006144) (xy 386.404866 -230.105966) (xy 386.404866 -230.150416)
			(xy 386.605018 -230.150416)
		)
		(stroke
			(width 0)
			(type solid)
		)
		(fill yes)
		(layer "In2.Cu")
		(net "M_I_CPU0_SA_DQ<8>")
	)
	(gr_poly
		(pts
			(xy 386.605018 -229.70236) (xy 386.605018 -229.65791) (xy 386.404866 -229.65791) (xy 386.404866 -229.70236)
			(xy 386.504942 -229.802436)
		)
		(stroke
			(width 0)
			(type solid)
		)
		(fill yes)
		(layer "In2.Cu")
		(net "M_I_CPU0_SA_DQ<7>")
	)
	(gr_poly
		(pts
			(xy 386.605018 -228.486208) (xy 386.504942 -228.386132) (xy 386.404866 -228.486208) (xy 386.404866 -228.530658)
			(xy 386.605018 -228.530658)
		)
		(stroke
			(width 0)
			(type solid)
		)
		(fill yes)
		(layer "In2.Cu")
		(net "M_I_CPU0_SA_DQ<4>")
	)
	(gr_poly
		(pts
			(xy 386.605018 -228.082602) (xy 386.605018 -228.03485) (xy 386.404866 -228.03485) (xy 386.404866 -228.082602)
			(xy 386.504942 -228.182424)
		)
		(stroke
			(width 0)
			(type solid)
		)
		(fill yes)
		(layer "In2.Cu")
		(net "M_I_CPU0_SA_DQS_DP<5>")
	)
	(gr_poly
		(pts
			(xy 386.605018 -226.865942) (xy 386.504942 -226.76612) (xy 386.404866 -226.865942) (xy 386.404866 -226.913694)
			(xy 386.605018 -226.913694)
		)
		(stroke
			(width 0)
			(type solid)
		)
		(fill yes)
		(layer "In2.Cu")
		(net "M_I_CPU0_SA_DQS_DP<0>")
	)
	(gr_poly
		(pts
			(xy 386.605018 -226.462336) (xy 386.605018 -226.417886) (xy 386.404866 -226.417886) (xy 386.404866 -226.462336)
			(xy 386.504942 -226.562412)
		)
		(stroke
			(width 0)
			(type solid)
		)
		(fill yes)
		(layer "In2.Cu")
		(net "M_I_CPU0_SA_DQ<3>")
	)
	(gr_poly
		(pts
			(xy 386.605018 -225.246184) (xy 386.504942 -225.146108) (xy 386.404866 -225.246184) (xy 386.404866 -225.290634)
			(xy 386.605018 -225.290634)
		)
		(stroke
			(width 0)
			(type solid)
		)
		(fill yes)
		(layer "In2.Cu")
		(net "M_I_CPU0_SA_DQ<0>")
	)
	(gr_poly
		(pts
			(xy 386.904992 -292.91788) (xy 386.804916 -292.817804) (xy 386.70484 -292.91788) (xy 386.70484 -292.96233)
			(xy 386.904992 -292.96233)
		)
		(stroke
			(width 0)
			(type solid)
		)
		(fill yes)
		(layer "In2.Cu")
		(net "M_I_CPU0_SB_DQ<29>")
	)
	(gr_poly
		(pts
			(xy 386.904992 -292.51402) (xy 386.904992 -292.46957) (xy 386.70484 -292.46957) (xy 386.70484 -292.51402)
			(xy 386.804916 -292.614096)
		)
		(stroke
			(width 0)
			(type solid)
		)
		(fill yes)
		(layer "In2.Cu")
		(net "M_I_CPU0_SB_DQ<30>")
	)
	(gr_poly
		(pts
			(xy 386.904992 -291.297614) (xy 386.804916 -291.197792) (xy 386.70484 -291.297614) (xy 386.70484 -291.345366)
			(xy 386.904992 -291.345366)
		)
		(stroke
			(width 0)
			(type solid)
		)
		(fill yes)
		(layer "In2.Cu")
		(net "M_I_CPU0_SB_DQS_DN<8>")
	)
	(gr_poly
		(pts
			(xy 386.904992 -290.894262) (xy 386.904992 -290.84651) (xy 386.70484 -290.84651) (xy 386.70484 -290.894262)
			(xy 386.804916 -290.994084)
		)
		(stroke
			(width 0)
			(type solid)
		)
		(fill yes)
		(layer "In2.Cu")
		(net "M_I_CPU0_SB_DQS_DN<3>")
	)
	(gr_poly
		(pts
			(xy 386.904992 -289.677856) (xy 386.804916 -289.57778) (xy 386.70484 -289.677856) (xy 386.70484 -289.722306)
			(xy 386.904992 -289.722306)
		)
		(stroke
			(width 0)
			(type solid)
		)
		(fill yes)
		(layer "In2.Cu")
		(net "M_I_CPU0_SB_DQ<25>")
	)
	(gr_poly
		(pts
			(xy 386.904992 -289.273996) (xy 386.904992 -289.229546) (xy 386.70484 -289.229546) (xy 386.70484 -289.273996)
			(xy 386.804916 -289.374072)
		)
		(stroke
			(width 0)
			(type solid)
		)
		(fill yes)
		(layer "In2.Cu")
		(net "M_I_CPU0_SB_DQ<26>")
	)
	(gr_poly
		(pts
			(xy 386.904992 -288.057844) (xy 386.804916 -287.957768) (xy 386.70484 -288.057844) (xy 386.70484 -288.102294)
			(xy 386.904992 -288.102294)
		)
		(stroke
			(width 0)
			(type solid)
		)
		(fill yes)
		(layer "In2.Cu")
		(net "M_I_CPU0_SB_DQ<21>")
	)
	(gr_poly
		(pts
			(xy 386.904992 -287.654238) (xy 386.904992 -287.609788) (xy 386.70484 -287.609788) (xy 386.70484 -287.654238)
			(xy 386.804916 -287.75406)
		)
		(stroke
			(width 0)
			(type solid)
		)
		(fill yes)
		(layer "In2.Cu")
		(net "M_I_CPU0_SB_DQ<22>")
	)
	(gr_poly
		(pts
			(xy 386.904992 -286.437832) (xy 386.804916 -286.337756) (xy 386.70484 -286.437832) (xy 386.70484 -286.485584)
			(xy 386.904992 -286.485584)
		)
		(stroke
			(width 0)
			(type solid)
		)
		(fill yes)
		(layer "In2.Cu")
		(net "M_I_CPU0_SB_DQS_DN<7>")
	)
	(gr_poly
		(pts
			(xy 386.904992 -286.03448) (xy 386.904992 -285.986728) (xy 386.70484 -285.986728) (xy 386.70484 -286.03448)
			(xy 386.804916 -286.134302)
		)
		(stroke
			(width 0)
			(type solid)
		)
		(fill yes)
		(layer "In2.Cu")
		(net "M_I_CPU0_SB_DQS_DN<2>")
	)
	(gr_poly
		(pts
			(xy 386.904992 -284.818074) (xy 386.804916 -284.717998) (xy 386.70484 -284.818074) (xy 386.70484 -284.862524)
			(xy 386.904992 -284.862524)
		)
		(stroke
			(width 0)
			(type solid)
		)
		(fill yes)
		(layer "In2.Cu")
		(net "M_I_CPU0_SB_DQ<17>")
	)
	(gr_poly
		(pts
			(xy 386.904992 -284.414214) (xy 386.904992 -284.369764) (xy 386.70484 -284.369764) (xy 386.70484 -284.414214)
			(xy 386.804916 -284.51429)
		)
		(stroke
			(width 0)
			(type solid)
		)
		(fill yes)
		(layer "In2.Cu")
		(net "M_I_CPU0_SB_DQ<18>")
	)
	(gr_poly
		(pts
			(xy 386.904992 -283.198062) (xy 386.804916 -283.097986) (xy 386.70484 -283.198062) (xy 386.70484 -283.242512)
			(xy 386.904992 -283.242512)
		)
		(stroke
			(width 0)
			(type solid)
		)
		(fill yes)
		(layer "In2.Cu")
		(net "M_I_CPU0_SB_DQ<13>")
	)
	(gr_poly
		(pts
			(xy 386.904992 -282.794202) (xy 386.904992 -282.749752) (xy 386.70484 -282.749752) (xy 386.70484 -282.794202)
			(xy 386.804916 -282.894278)
		)
		(stroke
			(width 0)
			(type solid)
		)
		(fill yes)
		(layer "In2.Cu")
		(net "M_I_CPU0_SB_DQ<14>")
	)
	(gr_poly
		(pts
			(xy 386.904992 -281.577796) (xy 386.804916 -281.477974) (xy 386.70484 -281.577796) (xy 386.70484 -281.625548)
			(xy 386.904992 -281.625548)
		)
		(stroke
			(width 0)
			(type solid)
		)
		(fill yes)
		(layer "In2.Cu")
		(net "M_I_CPU0_SB_DQS_DN<6>")
	)
	(gr_poly
		(pts
			(xy 386.904992 -281.174444) (xy 386.904992 -281.126692) (xy 386.70484 -281.126692) (xy 386.70484 -281.174444)
			(xy 386.804916 -281.274266)
		)
		(stroke
			(width 0)
			(type solid)
		)
		(fill yes)
		(layer "In2.Cu")
		(net "M_I_CPU0_SB_DQS_DN<1>")
	)
	(gr_poly
		(pts
			(xy 386.904992 -279.958038) (xy 386.804916 -279.857962) (xy 386.70484 -279.958038) (xy 386.70484 -280.002488)
			(xy 386.904992 -280.002488)
		)
		(stroke
			(width 0)
			(type solid)
		)
		(fill yes)
		(layer "In2.Cu")
		(net "M_I_CPU0_SB_DQ<9>")
	)
	(gr_poly
		(pts
			(xy 386.904992 -279.554178) (xy 386.904992 -279.509728) (xy 386.70484 -279.509728) (xy 386.70484 -279.554178)
			(xy 386.804916 -279.654254)
		)
		(stroke
			(width 0)
			(type solid)
		)
		(fill yes)
		(layer "In2.Cu")
		(net "M_I_CPU0_SB_DQ<10>")
	)
	(gr_poly
		(pts
			(xy 386.904992 -278.338026) (xy 386.804916 -278.23795) (xy 386.70484 -278.338026) (xy 386.70484 -278.382476)
			(xy 386.904992 -278.382476)
		)
		(stroke
			(width 0)
			(type solid)
		)
		(fill yes)
		(layer "In2.Cu")
		(net "M_I_CPU0_SB_DQ<5>")
	)
	(gr_poly
		(pts
			(xy 386.904992 -277.934166) (xy 386.904992 -277.889716) (xy 386.70484 -277.889716) (xy 386.70484 -277.934166)
			(xy 386.804916 -278.034242)
		)
		(stroke
			(width 0)
			(type solid)
		)
		(fill yes)
		(layer "In2.Cu")
		(net "M_I_CPU0_SB_DQ<6>")
	)
	(gr_poly
		(pts
			(xy 386.904992 -276.71776) (xy 386.804916 -276.617938) (xy 386.70484 -276.71776) (xy 386.70484 -276.765512)
			(xy 386.904992 -276.765512)
		)
		(stroke
			(width 0)
			(type solid)
		)
		(fill yes)
		(layer "In2.Cu")
		(net "M_I_CPU0_SB_DQS_DN<5>")
	)
	(gr_poly
		(pts
			(xy 386.904992 -276.314408) (xy 386.904992 -276.266656) (xy 386.70484 -276.266656) (xy 386.70484 -276.314408)
			(xy 386.804916 -276.41423)
		)
		(stroke
			(width 0)
			(type solid)
		)
		(fill yes)
		(layer "In2.Cu")
		(net "M_I_CPU0_SB_DQS_DN<0>")
	)
	(gr_poly
		(pts
			(xy 386.904992 -275.098002) (xy 386.804916 -274.997926) (xy 386.70484 -275.098002) (xy 386.70484 -275.142452)
			(xy 386.904992 -275.142452)
		)
		(stroke
			(width 0)
			(type solid)
		)
		(fill yes)
		(layer "In2.Cu")
		(net "M_I_CPU0_SB_DQ<1>")
	)
	(gr_poly
		(pts
			(xy 386.904992 -274.694142) (xy 386.904992 -274.649692) (xy 386.70484 -274.649692) (xy 386.70484 -274.694142)
			(xy 386.804916 -274.794218)
		)
		(stroke
			(width 0)
			(type solid)
		)
		(fill yes)
		(layer "In2.Cu")
		(net "M_I_CPU0_SB_DQ<2>")
	)
	(gr_poly
		(pts
			(xy 386.904992 -273.47799) (xy 386.804916 -273.377914) (xy 386.70484 -273.47799) (xy 386.70484 -273.52244)
			(xy 386.904992 -273.52244)
		)
		(stroke
			(width 0)
			(type solid)
		)
		(fill yes)
		(layer "In2.Cu")
		(net "M_I_CPU0_SB_CB<1>")
	)
	(gr_poly
		(pts
			(xy 386.904992 -273.07413) (xy 386.904992 -273.02968) (xy 386.70484 -273.02968) (xy 386.70484 -273.07413)
			(xy 386.804916 -273.174206)
		)
		(stroke
			(width 0)
			(type solid)
		)
		(fill yes)
		(layer "In2.Cu")
		(net "M_I_CPU0_SB_CB<2>")
	)
	(gr_poly
		(pts
			(xy 386.904992 -271.857724) (xy 386.804916 -271.757902) (xy 386.70484 -271.857724) (xy 386.70484 -271.905476)
			(xy 386.904992 -271.905476)
		)
		(stroke
			(width 0)
			(type solid)
		)
		(fill yes)
		(layer "In2.Cu")
		(net "M_I_CPU0_SB_DQS_DN<4>")
	)
	(gr_poly
		(pts
			(xy 386.904992 -271.454372) (xy 386.904992 -271.40662) (xy 386.70484 -271.40662) (xy 386.70484 -271.454372)
			(xy 386.804916 -271.554194)
		)
		(stroke
			(width 0)
			(type solid)
		)
		(fill yes)
		(layer "In2.Cu")
		(net "M_I_CPU0_SB_DQS_DN<9>")
	)
	(gr_poly
		(pts
			(xy 386.904992 -270.237966) (xy 386.804916 -270.13789) (xy 386.70484 -270.237966) (xy 386.70484 -270.282416)
			(xy 386.904992 -270.282416)
		)
		(stroke
			(width 0)
			(type solid)
		)
		(fill yes)
		(layer "In2.Cu")
		(net "M_I_CPU0_SB_CB<5>")
	)
	(gr_poly
		(pts
			(xy 386.904992 -269.834106) (xy 386.904992 -269.789656) (xy 386.70484 -269.789656) (xy 386.70484 -269.834106)
			(xy 386.804916 -269.934182)
		)
		(stroke
			(width 0)
			(type solid)
		)
		(fill yes)
		(layer "In2.Cu")
		(net "M_I_CPU0_SB_CB<6>")
	)
	(gr_poly
		(pts
			(xy 386.904992 -266.997942) (xy 386.804916 -266.897866) (xy 386.70484 -266.997942) (xy 386.70484 -267.042392)
			(xy 386.904992 -267.042392)
		)
		(stroke
			(width 0)
			(type solid)
		)
		(fill yes)
		(layer "In2.Cu")
		(net "M_I_CPU0_SA_RSP<0>")
	)
	(gr_poly
		(pts
			(xy 386.904992 -266.594082) (xy 386.904992 -266.549632) (xy 386.70484 -266.549632) (xy 386.70484 -266.594082)
			(xy 386.804916 -266.694158)
		)
		(stroke
			(width 0)
			(type solid)
		)
		(fill yes)
		(layer "In2.Cu")
		(net "M_I_CPU0_SB_CS_N<1>")
	)
	(gr_poly
		(pts
			(xy 386.904992 -265.37793) (xy 386.804916 -265.277854) (xy 386.70484 -265.37793) (xy 386.70484 -265.42238)
			(xy 386.904992 -265.42238)
		)
		(stroke
			(width 0)
			(type solid)
		)
		(fill yes)
		(layer "In2.Cu")
		(net "M_I_CPU0_SB_PAR")
	)
	(gr_poly
		(pts
			(xy 386.904992 -263.757918) (xy 386.804916 -263.657842) (xy 386.70484 -263.757918) (xy 386.70484 -263.802368)
			(xy 386.904992 -263.802368)
		)
		(stroke
			(width 0)
			(type solid)
		)
		(fill yes)
		(layer "In2.Cu")
		(net "M_I_CPU0_SB_CA<4>")
	)
	(gr_poly
		(pts
			(xy 386.904992 -263.354058) (xy 386.904992 -263.309608) (xy 386.70484 -263.309608) (xy 386.70484 -263.354058)
			(xy 386.804916 -263.454134)
		)
		(stroke
			(width 0)
			(type solid)
		)
		(fill yes)
		(layer "In2.Cu")
		(net "M_I_CPU0_SB_CA<3>")
	)
	(gr_poly
		(pts
			(xy 386.904992 -262.137906) (xy 386.804916 -262.03783) (xy 386.70484 -262.137906) (xy 386.70484 -262.182356)
			(xy 386.904992 -262.182356)
		)
		(stroke
			(width 0)
			(type solid)
		)
		(fill yes)
		(layer "In2.Cu")
		(net "M_I_CPU0_SB_CA<0>")
	)
	(gr_poly
		(pts
			(xy 387.074918 -256.432558) (xy 387.074918 -256.384806) (xy 386.874766 -256.384806) (xy 386.874766 -256.432558)
			(xy 386.974842 -256.53238)
		)
		(stroke
			(width 0)
			(type solid)
		)
		(fill yes)
		(layer "In2.Cu")
		(net "M_I_CPU0_CLK_DN<0>")
	)
	(gr_poly
		(pts
			(xy 387.074918 -255.216152) (xy 386.974842 -255.116076) (xy 386.874766 -255.216152) (xy 386.874766 -255.260602)
			(xy 387.074918 -255.260602)
		)
		(stroke
			(width 0)
			(type solid)
		)
		(fill yes)
		(layer "In2.Cu")
		(net "M_I_CPU0_SA_CA<6>")
	)
	(gr_poly
		(pts
			(xy 387.074918 -254.812292) (xy 387.074918 -254.767842) (xy 386.874766 -254.767842) (xy 386.874766 -254.812292)
			(xy 386.974842 -254.912368)
		)
		(stroke
			(width 0)
			(type solid)
		)
		(fill yes)
		(layer "In2.Cu")
		(net "M_I_CPU0_SA_CA<5>")
	)
	(gr_poly
		(pts
			(xy 387.074918 -253.59614) (xy 386.974842 -253.496064) (xy 386.874766 -253.59614) (xy 386.874766 -253.64059)
			(xy 387.074918 -253.64059)
		)
		(stroke
			(width 0)
			(type solid)
		)
		(fill yes)
		(layer "In2.Cu")
		(net "M_I_CPU0_SA_CA<2>")
	)
	(gr_poly
		(pts
			(xy 387.074918 -253.19228) (xy 387.074918 -253.14783) (xy 386.874766 -253.14783) (xy 386.874766 -253.19228)
			(xy 386.974842 -253.292356)
		)
		(stroke
			(width 0)
			(type solid)
		)
		(fill yes)
		(layer "In2.Cu")
		(net "M_I_CPU0_SA_CA<1>")
	)
	(gr_poly
		(pts
			(xy 387.074918 -251.976128) (xy 386.974842 -251.876052) (xy 386.874766 -251.976128) (xy 386.874766 -252.020578)
			(xy 387.074918 -252.020578)
		)
		(stroke
			(width 0)
			(type solid)
		)
		(fill yes)
		(layer "In2.Cu")
		(net "M_I_CPU0_SA_CS_N<1>")
	)
	(gr_poly
		(pts
			(xy 387.074918 -250.356116) (xy 386.974842 -250.25604) (xy 386.874766 -250.356116) (xy 386.874766 -250.400566)
			(xy 387.074918 -250.400566)
		)
		(stroke
			(width 0)
			(type solid)
		)
		(fill yes)
		(layer "In2.Cu")
		(net "M_I_CPU0_ALERT_R_N")
	)
	(gr_poly
		(pts
			(xy 387.074918 -248.736104) (xy 386.974842 -248.636028) (xy 386.874766 -248.736104) (xy 386.874766 -248.780554)
			(xy 387.074918 -248.780554)
		)
		(stroke
			(width 0)
			(type solid)
		)
		(fill yes)
		(layer "In2.Cu")
		(net "M_I_CPU0_SA_CB<5>")
	)
	(gr_poly
		(pts
			(xy 387.074918 -248.332244) (xy 387.074918 -248.287794) (xy 386.874766 -248.287794) (xy 386.874766 -248.332244)
			(xy 386.974842 -248.43232)
		)
		(stroke
			(width 0)
			(type solid)
		)
		(fill yes)
		(layer "In2.Cu")
		(net "M_I_CPU0_SA_CB<6>")
	)
	(gr_poly
		(pts
			(xy 387.074918 -247.115838) (xy 386.974842 -247.016016) (xy 386.874766 -247.115838) (xy 386.874766 -247.16359)
			(xy 387.074918 -247.16359)
		)
		(stroke
			(width 0)
			(type solid)
		)
		(fill yes)
		(layer "In2.Cu")
		(net "M_I_CPU0_SA_DQS_DN<9>")
	)
	(gr_poly
		(pts
			(xy 387.074918 -246.712486) (xy 387.074918 -246.664734) (xy 386.874766 -246.664734) (xy 386.874766 -246.712486)
			(xy 386.974842 -246.812308)
		)
		(stroke
			(width 0)
			(type solid)
		)
		(fill yes)
		(layer "In2.Cu")
		(net "M_I_CPU0_SA_DQS_DN<4>")
	)
	(gr_poly
		(pts
			(xy 387.074918 -245.49608) (xy 386.974842 -245.396004) (xy 386.874766 -245.49608) (xy 386.874766 -245.54053)
			(xy 387.074918 -245.54053)
		)
		(stroke
			(width 0)
			(type solid)
		)
		(fill yes)
		(layer "In2.Cu")
		(net "M_I_CPU0_SA_CB<1>")
	)
	(gr_poly
		(pts
			(xy 387.074918 -245.09222) (xy 387.074918 -245.04777) (xy 386.874766 -245.04777) (xy 386.874766 -245.09222)
			(xy 386.974842 -245.192296)
		)
		(stroke
			(width 0)
			(type solid)
		)
		(fill yes)
		(layer "In2.Cu")
		(net "M_I_CPU0_SA_CB<2>")
	)
	(gr_poly
		(pts
			(xy 387.074918 -243.876068) (xy 386.974842 -243.775992) (xy 386.874766 -243.876068) (xy 386.874766 -243.920518)
			(xy 387.074918 -243.920518)
		)
		(stroke
			(width 0)
			(type solid)
		)
		(fill yes)
		(layer "In2.Cu")
		(net "M_I_CPU0_SA_DQ<29>")
	)
	(gr_poly
		(pts
			(xy 387.074918 -243.472208) (xy 387.074918 -243.427758) (xy 386.874766 -243.427758) (xy 386.874766 -243.472208)
			(xy 386.974842 -243.572284)
		)
		(stroke
			(width 0)
			(type solid)
		)
		(fill yes)
		(layer "In2.Cu")
		(net "M_I_CPU0_SA_DQ<30>")
	)
	(gr_poly
		(pts
			(xy 387.074918 -242.255802) (xy 386.974842 -242.15598) (xy 386.874766 -242.255802) (xy 386.874766 -242.303554)
			(xy 387.074918 -242.303554)
		)
		(stroke
			(width 0)
			(type solid)
		)
		(fill yes)
		(layer "In2.Cu")
		(net "M_I_CPU0_SA_DQS_DN<8>")
	)
	(gr_poly
		(pts
			(xy 387.074918 -241.85245) (xy 387.074918 -241.804698) (xy 386.874766 -241.804698) (xy 386.874766 -241.85245)
			(xy 386.974842 -241.952272)
		)
		(stroke
			(width 0)
			(type solid)
		)
		(fill yes)
		(layer "In2.Cu")
		(net "M_I_CPU0_SA_DQS_DN<3>")
	)
	(gr_poly
		(pts
			(xy 387.074918 -240.636044) (xy 386.974842 -240.535968) (xy 386.874766 -240.636044) (xy 386.874766 -240.680494)
			(xy 387.074918 -240.680494)
		)
		(stroke
			(width 0)
			(type solid)
		)
		(fill yes)
		(layer "In2.Cu")
		(net "M_I_CPU0_SA_DQ<25>")
	)
	(gr_poly
		(pts
			(xy 387.074918 -240.232184) (xy 387.074918 -240.187734) (xy 386.874766 -240.187734) (xy 386.874766 -240.232184)
			(xy 386.974842 -240.33226)
		)
		(stroke
			(width 0)
			(type solid)
		)
		(fill yes)
		(layer "In2.Cu")
		(net "M_I_CPU0_SA_DQ<26>")
	)
	(gr_poly
		(pts
			(xy 387.074918 -239.016032) (xy 386.974842 -238.915956) (xy 386.874766 -239.016032) (xy 386.874766 -239.060482)
			(xy 387.074918 -239.060482)
		)
		(stroke
			(width 0)
			(type solid)
		)
		(fill yes)
		(layer "In2.Cu")
		(net "M_I_CPU0_SA_DQ<21>")
	)
	(gr_poly
		(pts
			(xy 387.074918 -238.612172) (xy 387.074918 -238.567722) (xy 386.874766 -238.567722) (xy 386.874766 -238.612172)
			(xy 386.974842 -238.712248)
		)
		(stroke
			(width 0)
			(type solid)
		)
		(fill yes)
		(layer "In2.Cu")
		(net "M_I_CPU0_SA_DQ<22>")
	)
	(gr_poly
		(pts
			(xy 387.074918 -237.395766) (xy 386.974842 -237.295944) (xy 386.874766 -237.395766) (xy 386.874766 -237.443518)
			(xy 387.074918 -237.443518)
		)
		(stroke
			(width 0)
			(type solid)
		)
		(fill yes)
		(layer "In2.Cu")
		(net "M_I_CPU0_SA_DQS_DN<7>")
	)
	(gr_poly
		(pts
			(xy 387.074918 -236.992414) (xy 387.074918 -236.944662) (xy 386.874766 -236.944662) (xy 386.874766 -236.992414)
			(xy 386.974842 -237.092236)
		)
		(stroke
			(width 0)
			(type solid)
		)
		(fill yes)
		(layer "In2.Cu")
		(net "M_I_CPU0_SA_DQS_DN<2>")
	)
	(gr_poly
		(pts
			(xy 387.074918 -235.776008) (xy 386.974842 -235.675932) (xy 386.874766 -235.776008) (xy 386.874766 -235.820458)
			(xy 387.074918 -235.820458)
		)
		(stroke
			(width 0)
			(type solid)
		)
		(fill yes)
		(layer "In2.Cu")
		(net "M_I_CPU0_SA_DQ<17>")
	)
	(gr_poly
		(pts
			(xy 387.074918 -235.372148) (xy 387.074918 -235.327698) (xy 386.874766 -235.327698) (xy 386.874766 -235.372148)
			(xy 386.974842 -235.472224)
		)
		(stroke
			(width 0)
			(type solid)
		)
		(fill yes)
		(layer "In2.Cu")
		(net "M_I_CPU0_SA_DQ<18>")
	)
	(gr_poly
		(pts
			(xy 387.074918 -234.155996) (xy 386.974842 -234.05592) (xy 386.874766 -234.155996) (xy 386.874766 -234.200446)
			(xy 387.074918 -234.200446)
		)
		(stroke
			(width 0)
			(type solid)
		)
		(fill yes)
		(layer "In2.Cu")
		(net "M_I_CPU0_SA_DQ<13>")
	)
	(gr_poly
		(pts
			(xy 387.074918 -233.752136) (xy 387.074918 -233.707686) (xy 386.874766 -233.707686) (xy 386.874766 -233.752136)
			(xy 386.974842 -233.852212)
		)
		(stroke
			(width 0)
			(type solid)
		)
		(fill yes)
		(layer "In2.Cu")
		(net "M_I_CPU0_SA_DQ<14>")
	)
	(gr_poly
		(pts
			(xy 387.074918 -232.53573) (xy 386.974842 -232.435908) (xy 386.874766 -232.53573) (xy 386.874766 -232.583482)
			(xy 387.074918 -232.583482)
		)
		(stroke
			(width 0)
			(type solid)
		)
		(fill yes)
		(layer "In2.Cu")
		(net "M_I_CPU0_SA_DQS_DN<6>")
	)
	(gr_poly
		(pts
			(xy 387.074918 -232.132378) (xy 387.074918 -232.084626) (xy 386.874766 -232.084626) (xy 386.874766 -232.132378)
			(xy 386.974842 -232.2322)
		)
		(stroke
			(width 0)
			(type solid)
		)
		(fill yes)
		(layer "In2.Cu")
		(net "M_I_CPU0_SA_DQS_DN<1>")
	)
	(gr_poly
		(pts
			(xy 387.074918 -230.915972) (xy 386.974842 -230.815896) (xy 386.874766 -230.915972) (xy 386.874766 -230.960422)
			(xy 387.074918 -230.960422)
		)
		(stroke
			(width 0)
			(type solid)
		)
		(fill yes)
		(layer "In2.Cu")
		(net "M_I_CPU0_SA_DQ<9>")
	)
	(gr_poly
		(pts
			(xy 387.074918 -230.512366) (xy 387.074918 -230.467916) (xy 386.874766 -230.467916) (xy 386.874766 -230.512366)
			(xy 386.974842 -230.612188)
		)
		(stroke
			(width 0)
			(type solid)
		)
		(fill yes)
		(layer "In2.Cu")
		(net "M_I_CPU0_SA_DQ<10>")
	)
	(gr_poly
		(pts
			(xy 387.074918 -229.29596) (xy 386.974842 -229.195884) (xy 386.874766 -229.29596) (xy 386.874766 -229.34041)
			(xy 387.074918 -229.34041)
		)
		(stroke
			(width 0)
			(type solid)
		)
		(fill yes)
		(layer "In2.Cu")
		(net "M_I_CPU0_SA_DQ<5>")
	)
	(gr_poly
		(pts
			(xy 387.074918 -228.892354) (xy 387.074918 -228.847904) (xy 386.874766 -228.847904) (xy 386.874766 -228.892354)
			(xy 386.974842 -228.99243)
		)
		(stroke
			(width 0)
			(type solid)
		)
		(fill yes)
		(layer "In2.Cu")
		(net "M_I_CPU0_SA_DQ<6>")
	)
	(gr_poly
		(pts
			(xy 387.074918 -227.675948) (xy 386.974842 -227.576126) (xy 386.874766 -227.675948) (xy 386.874766 -227.7237)
			(xy 387.074918 -227.7237)
		)
		(stroke
			(width 0)
			(type solid)
		)
		(fill yes)
		(layer "In2.Cu")
		(net "M_I_CPU0_SA_DQS_DN<5>")
	)
	(gr_poly
		(pts
			(xy 387.074918 -227.272596) (xy 387.074918 -227.224844) (xy 386.874766 -227.224844) (xy 386.874766 -227.272596)
			(xy 386.974842 -227.372418)
		)
		(stroke
			(width 0)
			(type solid)
		)
		(fill yes)
		(layer "In2.Cu")
		(net "M_I_CPU0_SA_DQS_DN<0>")
	)
	(gr_poly
		(pts
			(xy 387.074918 -226.05619) (xy 386.974842 -225.956114) (xy 386.874766 -226.05619) (xy 386.874766 -226.10064)
			(xy 387.074918 -226.10064)
		)
		(stroke
			(width 0)
			(type solid)
		)
		(fill yes)
		(layer "In2.Cu")
		(net "M_I_CPU0_SA_DQ<1>")
	)
	(gr_poly
		(pts
			(xy 387.074918 -225.65233) (xy 387.074918 -225.60788) (xy 386.874766 -225.60788) (xy 386.874766 -225.65233)
			(xy 386.974842 -225.752406)
		)
		(stroke
			(width 0)
			(type solid)
		)
		(fill yes)
		(layer "In2.Cu")
		(net "M_I_CPU0_SA_DQ<2>")
	)
	(gr_poly
		(pts
			(xy 387.374892 -293.324026) (xy 387.374892 -293.279576) (xy 387.17474 -293.279576) (xy 387.17474 -293.324026)
			(xy 387.274816 -293.424102)
		)
		(stroke
			(width 0)
			(type solid)
		)
		(fill yes)
		(layer "In2.Cu")
		(net "M_I_CPU0_SB_DQ<31>")
	)
	(gr_poly
		(pts
			(xy 387.374892 -292.107874) (xy 387.274816 -292.007798) (xy 387.17474 -292.107874) (xy 387.17474 -292.152324)
			(xy 387.374892 -292.152324)
		)
		(stroke
			(width 0)
			(type solid)
		)
		(fill yes)
		(layer "In2.Cu")
		(net "M_I_CPU0_SB_DQ<28>")
	)
	(gr_poly
		(pts
			(xy 387.374892 -291.704268) (xy 387.374892 -291.656516) (xy 387.17474 -291.656516) (xy 387.17474 -291.704268)
			(xy 387.274816 -291.80409)
		)
		(stroke
			(width 0)
			(type solid)
		)
		(fill yes)
		(layer "In2.Cu")
		(net "M_I_CPU0_SB_DQS_DP<8>")
	)
	(gr_poly
		(pts
			(xy 387.374892 -290.487608) (xy 387.274816 -290.387786) (xy 387.17474 -290.487608) (xy 387.17474 -290.53536)
			(xy 387.374892 -290.53536)
		)
		(stroke
			(width 0)
			(type solid)
		)
		(fill yes)
		(layer "In2.Cu")
		(net "M_I_CPU0_SB_DQS_DP<3>")
	)
	(gr_poly
		(pts
			(xy 387.374892 -290.084002) (xy 387.374892 -290.039552) (xy 387.17474 -290.039552) (xy 387.17474 -290.084002)
			(xy 387.274816 -290.184078)
		)
		(stroke
			(width 0)
			(type solid)
		)
		(fill yes)
		(layer "In2.Cu")
		(net "M_I_CPU0_SB_DQ<27>")
	)
	(gr_poly
		(pts
			(xy 387.374892 -288.86785) (xy 387.274816 -288.767774) (xy 387.17474 -288.86785) (xy 387.17474 -288.9123)
			(xy 387.374892 -288.9123)
		)
		(stroke
			(width 0)
			(type solid)
		)
		(fill yes)
		(layer "In2.Cu")
		(net "M_I_CPU0_SB_DQ<24>")
	)
	(gr_poly
		(pts
			(xy 387.374892 -288.464244) (xy 387.374892 -288.419794) (xy 387.17474 -288.419794) (xy 387.17474 -288.464244)
			(xy 387.274816 -288.56432)
		)
		(stroke
			(width 0)
			(type solid)
		)
		(fill yes)
		(layer "In2.Cu")
		(net "M_I_CPU0_SB_DQ<23>")
	)
	(gr_poly
		(pts
			(xy 387.374892 -287.247838) (xy 387.274816 -287.148016) (xy 387.17474 -287.247838) (xy 387.17474 -287.292288)
			(xy 387.374892 -287.292288)
		)
		(stroke
			(width 0)
			(type solid)
		)
		(fill yes)
		(layer "In2.Cu")
		(net "M_I_CPU0_SB_DQ<20>")
	)
	(gr_poly
		(pts
			(xy 387.374892 -286.844232) (xy 387.374892 -286.79648) (xy 387.17474 -286.79648) (xy 387.17474 -286.844232)
			(xy 387.274816 -286.944308)
		)
		(stroke
			(width 0)
			(type solid)
		)
		(fill yes)
		(layer "In2.Cu")
		(net "M_I_CPU0_SB_DQS_DP<7>")
	)
	(gr_poly
		(pts
			(xy 387.374892 -285.627826) (xy 387.274816 -285.528004) (xy 387.17474 -285.627826) (xy 387.17474 -285.675578)
			(xy 387.374892 -285.675578)
		)
		(stroke
			(width 0)
			(type solid)
		)
		(fill yes)
		(layer "In2.Cu")
		(net "M_I_CPU0_SB_DQS_DP<2>")
	)
	(gr_poly
		(pts
			(xy 387.374892 -285.22422) (xy 387.374892 -285.17977) (xy 387.17474 -285.17977) (xy 387.17474 -285.22422)
			(xy 387.274816 -285.324296)
		)
		(stroke
			(width 0)
			(type solid)
		)
		(fill yes)
		(layer "In2.Cu")
		(net "M_I_CPU0_SB_DQ<19>")
	)
	(gr_poly
		(pts
			(xy 387.374892 -284.008068) (xy 387.274816 -283.907992) (xy 387.17474 -284.008068) (xy 387.17474 -284.052518)
			(xy 387.374892 -284.052518)
		)
		(stroke
			(width 0)
			(type solid)
		)
		(fill yes)
		(layer "In2.Cu")
		(net "M_I_CPU0_SB_DQ<16>")
	)
	(gr_poly
		(pts
			(xy 387.374892 -283.604208) (xy 387.374892 -283.559758) (xy 387.17474 -283.559758) (xy 387.17474 -283.604208)
			(xy 387.274816 -283.704284)
		)
		(stroke
			(width 0)
			(type solid)
		)
		(fill yes)
		(layer "In2.Cu")
		(net "M_I_CPU0_SB_DQ<15>")
	)
	(gr_poly
		(pts
			(xy 387.374892 -282.388056) (xy 387.274816 -282.28798) (xy 387.17474 -282.388056) (xy 387.17474 -282.432506)
			(xy 387.374892 -282.432506)
		)
		(stroke
			(width 0)
			(type solid)
		)
		(fill yes)
		(layer "In2.Cu")
		(net "M_I_CPU0_SB_DQ<12>")
	)
	(gr_poly
		(pts
			(xy 387.374892 -281.98445) (xy 387.374892 -281.936698) (xy 387.17474 -281.936698) (xy 387.17474 -281.98445)
			(xy 387.274816 -282.084272)
		)
		(stroke
			(width 0)
			(type solid)
		)
		(fill yes)
		(layer "In2.Cu")
		(net "M_I_CPU0_SB_DQS_DP<6>")
	)
	(gr_poly
		(pts
			(xy 387.374892 -280.76779) (xy 387.274816 -280.667968) (xy 387.17474 -280.76779) (xy 387.17474 -280.815542)
			(xy 387.374892 -280.815542)
		)
		(stroke
			(width 0)
			(type solid)
		)
		(fill yes)
		(layer "In2.Cu")
		(net "M_I_CPU0_SB_DQS_DP<1>")
	)
	(gr_poly
		(pts
			(xy 387.374892 -280.364184) (xy 387.374892 -280.319734) (xy 387.17474 -280.319734) (xy 387.17474 -280.364184)
			(xy 387.274816 -280.46426)
		)
		(stroke
			(width 0)
			(type solid)
		)
		(fill yes)
		(layer "In2.Cu")
		(net "M_I_CPU0_SB_DQ<11>")
	)
	(gr_poly
		(pts
			(xy 387.374892 -279.148032) (xy 387.274816 -279.047956) (xy 387.17474 -279.148032) (xy 387.17474 -279.192482)
			(xy 387.374892 -279.192482)
		)
		(stroke
			(width 0)
			(type solid)
		)
		(fill yes)
		(layer "In2.Cu")
		(net "M_I_CPU0_SB_DQ<8>")
	)
	(gr_poly
		(pts
			(xy 387.374892 -278.744172) (xy 387.374892 -278.699722) (xy 387.17474 -278.699722) (xy 387.17474 -278.744172)
			(xy 387.274816 -278.844248)
		)
		(stroke
			(width 0)
			(type solid)
		)
		(fill yes)
		(layer "In2.Cu")
		(net "M_I_CPU0_SB_DQ<7>")
	)
	(gr_poly
		(pts
			(xy 387.374892 -277.52802) (xy 387.274816 -277.427944) (xy 387.17474 -277.52802) (xy 387.17474 -277.57247)
			(xy 387.374892 -277.57247)
		)
		(stroke
			(width 0)
			(type solid)
		)
		(fill yes)
		(layer "In2.Cu")
		(net "M_I_CPU0_SB_DQ<4>")
	)
	(gr_poly
		(pts
			(xy 387.374892 -277.124414) (xy 387.374892 -277.076662) (xy 387.17474 -277.076662) (xy 387.17474 -277.124414)
			(xy 387.274816 -277.224236)
		)
		(stroke
			(width 0)
			(type solid)
		)
		(fill yes)
		(layer "In2.Cu")
		(net "M_I_CPU0_SB_DQS_DP<5>")
	)
	(gr_poly
		(pts
			(xy 387.374892 -275.907754) (xy 387.274816 -275.807932) (xy 387.17474 -275.907754) (xy 387.17474 -275.955506)
			(xy 387.374892 -275.955506)
		)
		(stroke
			(width 0)
			(type solid)
		)
		(fill yes)
		(layer "In2.Cu")
		(net "M_I_CPU0_SB_DQS_DP<0>")
	)
	(gr_poly
		(pts
			(xy 387.374892 -275.504148) (xy 387.374892 -275.459698) (xy 387.17474 -275.459698) (xy 387.17474 -275.504148)
			(xy 387.274816 -275.604224)
		)
		(stroke
			(width 0)
			(type solid)
		)
		(fill yes)
		(layer "In2.Cu")
		(net "M_I_CPU0_SB_DQ<3>")
	)
	(gr_poly
		(pts
			(xy 387.374892 -274.287996) (xy 387.274816 -274.18792) (xy 387.17474 -274.287996) (xy 387.17474 -274.332446)
			(xy 387.374892 -274.332446)
		)
		(stroke
			(width 0)
			(type solid)
		)
		(fill yes)
		(layer "In2.Cu")
		(net "M_I_CPU0_SB_DQ<0>")
	)
	(gr_poly
		(pts
			(xy 387.374892 -273.884136) (xy 387.374892 -273.839686) (xy 387.17474 -273.839686) (xy 387.17474 -273.884136)
			(xy 387.274816 -273.984212)
		)
		(stroke
			(width 0)
			(type solid)
		)
		(fill yes)
		(layer "In2.Cu")
		(net "M_I_CPU0_SB_CB<3>")
	)
	(gr_poly
		(pts
			(xy 387.374892 -272.667984) (xy 387.274816 -272.567908) (xy 387.17474 -272.667984) (xy 387.17474 -272.712434)
			(xy 387.374892 -272.712434)
		)
		(stroke
			(width 0)
			(type solid)
		)
		(fill yes)
		(layer "In2.Cu")
		(net "M_I_CPU0_SB_CB<0>")
	)
	(gr_poly
		(pts
			(xy 387.374892 -272.264378) (xy 387.374892 -272.216626) (xy 387.17474 -272.216626) (xy 387.17474 -272.264378)
			(xy 387.274816 -272.3642)
		)
		(stroke
			(width 0)
			(type solid)
		)
		(fill yes)
		(layer "In2.Cu")
		(net "M_I_CPU0_SB_DQS_DP<4>")
	)
	(gr_poly
		(pts
			(xy 387.374892 -271.047718) (xy 387.274816 -270.947896) (xy 387.17474 -271.047718) (xy 387.17474 -271.09547)
			(xy 387.374892 -271.09547)
		)
		(stroke
			(width 0)
			(type solid)
		)
		(fill yes)
		(layer "In2.Cu")
		(net "M_I_CPU0_SB_DQS_DP<9>")
	)
	(gr_poly
		(pts
			(xy 387.374892 -270.644112) (xy 387.374892 -270.599662) (xy 387.17474 -270.599662) (xy 387.17474 -270.644112)
			(xy 387.274816 -270.744188)
		)
		(stroke
			(width 0)
			(type solid)
		)
		(fill yes)
		(layer "In2.Cu")
		(net "M_I_CPU0_SB_CB<7>")
	)
	(gr_poly
		(pts
			(xy 387.374892 -269.42796) (xy 387.274816 -269.327884) (xy 387.17474 -269.42796) (xy 387.17474 -269.47241)
			(xy 387.374892 -269.47241)
		)
		(stroke
			(width 0)
			(type solid)
		)
		(fill yes)
		(layer "In2.Cu")
		(net "M_I_CPU0_SB_CB<4>")
	)
	(gr_poly
		(pts
			(xy 387.374892 -267.404088) (xy 387.374892 -267.359638) (xy 387.17474 -267.359638) (xy 387.17474 -267.404088)
			(xy 387.274816 -267.504164)
		)
		(stroke
			(width 0)
			(type solid)
		)
		(fill yes)
		(layer "In2.Cu")
		(net "M_I_CPU0_SB_RSP<0>")
	)
	(gr_poly
		(pts
			(xy 387.374892 -265.784076) (xy 387.374892 -265.739626) (xy 387.17474 -265.739626) (xy 387.17474 -265.784076)
			(xy 387.274816 -265.884152)
		)
		(stroke
			(width 0)
			(type solid)
		)
		(fill yes)
		(layer "In2.Cu")
		(net "M_I_CPU0_SB_CS_N<0>")
	)
	(gr_poly
		(pts
			(xy 387.374892 -264.567924) (xy 387.274816 -264.467848) (xy 387.17474 -264.567924) (xy 387.17474 -264.612374)
			(xy 387.374892 -264.612374)
		)
		(stroke
			(width 0)
			(type solid)
		)
		(fill yes)
		(layer "In2.Cu")
		(net "M_I_CPU0_SB_CA<6>")
	)
	(gr_poly
		(pts
			(xy 387.374892 -264.164064) (xy 387.374892 -264.119614) (xy 387.17474 -264.119614) (xy 387.17474 -264.164064)
			(xy 387.274816 -264.26414)
		)
		(stroke
			(width 0)
			(type solid)
		)
		(fill yes)
		(layer "In2.Cu")
		(net "M_I_CPU0_SB_CA<5>")
	)
	(gr_poly
		(pts
			(xy 387.374892 -262.947912) (xy 387.274816 -262.847836) (xy 387.17474 -262.947912) (xy 387.17474 -262.992362)
			(xy 387.374892 -262.992362)
		)
		(stroke
			(width 0)
			(type solid)
		)
		(fill yes)
		(layer "In2.Cu")
		(net "M_I_CPU0_SB_CA<2>")
	)
	(gr_poly
		(pts
			(xy 387.374892 -262.544052) (xy 387.374892 -262.499602) (xy 387.17474 -262.499602) (xy 387.17474 -262.544052)
			(xy 387.274816 -262.644128)
		)
		(stroke
			(width 0)
			(type solid)
		)
		(fill yes)
		(layer "In2.Cu")
		(net "M_I_CPU0_SB_CA<1>")
	)
	(gr_poly
		(pts
			(xy 387.464046 -224.695512) (xy 387.425438 -224.67316) (xy 387.288786 -224.709736) (xy 387.325616 -224.846388)
			(xy 387.36397 -224.86874)
		)
		(stroke
			(width 0)
			(type solid)
		)
		(fill yes)
		(layer "In2.Cu")
		(net "M_I_CPU0_SA_DQ<0>")
	)
	(gr_poly
		(pts
			(xy 387.544818 -256.025904) (xy 387.444742 -255.926082) (xy 387.344666 -256.025904) (xy 387.344666 -256.073656)
			(xy 387.544818 -256.073656)
		)
		(stroke
			(width 0)
			(type solid)
		)
		(fill yes)
		(layer "In2.Cu")
		(net "M_I_CPU0_CLK_DP<0>")
	)
	(gr_poly
		(pts
			(xy 387.544818 -255.622298) (xy 387.544818 -255.577848) (xy 387.344666 -255.577848) (xy 387.344666 -255.622298)
			(xy 387.444742 -255.722374)
		)
		(stroke
			(width 0)
			(type solid)
		)
		(fill yes)
		(layer "In2.Cu")
		(net "M_I_CPU0_SA_PAR")
	)
	(gr_poly
		(pts
			(xy 387.544818 -254.406146) (xy 387.444742 -254.30607) (xy 387.344666 -254.406146) (xy 387.344666 -254.450596)
			(xy 387.544818 -254.450596)
		)
		(stroke
			(width 0)
			(type solid)
		)
		(fill yes)
		(layer "In2.Cu")
		(net "M_I_CPU0_SA_CA<4>")
	)
	(gr_poly
		(pts
			(xy 387.544818 -254.002286) (xy 387.544818 -253.957836) (xy 387.344666 -253.957836) (xy 387.344666 -254.002286)
			(xy 387.444742 -254.102362)
		)
		(stroke
			(width 0)
			(type solid)
		)
		(fill yes)
		(layer "In2.Cu")
		(net "M_I_CPU0_SA_CA<3>")
	)
	(gr_poly
		(pts
			(xy 387.544818 -252.786134) (xy 387.444742 -252.686058) (xy 387.344666 -252.786134) (xy 387.344666 -252.830584)
			(xy 387.544818 -252.830584)
		)
		(stroke
			(width 0)
			(type solid)
		)
		(fill yes)
		(layer "In2.Cu")
		(net "M_I_CPU0_SA_CA<0>")
	)
	(gr_poly
		(pts
			(xy 387.544818 -251.166122) (xy 387.444742 -251.066046) (xy 387.344666 -251.166122) (xy 387.344666 -251.210572)
			(xy 387.544818 -251.210572)
		)
		(stroke
			(width 0)
			(type solid)
		)
		(fill yes)
		(layer "In2.Cu")
		(net "M_I_CPU0_SA_CS_N<0>")
	)
	(gr_poly
		(pts
			(xy 387.544818 -250.762262) (xy 387.544818 -250.717812) (xy 387.344666 -250.717812) (xy 387.344666 -250.762262)
			(xy 387.444742 -250.862338)
		)
		(stroke
			(width 0)
			(type solid)
		)
		(fill yes)
		(layer "In2.Cu")
		(net "M_I_CPU0_RESET_N")
	)
	(gr_poly
		(pts
			(xy 387.544818 -249.14225) (xy 387.544818 -249.0978) (xy 387.344666 -249.0978) (xy 387.344666 -249.14225)
			(xy 387.444742 -249.242326)
		)
		(stroke
			(width 0)
			(type solid)
		)
		(fill yes)
		(layer "In2.Cu")
		(net "M_I_CPU0_SA_CB<7>")
	)
	(gr_poly
		(pts
			(xy 387.544818 -247.926098) (xy 387.444742 -247.826022) (xy 387.344666 -247.926098) (xy 387.344666 -247.970548)
			(xy 387.544818 -247.970548)
		)
		(stroke
			(width 0)
			(type solid)
		)
		(fill yes)
		(layer "In2.Cu")
		(net "M_I_CPU0_SA_CB<4>")
	)
	(gr_poly
		(pts
			(xy 387.544818 -247.522492) (xy 387.544818 -247.47474) (xy 387.344666 -247.47474) (xy 387.344666 -247.522492)
			(xy 387.444742 -247.622314)
		)
		(stroke
			(width 0)
			(type solid)
		)
		(fill yes)
		(layer "In2.Cu")
		(net "M_I_CPU0_SA_DQS_DP<9>")
	)
	(gr_poly
		(pts
			(xy 387.544818 -246.305832) (xy 387.444742 -246.20601) (xy 387.344666 -246.305832) (xy 387.344666 -246.353584)
			(xy 387.544818 -246.353584)
		)
		(stroke
			(width 0)
			(type solid)
		)
		(fill yes)
		(layer "In2.Cu")
		(net "M_I_CPU0_SA_DQS_DP<4>")
	)
	(gr_poly
		(pts
			(xy 387.544818 -245.902226) (xy 387.544818 -245.857776) (xy 387.344666 -245.857776) (xy 387.344666 -245.902226)
			(xy 387.444742 -246.002302)
		)
		(stroke
			(width 0)
			(type solid)
		)
		(fill yes)
		(layer "In2.Cu")
		(net "M_I_CPU0_SA_CB<3>")
	)
	(gr_poly
		(pts
			(xy 387.544818 -244.686074) (xy 387.444742 -244.585998) (xy 387.344666 -244.686074) (xy 387.344666 -244.730524)
			(xy 387.544818 -244.730524)
		)
		(stroke
			(width 0)
			(type solid)
		)
		(fill yes)
		(layer "In2.Cu")
		(net "M_I_CPU0_SA_CB<0>")
	)
	(gr_poly
		(pts
			(xy 387.544818 -244.282214) (xy 387.544818 -244.237764) (xy 387.344666 -244.237764) (xy 387.344666 -244.282214)
			(xy 387.444742 -244.38229)
		)
		(stroke
			(width 0)
			(type solid)
		)
		(fill yes)
		(layer "In2.Cu")
		(net "M_I_CPU0_SA_DQ<31>")
	)
	(gr_poly
		(pts
			(xy 387.544818 -243.066062) (xy 387.444742 -242.965986) (xy 387.344666 -243.066062) (xy 387.344666 -243.110512)
			(xy 387.544818 -243.110512)
		)
		(stroke
			(width 0)
			(type solid)
		)
		(fill yes)
		(layer "In2.Cu")
		(net "M_I_CPU0_SA_DQ<28>")
	)
	(gr_poly
		(pts
			(xy 387.544818 -242.662456) (xy 387.544818 -242.614704) (xy 387.344666 -242.614704) (xy 387.344666 -242.662456)
			(xy 387.444742 -242.762278)
		)
		(stroke
			(width 0)
			(type solid)
		)
		(fill yes)
		(layer "In2.Cu")
		(net "M_I_CPU0_SA_DQS_DP<8>")
	)
	(gr_poly
		(pts
			(xy 387.544818 -241.445796) (xy 387.444742 -241.345974) (xy 387.344666 -241.445796) (xy 387.344666 -241.493548)
			(xy 387.544818 -241.493548)
		)
		(stroke
			(width 0)
			(type solid)
		)
		(fill yes)
		(layer "In2.Cu")
		(net "M_I_CPU0_SA_DQS_DP<3>")
	)
	(gr_poly
		(pts
			(xy 387.544818 -241.04219) (xy 387.544818 -240.99774) (xy 387.344666 -240.99774) (xy 387.344666 -241.04219)
			(xy 387.444742 -241.142266)
		)
		(stroke
			(width 0)
			(type solid)
		)
		(fill yes)
		(layer "In2.Cu")
		(net "M_I_CPU0_SA_DQ<27>")
	)
	(gr_poly
		(pts
			(xy 387.544818 -239.826038) (xy 387.444742 -239.725962) (xy 387.344666 -239.826038) (xy 387.344666 -239.870488)
			(xy 387.544818 -239.870488)
		)
		(stroke
			(width 0)
			(type solid)
		)
		(fill yes)
		(layer "In2.Cu")
		(net "M_I_CPU0_SA_DQ<24>")
	)
	(gr_poly
		(pts
			(xy 387.544818 -239.422178) (xy 387.544818 -239.377728) (xy 387.344666 -239.377728) (xy 387.344666 -239.422178)
			(xy 387.444742 -239.522254)
		)
		(stroke
			(width 0)
			(type solid)
		)
		(fill yes)
		(layer "In2.Cu")
		(net "M_I_CPU0_SA_DQ<23>")
	)
	(gr_poly
		(pts
			(xy 387.544818 -238.206026) (xy 387.444742 -238.10595) (xy 387.344666 -238.206026) (xy 387.344666 -238.250476)
			(xy 387.544818 -238.250476)
		)
		(stroke
			(width 0)
			(type solid)
		)
		(fill yes)
		(layer "In2.Cu")
		(net "M_I_CPU0_SA_DQ<20>")
	)
	(gr_poly
		(pts
			(xy 387.544818 -237.80242) (xy 387.544818 -237.754668) (xy 387.344666 -237.754668) (xy 387.344666 -237.80242)
			(xy 387.444742 -237.902242)
		)
		(stroke
			(width 0)
			(type solid)
		)
		(fill yes)
		(layer "In2.Cu")
		(net "M_I_CPU0_SA_DQS_DP<7>")
	)
	(gr_poly
		(pts
			(xy 387.544818 -236.58576) (xy 387.444742 -236.485938) (xy 387.344666 -236.58576) (xy 387.344666 -236.633512)
			(xy 387.544818 -236.633512)
		)
		(stroke
			(width 0)
			(type solid)
		)
		(fill yes)
		(layer "In2.Cu")
		(net "M_I_CPU0_SA_DQS_DP<2>")
	)
	(gr_poly
		(pts
			(xy 387.544818 -236.182154) (xy 387.544818 -236.137704) (xy 387.344666 -236.137704) (xy 387.344666 -236.182154)
			(xy 387.444742 -236.28223)
		)
		(stroke
			(width 0)
			(type solid)
		)
		(fill yes)
		(layer "In2.Cu")
		(net "M_I_CPU0_SA_DQ<19>")
	)
	(gr_poly
		(pts
			(xy 387.544818 -234.966002) (xy 387.444742 -234.865926) (xy 387.344666 -234.966002) (xy 387.344666 -235.010452)
			(xy 387.544818 -235.010452)
		)
		(stroke
			(width 0)
			(type solid)
		)
		(fill yes)
		(layer "In2.Cu")
		(net "M_I_CPU0_SA_DQ<16>")
	)
	(gr_poly
		(pts
			(xy 387.544818 -234.562142) (xy 387.544818 -234.517692) (xy 387.344666 -234.517692) (xy 387.344666 -234.562142)
			(xy 387.444742 -234.662218)
		)
		(stroke
			(width 0)
			(type solid)
		)
		(fill yes)
		(layer "In2.Cu")
		(net "M_I_CPU0_SA_DQ<15>")
	)
	(gr_poly
		(pts
			(xy 387.544818 -233.34599) (xy 387.444742 -233.245914) (xy 387.344666 -233.34599) (xy 387.344666 -233.39044)
			(xy 387.544818 -233.39044)
		)
		(stroke
			(width 0)
			(type solid)
		)
		(fill yes)
		(layer "In2.Cu")
		(net "M_I_CPU0_SA_DQ<12>")
	)
	(gr_poly
		(pts
			(xy 387.544818 -232.942384) (xy 387.544818 -232.894632) (xy 387.344666 -232.894632) (xy 387.344666 -232.942384)
			(xy 387.444742 -233.042206)
		)
		(stroke
			(width 0)
			(type solid)
		)
		(fill yes)
		(layer "In2.Cu")
		(net "M_I_CPU0_SA_DQS_DP<6>")
	)
	(gr_poly
		(pts
			(xy 387.544818 -231.725724) (xy 387.444742 -231.625902) (xy 387.344666 -231.725724) (xy 387.344666 -231.773476)
			(xy 387.544818 -231.773476)
		)
		(stroke
			(width 0)
			(type solid)
		)
		(fill yes)
		(layer "In2.Cu")
		(net "M_I_CPU0_SA_DQS_DP<1>")
	)
	(gr_poly
		(pts
			(xy 387.544818 -231.322372) (xy 387.544818 -231.277922) (xy 387.344666 -231.277922) (xy 387.344666 -231.322372)
			(xy 387.444742 -231.422448)
		)
		(stroke
			(width 0)
			(type solid)
		)
		(fill yes)
		(layer "In2.Cu")
		(net "M_I_CPU0_SA_DQ<11>")
	)
	(gr_poly
		(pts
			(xy 387.544818 -230.105966) (xy 387.444742 -230.006144) (xy 387.344666 -230.105966) (xy 387.344666 -230.150416)
			(xy 387.544818 -230.150416)
		)
		(stroke
			(width 0)
			(type solid)
		)
		(fill yes)
		(layer "In2.Cu")
		(net "M_I_CPU0_SA_DQ<8>")
	)
	(gr_poly
		(pts
			(xy 387.544818 -229.70236) (xy 387.544818 -229.65791) (xy 387.344666 -229.65791) (xy 387.344666 -229.70236)
			(xy 387.444742 -229.802436)
		)
		(stroke
			(width 0)
			(type solid)
		)
		(fill yes)
		(layer "In2.Cu")
		(net "M_I_CPU0_SA_DQ<7>")
	)
	(gr_poly
		(pts
			(xy 387.544818 -228.486208) (xy 387.444742 -228.386132) (xy 387.344666 -228.486208) (xy 387.344666 -228.530658)
			(xy 387.544818 -228.530658)
		)
		(stroke
			(width 0)
			(type solid)
		)
		(fill yes)
		(layer "In2.Cu")
		(net "M_I_CPU0_SA_DQ<4>")
	)
	(gr_poly
		(pts
			(xy 387.544818 -228.082602) (xy 387.544818 -228.03485) (xy 387.344666 -228.03485) (xy 387.344666 -228.082602)
			(xy 387.444742 -228.182424)
		)
		(stroke
			(width 0)
			(type solid)
		)
		(fill yes)
		(layer "In2.Cu")
		(net "M_I_CPU0_SA_DQS_DP<5>")
	)
	(gr_poly
		(pts
			(xy 387.544818 -226.865942) (xy 387.444742 -226.76612) (xy 387.344666 -226.865942) (xy 387.344666 -226.913694)
			(xy 387.544818 -226.913694)
		)
		(stroke
			(width 0)
			(type solid)
		)
		(fill yes)
		(layer "In2.Cu")
		(net "M_I_CPU0_SA_DQS_DP<0>")
	)
	(gr_poly
		(pts
			(xy 387.544818 -226.462336) (xy 387.544818 -226.417886) (xy 387.344666 -226.417886) (xy 387.344666 -226.462336)
			(xy 387.444742 -226.562412)
		)
		(stroke
			(width 0)
			(type solid)
		)
		(fill yes)
		(layer "In2.Cu")
		(net "M_I_CPU0_SA_DQ<3>")
	)
	(gr_poly
		(pts
			(xy 387.600698 -225.378772) (xy 387.564122 -225.24212) (xy 387.525768 -225.219768) (xy 387.425692 -225.392996)
			(xy 387.4643 -225.415348)
		)
		(stroke
			(width 0)
			(type solid)
		)
		(fill yes)
		(layer "In2.Cu")
		(net "M_I_CPU0_SA_DQ<2>")
	)
	(gr_poly
		(pts
			(xy 387.844792 -292.91788) (xy 387.744716 -292.817804) (xy 387.64464 -292.91788) (xy 387.64464 -292.96233)
			(xy 387.844792 -292.96233)
		)
		(stroke
			(width 0)
			(type solid)
		)
		(fill yes)
		(layer "In2.Cu")
		(net "M_I_CPU0_SB_DQ<29>")
	)
	(gr_poly
		(pts
			(xy 387.844792 -292.51402) (xy 387.844792 -292.46957) (xy 387.64464 -292.46957) (xy 387.64464 -292.51402)
			(xy 387.744716 -292.614096)
		)
		(stroke
			(width 0)
			(type solid)
		)
		(fill yes)
		(layer "In2.Cu")
		(net "M_I_CPU0_SB_DQ<30>")
	)
	(gr_poly
		(pts
			(xy 387.844792 -291.297614) (xy 387.744716 -291.197792) (xy 387.64464 -291.297614) (xy 387.64464 -291.345366)
			(xy 387.844792 -291.345366)
		)
		(stroke
			(width 0)
			(type solid)
		)
		(fill yes)
		(layer "In2.Cu")
		(net "M_I_CPU0_SB_DQS_DN<8>")
	)
	(gr_poly
		(pts
			(xy 387.844792 -290.894262) (xy 387.844792 -290.84651) (xy 387.64464 -290.84651) (xy 387.64464 -290.894262)
			(xy 387.744716 -290.994084)
		)
		(stroke
			(width 0)
			(type solid)
		)
		(fill yes)
		(layer "In2.Cu")
		(net "M_I_CPU0_SB_DQS_DN<3>")
	)
	(gr_poly
		(pts
			(xy 387.844792 -289.677856) (xy 387.744716 -289.57778) (xy 387.64464 -289.677856) (xy 387.64464 -289.722306)
			(xy 387.844792 -289.722306)
		)
		(stroke
			(width 0)
			(type solid)
		)
		(fill yes)
		(layer "In2.Cu")
		(net "M_I_CPU0_SB_DQ<25>")
	)
	(gr_poly
		(pts
			(xy 387.844792 -289.273996) (xy 387.844792 -289.229546) (xy 387.64464 -289.229546) (xy 387.64464 -289.273996)
			(xy 387.744716 -289.374072)
		)
		(stroke
			(width 0)
			(type solid)
		)
		(fill yes)
		(layer "In2.Cu")
		(net "M_I_CPU0_SB_DQ<26>")
	)
	(gr_poly
		(pts
			(xy 387.844792 -288.057844) (xy 387.744716 -287.957768) (xy 387.64464 -288.057844) (xy 387.64464 -288.102294)
			(xy 387.844792 -288.102294)
		)
		(stroke
			(width 0)
			(type solid)
		)
		(fill yes)
		(layer "In2.Cu")
		(net "M_I_CPU0_SB_DQ<21>")
	)
	(gr_poly
		(pts
			(xy 387.844792 -287.654238) (xy 387.844792 -287.609788) (xy 387.64464 -287.609788) (xy 387.64464 -287.654238)
			(xy 387.744716 -287.75406)
		)
		(stroke
			(width 0)
			(type solid)
		)
		(fill yes)
		(layer "In2.Cu")
		(net "M_I_CPU0_SB_DQ<22>")
	)
	(gr_poly
		(pts
			(xy 387.844792 -286.437832) (xy 387.744716 -286.337756) (xy 387.64464 -286.437832) (xy 387.64464 -286.485584)
			(xy 387.844792 -286.485584)
		)
		(stroke
			(width 0)
			(type solid)
		)
		(fill yes)
		(layer "In2.Cu")
		(net "M_I_CPU0_SB_DQS_DN<7>")
	)
	(gr_poly
		(pts
			(xy 387.844792 -286.03448) (xy 387.844792 -285.986728) (xy 387.64464 -285.986728) (xy 387.64464 -286.03448)
			(xy 387.744716 -286.134302)
		)
		(stroke
			(width 0)
			(type solid)
		)
		(fill yes)
		(layer "In2.Cu")
		(net "M_I_CPU0_SB_DQS_DN<2>")
	)
	(gr_poly
		(pts
			(xy 387.844792 -284.818074) (xy 387.744716 -284.717998) (xy 387.64464 -284.818074) (xy 387.64464 -284.862524)
			(xy 387.844792 -284.862524)
		)
		(stroke
			(width 0)
			(type solid)
		)
		(fill yes)
		(layer "In2.Cu")
		(net "M_I_CPU0_SB_DQ<17>")
	)
	(gr_poly
		(pts
			(xy 387.844792 -284.414214) (xy 387.844792 -284.369764) (xy 387.64464 -284.369764) (xy 387.64464 -284.414214)
			(xy 387.744716 -284.51429)
		)
		(stroke
			(width 0)
			(type solid)
		)
		(fill yes)
		(layer "In2.Cu")
		(net "M_I_CPU0_SB_DQ<18>")
	)
	(gr_poly
		(pts
			(xy 387.844792 -283.198062) (xy 387.744716 -283.097986) (xy 387.64464 -283.198062) (xy 387.64464 -283.242512)
			(xy 387.844792 -283.242512)
		)
		(stroke
			(width 0)
			(type solid)
		)
		(fill yes)
		(layer "In2.Cu")
		(net "M_I_CPU0_SB_DQ<13>")
	)
	(gr_poly
		(pts
			(xy 387.844792 -282.794202) (xy 387.844792 -282.749752) (xy 387.64464 -282.749752) (xy 387.64464 -282.794202)
			(xy 387.744716 -282.894278)
		)
		(stroke
			(width 0)
			(type solid)
		)
		(fill yes)
		(layer "In2.Cu")
		(net "M_I_CPU0_SB_DQ<14>")
	)
	(gr_poly
		(pts
			(xy 387.844792 -281.577796) (xy 387.744716 -281.477974) (xy 387.64464 -281.577796) (xy 387.64464 -281.625548)
			(xy 387.844792 -281.625548)
		)
		(stroke
			(width 0)
			(type solid)
		)
		(fill yes)
		(layer "In2.Cu")
		(net "M_I_CPU0_SB_DQS_DN<6>")
	)
	(gr_poly
		(pts
			(xy 387.844792 -281.174444) (xy 387.844792 -281.126692) (xy 387.64464 -281.126692) (xy 387.64464 -281.174444)
			(xy 387.744716 -281.274266)
		)
		(stroke
			(width 0)
			(type solid)
		)
		(fill yes)
		(layer "In2.Cu")
		(net "M_I_CPU0_SB_DQS_DN<1>")
	)
	(gr_poly
		(pts
			(xy 387.844792 -279.958038) (xy 387.744716 -279.857962) (xy 387.64464 -279.958038) (xy 387.64464 -280.002488)
			(xy 387.844792 -280.002488)
		)
		(stroke
			(width 0)
			(type solid)
		)
		(fill yes)
		(layer "In2.Cu")
		(net "M_I_CPU0_SB_DQ<9>")
	)
	(gr_poly
		(pts
			(xy 387.844792 -279.554178) (xy 387.844792 -279.509728) (xy 387.64464 -279.509728) (xy 387.64464 -279.554178)
			(xy 387.744716 -279.654254)
		)
		(stroke
			(width 0)
			(type solid)
		)
		(fill yes)
		(layer "In2.Cu")
		(net "M_I_CPU0_SB_DQ<10>")
	)
	(gr_poly
		(pts
			(xy 387.844792 -278.338026) (xy 387.744716 -278.23795) (xy 387.64464 -278.338026) (xy 387.64464 -278.382476)
			(xy 387.844792 -278.382476)
		)
		(stroke
			(width 0)
			(type solid)
		)
		(fill yes)
		(layer "In2.Cu")
		(net "M_I_CPU0_SB_DQ<5>")
	)
	(gr_poly
		(pts
			(xy 387.844792 -277.934166) (xy 387.844792 -277.889716) (xy 387.64464 -277.889716) (xy 387.64464 -277.934166)
			(xy 387.744716 -278.034242)
		)
		(stroke
			(width 0)
			(type solid)
		)
		(fill yes)
		(layer "In2.Cu")
		(net "M_I_CPU0_SB_DQ<6>")
	)
	(gr_poly
		(pts
			(xy 387.844792 -276.71776) (xy 387.744716 -276.617938) (xy 387.64464 -276.71776) (xy 387.64464 -276.765512)
			(xy 387.844792 -276.765512)
		)
		(stroke
			(width 0)
			(type solid)
		)
		(fill yes)
		(layer "In2.Cu")
		(net "M_I_CPU0_SB_DQS_DN<5>")
	)
	(gr_poly
		(pts
			(xy 387.844792 -276.314408) (xy 387.844792 -276.266656) (xy 387.64464 -276.266656) (xy 387.64464 -276.314408)
			(xy 387.744716 -276.41423)
		)
		(stroke
			(width 0)
			(type solid)
		)
		(fill yes)
		(layer "In2.Cu")
		(net "M_I_CPU0_SB_DQS_DN<0>")
	)
	(gr_poly
		(pts
			(xy 387.844792 -275.098002) (xy 387.744716 -274.997926) (xy 387.64464 -275.098002) (xy 387.64464 -275.142452)
			(xy 387.844792 -275.142452)
		)
		(stroke
			(width 0)
			(type solid)
		)
		(fill yes)
		(layer "In2.Cu")
		(net "M_I_CPU0_SB_DQ<1>")
	)
	(gr_poly
		(pts
			(xy 387.844792 -274.694142) (xy 387.844792 -274.649692) (xy 387.64464 -274.649692) (xy 387.64464 -274.694142)
			(xy 387.744716 -274.794218)
		)
		(stroke
			(width 0)
			(type solid)
		)
		(fill yes)
		(layer "In2.Cu")
		(net "M_I_CPU0_SB_DQ<2>")
	)
	(gr_poly
		(pts
			(xy 387.844792 -273.47799) (xy 387.744716 -273.377914) (xy 387.64464 -273.47799) (xy 387.64464 -273.52244)
			(xy 387.844792 -273.52244)
		)
		(stroke
			(width 0)
			(type solid)
		)
		(fill yes)
		(layer "In2.Cu")
		(net "M_I_CPU0_SB_CB<1>")
	)
	(gr_poly
		(pts
			(xy 387.844792 -273.07413) (xy 387.844792 -273.02968) (xy 387.64464 -273.02968) (xy 387.64464 -273.07413)
			(xy 387.744716 -273.174206)
		)
		(stroke
			(width 0)
			(type solid)
		)
		(fill yes)
		(layer "In2.Cu")
		(net "M_I_CPU0_SB_CB<2>")
	)
	(gr_poly
		(pts
			(xy 387.844792 -271.857724) (xy 387.744716 -271.757902) (xy 387.64464 -271.857724) (xy 387.64464 -271.905476)
			(xy 387.844792 -271.905476)
		)
		(stroke
			(width 0)
			(type solid)
		)
		(fill yes)
		(layer "In2.Cu")
		(net "M_I_CPU0_SB_DQS_DN<4>")
	)
	(gr_poly
		(pts
			(xy 387.844792 -271.454372) (xy 387.844792 -271.40662) (xy 387.64464 -271.40662) (xy 387.64464 -271.454372)
			(xy 387.744716 -271.554194)
		)
		(stroke
			(width 0)
			(type solid)
		)
		(fill yes)
		(layer "In2.Cu")
		(net "M_I_CPU0_SB_DQS_DN<9>")
	)
	(gr_poly
		(pts
			(xy 387.844792 -270.237966) (xy 387.744716 -270.13789) (xy 387.64464 -270.237966) (xy 387.64464 -270.282416)
			(xy 387.844792 -270.282416)
		)
		(stroke
			(width 0)
			(type solid)
		)
		(fill yes)
		(layer "In2.Cu")
		(net "M_I_CPU0_SB_CB<5>")
	)
	(gr_poly
		(pts
			(xy 387.844792 -269.834106) (xy 387.844792 -269.789656) (xy 387.64464 -269.789656) (xy 387.64464 -269.834106)
			(xy 387.744716 -269.934182)
		)
		(stroke
			(width 0)
			(type solid)
		)
		(fill yes)
		(layer "In2.Cu")
		(net "M_I_CPU0_SB_CB<6>")
	)
	(gr_poly
		(pts
			(xy 387.844792 -266.997942) (xy 387.744716 -266.897866) (xy 387.64464 -266.997942) (xy 387.64464 -267.042392)
			(xy 387.844792 -267.042392)
		)
		(stroke
			(width 0)
			(type solid)
		)
		(fill yes)
		(layer "In2.Cu")
		(net "M_I_CPU0_SA_RSP<0>")
	)
	(gr_poly
		(pts
			(xy 387.844792 -266.594082) (xy 387.844792 -266.549632) (xy 387.64464 -266.549632) (xy 387.64464 -266.594082)
			(xy 387.744716 -266.694158)
		)
		(stroke
			(width 0)
			(type solid)
		)
		(fill yes)
		(layer "In2.Cu")
		(net "M_I_CPU0_SB_CS_N<1>")
	)
	(gr_poly
		(pts
			(xy 387.844792 -265.37793) (xy 387.744716 -265.277854) (xy 387.64464 -265.37793) (xy 387.64464 -265.42238)
			(xy 387.844792 -265.42238)
		)
		(stroke
			(width 0)
			(type solid)
		)
		(fill yes)
		(layer "In2.Cu")
		(net "M_I_CPU0_SB_PAR")
	)
	(gr_poly
		(pts
			(xy 387.844792 -263.757918) (xy 387.744716 -263.657842) (xy 387.64464 -263.757918) (xy 387.64464 -263.802368)
			(xy 387.844792 -263.802368)
		)
		(stroke
			(width 0)
			(type solid)
		)
		(fill yes)
		(layer "In2.Cu")
		(net "M_I_CPU0_SB_CA<4>")
	)
	(gr_poly
		(pts
			(xy 387.844792 -263.354058) (xy 387.844792 -263.309608) (xy 387.64464 -263.309608) (xy 387.64464 -263.354058)
			(xy 387.744716 -263.454134)
		)
		(stroke
			(width 0)
			(type solid)
		)
		(fill yes)
		(layer "In2.Cu")
		(net "M_I_CPU0_SB_CA<3>")
	)
	(gr_poly
		(pts
			(xy 387.844792 -262.137906) (xy 387.744716 -262.03783) (xy 387.64464 -262.137906) (xy 387.64464 -262.182356)
			(xy 387.844792 -262.182356)
		)
		(stroke
			(width 0)
			(type solid)
		)
		(fill yes)
		(layer "In2.Cu")
		(net "M_I_CPU0_SB_CA<0>")
	)
	(gr_poly
		(pts
			(xy 387.933946 -225.505518) (xy 387.895338 -225.483166) (xy 387.758686 -225.519742) (xy 387.795516 -225.656394)
			(xy 387.83387 -225.678746)
		)
		(stroke
			(width 0)
			(type solid)
		)
		(fill yes)
		(layer "In2.Cu")
		(net "M_I_CPU0_SA_DQ<1>")
	)
	(gr_poly
		(pts
			(xy 387.9342 -223.884744) (xy 387.895846 -223.862392) (xy 387.759194 -223.898968) (xy 387.79577 -224.03562)
			(xy 387.834378 -224.057972)
		)
		(stroke
			(width 0)
			(type solid)
		)
		(fill yes)
		(layer "In2.Cu")
		(net "M_I_CPU0_SA_DQ<0>")
	)
	(gr_poly
		(pts
			(xy 388.014972 -256.432558) (xy 388.014972 -256.384806) (xy 387.81482 -256.384806) (xy 387.81482 -256.432558)
			(xy 387.914896 -256.53238)
		)
		(stroke
			(width 0)
			(type solid)
		)
		(fill yes)
		(layer "In2.Cu")
		(net "M_I_CPU0_CLK_DN<0>")
	)
	(gr_poly
		(pts
			(xy 388.014972 -255.216152) (xy 387.914896 -255.116076) (xy 387.81482 -255.216152) (xy 387.81482 -255.260602)
			(xy 388.014972 -255.260602)
		)
		(stroke
			(width 0)
			(type solid)
		)
		(fill yes)
		(layer "In2.Cu")
		(net "M_I_CPU0_SA_CA<6>")
	)
	(gr_poly
		(pts
			(xy 388.014972 -254.812292) (xy 388.014972 -254.767842) (xy 387.81482 -254.767842) (xy 387.81482 -254.812292)
			(xy 387.914896 -254.912368)
		)
		(stroke
			(width 0)
			(type solid)
		)
		(fill yes)
		(layer "In2.Cu")
		(net "M_I_CPU0_SA_CA<5>")
	)
	(gr_poly
		(pts
			(xy 388.014972 -253.59614) (xy 387.914896 -253.496064) (xy 387.81482 -253.59614) (xy 387.81482 -253.64059)
			(xy 388.014972 -253.64059)
		)
		(stroke
			(width 0)
			(type solid)
		)
		(fill yes)
		(layer "In2.Cu")
		(net "M_I_CPU0_SA_CA<2>")
	)
	(gr_poly
		(pts
			(xy 388.014972 -253.19228) (xy 388.014972 -253.14783) (xy 387.81482 -253.14783) (xy 387.81482 -253.19228)
			(xy 387.914896 -253.292356)
		)
		(stroke
			(width 0)
			(type solid)
		)
		(fill yes)
		(layer "In2.Cu")
		(net "M_I_CPU0_SA_CA<1>")
	)
	(gr_poly
		(pts
			(xy 388.014972 -251.976128) (xy 387.914896 -251.876052) (xy 387.81482 -251.976128) (xy 387.81482 -252.020578)
			(xy 388.014972 -252.020578)
		)
		(stroke
			(width 0)
			(type solid)
		)
		(fill yes)
		(layer "In2.Cu")
		(net "M_I_CPU0_SA_CS_N<1>")
	)
	(gr_poly
		(pts
			(xy 388.014972 -250.356116) (xy 387.914896 -250.25604) (xy 387.81482 -250.356116) (xy 387.81482 -250.400566)
			(xy 388.014972 -250.400566)
		)
		(stroke
			(width 0)
			(type solid)
		)
		(fill yes)
		(layer "In2.Cu")
		(net "M_I_CPU0_ALERT_R_N")
	)
	(gr_poly
		(pts
			(xy 388.014972 -248.736104) (xy 387.914896 -248.636028) (xy 387.81482 -248.736104) (xy 387.81482 -248.780554)
			(xy 388.014972 -248.780554)
		)
		(stroke
			(width 0)
			(type solid)
		)
		(fill yes)
		(layer "In2.Cu")
		(net "M_I_CPU0_SA_CB<5>")
	)
	(gr_poly
		(pts
			(xy 388.014972 -248.332244) (xy 388.014972 -248.287794) (xy 387.81482 -248.287794) (xy 387.81482 -248.332244)
			(xy 387.914896 -248.43232)
		)
		(stroke
			(width 0)
			(type solid)
		)
		(fill yes)
		(layer "In2.Cu")
		(net "M_I_CPU0_SA_CB<6>")
	)
	(gr_poly
		(pts
			(xy 388.014972 -247.115838) (xy 387.914896 -247.016016) (xy 387.81482 -247.115838) (xy 387.81482 -247.16359)
			(xy 388.014972 -247.16359)
		)
		(stroke
			(width 0)
			(type solid)
		)
		(fill yes)
		(layer "In2.Cu")
		(net "M_I_CPU0_SA_DQS_DN<9>")
	)
	(gr_poly
		(pts
			(xy 388.014972 -246.712486) (xy 388.014972 -246.664734) (xy 387.81482 -246.664734) (xy 387.81482 -246.712486)
			(xy 387.914896 -246.812308)
		)
		(stroke
			(width 0)
			(type solid)
		)
		(fill yes)
		(layer "In2.Cu")
		(net "M_I_CPU0_SA_DQS_DN<4>")
	)
	(gr_poly
		(pts
			(xy 388.014972 -245.49608) (xy 387.914896 -245.396004) (xy 387.81482 -245.49608) (xy 387.81482 -245.54053)
			(xy 388.014972 -245.54053)
		)
		(stroke
			(width 0)
			(type solid)
		)
		(fill yes)
		(layer "In2.Cu")
		(net "M_I_CPU0_SA_CB<1>")
	)
	(gr_poly
		(pts
			(xy 388.014972 -245.09222) (xy 388.014972 -245.04777) (xy 387.81482 -245.04777) (xy 387.81482 -245.09222)
			(xy 387.914896 -245.192296)
		)
		(stroke
			(width 0)
			(type solid)
		)
		(fill yes)
		(layer "In2.Cu")
		(net "M_I_CPU0_SA_CB<2>")
	)
	(gr_poly
		(pts
			(xy 388.014972 -243.876068) (xy 387.914896 -243.775992) (xy 387.81482 -243.876068) (xy 387.81482 -243.920518)
			(xy 388.014972 -243.920518)
		)
		(stroke
			(width 0)
			(type solid)
		)
		(fill yes)
		(layer "In2.Cu")
		(net "M_I_CPU0_SA_DQ<29>")
	)
	(gr_poly
		(pts
			(xy 388.014972 -243.472208) (xy 388.014972 -243.427758) (xy 387.81482 -243.427758) (xy 387.81482 -243.472208)
			(xy 387.914896 -243.572284)
		)
		(stroke
			(width 0)
			(type solid)
		)
		(fill yes)
		(layer "In2.Cu")
		(net "M_I_CPU0_SA_DQ<30>")
	)
	(gr_poly
		(pts
			(xy 388.014972 -242.255802) (xy 387.914896 -242.15598) (xy 387.81482 -242.255802) (xy 387.81482 -242.303554)
			(xy 388.014972 -242.303554)
		)
		(stroke
			(width 0)
			(type solid)
		)
		(fill yes)
		(layer "In2.Cu")
		(net "M_I_CPU0_SA_DQS_DN<8>")
	)
	(gr_poly
		(pts
			(xy 388.014972 -241.85245) (xy 388.014972 -241.804698) (xy 387.81482 -241.804698) (xy 387.81482 -241.85245)
			(xy 387.914896 -241.952272)
		)
		(stroke
			(width 0)
			(type solid)
		)
		(fill yes)
		(layer "In2.Cu")
		(net "M_I_CPU0_SA_DQS_DN<3>")
	)
	(gr_poly
		(pts
			(xy 388.014972 -240.636044) (xy 387.914896 -240.535968) (xy 387.81482 -240.636044) (xy 387.81482 -240.680494)
			(xy 388.014972 -240.680494)
		)
		(stroke
			(width 0)
			(type solid)
		)
		(fill yes)
		(layer "In2.Cu")
		(net "M_I_CPU0_SA_DQ<25>")
	)
	(gr_poly
		(pts
			(xy 388.014972 -240.232184) (xy 388.014972 -240.187734) (xy 387.81482 -240.187734) (xy 387.81482 -240.232184)
			(xy 387.914896 -240.33226)
		)
		(stroke
			(width 0)
			(type solid)
		)
		(fill yes)
		(layer "In2.Cu")
		(net "M_I_CPU0_SA_DQ<26>")
	)
	(gr_poly
		(pts
			(xy 388.014972 -239.016032) (xy 387.914896 -238.915956) (xy 387.81482 -239.016032) (xy 387.81482 -239.060482)
			(xy 388.014972 -239.060482)
		)
		(stroke
			(width 0)
			(type solid)
		)
		(fill yes)
		(layer "In2.Cu")
		(net "M_I_CPU0_SA_DQ<21>")
	)
	(gr_poly
		(pts
			(xy 388.014972 -238.612172) (xy 388.014972 -238.567722) (xy 387.81482 -238.567722) (xy 387.81482 -238.612172)
			(xy 387.914896 -238.712248)
		)
		(stroke
			(width 0)
			(type solid)
		)
		(fill yes)
		(layer "In2.Cu")
		(net "M_I_CPU0_SA_DQ<22>")
	)
	(gr_poly
		(pts
			(xy 388.014972 -237.395766) (xy 387.914896 -237.295944) (xy 387.81482 -237.395766) (xy 387.81482 -237.443518)
			(xy 388.014972 -237.443518)
		)
		(stroke
			(width 0)
			(type solid)
		)
		(fill yes)
		(layer "In2.Cu")
		(net "M_I_CPU0_SA_DQS_DN<7>")
	)
	(gr_poly
		(pts
			(xy 388.014972 -236.992414) (xy 388.014972 -236.944662) (xy 387.81482 -236.944662) (xy 387.81482 -236.992414)
			(xy 387.914896 -237.092236)
		)
		(stroke
			(width 0)
			(type solid)
		)
		(fill yes)
		(layer "In2.Cu")
		(net "M_I_CPU0_SA_DQS_DN<2>")
	)
	(gr_poly
		(pts
			(xy 388.014972 -235.776008) (xy 387.914896 -235.675932) (xy 387.81482 -235.776008) (xy 387.81482 -235.820458)
			(xy 388.014972 -235.820458)
		)
		(stroke
			(width 0)
			(type solid)
		)
		(fill yes)
		(layer "In2.Cu")
		(net "M_I_CPU0_SA_DQ<17>")
	)
	(gr_poly
		(pts
			(xy 388.014972 -235.372148) (xy 388.014972 -235.327698) (xy 387.81482 -235.327698) (xy 387.81482 -235.372148)
			(xy 387.914896 -235.472224)
		)
		(stroke
			(width 0)
			(type solid)
		)
		(fill yes)
		(layer "In2.Cu")
		(net "M_I_CPU0_SA_DQ<18>")
	)
	(gr_poly
		(pts
			(xy 388.014972 -234.155996) (xy 387.914896 -234.05592) (xy 387.81482 -234.155996) (xy 387.81482 -234.200446)
			(xy 388.014972 -234.200446)
		)
		(stroke
			(width 0)
			(type solid)
		)
		(fill yes)
		(layer "In2.Cu")
		(net "M_I_CPU0_SA_DQ<13>")
	)
	(gr_poly
		(pts
			(xy 388.014972 -233.752136) (xy 388.014972 -233.707686) (xy 387.81482 -233.707686) (xy 387.81482 -233.752136)
			(xy 387.914896 -233.852212)
		)
		(stroke
			(width 0)
			(type solid)
		)
		(fill yes)
		(layer "In2.Cu")
		(net "M_I_CPU0_SA_DQ<14>")
	)
	(gr_poly
		(pts
			(xy 388.014972 -232.53573) (xy 387.914896 -232.435908) (xy 387.81482 -232.53573) (xy 387.81482 -232.583482)
			(xy 388.014972 -232.583482)
		)
		(stroke
			(width 0)
			(type solid)
		)
		(fill yes)
		(layer "In2.Cu")
		(net "M_I_CPU0_SA_DQS_DN<6>")
	)
	(gr_poly
		(pts
			(xy 388.014972 -232.132378) (xy 388.014972 -232.084626) (xy 387.81482 -232.084626) (xy 387.81482 -232.132378)
			(xy 387.914896 -232.2322)
		)
		(stroke
			(width 0)
			(type solid)
		)
		(fill yes)
		(layer "In2.Cu")
		(net "M_I_CPU0_SA_DQS_DN<1>")
	)
	(gr_poly
		(pts
			(xy 388.014972 -230.915972) (xy 387.914896 -230.815896) (xy 387.81482 -230.915972) (xy 387.81482 -230.960422)
			(xy 388.014972 -230.960422)
		)
		(stroke
			(width 0)
			(type solid)
		)
		(fill yes)
		(layer "In2.Cu")
		(net "M_I_CPU0_SA_DQ<9>")
	)
	(gr_poly
		(pts
			(xy 388.014972 -230.512366) (xy 388.014972 -230.467916) (xy 387.81482 -230.467916) (xy 387.81482 -230.512366)
			(xy 387.914896 -230.612188)
		)
		(stroke
			(width 0)
			(type solid)
		)
		(fill yes)
		(layer "In2.Cu")
		(net "M_I_CPU0_SA_DQ<10>")
	)
	(gr_poly
		(pts
			(xy 388.014972 -229.29596) (xy 387.914896 -229.195884) (xy 387.81482 -229.29596) (xy 387.81482 -229.34041)
			(xy 388.014972 -229.34041)
		)
		(stroke
			(width 0)
			(type solid)
		)
		(fill yes)
		(layer "In2.Cu")
		(net "M_I_CPU0_SA_DQ<5>")
	)
	(gr_poly
		(pts
			(xy 388.014972 -228.892354) (xy 388.014972 -228.847904) (xy 387.81482 -228.847904) (xy 387.81482 -228.892354)
			(xy 387.914896 -228.99243)
		)
		(stroke
			(width 0)
			(type solid)
		)
		(fill yes)
		(layer "In2.Cu")
		(net "M_I_CPU0_SA_DQ<6>")
	)
	(gr_poly
		(pts
			(xy 388.014972 -227.675948) (xy 387.914896 -227.576126) (xy 387.81482 -227.675948) (xy 387.81482 -227.7237)
			(xy 388.014972 -227.7237)
		)
		(stroke
			(width 0)
			(type solid)
		)
		(fill yes)
		(layer "In2.Cu")
		(net "M_I_CPU0_SA_DQS_DN<5>")
	)
	(gr_poly
		(pts
			(xy 388.014972 -227.272596) (xy 388.014972 -227.224844) (xy 387.81482 -227.224844) (xy 387.81482 -227.272596)
			(xy 387.914896 -227.372418)
		)
		(stroke
			(width 0)
			(type solid)
		)
		(fill yes)
		(layer "In2.Cu")
		(net "M_I_CPU0_SA_DQS_DN<0>")
	)
	(gr_poly
		(pts
			(xy 388.069836 -224.570036) (xy 388.03326 -224.433384) (xy 387.994652 -224.411286) (xy 387.894576 -224.584514)
			(xy 387.933184 -224.606612)
		)
		(stroke
			(width 0)
			(type solid)
		)
		(fill yes)
		(layer "In2.Cu")
		(net "M_I_CPU0_SA_DQ<2>")
	)
	(gr_poly
		(pts
			(xy 388.070598 -226.188778) (xy 388.034022 -226.052126) (xy 387.995668 -226.029774) (xy 387.895592 -226.203002)
			(xy 387.9342 -226.225354)
		)
		(stroke
			(width 0)
			(type solid)
		)
		(fill yes)
		(layer "In2.Cu")
		(net "M_I_CPU0_SA_DQ<3>")
	)
	(gr_poly
		(pts
			(xy 388.314946 -293.324026) (xy 388.314946 -293.279576) (xy 388.114794 -293.279576) (xy 388.114794 -293.324026)
			(xy 388.21487 -293.424102)
		)
		(stroke
			(width 0)
			(type solid)
		)
		(fill yes)
		(layer "In2.Cu")
		(net "M_I_CPU0_SB_DQ<31>")
	)
	(gr_poly
		(pts
			(xy 388.314946 -292.107874) (xy 388.21487 -292.007798) (xy 388.114794 -292.107874) (xy 388.114794 -292.152324)
			(xy 388.314946 -292.152324)
		)
		(stroke
			(width 0)
			(type solid)
		)
		(fill yes)
		(layer "In2.Cu")
		(net "M_I_CPU0_SB_DQ<28>")
	)
	(gr_poly
		(pts
			(xy 388.314946 -291.704268) (xy 388.314946 -291.656516) (xy 388.114794 -291.656516) (xy 388.114794 -291.704268)
			(xy 388.21487 -291.80409)
		)
		(stroke
			(width 0)
			(type solid)
		)
		(fill yes)
		(layer "In2.Cu")
		(net "M_I_CPU0_SB_DQS_DP<8>")
	)
	(gr_poly
		(pts
			(xy 388.314946 -290.487608) (xy 388.21487 -290.387786) (xy 388.114794 -290.487608) (xy 388.114794 -290.53536)
			(xy 388.314946 -290.53536)
		)
		(stroke
			(width 0)
			(type solid)
		)
		(fill yes)
		(layer "In2.Cu")
		(net "M_I_CPU0_SB_DQS_DP<3>")
	)
	(gr_poly
		(pts
			(xy 388.314946 -290.084002) (xy 388.314946 -290.039552) (xy 388.114794 -290.039552) (xy 388.114794 -290.084002)
			(xy 388.21487 -290.184078)
		)
		(stroke
			(width 0)
			(type solid)
		)
		(fill yes)
		(layer "In2.Cu")
		(net "M_I_CPU0_SB_DQ<27>")
	)
	(gr_poly
		(pts
			(xy 388.314946 -288.86785) (xy 388.21487 -288.767774) (xy 388.114794 -288.86785) (xy 388.114794 -288.9123)
			(xy 388.314946 -288.9123)
		)
		(stroke
			(width 0)
			(type solid)
		)
		(fill yes)
		(layer "In2.Cu")
		(net "M_I_CPU0_SB_DQ<24>")
	)
	(gr_poly
		(pts
			(xy 388.314946 -288.464244) (xy 388.314946 -288.419794) (xy 388.114794 -288.419794) (xy 388.114794 -288.464244)
			(xy 388.21487 -288.56432)
		)
		(stroke
			(width 0)
			(type solid)
		)
		(fill yes)
		(layer "In2.Cu")
		(net "M_I_CPU0_SB_DQ<23>")
	)
	(gr_poly
		(pts
			(xy 388.314946 -287.247838) (xy 388.21487 -287.148016) (xy 388.114794 -287.247838) (xy 388.114794 -287.292288)
			(xy 388.314946 -287.292288)
		)
		(stroke
			(width 0)
			(type solid)
		)
		(fill yes)
		(layer "In2.Cu")
		(net "M_I_CPU0_SB_DQ<20>")
	)
	(gr_poly
		(pts
			(xy 388.314946 -286.844232) (xy 388.314946 -286.79648) (xy 388.114794 -286.79648) (xy 388.114794 -286.844232)
			(xy 388.21487 -286.944308)
		)
		(stroke
			(width 0)
			(type solid)
		)
		(fill yes)
		(layer "In2.Cu")
		(net "M_I_CPU0_SB_DQS_DP<7>")
	)
	(gr_poly
		(pts
			(xy 388.314946 -285.627826) (xy 388.21487 -285.528004) (xy 388.114794 -285.627826) (xy 388.114794 -285.675578)
			(xy 388.314946 -285.675578)
		)
		(stroke
			(width 0)
			(type solid)
		)
		(fill yes)
		(layer "In2.Cu")
		(net "M_I_CPU0_SB_DQS_DP<2>")
	)
	(gr_poly
		(pts
			(xy 388.314946 -285.22422) (xy 388.314946 -285.17977) (xy 388.114794 -285.17977) (xy 388.114794 -285.22422)
			(xy 388.21487 -285.324296)
		)
		(stroke
			(width 0)
			(type solid)
		)
		(fill yes)
		(layer "In2.Cu")
		(net "M_I_CPU0_SB_DQ<19>")
	)
	(gr_poly
		(pts
			(xy 388.314946 -284.008068) (xy 388.21487 -283.907992) (xy 388.114794 -284.008068) (xy 388.114794 -284.052518)
			(xy 388.314946 -284.052518)
		)
		(stroke
			(width 0)
			(type solid)
		)
		(fill yes)
		(layer "In2.Cu")
		(net "M_I_CPU0_SB_DQ<16>")
	)
	(gr_poly
		(pts
			(xy 388.314946 -283.604208) (xy 388.314946 -283.559758) (xy 388.114794 -283.559758) (xy 388.114794 -283.604208)
			(xy 388.21487 -283.704284)
		)
		(stroke
			(width 0)
			(type solid)
		)
		(fill yes)
		(layer "In2.Cu")
		(net "M_I_CPU0_SB_DQ<15>")
	)
	(gr_poly
		(pts
			(xy 388.314946 -282.388056) (xy 388.21487 -282.28798) (xy 388.114794 -282.388056) (xy 388.114794 -282.432506)
			(xy 388.314946 -282.432506)
		)
		(stroke
			(width 0)
			(type solid)
		)
		(fill yes)
		(layer "In2.Cu")
		(net "M_I_CPU0_SB_DQ<12>")
	)
	(gr_poly
		(pts
			(xy 388.314946 -281.98445) (xy 388.314946 -281.936698) (xy 388.114794 -281.936698) (xy 388.114794 -281.98445)
			(xy 388.21487 -282.084272)
		)
		(stroke
			(width 0)
			(type solid)
		)
		(fill yes)
		(layer "In2.Cu")
		(net "M_I_CPU0_SB_DQS_DP<6>")
	)
	(gr_poly
		(pts
			(xy 388.314946 -280.76779) (xy 388.21487 -280.667968) (xy 388.114794 -280.76779) (xy 388.114794 -280.815542)
			(xy 388.314946 -280.815542)
		)
		(stroke
			(width 0)
			(type solid)
		)
		(fill yes)
		(layer "In2.Cu")
		(net "M_I_CPU0_SB_DQS_DP<1>")
	)
	(gr_poly
		(pts
			(xy 388.314946 -280.364184) (xy 388.314946 -280.319734) (xy 388.114794 -280.319734) (xy 388.114794 -280.364184)
			(xy 388.21487 -280.46426)
		)
		(stroke
			(width 0)
			(type solid)
		)
		(fill yes)
		(layer "In2.Cu")
		(net "M_I_CPU0_SB_DQ<11>")
	)
	(gr_poly
		(pts
			(xy 388.314946 -279.148032) (xy 388.21487 -279.047956) (xy 388.114794 -279.148032) (xy 388.114794 -279.192482)
			(xy 388.314946 -279.192482)
		)
		(stroke
			(width 0)
			(type solid)
		)
		(fill yes)
		(layer "In2.Cu")
		(net "M_I_CPU0_SB_DQ<8>")
	)
	(gr_poly
		(pts
			(xy 388.314946 -278.744172) (xy 388.314946 -278.699722) (xy 388.114794 -278.699722) (xy 388.114794 -278.744172)
			(xy 388.21487 -278.844248)
		)
		(stroke
			(width 0)
			(type solid)
		)
		(fill yes)
		(layer "In2.Cu")
		(net "M_I_CPU0_SB_DQ<7>")
	)
	(gr_poly
		(pts
			(xy 388.314946 -277.52802) (xy 388.21487 -277.427944) (xy 388.114794 -277.52802) (xy 388.114794 -277.57247)
			(xy 388.314946 -277.57247)
		)
		(stroke
			(width 0)
			(type solid)
		)
		(fill yes)
		(layer "In2.Cu")
		(net "M_I_CPU0_SB_DQ<4>")
	)
	(gr_poly
		(pts
			(xy 388.314946 -277.124414) (xy 388.314946 -277.076662) (xy 388.114794 -277.076662) (xy 388.114794 -277.124414)
			(xy 388.21487 -277.224236)
		)
		(stroke
			(width 0)
			(type solid)
		)
		(fill yes)
		(layer "In2.Cu")
		(net "M_I_CPU0_SB_DQS_DP<5>")
	)
	(gr_poly
		(pts
			(xy 388.314946 -275.907754) (xy 388.21487 -275.807932) (xy 388.114794 -275.907754) (xy 388.114794 -275.955506)
			(xy 388.314946 -275.955506)
		)
		(stroke
			(width 0)
			(type solid)
		)
		(fill yes)
		(layer "In2.Cu")
		(net "M_I_CPU0_SB_DQS_DP<0>")
	)
	(gr_poly
		(pts
			(xy 388.314946 -275.504148) (xy 388.314946 -275.459698) (xy 388.114794 -275.459698) (xy 388.114794 -275.504148)
			(xy 388.21487 -275.604224)
		)
		(stroke
			(width 0)
			(type solid)
		)
		(fill yes)
		(layer "In2.Cu")
		(net "M_I_CPU0_SB_DQ<3>")
	)
	(gr_poly
		(pts
			(xy 388.314946 -274.287996) (xy 388.21487 -274.18792) (xy 388.114794 -274.287996) (xy 388.114794 -274.332446)
			(xy 388.314946 -274.332446)
		)
		(stroke
			(width 0)
			(type solid)
		)
		(fill yes)
		(layer "In2.Cu")
		(net "M_I_CPU0_SB_DQ<0>")
	)
	(gr_poly
		(pts
			(xy 388.314946 -273.884136) (xy 388.314946 -273.839686) (xy 388.114794 -273.839686) (xy 388.114794 -273.884136)
			(xy 388.21487 -273.984212)
		)
		(stroke
			(width 0)
			(type solid)
		)
		(fill yes)
		(layer "In2.Cu")
		(net "M_I_CPU0_SB_CB<3>")
	)
	(gr_poly
		(pts
			(xy 388.314946 -272.667984) (xy 388.21487 -272.567908) (xy 388.114794 -272.667984) (xy 388.114794 -272.712434)
			(xy 388.314946 -272.712434)
		)
		(stroke
			(width 0)
			(type solid)
		)
		(fill yes)
		(layer "In2.Cu")
		(net "M_I_CPU0_SB_CB<0>")
	)
	(gr_poly
		(pts
			(xy 388.314946 -272.264378) (xy 388.314946 -272.216626) (xy 388.114794 -272.216626) (xy 388.114794 -272.264378)
			(xy 388.21487 -272.3642)
		)
		(stroke
			(width 0)
			(type solid)
		)
		(fill yes)
		(layer "In2.Cu")
		(net "M_I_CPU0_SB_DQS_DP<4>")
	)
	(gr_poly
		(pts
			(xy 388.314946 -271.047718) (xy 388.21487 -270.947896) (xy 388.114794 -271.047718) (xy 388.114794 -271.09547)
			(xy 388.314946 -271.09547)
		)
		(stroke
			(width 0)
			(type solid)
		)
		(fill yes)
		(layer "In2.Cu")
		(net "M_I_CPU0_SB_DQS_DP<9>")
	)
	(gr_poly
		(pts
			(xy 388.314946 -270.644112) (xy 388.314946 -270.599662) (xy 388.114794 -270.599662) (xy 388.114794 -270.644112)
			(xy 388.21487 -270.744188)
		)
		(stroke
			(width 0)
			(type solid)
		)
		(fill yes)
		(layer "In2.Cu")
		(net "M_I_CPU0_SB_CB<7>")
	)
	(gr_poly
		(pts
			(xy 388.314946 -269.42796) (xy 388.21487 -269.327884) (xy 388.114794 -269.42796) (xy 388.114794 -269.47241)
			(xy 388.314946 -269.47241)
		)
		(stroke
			(width 0)
			(type solid)
		)
		(fill yes)
		(layer "In2.Cu")
		(net "M_I_CPU0_SB_CB<4>")
	)
	(gr_poly
		(pts
			(xy 388.314946 -267.404088) (xy 388.314946 -267.359638) (xy 388.114794 -267.359638) (xy 388.114794 -267.404088)
			(xy 388.21487 -267.504164)
		)
		(stroke
			(width 0)
			(type solid)
		)
		(fill yes)
		(layer "In2.Cu")
		(net "M_I_CPU0_SB_RSP<0>")
	)
	(gr_poly
		(pts
			(xy 388.314946 -265.784076) (xy 388.314946 -265.739626) (xy 388.114794 -265.739626) (xy 388.114794 -265.784076)
			(xy 388.21487 -265.884152)
		)
		(stroke
			(width 0)
			(type solid)
		)
		(fill yes)
		(layer "In2.Cu")
		(net "M_I_CPU0_SB_CS_N<0>")
	)
	(gr_poly
		(pts
			(xy 388.314946 -264.567924) (xy 388.21487 -264.467848) (xy 388.114794 -264.567924) (xy 388.114794 -264.612374)
			(xy 388.314946 -264.612374)
		)
		(stroke
			(width 0)
			(type solid)
		)
		(fill yes)
		(layer "In2.Cu")
		(net "M_I_CPU0_SB_CA<6>")
	)
	(gr_poly
		(pts
			(xy 388.314946 -264.164064) (xy 388.314946 -264.119614) (xy 388.114794 -264.119614) (xy 388.114794 -264.164064)
			(xy 388.21487 -264.26414)
		)
		(stroke
			(width 0)
			(type solid)
		)
		(fill yes)
		(layer "In2.Cu")
		(net "M_I_CPU0_SB_CA<5>")
	)
	(gr_poly
		(pts
			(xy 388.314946 -262.947912) (xy 388.21487 -262.847836) (xy 388.114794 -262.947912) (xy 388.114794 -262.992362)
			(xy 388.314946 -262.992362)
		)
		(stroke
			(width 0)
			(type solid)
		)
		(fill yes)
		(layer "In2.Cu")
		(net "M_I_CPU0_SB_CA<2>")
	)
	(gr_poly
		(pts
			(xy 388.314946 -262.544052) (xy 388.314946 -262.499602) (xy 388.114794 -262.499602) (xy 388.114794 -262.544052)
			(xy 388.21487 -262.644128)
		)
		(stroke
			(width 0)
			(type solid)
		)
		(fill yes)
		(layer "In2.Cu")
		(net "M_I_CPU0_SB_CA<1>")
	)
	(gr_poly
		(pts
			(xy 388.403846 -224.69602) (xy 388.365238 -224.673668) (xy 388.228586 -224.710498) (xy 388.265416 -224.846896)
			(xy 388.30377 -224.869248)
		)
		(stroke
			(width 0)
			(type solid)
		)
		(fill yes)
		(layer "In2.Cu")
		(net "M_I_CPU0_SA_DQ<1>")
	)
	(gr_poly
		(pts
			(xy 388.4041 -223.074738) (xy 388.365746 -223.052386) (xy 388.229094 -223.088962) (xy 388.26567 -223.225614)
			(xy 388.304278 -223.247966)
		)
		(stroke
			(width 0)
			(type solid)
		)
		(fill yes)
		(layer "In2.Cu")
		(net "M_I_CPU0_SA_DQ<0>")
	)
	(gr_poly
		(pts
			(xy 388.406894 -226.316286) (xy 388.365746 -226.292664) (xy 388.229094 -226.32924) (xy 388.26567 -226.465638)
			(xy 388.307072 -226.489514)
		)
		(stroke
			(width 0)
			(type solid)
		)
		(fill yes)
		(layer "In2.Cu")
		(net "M_I_CPU0_SA_DQS_DP<0>")
	)
	(gr_poly
		(pts
			(xy 388.484872 -256.025904) (xy 388.384796 -255.926082) (xy 388.28472 -256.025904) (xy 388.28472 -256.073656)
			(xy 388.484872 -256.073656)
		)
		(stroke
			(width 0)
			(type solid)
		)
		(fill yes)
		(layer "In2.Cu")
		(net "M_I_CPU0_CLK_DP<0>")
	)
	(gr_poly
		(pts
			(xy 388.484872 -255.622298) (xy 388.484872 -255.577848) (xy 388.28472 -255.577848) (xy 388.28472 -255.622298)
			(xy 388.384796 -255.722374)
		)
		(stroke
			(width 0)
			(type solid)
		)
		(fill yes)
		(layer "In2.Cu")
		(net "M_I_CPU0_SA_PAR")
	)
	(gr_poly
		(pts
			(xy 388.484872 -254.406146) (xy 388.384796 -254.30607) (xy 388.28472 -254.406146) (xy 388.28472 -254.450596)
			(xy 388.484872 -254.450596)
		)
		(stroke
			(width 0)
			(type solid)
		)
		(fill yes)
		(layer "In2.Cu")
		(net "M_I_CPU0_SA_CA<4>")
	)
	(gr_poly
		(pts
			(xy 388.484872 -254.002286) (xy 388.484872 -253.957836) (xy 388.28472 -253.957836) (xy 388.28472 -254.002286)
			(xy 388.384796 -254.102362)
		)
		(stroke
			(width 0)
			(type solid)
		)
		(fill yes)
		(layer "In2.Cu")
		(net "M_I_CPU0_SA_CA<3>")
	)
	(gr_poly
		(pts
			(xy 388.484872 -252.786134) (xy 388.384796 -252.686058) (xy 388.28472 -252.786134) (xy 388.28472 -252.830584)
			(xy 388.484872 -252.830584)
		)
		(stroke
			(width 0)
			(type solid)
		)
		(fill yes)
		(layer "In2.Cu")
		(net "M_I_CPU0_SA_CA<0>")
	)
	(gr_poly
		(pts
			(xy 388.484872 -251.166122) (xy 388.384796 -251.066046) (xy 388.28472 -251.166122) (xy 388.28472 -251.210572)
			(xy 388.484872 -251.210572)
		)
		(stroke
			(width 0)
			(type solid)
		)
		(fill yes)
		(layer "In2.Cu")
		(net "M_I_CPU0_SA_CS_N<0>")
	)
	(gr_poly
		(pts
			(xy 388.484872 -250.762262) (xy 388.484872 -250.717812) (xy 388.28472 -250.717812) (xy 388.28472 -250.762262)
			(xy 388.384796 -250.862338)
		)
		(stroke
			(width 0)
			(type solid)
		)
		(fill yes)
		(layer "In2.Cu")
		(net "M_I_CPU0_RESET_N")
	)
	(gr_poly
		(pts
			(xy 388.484872 -249.14225) (xy 388.484872 -249.0978) (xy 388.28472 -249.0978) (xy 388.28472 -249.14225)
			(xy 388.384796 -249.242326)
		)
		(stroke
			(width 0)
			(type solid)
		)
		(fill yes)
		(layer "In2.Cu")
		(net "M_I_CPU0_SA_CB<7>")
	)
	(gr_poly
		(pts
			(xy 388.484872 -247.926098) (xy 388.384796 -247.826022) (xy 388.28472 -247.926098) (xy 388.28472 -247.970548)
			(xy 388.484872 -247.970548)
		)
		(stroke
			(width 0)
			(type solid)
		)
		(fill yes)
		(layer "In2.Cu")
		(net "M_I_CPU0_SA_CB<4>")
	)
	(gr_poly
		(pts
			(xy 388.484872 -247.522492) (xy 388.484872 -247.47474) (xy 388.28472 -247.47474) (xy 388.28472 -247.522492)
			(xy 388.384796 -247.622314)
		)
		(stroke
			(width 0)
			(type solid)
		)
		(fill yes)
		(layer "In2.Cu")
		(net "M_I_CPU0_SA_DQS_DP<9>")
	)
	(gr_poly
		(pts
			(xy 388.484872 -246.305832) (xy 388.384796 -246.20601) (xy 388.28472 -246.305832) (xy 388.28472 -246.353584)
			(xy 388.484872 -246.353584)
		)
		(stroke
			(width 0)
			(type solid)
		)
		(fill yes)
		(layer "In2.Cu")
		(net "M_I_CPU0_SA_DQS_DP<4>")
	)
	(gr_poly
		(pts
			(xy 388.484872 -245.902226) (xy 388.484872 -245.857776) (xy 388.28472 -245.857776) (xy 388.28472 -245.902226)
			(xy 388.384796 -246.002302)
		)
		(stroke
			(width 0)
			(type solid)
		)
		(fill yes)
		(layer "In2.Cu")
		(net "M_I_CPU0_SA_CB<3>")
	)
	(gr_poly
		(pts
			(xy 388.484872 -244.686074) (xy 388.384796 -244.585998) (xy 388.28472 -244.686074) (xy 388.28472 -244.730524)
			(xy 388.484872 -244.730524)
		)
		(stroke
			(width 0)
			(type solid)
		)
		(fill yes)
		(layer "In2.Cu")
		(net "M_I_CPU0_SA_CB<0>")
	)
	(gr_poly
		(pts
			(xy 388.484872 -244.282214) (xy 388.484872 -244.237764) (xy 388.28472 -244.237764) (xy 388.28472 -244.282214)
			(xy 388.384796 -244.38229)
		)
		(stroke
			(width 0)
			(type solid)
		)
		(fill yes)
		(layer "In2.Cu")
		(net "M_I_CPU0_SA_DQ<31>")
	)
	(gr_poly
		(pts
			(xy 388.484872 -243.066062) (xy 388.384796 -242.965986) (xy 388.28472 -243.066062) (xy 388.28472 -243.110512)
			(xy 388.484872 -243.110512)
		)
		(stroke
			(width 0)
			(type solid)
		)
		(fill yes)
		(layer "In2.Cu")
		(net "M_I_CPU0_SA_DQ<28>")
	)
	(gr_poly
		(pts
			(xy 388.484872 -242.662456) (xy 388.484872 -242.614704) (xy 388.28472 -242.614704) (xy 388.28472 -242.662456)
			(xy 388.384796 -242.762278)
		)
		(stroke
			(width 0)
			(type solid)
		)
		(fill yes)
		(layer "In2.Cu")
		(net "M_I_CPU0_SA_DQS_DP<8>")
	)
	(gr_poly
		(pts
			(xy 388.484872 -241.445796) (xy 388.384796 -241.345974) (xy 388.28472 -241.445796) (xy 388.28472 -241.493548)
			(xy 388.484872 -241.493548)
		)
		(stroke
			(width 0)
			(type solid)
		)
		(fill yes)
		(layer "In2.Cu")
		(net "M_I_CPU0_SA_DQS_DP<3>")
	)
	(gr_poly
		(pts
			(xy 388.484872 -241.04219) (xy 388.484872 -240.99774) (xy 388.28472 -240.99774) (xy 388.28472 -241.04219)
			(xy 388.384796 -241.142266)
		)
		(stroke
			(width 0)
			(type solid)
		)
		(fill yes)
		(layer "In2.Cu")
		(net "M_I_CPU0_SA_DQ<27>")
	)
	(gr_poly
		(pts
			(xy 388.484872 -239.826038) (xy 388.384796 -239.725962) (xy 388.28472 -239.826038) (xy 388.28472 -239.870488)
			(xy 388.484872 -239.870488)
		)
		(stroke
			(width 0)
			(type solid)
		)
		(fill yes)
		(layer "In2.Cu")
		(net "M_I_CPU0_SA_DQ<24>")
	)
	(gr_poly
		(pts
			(xy 388.484872 -239.422178) (xy 388.484872 -239.377728) (xy 388.28472 -239.377728) (xy 388.28472 -239.422178)
			(xy 388.384796 -239.522254)
		)
		(stroke
			(width 0)
			(type solid)
		)
		(fill yes)
		(layer "In2.Cu")
		(net "M_I_CPU0_SA_DQ<23>")
	)
	(gr_poly
		(pts
			(xy 388.484872 -238.206026) (xy 388.384796 -238.10595) (xy 388.28472 -238.206026) (xy 388.28472 -238.250476)
			(xy 388.484872 -238.250476)
		)
		(stroke
			(width 0)
			(type solid)
		)
		(fill yes)
		(layer "In2.Cu")
		(net "M_I_CPU0_SA_DQ<20>")
	)
	(gr_poly
		(pts
			(xy 388.484872 -237.80242) (xy 388.484872 -237.754668) (xy 388.28472 -237.754668) (xy 388.28472 -237.80242)
			(xy 388.384796 -237.902242)
		)
		(stroke
			(width 0)
			(type solid)
		)
		(fill yes)
		(layer "In2.Cu")
		(net "M_I_CPU0_SA_DQS_DP<7>")
	)
	(gr_poly
		(pts
			(xy 388.484872 -236.58576) (xy 388.384796 -236.485938) (xy 388.28472 -236.58576) (xy 388.28472 -236.633512)
			(xy 388.484872 -236.633512)
		)
		(stroke
			(width 0)
			(type solid)
		)
		(fill yes)
		(layer "In2.Cu")
		(net "M_I_CPU0_SA_DQS_DP<2>")
	)
	(gr_poly
		(pts
			(xy 388.484872 -236.182154) (xy 388.484872 -236.137704) (xy 388.28472 -236.137704) (xy 388.28472 -236.182154)
			(xy 388.384796 -236.28223)
		)
		(stroke
			(width 0)
			(type solid)
		)
		(fill yes)
		(layer "In2.Cu")
		(net "M_I_CPU0_SA_DQ<19>")
	)
	(gr_poly
		(pts
			(xy 388.484872 -234.966002) (xy 388.384796 -234.865926) (xy 388.28472 -234.966002) (xy 388.28472 -235.010452)
			(xy 388.484872 -235.010452)
		)
		(stroke
			(width 0)
			(type solid)
		)
		(fill yes)
		(layer "In2.Cu")
		(net "M_I_CPU0_SA_DQ<16>")
	)
	(gr_poly
		(pts
			(xy 388.484872 -234.562142) (xy 388.484872 -234.517692) (xy 388.28472 -234.517692) (xy 388.28472 -234.562142)
			(xy 388.384796 -234.662218)
		)
		(stroke
			(width 0)
			(type solid)
		)
		(fill yes)
		(layer "In2.Cu")
		(net "M_I_CPU0_SA_DQ<15>")
	)
	(gr_poly
		(pts
			(xy 388.484872 -233.34599) (xy 388.384796 -233.245914) (xy 388.28472 -233.34599) (xy 388.28472 -233.39044)
			(xy 388.484872 -233.39044)
		)
		(stroke
			(width 0)
			(type solid)
		)
		(fill yes)
		(layer "In2.Cu")
		(net "M_I_CPU0_SA_DQ<12>")
	)
	(gr_poly
		(pts
			(xy 388.484872 -232.942384) (xy 388.484872 -232.894632) (xy 388.28472 -232.894632) (xy 388.28472 -232.942384)
			(xy 388.384796 -233.042206)
		)
		(stroke
			(width 0)
			(type solid)
		)
		(fill yes)
		(layer "In2.Cu")
		(net "M_I_CPU0_SA_DQS_DP<6>")
	)
	(gr_poly
		(pts
			(xy 388.484872 -231.725724) (xy 388.384796 -231.625902) (xy 388.28472 -231.725724) (xy 388.28472 -231.773476)
			(xy 388.484872 -231.773476)
		)
		(stroke
			(width 0)
			(type solid)
		)
		(fill yes)
		(layer "In2.Cu")
		(net "M_I_CPU0_SA_DQS_DP<1>")
	)
	(gr_poly
		(pts
			(xy 388.484872 -231.322372) (xy 388.484872 -231.277922) (xy 388.28472 -231.277922) (xy 388.28472 -231.322372)
			(xy 388.384796 -231.422448)
		)
		(stroke
			(width 0)
			(type solid)
		)
		(fill yes)
		(layer "In2.Cu")
		(net "M_I_CPU0_SA_DQ<11>")
	)
	(gr_poly
		(pts
			(xy 388.484872 -230.105966) (xy 388.384796 -230.006144) (xy 388.28472 -230.105966) (xy 388.28472 -230.150416)
			(xy 388.484872 -230.150416)
		)
		(stroke
			(width 0)
			(type solid)
		)
		(fill yes)
		(layer "In2.Cu")
		(net "M_I_CPU0_SA_DQ<8>")
	)
	(gr_poly
		(pts
			(xy 388.484872 -229.70236) (xy 388.484872 -229.65791) (xy 388.28472 -229.65791) (xy 388.28472 -229.70236)
			(xy 388.384796 -229.802436)
		)
		(stroke
			(width 0)
			(type solid)
		)
		(fill yes)
		(layer "In2.Cu")
		(net "M_I_CPU0_SA_DQ<7>")
	)
	(gr_poly
		(pts
			(xy 388.484872 -228.486208) (xy 388.384796 -228.386132) (xy 388.28472 -228.486208) (xy 388.28472 -228.530658)
			(xy 388.484872 -228.530658)
		)
		(stroke
			(width 0)
			(type solid)
		)
		(fill yes)
		(layer "In2.Cu")
		(net "M_I_CPU0_SA_DQ<4>")
	)
	(gr_poly
		(pts
			(xy 388.484872 -228.082602) (xy 388.484872 -228.03485) (xy 388.28472 -228.03485) (xy 388.28472 -228.082602)
			(xy 388.384796 -228.182424)
		)
		(stroke
			(width 0)
			(type solid)
		)
		(fill yes)
		(layer "In2.Cu")
		(net "M_I_CPU0_SA_DQS_DP<5>")
	)
	(gr_poly
		(pts
			(xy 388.540244 -223.759522) (xy 388.503668 -223.62287) (xy 388.46506 -223.600518) (xy 388.365238 -223.773746)
			(xy 388.403592 -223.796098)
		)
		(stroke
			(width 0)
			(type solid)
		)
		(fill yes)
		(layer "In2.Cu")
		(net "M_I_CPU0_SA_DQ<2>")
	)
	(gr_poly
		(pts
			(xy 388.540752 -226.999292) (xy 388.504176 -226.862894) (xy 388.462774 -226.839018) (xy 388.362952 -227.012246)
			(xy 388.4041 -227.035868)
		)
		(stroke
			(width 0)
			(type solid)
		)
		(fill yes)
		(layer "In2.Cu")
		(net "M_I_CPU0_SA_DQS_DN<0>")
	)
	(gr_poly
		(pts
			(xy 388.541006 -225.378772) (xy 388.504176 -225.24212) (xy 388.465822 -225.219768) (xy 388.365746 -225.392996)
			(xy 388.404354 -225.415348)
		)
		(stroke
			(width 0)
			(type solid)
		)
		(fill yes)
		(layer "In2.Cu")
		(net "M_I_CPU0_SA_DQ<3>")
	)
	(gr_poly
		(pts
			(xy 388.784846 -292.91788) (xy 388.68477 -292.817804) (xy 388.584694 -292.91788) (xy 388.584694 -292.96233)
			(xy 388.784846 -292.96233)
		)
		(stroke
			(width 0)
			(type solid)
		)
		(fill yes)
		(layer "In2.Cu")
		(net "M_I_CPU0_SB_DQ<29>")
	)
	(gr_poly
		(pts
			(xy 388.784846 -292.51402) (xy 388.784846 -292.46957) (xy 388.584694 -292.46957) (xy 388.584694 -292.51402)
			(xy 388.68477 -292.614096)
		)
		(stroke
			(width 0)
			(type solid)
		)
		(fill yes)
		(layer "In2.Cu")
		(net "M_I_CPU0_SB_DQ<30>")
	)
	(gr_poly
		(pts
			(xy 388.784846 -291.297614) (xy 388.68477 -291.197792) (xy 388.584694 -291.297614) (xy 388.584694 -291.345366)
			(xy 388.784846 -291.345366)
		)
		(stroke
			(width 0)
			(type solid)
		)
		(fill yes)
		(layer "In2.Cu")
		(net "M_I_CPU0_SB_DQS_DN<8>")
	)
	(gr_poly
		(pts
			(xy 388.784846 -290.894262) (xy 388.784846 -290.84651) (xy 388.584694 -290.84651) (xy 388.584694 -290.894262)
			(xy 388.68477 -290.994084)
		)
		(stroke
			(width 0)
			(type solid)
		)
		(fill yes)
		(layer "In2.Cu")
		(net "M_I_CPU0_SB_DQS_DN<3>")
	)
	(gr_poly
		(pts
			(xy 388.784846 -289.677856) (xy 388.68477 -289.57778) (xy 388.584694 -289.677856) (xy 388.584694 -289.722306)
			(xy 388.784846 -289.722306)
		)
		(stroke
			(width 0)
			(type solid)
		)
		(fill yes)
		(layer "In2.Cu")
		(net "M_I_CPU0_SB_DQ<25>")
	)
	(gr_poly
		(pts
			(xy 388.784846 -289.273996) (xy 388.784846 -289.229546) (xy 388.584694 -289.229546) (xy 388.584694 -289.273996)
			(xy 388.68477 -289.374072)
		)
		(stroke
			(width 0)
			(type solid)
		)
		(fill yes)
		(layer "In2.Cu")
		(net "M_I_CPU0_SB_DQ<26>")
	)
	(gr_poly
		(pts
			(xy 388.784846 -288.057844) (xy 388.68477 -287.957768) (xy 388.584694 -288.057844) (xy 388.584694 -288.102294)
			(xy 388.784846 -288.102294)
		)
		(stroke
			(width 0)
			(type solid)
		)
		(fill yes)
		(layer "In2.Cu")
		(net "M_I_CPU0_SB_DQ<21>")
	)
	(gr_poly
		(pts
			(xy 388.784846 -287.654238) (xy 388.784846 -287.609788) (xy 388.584694 -287.609788) (xy 388.584694 -287.654238)
			(xy 388.68477 -287.75406)
		)
		(stroke
			(width 0)
			(type solid)
		)
		(fill yes)
		(layer "In2.Cu")
		(net "M_I_CPU0_SB_DQ<22>")
	)
	(gr_poly
		(pts
			(xy 388.784846 -286.437832) (xy 388.68477 -286.337756) (xy 388.584694 -286.437832) (xy 388.584694 -286.485584)
			(xy 388.784846 -286.485584)
		)
		(stroke
			(width 0)
			(type solid)
		)
		(fill yes)
		(layer "In2.Cu")
		(net "M_I_CPU0_SB_DQS_DN<7>")
	)
	(gr_poly
		(pts
			(xy 388.784846 -286.03448) (xy 388.784846 -285.986728) (xy 388.584694 -285.986728) (xy 388.584694 -286.03448)
			(xy 388.68477 -286.134302)
		)
		(stroke
			(width 0)
			(type solid)
		)
		(fill yes)
		(layer "In2.Cu")
		(net "M_I_CPU0_SB_DQS_DN<2>")
	)
	(gr_poly
		(pts
			(xy 388.784846 -284.818074) (xy 388.68477 -284.717998) (xy 388.584694 -284.818074) (xy 388.584694 -284.862524)
			(xy 388.784846 -284.862524)
		)
		(stroke
			(width 0)
			(type solid)
		)
		(fill yes)
		(layer "In2.Cu")
		(net "M_I_CPU0_SB_DQ<17>")
	)
	(gr_poly
		(pts
			(xy 388.784846 -284.414214) (xy 388.784846 -284.369764) (xy 388.584694 -284.369764) (xy 388.584694 -284.414214)
			(xy 388.68477 -284.51429)
		)
		(stroke
			(width 0)
			(type solid)
		)
		(fill yes)
		(layer "In2.Cu")
		(net "M_I_CPU0_SB_DQ<18>")
	)
	(gr_poly
		(pts
			(xy 388.784846 -283.198062) (xy 388.68477 -283.097986) (xy 388.584694 -283.198062) (xy 388.584694 -283.242512)
			(xy 388.784846 -283.242512)
		)
		(stroke
			(width 0)
			(type solid)
		)
		(fill yes)
		(layer "In2.Cu")
		(net "M_I_CPU0_SB_DQ<13>")
	)
	(gr_poly
		(pts
			(xy 388.784846 -282.794202) (xy 388.784846 -282.749752) (xy 388.584694 -282.749752) (xy 388.584694 -282.794202)
			(xy 388.68477 -282.894278)
		)
		(stroke
			(width 0)
			(type solid)
		)
		(fill yes)
		(layer "In2.Cu")
		(net "M_I_CPU0_SB_DQ<14>")
	)
	(gr_poly
		(pts
			(xy 388.784846 -281.577796) (xy 388.68477 -281.477974) (xy 388.584694 -281.577796) (xy 388.584694 -281.625548)
			(xy 388.784846 -281.625548)
		)
		(stroke
			(width 0)
			(type solid)
		)
		(fill yes)
		(layer "In2.Cu")
		(net "M_I_CPU0_SB_DQS_DN<6>")
	)
	(gr_poly
		(pts
			(xy 388.784846 -281.174444) (xy 388.784846 -281.126692) (xy 388.584694 -281.126692) (xy 388.584694 -281.174444)
			(xy 388.68477 -281.274266)
		)
		(stroke
			(width 0)
			(type solid)
		)
		(fill yes)
		(layer "In2.Cu")
		(net "M_I_CPU0_SB_DQS_DN<1>")
	)
	(gr_poly
		(pts
			(xy 388.784846 -279.958038) (xy 388.68477 -279.857962) (xy 388.584694 -279.958038) (xy 388.584694 -280.002488)
			(xy 388.784846 -280.002488)
		)
		(stroke
			(width 0)
			(type solid)
		)
		(fill yes)
		(layer "In2.Cu")
		(net "M_I_CPU0_SB_DQ<9>")
	)
	(gr_poly
		(pts
			(xy 388.784846 -279.554178) (xy 388.784846 -279.509728) (xy 388.584694 -279.509728) (xy 388.584694 -279.554178)
			(xy 388.68477 -279.654254)
		)
		(stroke
			(width 0)
			(type solid)
		)
		(fill yes)
		(layer "In2.Cu")
		(net "M_I_CPU0_SB_DQ<10>")
	)
	(gr_poly
		(pts
			(xy 388.784846 -278.338026) (xy 388.68477 -278.23795) (xy 388.584694 -278.338026) (xy 388.584694 -278.382476)
			(xy 388.784846 -278.382476)
		)
		(stroke
			(width 0)
			(type solid)
		)
		(fill yes)
		(layer "In2.Cu")
		(net "M_I_CPU0_SB_DQ<5>")
	)
	(gr_poly
		(pts
			(xy 388.784846 -277.934166) (xy 388.784846 -277.889716) (xy 388.584694 -277.889716) (xy 388.584694 -277.934166)
			(xy 388.68477 -278.034242)
		)
		(stroke
			(width 0)
			(type solid)
		)
		(fill yes)
		(layer "In2.Cu")
		(net "M_I_CPU0_SB_DQ<6>")
	)
	(gr_poly
		(pts
			(xy 388.784846 -276.71776) (xy 388.68477 -276.617938) (xy 388.584694 -276.71776) (xy 388.584694 -276.765512)
			(xy 388.784846 -276.765512)
		)
		(stroke
			(width 0)
			(type solid)
		)
		(fill yes)
		(layer "In2.Cu")
		(net "M_I_CPU0_SB_DQS_DN<5>")
	)
	(gr_poly
		(pts
			(xy 388.784846 -276.314408) (xy 388.784846 -276.266656) (xy 388.584694 -276.266656) (xy 388.584694 -276.314408)
			(xy 388.68477 -276.41423)
		)
		(stroke
			(width 0)
			(type solid)
		)
		(fill yes)
		(layer "In2.Cu")
		(net "M_I_CPU0_SB_DQS_DN<0>")
	)
	(gr_poly
		(pts
			(xy 388.784846 -275.098002) (xy 388.68477 -274.997926) (xy 388.584694 -275.098002) (xy 388.584694 -275.142452)
			(xy 388.784846 -275.142452)
		)
		(stroke
			(width 0)
			(type solid)
		)
		(fill yes)
		(layer "In2.Cu")
		(net "M_I_CPU0_SB_DQ<1>")
	)
	(gr_poly
		(pts
			(xy 388.784846 -274.694142) (xy 388.784846 -274.649692) (xy 388.584694 -274.649692) (xy 388.584694 -274.694142)
			(xy 388.68477 -274.794218)
		)
		(stroke
			(width 0)
			(type solid)
		)
		(fill yes)
		(layer "In2.Cu")
		(net "M_I_CPU0_SB_DQ<2>")
	)
	(gr_poly
		(pts
			(xy 388.784846 -273.47799) (xy 388.68477 -273.377914) (xy 388.584694 -273.47799) (xy 388.584694 -273.52244)
			(xy 388.784846 -273.52244)
		)
		(stroke
			(width 0)
			(type solid)
		)
		(fill yes)
		(layer "In2.Cu")
		(net "M_I_CPU0_SB_CB<1>")
	)
	(gr_poly
		(pts
			(xy 388.784846 -273.07413) (xy 388.784846 -273.02968) (xy 388.584694 -273.02968) (xy 388.584694 -273.07413)
			(xy 388.68477 -273.174206)
		)
		(stroke
			(width 0)
			(type solid)
		)
		(fill yes)
		(layer "In2.Cu")
		(net "M_I_CPU0_SB_CB<2>")
	)
	(gr_poly
		(pts
			(xy 388.784846 -271.857724) (xy 388.68477 -271.757902) (xy 388.584694 -271.857724) (xy 388.584694 -271.905476)
			(xy 388.784846 -271.905476)
		)
		(stroke
			(width 0)
			(type solid)
		)
		(fill yes)
		(layer "In2.Cu")
		(net "M_I_CPU0_SB_DQS_DN<4>")
	)
	(gr_poly
		(pts
			(xy 388.784846 -271.454372) (xy 388.784846 -271.40662) (xy 388.584694 -271.40662) (xy 388.584694 -271.454372)
			(xy 388.68477 -271.554194)
		)
		(stroke
			(width 0)
			(type solid)
		)
		(fill yes)
		(layer "In2.Cu")
		(net "M_I_CPU0_SB_DQS_DN<9>")
	)
	(gr_poly
		(pts
			(xy 388.784846 -270.237966) (xy 388.68477 -270.13789) (xy 388.584694 -270.237966) (xy 388.584694 -270.282416)
			(xy 388.784846 -270.282416)
		)
		(stroke
			(width 0)
			(type solid)
		)
		(fill yes)
		(layer "In2.Cu")
		(net "M_I_CPU0_SB_CB<5>")
	)
	(gr_poly
		(pts
			(xy 388.784846 -269.834106) (xy 388.784846 -269.789656) (xy 388.584694 -269.789656) (xy 388.584694 -269.834106)
			(xy 388.68477 -269.934182)
		)
		(stroke
			(width 0)
			(type solid)
		)
		(fill yes)
		(layer "In2.Cu")
		(net "M_I_CPU0_SB_CB<6>")
	)
	(gr_poly
		(pts
			(xy 388.784846 -266.997942) (xy 388.68477 -266.897866) (xy 388.584694 -266.997942) (xy 388.584694 -267.042392)
			(xy 388.784846 -267.042392)
		)
		(stroke
			(width 0)
			(type solid)
		)
		(fill yes)
		(layer "In2.Cu")
		(net "M_I_CPU0_SA_RSP<0>")
	)
	(gr_poly
		(pts
			(xy 388.784846 -266.594082) (xy 388.784846 -266.549632) (xy 388.584694 -266.549632) (xy 388.584694 -266.594082)
			(xy 388.68477 -266.694158)
		)
		(stroke
			(width 0)
			(type solid)
		)
		(fill yes)
		(layer "In2.Cu")
		(net "M_I_CPU0_SB_CS_N<1>")
	)
	(gr_poly
		(pts
			(xy 388.784846 -265.37793) (xy 388.68477 -265.277854) (xy 388.584694 -265.37793) (xy 388.584694 -265.42238)
			(xy 388.784846 -265.42238)
		)
		(stroke
			(width 0)
			(type solid)
		)
		(fill yes)
		(layer "In2.Cu")
		(net "M_I_CPU0_SB_PAR")
	)
	(gr_poly
		(pts
			(xy 388.784846 -263.757918) (xy 388.68477 -263.657842) (xy 388.584694 -263.757918) (xy 388.584694 -263.802368)
			(xy 388.784846 -263.802368)
		)
		(stroke
			(width 0)
			(type solid)
		)
		(fill yes)
		(layer "In2.Cu")
		(net "M_I_CPU0_SB_CA<4>")
	)
	(gr_poly
		(pts
			(xy 388.784846 -263.354058) (xy 388.784846 -263.309608) (xy 388.584694 -263.309608) (xy 388.584694 -263.354058)
			(xy 388.68477 -263.454134)
		)
		(stroke
			(width 0)
			(type solid)
		)
		(fill yes)
		(layer "In2.Cu")
		(net "M_I_CPU0_SB_CA<3>")
	)
	(gr_poly
		(pts
			(xy 388.784846 -262.137906) (xy 388.68477 -262.03783) (xy 388.584694 -262.137906) (xy 388.584694 -262.182356)
			(xy 388.784846 -262.182356)
		)
		(stroke
			(width 0)
			(type solid)
		)
		(fill yes)
		(layer "In2.Cu")
		(net "M_I_CPU0_SB_CA<0>")
	)
	(gr_poly
		(pts
			(xy 388.874254 -222.264732) (xy 388.8359 -222.24238) (xy 388.699248 -222.278956) (xy 388.735824 -222.415608)
			(xy 388.774432 -222.43796)
		)
		(stroke
			(width 0)
			(type solid)
		)
		(fill yes)
		(layer "In2.Cu")
		(net "M_I_CPU0_SA_DQ<0>")
	)
	(gr_poly
		(pts
			(xy 388.874508 -223.884744) (xy 388.836154 -223.862392) (xy 388.699502 -223.898968) (xy 388.736078 -224.03562)
			(xy 388.774686 -224.057972)
		)
		(stroke
			(width 0)
			(type solid)
		)
		(fill yes)
		(layer "In2.Cu")
		(net "M_I_CPU0_SA_DQ<1>")
	)
	(gr_poly
		(pts
			(xy 388.876794 -227.126292) (xy 388.835646 -227.10267) (xy 388.698994 -227.139246) (xy 388.73557 -227.275644)
			(xy 388.776972 -227.29952)
		)
		(stroke
			(width 0)
			(type solid)
		)
		(fill yes)
		(layer "In2.Cu")
		(net "M_I_CPU0_SA_DQS_DN<5>")
	)
	(gr_poly
		(pts
			(xy 388.876794 -225.50628) (xy 388.835646 -225.482404) (xy 388.698994 -225.519234) (xy 388.73557 -225.655632)
			(xy 388.776972 -225.679508)
		)
		(stroke
			(width 0)
			(type solid)
		)
		(fill yes)
		(layer "In2.Cu")
		(net "M_I_CPU0_SA_DQS_DP<0>")
	)
	(gr_poly
		(pts
			(xy 388.955026 -256.432558) (xy 388.955026 -256.384806) (xy 388.754874 -256.384806) (xy 388.754874 -256.432558)
			(xy 388.85495 -256.53238)
		)
		(stroke
			(width 0)
			(type solid)
		)
		(fill yes)
		(layer "In2.Cu")
		(net "M_I_CPU0_CLK_DN<0>")
	)
	(gr_poly
		(pts
			(xy 388.955026 -255.216152) (xy 388.85495 -255.116076) (xy 388.754874 -255.216152) (xy 388.754874 -255.260602)
			(xy 388.955026 -255.260602)
		)
		(stroke
			(width 0)
			(type solid)
		)
		(fill yes)
		(layer "In2.Cu")
		(net "M_I_CPU0_SA_CA<6>")
	)
	(gr_poly
		(pts
			(xy 388.955026 -254.812292) (xy 388.955026 -254.767842) (xy 388.754874 -254.767842) (xy 388.754874 -254.812292)
			(xy 388.85495 -254.912368)
		)
		(stroke
			(width 0)
			(type solid)
		)
		(fill yes)
		(layer "In2.Cu")
		(net "M_I_CPU0_SA_CA<5>")
	)
	(gr_poly
		(pts
			(xy 388.955026 -253.59614) (xy 388.85495 -253.496064) (xy 388.754874 -253.59614) (xy 388.754874 -253.64059)
			(xy 388.955026 -253.64059)
		)
		(stroke
			(width 0)
			(type solid)
		)
		(fill yes)
		(layer "In2.Cu")
		(net "M_I_CPU0_SA_CA<2>")
	)
	(gr_poly
		(pts
			(xy 388.955026 -253.19228) (xy 388.955026 -253.14783) (xy 388.754874 -253.14783) (xy 388.754874 -253.19228)
			(xy 388.85495 -253.292356)
		)
		(stroke
			(width 0)
			(type solid)
		)
		(fill yes)
		(layer "In2.Cu")
		(net "M_I_CPU0_SA_CA<1>")
	)
	(gr_poly
		(pts
			(xy 388.955026 -251.976128) (xy 388.85495 -251.876052) (xy 388.754874 -251.976128) (xy 388.754874 -252.020578)
			(xy 388.955026 -252.020578)
		)
		(stroke
			(width 0)
			(type solid)
		)
		(fill yes)
		(layer "In2.Cu")
		(net "M_I_CPU0_SA_CS_N<1>")
	)
	(gr_poly
		(pts
			(xy 388.955026 -250.356116) (xy 388.85495 -250.25604) (xy 388.754874 -250.356116) (xy 388.754874 -250.400566)
			(xy 388.955026 -250.400566)
		)
		(stroke
			(width 0)
			(type solid)
		)
		(fill yes)
		(layer "In2.Cu")
		(net "M_I_CPU0_ALERT_R_N")
	)
	(gr_poly
		(pts
			(xy 388.955026 -248.736104) (xy 388.85495 -248.636028) (xy 388.754874 -248.736104) (xy 388.754874 -248.780554)
			(xy 388.955026 -248.780554)
		)
		(stroke
			(width 0)
			(type solid)
		)
		(fill yes)
		(layer "In2.Cu")
		(net "M_I_CPU0_SA_CB<5>")
	)
	(gr_poly
		(pts
			(xy 388.955026 -248.332244) (xy 388.955026 -248.287794) (xy 388.754874 -248.287794) (xy 388.754874 -248.332244)
			(xy 388.85495 -248.43232)
		)
		(stroke
			(width 0)
			(type solid)
		)
		(fill yes)
		(layer "In2.Cu")
		(net "M_I_CPU0_SA_CB<6>")
	)
	(gr_poly
		(pts
			(xy 388.955026 -247.115838) (xy 388.85495 -247.016016) (xy 388.754874 -247.115838) (xy 388.754874 -247.16359)
			(xy 388.955026 -247.16359)
		)
		(stroke
			(width 0)
			(type solid)
		)
		(fill yes)
		(layer "In2.Cu")
		(net "M_I_CPU0_SA_DQS_DN<9>")
	)
	(gr_poly
		(pts
			(xy 388.955026 -246.712486) (xy 388.955026 -246.664734) (xy 388.754874 -246.664734) (xy 388.754874 -246.712486)
			(xy 388.85495 -246.812308)
		)
		(stroke
			(width 0)
			(type solid)
		)
		(fill yes)
		(layer "In2.Cu")
		(net "M_I_CPU0_SA_DQS_DN<4>")
	)
	(gr_poly
		(pts
			(xy 388.955026 -245.49608) (xy 388.85495 -245.396004) (xy 388.754874 -245.49608) (xy 388.754874 -245.54053)
			(xy 388.955026 -245.54053)
		)
		(stroke
			(width 0)
			(type solid)
		)
		(fill yes)
		(layer "In2.Cu")
		(net "M_I_CPU0_SA_CB<1>")
	)
	(gr_poly
		(pts
			(xy 388.955026 -245.09222) (xy 388.955026 -245.04777) (xy 388.754874 -245.04777) (xy 388.754874 -245.09222)
			(xy 388.85495 -245.192296)
		)
		(stroke
			(width 0)
			(type solid)
		)
		(fill yes)
		(layer "In2.Cu")
		(net "M_I_CPU0_SA_CB<2>")
	)
	(gr_poly
		(pts
			(xy 388.955026 -243.876068) (xy 388.85495 -243.775992) (xy 388.754874 -243.876068) (xy 388.754874 -243.920518)
			(xy 388.955026 -243.920518)
		)
		(stroke
			(width 0)
			(type solid)
		)
		(fill yes)
		(layer "In2.Cu")
		(net "M_I_CPU0_SA_DQ<29>")
	)
	(gr_poly
		(pts
			(xy 388.955026 -243.472208) (xy 388.955026 -243.427758) (xy 388.754874 -243.427758) (xy 388.754874 -243.472208)
			(xy 388.85495 -243.572284)
		)
		(stroke
			(width 0)
			(type solid)
		)
		(fill yes)
		(layer "In2.Cu")
		(net "M_I_CPU0_SA_DQ<30>")
	)
	(gr_poly
		(pts
			(xy 388.955026 -242.255802) (xy 388.85495 -242.15598) (xy 388.754874 -242.255802) (xy 388.754874 -242.303554)
			(xy 388.955026 -242.303554)
		)
		(stroke
			(width 0)
			(type solid)
		)
		(fill yes)
		(layer "In2.Cu")
		(net "M_I_CPU0_SA_DQS_DN<8>")
	)
	(gr_poly
		(pts
			(xy 388.955026 -241.85245) (xy 388.955026 -241.804698) (xy 388.754874 -241.804698) (xy 388.754874 -241.85245)
			(xy 388.85495 -241.952272)
		)
		(stroke
			(width 0)
			(type solid)
		)
		(fill yes)
		(layer "In2.Cu")
		(net "M_I_CPU0_SA_DQS_DN<3>")
	)
	(gr_poly
		(pts
			(xy 388.955026 -240.636044) (xy 388.85495 -240.535968) (xy 388.754874 -240.636044) (xy 388.754874 -240.680494)
			(xy 388.955026 -240.680494)
		)
		(stroke
			(width 0)
			(type solid)
		)
		(fill yes)
		(layer "In2.Cu")
		(net "M_I_CPU0_SA_DQ<25>")
	)
	(gr_poly
		(pts
			(xy 388.955026 -240.232184) (xy 388.955026 -240.187734) (xy 388.754874 -240.187734) (xy 388.754874 -240.232184)
			(xy 388.85495 -240.33226)
		)
		(stroke
			(width 0)
			(type solid)
		)
		(fill yes)
		(layer "In2.Cu")
		(net "M_I_CPU0_SA_DQ<26>")
	)
	(gr_poly
		(pts
			(xy 388.955026 -239.016032) (xy 388.85495 -238.915956) (xy 388.754874 -239.016032) (xy 388.754874 -239.060482)
			(xy 388.955026 -239.060482)
		)
		(stroke
			(width 0)
			(type solid)
		)
		(fill yes)
		(layer "In2.Cu")
		(net "M_I_CPU0_SA_DQ<21>")
	)
	(gr_poly
		(pts
			(xy 388.955026 -238.612172) (xy 388.955026 -238.567722) (xy 388.754874 -238.567722) (xy 388.754874 -238.612172)
			(xy 388.85495 -238.712248)
		)
		(stroke
			(width 0)
			(type solid)
		)
		(fill yes)
		(layer "In2.Cu")
		(net "M_I_CPU0_SA_DQ<22>")
	)
	(gr_poly
		(pts
			(xy 388.955026 -237.395766) (xy 388.85495 -237.295944) (xy 388.754874 -237.395766) (xy 388.754874 -237.443518)
			(xy 388.955026 -237.443518)
		)
		(stroke
			(width 0)
			(type solid)
		)
		(fill yes)
		(layer "In2.Cu")
		(net "M_I_CPU0_SA_DQS_DN<7>")
	)
	(gr_poly
		(pts
			(xy 388.955026 -236.992414) (xy 388.955026 -236.944662) (xy 388.754874 -236.944662) (xy 388.754874 -236.992414)
			(xy 388.85495 -237.092236)
		)
		(stroke
			(width 0)
			(type solid)
		)
		(fill yes)
		(layer "In2.Cu")
		(net "M_I_CPU0_SA_DQS_DN<2>")
	)
	(gr_poly
		(pts
			(xy 388.955026 -235.776008) (xy 388.85495 -235.675932) (xy 388.754874 -235.776008) (xy 388.754874 -235.820458)
			(xy 388.955026 -235.820458)
		)
		(stroke
			(width 0)
			(type solid)
		)
		(fill yes)
		(layer "In2.Cu")
		(net "M_I_CPU0_SA_DQ<17>")
	)
	(gr_poly
		(pts
			(xy 388.955026 -235.372148) (xy 388.955026 -235.327698) (xy 388.754874 -235.327698) (xy 388.754874 -235.372148)
			(xy 388.85495 -235.472224)
		)
		(stroke
			(width 0)
			(type solid)
		)
		(fill yes)
		(layer "In2.Cu")
		(net "M_I_CPU0_SA_DQ<18>")
	)
	(gr_poly
		(pts
			(xy 388.955026 -234.155996) (xy 388.85495 -234.05592) (xy 388.754874 -234.155996) (xy 388.754874 -234.200446)
			(xy 388.955026 -234.200446)
		)
		(stroke
			(width 0)
			(type solid)
		)
		(fill yes)
		(layer "In2.Cu")
		(net "M_I_CPU0_SA_DQ<13>")
	)
	(gr_poly
		(pts
			(xy 388.955026 -233.752136) (xy 388.955026 -233.707686) (xy 388.754874 -233.707686) (xy 388.754874 -233.752136)
			(xy 388.85495 -233.852212)
		)
		(stroke
			(width 0)
			(type solid)
		)
		(fill yes)
		(layer "In2.Cu")
		(net "M_I_CPU0_SA_DQ<14>")
	)
	(gr_poly
		(pts
			(xy 388.955026 -232.53573) (xy 388.85495 -232.435908) (xy 388.754874 -232.53573) (xy 388.754874 -232.583482)
			(xy 388.955026 -232.583482)
		)
		(stroke
			(width 0)
			(type solid)
		)
		(fill yes)
		(layer "In2.Cu")
		(net "M_I_CPU0_SA_DQS_DN<6>")
	)
	(gr_poly
		(pts
			(xy 388.955026 -232.132378) (xy 388.955026 -232.084626) (xy 388.754874 -232.084626) (xy 388.754874 -232.132378)
			(xy 388.85495 -232.2322)
		)
		(stroke
			(width 0)
			(type solid)
		)
		(fill yes)
		(layer "In2.Cu")
		(net "M_I_CPU0_SA_DQS_DN<1>")
	)
	(gr_poly
		(pts
			(xy 388.955026 -230.915972) (xy 388.85495 -230.815896) (xy 388.754874 -230.915972) (xy 388.754874 -230.960422)
			(xy 388.955026 -230.960422)
		)
		(stroke
			(width 0)
			(type solid)
		)
		(fill yes)
		(layer "In2.Cu")
		(net "M_I_CPU0_SA_DQ<9>")
	)
	(gr_poly
		(pts
			(xy 388.955026 -230.512366) (xy 388.955026 -230.467916) (xy 388.754874 -230.467916) (xy 388.754874 -230.512366)
			(xy 388.85495 -230.612188)
		)
		(stroke
			(width 0)
			(type solid)
		)
		(fill yes)
		(layer "In2.Cu")
		(net "M_I_CPU0_SA_DQ<10>")
	)
	(gr_poly
		(pts
			(xy 388.955026 -229.29596) (xy 388.85495 -229.195884) (xy 388.754874 -229.29596) (xy 388.754874 -229.34041)
			(xy 388.955026 -229.34041)
		)
		(stroke
			(width 0)
			(type solid)
		)
		(fill yes)
		(layer "In2.Cu")
		(net "M_I_CPU0_SA_DQ<5>")
	)
	(gr_poly
		(pts
			(xy 388.955026 -228.892354) (xy 388.955026 -228.847904) (xy 388.754874 -228.847904) (xy 388.754874 -228.892354)
			(xy 388.85495 -228.99243)
		)
		(stroke
			(width 0)
			(type solid)
		)
		(fill yes)
		(layer "In2.Cu")
		(net "M_I_CPU0_SA_DQ<6>")
	)
	(gr_poly
		(pts
			(xy 389.010652 -227.809298) (xy 388.974076 -227.6729) (xy 388.932674 -227.649024) (xy 388.832852 -227.822252)
			(xy 388.874 -227.846128)
		)
		(stroke
			(width 0)
			(type solid)
		)
		(fill yes)
		(layer "In2.Cu")
		(net "M_I_CPU0_SA_DQS_DP<5>")
	)
	(gr_poly
		(pts
			(xy 389.010652 -226.189286) (xy 388.974076 -226.052888) (xy 388.932674 -226.029012) (xy 388.832852 -226.20224)
			(xy 388.874 -226.226116)
		)
		(stroke
			(width 0)
			(type solid)
		)
		(fill yes)
		(layer "In2.Cu")
		(net "M_I_CPU0_SA_DQS_DN<0>")
	)
	(gr_poly
		(pts
			(xy 389.010652 -224.569528) (xy 388.974076 -224.432876) (xy 388.935468 -224.410524) (xy 388.835646 -224.583752)
			(xy 388.874 -224.606104)
		)
		(stroke
			(width 0)
			(type solid)
		)
		(fill yes)
		(layer "In2.Cu")
		(net "M_I_CPU0_SA_DQ<3>")
	)
	(gr_poly
		(pts
			(xy 389.010906 -222.947992) (xy 388.97433 -222.81134) (xy 388.935976 -222.789242) (xy 388.8359 -222.96247)
			(xy 388.874508 -222.984568)
		)
		(stroke
			(width 0)
			(type solid)
		)
		(fill yes)
		(layer "In2.Cu")
		(net "M_I_CPU0_SA_DQ<2>")
	)
	(gr_poly
		(pts
			(xy 389.255 -293.324026) (xy 389.255 -293.279576) (xy 389.054848 -293.279576) (xy 389.054848 -293.324026)
			(xy 389.154924 -293.424102)
		)
		(stroke
			(width 0)
			(type solid)
		)
		(fill yes)
		(layer "In2.Cu")
		(net "M_I_CPU0_SB_DQ<31>")
	)
	(gr_poly
		(pts
			(xy 389.255 -292.107874) (xy 389.154924 -292.007798) (xy 389.054848 -292.107874) (xy 389.054848 -292.152324)
			(xy 389.255 -292.152324)
		)
		(stroke
			(width 0)
			(type solid)
		)
		(fill yes)
		(layer "In2.Cu")
		(net "M_I_CPU0_SB_DQ<28>")
	)
	(gr_poly
		(pts
			(xy 389.255 -291.704268) (xy 389.255 -291.656516) (xy 389.054848 -291.656516) (xy 389.054848 -291.704268)
			(xy 389.154924 -291.80409)
		)
		(stroke
			(width 0)
			(type solid)
		)
		(fill yes)
		(layer "In2.Cu")
		(net "M_I_CPU0_SB_DQS_DP<8>")
	)
	(gr_poly
		(pts
			(xy 389.255 -290.487608) (xy 389.154924 -290.387786) (xy 389.054848 -290.487608) (xy 389.054848 -290.53536)
			(xy 389.255 -290.53536)
		)
		(stroke
			(width 0)
			(type solid)
		)
		(fill yes)
		(layer "In2.Cu")
		(net "M_I_CPU0_SB_DQS_DP<3>")
	)
	(gr_poly
		(pts
			(xy 389.255 -290.084002) (xy 389.255 -290.039552) (xy 389.054848 -290.039552) (xy 389.054848 -290.084002)
			(xy 389.154924 -290.184078)
		)
		(stroke
			(width 0)
			(type solid)
		)
		(fill yes)
		(layer "In2.Cu")
		(net "M_I_CPU0_SB_DQ<27>")
	)
	(gr_poly
		(pts
			(xy 389.255 -288.86785) (xy 389.154924 -288.767774) (xy 389.054848 -288.86785) (xy 389.054848 -288.9123)
			(xy 389.255 -288.9123)
		)
		(stroke
			(width 0)
			(type solid)
		)
		(fill yes)
		(layer "In2.Cu")
		(net "M_I_CPU0_SB_DQ<24>")
	)
	(gr_poly
		(pts
			(xy 389.255 -288.464244) (xy 389.255 -288.419794) (xy 389.054848 -288.419794) (xy 389.054848 -288.464244)
			(xy 389.154924 -288.56432)
		)
		(stroke
			(width 0)
			(type solid)
		)
		(fill yes)
		(layer "In2.Cu")
		(net "M_I_CPU0_SB_DQ<23>")
	)
	(gr_poly
		(pts
			(xy 389.255 -287.247838) (xy 389.154924 -287.148016) (xy 389.054848 -287.247838) (xy 389.054848 -287.292288)
			(xy 389.255 -287.292288)
		)
		(stroke
			(width 0)
			(type solid)
		)
		(fill yes)
		(layer "In2.Cu")
		(net "M_I_CPU0_SB_DQ<20>")
	)
	(gr_poly
		(pts
			(xy 389.255 -286.844232) (xy 389.255 -286.79648) (xy 389.054848 -286.79648) (xy 389.054848 -286.844232)
			(xy 389.154924 -286.944308)
		)
		(stroke
			(width 0)
			(type solid)
		)
		(fill yes)
		(layer "In2.Cu")
		(net "M_I_CPU0_SB_DQS_DP<7>")
	)
	(gr_poly
		(pts
			(xy 389.255 -285.627826) (xy 389.154924 -285.528004) (xy 389.054848 -285.627826) (xy 389.054848 -285.675578)
			(xy 389.255 -285.675578)
		)
		(stroke
			(width 0)
			(type solid)
		)
		(fill yes)
		(layer "In2.Cu")
		(net "M_I_CPU0_SB_DQS_DP<2>")
	)
	(gr_poly
		(pts
			(xy 389.255 -285.22422) (xy 389.255 -285.17977) (xy 389.054848 -285.17977) (xy 389.054848 -285.22422)
			(xy 389.154924 -285.324296)
		)
		(stroke
			(width 0)
			(type solid)
		)
		(fill yes)
		(layer "In2.Cu")
		(net "M_I_CPU0_SB_DQ<19>")
	)
	(gr_poly
		(pts
			(xy 389.255 -284.008068) (xy 389.154924 -283.907992) (xy 389.054848 -284.008068) (xy 389.054848 -284.052518)
			(xy 389.255 -284.052518)
		)
		(stroke
			(width 0)
			(type solid)
		)
		(fill yes)
		(layer "In2.Cu")
		(net "M_I_CPU0_SB_DQ<16>")
	)
	(gr_poly
		(pts
			(xy 389.255 -283.604208) (xy 389.255 -283.559758) (xy 389.054848 -283.559758) (xy 389.054848 -283.604208)
			(xy 389.154924 -283.704284)
		)
		(stroke
			(width 0)
			(type solid)
		)
		(fill yes)
		(layer "In2.Cu")
		(net "M_I_CPU0_SB_DQ<15>")
	)
	(gr_poly
		(pts
			(xy 389.255 -282.388056) (xy 389.154924 -282.28798) (xy 389.054848 -282.388056) (xy 389.054848 -282.432506)
			(xy 389.255 -282.432506)
		)
		(stroke
			(width 0)
			(type solid)
		)
		(fill yes)
		(layer "In2.Cu")
		(net "M_I_CPU0_SB_DQ<12>")
	)
	(gr_poly
		(pts
			(xy 389.255 -281.98445) (xy 389.255 -281.936698) (xy 389.054848 -281.936698) (xy 389.054848 -281.98445)
			(xy 389.154924 -282.084272)
		)
		(stroke
			(width 0)
			(type solid)
		)
		(fill yes)
		(layer "In2.Cu")
		(net "M_I_CPU0_SB_DQS_DP<6>")
	)
	(gr_poly
		(pts
			(xy 389.255 -280.76779) (xy 389.154924 -280.667968) (xy 389.054848 -280.76779) (xy 389.054848 -280.815542)
			(xy 389.255 -280.815542)
		)
		(stroke
			(width 0)
			(type solid)
		)
		(fill yes)
		(layer "In2.Cu")
		(net "M_I_CPU0_SB_DQS_DP<1>")
	)
	(gr_poly
		(pts
			(xy 389.255 -280.364184) (xy 389.255 -280.319734) (xy 389.054848 -280.319734) (xy 389.054848 -280.364184)
			(xy 389.154924 -280.46426)
		)
		(stroke
			(width 0)
			(type solid)
		)
		(fill yes)
		(layer "In2.Cu")
		(net "M_I_CPU0_SB_DQ<11>")
	)
	(gr_poly
		(pts
			(xy 389.255 -279.148032) (xy 389.154924 -279.047956) (xy 389.054848 -279.148032) (xy 389.054848 -279.192482)
			(xy 389.255 -279.192482)
		)
		(stroke
			(width 0)
			(type solid)
		)
		(fill yes)
		(layer "In2.Cu")
		(net "M_I_CPU0_SB_DQ<8>")
	)
	(gr_poly
		(pts
			(xy 389.255 -278.744172) (xy 389.255 -278.699722) (xy 389.054848 -278.699722) (xy 389.054848 -278.744172)
			(xy 389.154924 -278.844248)
		)
		(stroke
			(width 0)
			(type solid)
		)
		(fill yes)
		(layer "In2.Cu")
		(net "M_I_CPU0_SB_DQ<7>")
	)
	(gr_poly
		(pts
			(xy 389.255 -277.52802) (xy 389.154924 -277.427944) (xy 389.054848 -277.52802) (xy 389.054848 -277.57247)
			(xy 389.255 -277.57247)
		)
		(stroke
			(width 0)
			(type solid)
		)
		(fill yes)
		(layer "In2.Cu")
		(net "M_I_CPU0_SB_DQ<4>")
	)
	(gr_poly
		(pts
			(xy 389.255 -277.124414) (xy 389.255 -277.076662) (xy 389.054848 -277.076662) (xy 389.054848 -277.124414)
			(xy 389.154924 -277.224236)
		)
		(stroke
			(width 0)
			(type solid)
		)
		(fill yes)
		(layer "In2.Cu")
		(net "M_I_CPU0_SB_DQS_DP<5>")
	)
	(gr_poly
		(pts
			(xy 389.255 -275.907754) (xy 389.154924 -275.807932) (xy 389.054848 -275.907754) (xy 389.054848 -275.955506)
			(xy 389.255 -275.955506)
		)
		(stroke
			(width 0)
			(type solid)
		)
		(fill yes)
		(layer "In2.Cu")
		(net "M_I_CPU0_SB_DQS_DP<0>")
	)
	(gr_poly
		(pts
			(xy 389.255 -275.504148) (xy 389.255 -275.459698) (xy 389.054848 -275.459698) (xy 389.054848 -275.504148)
			(xy 389.154924 -275.604224)
		)
		(stroke
			(width 0)
			(type solid)
		)
		(fill yes)
		(layer "In2.Cu")
		(net "M_I_CPU0_SB_DQ<3>")
	)
	(gr_poly
		(pts
			(xy 389.255 -274.287996) (xy 389.154924 -274.18792) (xy 389.054848 -274.287996) (xy 389.054848 -274.332446)
			(xy 389.255 -274.332446)
		)
		(stroke
			(width 0)
			(type solid)
		)
		(fill yes)
		(layer "In2.Cu")
		(net "M_I_CPU0_SB_DQ<0>")
	)
	(gr_poly
		(pts
			(xy 389.255 -273.884136) (xy 389.255 -273.839686) (xy 389.054848 -273.839686) (xy 389.054848 -273.884136)
			(xy 389.154924 -273.984212)
		)
		(stroke
			(width 0)
			(type solid)
		)
		(fill yes)
		(layer "In2.Cu")
		(net "M_I_CPU0_SB_CB<3>")
	)
	(gr_poly
		(pts
			(xy 389.255 -272.667984) (xy 389.154924 -272.567908) (xy 389.054848 -272.667984) (xy 389.054848 -272.712434)
			(xy 389.255 -272.712434)
		)
		(stroke
			(width 0)
			(type solid)
		)
		(fill yes)
		(layer "In2.Cu")
		(net "M_I_CPU0_SB_CB<0>")
	)
	(gr_poly
		(pts
			(xy 389.255 -272.264378) (xy 389.255 -272.216626) (xy 389.054848 -272.216626) (xy 389.054848 -272.264378)
			(xy 389.154924 -272.3642)
		)
		(stroke
			(width 0)
			(type solid)
		)
		(fill yes)
		(layer "In2.Cu")
		(net "M_I_CPU0_SB_DQS_DP<4>")
	)
	(gr_poly
		(pts
			(xy 389.255 -271.047718) (xy 389.154924 -270.947896) (xy 389.054848 -271.047718) (xy 389.054848 -271.09547)
			(xy 389.255 -271.09547)
		)
		(stroke
			(width 0)
			(type solid)
		)
		(fill yes)
		(layer "In2.Cu")
		(net "M_I_CPU0_SB_DQS_DP<9>")
	)
	(gr_poly
		(pts
			(xy 389.255 -270.644112) (xy 389.255 -270.599662) (xy 389.054848 -270.599662) (xy 389.054848 -270.644112)
			(xy 389.154924 -270.744188)
		)
		(stroke
			(width 0)
			(type solid)
		)
		(fill yes)
		(layer "In2.Cu")
		(net "M_I_CPU0_SB_CB<7>")
	)
	(gr_poly
		(pts
			(xy 389.255 -269.42796) (xy 389.154924 -269.327884) (xy 389.054848 -269.42796) (xy 389.054848 -269.47241)
			(xy 389.255 -269.47241)
		)
		(stroke
			(width 0)
			(type solid)
		)
		(fill yes)
		(layer "In2.Cu")
		(net "M_I_CPU0_SB_CB<4>")
	)
	(gr_poly
		(pts
			(xy 389.255 -267.404088) (xy 389.255 -267.359638) (xy 389.054848 -267.359638) (xy 389.054848 -267.404088)
			(xy 389.154924 -267.504164)
		)
		(stroke
			(width 0)
			(type solid)
		)
		(fill yes)
		(layer "In2.Cu")
		(net "M_I_CPU0_SB_RSP<0>")
	)
	(gr_poly
		(pts
			(xy 389.255 -265.784076) (xy 389.255 -265.739626) (xy 389.054848 -265.739626) (xy 389.054848 -265.784076)
			(xy 389.154924 -265.884152)
		)
		(stroke
			(width 0)
			(type solid)
		)
		(fill yes)
		(layer "In2.Cu")
		(net "M_I_CPU0_SB_CS_N<0>")
	)
	(gr_poly
		(pts
			(xy 389.255 -264.567924) (xy 389.154924 -264.467848) (xy 389.054848 -264.567924) (xy 389.054848 -264.612374)
			(xy 389.255 -264.612374)
		)
		(stroke
			(width 0)
			(type solid)
		)
		(fill yes)
		(layer "In2.Cu")
		(net "M_I_CPU0_SB_CA<6>")
	)
	(gr_poly
		(pts
			(xy 389.255 -264.164064) (xy 389.255 -264.119614) (xy 389.054848 -264.119614) (xy 389.054848 -264.164064)
			(xy 389.154924 -264.26414)
		)
		(stroke
			(width 0)
			(type solid)
		)
		(fill yes)
		(layer "In2.Cu")
		(net "M_I_CPU0_SB_CA<5>")
	)
	(gr_poly
		(pts
			(xy 389.255 -262.947912) (xy 389.154924 -262.847836) (xy 389.054848 -262.947912) (xy 389.054848 -262.992362)
			(xy 389.255 -262.992362)
		)
		(stroke
			(width 0)
			(type solid)
		)
		(fill yes)
		(layer "In2.Cu")
		(net "M_I_CPU0_SB_CA<2>")
	)
	(gr_poly
		(pts
			(xy 389.255 -262.544052) (xy 389.255 -262.499602) (xy 389.054848 -262.499602) (xy 389.054848 -262.544052)
			(xy 389.154924 -262.644128)
		)
		(stroke
			(width 0)
			(type solid)
		)
		(fill yes)
		(layer "In2.Cu")
		(net "M_I_CPU0_SB_CA<1>")
	)
	(gr_poly
		(pts
			(xy 389.344916 -227.934012) (xy 389.306308 -227.911914) (xy 389.169656 -227.94849) (xy 389.206232 -228.085142)
			(xy 389.24484 -228.10724)
		)
		(stroke
			(width 0)
			(type solid)
		)
		(fill yes)
		(layer "In2.Cu")
		(net "M_I_CPU0_SA_DQ<4>")
	)
	(gr_poly
		(pts
			(xy 389.344916 -223.074738) (xy 389.306562 -223.052386) (xy 389.16991 -223.088962) (xy 389.206486 -223.225614)
			(xy 389.245094 -223.247966)
		)
		(stroke
			(width 0)
			(type solid)
		)
		(fill yes)
		(layer "In2.Cu")
		(net "M_I_CPU0_SA_DQ<1>")
	)
	(gr_poly
		(pts
			(xy 389.347964 -226.315016) (xy 389.306562 -226.29114) (xy 389.16991 -226.32797) (xy 389.20674 -226.464368)
			(xy 389.247888 -226.488244)
		)
		(stroke
			(width 0)
			(type solid)
		)
		(fill yes)
		(layer "In2.Cu")
		(net "M_I_CPU0_SA_DQS_DN<5>")
	)
	(gr_poly
		(pts
			(xy 389.347964 -224.695004) (xy 389.306562 -224.671128) (xy 389.16991 -224.707704) (xy 389.20674 -224.844356)
			(xy 389.247888 -224.868232)
		)
		(stroke
			(width 0)
			(type solid)
		)
		(fill yes)
		(layer "In2.Cu")
		(net "M_I_CPU0_SA_DQS_DP<0>")
	)
	(gr_poly
		(pts
			(xy 389.424926 -256.025904) (xy 389.32485 -255.926082) (xy 389.224774 -256.025904) (xy 389.224774 -256.073656)
			(xy 389.424926 -256.073656)
		)
		(stroke
			(width 0)
			(type solid)
		)
		(fill yes)
		(layer "In2.Cu")
		(net "M_I_CPU0_CLK_DP<0>")
	)
	(gr_poly
		(pts
			(xy 389.424926 -255.622298) (xy 389.424926 -255.577848) (xy 389.224774 -255.577848) (xy 389.224774 -255.622298)
			(xy 389.32485 -255.722374)
		)
		(stroke
			(width 0)
			(type solid)
		)
		(fill yes)
		(layer "In2.Cu")
		(net "M_I_CPU0_SA_PAR")
	)
	(gr_poly
		(pts
			(xy 389.424926 -254.406146) (xy 389.32485 -254.30607) (xy 389.224774 -254.406146) (xy 389.224774 -254.450596)
			(xy 389.424926 -254.450596)
		)
		(stroke
			(width 0)
			(type solid)
		)
		(fill yes)
		(layer "In2.Cu")
		(net "M_I_CPU0_SA_CA<4>")
	)
	(gr_poly
		(pts
			(xy 389.424926 -254.002286) (xy 389.424926 -253.957836) (xy 389.224774 -253.957836) (xy 389.224774 -254.002286)
			(xy 389.32485 -254.102362)
		)
		(stroke
			(width 0)
			(type solid)
		)
		(fill yes)
		(layer "In2.Cu")
		(net "M_I_CPU0_SA_CA<3>")
	)
	(gr_poly
		(pts
			(xy 389.424926 -252.786134) (xy 389.32485 -252.686058) (xy 389.224774 -252.786134) (xy 389.224774 -252.830584)
			(xy 389.424926 -252.830584)
		)
		(stroke
			(width 0)
			(type solid)
		)
		(fill yes)
		(layer "In2.Cu")
		(net "M_I_CPU0_SA_CA<0>")
	)
	(gr_poly
		(pts
			(xy 389.424926 -251.166122) (xy 389.32485 -251.066046) (xy 389.224774 -251.166122) (xy 389.224774 -251.210572)
			(xy 389.424926 -251.210572)
		)
		(stroke
			(width 0)
			(type solid)
		)
		(fill yes)
		(layer "In2.Cu")
		(net "M_I_CPU0_SA_CS_N<0>")
	)
	(gr_poly
		(pts
			(xy 389.424926 -250.762262) (xy 389.424926 -250.717812) (xy 389.224774 -250.717812) (xy 389.224774 -250.762262)
			(xy 389.32485 -250.862338)
		)
		(stroke
			(width 0)
			(type solid)
		)
		(fill yes)
		(layer "In2.Cu")
		(net "M_I_CPU0_RESET_N")
	)
	(gr_poly
		(pts
			(xy 389.424926 -249.14225) (xy 389.424926 -249.0978) (xy 389.224774 -249.0978) (xy 389.224774 -249.14225)
			(xy 389.32485 -249.242326)
		)
		(stroke
			(width 0)
			(type solid)
		)
		(fill yes)
		(layer "In2.Cu")
		(net "M_I_CPU0_SA_CB<7>")
	)
	(gr_poly
		(pts
			(xy 389.424926 -247.926098) (xy 389.32485 -247.826022) (xy 389.224774 -247.926098) (xy 389.224774 -247.970548)
			(xy 389.424926 -247.970548)
		)
		(stroke
			(width 0)
			(type solid)
		)
		(fill yes)
		(layer "In2.Cu")
		(net "M_I_CPU0_SA_CB<4>")
	)
	(gr_poly
		(pts
			(xy 389.424926 -247.522492) (xy 389.424926 -247.47474) (xy 389.224774 -247.47474) (xy 389.224774 -247.522492)
			(xy 389.32485 -247.622314)
		)
		(stroke
			(width 0)
			(type solid)
		)
		(fill yes)
		(layer "In2.Cu")
		(net "M_I_CPU0_SA_DQS_DP<9>")
	)
	(gr_poly
		(pts
			(xy 389.424926 -246.305832) (xy 389.32485 -246.20601) (xy 389.224774 -246.305832) (xy 389.224774 -246.353584)
			(xy 389.424926 -246.353584)
		)
		(stroke
			(width 0)
			(type solid)
		)
		(fill yes)
		(layer "In2.Cu")
		(net "M_I_CPU0_SA_DQS_DP<4>")
	)
	(gr_poly
		(pts
			(xy 389.424926 -245.902226) (xy 389.424926 -245.857776) (xy 389.224774 -245.857776) (xy 389.224774 -245.902226)
			(xy 389.32485 -246.002302)
		)
		(stroke
			(width 0)
			(type solid)
		)
		(fill yes)
		(layer "In2.Cu")
		(net "M_I_CPU0_SA_CB<3>")
	)
	(gr_poly
		(pts
			(xy 389.424926 -244.686074) (xy 389.32485 -244.585998) (xy 389.224774 -244.686074) (xy 389.224774 -244.730524)
			(xy 389.424926 -244.730524)
		)
		(stroke
			(width 0)
			(type solid)
		)
		(fill yes)
		(layer "In2.Cu")
		(net "M_I_CPU0_SA_CB<0>")
	)
	(gr_poly
		(pts
			(xy 389.424926 -244.282214) (xy 389.424926 -244.237764) (xy 389.224774 -244.237764) (xy 389.224774 -244.282214)
			(xy 389.32485 -244.38229)
		)
		(stroke
			(width 0)
			(type solid)
		)
		(fill yes)
		(layer "In2.Cu")
		(net "M_I_CPU0_SA_DQ<31>")
	)
	(gr_poly
		(pts
			(xy 389.424926 -243.066062) (xy 389.32485 -242.965986) (xy 389.224774 -243.066062) (xy 389.224774 -243.110512)
			(xy 389.424926 -243.110512)
		)
		(stroke
			(width 0)
			(type solid)
		)
		(fill yes)
		(layer "In2.Cu")
		(net "M_I_CPU0_SA_DQ<28>")
	)
	(gr_poly
		(pts
			(xy 389.424926 -242.662456) (xy 389.424926 -242.614704) (xy 389.224774 -242.614704) (xy 389.224774 -242.662456)
			(xy 389.32485 -242.762278)
		)
		(stroke
			(width 0)
			(type solid)
		)
		(fill yes)
		(layer "In2.Cu")
		(net "M_I_CPU0_SA_DQS_DP<8>")
	)
	(gr_poly
		(pts
			(xy 389.424926 -241.445796) (xy 389.32485 -241.345974) (xy 389.224774 -241.445796) (xy 389.224774 -241.493548)
			(xy 389.424926 -241.493548)
		)
		(stroke
			(width 0)
			(type solid)
		)
		(fill yes)
		(layer "In2.Cu")
		(net "M_I_CPU0_SA_DQS_DP<3>")
	)
	(gr_poly
		(pts
			(xy 389.424926 -241.04219) (xy 389.424926 -240.99774) (xy 389.224774 -240.99774) (xy 389.224774 -241.04219)
			(xy 389.32485 -241.142266)
		)
		(stroke
			(width 0)
			(type solid)
		)
		(fill yes)
		(layer "In2.Cu")
		(net "M_I_CPU0_SA_DQ<27>")
	)
	(gr_poly
		(pts
			(xy 389.424926 -239.826038) (xy 389.32485 -239.725962) (xy 389.224774 -239.826038) (xy 389.224774 -239.870488)
			(xy 389.424926 -239.870488)
		)
		(stroke
			(width 0)
			(type solid)
		)
		(fill yes)
		(layer "In2.Cu")
		(net "M_I_CPU0_SA_DQ<24>")
	)
	(gr_poly
		(pts
			(xy 389.424926 -239.422178) (xy 389.424926 -239.377728) (xy 389.224774 -239.377728) (xy 389.224774 -239.422178)
			(xy 389.32485 -239.522254)
		)
		(stroke
			(width 0)
			(type solid)
		)
		(fill yes)
		(layer "In2.Cu")
		(net "M_I_CPU0_SA_DQ<23>")
	)
	(gr_poly
		(pts
			(xy 389.424926 -238.206026) (xy 389.32485 -238.10595) (xy 389.224774 -238.206026) (xy 389.224774 -238.250476)
			(xy 389.424926 -238.250476)
		)
		(stroke
			(width 0)
			(type solid)
		)
		(fill yes)
		(layer "In2.Cu")
		(net "M_I_CPU0_SA_DQ<20>")
	)
	(gr_poly
		(pts
			(xy 389.424926 -237.80242) (xy 389.424926 -237.754668) (xy 389.224774 -237.754668) (xy 389.224774 -237.80242)
			(xy 389.32485 -237.902242)
		)
		(stroke
			(width 0)
			(type solid)
		)
		(fill yes)
		(layer "In2.Cu")
		(net "M_I_CPU0_SA_DQS_DP<7>")
	)
	(gr_poly
		(pts
			(xy 389.424926 -236.58576) (xy 389.32485 -236.485938) (xy 389.224774 -236.58576) (xy 389.224774 -236.633512)
			(xy 389.424926 -236.633512)
		)
		(stroke
			(width 0)
			(type solid)
		)
		(fill yes)
		(layer "In2.Cu")
		(net "M_I_CPU0_SA_DQS_DP<2>")
	)
	(gr_poly
		(pts
			(xy 389.424926 -236.182154) (xy 389.424926 -236.137704) (xy 389.224774 -236.137704) (xy 389.224774 -236.182154)
			(xy 389.32485 -236.28223)
		)
		(stroke
			(width 0)
			(type solid)
		)
		(fill yes)
		(layer "In2.Cu")
		(net "M_I_CPU0_SA_DQ<19>")
	)
	(gr_poly
		(pts
			(xy 389.424926 -234.966002) (xy 389.32485 -234.865926) (xy 389.224774 -234.966002) (xy 389.224774 -235.010452)
			(xy 389.424926 -235.010452)
		)
		(stroke
			(width 0)
			(type solid)
		)
		(fill yes)
		(layer "In2.Cu")
		(net "M_I_CPU0_SA_DQ<16>")
	)
	(gr_poly
		(pts
			(xy 389.424926 -234.562142) (xy 389.424926 -234.517692) (xy 389.224774 -234.517692) (xy 389.224774 -234.562142)
			(xy 389.32485 -234.662218)
		)
		(stroke
			(width 0)
			(type solid)
		)
		(fill yes)
		(layer "In2.Cu")
		(net "M_I_CPU0_SA_DQ<15>")
	)
	(gr_poly
		(pts
			(xy 389.424926 -233.34599) (xy 389.32485 -233.245914) (xy 389.224774 -233.34599) (xy 389.224774 -233.39044)
			(xy 389.424926 -233.39044)
		)
		(stroke
			(width 0)
			(type solid)
		)
		(fill yes)
		(layer "In2.Cu")
		(net "M_I_CPU0_SA_DQ<12>")
	)
	(gr_poly
		(pts
			(xy 389.424926 -232.942384) (xy 389.424926 -232.894632) (xy 389.224774 -232.894632) (xy 389.224774 -232.942384)
			(xy 389.32485 -233.042206)
		)
		(stroke
			(width 0)
			(type solid)
		)
		(fill yes)
		(layer "In2.Cu")
		(net "M_I_CPU0_SA_DQS_DP<6>")
	)
	(gr_poly
		(pts
			(xy 389.424926 -231.725724) (xy 389.32485 -231.625902) (xy 389.224774 -231.725724) (xy 389.224774 -231.773476)
			(xy 389.424926 -231.773476)
		)
		(stroke
			(width 0)
			(type solid)
		)
		(fill yes)
		(layer "In2.Cu")
		(net "M_I_CPU0_SA_DQS_DP<1>")
	)
	(gr_poly
		(pts
			(xy 389.424926 -231.322372) (xy 389.424926 -231.277922) (xy 389.224774 -231.277922) (xy 389.224774 -231.322372)
			(xy 389.32485 -231.422448)
		)
		(stroke
			(width 0)
			(type solid)
		)
		(fill yes)
		(layer "In2.Cu")
		(net "M_I_CPU0_SA_DQ<11>")
	)
	(gr_poly
		(pts
			(xy 389.424926 -230.105966) (xy 389.32485 -230.006144) (xy 389.224774 -230.105966) (xy 389.224774 -230.150416)
			(xy 389.424926 -230.150416)
		)
		(stroke
			(width 0)
			(type solid)
		)
		(fill yes)
		(layer "In2.Cu")
		(net "M_I_CPU0_SA_DQ<8>")
	)
	(gr_poly
		(pts
			(xy 389.424926 -229.70236) (xy 389.424926 -229.65791) (xy 389.224774 -229.65791) (xy 389.224774 -229.70236)
			(xy 389.32485 -229.802436)
		)
		(stroke
			(width 0)
			(type solid)
		)
		(fill yes)
		(layer "In2.Cu")
		(net "M_I_CPU0_SA_DQ<7>")
	)
	(gr_poly
		(pts
			(xy 389.479028 -222.14078) (xy 389.442452 -222.004128) (xy 389.404098 -221.981776) (xy 389.304022 -222.155004)
			(xy 389.34263 -222.177356)
		)
		(stroke
			(width 0)
			(type solid)
		)
		(fill yes)
		(layer "In2.Cu")
		(net "M_I_CPU0_SA_DQ<2>")
	)
	(gr_poly
		(pts
			(xy 389.47979 -227.000816) (xy 389.44296 -226.864164) (xy 389.401812 -226.840288) (xy 389.301736 -227.013516)
			(xy 389.343138 -227.037392)
		)
		(stroke
			(width 0)
			(type solid)
		)
		(fill yes)
		(layer "In2.Cu")
		(net "M_I_CPU0_SA_DQS_DP<5>")
	)
	(gr_poly
		(pts
			(xy 389.47979 -225.380804) (xy 389.44296 -225.244152) (xy 389.401812 -225.220276) (xy 389.301736 -225.393504)
			(xy 389.343138 -225.41738)
		)
		(stroke
			(width 0)
			(type solid)
		)
		(fill yes)
		(layer "In2.Cu")
		(net "M_I_CPU0_SA_DQS_DN<0>")
	)
	(gr_poly
		(pts
			(xy 389.480044 -228.620066) (xy 389.443468 -228.483414) (xy 389.40486 -228.461316) (xy 389.304784 -228.634544)
			(xy 389.343392 -228.656642)
		)
		(stroke
			(width 0)
			(type solid)
		)
		(fill yes)
		(layer "In2.Cu")
		(net "M_I_CPU0_SA_DQ<6>")
	)
	(gr_poly
		(pts
			(xy 389.481822 -223.757998) (xy 389.444992 -223.6216) (xy 389.406638 -223.599248) (xy 389.306562 -223.772476)
			(xy 389.34517 -223.794828)
		)
		(stroke
			(width 0)
			(type solid)
		)
		(fill yes)
		(layer "In2.Cu")
		(net "M_I_CPU0_SA_DQ<3>")
	)
	(gr_poly
		(pts
			(xy 389.7249 -292.91788) (xy 389.624824 -292.817804) (xy 389.524748 -292.91788) (xy 389.524748 -292.96233)
			(xy 389.7249 -292.96233)
		)
		(stroke
			(width 0)
			(type solid)
		)
		(fill yes)
		(layer "In2.Cu")
		(net "M_I_CPU0_SB_DQ<29>")
	)
	(gr_poly
		(pts
			(xy 389.7249 -292.51402) (xy 389.7249 -292.46957) (xy 389.524748 -292.46957) (xy 389.524748 -292.51402)
			(xy 389.624824 -292.614096)
		)
		(stroke
			(width 0)
			(type solid)
		)
		(fill yes)
		(layer "In2.Cu")
		(net "M_I_CPU0_SB_DQ<30>")
	)
	(gr_poly
		(pts
			(xy 389.7249 -291.297614) (xy 389.624824 -291.197792) (xy 389.524748 -291.297614) (xy 389.524748 -291.345366)
			(xy 389.7249 -291.345366)
		)
		(stroke
			(width 0)
			(type solid)
		)
		(fill yes)
		(layer "In2.Cu")
		(net "M_I_CPU0_SB_DQS_DN<8>")
	)
	(gr_poly
		(pts
			(xy 389.7249 -290.894262) (xy 389.7249 -290.84651) (xy 389.524748 -290.84651) (xy 389.524748 -290.894262)
			(xy 389.624824 -290.994084)
		)
		(stroke
			(width 0)
			(type solid)
		)
		(fill yes)
		(layer "In2.Cu")
		(net "M_I_CPU0_SB_DQS_DN<3>")
	)
	(gr_poly
		(pts
			(xy 389.7249 -289.677856) (xy 389.624824 -289.57778) (xy 389.524748 -289.677856) (xy 389.524748 -289.722306)
			(xy 389.7249 -289.722306)
		)
		(stroke
			(width 0)
			(type solid)
		)
		(fill yes)
		(layer "In2.Cu")
		(net "M_I_CPU0_SB_DQ<25>")
	)
	(gr_poly
		(pts
			(xy 389.7249 -289.273996) (xy 389.7249 -289.229546) (xy 389.524748 -289.229546) (xy 389.524748 -289.273996)
			(xy 389.624824 -289.374072)
		)
		(stroke
			(width 0)
			(type solid)
		)
		(fill yes)
		(layer "In2.Cu")
		(net "M_I_CPU0_SB_DQ<26>")
	)
	(gr_poly
		(pts
			(xy 389.7249 -288.057844) (xy 389.624824 -287.957768) (xy 389.524748 -288.057844) (xy 389.524748 -288.102294)
			(xy 389.7249 -288.102294)
		)
		(stroke
			(width 0)
			(type solid)
		)
		(fill yes)
		(layer "In2.Cu")
		(net "M_I_CPU0_SB_DQ<21>")
	)
	(gr_poly
		(pts
			(xy 389.7249 -287.654238) (xy 389.7249 -287.609788) (xy 389.524748 -287.609788) (xy 389.524748 -287.654238)
			(xy 389.624824 -287.75406)
		)
		(stroke
			(width 0)
			(type solid)
		)
		(fill yes)
		(layer "In2.Cu")
		(net "M_I_CPU0_SB_DQ<22>")
	)
	(gr_poly
		(pts
			(xy 389.7249 -286.437832) (xy 389.624824 -286.337756) (xy 389.524748 -286.437832) (xy 389.524748 -286.485584)
			(xy 389.7249 -286.485584)
		)
		(stroke
			(width 0)
			(type solid)
		)
		(fill yes)
		(layer "In2.Cu")
		(net "M_I_CPU0_SB_DQS_DN<7>")
	)
	(gr_poly
		(pts
			(xy 389.7249 -286.03448) (xy 389.7249 -285.986728) (xy 389.524748 -285.986728) (xy 389.524748 -286.03448)
			(xy 389.624824 -286.134302)
		)
		(stroke
			(width 0)
			(type solid)
		)
		(fill yes)
		(layer "In2.Cu")
		(net "M_I_CPU0_SB_DQS_DN<2>")
	)
	(gr_poly
		(pts
			(xy 389.7249 -284.818074) (xy 389.624824 -284.717998) (xy 389.524748 -284.818074) (xy 389.524748 -284.862524)
			(xy 389.7249 -284.862524)
		)
		(stroke
			(width 0)
			(type solid)
		)
		(fill yes)
		(layer "In2.Cu")
		(net "M_I_CPU0_SB_DQ<17>")
	)
	(gr_poly
		(pts
			(xy 389.7249 -284.414214) (xy 389.7249 -284.369764) (xy 389.524748 -284.369764) (xy 389.524748 -284.414214)
			(xy 389.624824 -284.51429)
		)
		(stroke
			(width 0)
			(type solid)
		)
		(fill yes)
		(layer "In2.Cu")
		(net "M_I_CPU0_SB_DQ<18>")
	)
	(gr_poly
		(pts
			(xy 389.7249 -283.198062) (xy 389.624824 -283.097986) (xy 389.524748 -283.198062) (xy 389.524748 -283.242512)
			(xy 389.7249 -283.242512)
		)
		(stroke
			(width 0)
			(type solid)
		)
		(fill yes)
		(layer "In2.Cu")
		(net "M_I_CPU0_SB_DQ<13>")
	)
	(gr_poly
		(pts
			(xy 389.7249 -282.794202) (xy 389.7249 -282.749752) (xy 389.524748 -282.749752) (xy 389.524748 -282.794202)
			(xy 389.624824 -282.894278)
		)
		(stroke
			(width 0)
			(type solid)
		)
		(fill yes)
		(layer "In2.Cu")
		(net "M_I_CPU0_SB_DQ<14>")
	)
	(gr_poly
		(pts
			(xy 389.7249 -281.577796) (xy 389.624824 -281.477974) (xy 389.524748 -281.577796) (xy 389.524748 -281.625548)
			(xy 389.7249 -281.625548)
		)
		(stroke
			(width 0)
			(type solid)
		)
		(fill yes)
		(layer "In2.Cu")
		(net "M_I_CPU0_SB_DQS_DN<6>")
	)
	(gr_poly
		(pts
			(xy 389.7249 -281.174444) (xy 389.7249 -281.126692) (xy 389.524748 -281.126692) (xy 389.524748 -281.174444)
			(xy 389.624824 -281.274266)
		)
		(stroke
			(width 0)
			(type solid)
		)
		(fill yes)
		(layer "In2.Cu")
		(net "M_I_CPU0_SB_DQS_DN<1>")
	)
	(gr_poly
		(pts
			(xy 389.7249 -279.958038) (xy 389.624824 -279.857962) (xy 389.524748 -279.958038) (xy 389.524748 -280.002488)
			(xy 389.7249 -280.002488)
		)
		(stroke
			(width 0)
			(type solid)
		)
		(fill yes)
		(layer "In2.Cu")
		(net "M_I_CPU0_SB_DQ<9>")
	)
	(gr_poly
		(pts
			(xy 389.7249 -279.554178) (xy 389.7249 -279.509728) (xy 389.524748 -279.509728) (xy 389.524748 -279.554178)
			(xy 389.624824 -279.654254)
		)
		(stroke
			(width 0)
			(type solid)
		)
		(fill yes)
		(layer "In2.Cu")
		(net "M_I_CPU0_SB_DQ<10>")
	)
	(gr_poly
		(pts
			(xy 389.7249 -278.338026) (xy 389.624824 -278.23795) (xy 389.524748 -278.338026) (xy 389.524748 -278.382476)
			(xy 389.7249 -278.382476)
		)
		(stroke
			(width 0)
			(type solid)
		)
		(fill yes)
		(layer "In2.Cu")
		(net "M_I_CPU0_SB_DQ<5>")
	)
	(gr_poly
		(pts
			(xy 389.7249 -277.934166) (xy 389.7249 -277.889716) (xy 389.524748 -277.889716) (xy 389.524748 -277.934166)
			(xy 389.624824 -278.034242)
		)
		(stroke
			(width 0)
			(type solid)
		)
		(fill yes)
		(layer "In2.Cu")
		(net "M_I_CPU0_SB_DQ<6>")
	)
	(gr_poly
		(pts
			(xy 389.7249 -276.71776) (xy 389.624824 -276.617938) (xy 389.524748 -276.71776) (xy 389.524748 -276.765512)
			(xy 389.7249 -276.765512)
		)
		(stroke
			(width 0)
			(type solid)
		)
		(fill yes)
		(layer "In2.Cu")
		(net "M_I_CPU0_SB_DQS_DN<5>")
	)
	(gr_poly
		(pts
			(xy 389.7249 -276.314408) (xy 389.7249 -276.266656) (xy 389.524748 -276.266656) (xy 389.524748 -276.314408)
			(xy 389.624824 -276.41423)
		)
		(stroke
			(width 0)
			(type solid)
		)
		(fill yes)
		(layer "In2.Cu")
		(net "M_I_CPU0_SB_DQS_DN<0>")
	)
	(gr_poly
		(pts
			(xy 389.7249 -275.098002) (xy 389.624824 -274.997926) (xy 389.524748 -275.098002) (xy 389.524748 -275.142452)
			(xy 389.7249 -275.142452)
		)
		(stroke
			(width 0)
			(type solid)
		)
		(fill yes)
		(layer "In2.Cu")
		(net "M_I_CPU0_SB_DQ<1>")
	)
	(gr_poly
		(pts
			(xy 389.7249 -274.694142) (xy 389.7249 -274.649692) (xy 389.524748 -274.649692) (xy 389.524748 -274.694142)
			(xy 389.624824 -274.794218)
		)
		(stroke
			(width 0)
			(type solid)
		)
		(fill yes)
		(layer "In2.Cu")
		(net "M_I_CPU0_SB_DQ<2>")
	)
	(gr_poly
		(pts
			(xy 389.7249 -273.47799) (xy 389.624824 -273.377914) (xy 389.524748 -273.47799) (xy 389.524748 -273.52244)
			(xy 389.7249 -273.52244)
		)
		(stroke
			(width 0)
			(type solid)
		)
		(fill yes)
		(layer "In2.Cu")
		(net "M_I_CPU0_SB_CB<1>")
	)
	(gr_poly
		(pts
			(xy 389.7249 -273.07413) (xy 389.7249 -273.02968) (xy 389.524748 -273.02968) (xy 389.524748 -273.07413)
			(xy 389.624824 -273.174206)
		)
		(stroke
			(width 0)
			(type solid)
		)
		(fill yes)
		(layer "In2.Cu")
		(net "M_I_CPU0_SB_CB<2>")
	)
	(gr_poly
		(pts
			(xy 389.7249 -271.857724) (xy 389.624824 -271.757902) (xy 389.524748 -271.857724) (xy 389.524748 -271.905476)
			(xy 389.7249 -271.905476)
		)
		(stroke
			(width 0)
			(type solid)
		)
		(fill yes)
		(layer "In2.Cu")
		(net "M_I_CPU0_SB_DQS_DN<4>")
	)
	(gr_poly
		(pts
			(xy 389.7249 -271.454372) (xy 389.7249 -271.40662) (xy 389.524748 -271.40662) (xy 389.524748 -271.454372)
			(xy 389.624824 -271.554194)
		)
		(stroke
			(width 0)
			(type solid)
		)
		(fill yes)
		(layer "In2.Cu")
		(net "M_I_CPU0_SB_DQS_DN<9>")
	)
	(gr_poly
		(pts
			(xy 389.7249 -270.237966) (xy 389.624824 -270.13789) (xy 389.524748 -270.237966) (xy 389.524748 -270.282416)
			(xy 389.7249 -270.282416)
		)
		(stroke
			(width 0)
			(type solid)
		)
		(fill yes)
		(layer "In2.Cu")
		(net "M_I_CPU0_SB_CB<5>")
	)
	(gr_poly
		(pts
			(xy 389.7249 -269.834106) (xy 389.7249 -269.789656) (xy 389.524748 -269.789656) (xy 389.524748 -269.834106)
			(xy 389.624824 -269.934182)
		)
		(stroke
			(width 0)
			(type solid)
		)
		(fill yes)
		(layer "In2.Cu")
		(net "M_I_CPU0_SB_CB<6>")
	)
	(gr_poly
		(pts
			(xy 389.7249 -266.997942) (xy 389.624824 -266.897866) (xy 389.524748 -266.997942) (xy 389.524748 -267.042392)
			(xy 389.7249 -267.042392)
		)
		(stroke
			(width 0)
			(type solid)
		)
		(fill yes)
		(layer "In2.Cu")
		(net "M_I_CPU0_SA_RSP<0>")
	)
	(gr_poly
		(pts
			(xy 389.7249 -266.594082) (xy 389.7249 -266.549632) (xy 389.524748 -266.549632) (xy 389.524748 -266.594082)
			(xy 389.624824 -266.694158)
		)
		(stroke
			(width 0)
			(type solid)
		)
		(fill yes)
		(layer "In2.Cu")
		(net "M_I_CPU0_SB_CS_N<1>")
	)
	(gr_poly
		(pts
			(xy 389.7249 -265.37793) (xy 389.624824 -265.277854) (xy 389.524748 -265.37793) (xy 389.524748 -265.42238)
			(xy 389.7249 -265.42238)
		)
		(stroke
			(width 0)
			(type solid)
		)
		(fill yes)
		(layer "In2.Cu")
		(net "M_I_CPU0_SB_PAR")
	)
	(gr_poly
		(pts
			(xy 389.7249 -263.757918) (xy 389.624824 -263.657842) (xy 389.524748 -263.757918) (xy 389.524748 -263.802368)
			(xy 389.7249 -263.802368)
		)
		(stroke
			(width 0)
			(type solid)
		)
		(fill yes)
		(layer "In2.Cu")
		(net "M_I_CPU0_SB_CA<4>")
	)
	(gr_poly
		(pts
			(xy 389.7249 -263.354058) (xy 389.7249 -263.309608) (xy 389.524748 -263.309608) (xy 389.524748 -263.354058)
			(xy 389.624824 -263.454134)
		)
		(stroke
			(width 0)
			(type solid)
		)
		(fill yes)
		(layer "In2.Cu")
		(net "M_I_CPU0_SB_CA<3>")
	)
	(gr_poly
		(pts
			(xy 389.7249 -262.137906) (xy 389.624824 -262.03783) (xy 389.524748 -262.137906) (xy 389.524748 -262.182356)
			(xy 389.7249 -262.182356)
		)
		(stroke
			(width 0)
			(type solid)
		)
		(fill yes)
		(layer "In2.Cu")
		(net "M_I_CPU0_SB_CA<0>")
	)
	(gr_poly
		(pts
			(xy 389.814054 -228.745542) (xy 389.775446 -228.72319) (xy 389.638794 -228.759766) (xy 389.675624 -228.896418)
			(xy 389.713978 -228.91877)
		)
		(stroke
			(width 0)
			(type solid)
		)
		(fill yes)
		(layer "In2.Cu")
		(net "M_I_CPU0_SA_DQ<5>")
	)
	(gr_poly
		(pts
			(xy 389.814054 -227.12553) (xy 389.775446 -227.103178) (xy 389.638794 -227.139754) (xy 389.675624 -227.276406)
			(xy 389.713978 -227.298758)
		)
		(stroke
			(width 0)
			(type solid)
		)
		(fill yes)
		(layer "In2.Cu")
		(net "M_I_CPU0_SA_DQ<4>")
	)
	(gr_poly
		(pts
			(xy 389.816848 -225.50628) (xy 389.7757 -225.482404) (xy 389.639048 -225.519234) (xy 389.675624 -225.655632)
			(xy 389.717026 -225.679508)
		)
		(stroke
			(width 0)
			(type solid)
		)
		(fill yes)
		(layer "In2.Cu")
		(net "M_I_CPU0_SA_DQS_DN<5>")
	)
	(gr_poly
		(pts
			(xy 389.816848 -223.886268) (xy 389.7757 -223.862392) (xy 389.639048 -223.899222) (xy 389.675624 -224.03562)
			(xy 389.717026 -224.059496)
		)
		(stroke
			(width 0)
			(type solid)
		)
		(fill yes)
		(layer "In2.Cu")
		(net "M_I_CPU0_SA_DQS_DP<0>")
	)
	(gr_poly
		(pts
			(xy 389.894826 -256.432558) (xy 389.894826 -256.384806) (xy 389.694674 -256.384806) (xy 389.694674 -256.432558)
			(xy 389.79475 -256.53238)
		)
		(stroke
			(width 0)
			(type solid)
		)
		(fill yes)
		(layer "In2.Cu")
		(net "M_I_CPU0_CLK_DN<0>")
	)
	(gr_poly
		(pts
			(xy 389.894826 -255.216152) (xy 389.79475 -255.116076) (xy 389.694674 -255.216152) (xy 389.694674 -255.260602)
			(xy 389.894826 -255.260602)
		)
		(stroke
			(width 0)
			(type solid)
		)
		(fill yes)
		(layer "In2.Cu")
		(net "M_I_CPU0_SA_CA<6>")
	)
	(gr_poly
		(pts
			(xy 389.894826 -254.812292) (xy 389.894826 -254.767842) (xy 389.694674 -254.767842) (xy 389.694674 -254.812292)
			(xy 389.79475 -254.912368)
		)
		(stroke
			(width 0)
			(type solid)
		)
		(fill yes)
		(layer "In2.Cu")
		(net "M_I_CPU0_SA_CA<5>")
	)
	(gr_poly
		(pts
			(xy 389.894826 -253.59614) (xy 389.79475 -253.496064) (xy 389.694674 -253.59614) (xy 389.694674 -253.64059)
			(xy 389.894826 -253.64059)
		)
		(stroke
			(width 0)
			(type solid)
		)
		(fill yes)
		(layer "In2.Cu")
		(net "M_I_CPU0_SA_CA<2>")
	)
	(gr_poly
		(pts
			(xy 389.894826 -253.19228) (xy 389.894826 -253.14783) (xy 389.694674 -253.14783) (xy 389.694674 -253.19228)
			(xy 389.79475 -253.292356)
		)
		(stroke
			(width 0)
			(type solid)
		)
		(fill yes)
		(layer "In2.Cu")
		(net "M_I_CPU0_SA_CA<1>")
	)
	(gr_poly
		(pts
			(xy 389.894826 -251.976128) (xy 389.79475 -251.876052) (xy 389.694674 -251.976128) (xy 389.694674 -252.020578)
			(xy 389.894826 -252.020578)
		)
		(stroke
			(width 0)
			(type solid)
		)
		(fill yes)
		(layer "In2.Cu")
		(net "M_I_CPU0_SA_CS_N<1>")
	)
	(gr_poly
		(pts
			(xy 389.894826 -250.356116) (xy 389.79475 -250.25604) (xy 389.694674 -250.356116) (xy 389.694674 -250.400566)
			(xy 389.894826 -250.400566)
		)
		(stroke
			(width 0)
			(type solid)
		)
		(fill yes)
		(layer "In2.Cu")
		(net "M_I_CPU0_ALERT_R_N")
	)
	(gr_poly
		(pts
			(xy 389.894826 -248.736104) (xy 389.79475 -248.636028) (xy 389.694674 -248.736104) (xy 389.694674 -248.780554)
			(xy 389.894826 -248.780554)
		)
		(stroke
			(width 0)
			(type solid)
		)
		(fill yes)
		(layer "In2.Cu")
		(net "M_I_CPU0_SA_CB<5>")
	)
	(gr_poly
		(pts
			(xy 389.894826 -248.332244) (xy 389.894826 -248.287794) (xy 389.694674 -248.287794) (xy 389.694674 -248.332244)
			(xy 389.79475 -248.43232)
		)
		(stroke
			(width 0)
			(type solid)
		)
		(fill yes)
		(layer "In2.Cu")
		(net "M_I_CPU0_SA_CB<6>")
	)
	(gr_poly
		(pts
			(xy 389.894826 -247.115838) (xy 389.79475 -247.016016) (xy 389.694674 -247.115838) (xy 389.694674 -247.16359)
			(xy 389.894826 -247.16359)
		)
		(stroke
			(width 0)
			(type solid)
		)
		(fill yes)
		(layer "In2.Cu")
		(net "M_I_CPU0_SA_DQS_DN<9>")
	)
	(gr_poly
		(pts
			(xy 389.894826 -246.712486) (xy 389.894826 -246.664734) (xy 389.694674 -246.664734) (xy 389.694674 -246.712486)
			(xy 389.79475 -246.812308)
		)
		(stroke
			(width 0)
			(type solid)
		)
		(fill yes)
		(layer "In2.Cu")
		(net "M_I_CPU0_SA_DQS_DN<4>")
	)
	(gr_poly
		(pts
			(xy 389.894826 -245.49608) (xy 389.79475 -245.396004) (xy 389.694674 -245.49608) (xy 389.694674 -245.54053)
			(xy 389.894826 -245.54053)
		)
		(stroke
			(width 0)
			(type solid)
		)
		(fill yes)
		(layer "In2.Cu")
		(net "M_I_CPU0_SA_CB<1>")
	)
	(gr_poly
		(pts
			(xy 389.894826 -245.09222) (xy 389.894826 -245.04777) (xy 389.694674 -245.04777) (xy 389.694674 -245.09222)
			(xy 389.79475 -245.192296)
		)
		(stroke
			(width 0)
			(type solid)
		)
		(fill yes)
		(layer "In2.Cu")
		(net "M_I_CPU0_SA_CB<2>")
	)
	(gr_poly
		(pts
			(xy 389.894826 -243.876068) (xy 389.79475 -243.775992) (xy 389.694674 -243.876068) (xy 389.694674 -243.920518)
			(xy 389.894826 -243.920518)
		)
		(stroke
			(width 0)
			(type solid)
		)
		(fill yes)
		(layer "In2.Cu")
		(net "M_I_CPU0_SA_DQ<29>")
	)
	(gr_poly
		(pts
			(xy 389.894826 -243.472208) (xy 389.894826 -243.427758) (xy 389.694674 -243.427758) (xy 389.694674 -243.472208)
			(xy 389.79475 -243.572284)
		)
		(stroke
			(width 0)
			(type solid)
		)
		(fill yes)
		(layer "In2.Cu")
		(net "M_I_CPU0_SA_DQ<30>")
	)
	(gr_poly
		(pts
			(xy 389.894826 -242.255802) (xy 389.79475 -242.15598) (xy 389.694674 -242.255802) (xy 389.694674 -242.303554)
			(xy 389.894826 -242.303554)
		)
		(stroke
			(width 0)
			(type solid)
		)
		(fill yes)
		(layer "In2.Cu")
		(net "M_I_CPU0_SA_DQS_DN<8>")
	)
	(gr_poly
		(pts
			(xy 389.894826 -241.85245) (xy 389.894826 -241.804698) (xy 389.694674 -241.804698) (xy 389.694674 -241.85245)
			(xy 389.79475 -241.952272)
		)
		(stroke
			(width 0)
			(type solid)
		)
		(fill yes)
		(layer "In2.Cu")
		(net "M_I_CPU0_SA_DQS_DN<3>")
	)
	(gr_poly
		(pts
			(xy 389.894826 -240.636044) (xy 389.79475 -240.535968) (xy 389.694674 -240.636044) (xy 389.694674 -240.680494)
			(xy 389.894826 -240.680494)
		)
		(stroke
			(width 0)
			(type solid)
		)
		(fill yes)
		(layer "In2.Cu")
		(net "M_I_CPU0_SA_DQ<25>")
	)
	(gr_poly
		(pts
			(xy 389.894826 -240.232184) (xy 389.894826 -240.187734) (xy 389.694674 -240.187734) (xy 389.694674 -240.232184)
			(xy 389.79475 -240.33226)
		)
		(stroke
			(width 0)
			(type solid)
		)
		(fill yes)
		(layer "In2.Cu")
		(net "M_I_CPU0_SA_DQ<26>")
	)
	(gr_poly
		(pts
			(xy 389.894826 -239.016032) (xy 389.79475 -238.915956) (xy 389.694674 -239.016032) (xy 389.694674 -239.060482)
			(xy 389.894826 -239.060482)
		)
		(stroke
			(width 0)
			(type solid)
		)
		(fill yes)
		(layer "In2.Cu")
		(net "M_I_CPU0_SA_DQ<21>")
	)
	(gr_poly
		(pts
			(xy 389.894826 -238.612172) (xy 389.894826 -238.567722) (xy 389.694674 -238.567722) (xy 389.694674 -238.612172)
			(xy 389.79475 -238.712248)
		)
		(stroke
			(width 0)
			(type solid)
		)
		(fill yes)
		(layer "In2.Cu")
		(net "M_I_CPU0_SA_DQ<22>")
	)
	(gr_poly
		(pts
			(xy 389.894826 -237.395766) (xy 389.79475 -237.295944) (xy 389.694674 -237.395766) (xy 389.694674 -237.443518)
			(xy 389.894826 -237.443518)
		)
		(stroke
			(width 0)
			(type solid)
		)
		(fill yes)
		(layer "In2.Cu")
		(net "M_I_CPU0_SA_DQS_DN<7>")
	)
	(gr_poly
		(pts
			(xy 389.894826 -236.992414) (xy 389.894826 -236.944662) (xy 389.694674 -236.944662) (xy 389.694674 -236.992414)
			(xy 389.79475 -237.092236)
		)
		(stroke
			(width 0)
			(type solid)
		)
		(fill yes)
		(layer "In2.Cu")
		(net "M_I_CPU0_SA_DQS_DN<2>")
	)
	(gr_poly
		(pts
			(xy 389.894826 -235.776008) (xy 389.79475 -235.675932) (xy 389.694674 -235.776008) (xy 389.694674 -235.820458)
			(xy 389.894826 -235.820458)
		)
		(stroke
			(width 0)
			(type solid)
		)
		(fill yes)
		(layer "In2.Cu")
		(net "M_I_CPU0_SA_DQ<17>")
	)
	(gr_poly
		(pts
			(xy 389.894826 -235.372148) (xy 389.894826 -235.327698) (xy 389.694674 -235.327698) (xy 389.694674 -235.372148)
			(xy 389.79475 -235.472224)
		)
		(stroke
			(width 0)
			(type solid)
		)
		(fill yes)
		(layer "In2.Cu")
		(net "M_I_CPU0_SA_DQ<18>")
	)
	(gr_poly
		(pts
			(xy 389.894826 -234.155996) (xy 389.79475 -234.05592) (xy 389.694674 -234.155996) (xy 389.694674 -234.200446)
			(xy 389.894826 -234.200446)
		)
		(stroke
			(width 0)
			(type solid)
		)
		(fill yes)
		(layer "In2.Cu")
		(net "M_I_CPU0_SA_DQ<13>")
	)
	(gr_poly
		(pts
			(xy 389.894826 -233.752136) (xy 389.894826 -233.707686) (xy 389.694674 -233.707686) (xy 389.694674 -233.752136)
			(xy 389.79475 -233.852212)
		)
		(stroke
			(width 0)
			(type solid)
		)
		(fill yes)
		(layer "In2.Cu")
		(net "M_I_CPU0_SA_DQ<14>")
	)
	(gr_poly
		(pts
			(xy 389.894826 -232.53573) (xy 389.79475 -232.435908) (xy 389.694674 -232.53573) (xy 389.694674 -232.583482)
			(xy 389.894826 -232.583482)
		)
		(stroke
			(width 0)
			(type solid)
		)
		(fill yes)
		(layer "In2.Cu")
		(net "M_I_CPU0_SA_DQS_DN<6>")
	)
	(gr_poly
		(pts
			(xy 389.894826 -232.132378) (xy 389.894826 -232.084626) (xy 389.694674 -232.084626) (xy 389.694674 -232.132378)
			(xy 389.79475 -232.2322)
		)
		(stroke
			(width 0)
			(type solid)
		)
		(fill yes)
		(layer "In2.Cu")
		(net "M_I_CPU0_SA_DQS_DN<1>")
	)
	(gr_poly
		(pts
			(xy 389.894826 -230.915972) (xy 389.79475 -230.815896) (xy 389.694674 -230.915972) (xy 389.694674 -230.960422)
			(xy 389.894826 -230.960422)
		)
		(stroke
			(width 0)
			(type solid)
		)
		(fill yes)
		(layer "In2.Cu")
		(net "M_I_CPU0_SA_DQ<9>")
	)
	(gr_poly
		(pts
			(xy 389.894826 -230.512366) (xy 389.894826 -230.467916) (xy 389.694674 -230.467916) (xy 389.694674 -230.512366)
			(xy 389.79475 -230.612188)
		)
		(stroke
			(width 0)
			(type solid)
		)
		(fill yes)
		(layer "In2.Cu")
		(net "M_I_CPU0_SA_DQ<10>")
	)
	(gr_poly
		(pts
			(xy 389.950706 -229.428802) (xy 389.91413 -229.29215) (xy 389.875776 -229.269798) (xy 389.7757 -229.443026)
			(xy 389.814308 -229.465378)
		)
		(stroke
			(width 0)
			(type solid)
		)
		(fill yes)
		(layer "In2.Cu")
		(net "M_I_CPU0_SA_DQ<7>")
	)
	(gr_poly
		(pts
			(xy 389.950706 -227.80879) (xy 389.91413 -227.672138) (xy 389.875776 -227.649786) (xy 389.7757 -227.823014)
			(xy 389.814308 -227.845366)
		)
		(stroke
			(width 0)
			(type solid)
		)
		(fill yes)
		(layer "In2.Cu")
		(net "M_I_CPU0_SA_DQ<6>")
	)
	(gr_poly
		(pts
			(xy 389.950706 -226.189286) (xy 389.91413 -226.052888) (xy 389.872728 -226.029012) (xy 389.772906 -226.20224)
			(xy 389.814054 -226.226116)
		)
		(stroke
			(width 0)
			(type solid)
		)
		(fill yes)
		(layer "In2.Cu")
		(net "M_I_CPU0_SA_DQS_DP<5>")
	)
	(gr_poly
		(pts
			(xy 389.950706 -224.569274) (xy 389.91413 -224.432876) (xy 389.872728 -224.409) (xy 389.772906 -224.582228)
			(xy 389.814054 -224.606104)
		)
		(stroke
			(width 0)
			(type solid)
		)
		(fill yes)
		(layer "In2.Cu")
		(net "M_I_CPU0_SA_DQS_DN<0>")
	)
	(gr_poly
		(pts
			(xy 389.951468 -222.947992) (xy 389.914892 -222.81134) (xy 389.876284 -222.789242) (xy 389.776462 -222.96247)
			(xy 389.814816 -222.984568)
		)
		(stroke
			(width 0)
			(type solid)
		)
		(fill yes)
		(layer "In2.Cu")
		(net "M_I_CPU0_SA_DQ<3>")
	)
	(gr_poly
		(pts
			(xy 390.114028 -293.874698) (xy 390.013952 -293.70147) (xy 389.975598 -293.723822) (xy 389.939022 -293.860474)
			(xy 390.07542 -293.89705)
		)
		(stroke
			(width 0)
			(type solid)
		)
		(fill yes)
		(layer "In2.Cu")
		(net "M_I_CPU0_SB_DQ<31>")
	)
	(gr_poly
		(pts
			(xy 390.1948 -292.107874) (xy 390.094724 -292.007798) (xy 389.994648 -292.107874) (xy 389.994648 -292.152324)
			(xy 390.1948 -292.152324)
		)
		(stroke
			(width 0)
			(type solid)
		)
		(fill yes)
		(layer "In2.Cu")
		(net "M_I_CPU0_SB_DQ<28>")
	)
	(gr_poly
		(pts
			(xy 390.1948 -291.704268) (xy 390.1948 -291.656516) (xy 389.994648 -291.656516) (xy 389.994648 -291.704268)
			(xy 390.094724 -291.80409)
		)
		(stroke
			(width 0)
			(type solid)
		)
		(fill yes)
		(layer "In2.Cu")
		(net "M_I_CPU0_SB_DQS_DP<8>")
	)
	(gr_poly
		(pts
			(xy 390.1948 -290.487608) (xy 390.094724 -290.387786) (xy 389.994648 -290.487608) (xy 389.994648 -290.53536)
			(xy 390.1948 -290.53536)
		)
		(stroke
			(width 0)
			(type solid)
		)
		(fill yes)
		(layer "In2.Cu")
		(net "M_I_CPU0_SB_DQS_DP<3>")
	)
	(gr_poly
		(pts
			(xy 390.1948 -290.084002) (xy 390.1948 -290.039552) (xy 389.994648 -290.039552) (xy 389.994648 -290.084002)
			(xy 390.094724 -290.184078)
		)
		(stroke
			(width 0)
			(type solid)
		)
		(fill yes)
		(layer "In2.Cu")
		(net "M_I_CPU0_SB_DQ<27>")
	)
	(gr_poly
		(pts
			(xy 390.1948 -288.86785) (xy 390.094724 -288.767774) (xy 389.994648 -288.86785) (xy 389.994648 -288.9123)
			(xy 390.1948 -288.9123)
		)
		(stroke
			(width 0)
			(type solid)
		)
		(fill yes)
		(layer "In2.Cu")
		(net "M_I_CPU0_SB_DQ<24>")
	)
	(gr_poly
		(pts
			(xy 390.1948 -288.464244) (xy 390.1948 -288.419794) (xy 389.994648 -288.419794) (xy 389.994648 -288.464244)
			(xy 390.094724 -288.56432)
		)
		(stroke
			(width 0)
			(type solid)
		)
		(fill yes)
		(layer "In2.Cu")
		(net "M_I_CPU0_SB_DQ<23>")
	)
	(gr_poly
		(pts
			(xy 390.1948 -287.247838) (xy 390.094724 -287.148016) (xy 389.994648 -287.247838) (xy 389.994648 -287.292288)
			(xy 390.1948 -287.292288)
		)
		(stroke
			(width 0)
			(type solid)
		)
		(fill yes)
		(layer "In2.Cu")
		(net "M_I_CPU0_SB_DQ<20>")
	)
	(gr_poly
		(pts
			(xy 390.1948 -286.844232) (xy 390.1948 -286.79648) (xy 389.994648 -286.79648) (xy 389.994648 -286.844232)
			(xy 390.094724 -286.944308)
		)
		(stroke
			(width 0)
			(type solid)
		)
		(fill yes)
		(layer "In2.Cu")
		(net "M_I_CPU0_SB_DQS_DP<7>")
	)
	(gr_poly
		(pts
			(xy 390.1948 -285.627826) (xy 390.094724 -285.528004) (xy 389.994648 -285.627826) (xy 389.994648 -285.675578)
			(xy 390.1948 -285.675578)
		)
		(stroke
			(width 0)
			(type solid)
		)
		(fill yes)
		(layer "In2.Cu")
		(net "M_I_CPU0_SB_DQS_DP<2>")
	)
	(gr_poly
		(pts
			(xy 390.1948 -285.22422) (xy 390.1948 -285.17977) (xy 389.994648 -285.17977) (xy 389.994648 -285.22422)
			(xy 390.094724 -285.324296)
		)
		(stroke
			(width 0)
			(type solid)
		)
		(fill yes)
		(layer "In2.Cu")
		(net "M_I_CPU0_SB_DQ<19>")
	)
	(gr_poly
		(pts
			(xy 390.1948 -284.008068) (xy 390.094724 -283.907992) (xy 389.994648 -284.008068) (xy 389.994648 -284.052518)
			(xy 390.1948 -284.052518)
		)
		(stroke
			(width 0)
			(type solid)
		)
		(fill yes)
		(layer "In2.Cu")
		(net "M_I_CPU0_SB_DQ<16>")
	)
	(gr_poly
		(pts
			(xy 390.1948 -283.604208) (xy 390.1948 -283.559758) (xy 389.994648 -283.559758) (xy 389.994648 -283.604208)
			(xy 390.094724 -283.704284)
		)
		(stroke
			(width 0)
			(type solid)
		)
		(fill yes)
		(layer "In2.Cu")
		(net "M_I_CPU0_SB_DQ<15>")
	)
	(gr_poly
		(pts
			(xy 390.1948 -282.388056) (xy 390.094724 -282.28798) (xy 389.994648 -282.388056) (xy 389.994648 -282.432506)
			(xy 390.1948 -282.432506)
		)
		(stroke
			(width 0)
			(type solid)
		)
		(fill yes)
		(layer "In2.Cu")
		(net "M_I_CPU0_SB_DQ<12>")
	)
	(gr_poly
		(pts
			(xy 390.1948 -281.98445) (xy 390.1948 -281.936698) (xy 389.994648 -281.936698) (xy 389.994648 -281.98445)
			(xy 390.094724 -282.084272)
		)
		(stroke
			(width 0)
			(type solid)
		)
		(fill yes)
		(layer "In2.Cu")
		(net "M_I_CPU0_SB_DQS_DP<6>")
	)
	(gr_poly
		(pts
			(xy 390.1948 -280.76779) (xy 390.094724 -280.667968) (xy 389.994648 -280.76779) (xy 389.994648 -280.815542)
			(xy 390.1948 -280.815542)
		)
		(stroke
			(width 0)
			(type solid)
		)
		(fill yes)
		(layer "In2.Cu")
		(net "M_I_CPU0_SB_DQS_DP<1>")
	)
	(gr_poly
		(pts
			(xy 390.1948 -280.364184) (xy 390.1948 -280.319734) (xy 389.994648 -280.319734) (xy 389.994648 -280.364184)
			(xy 390.094724 -280.46426)
		)
		(stroke
			(width 0)
			(type solid)
		)
		(fill yes)
		(layer "In2.Cu")
		(net "M_I_CPU0_SB_DQ<11>")
	)
	(gr_poly
		(pts
			(xy 390.1948 -279.148032) (xy 390.094724 -279.047956) (xy 389.994648 -279.148032) (xy 389.994648 -279.192482)
			(xy 390.1948 -279.192482)
		)
		(stroke
			(width 0)
			(type solid)
		)
		(fill yes)
		(layer "In2.Cu")
		(net "M_I_CPU0_SB_DQ<8>")
	)
	(gr_poly
		(pts
			(xy 390.1948 -278.744172) (xy 390.1948 -278.699722) (xy 389.994648 -278.699722) (xy 389.994648 -278.744172)
			(xy 390.094724 -278.844248)
		)
		(stroke
			(width 0)
			(type solid)
		)
		(fill yes)
		(layer "In2.Cu")
		(net "M_I_CPU0_SB_DQ<7>")
	)
	(gr_poly
		(pts
			(xy 390.1948 -277.52802) (xy 390.094724 -277.427944) (xy 389.994648 -277.52802) (xy 389.994648 -277.57247)
			(xy 390.1948 -277.57247)
		)
		(stroke
			(width 0)
			(type solid)
		)
		(fill yes)
		(layer "In2.Cu")
		(net "M_I_CPU0_SB_DQ<4>")
	)
	(gr_poly
		(pts
			(xy 390.1948 -277.124414) (xy 390.1948 -277.076662) (xy 389.994648 -277.076662) (xy 389.994648 -277.124414)
			(xy 390.094724 -277.224236)
		)
		(stroke
			(width 0)
			(type solid)
		)
		(fill yes)
		(layer "In2.Cu")
		(net "M_I_CPU0_SB_DQS_DP<5>")
	)
	(gr_poly
		(pts
			(xy 390.1948 -275.907754) (xy 390.094724 -275.807932) (xy 389.994648 -275.907754) (xy 389.994648 -275.955506)
			(xy 390.1948 -275.955506)
		)
		(stroke
			(width 0)
			(type solid)
		)
		(fill yes)
		(layer "In2.Cu")
		(net "M_I_CPU0_SB_DQS_DP<0>")
	)
	(gr_poly
		(pts
			(xy 390.1948 -275.504148) (xy 390.1948 -275.459698) (xy 389.994648 -275.459698) (xy 389.994648 -275.504148)
			(xy 390.094724 -275.604224)
		)
		(stroke
			(width 0)
			(type solid)
		)
		(fill yes)
		(layer "In2.Cu")
		(net "M_I_CPU0_SB_DQ<3>")
	)
	(gr_poly
		(pts
			(xy 390.1948 -274.287996) (xy 390.094724 -274.18792) (xy 389.994648 -274.287996) (xy 389.994648 -274.332446)
			(xy 390.1948 -274.332446)
		)
		(stroke
			(width 0)
			(type solid)
		)
		(fill yes)
		(layer "In2.Cu")
		(net "M_I_CPU0_SB_DQ<0>")
	)
	(gr_poly
		(pts
			(xy 390.1948 -273.884136) (xy 390.1948 -273.839686) (xy 389.994648 -273.839686) (xy 389.994648 -273.884136)
			(xy 390.094724 -273.984212)
		)
		(stroke
			(width 0)
			(type solid)
		)
		(fill yes)
		(layer "In2.Cu")
		(net "M_I_CPU0_SB_CB<3>")
	)
	(gr_poly
		(pts
			(xy 390.1948 -272.667984) (xy 390.094724 -272.567908) (xy 389.994648 -272.667984) (xy 389.994648 -272.712434)
			(xy 390.1948 -272.712434)
		)
		(stroke
			(width 0)
			(type solid)
		)
		(fill yes)
		(layer "In2.Cu")
		(net "M_I_CPU0_SB_CB<0>")
	)
	(gr_poly
		(pts
			(xy 390.1948 -272.264378) (xy 390.1948 -272.216626) (xy 389.994648 -272.216626) (xy 389.994648 -272.264378)
			(xy 390.094724 -272.3642)
		)
		(stroke
			(width 0)
			(type solid)
		)
		(fill yes)
		(layer "In2.Cu")
		(net "M_I_CPU0_SB_DQS_DP<4>")
	)
	(gr_poly
		(pts
			(xy 390.1948 -271.047718) (xy 390.094724 -270.947896) (xy 389.994648 -271.047718) (xy 389.994648 -271.09547)
			(xy 390.1948 -271.09547)
		)
		(stroke
			(width 0)
			(type solid)
		)
		(fill yes)
		(layer "In2.Cu")
		(net "M_I_CPU0_SB_DQS_DP<9>")
	)
	(gr_poly
		(pts
			(xy 390.1948 -270.644112) (xy 390.1948 -270.599662) (xy 389.994648 -270.599662) (xy 389.994648 -270.644112)
			(xy 390.094724 -270.744188)
		)
		(stroke
			(width 0)
			(type solid)
		)
		(fill yes)
		(layer "In2.Cu")
		(net "M_I_CPU0_SB_CB<7>")
	)
	(gr_poly
		(pts
			(xy 390.1948 -269.42796) (xy 390.094724 -269.327884) (xy 389.994648 -269.42796) (xy 389.994648 -269.47241)
			(xy 390.1948 -269.47241)
		)
		(stroke
			(width 0)
			(type solid)
		)
		(fill yes)
		(layer "In2.Cu")
		(net "M_I_CPU0_SB_CB<4>")
	)
	(gr_poly
		(pts
			(xy 390.1948 -267.404088) (xy 390.1948 -267.359638) (xy 389.994648 -267.359638) (xy 389.994648 -267.404088)
			(xy 390.094724 -267.504164)
		)
		(stroke
			(width 0)
			(type solid)
		)
		(fill yes)
		(layer "In2.Cu")
		(net "M_I_CPU0_SB_RSP<0>")
	)
	(gr_poly
		(pts
			(xy 390.1948 -265.784076) (xy 390.1948 -265.739626) (xy 389.994648 -265.739626) (xy 389.994648 -265.784076)
			(xy 390.094724 -265.884152)
		)
		(stroke
			(width 0)
			(type solid)
		)
		(fill yes)
		(layer "In2.Cu")
		(net "M_I_CPU0_SB_CS_N<0>")
	)
	(gr_poly
		(pts
			(xy 390.1948 -264.567924) (xy 390.094724 -264.467848) (xy 389.994648 -264.567924) (xy 389.994648 -264.612374)
			(xy 390.1948 -264.612374)
		)
		(stroke
			(width 0)
			(type solid)
		)
		(fill yes)
		(layer "In2.Cu")
		(net "M_I_CPU0_SB_CA<6>")
	)
	(gr_poly
		(pts
			(xy 390.1948 -264.164064) (xy 390.1948 -264.119614) (xy 389.994648 -264.119614) (xy 389.994648 -264.164064)
			(xy 390.094724 -264.26414)
		)
		(stroke
			(width 0)
			(type solid)
		)
		(fill yes)
		(layer "In2.Cu")
		(net "M_I_CPU0_SB_CA<5>")
	)
	(gr_poly
		(pts
			(xy 390.1948 -262.947912) (xy 390.094724 -262.847836) (xy 389.994648 -262.947912) (xy 389.994648 -262.992362)
			(xy 390.1948 -262.992362)
		)
		(stroke
			(width 0)
			(type solid)
		)
		(fill yes)
		(layer "In2.Cu")
		(net "M_I_CPU0_SB_CA<2>")
	)
	(gr_poly
		(pts
			(xy 390.1948 -262.544052) (xy 390.1948 -262.499602) (xy 389.994648 -262.499602) (xy 389.994648 -262.544052)
			(xy 390.094724 -262.644128)
		)
		(stroke
			(width 0)
			(type solid)
		)
		(fill yes)
		(layer "In2.Cu")
		(net "M_I_CPU0_SB_CA<1>")
	)
	(gr_poly
		(pts
			(xy 390.214104 -293.32809) (xy 390.250934 -293.191438) (xy 390.114282 -293.154862) (xy 390.075674 -293.177214)
			(xy 390.17575 -293.350442)
		)
		(stroke
			(width 0)
			(type solid)
		)
		(fill yes)
		(layer "In2.Cu")
		(net "M_I_CPU0_SB_DQ<29>")
	)
	(gr_poly
		(pts
			(xy 390.283954 -229.555294) (xy 390.245346 -229.532942) (xy 390.108694 -229.569518) (xy 390.145524 -229.70617)
			(xy 390.183878 -229.728522)
		)
		(stroke
			(width 0)
			(type solid)
		)
		(fill yes)
		(layer "In2.Cu")
		(net "M_I_CPU0_SA_DQ<8>")
	)
	(gr_poly
		(pts
			(xy 390.283954 -227.935536) (xy 390.245346 -227.913184) (xy 390.108694 -227.94976) (xy 390.145524 -228.086412)
			(xy 390.183878 -228.108764)
		)
		(stroke
			(width 0)
			(type solid)
		)
		(fill yes)
		(layer "In2.Cu")
		(net "M_I_CPU0_SA_DQ<5>")
	)
	(gr_poly
		(pts
			(xy 390.283954 -226.315524) (xy 390.245346 -226.293172) (xy 390.108694 -226.329748) (xy 390.145524 -226.4664)
			(xy 390.183878 -226.488752)
		)
		(stroke
			(width 0)
			(type solid)
		)
		(fill yes)
		(layer "In2.Cu")
		(net "M_I_CPU0_SA_DQ<4>")
	)
	(gr_poly
		(pts
			(xy 390.286748 -224.696274) (xy 390.2456 -224.672652) (xy 390.108948 -224.709228) (xy 390.145524 -224.845626)
			(xy 390.186926 -224.869502)
		)
		(stroke
			(width 0)
			(type solid)
		)
		(fill yes)
		(layer "In2.Cu")
		(net "M_I_CPU0_SA_DQS_DN<5>")
	)
	(gr_poly
		(pts
			(xy 390.286748 -223.076262) (xy 390.2456 -223.05264) (xy 390.108948 -223.089216) (xy 390.145524 -223.225614)
			(xy 390.186926 -223.24949)
		)
		(stroke
			(width 0)
			(type solid)
		)
		(fill yes)
		(layer "In2.Cu")
		(net "M_I_CPU0_SA_DQS_DP<0>")
	)
	(gr_poly
		(pts
			(xy 390.36498 -256.025904) (xy 390.264904 -255.926082) (xy 390.164828 -256.025904) (xy 390.164828 -256.073656)
			(xy 390.36498 -256.073656)
		)
		(stroke
			(width 0)
			(type solid)
		)
		(fill yes)
		(layer "In2.Cu")
		(net "M_I_CPU0_CLK_DP<0>")
	)
	(gr_poly
		(pts
			(xy 390.36498 -255.622298) (xy 390.36498 -255.577848) (xy 390.164828 -255.577848) (xy 390.164828 -255.622298)
			(xy 390.264904 -255.722374)
		)
		(stroke
			(width 0)
			(type solid)
		)
		(fill yes)
		(layer "In2.Cu")
		(net "M_I_CPU0_SA_PAR")
	)
	(gr_poly
		(pts
			(xy 390.36498 -254.406146) (xy 390.264904 -254.30607) (xy 390.164828 -254.406146) (xy 390.164828 -254.450596)
			(xy 390.36498 -254.450596)
		)
		(stroke
			(width 0)
			(type solid)
		)
		(fill yes)
		(layer "In2.Cu")
		(net "M_I_CPU0_SA_CA<4>")
	)
	(gr_poly
		(pts
			(xy 390.36498 -254.002286) (xy 390.36498 -253.957836) (xy 390.164828 -253.957836) (xy 390.164828 -254.002286)
			(xy 390.264904 -254.102362)
		)
		(stroke
			(width 0)
			(type solid)
		)
		(fill yes)
		(layer "In2.Cu")
		(net "M_I_CPU0_SA_CA<3>")
	)
	(gr_poly
		(pts
			(xy 390.36498 -252.786134) (xy 390.264904 -252.686058) (xy 390.164828 -252.786134) (xy 390.164828 -252.830584)
			(xy 390.36498 -252.830584)
		)
		(stroke
			(width 0)
			(type solid)
		)
		(fill yes)
		(layer "In2.Cu")
		(net "M_I_CPU0_SA_CA<0>")
	)
	(gr_poly
		(pts
			(xy 390.36498 -251.166122) (xy 390.264904 -251.066046) (xy 390.164828 -251.166122) (xy 390.164828 -251.210572)
			(xy 390.36498 -251.210572)
		)
		(stroke
			(width 0)
			(type solid)
		)
		(fill yes)
		(layer "In2.Cu")
		(net "M_I_CPU0_SA_CS_N<0>")
	)
	(gr_poly
		(pts
			(xy 390.36498 -250.762262) (xy 390.36498 -250.717812) (xy 390.164828 -250.717812) (xy 390.164828 -250.762262)
			(xy 390.264904 -250.862338)
		)
		(stroke
			(width 0)
			(type solid)
		)
		(fill yes)
		(layer "In2.Cu")
		(net "M_I_CPU0_RESET_N")
	)
	(gr_poly
		(pts
			(xy 390.36498 -249.14225) (xy 390.36498 -249.0978) (xy 390.164828 -249.0978) (xy 390.164828 -249.14225)
			(xy 390.264904 -249.242326)
		)
		(stroke
			(width 0)
			(type solid)
		)
		(fill yes)
		(layer "In2.Cu")
		(net "M_I_CPU0_SA_CB<7>")
	)
	(gr_poly
		(pts
			(xy 390.36498 -247.926098) (xy 390.264904 -247.826022) (xy 390.164828 -247.926098) (xy 390.164828 -247.970548)
			(xy 390.36498 -247.970548)
		)
		(stroke
			(width 0)
			(type solid)
		)
		(fill yes)
		(layer "In2.Cu")
		(net "M_I_CPU0_SA_CB<4>")
	)
	(gr_poly
		(pts
			(xy 390.36498 -247.522492) (xy 390.36498 -247.47474) (xy 390.164828 -247.47474) (xy 390.164828 -247.522492)
			(xy 390.264904 -247.622314)
		)
		(stroke
			(width 0)
			(type solid)
		)
		(fill yes)
		(layer "In2.Cu")
		(net "M_I_CPU0_SA_DQS_DP<9>")
	)
	(gr_poly
		(pts
			(xy 390.36498 -246.305832) (xy 390.264904 -246.20601) (xy 390.164828 -246.305832) (xy 390.164828 -246.353584)
			(xy 390.36498 -246.353584)
		)
		(stroke
			(width 0)
			(type solid)
		)
		(fill yes)
		(layer "In2.Cu")
		(net "M_I_CPU0_SA_DQS_DP<4>")
	)
	(gr_poly
		(pts
			(xy 390.36498 -245.902226) (xy 390.36498 -245.857776) (xy 390.164828 -245.857776) (xy 390.164828 -245.902226)
			(xy 390.264904 -246.002302)
		)
		(stroke
			(width 0)
			(type solid)
		)
		(fill yes)
		(layer "In2.Cu")
		(net "M_I_CPU0_SA_CB<3>")
	)
	(gr_poly
		(pts
			(xy 390.36498 -244.686074) (xy 390.264904 -244.585998) (xy 390.164828 -244.686074) (xy 390.164828 -244.730524)
			(xy 390.36498 -244.730524)
		)
		(stroke
			(width 0)
			(type solid)
		)
		(fill yes)
		(layer "In2.Cu")
		(net "M_I_CPU0_SA_CB<0>")
	)
	(gr_poly
		(pts
			(xy 390.36498 -244.282214) (xy 390.36498 -244.237764) (xy 390.164828 -244.237764) (xy 390.164828 -244.282214)
			(xy 390.264904 -244.38229)
		)
		(stroke
			(width 0)
			(type solid)
		)
		(fill yes)
		(layer "In2.Cu")
		(net "M_I_CPU0_SA_DQ<31>")
	)
	(gr_poly
		(pts
			(xy 390.36498 -243.066062) (xy 390.264904 -242.965986) (xy 390.164828 -243.066062) (xy 390.164828 -243.110512)
			(xy 390.36498 -243.110512)
		)
		(stroke
			(width 0)
			(type solid)
		)
		(fill yes)
		(layer "In2.Cu")
		(net "M_I_CPU0_SA_DQ<28>")
	)
	(gr_poly
		(pts
			(xy 390.36498 -242.662456) (xy 390.36498 -242.614704) (xy 390.164828 -242.614704) (xy 390.164828 -242.662456)
			(xy 390.264904 -242.762278)
		)
		(stroke
			(width 0)
			(type solid)
		)
		(fill yes)
		(layer "In2.Cu")
		(net "M_I_CPU0_SA_DQS_DP<8>")
	)
	(gr_poly
		(pts
			(xy 390.36498 -241.445796) (xy 390.264904 -241.345974) (xy 390.164828 -241.445796) (xy 390.164828 -241.493548)
			(xy 390.36498 -241.493548)
		)
		(stroke
			(width 0)
			(type solid)
		)
		(fill yes)
		(layer "In2.Cu")
		(net "M_I_CPU0_SA_DQS_DP<3>")
	)
	(gr_poly
		(pts
			(xy 390.36498 -241.04219) (xy 390.36498 -240.99774) (xy 390.164828 -240.99774) (xy 390.164828 -241.04219)
			(xy 390.264904 -241.142266)
		)
		(stroke
			(width 0)
			(type solid)
		)
		(fill yes)
		(layer "In2.Cu")
		(net "M_I_CPU0_SA_DQ<27>")
	)
	(gr_poly
		(pts
			(xy 390.36498 -239.826038) (xy 390.264904 -239.725962) (xy 390.164828 -239.826038) (xy 390.164828 -239.870488)
			(xy 390.36498 -239.870488)
		)
		(stroke
			(width 0)
			(type solid)
		)
		(fill yes)
		(layer "In2.Cu")
		(net "M_I_CPU0_SA_DQ<24>")
	)
	(gr_poly
		(pts
			(xy 390.36498 -239.422178) (xy 390.36498 -239.377728) (xy 390.164828 -239.377728) (xy 390.164828 -239.422178)
			(xy 390.264904 -239.522254)
		)
		(stroke
			(width 0)
			(type solid)
		)
		(fill yes)
		(layer "In2.Cu")
		(net "M_I_CPU0_SA_DQ<23>")
	)
	(gr_poly
		(pts
			(xy 390.36498 -238.206026) (xy 390.264904 -238.10595) (xy 390.164828 -238.206026) (xy 390.164828 -238.250476)
			(xy 390.36498 -238.250476)
		)
		(stroke
			(width 0)
			(type solid)
		)
		(fill yes)
		(layer "In2.Cu")
		(net "M_I_CPU0_SA_DQ<20>")
	)
	(gr_poly
		(pts
			(xy 390.36498 -237.80242) (xy 390.36498 -237.754668) (xy 390.164828 -237.754668) (xy 390.164828 -237.80242)
			(xy 390.264904 -237.902242)
		)
		(stroke
			(width 0)
			(type solid)
		)
		(fill yes)
		(layer "In2.Cu")
		(net "M_I_CPU0_SA_DQS_DP<7>")
	)
	(gr_poly
		(pts
			(xy 390.36498 -236.58576) (xy 390.264904 -236.485938) (xy 390.164828 -236.58576) (xy 390.164828 -236.633512)
			(xy 390.36498 -236.633512)
		)
		(stroke
			(width 0)
			(type solid)
		)
		(fill yes)
		(layer "In2.Cu")
		(net "M_I_CPU0_SA_DQS_DP<2>")
	)
	(gr_poly
		(pts
			(xy 390.36498 -236.182154) (xy 390.36498 -236.137704) (xy 390.164828 -236.137704) (xy 390.164828 -236.182154)
			(xy 390.264904 -236.28223)
		)
		(stroke
			(width 0)
			(type solid)
		)
		(fill yes)
		(layer "In2.Cu")
		(net "M_I_CPU0_SA_DQ<19>")
	)
	(gr_poly
		(pts
			(xy 390.36498 -234.966002) (xy 390.264904 -234.865926) (xy 390.164828 -234.966002) (xy 390.164828 -235.010452)
			(xy 390.36498 -235.010452)
		)
		(stroke
			(width 0)
			(type solid)
		)
		(fill yes)
		(layer "In2.Cu")
		(net "M_I_CPU0_SA_DQ<16>")
	)
	(gr_poly
		(pts
			(xy 390.36498 -234.562142) (xy 390.36498 -234.517692) (xy 390.164828 -234.517692) (xy 390.164828 -234.562142)
			(xy 390.264904 -234.662218)
		)
		(stroke
			(width 0)
			(type solid)
		)
		(fill yes)
		(layer "In2.Cu")
		(net "M_I_CPU0_SA_DQ<15>")
	)
	(gr_poly
		(pts
			(xy 390.36498 -233.34599) (xy 390.264904 -233.245914) (xy 390.164828 -233.34599) (xy 390.164828 -233.39044)
			(xy 390.36498 -233.39044)
		)
		(stroke
			(width 0)
			(type solid)
		)
		(fill yes)
		(layer "In2.Cu")
		(net "M_I_CPU0_SA_DQ<12>")
	)
	(gr_poly
		(pts
			(xy 390.36498 -232.942384) (xy 390.36498 -232.894632) (xy 390.164828 -232.894632) (xy 390.164828 -232.942384)
			(xy 390.264904 -233.042206)
		)
		(stroke
			(width 0)
			(type solid)
		)
		(fill yes)
		(layer "In2.Cu")
		(net "M_I_CPU0_SA_DQS_DP<6>")
	)
	(gr_poly
		(pts
			(xy 390.36498 -231.725724) (xy 390.264904 -231.625902) (xy 390.164828 -231.725724) (xy 390.164828 -231.773476)
			(xy 390.36498 -231.773476)
		)
		(stroke
			(width 0)
			(type solid)
		)
		(fill yes)
		(layer "In2.Cu")
		(net "M_I_CPU0_SA_DQS_DP<1>")
	)
	(gr_poly
		(pts
			(xy 390.36498 -231.322372) (xy 390.36498 -231.277922) (xy 390.164828 -231.277922) (xy 390.164828 -231.322372)
			(xy 390.264904 -231.422448)
		)
		(stroke
			(width 0)
			(type solid)
		)
		(fill yes)
		(layer "In2.Cu")
		(net "M_I_CPU0_SA_DQ<11>")
	)
	(gr_poly
		(pts
			(xy 390.420098 -230.239824) (xy 390.383522 -230.103172) (xy 390.344914 -230.081074) (xy 390.244838 -230.254302)
			(xy 390.283446 -230.2764)
		)
		(stroke
			(width 0)
			(type solid)
		)
		(fill yes)
		(layer "In2.Cu")
		(net "M_I_CPU0_SA_DQ<10>")
	)
	(gr_poly
		(pts
			(xy 390.420606 -228.618796) (xy 390.38403 -228.482144) (xy 390.345676 -228.459792) (xy 390.2456 -228.63302)
			(xy 390.284208 -228.655372)
		)
		(stroke
			(width 0)
			(type solid)
		)
		(fill yes)
		(layer "In2.Cu")
		(net "M_I_CPU0_SA_DQ<7>")
	)
	(gr_poly
		(pts
			(xy 390.420606 -226.998784) (xy 390.38403 -226.862132) (xy 390.345676 -226.83978) (xy 390.2456 -227.013008)
			(xy 390.284208 -227.03536)
		)
		(stroke
			(width 0)
			(type solid)
		)
		(fill yes)
		(layer "In2.Cu")
		(net "M_I_CPU0_SA_DQ<6>")
	)
	(gr_poly
		(pts
			(xy 390.420606 -225.37928) (xy 390.38403 -225.242882) (xy 390.342628 -225.219006) (xy 390.242806 -225.392234)
			(xy 390.283954 -225.415856)
		)
		(stroke
			(width 0)
			(type solid)
		)
		(fill yes)
		(layer "In2.Cu")
		(net "M_I_CPU0_SA_DQS_DP<5>")
	)
	(gr_poly
		(pts
			(xy 390.420606 -223.759268) (xy 390.38403 -223.62287) (xy 390.342628 -223.598994) (xy 390.242806 -223.772222)
			(xy 390.283954 -223.795844)
		)
		(stroke
			(width 0)
			(type solid)
		)
		(fill yes)
		(layer "In2.Cu")
		(net "M_I_CPU0_SA_DQS_DN<0>")
	)
	(gr_poly
		(pts
			(xy 390.583928 -294.684704) (xy 390.483852 -294.511476) (xy 390.445498 -294.533828) (xy 390.408922 -294.67048)
			(xy 390.54532 -294.707056)
		)
		(stroke
			(width 0)
			(type solid)
		)
		(fill yes)
		(layer "In2.Cu")
		(net "M_I_CPU0_SB_DQ<31>")
	)
	(gr_poly
		(pts
			(xy 390.583928 -293.064692) (xy 390.483852 -292.891464) (xy 390.445498 -292.913816) (xy 390.408922 -293.050468)
			(xy 390.54532 -293.087044)
		)
		(stroke
			(width 0)
			(type solid)
		)
		(fill yes)
		(layer "In2.Cu")
		(net "M_I_CPU0_SB_DQ<30>")
	)
	(gr_poly
		(pts
			(xy 390.664954 -291.297614) (xy 390.564878 -291.197792) (xy 390.464802 -291.297614) (xy 390.464802 -291.345366)
			(xy 390.664954 -291.345366)
		)
		(stroke
			(width 0)
			(type solid)
		)
		(fill yes)
		(layer "In2.Cu")
		(net "M_I_CPU0_SB_DQS_DN<8>")
	)
	(gr_poly
		(pts
			(xy 390.664954 -290.894262) (xy 390.664954 -290.84651) (xy 390.464802 -290.84651) (xy 390.464802 -290.894262)
			(xy 390.564878 -290.994084)
		)
		(stroke
			(width 0)
			(type solid)
		)
		(fill yes)
		(layer "In2.Cu")
		(net "M_I_CPU0_SB_DQS_DN<3>")
	)
	(gr_poly
		(pts
			(xy 390.664954 -289.677856) (xy 390.564878 -289.57778) (xy 390.464802 -289.677856) (xy 390.464802 -289.722306)
			(xy 390.664954 -289.722306)
		)
		(stroke
			(width 0)
			(type solid)
		)
		(fill yes)
		(layer "In2.Cu")
		(net "M_I_CPU0_SB_DQ<25>")
	)
	(gr_poly
		(pts
			(xy 390.664954 -289.273996) (xy 390.664954 -289.229546) (xy 390.464802 -289.229546) (xy 390.464802 -289.273996)
			(xy 390.564878 -289.374072)
		)
		(stroke
			(width 0)
			(type solid)
		)
		(fill yes)
		(layer "In2.Cu")
		(net "M_I_CPU0_SB_DQ<26>")
	)
	(gr_poly
		(pts
			(xy 390.664954 -288.057844) (xy 390.564878 -287.957768) (xy 390.464802 -288.057844) (xy 390.464802 -288.102294)
			(xy 390.664954 -288.102294)
		)
		(stroke
			(width 0)
			(type solid)
		)
		(fill yes)
		(layer "In2.Cu")
		(net "M_I_CPU0_SB_DQ<21>")
	)
	(gr_poly
		(pts
			(xy 390.664954 -287.654238) (xy 390.664954 -287.609788) (xy 390.464802 -287.609788) (xy 390.464802 -287.654238)
			(xy 390.564878 -287.75406)
		)
		(stroke
			(width 0)
			(type solid)
		)
		(fill yes)
		(layer "In2.Cu")
		(net "M_I_CPU0_SB_DQ<22>")
	)
	(gr_poly
		(pts
			(xy 390.664954 -286.437832) (xy 390.564878 -286.337756) (xy 390.464802 -286.437832) (xy 390.464802 -286.485584)
			(xy 390.664954 -286.485584)
		)
		(stroke
			(width 0)
			(type solid)
		)
		(fill yes)
		(layer "In2.Cu")
		(net "M_I_CPU0_SB_DQS_DN<7>")
	)
	(gr_poly
		(pts
			(xy 390.664954 -286.03448) (xy 390.664954 -285.986728) (xy 390.464802 -285.986728) (xy 390.464802 -286.03448)
			(xy 390.564878 -286.134302)
		)
		(stroke
			(width 0)
			(type solid)
		)
		(fill yes)
		(layer "In2.Cu")
		(net "M_I_CPU0_SB_DQS_DN<2>")
	)
	(gr_poly
		(pts
			(xy 390.664954 -284.818074) (xy 390.564878 -284.717998) (xy 390.464802 -284.818074) (xy 390.464802 -284.862524)
			(xy 390.664954 -284.862524)
		)
		(stroke
			(width 0)
			(type solid)
		)
		(fill yes)
		(layer "In2.Cu")
		(net "M_I_CPU0_SB_DQ<17>")
	)
	(gr_poly
		(pts
			(xy 390.664954 -284.414214) (xy 390.664954 -284.369764) (xy 390.464802 -284.369764) (xy 390.464802 -284.414214)
			(xy 390.564878 -284.51429)
		)
		(stroke
			(width 0)
			(type solid)
		)
		(fill yes)
		(layer "In2.Cu")
		(net "M_I_CPU0_SB_DQ<18>")
	)
	(gr_poly
		(pts
			(xy 390.664954 -283.198062) (xy 390.564878 -283.097986) (xy 390.464802 -283.198062) (xy 390.464802 -283.242512)
			(xy 390.664954 -283.242512)
		)
		(stroke
			(width 0)
			(type solid)
		)
		(fill yes)
		(layer "In2.Cu")
		(net "M_I_CPU0_SB_DQ<13>")
	)
	(gr_poly
		(pts
			(xy 390.664954 -282.794202) (xy 390.664954 -282.749752) (xy 390.464802 -282.749752) (xy 390.464802 -282.794202)
			(xy 390.564878 -282.894278)
		)
		(stroke
			(width 0)
			(type solid)
		)
		(fill yes)
		(layer "In2.Cu")
		(net "M_I_CPU0_SB_DQ<14>")
	)
	(gr_poly
		(pts
			(xy 390.664954 -281.577796) (xy 390.564878 -281.477974) (xy 390.464802 -281.577796) (xy 390.464802 -281.625548)
			(xy 390.664954 -281.625548)
		)
		(stroke
			(width 0)
			(type solid)
		)
		(fill yes)
		(layer "In2.Cu")
		(net "M_I_CPU0_SB_DQS_DN<6>")
	)
	(gr_poly
		(pts
			(xy 390.664954 -281.174444) (xy 390.664954 -281.126692) (xy 390.464802 -281.126692) (xy 390.464802 -281.174444)
			(xy 390.564878 -281.274266)
		)
		(stroke
			(width 0)
			(type solid)
		)
		(fill yes)
		(layer "In2.Cu")
		(net "M_I_CPU0_SB_DQS_DN<1>")
	)
	(gr_poly
		(pts
			(xy 390.664954 -279.958038) (xy 390.564878 -279.857962) (xy 390.464802 -279.958038) (xy 390.464802 -280.002488)
			(xy 390.664954 -280.002488)
		)
		(stroke
			(width 0)
			(type solid)
		)
		(fill yes)
		(layer "In2.Cu")
		(net "M_I_CPU0_SB_DQ<9>")
	)
	(gr_poly
		(pts
			(xy 390.664954 -279.554178) (xy 390.664954 -279.509728) (xy 390.464802 -279.509728) (xy 390.464802 -279.554178)
			(xy 390.564878 -279.654254)
		)
		(stroke
			(width 0)
			(type solid)
		)
		(fill yes)
		(layer "In2.Cu")
		(net "M_I_CPU0_SB_DQ<10>")
	)
	(gr_poly
		(pts
			(xy 390.664954 -278.338026) (xy 390.564878 -278.23795) (xy 390.464802 -278.338026) (xy 390.464802 -278.382476)
			(xy 390.664954 -278.382476)
		)
		(stroke
			(width 0)
			(type solid)
		)
		(fill yes)
		(layer "In2.Cu")
		(net "M_I_CPU0_SB_DQ<5>")
	)
	(gr_poly
		(pts
			(xy 390.664954 -277.934166) (xy 390.664954 -277.889716) (xy 390.464802 -277.889716) (xy 390.464802 -277.934166)
			(xy 390.564878 -278.034242)
		)
		(stroke
			(width 0)
			(type solid)
		)
		(fill yes)
		(layer "In2.Cu")
		(net "M_I_CPU0_SB_DQ<6>")
	)
	(gr_poly
		(pts
			(xy 390.664954 -276.71776) (xy 390.564878 -276.617938) (xy 390.464802 -276.71776) (xy 390.464802 -276.765512)
			(xy 390.664954 -276.765512)
		)
		(stroke
			(width 0)
			(type solid)
		)
		(fill yes)
		(layer "In2.Cu")
		(net "M_I_CPU0_SB_DQS_DN<5>")
	)
	(gr_poly
		(pts
			(xy 390.664954 -276.314408) (xy 390.664954 -276.266656) (xy 390.464802 -276.266656) (xy 390.464802 -276.314408)
			(xy 390.564878 -276.41423)
		)
		(stroke
			(width 0)
			(type solid)
		)
		(fill yes)
		(layer "In2.Cu")
		(net "M_I_CPU0_SB_DQS_DN<0>")
	)
	(gr_poly
		(pts
			(xy 390.664954 -275.098002) (xy 390.564878 -274.997926) (xy 390.464802 -275.098002) (xy 390.464802 -275.142452)
			(xy 390.664954 -275.142452)
		)
		(stroke
			(width 0)
			(type solid)
		)
		(fill yes)
		(layer "In2.Cu")
		(net "M_I_CPU0_SB_DQ<1>")
	)
	(gr_poly
		(pts
			(xy 390.664954 -274.694142) (xy 390.664954 -274.649692) (xy 390.464802 -274.649692) (xy 390.464802 -274.694142)
			(xy 390.564878 -274.794218)
		)
		(stroke
			(width 0)
			(type solid)
		)
		(fill yes)
		(layer "In2.Cu")
		(net "M_I_CPU0_SB_DQ<2>")
	)
	(gr_poly
		(pts
			(xy 390.664954 -273.47799) (xy 390.564878 -273.377914) (xy 390.464802 -273.47799) (xy 390.464802 -273.52244)
			(xy 390.664954 -273.52244)
		)
		(stroke
			(width 0)
			(type solid)
		)
		(fill yes)
		(layer "In2.Cu")
		(net "M_I_CPU0_SB_CB<1>")
	)
	(gr_poly
		(pts
			(xy 390.664954 -273.07413) (xy 390.664954 -273.02968) (xy 390.464802 -273.02968) (xy 390.464802 -273.07413)
			(xy 390.564878 -273.174206)
		)
		(stroke
			(width 0)
			(type solid)
		)
		(fill yes)
		(layer "In2.Cu")
		(net "M_I_CPU0_SB_CB<2>")
	)
	(gr_poly
		(pts
			(xy 390.664954 -271.857724) (xy 390.564878 -271.757902) (xy 390.464802 -271.857724) (xy 390.464802 -271.905476)
			(xy 390.664954 -271.905476)
		)
		(stroke
			(width 0)
			(type solid)
		)
		(fill yes)
		(layer "In2.Cu")
		(net "M_I_CPU0_SB_DQS_DN<4>")
	)
	(gr_poly
		(pts
			(xy 390.664954 -271.454372) (xy 390.664954 -271.40662) (xy 390.464802 -271.40662) (xy 390.464802 -271.454372)
			(xy 390.564878 -271.554194)
		)
		(stroke
			(width 0)
			(type solid)
		)
		(fill yes)
		(layer "In2.Cu")
		(net "M_I_CPU0_SB_DQS_DN<9>")
	)
	(gr_poly
		(pts
			(xy 390.664954 -270.237966) (xy 390.564878 -270.13789) (xy 390.464802 -270.237966) (xy 390.464802 -270.282416)
			(xy 390.664954 -270.282416)
		)
		(stroke
			(width 0)
			(type solid)
		)
		(fill yes)
		(layer "In2.Cu")
		(net "M_I_CPU0_SB_CB<5>")
	)
	(gr_poly
		(pts
			(xy 390.664954 -269.834106) (xy 390.664954 -269.789656) (xy 390.464802 -269.789656) (xy 390.464802 -269.834106)
			(xy 390.564878 -269.934182)
		)
		(stroke
			(width 0)
			(type solid)
		)
		(fill yes)
		(layer "In2.Cu")
		(net "M_I_CPU0_SB_CB<6>")
	)
	(gr_poly
		(pts
			(xy 390.664954 -266.997942) (xy 390.564878 -266.897866) (xy 390.464802 -266.997942) (xy 390.464802 -267.042392)
			(xy 390.664954 -267.042392)
		)
		(stroke
			(width 0)
			(type solid)
		)
		(fill yes)
		(layer "In2.Cu")
		(net "M_I_CPU0_SA_RSP<0>")
	)
	(gr_poly
		(pts
			(xy 390.664954 -266.594082) (xy 390.664954 -266.549632) (xy 390.464802 -266.549632) (xy 390.464802 -266.594082)
			(xy 390.564878 -266.694158)
		)
		(stroke
			(width 0)
			(type solid)
		)
		(fill yes)
		(layer "In2.Cu")
		(net "M_I_CPU0_SB_CS_N<1>")
	)
	(gr_poly
		(pts
			(xy 390.664954 -265.37793) (xy 390.564878 -265.277854) (xy 390.464802 -265.37793) (xy 390.464802 -265.42238)
			(xy 390.664954 -265.42238)
		)
		(stroke
			(width 0)
			(type solid)
		)
		(fill yes)
		(layer "In2.Cu")
		(net "M_I_CPU0_SB_PAR")
	)
	(gr_poly
		(pts
			(xy 390.664954 -263.757918) (xy 390.564878 -263.657842) (xy 390.464802 -263.757918) (xy 390.464802 -263.802368)
			(xy 390.664954 -263.802368)
		)
		(stroke
			(width 0)
			(type solid)
		)
		(fill yes)
		(layer "In2.Cu")
		(net "M_I_CPU0_SB_CA<4>")
	)
	(gr_poly
		(pts
			(xy 390.664954 -263.354058) (xy 390.664954 -263.309608) (xy 390.464802 -263.309608) (xy 390.464802 -263.354058)
			(xy 390.564878 -263.454134)
		)
		(stroke
			(width 0)
			(type solid)
		)
		(fill yes)
		(layer "In2.Cu")
		(net "M_I_CPU0_SB_CA<3>")
	)
	(gr_poly
		(pts
			(xy 390.664954 -262.137906) (xy 390.564878 -262.03783) (xy 390.464802 -262.137906) (xy 390.464802 -262.182356)
			(xy 390.664954 -262.182356)
		)
		(stroke
			(width 0)
			(type solid)
		)
		(fill yes)
		(layer "In2.Cu")
		(net "M_I_CPU0_SB_CA<0>")
	)
	(gr_poly
		(pts
			(xy 390.684004 -294.138096) (xy 390.720834 -294.001444) (xy 390.584182 -293.964868) (xy 390.545574 -293.98722)
			(xy 390.64565 -294.160448)
		)
		(stroke
			(width 0)
			(type solid)
		)
		(fill yes)
		(layer "In2.Cu")
		(net "M_I_CPU0_SB_DQ<29>")
	)
	(gr_poly
		(pts
			(xy 390.684004 -292.518084) (xy 390.720834 -292.381432) (xy 390.584182 -292.344856) (xy 390.545574 -292.367208)
			(xy 390.64565 -292.540436)
		)
		(stroke
			(width 0)
			(type solid)
		)
		(fill yes)
		(layer "In2.Cu")
		(net "M_I_CPU0_SB_DQ<28>")
	)
	(gr_poly
		(pts
			(xy 390.75487 -228.744018) (xy 390.716262 -228.72192) (xy 390.57961 -228.758496) (xy 390.616186 -228.895148)
			(xy 390.654794 -228.917246)
		)
		(stroke
			(width 0)
			(type solid)
		)
		(fill yes)
		(layer "In2.Cu")
		(net "M_I_CPU0_SA_DQ<8>")
	)
	(gr_poly
		(pts
			(xy 390.75487 -227.124006) (xy 390.716262 -227.101908) (xy 390.57961 -227.138484) (xy 390.616186 -227.275136)
			(xy 390.654794 -227.297234)
		)
		(stroke
			(width 0)
			(type solid)
		)
		(fill yes)
		(layer "In2.Cu")
		(net "M_I_CPU0_SA_DQ<5>")
	)
	(gr_poly
		(pts
			(xy 390.75487 -225.503994) (xy 390.716262 -225.481896) (xy 390.57961 -225.518472) (xy 390.616186 -225.655124)
			(xy 390.654794 -225.677222)
		)
		(stroke
			(width 0)
			(type solid)
		)
		(fill yes)
		(layer "In2.Cu")
		(net "M_I_CPU0_SA_DQ<4>")
	)
	(gr_poly
		(pts
			(xy 390.755632 -230.36276) (xy 390.717024 -230.340408) (xy 390.580372 -230.376984) (xy 390.617202 -230.513636)
			(xy 390.655556 -230.535988)
		)
		(stroke
			(width 0)
			(type solid)
		)
		(fill yes)
		(layer "In2.Cu")
		(net "M_I_CPU0_SA_DQ<9>")
	)
	(gr_poly
		(pts
			(xy 390.756648 -222.266256) (xy 390.7155 -222.242634) (xy 390.578848 -222.27921) (xy 390.615424 -222.415608)
			(xy 390.656826 -222.439484)
		)
		(stroke
			(width 0)
			(type solid)
		)
		(fill yes)
		(layer "In2.Cu")
		(net "M_I_CPU0_SA_DQS_DP<0>")
	)
	(gr_poly
		(pts
			(xy 390.83488 -256.432558) (xy 390.83488 -256.384806) (xy 390.634728 -256.384806) (xy 390.634728 -256.432558)
			(xy 390.734804 -256.53238)
		)
		(stroke
			(width 0)
			(type solid)
		)
		(fill yes)
		(layer "In2.Cu")
		(net "M_I_CPU0_CLK_DN<0>")
	)
	(gr_poly
		(pts
			(xy 390.83488 -255.216152) (xy 390.734804 -255.116076) (xy 390.634728 -255.216152) (xy 390.634728 -255.260602)
			(xy 390.83488 -255.260602)
		)
		(stroke
			(width 0)
			(type solid)
		)
		(fill yes)
		(layer "In2.Cu")
		(net "M_I_CPU0_SA_CA<6>")
	)
	(gr_poly
		(pts
			(xy 390.83488 -254.812292) (xy 390.83488 -254.767842) (xy 390.634728 -254.767842) (xy 390.634728 -254.812292)
			(xy 390.734804 -254.912368)
		)
		(stroke
			(width 0)
			(type solid)
		)
		(fill yes)
		(layer "In2.Cu")
		(net "M_I_CPU0_SA_CA<5>")
	)
	(gr_poly
		(pts
			(xy 390.83488 -253.59614) (xy 390.734804 -253.496064) (xy 390.634728 -253.59614) (xy 390.634728 -253.64059)
			(xy 390.83488 -253.64059)
		)
		(stroke
			(width 0)
			(type solid)
		)
		(fill yes)
		(layer "In2.Cu")
		(net "M_I_CPU0_SA_CA<2>")
	)
	(gr_poly
		(pts
			(xy 390.83488 -253.19228) (xy 390.83488 -253.14783) (xy 390.634728 -253.14783) (xy 390.634728 -253.19228)
			(xy 390.734804 -253.292356)
		)
		(stroke
			(width 0)
			(type solid)
		)
		(fill yes)
		(layer "In2.Cu")
		(net "M_I_CPU0_SA_CA<1>")
	)
	(gr_poly
		(pts
			(xy 390.83488 -251.976128) (xy 390.734804 -251.876052) (xy 390.634728 -251.976128) (xy 390.634728 -252.020578)
			(xy 390.83488 -252.020578)
		)
		(stroke
			(width 0)
			(type solid)
		)
		(fill yes)
		(layer "In2.Cu")
		(net "M_I_CPU0_SA_CS_N<1>")
	)
	(gr_poly
		(pts
			(xy 390.83488 -250.356116) (xy 390.734804 -250.25604) (xy 390.634728 -250.356116) (xy 390.634728 -250.400566)
			(xy 390.83488 -250.400566)
		)
		(stroke
			(width 0)
			(type solid)
		)
		(fill yes)
		(layer "In2.Cu")
		(net "M_I_CPU0_ALERT_R_N")
	)
	(gr_poly
		(pts
			(xy 390.83488 -248.736104) (xy 390.734804 -248.636028) (xy 390.634728 -248.736104) (xy 390.634728 -248.780554)
			(xy 390.83488 -248.780554)
		)
		(stroke
			(width 0)
			(type solid)
		)
		(fill yes)
		(layer "In2.Cu")
		(net "M_I_CPU0_SA_CB<5>")
	)
	(gr_poly
		(pts
			(xy 390.83488 -248.332244) (xy 390.83488 -248.287794) (xy 390.634728 -248.287794) (xy 390.634728 -248.332244)
			(xy 390.734804 -248.43232)
		)
		(stroke
			(width 0)
			(type solid)
		)
		(fill yes)
		(layer "In2.Cu")
		(net "M_I_CPU0_SA_CB<6>")
	)
	(gr_poly
		(pts
			(xy 390.83488 -247.115838) (xy 390.734804 -247.016016) (xy 390.634728 -247.115838) (xy 390.634728 -247.16359)
			(xy 390.83488 -247.16359)
		)
		(stroke
			(width 0)
			(type solid)
		)
		(fill yes)
		(layer "In2.Cu")
		(net "M_I_CPU0_SA_DQS_DN<9>")
	)
	(gr_poly
		(pts
			(xy 390.83488 -246.712486) (xy 390.83488 -246.664734) (xy 390.634728 -246.664734) (xy 390.634728 -246.712486)
			(xy 390.734804 -246.812308)
		)
		(stroke
			(width 0)
			(type solid)
		)
		(fill yes)
		(layer "In2.Cu")
		(net "M_I_CPU0_SA_DQS_DN<4>")
	)
	(gr_poly
		(pts
			(xy 390.83488 -245.49608) (xy 390.734804 -245.396004) (xy 390.634728 -245.49608) (xy 390.634728 -245.54053)
			(xy 390.83488 -245.54053)
		)
		(stroke
			(width 0)
			(type solid)
		)
		(fill yes)
		(layer "In2.Cu")
		(net "M_I_CPU0_SA_CB<1>")
	)
	(gr_poly
		(pts
			(xy 390.83488 -245.09222) (xy 390.83488 -245.04777) (xy 390.634728 -245.04777) (xy 390.634728 -245.09222)
			(xy 390.734804 -245.192296)
		)
		(stroke
			(width 0)
			(type solid)
		)
		(fill yes)
		(layer "In2.Cu")
		(net "M_I_CPU0_SA_CB<2>")
	)
	(gr_poly
		(pts
			(xy 390.83488 -243.876068) (xy 390.734804 -243.775992) (xy 390.634728 -243.876068) (xy 390.634728 -243.920518)
			(xy 390.83488 -243.920518)
		)
		(stroke
			(width 0)
			(type solid)
		)
		(fill yes)
		(layer "In2.Cu")
		(net "M_I_CPU0_SA_DQ<29>")
	)
	(gr_poly
		(pts
			(xy 390.83488 -243.472208) (xy 390.83488 -243.427758) (xy 390.634728 -243.427758) (xy 390.634728 -243.472208)
			(xy 390.734804 -243.572284)
		)
		(stroke
			(width 0)
			(type solid)
		)
		(fill yes)
		(layer "In2.Cu")
		(net "M_I_CPU0_SA_DQ<30>")
	)
	(gr_poly
		(pts
			(xy 390.83488 -242.255802) (xy 390.734804 -242.15598) (xy 390.634728 -242.255802) (xy 390.634728 -242.303554)
			(xy 390.83488 -242.303554)
		)
		(stroke
			(width 0)
			(type solid)
		)
		(fill yes)
		(layer "In2.Cu")
		(net "M_I_CPU0_SA_DQS_DN<8>")
	)
	(gr_poly
		(pts
			(xy 390.83488 -241.85245) (xy 390.83488 -241.804698) (xy 390.634728 -241.804698) (xy 390.634728 -241.85245)
			(xy 390.734804 -241.952272)
		)
		(stroke
			(width 0)
			(type solid)
		)
		(fill yes)
		(layer "In2.Cu")
		(net "M_I_CPU0_SA_DQS_DN<3>")
	)
	(gr_poly
		(pts
			(xy 390.83488 -240.636044) (xy 390.734804 -240.535968) (xy 390.634728 -240.636044) (xy 390.634728 -240.680494)
			(xy 390.83488 -240.680494)
		)
		(stroke
			(width 0)
			(type solid)
		)
		(fill yes)
		(layer "In2.Cu")
		(net "M_I_CPU0_SA_DQ<25>")
	)
	(gr_poly
		(pts
			(xy 390.83488 -240.232184) (xy 390.83488 -240.187734) (xy 390.634728 -240.187734) (xy 390.634728 -240.232184)
			(xy 390.734804 -240.33226)
		)
		(stroke
			(width 0)
			(type solid)
		)
		(fill yes)
		(layer "In2.Cu")
		(net "M_I_CPU0_SA_DQ<26>")
	)
	(gr_poly
		(pts
			(xy 390.83488 -239.016032) (xy 390.734804 -238.915956) (xy 390.634728 -239.016032) (xy 390.634728 -239.060482)
			(xy 390.83488 -239.060482)
		)
		(stroke
			(width 0)
			(type solid)
		)
		(fill yes)
		(layer "In2.Cu")
		(net "M_I_CPU0_SA_DQ<21>")
	)
	(gr_poly
		(pts
			(xy 390.83488 -238.612172) (xy 390.83488 -238.567722) (xy 390.634728 -238.567722) (xy 390.634728 -238.612172)
			(xy 390.734804 -238.712248)
		)
		(stroke
			(width 0)
			(type solid)
		)
		(fill yes)
		(layer "In2.Cu")
		(net "M_I_CPU0_SA_DQ<22>")
	)
	(gr_poly
		(pts
			(xy 390.83488 -237.395766) (xy 390.734804 -237.295944) (xy 390.634728 -237.395766) (xy 390.634728 -237.443518)
			(xy 390.83488 -237.443518)
		)
		(stroke
			(width 0)
			(type solid)
		)
		(fill yes)
		(layer "In2.Cu")
		(net "M_I_CPU0_SA_DQS_DN<7>")
	)
	(gr_poly
		(pts
			(xy 390.83488 -236.992414) (xy 390.83488 -236.944662) (xy 390.634728 -236.944662) (xy 390.634728 -236.992414)
			(xy 390.734804 -237.092236)
		)
		(stroke
			(width 0)
			(type solid)
		)
		(fill yes)
		(layer "In2.Cu")
		(net "M_I_CPU0_SA_DQS_DN<2>")
	)
	(gr_poly
		(pts
			(xy 390.83488 -235.776008) (xy 390.734804 -235.675932) (xy 390.634728 -235.776008) (xy 390.634728 -235.820458)
			(xy 390.83488 -235.820458)
		)
		(stroke
			(width 0)
			(type solid)
		)
		(fill yes)
		(layer "In2.Cu")
		(net "M_I_CPU0_SA_DQ<17>")
	)
	(gr_poly
		(pts
			(xy 390.83488 -235.372148) (xy 390.83488 -235.327698) (xy 390.634728 -235.327698) (xy 390.634728 -235.372148)
			(xy 390.734804 -235.472224)
		)
		(stroke
			(width 0)
			(type solid)
		)
		(fill yes)
		(layer "In2.Cu")
		(net "M_I_CPU0_SA_DQ<18>")
	)
	(gr_poly
		(pts
			(xy 390.83488 -234.155996) (xy 390.734804 -234.05592) (xy 390.634728 -234.155996) (xy 390.634728 -234.200446)
			(xy 390.83488 -234.200446)
		)
		(stroke
			(width 0)
			(type solid)
		)
		(fill yes)
		(layer "In2.Cu")
		(net "M_I_CPU0_SA_DQ<13>")
	)
	(gr_poly
		(pts
			(xy 390.83488 -233.752136) (xy 390.83488 -233.707686) (xy 390.634728 -233.707686) (xy 390.634728 -233.752136)
			(xy 390.734804 -233.852212)
		)
		(stroke
			(width 0)
			(type solid)
		)
		(fill yes)
		(layer "In2.Cu")
		(net "M_I_CPU0_SA_DQ<14>")
	)
	(gr_poly
		(pts
			(xy 390.83488 -232.53573) (xy 390.734804 -232.435908) (xy 390.634728 -232.53573) (xy 390.634728 -232.583482)
			(xy 390.83488 -232.583482)
		)
		(stroke
			(width 0)
			(type solid)
		)
		(fill yes)
		(layer "In2.Cu")
		(net "M_I_CPU0_SA_DQS_DN<6>")
	)
	(gr_poly
		(pts
			(xy 390.83488 -232.132378) (xy 390.83488 -232.084626) (xy 390.634728 -232.084626) (xy 390.634728 -232.132378)
			(xy 390.734804 -232.2322)
		)
		(stroke
			(width 0)
			(type solid)
		)
		(fill yes)
		(layer "In2.Cu")
		(net "M_I_CPU0_SA_DQS_DN<1>")
	)
	(gr_poly
		(pts
			(xy 390.889998 -231.050084) (xy 390.853422 -230.913432) (xy 390.814814 -230.891334) (xy 390.714738 -231.064562)
			(xy 390.753346 -231.08666)
		)
		(stroke
			(width 0)
			(type solid)
		)
		(fill yes)
		(layer "In2.Cu")
		(net "M_I_CPU0_SA_DQ<11>")
	)
	(gr_poly
		(pts
			(xy 390.889998 -229.430072) (xy 390.853422 -229.29342) (xy 390.814814 -229.271322) (xy 390.714738 -229.44455)
			(xy 390.753346 -229.466648)
		)
		(stroke
			(width 0)
			(type solid)
		)
		(fill yes)
		(layer "In2.Cu")
		(net "M_I_CPU0_SA_DQ<10>")
	)
	(gr_poly
		(pts
			(xy 390.889998 -227.81006) (xy 390.853422 -227.673408) (xy 390.814814 -227.65131) (xy 390.714738 -227.824538)
			(xy 390.753346 -227.846636)
		)
		(stroke
			(width 0)
			(type solid)
		)
		(fill yes)
		(layer "In2.Cu")
		(net "M_I_CPU0_SA_DQ<7>")
	)
	(gr_poly
		(pts
			(xy 390.889998 -226.190048) (xy 390.853422 -226.053396) (xy 390.814814 -226.031298) (xy 390.714738 -226.204526)
			(xy 390.753346 -226.226624)
		)
		(stroke
			(width 0)
			(type solid)
		)
		(fill yes)
		(layer "In2.Cu")
		(net "M_I_CPU0_SA_DQ<6>")
	)
	(gr_poly
		(pts
			(xy 390.890506 -222.949262) (xy 390.85393 -222.812864) (xy 390.812528 -222.788988) (xy 390.712706 -222.962216)
			(xy 390.753854 -222.985838)
		)
		(stroke
			(width 0)
			(type solid)
		)
		(fill yes)
		(layer "In2.Cu")
		(net "M_I_CPU0_SA_DQS_DN<0>")
	)
	(gr_poly
		(pts
			(xy 391.054844 -295.496234) (xy 390.954768 -295.323006) (xy 390.91616 -295.345104) (xy 390.879584 -295.481756)
			(xy 391.016236 -295.518332)
		)
		(stroke
			(width 0)
			(type solid)
		)
		(fill yes)
		(layer "In2.Cu")
		(net "M_I_CPU0_SB_DQ<31>")
	)
	(gr_poly
		(pts
			(xy 391.054844 -293.876222) (xy 390.954768 -293.702994) (xy 390.91616 -293.725092) (xy 390.879584 -293.861744)
			(xy 391.016236 -293.89832)
		)
		(stroke
			(width 0)
			(type solid)
		)
		(fill yes)
		(layer "In2.Cu")
		(net "M_I_CPU0_SB_DQ<30>")
	)
	(gr_poly
		(pts
			(xy 391.057892 -292.255194) (xy 390.957816 -292.081966) (xy 390.916668 -292.105842) (xy 390.879838 -292.24224)
			(xy 391.01649 -292.27907)
		)
		(stroke
			(width 0)
			(type solid)
		)
		(fill yes)
		(layer "In2.Cu")
		(net "M_I_CPU0_SB_DQS_DP<8>")
	)
	(gr_poly
		(pts
			(xy 391.134854 -290.487608) (xy 391.034778 -290.387786) (xy 390.934702 -290.487608) (xy 390.934702 -290.53536)
			(xy 391.134854 -290.53536)
		)
		(stroke
			(width 0)
			(type solid)
		)
		(fill yes)
		(layer "In2.Cu")
		(net "M_I_CPU0_SB_DQS_DP<3>")
	)
	(gr_poly
		(pts
			(xy 391.134854 -290.084002) (xy 391.134854 -290.039552) (xy 390.934702 -290.039552) (xy 390.934702 -290.084002)
			(xy 391.034778 -290.184078)
		)
		(stroke
			(width 0)
			(type solid)
		)
		(fill yes)
		(layer "In2.Cu")
		(net "M_I_CPU0_SB_DQ<27>")
	)
	(gr_poly
		(pts
			(xy 391.134854 -288.86785) (xy 391.034778 -288.767774) (xy 390.934702 -288.86785) (xy 390.934702 -288.9123)
			(xy 391.134854 -288.9123)
		)
		(stroke
			(width 0)
			(type solid)
		)
		(fill yes)
		(layer "In2.Cu")
		(net "M_I_CPU0_SB_DQ<24>")
	)
	(gr_poly
		(pts
			(xy 391.134854 -288.464244) (xy 391.134854 -288.419794) (xy 390.934702 -288.419794) (xy 390.934702 -288.464244)
			(xy 391.034778 -288.56432)
		)
		(stroke
			(width 0)
			(type solid)
		)
		(fill yes)
		(layer "In2.Cu")
		(net "M_I_CPU0_SB_DQ<23>")
	)
	(gr_poly
		(pts
			(xy 391.134854 -287.247838) (xy 391.034778 -287.148016) (xy 390.934702 -287.247838) (xy 390.934702 -287.292288)
			(xy 391.134854 -287.292288)
		)
		(stroke
			(width 0)
			(type solid)
		)
		(fill yes)
		(layer "In2.Cu")
		(net "M_I_CPU0_SB_DQ<20>")
	)
	(gr_poly
		(pts
			(xy 391.134854 -286.844232) (xy 391.134854 -286.79648) (xy 390.934702 -286.79648) (xy 390.934702 -286.844232)
			(xy 391.034778 -286.944308)
		)
		(stroke
			(width 0)
			(type solid)
		)
		(fill yes)
		(layer "In2.Cu")
		(net "M_I_CPU0_SB_DQS_DP<7>")
	)
	(gr_poly
		(pts
			(xy 391.134854 -285.627826) (xy 391.034778 -285.528004) (xy 390.934702 -285.627826) (xy 390.934702 -285.675578)
			(xy 391.134854 -285.675578)
		)
		(stroke
			(width 0)
			(type solid)
		)
		(fill yes)
		(layer "In2.Cu")
		(net "M_I_CPU0_SB_DQS_DP<2>")
	)
	(gr_poly
		(pts
			(xy 391.134854 -285.22422) (xy 391.134854 -285.17977) (xy 390.934702 -285.17977) (xy 390.934702 -285.22422)
			(xy 391.034778 -285.324296)
		)
		(stroke
			(width 0)
			(type solid)
		)
		(fill yes)
		(layer "In2.Cu")
		(net "M_I_CPU0_SB_DQ<19>")
	)
	(gr_poly
		(pts
			(xy 391.134854 -284.008068) (xy 391.034778 -283.907992) (xy 390.934702 -284.008068) (xy 390.934702 -284.052518)
			(xy 391.134854 -284.052518)
		)
		(stroke
			(width 0)
			(type solid)
		)
		(fill yes)
		(layer "In2.Cu")
		(net "M_I_CPU0_SB_DQ<16>")
	)
	(gr_poly
		(pts
			(xy 391.134854 -283.604208) (xy 391.134854 -283.559758) (xy 390.934702 -283.559758) (xy 390.934702 -283.604208)
			(xy 391.034778 -283.704284)
		)
		(stroke
			(width 0)
			(type solid)
		)
		(fill yes)
		(layer "In2.Cu")
		(net "M_I_CPU0_SB_DQ<15>")
	)
	(gr_poly
		(pts
			(xy 391.134854 -282.388056) (xy 391.034778 -282.28798) (xy 390.934702 -282.388056) (xy 390.934702 -282.432506)
			(xy 391.134854 -282.432506)
		)
		(stroke
			(width 0)
			(type solid)
		)
		(fill yes)
		(layer "In2.Cu")
		(net "M_I_CPU0_SB_DQ<12>")
	)
	(gr_poly
		(pts
			(xy 391.134854 -281.98445) (xy 391.134854 -281.936698) (xy 390.934702 -281.936698) (xy 390.934702 -281.98445)
			(xy 391.034778 -282.084272)
		)
		(stroke
			(width 0)
			(type solid)
		)
		(fill yes)
		(layer "In2.Cu")
		(net "M_I_CPU0_SB_DQS_DP<6>")
	)
	(gr_poly
		(pts
			(xy 391.134854 -280.76779) (xy 391.034778 -280.667968) (xy 390.934702 -280.76779) (xy 390.934702 -280.815542)
			(xy 391.134854 -280.815542)
		)
		(stroke
			(width 0)
			(type solid)
		)
		(fill yes)
		(layer "In2.Cu")
		(net "M_I_CPU0_SB_DQS_DP<1>")
	)
	(gr_poly
		(pts
			(xy 391.134854 -280.364184) (xy 391.134854 -280.319734) (xy 390.934702 -280.319734) (xy 390.934702 -280.364184)
			(xy 391.034778 -280.46426)
		)
		(stroke
			(width 0)
			(type solid)
		)
		(fill yes)
		(layer "In2.Cu")
		(net "M_I_CPU0_SB_DQ<11>")
	)
	(gr_poly
		(pts
			(xy 391.134854 -279.148032) (xy 391.034778 -279.047956) (xy 390.934702 -279.148032) (xy 390.934702 -279.192482)
			(xy 391.134854 -279.192482)
		)
		(stroke
			(width 0)
			(type solid)
		)
		(fill yes)
		(layer "In2.Cu")
		(net "M_I_CPU0_SB_DQ<8>")
	)
	(gr_poly
		(pts
			(xy 391.134854 -278.744172) (xy 391.134854 -278.699722) (xy 390.934702 -278.699722) (xy 390.934702 -278.744172)
			(xy 391.034778 -278.844248)
		)
		(stroke
			(width 0)
			(type solid)
		)
		(fill yes)
		(layer "In2.Cu")
		(net "M_I_CPU0_SB_DQ<7>")
	)
	(gr_poly
		(pts
			(xy 391.134854 -277.52802) (xy 391.034778 -277.427944) (xy 390.934702 -277.52802) (xy 390.934702 -277.57247)
			(xy 391.134854 -277.57247)
		)
		(stroke
			(width 0)
			(type solid)
		)
		(fill yes)
		(layer "In2.Cu")
		(net "M_I_CPU0_SB_DQ<4>")
	)
	(gr_poly
		(pts
			(xy 391.134854 -277.124414) (xy 391.134854 -277.076662) (xy 390.934702 -277.076662) (xy 390.934702 -277.124414)
			(xy 391.034778 -277.224236)
		)
		(stroke
			(width 0)
			(type solid)
		)
		(fill yes)
		(layer "In2.Cu")
		(net "M_I_CPU0_SB_DQS_DP<5>")
	)
	(gr_poly
		(pts
			(xy 391.134854 -275.907754) (xy 391.034778 -275.807932) (xy 390.934702 -275.907754) (xy 390.934702 -275.955506)
			(xy 391.134854 -275.955506)
		)
		(stroke
			(width 0)
			(type solid)
		)
		(fill yes)
		(layer "In2.Cu")
		(net "M_I_CPU0_SB_DQS_DP<0>")
	)
	(gr_poly
		(pts
			(xy 391.134854 -275.504148) (xy 391.134854 -275.459698) (xy 390.934702 -275.459698) (xy 390.934702 -275.504148)
			(xy 391.034778 -275.604224)
		)
		(stroke
			(width 0)
			(type solid)
		)
		(fill yes)
		(layer "In2.Cu")
		(net "M_I_CPU0_SB_DQ<3>")
	)
	(gr_poly
		(pts
			(xy 391.134854 -274.287996) (xy 391.034778 -274.18792) (xy 390.934702 -274.287996) (xy 390.934702 -274.332446)
			(xy 391.134854 -274.332446)
		)
		(stroke
			(width 0)
			(type solid)
		)
		(fill yes)
		(layer "In2.Cu")
		(net "M_I_CPU0_SB_DQ<0>")
	)
	(gr_poly
		(pts
			(xy 391.134854 -273.884136) (xy 391.134854 -273.839686) (xy 390.934702 -273.839686) (xy 390.934702 -273.884136)
			(xy 391.034778 -273.984212)
		)
		(stroke
			(width 0)
			(type solid)
		)
		(fill yes)
		(layer "In2.Cu")
		(net "M_I_CPU0_SB_CB<3>")
	)
	(gr_poly
		(pts
			(xy 391.134854 -272.667984) (xy 391.034778 -272.567908) (xy 390.934702 -272.667984) (xy 390.934702 -272.712434)
			(xy 391.134854 -272.712434)
		)
		(stroke
			(width 0)
			(type solid)
		)
		(fill yes)
		(layer "In2.Cu")
		(net "M_I_CPU0_SB_CB<0>")
	)
	(gr_poly
		(pts
			(xy 391.134854 -272.264378) (xy 391.134854 -272.216626) (xy 390.934702 -272.216626) (xy 390.934702 -272.264378)
			(xy 391.034778 -272.3642)
		)
		(stroke
			(width 0)
			(type solid)
		)
		(fill yes)
		(layer "In2.Cu")
		(net "M_I_CPU0_SB_DQS_DP<4>")
	)
	(gr_poly
		(pts
			(xy 391.134854 -271.047718) (xy 391.034778 -270.947896) (xy 390.934702 -271.047718) (xy 390.934702 -271.09547)
			(xy 391.134854 -271.09547)
		)
		(stroke
			(width 0)
			(type solid)
		)
		(fill yes)
		(layer "In2.Cu")
		(net "M_I_CPU0_SB_DQS_DP<9>")
	)
	(gr_poly
		(pts
			(xy 391.134854 -270.644112) (xy 391.134854 -270.599662) (xy 390.934702 -270.599662) (xy 390.934702 -270.644112)
			(xy 391.034778 -270.744188)
		)
		(stroke
			(width 0)
			(type solid)
		)
		(fill yes)
		(layer "In2.Cu")
		(net "M_I_CPU0_SB_CB<7>")
	)
	(gr_poly
		(pts
			(xy 391.134854 -269.42796) (xy 391.034778 -269.327884) (xy 390.934702 -269.42796) (xy 390.934702 -269.47241)
			(xy 391.134854 -269.47241)
		)
		(stroke
			(width 0)
			(type solid)
		)
		(fill yes)
		(layer "In2.Cu")
		(net "M_I_CPU0_SB_CB<4>")
	)
	(gr_poly
		(pts
			(xy 391.134854 -267.404088) (xy 391.134854 -267.359638) (xy 390.934702 -267.359638) (xy 390.934702 -267.404088)
			(xy 391.034778 -267.504164)
		)
		(stroke
			(width 0)
			(type solid)
		)
		(fill yes)
		(layer "In2.Cu")
		(net "M_I_CPU0_SB_RSP<0>")
	)
	(gr_poly
		(pts
			(xy 391.134854 -265.784076) (xy 391.134854 -265.739626) (xy 390.934702 -265.739626) (xy 390.934702 -265.784076)
			(xy 391.034778 -265.884152)
		)
		(stroke
			(width 0)
			(type solid)
		)
		(fill yes)
		(layer "In2.Cu")
		(net "M_I_CPU0_SB_CS_N<0>")
	)
	(gr_poly
		(pts
			(xy 391.134854 -264.567924) (xy 391.034778 -264.467848) (xy 390.934702 -264.567924) (xy 390.934702 -264.612374)
			(xy 391.134854 -264.612374)
		)
		(stroke
			(width 0)
			(type solid)
		)
		(fill yes)
		(layer "In2.Cu")
		(net "M_I_CPU0_SB_CA<6>")
	)
	(gr_poly
		(pts
			(xy 391.134854 -264.164064) (xy 391.134854 -264.119614) (xy 390.934702 -264.119614) (xy 390.934702 -264.164064)
			(xy 391.034778 -264.26414)
		)
		(stroke
			(width 0)
			(type solid)
		)
		(fill yes)
		(layer "In2.Cu")
		(net "M_I_CPU0_SB_CA<5>")
	)
	(gr_poly
		(pts
			(xy 391.134854 -262.947912) (xy 391.034778 -262.847836) (xy 390.934702 -262.947912) (xy 390.934702 -262.992362)
			(xy 391.134854 -262.992362)
		)
		(stroke
			(width 0)
			(type solid)
		)
		(fill yes)
		(layer "In2.Cu")
		(net "M_I_CPU0_SB_CA<2>")
	)
	(gr_poly
		(pts
			(xy 391.134854 -262.544052) (xy 391.134854 -262.499602) (xy 390.934702 -262.499602) (xy 390.934702 -262.544052)
			(xy 391.034778 -262.644128)
		)
		(stroke
			(width 0)
			(type solid)
		)
		(fill yes)
		(layer "In2.Cu")
		(net "M_I_CPU0_SB_CA<1>")
	)
	(gr_poly
		(pts
			(xy 391.152888 -291.706046) (xy 391.189718 -291.569648) (xy 391.053066 -291.532818) (xy 391.011664 -291.556694)
			(xy 391.11174 -291.729922)
		)
		(stroke
			(width 0)
			(type solid)
		)
		(fill yes)
		(layer "In2.Cu")
		(net "M_I_CPU0_SB_DQS_DN<8>")
	)
	(gr_poly
		(pts
			(xy 391.153396 -294.946832) (xy 391.189972 -294.81018) (xy 391.05332 -294.773604) (xy 391.014712 -294.795702)
			(xy 391.114788 -294.96893)
		)
		(stroke
			(width 0)
			(type solid)
		)
		(fill yes)
		(layer "In2.Cu")
		(net "M_I_CPU0_SB_DQ<29>")
	)
	(gr_poly
		(pts
			(xy 391.153396 -293.32682) (xy 391.189972 -293.190168) (xy 391.05332 -293.153592) (xy 391.014712 -293.17569)
			(xy 391.114788 -293.348918)
		)
		(stroke
			(width 0)
			(type solid)
		)
		(fill yes)
		(layer "In2.Cu")
		(net "M_I_CPU0_SB_DQ<28>")
	)
	(gr_poly
		(pts
			(xy 391.224008 -229.555294) (xy 391.1854 -229.532942) (xy 391.049002 -229.569518) (xy 391.085578 -229.70617)
			(xy 391.123932 -229.728522)
		)
		(stroke
			(width 0)
			(type solid)
		)
		(fill yes)
		(layer "In2.Cu")
		(net "M_I_CPU0_SA_DQ<9>")
	)
	(gr_poly
		(pts
			(xy 391.224008 -227.935536) (xy 391.1854 -227.913184) (xy 391.049002 -227.94976) (xy 391.085578 -228.086412)
			(xy 391.123932 -228.108764)
		)
		(stroke
			(width 0)
			(type solid)
		)
		(fill yes)
		(layer "In2.Cu")
		(net "M_I_CPU0_SA_DQ<8>")
	)
	(gr_poly
		(pts
			(xy 391.224008 -226.315524) (xy 391.1854 -226.293172) (xy 391.049002 -226.329748) (xy 391.085578 -226.4664)
			(xy 391.123932 -226.488752)
		)
		(stroke
			(width 0)
			(type solid)
		)
		(fill yes)
		(layer "In2.Cu")
		(net "M_I_CPU0_SA_DQ<5>")
	)
	(gr_poly
		(pts
			(xy 391.224008 -224.695512) (xy 391.1854 -224.67316) (xy 391.049002 -224.709736) (xy 391.085578 -224.846388)
			(xy 391.123932 -224.86874)
		)
		(stroke
			(width 0)
			(type solid)
		)
		(fill yes)
		(layer "In2.Cu")
		(net "M_I_CPU0_SA_DQ<4>")
	)
	(gr_poly
		(pts
			(xy 391.226294 -231.177338) (xy 391.185146 -231.153716) (xy 391.048494 -231.190292) (xy 391.08507 -231.326944)
			(xy 391.126218 -231.350566)
		)
		(stroke
			(width 0)
			(type solid)
		)
		(fill yes)
		(layer "In2.Cu")
		(net "M_I_CPU0_SA_DQS_DP<1>")
	)
	(gr_poly
		(pts
			(xy 391.226802 -223.076262) (xy 391.185654 -223.05264) (xy 391.049002 -223.089216) (xy 391.085578 -223.225614)
			(xy 391.12698 -223.24949)
		)
		(stroke
			(width 0)
			(type solid)
		)
		(fill yes)
		(layer "In2.Cu")
		(net "M_I_CPU0_SA_DQS_DN<5>")
	)
	(gr_poly
		(pts
			(xy 391.30478 -256.025904) (xy 391.204704 -255.926082) (xy 391.104628 -256.025904) (xy 391.104628 -256.073656)
			(xy 391.30478 -256.073656)
		)
		(stroke
			(width 0)
			(type solid)
		)
		(fill yes)
		(layer "In2.Cu")
		(net "M_I_CPU0_CLK_DP<0>")
	)
	(gr_poly
		(pts
			(xy 391.30478 -255.622298) (xy 391.30478 -255.577848) (xy 391.104628 -255.577848) (xy 391.104628 -255.622298)
			(xy 391.204704 -255.722374)
		)
		(stroke
			(width 0)
			(type solid)
		)
		(fill yes)
		(layer "In2.Cu")
		(net "M_I_CPU0_SA_PAR")
	)
	(gr_poly
		(pts
			(xy 391.30478 -254.406146) (xy 391.204704 -254.30607) (xy 391.104628 -254.406146) (xy 391.104628 -254.450596)
			(xy 391.30478 -254.450596)
		)
		(stroke
			(width 0)
			(type solid)
		)
		(fill yes)
		(layer "In2.Cu")
		(net "M_I_CPU0_SA_CA<4>")
	)
	(gr_poly
		(pts
			(xy 391.30478 -254.002286) (xy 391.30478 -253.957836) (xy 391.104628 -253.957836) (xy 391.104628 -254.002286)
			(xy 391.204704 -254.102362)
		)
		(stroke
			(width 0)
			(type solid)
		)
		(fill yes)
		(layer "In2.Cu")
		(net "M_I_CPU0_SA_CA<3>")
	)
	(gr_poly
		(pts
			(xy 391.30478 -252.786134) (xy 391.204704 -252.686058) (xy 391.104628 -252.786134) (xy 391.104628 -252.830584)
			(xy 391.30478 -252.830584)
		)
		(stroke
			(width 0)
			(type solid)
		)
		(fill yes)
		(layer "In2.Cu")
		(net "M_I_CPU0_SA_CA<0>")
	)
	(gr_poly
		(pts
			(xy 391.30478 -251.166122) (xy 391.204704 -251.066046) (xy 391.104628 -251.166122) (xy 391.104628 -251.210572)
			(xy 391.30478 -251.210572)
		)
		(stroke
			(width 0)
			(type solid)
		)
		(fill yes)
		(layer "In2.Cu")
		(net "M_I_CPU0_SA_CS_N<0>")
	)
	(gr_poly
		(pts
			(xy 391.30478 -250.762262) (xy 391.30478 -250.717812) (xy 391.104628 -250.717812) (xy 391.104628 -250.762262)
			(xy 391.204704 -250.862338)
		)
		(stroke
			(width 0)
			(type solid)
		)
		(fill yes)
		(layer "In2.Cu")
		(net "M_I_CPU0_RESET_N")
	)
	(gr_poly
		(pts
			(xy 391.30478 -249.14225) (xy 391.30478 -249.0978) (xy 391.104628 -249.0978) (xy 391.104628 -249.14225)
			(xy 391.204704 -249.242326)
		)
		(stroke
			(width 0)
			(type solid)
		)
		(fill yes)
		(layer "In2.Cu")
		(net "M_I_CPU0_SA_CB<7>")
	)
	(gr_poly
		(pts
			(xy 391.30478 -247.926098) (xy 391.204704 -247.826022) (xy 391.104628 -247.926098) (xy 391.104628 -247.970548)
			(xy 391.30478 -247.970548)
		)
		(stroke
			(width 0)
			(type solid)
		)
		(fill yes)
		(layer "In2.Cu")
		(net "M_I_CPU0_SA_CB<4>")
	)
	(gr_poly
		(pts
			(xy 391.30478 -247.522492) (xy 391.30478 -247.47474) (xy 391.104628 -247.47474) (xy 391.104628 -247.522492)
			(xy 391.204704 -247.622314)
		)
		(stroke
			(width 0)
			(type solid)
		)
		(fill yes)
		(layer "In2.Cu")
		(net "M_I_CPU0_SA_DQS_DP<9>")
	)
	(gr_poly
		(pts
			(xy 391.30478 -246.305832) (xy 391.204704 -246.20601) (xy 391.104628 -246.305832) (xy 391.104628 -246.353584)
			(xy 391.30478 -246.353584)
		)
		(stroke
			(width 0)
			(type solid)
		)
		(fill yes)
		(layer "In2.Cu")
		(net "M_I_CPU0_SA_DQS_DP<4>")
	)
	(gr_poly
		(pts
			(xy 391.30478 -245.902226) (xy 391.30478 -245.857776) (xy 391.104628 -245.857776) (xy 391.104628 -245.902226)
			(xy 391.204704 -246.002302)
		)
		(stroke
			(width 0)
			(type solid)
		)
		(fill yes)
		(layer "In2.Cu")
		(net "M_I_CPU0_SA_CB<3>")
	)
	(gr_poly
		(pts
			(xy 391.30478 -244.686074) (xy 391.204704 -244.585998) (xy 391.104628 -244.686074) (xy 391.104628 -244.730524)
			(xy 391.30478 -244.730524)
		)
		(stroke
			(width 0)
			(type solid)
		)
		(fill yes)
		(layer "In2.Cu")
		(net "M_I_CPU0_SA_CB<0>")
	)
	(gr_poly
		(pts
			(xy 391.30478 -244.282214) (xy 391.30478 -244.237764) (xy 391.104628 -244.237764) (xy 391.104628 -244.282214)
			(xy 391.204704 -244.38229)
		)
		(stroke
			(width 0)
			(type solid)
		)
		(fill yes)
		(layer "In2.Cu")
		(net "M_I_CPU0_SA_DQ<31>")
	)
	(gr_poly
		(pts
			(xy 391.30478 -243.066062) (xy 391.204704 -242.965986) (xy 391.104628 -243.066062) (xy 391.104628 -243.110512)
			(xy 391.30478 -243.110512)
		)
		(stroke
			(width 0)
			(type solid)
		)
		(fill yes)
		(layer "In2.Cu")
		(net "M_I_CPU0_SA_DQ<28>")
	)
	(gr_poly
		(pts
			(xy 391.30478 -242.662456) (xy 391.30478 -242.614704) (xy 391.104628 -242.614704) (xy 391.104628 -242.662456)
			(xy 391.204704 -242.762278)
		)
		(stroke
			(width 0)
			(type solid)
		)
		(fill yes)
		(layer "In2.Cu")
		(net "M_I_CPU0_SA_DQS_DP<8>")
	)
	(gr_poly
		(pts
			(xy 391.30478 -241.445796) (xy 391.204704 -241.345974) (xy 391.104628 -241.445796) (xy 391.104628 -241.493548)
			(xy 391.30478 -241.493548)
		)
		(stroke
			(width 0)
			(type solid)
		)
		(fill yes)
		(layer "In2.Cu")
		(net "M_I_CPU0_SA_DQS_DP<3>")
	)
	(gr_poly
		(pts
			(xy 391.30478 -241.04219) (xy 391.30478 -240.99774) (xy 391.104628 -240.99774) (xy 391.104628 -241.04219)
			(xy 391.204704 -241.142266)
		)
		(stroke
			(width 0)
			(type solid)
		)
		(fill yes)
		(layer "In2.Cu")
		(net "M_I_CPU0_SA_DQ<27>")
	)
	(gr_poly
		(pts
			(xy 391.30478 -239.826038) (xy 391.204704 -239.725962) (xy 391.104628 -239.826038) (xy 391.104628 -239.870488)
			(xy 391.30478 -239.870488)
		)
		(stroke
			(width 0)
			(type solid)
		)
		(fill yes)
		(layer "In2.Cu")
		(net "M_I_CPU0_SA_DQ<24>")
	)
	(gr_poly
		(pts
			(xy 391.30478 -239.422178) (xy 391.30478 -239.377728) (xy 391.104628 -239.377728) (xy 391.104628 -239.422178)
			(xy 391.204704 -239.522254)
		)
		(stroke
			(width 0)
			(type solid)
		)
		(fill yes)
		(layer "In2.Cu")
		(net "M_I_CPU0_SA_DQ<23>")
	)
	(gr_poly
		(pts
			(xy 391.30478 -238.206026) (xy 391.204704 -238.10595) (xy 391.104628 -238.206026) (xy 391.104628 -238.250476)
			(xy 391.30478 -238.250476)
		)
		(stroke
			(width 0)
			(type solid)
		)
		(fill yes)
		(layer "In2.Cu")
		(net "M_I_CPU0_SA_DQ<20>")
	)
	(gr_poly
		(pts
			(xy 391.30478 -236.58576) (xy 391.204704 -236.485938) (xy 391.104628 -236.58576) (xy 391.104628 -236.633512)
			(xy 391.30478 -236.633512)
		)
		(stroke
			(width 0)
			(type solid)
		)
		(fill yes)
		(layer "In2.Cu")
		(net "M_I_CPU0_SA_DQS_DP<2>")
	)
	(gr_poly
		(pts
			(xy 391.30478 -236.182154) (xy 391.30478 -236.137704) (xy 391.104628 -236.137704) (xy 391.104628 -236.182154)
			(xy 391.204704 -236.28223)
		)
		(stroke
			(width 0)
			(type solid)
		)
		(fill yes)
		(layer "In2.Cu")
		(net "M_I_CPU0_SA_DQ<19>")
	)
	(gr_poly
		(pts
			(xy 391.30478 -234.966002) (xy 391.204704 -234.865926) (xy 391.104628 -234.966002) (xy 391.104628 -235.010452)
			(xy 391.30478 -235.010452)
		)
		(stroke
			(width 0)
			(type solid)
		)
		(fill yes)
		(layer "In2.Cu")
		(net "M_I_CPU0_SA_DQ<16>")
	)
	(gr_poly
		(pts
			(xy 391.30478 -234.562142) (xy 391.30478 -234.517692) (xy 391.104628 -234.517692) (xy 391.104628 -234.562142)
			(xy 391.204704 -234.662218)
		)
		(stroke
			(width 0)
			(type solid)
		)
		(fill yes)
		(layer "In2.Cu")
		(net "M_I_CPU0_SA_DQ<15>")
	)
	(gr_poly
		(pts
			(xy 391.30478 -233.34599) (xy 391.204704 -233.245914) (xy 391.104628 -233.34599) (xy 391.104628 -233.39044)
			(xy 391.30478 -233.39044)
		)
		(stroke
			(width 0)
			(type solid)
		)
		(fill yes)
		(layer "In2.Cu")
		(net "M_I_CPU0_SA_DQ<12>")
	)
	(gr_poly
		(pts
			(xy 391.30478 -232.942384) (xy 391.30478 -232.894632) (xy 391.104628 -232.894632) (xy 391.104628 -232.942384)
			(xy 391.204704 -233.042206)
		)
		(stroke
			(width 0)
			(type solid)
		)
		(fill yes)
		(layer "In2.Cu")
		(net "M_I_CPU0_SA_DQS_DP<6>")
	)
	(gr_poly
		(pts
			(xy 391.310876 -237.801912) (xy 391.310876 -237.754414) (xy 391.110978 -237.754414) (xy 391.110978 -237.801912)
			(xy 391.2108 -237.901988)
		)
		(stroke
			(width 0)
			(type solid)
		)
		(fill yes)
		(layer "In2.Cu")
		(net "M_I_CPU0_SA_DQS_DP<7>")
	)
	(gr_poly
		(pts
			(xy 391.360152 -230.239824) (xy 391.323576 -230.103172) (xy 391.284968 -230.081074) (xy 391.184892 -230.254302)
			(xy 391.2235 -230.2764)
		)
		(stroke
			(width 0)
			(type solid)
		)
		(fill yes)
		(layer "In2.Cu")
		(net "M_I_CPU0_SA_DQ<11>")
	)
	(gr_poly
		(pts
			(xy 391.360406 -222.138748) (xy 391.32383 -222.002096) (xy 391.282682 -221.978474) (xy 391.182606 -222.151702)
			(xy 391.223754 -222.175324)
		)
		(stroke
			(width 0)
			(type solid)
		)
		(fill yes)
		(layer "In2.Cu")
		(net "M_I_CPU0_SA_DQS_DN<0>")
	)
	(gr_poly
		(pts
			(xy 391.36066 -231.859074) (xy 391.324084 -231.722676) (xy 391.282682 -231.6988) (xy 391.18286 -231.872028)
			(xy 391.224008 -231.895904)
		)
		(stroke
			(width 0)
			(type solid)
		)
		(fill yes)
		(layer "In2.Cu")
		(net "M_I_CPU0_SA_DQS_DN<1>")
	)
	(gr_poly
		(pts
			(xy 391.36066 -223.759268) (xy 391.324084 -223.62287) (xy 391.282682 -223.598994) (xy 391.18286 -223.772222)
			(xy 391.224008 -223.795844)
		)
		(stroke
			(width 0)
			(type solid)
		)
		(fill yes)
		(layer "In2.Cu")
		(net "M_I_CPU0_SA_DQS_DP<5>")
	)
	(gr_poly
		(pts
			(xy 391.360914 -228.618796) (xy 391.324084 -228.482144) (xy 391.28573 -228.459792) (xy 391.185654 -228.63302)
			(xy 391.224262 -228.655372)
		)
		(stroke
			(width 0)
			(type solid)
		)
		(fill yes)
		(layer "In2.Cu")
		(net "M_I_CPU0_SA_DQ<10>")
	)
	(gr_poly
		(pts
			(xy 391.360914 -226.998784) (xy 391.324084 -226.862132) (xy 391.28573 -226.83978) (xy 391.185654 -227.013008)
			(xy 391.224262 -227.03536)
		)
		(stroke
			(width 0)
			(type solid)
		)
		(fill yes)
		(layer "In2.Cu")
		(net "M_I_CPU0_SA_DQ<7>")
	)
	(gr_poly
		(pts
			(xy 391.360914 -225.378772) (xy 391.324084 -225.24212) (xy 391.28573 -225.219768) (xy 391.185654 -225.392996)
			(xy 391.224262 -225.415348)
		)
		(stroke
			(width 0)
			(type solid)
		)
		(fill yes)
		(layer "In2.Cu")
		(net "M_I_CPU0_SA_DQ<6>")
	)
	(gr_poly
		(pts
			(xy 391.524744 -294.686228) (xy 391.424668 -294.513) (xy 391.38606 -294.535098) (xy 391.349484 -294.67175)
			(xy 391.486136 -294.708326)
		)
		(stroke
			(width 0)
			(type solid)
		)
		(fill yes)
		(layer "In2.Cu")
		(net "M_I_CPU0_SB_DQ<30>")
	)
	(gr_poly
		(pts
			(xy 391.526776 -293.06393) (xy 391.426954 -292.890702) (xy 391.385552 -292.914578) (xy 391.348976 -293.050976)
			(xy 391.485628 -293.087552)
		)
		(stroke
			(width 0)
			(type solid)
		)
		(fill yes)
		(layer "In2.Cu")
		(net "M_I_CPU0_SB_DQS_DP<8>")
	)
	(gr_poly
		(pts
			(xy 391.526776 -291.443918) (xy 391.426954 -291.27069) (xy 391.385552 -291.294566) (xy 391.348976 -291.430964)
			(xy 391.485628 -291.46754)
		)
		(stroke
			(width 0)
			(type solid)
		)
		(fill yes)
		(layer "In2.Cu")
		(net "M_I_CPU0_SB_DQS_DN<3>")
	)
	(gr_poly
		(pts
			(xy 391.604754 -289.677856) (xy 391.504678 -289.57778) (xy 391.404602 -289.677856) (xy 391.404602 -289.722306)
			(xy 391.604754 -289.722306)
		)
		(stroke
			(width 0)
			(type solid)
		)
		(fill yes)
		(layer "In2.Cu")
		(net "M_I_CPU0_SB_DQ<25>")
	)
	(gr_poly
		(pts
			(xy 391.604754 -289.273996) (xy 391.604754 -289.229546) (xy 391.404602 -289.229546) (xy 391.404602 -289.273996)
			(xy 391.504678 -289.374072)
		)
		(stroke
			(width 0)
			(type solid)
		)
		(fill yes)
		(layer "In2.Cu")
		(net "M_I_CPU0_SB_DQ<26>")
	)
	(gr_poly
		(pts
			(xy 391.604754 -288.057844) (xy 391.504678 -287.957768) (xy 391.404602 -288.057844) (xy 391.404602 -288.102294)
			(xy 391.604754 -288.102294)
		)
		(stroke
			(width 0)
			(type solid)
		)
		(fill yes)
		(layer "In2.Cu")
		(net "M_I_CPU0_SB_DQ<21>")
	)
	(gr_poly
		(pts
			(xy 391.604754 -287.654238) (xy 391.604754 -287.609788) (xy 391.404602 -287.609788) (xy 391.404602 -287.654238)
			(xy 391.504678 -287.75406)
		)
		(stroke
			(width 0)
			(type solid)
		)
		(fill yes)
		(layer "In2.Cu")
		(net "M_I_CPU0_SB_DQ<22>")
	)
	(gr_poly
		(pts
			(xy 391.604754 -286.437832) (xy 391.504678 -286.337756) (xy 391.404602 -286.437832) (xy 391.404602 -286.485584)
			(xy 391.604754 -286.485584)
		)
		(stroke
			(width 0)
			(type solid)
		)
		(fill yes)
		(layer "In2.Cu")
		(net "M_I_CPU0_SB_DQS_DN<7>")
	)
	(gr_poly
		(pts
			(xy 391.604754 -286.03448) (xy 391.604754 -285.986728) (xy 391.404602 -285.986728) (xy 391.404602 -286.03448)
			(xy 391.504678 -286.134302)
		)
		(stroke
			(width 0)
			(type solid)
		)
		(fill yes)
		(layer "In2.Cu")
		(net "M_I_CPU0_SB_DQS_DN<2>")
	)
	(gr_poly
		(pts
			(xy 391.604754 -284.818074) (xy 391.504678 -284.717998) (xy 391.404602 -284.818074) (xy 391.404602 -284.862524)
			(xy 391.604754 -284.862524)
		)
		(stroke
			(width 0)
			(type solid)
		)
		(fill yes)
		(layer "In2.Cu")
		(net "M_I_CPU0_SB_DQ<17>")
	)
	(gr_poly
		(pts
			(xy 391.604754 -284.414214) (xy 391.604754 -284.369764) (xy 391.404602 -284.369764) (xy 391.404602 -284.414214)
			(xy 391.504678 -284.51429)
		)
		(stroke
			(width 0)
			(type solid)
		)
		(fill yes)
		(layer "In2.Cu")
		(net "M_I_CPU0_SB_DQ<18>")
	)
	(gr_poly
		(pts
			(xy 391.604754 -283.198062) (xy 391.504678 -283.097986) (xy 391.404602 -283.198062) (xy 391.404602 -283.242512)
			(xy 391.604754 -283.242512)
		)
		(stroke
			(width 0)
			(type solid)
		)
		(fill yes)
		(layer "In2.Cu")
		(net "M_I_CPU0_SB_DQ<13>")
	)
	(gr_poly
		(pts
			(xy 391.604754 -282.794202) (xy 391.604754 -282.749752) (xy 391.404602 -282.749752) (xy 391.404602 -282.794202)
			(xy 391.504678 -282.894278)
		)
		(stroke
			(width 0)
			(type solid)
		)
		(fill yes)
		(layer "In2.Cu")
		(net "M_I_CPU0_SB_DQ<14>")
	)
	(gr_poly
		(pts
			(xy 391.604754 -281.577796) (xy 391.504678 -281.477974) (xy 391.404602 -281.577796) (xy 391.404602 -281.625548)
			(xy 391.604754 -281.625548)
		)
		(stroke
			(width 0)
			(type solid)
		)
		(fill yes)
		(layer "In2.Cu")
		(net "M_I_CPU0_SB_DQS_DN<6>")
	)
	(gr_poly
		(pts
			(xy 391.604754 -281.174444) (xy 391.604754 -281.126692) (xy 391.404602 -281.126692) (xy 391.404602 -281.174444)
			(xy 391.504678 -281.274266)
		)
		(stroke
			(width 0)
			(type solid)
		)
		(fill yes)
		(layer "In2.Cu")
		(net "M_I_CPU0_SB_DQS_DN<1>")
	)
	(gr_poly
		(pts
			(xy 391.604754 -279.958038) (xy 391.504678 -279.857962) (xy 391.404602 -279.958038) (xy 391.404602 -280.002488)
			(xy 391.604754 -280.002488)
		)
		(stroke
			(width 0)
			(type solid)
		)
		(fill yes)
		(layer "In2.Cu")
		(net "M_I_CPU0_SB_DQ<9>")
	)
	(gr_poly
		(pts
			(xy 391.604754 -279.554178) (xy 391.604754 -279.509728) (xy 391.404602 -279.509728) (xy 391.404602 -279.554178)
			(xy 391.504678 -279.654254)
		)
		(stroke
			(width 0)
			(type solid)
		)
		(fill yes)
		(layer "In2.Cu")
		(net "M_I_CPU0_SB_DQ<10>")
	)
	(gr_poly
		(pts
			(xy 391.604754 -278.338026) (xy 391.504678 -278.23795) (xy 391.404602 -278.338026) (xy 391.404602 -278.382476)
			(xy 391.604754 -278.382476)
		)
		(stroke
			(width 0)
			(type solid)
		)
		(fill yes)
		(layer "In2.Cu")
		(net "M_I_CPU0_SB_DQ<5>")
	)
	(gr_poly
		(pts
			(xy 391.604754 -277.934166) (xy 391.604754 -277.889716) (xy 391.404602 -277.889716) (xy 391.404602 -277.934166)
			(xy 391.504678 -278.034242)
		)
		(stroke
			(width 0)
			(type solid)
		)
		(fill yes)
		(layer "In2.Cu")
		(net "M_I_CPU0_SB_DQ<6>")
	)
	(gr_poly
		(pts
			(xy 391.604754 -276.71776) (xy 391.504678 -276.617938) (xy 391.404602 -276.71776) (xy 391.404602 -276.765512)
			(xy 391.604754 -276.765512)
		)
		(stroke
			(width 0)
			(type solid)
		)
		(fill yes)
		(layer "In2.Cu")
		(net "M_I_CPU0_SB_DQS_DN<5>")
	)
	(gr_poly
		(pts
			(xy 391.604754 -276.314408) (xy 391.604754 -276.266656) (xy 391.404602 -276.266656) (xy 391.404602 -276.314408)
			(xy 391.504678 -276.41423)
		)
		(stroke
			(width 0)
			(type solid)
		)
		(fill yes)
		(layer "In2.Cu")
		(net "M_I_CPU0_SB_DQS_DN<0>")
	)
	(gr_poly
		(pts
			(xy 391.604754 -275.098002) (xy 391.504678 -274.997926) (xy 391.404602 -275.098002) (xy 391.404602 -275.142452)
			(xy 391.604754 -275.142452)
		)
		(stroke
			(width 0)
			(type solid)
		)
		(fill yes)
		(layer "In2.Cu")
		(net "M_I_CPU0_SB_DQ<1>")
	)
	(gr_poly
		(pts
			(xy 391.604754 -274.694142) (xy 391.604754 -274.649692) (xy 391.404602 -274.649692) (xy 391.404602 -274.694142)
			(xy 391.504678 -274.794218)
		)
		(stroke
			(width 0)
			(type solid)
		)
		(fill yes)
		(layer "In2.Cu")
		(net "M_I_CPU0_SB_DQ<2>")
	)
	(gr_poly
		(pts
			(xy 391.604754 -273.47799) (xy 391.504678 -273.377914) (xy 391.404602 -273.47799) (xy 391.404602 -273.52244)
			(xy 391.604754 -273.52244)
		)
		(stroke
			(width 0)
			(type solid)
		)
		(fill yes)
		(layer "In2.Cu")
		(net "M_I_CPU0_SB_CB<1>")
	)
	(gr_poly
		(pts
			(xy 391.604754 -273.07413) (xy 391.604754 -273.02968) (xy 391.404602 -273.02968) (xy 391.404602 -273.07413)
			(xy 391.504678 -273.174206)
		)
		(stroke
			(width 0)
			(type solid)
		)
		(fill yes)
		(layer "In2.Cu")
		(net "M_I_CPU0_SB_CB<2>")
	)
	(gr_poly
		(pts
			(xy 391.604754 -271.857724) (xy 391.504678 -271.757902) (xy 391.404602 -271.857724) (xy 391.404602 -271.905476)
			(xy 391.604754 -271.905476)
		)
		(stroke
			(width 0)
			(type solid)
		)
		(fill yes)
		(layer "In2.Cu")
		(net "M_I_CPU0_SB_DQS_DN<4>")
	)
	(gr_poly
		(pts
			(xy 391.604754 -271.454372) (xy 391.604754 -271.40662) (xy 391.404602 -271.40662) (xy 391.404602 -271.454372)
			(xy 391.504678 -271.554194)
		)
		(stroke
			(width 0)
			(type solid)
		)
		(fill yes)
		(layer "In2.Cu")
		(net "M_I_CPU0_SB_DQS_DN<9>")
	)
	(gr_poly
		(pts
			(xy 391.604754 -270.237966) (xy 391.504678 -270.13789) (xy 391.404602 -270.237966) (xy 391.404602 -270.282416)
			(xy 391.604754 -270.282416)
		)
		(stroke
			(width 0)
			(type solid)
		)
		(fill yes)
		(layer "In2.Cu")
		(net "M_I_CPU0_SB_CB<5>")
	)
	(gr_poly
		(pts
			(xy 391.604754 -269.834106) (xy 391.604754 -269.789656) (xy 391.404602 -269.789656) (xy 391.404602 -269.834106)
			(xy 391.504678 -269.934182)
		)
		(stroke
			(width 0)
			(type solid)
		)
		(fill yes)
		(layer "In2.Cu")
		(net "M_I_CPU0_SB_CB<6>")
	)
	(gr_poly
		(pts
			(xy 391.604754 -266.997942) (xy 391.504678 -266.897866) (xy 391.404602 -266.997942) (xy 391.404602 -267.042392)
			(xy 391.604754 -267.042392)
		)
		(stroke
			(width 0)
			(type solid)
		)
		(fill yes)
		(layer "In2.Cu")
		(net "M_I_CPU0_SA_RSP<0>")
	)
	(gr_poly
		(pts
			(xy 391.604754 -266.594082) (xy 391.604754 -266.549632) (xy 391.404602 -266.549632) (xy 391.404602 -266.594082)
			(xy 391.504678 -266.694158)
		)
		(stroke
			(width 0)
			(type solid)
		)
		(fill yes)
		(layer "In2.Cu")
		(net "M_I_CPU0_SB_CS_N<1>")
	)
	(gr_poly
		(pts
			(xy 391.604754 -265.37793) (xy 391.504678 -265.277854) (xy 391.404602 -265.37793) (xy 391.404602 -265.42238)
			(xy 391.604754 -265.42238)
		)
		(stroke
			(width 0)
			(type solid)
		)
		(fill yes)
		(layer "In2.Cu")
		(net "M_I_CPU0_SB_PAR")
	)
	(gr_poly
		(pts
			(xy 391.604754 -263.757918) (xy 391.504678 -263.657842) (xy 391.404602 -263.757918) (xy 391.404602 -263.802368)
			(xy 391.604754 -263.802368)
		)
		(stroke
			(width 0)
			(type solid)
		)
		(fill yes)
		(layer "In2.Cu")
		(net "M_I_CPU0_SB_CA<4>")
	)
	(gr_poly
		(pts
			(xy 391.604754 -263.354058) (xy 391.604754 -263.309608) (xy 391.404602 -263.309608) (xy 391.404602 -263.354058)
			(xy 391.504678 -263.454134)
		)
		(stroke
			(width 0)
			(type solid)
		)
		(fill yes)
		(layer "In2.Cu")
		(net "M_I_CPU0_SB_CA<3>")
	)
	(gr_poly
		(pts
			(xy 391.604754 -262.137906) (xy 391.504678 -262.03783) (xy 391.404602 -262.137906) (xy 391.404602 -262.182356)
			(xy 391.604754 -262.182356)
		)
		(stroke
			(width 0)
			(type solid)
		)
		(fill yes)
		(layer "In2.Cu")
		(net "M_I_CPU0_SB_CA<0>")
	)
	(gr_poly
		(pts
			(xy 391.623296 -295.756838) (xy 391.659872 -295.620186) (xy 391.52322 -295.58361) (xy 391.484612 -295.605708)
			(xy 391.584688 -295.778936)
		)
		(stroke
			(width 0)
			(type solid)
		)
		(fill yes)
		(layer "In2.Cu")
		(net "M_I_CPU0_SB_DQ<29>")
	)
	(gr_poly
		(pts
			(xy 391.623296 -294.136826) (xy 391.659872 -294.000174) (xy 391.52322 -293.963598) (xy 391.484612 -293.985696)
			(xy 391.584688 -294.158924)
		)
		(stroke
			(width 0)
			(type solid)
		)
		(fill yes)
		(layer "In2.Cu")
		(net "M_I_CPU0_SB_DQ<28>")
	)
	(gr_poly
		(pts
			(xy 391.624058 -292.517322) (xy 391.660634 -292.380924) (xy 391.523982 -292.344348) (xy 391.482834 -292.36797)
			(xy 391.582656 -292.541198)
		)
		(stroke
			(width 0)
			(type solid)
		)
		(fill yes)
		(layer "In2.Cu")
		(net "M_I_CPU0_SB_DQS_DN<8>")
	)
	(gr_poly
		(pts
			(xy 391.624058 -290.89731) (xy 391.660634 -290.760912) (xy 391.523982 -290.724336) (xy 391.482834 -290.747958)
			(xy 391.582656 -290.921186)
		)
		(stroke
			(width 0)
			(type solid)
		)
		(fill yes)
		(layer "In2.Cu")
		(net "M_I_CPU0_SB_DQS_DP<3>")
	)
	(gr_poly
		(pts
			(xy 391.693908 -228.745542) (xy 391.6553 -228.72319) (xy 391.518902 -228.759766) (xy 391.555478 -228.896418)
			(xy 391.593832 -228.91877)
		)
		(stroke
			(width 0)
			(type solid)
		)
		(fill yes)
		(layer "In2.Cu")
		(net "M_I_CPU0_SA_DQ<9>")
	)
	(gr_poly
		(pts
			(xy 391.693908 -227.12553) (xy 391.6553 -227.103178) (xy 391.518902 -227.139754) (xy 391.555478 -227.276406)
			(xy 391.593832 -227.298758)
		)
		(stroke
			(width 0)
			(type solid)
		)
		(fill yes)
		(layer "In2.Cu")
		(net "M_I_CPU0_SA_DQ<8>")
	)
	(gr_poly
		(pts
			(xy 391.693908 -225.505518) (xy 391.6553 -225.483166) (xy 391.518902 -225.519742) (xy 391.555478 -225.656394)
			(xy 391.593832 -225.678746)
		)
		(stroke
			(width 0)
			(type solid)
		)
		(fill yes)
		(layer "In2.Cu")
		(net "M_I_CPU0_SA_DQ<5>")
	)
	(gr_poly
		(pts
			(xy 391.693908 -223.885506) (xy 391.6553 -223.863154) (xy 391.518902 -223.89973) (xy 391.555478 -224.036382)
			(xy 391.593832 -224.058734)
		)
		(stroke
			(width 0)
			(type solid)
		)
		(fill yes)
		(layer "In2.Cu")
		(net "M_I_CPU0_SA_DQ<4>")
	)
	(gr_poly
		(pts
			(xy 391.696702 -231.986074) (xy 391.655554 -231.962452) (xy 391.518902 -231.999028) (xy 391.555478 -232.135426)
			(xy 391.59688 -232.159302)
		)
		(stroke
			(width 0)
			(type solid)
		)
		(fill yes)
		(layer "In2.Cu")
		(net "M_I_CPU0_SA_DQS_DN<6>")
	)
	(gr_poly
		(pts
			(xy 391.696702 -222.266256) (xy 391.655554 -222.242634) (xy 391.518902 -222.27921) (xy 391.555478 -222.415608)
			(xy 391.59688 -222.439484)
		)
		(stroke
			(width 0)
			(type solid)
		)
		(fill yes)
		(layer "In2.Cu")
		(net "M_I_CPU0_SA_DQS_DN<5>")
	)
	(gr_poly
		(pts
			(xy 391.697464 -230.365046) (xy 391.656316 -230.34117) (xy 391.519664 -230.377746) (xy 391.55624 -230.514398)
			(xy 391.597388 -230.538274)
		)
		(stroke
			(width 0)
			(type solid)
		)
		(fill yes)
		(layer "In2.Cu")
		(net "M_I_CPU0_SA_DQS_DP<1>")
	)
	(gr_poly
		(pts
			(xy 391.760202 -254.812038) (xy 391.760202 -254.767588) (xy 391.560304 -254.767588) (xy 391.560304 -254.812038)
			(xy 391.660126 -254.912114)
		)
		(stroke
			(width 0)
			(type solid)
		)
		(fill yes)
		(layer "In2.Cu")
		(net "M_I_CPU0_SA_CA<5>")
	)
	(gr_poly
		(pts
			(xy 391.760202 -253.19228) (xy 391.760202 -253.147576) (xy 391.560304 -253.147576) (xy 391.560304 -253.19228)
			(xy 391.660126 -253.292102)
		)
		(stroke
			(width 0)
			(type solid)
		)
		(fill yes)
		(layer "In2.Cu")
		(net "M_I_CPU0_SA_CA<1>")
	)
	(gr_poly
		(pts
			(xy 391.760202 -248.332244) (xy 391.760202 -248.28754) (xy 391.560304 -248.28754) (xy 391.560304 -248.332244)
			(xy 391.660126 -248.432066)
		)
		(stroke
			(width 0)
			(type solid)
		)
		(fill yes)
		(layer "In2.Cu")
		(net "M_I_CPU0_SA_CB<6>")
	)
	(gr_poly
		(pts
			(xy 391.760202 -245.09222) (xy 391.760202 -245.04777) (xy 391.560304 -245.04777) (xy 391.560304 -245.09222)
			(xy 391.660126 -245.192042)
		)
		(stroke
			(width 0)
			(type solid)
		)
		(fill yes)
		(layer "In2.Cu")
		(net "M_I_CPU0_SA_CB<2>")
	)
	(gr_poly
		(pts
			(xy 391.768838 -243.472208) (xy 391.768838 -243.427758) (xy 391.568686 -243.427758) (xy 391.568686 -243.472208)
			(xy 391.668762 -243.572284)
		)
		(stroke
			(width 0)
			(type solid)
		)
		(fill yes)
		(layer "In2.Cu")
		(net "M_I_CPU0_SA_DQ<30>")
	)
	(gr_poly
		(pts
			(xy 391.768838 -241.85245) (xy 391.768838 -241.804698) (xy 391.568686 -241.804698) (xy 391.568686 -241.85245)
			(xy 391.668762 -241.952272)
		)
		(stroke
			(width 0)
			(type solid)
		)
		(fill yes)
		(layer "In2.Cu")
		(net "M_I_CPU0_SA_DQS_DN<3>")
	)
	(gr_poly
		(pts
			(xy 391.768838 -240.636044) (xy 391.668762 -240.535968) (xy 391.568686 -240.636044) (xy 391.568686 -240.680494)
			(xy 391.768838 -240.680494)
		)
		(stroke
			(width 0)
			(type solid)
		)
		(fill yes)
		(layer "In2.Cu")
		(net "M_I_CPU0_SA_DQ<25>")
	)
	(gr_poly
		(pts
			(xy 391.768838 -240.232184) (xy 391.768838 -240.187734) (xy 391.568686 -240.187734) (xy 391.568686 -240.232184)
			(xy 391.668762 -240.33226)
		)
		(stroke
			(width 0)
			(type solid)
		)
		(fill yes)
		(layer "In2.Cu")
		(net "M_I_CPU0_SA_DQ<26>")
	)
	(gr_poly
		(pts
			(xy 391.768838 -236.992414) (xy 391.768838 -236.944662) (xy 391.568686 -236.944662) (xy 391.568686 -236.992414)
			(xy 391.668762 -237.092236)
		)
		(stroke
			(width 0)
			(type solid)
		)
		(fill yes)
		(layer "In2.Cu")
		(net "M_I_CPU0_SA_DQS_DN<2>")
	)
	(gr_poly
		(pts
			(xy 391.768838 -235.372148) (xy 391.768838 -235.327698) (xy 391.568686 -235.327698) (xy 391.568686 -235.372148)
			(xy 391.668762 -235.472224)
		)
		(stroke
			(width 0)
			(type solid)
		)
		(fill yes)
		(layer "In2.Cu")
		(net "M_I_CPU0_SA_DQ<18>")
	)
	(gr_poly
		(pts
			(xy 391.768838 -233.752136) (xy 391.768838 -233.707686) (xy 391.568686 -233.707686) (xy 391.568686 -233.752136)
			(xy 391.668762 -233.852212)
		)
		(stroke
			(width 0)
			(type solid)
		)
		(fill yes)
		(layer "In2.Cu")
		(net "M_I_CPU0_SA_DQ<14>")
	)
	(gr_poly
		(pts
			(xy 391.774934 -256.432558) (xy 391.774934 -256.384806) (xy 391.574782 -256.384806) (xy 391.574782 -256.432558)
			(xy 391.674858 -256.53238)
		)
		(stroke
			(width 0)
			(type solid)
		)
		(fill yes)
		(layer "In2.Cu")
		(net "M_I_CPU0_CLK_DN<0>")
	)
	(gr_poly
		(pts
			(xy 391.774934 -253.59614) (xy 391.674858 -253.496064) (xy 391.574782 -253.59614) (xy 391.574782 -253.64059)
			(xy 391.774934 -253.64059)
		)
		(stroke
			(width 0)
			(type solid)
		)
		(fill yes)
		(layer "In2.Cu")
		(net "M_I_CPU0_SA_CA<2>")
	)
	(gr_poly
		(pts
			(xy 391.774934 -250.356116) (xy 391.674858 -250.25604) (xy 391.574782 -250.356116) (xy 391.574782 -250.400566)
			(xy 391.774934 -250.400566)
		)
		(stroke
			(width 0)
			(type solid)
		)
		(fill yes)
		(layer "In2.Cu")
		(net "M_I_CPU0_ALERT_R_N")
	)
	(gr_poly
		(pts
			(xy 391.774934 -245.49608) (xy 391.674858 -245.396004) (xy 391.574782 -245.49608) (xy 391.574782 -245.54053)
			(xy 391.774934 -245.54053)
		)
		(stroke
			(width 0)
			(type solid)
		)
		(fill yes)
		(layer "In2.Cu")
		(net "M_I_CPU0_SA_CB<1>")
	)
	(gr_poly
		(pts
			(xy 391.774934 -243.876068) (xy 391.674858 -243.775992) (xy 391.574782 -243.876068) (xy 391.574782 -243.920518)
			(xy 391.774934 -243.920518)
		)
		(stroke
			(width 0)
			(type solid)
		)
		(fill yes)
		(layer "In2.Cu")
		(net "M_I_CPU0_SA_DQ<29>")
	)
	(gr_poly
		(pts
			(xy 391.78103 -242.255802) (xy 391.680954 -242.155726) (xy 391.580878 -242.255802) (xy 391.580878 -242.3033)
			(xy 391.78103 -242.3033)
		)
		(stroke
			(width 0)
			(type solid)
		)
		(fill yes)
		(layer "In2.Cu")
		(net "M_I_CPU0_SA_DQS_DN<8>")
	)
	(gr_poly
		(pts
			(xy 391.78357 -255.215898) (xy 391.683494 -255.116076) (xy 391.583672 -255.215898) (xy 391.583672 -255.260348)
			(xy 391.78357 -255.260348)
		)
		(stroke
			(width 0)
			(type solid)
		)
		(fill yes)
		(layer "In2.Cu")
		(net "M_I_CPU0_SA_CA<6>")
	)
	(gr_poly
		(pts
			(xy 391.78357 -251.975874) (xy 391.683494 -251.876052) (xy 391.583672 -251.975874) (xy 391.583672 -252.020324)
			(xy 391.78357 -252.020324)
		)
		(stroke
			(width 0)
			(type solid)
		)
		(fill yes)
		(layer "In2.Cu")
		(net "M_I_CPU0_SA_CS_N<1>")
	)
	(gr_poly
		(pts
			(xy 391.78357 -248.73585) (xy 391.683494 -248.636028) (xy 391.583672 -248.73585) (xy 391.583672 -248.7803)
			(xy 391.78357 -248.7803)
		)
		(stroke
			(width 0)
			(type solid)
		)
		(fill yes)
		(layer "In2.Cu")
		(net "M_I_CPU0_SA_CB<5>")
	)
	(gr_poly
		(pts
			(xy 391.78357 -247.115584) (xy 391.683494 -247.015762) (xy 391.583672 -247.115584) (xy 391.583672 -247.163336)
			(xy 391.78357 -247.163336)
		)
		(stroke
			(width 0)
			(type solid)
		)
		(fill yes)
		(layer "In2.Cu")
		(net "M_I_CPU0_SA_DQS_DN<9>")
	)
	(gr_poly
		(pts
			(xy 391.83056 -232.66908) (xy 391.793984 -232.532682) (xy 391.752582 -232.508806) (xy 391.65276 -232.682034)
			(xy 391.693908 -232.705656)
		)
		(stroke
			(width 0)
			(type solid)
		)
		(fill yes)
		(layer "In2.Cu")
		(net "M_I_CPU0_SA_DQS_DP<6>")
	)
	(gr_poly
		(pts
			(xy 391.83056 -222.949262) (xy 391.793984 -222.812864) (xy 391.752582 -222.788988) (xy 391.65276 -222.962216)
			(xy 391.693908 -222.985838)
		)
		(stroke
			(width 0)
			(type solid)
		)
		(fill yes)
		(layer "In2.Cu")
		(net "M_I_CPU0_SA_DQS_DP<5>")
	)
	(gr_poly
		(pts
			(xy 391.830814 -229.428802) (xy 391.793984 -229.29215) (xy 391.75563 -229.269798) (xy 391.655554 -229.443026)
			(xy 391.694162 -229.465378)
		)
		(stroke
			(width 0)
			(type solid)
		)
		(fill yes)
		(layer "In2.Cu")
		(net "M_I_CPU0_SA_DQ<11>")
	)
	(gr_poly
		(pts
			(xy 391.830814 -227.80879) (xy 391.793984 -227.672138) (xy 391.75563 -227.649786) (xy 391.655554 -227.823014)
			(xy 391.694162 -227.845366)
		)
		(stroke
			(width 0)
			(type solid)
		)
		(fill yes)
		(layer "In2.Cu")
		(net "M_I_CPU0_SA_DQ<10>")
	)
	(gr_poly
		(pts
			(xy 391.830814 -226.188778) (xy 391.793984 -226.052126) (xy 391.75563 -226.029774) (xy 391.655554 -226.203002)
			(xy 391.694162 -226.225354)
		)
		(stroke
			(width 0)
			(type solid)
		)
		(fill yes)
		(layer "In2.Cu")
		(net "M_I_CPU0_SA_DQ<7>")
	)
	(gr_poly
		(pts
			(xy 391.830814 -224.568766) (xy 391.793984 -224.432114) (xy 391.75563 -224.409762) (xy 391.655554 -224.58299)
			(xy 391.694162 -224.605342)
		)
		(stroke
			(width 0)
			(type solid)
		)
		(fill yes)
		(layer "In2.Cu")
		(net "M_I_CPU0_SA_DQ<6>")
	)
	(gr_poly
		(pts
			(xy 391.831068 -231.048052) (xy 391.794492 -230.9114) (xy 391.753344 -230.887778) (xy 391.653268 -231.061006)
			(xy 391.69467 -231.084628)
		)
		(stroke
			(width 0)
			(type solid)
		)
		(fill yes)
		(layer "In2.Cu")
		(net "M_I_CPU0_SA_DQS_DN<1>")
	)
	(gr_poly
		(pts
			(xy 391.993882 -290.634674) (xy 391.893806 -290.461446) (xy 391.855452 -290.483798) (xy 391.818622 -290.62045)
			(xy 391.955274 -290.657026)
		)
		(stroke
			(width 0)
			(type solid)
		)
		(fill yes)
		(layer "In2.Cu")
		(net "M_I_CPU0_SB_DQ<27>")
	)
	(gr_poly
		(pts
			(xy 391.994644 -295.496234) (xy 391.894568 -295.323006) (xy 391.85596 -295.345104) (xy 391.819384 -295.481756)
			(xy 391.956036 -295.518332)
		)
		(stroke
			(width 0)
			(type solid)
		)
		(fill yes)
		(layer "In2.Cu")
		(net "M_I_CPU0_SB_DQ<30>")
	)
	(gr_poly
		(pts
			(xy 391.996676 -293.873936) (xy 391.896854 -293.700708) (xy 391.855452 -293.724584) (xy 391.818876 -293.860982)
			(xy 391.955528 -293.897812)
		)
		(stroke
			(width 0)
			(type solid)
		)
		(fill yes)
		(layer "In2.Cu")
		(net "M_I_CPU0_SB_DQS_DP<8>")
	)
	(gr_poly
		(pts
			(xy 391.99693 -292.253924) (xy 391.897108 -292.080696) (xy 391.855706 -292.104572) (xy 391.81913 -292.24097)
			(xy 391.955782 -292.2778)
		)
		(stroke
			(width 0)
			(type solid)
		)
		(fill yes)
		(layer "In2.Cu")
		(net "M_I_CPU0_SB_DQS_DN<3>")
	)
	(gr_poly
		(pts
			(xy 392.058906 -286.843978) (xy 392.058906 -286.79648) (xy 391.859008 -286.79648) (xy 391.859008 -286.843978)
			(xy 391.95883 -286.944054)
		)
		(stroke
			(width 0)
			(type solid)
		)
		(fill yes)
		(layer "In2.Cu")
		(net "M_I_CPU0_SB_DQS_DP<7>")
	)
	(gr_poly
		(pts
			(xy 392.058906 -285.223966) (xy 392.058906 -285.179516) (xy 391.858754 -285.179516) (xy 391.858754 -285.223966)
			(xy 391.95883 -285.324042)
		)
		(stroke
			(width 0)
			(type solid)
		)
		(fill yes)
		(layer "In2.Cu")
		(net "M_I_CPU0_SB_DQ<19>")
	)
	(gr_poly
		(pts
			(xy 392.058906 -283.603954) (xy 392.058906 -283.559504) (xy 391.858754 -283.559504) (xy 391.858754 -283.603954)
			(xy 391.95883 -283.70403)
		)
		(stroke
			(width 0)
			(type solid)
		)
		(fill yes)
		(layer "In2.Cu")
		(net "M_I_CPU0_SB_DQ<15>")
	)
	(gr_poly
		(pts
			(xy 392.058906 -281.984196) (xy 392.058906 -281.936444) (xy 391.859008 -281.936444) (xy 391.859008 -281.984196)
			(xy 391.95883 -282.084272)
		)
		(stroke
			(width 0)
			(type solid)
		)
		(fill yes)
		(layer "In2.Cu")
		(net "M_I_CPU0_SB_DQS_DP<6>")
	)
	(gr_poly
		(pts
			(xy 392.058906 -280.36393) (xy 392.058906 -280.31948) (xy 391.858754 -280.31948) (xy 391.858754 -280.36393)
			(xy 391.95883 -280.464006)
		)
		(stroke
			(width 0)
			(type solid)
		)
		(fill yes)
		(layer "In2.Cu")
		(net "M_I_CPU0_SB_DQ<11>")
	)
	(gr_poly
		(pts
			(xy 392.058906 -278.743918) (xy 392.058906 -278.699468) (xy 391.858754 -278.699468) (xy 391.858754 -278.743918)
			(xy 391.95883 -278.843994)
		)
		(stroke
			(width 0)
			(type solid)
		)
		(fill yes)
		(layer "In2.Cu")
		(net "M_I_CPU0_SB_DQ<7>")
	)
	(gr_poly
		(pts
			(xy 392.058906 -277.12416) (xy 392.058906 -277.076408) (xy 391.859008 -277.076408) (xy 391.859008 -277.12416)
			(xy 391.95883 -277.224236)
		)
		(stroke
			(width 0)
			(type solid)
		)
		(fill yes)
		(layer "In2.Cu")
		(net "M_I_CPU0_SB_DQS_DP<5>")
	)
	(gr_poly
		(pts
			(xy 392.058906 -275.503894) (xy 392.058906 -275.459444) (xy 391.858754 -275.459444) (xy 391.858754 -275.503894)
			(xy 391.95883 -275.60397)
		)
		(stroke
			(width 0)
			(type solid)
		)
		(fill yes)
		(layer "In2.Cu")
		(net "M_I_CPU0_SB_DQ<3>")
	)
	(gr_poly
		(pts
			(xy 392.058906 -273.883882) (xy 392.058906 -273.839432) (xy 391.858754 -273.839432) (xy 391.858754 -273.883882)
			(xy 391.95883 -273.983958)
		)
		(stroke
			(width 0)
			(type solid)
		)
		(fill yes)
		(layer "In2.Cu")
		(net "M_I_CPU0_SB_CB<3>")
	)
	(gr_poly
		(pts
			(xy 392.058906 -272.264124) (xy 392.058906 -272.216372) (xy 391.859008 -272.216372) (xy 391.859008 -272.264124)
			(xy 391.95883 -272.3642)
		)
		(stroke
			(width 0)
			(type solid)
		)
		(fill yes)
		(layer "In2.Cu")
		(net "M_I_CPU0_SB_DQS_DP<4>")
	)
	(gr_poly
		(pts
			(xy 392.058906 -267.403834) (xy 392.058906 -267.359384) (xy 391.858754 -267.359384) (xy 391.858754 -267.403834)
			(xy 391.95883 -267.50391)
		)
		(stroke
			(width 0)
			(type solid)
		)
		(fill yes)
		(layer "In2.Cu")
		(net "M_I_CPU0_SB_RSP<0>")
	)
	(gr_poly
		(pts
			(xy 392.058906 -265.783822) (xy 392.058906 -265.739372) (xy 391.858754 -265.739372) (xy 391.858754 -265.783822)
			(xy 391.95883 -265.883898)
		)
		(stroke
			(width 0)
			(type solid)
		)
		(fill yes)
		(layer "In2.Cu")
		(net "M_I_CPU0_SB_CS_N<0>")
	)
	(gr_poly
		(pts
			(xy 392.058906 -264.16381) (xy 392.058906 -264.11936) (xy 391.858754 -264.11936) (xy 391.858754 -264.16381)
			(xy 391.95883 -264.263886)
		)
		(stroke
			(width 0)
			(type solid)
		)
		(fill yes)
		(layer "In2.Cu")
		(net "M_I_CPU0_SB_CA<5>")
	)
	(gr_poly
		(pts
			(xy 392.058906 -262.543798) (xy 392.058906 -262.499348) (xy 391.858754 -262.499348) (xy 391.858754 -262.543798)
			(xy 391.95883 -262.643874)
		)
		(stroke
			(width 0)
			(type solid)
		)
		(fill yes)
		(layer "In2.Cu")
		(net "M_I_CPU0_SB_CA<1>")
	)
	(gr_poly
		(pts
			(xy 392.068558 -270.644112) (xy 392.068558 -270.599662) (xy 391.86866 -270.599662) (xy 391.86866 -270.644112)
			(xy 391.968736 -270.744188)
		)
		(stroke
			(width 0)
			(type solid)
		)
		(fill yes)
		(layer "In2.Cu")
		(net "M_I_CPU0_SB_CB<7>")
	)
	(gr_poly
		(pts
			(xy 392.074908 -285.627826) (xy 391.974832 -285.528004) (xy 391.874756 -285.627826) (xy 391.874756 -285.675578)
			(xy 392.074908 -285.675578)
		)
		(stroke
			(width 0)
			(type solid)
		)
		(fill yes)
		(layer "In2.Cu")
		(net "M_I_CPU0_SB_DQS_DP<2>")
	)
	(gr_poly
		(pts
			(xy 392.074908 -284.008068) (xy 391.974832 -283.907992) (xy 391.874756 -284.008068) (xy 391.874756 -284.052518)
			(xy 392.074908 -284.052518)
		)
		(stroke
			(width 0)
			(type solid)
		)
		(fill yes)
		(layer "In2.Cu")
		(net "M_I_CPU0_SB_DQ<16>")
	)
	(gr_poly
		(pts
			(xy 392.074908 -282.388056) (xy 391.974832 -282.28798) (xy 391.874756 -282.388056) (xy 391.874756 -282.432506)
			(xy 392.074908 -282.432506)
		)
		(stroke
			(width 0)
			(type solid)
		)
		(fill yes)
		(layer "In2.Cu")
		(net "M_I_CPU0_SB_DQ<12>")
	)
	(gr_poly
		(pts
			(xy 392.074908 -279.148032) (xy 391.974832 -279.047956) (xy 391.874756 -279.148032) (xy 391.874756 -279.192482)
			(xy 392.074908 -279.192482)
		)
		(stroke
			(width 0)
			(type solid)
		)
		(fill yes)
		(layer "In2.Cu")
		(net "M_I_CPU0_SB_DQ<8>")
	)
	(gr_poly
		(pts
			(xy 392.074908 -277.52802) (xy 391.974832 -277.427944) (xy 391.874756 -277.52802) (xy 391.874756 -277.57247)
			(xy 392.074908 -277.57247)
		)
		(stroke
			(width 0)
			(type solid)
		)
		(fill yes)
		(layer "In2.Cu")
		(net "M_I_CPU0_SB_DQ<4>")
	)
	(gr_poly
		(pts
			(xy 392.074908 -274.287996) (xy 391.974832 -274.18792) (xy 391.874756 -274.287996) (xy 391.874756 -274.332446)
			(xy 392.074908 -274.332446)
		)
		(stroke
			(width 0)
			(type solid)
		)
		(fill yes)
		(layer "In2.Cu")
		(net "M_I_CPU0_SB_DQ<0>")
	)
	(gr_poly
		(pts
			(xy 392.074908 -272.667984) (xy 391.974832 -272.567908) (xy 391.874756 -272.667984) (xy 391.874756 -272.712434)
			(xy 392.074908 -272.712434)
		)
		(stroke
			(width 0)
			(type solid)
		)
		(fill yes)
		(layer "In2.Cu")
		(net "M_I_CPU0_SB_CB<0>")
	)
	(gr_poly
		(pts
			(xy 392.074908 -271.047718) (xy 391.974832 -270.947896) (xy 391.874756 -271.047718) (xy 391.874756 -271.09547)
			(xy 392.074908 -271.09547)
		)
		(stroke
			(width 0)
			(type solid)
		)
		(fill yes)
		(layer "In2.Cu")
		(net "M_I_CPU0_SB_DQS_DP<9>")
	)
	(gr_poly
		(pts
			(xy 392.074908 -269.42796) (xy 391.974832 -269.327884) (xy 391.874756 -269.42796) (xy 391.874756 -269.47241)
			(xy 392.074908 -269.47241)
		)
		(stroke
			(width 0)
			(type solid)
		)
		(fill yes)
		(layer "In2.Cu")
		(net "M_I_CPU0_SB_CB<4>")
	)
	(gr_poly
		(pts
			(xy 392.074908 -264.567924) (xy 391.974832 -264.467848) (xy 391.874756 -264.567924) (xy 391.874756 -264.612374)
			(xy 392.074908 -264.612374)
		)
		(stroke
			(width 0)
			(type solid)
		)
		(fill yes)
		(layer "In2.Cu")
		(net "M_I_CPU0_SB_CA<6>")
	)
	(gr_poly
		(pts
			(xy 392.083544 -287.247584) (xy 391.983468 -287.147762) (xy 391.883646 -287.247584) (xy 391.883646 -287.292034)
			(xy 392.083544 -287.292034)
		)
		(stroke
			(width 0)
			(type solid)
		)
		(fill yes)
		(layer "In2.Cu")
		(net "M_I_CPU0_SB_DQ<20>")
	)
	(gr_poly
		(pts
			(xy 392.083544 -280.767536) (xy 391.983468 -280.667714) (xy 391.883646 -280.767536) (xy 391.883646 -280.815288)
			(xy 392.083544 -280.815288)
		)
		(stroke
			(width 0)
			(type solid)
		)
		(fill yes)
		(layer "In2.Cu")
		(net "M_I_CPU0_SB_DQS_DP<1>")
	)
	(gr_poly
		(pts
			(xy 392.083544 -275.9075) (xy 391.983468 -275.807678) (xy 391.883646 -275.9075) (xy 391.883646 -275.955252)
			(xy 392.083544 -275.955252)
		)
		(stroke
			(width 0)
			(type solid)
		)
		(fill yes)
		(layer "In2.Cu")
		(net "M_I_CPU0_SB_DQS_DP<0>")
	)
	(gr_poly
		(pts
			(xy 392.083544 -262.947658) (xy 391.983468 -262.847836) (xy 391.883646 -262.947658) (xy 391.883646 -262.992108)
			(xy 392.083544 -262.992108)
		)
		(stroke
			(width 0)
			(type solid)
		)
		(fill yes)
		(layer "In2.Cu")
		(net "M_I_CPU0_SB_CA<2>")
	)
	(gr_poly
		(pts
			(xy 392.092688 -291.706046) (xy 392.129518 -291.569648) (xy 391.992866 -291.532818) (xy 391.951464 -291.556694)
			(xy 392.05154 -291.729922)
		)
		(stroke
			(width 0)
			(type solid)
		)
		(fill yes)
		(layer "In2.Cu")
		(net "M_I_CPU0_SB_DQS_DP<3>")
	)
	(gr_poly
		(pts
			(xy 392.093196 -294.946832) (xy 392.129772 -294.81018) (xy 391.99312 -294.773604) (xy 391.954512 -294.795702)
			(xy 392.054588 -294.96893)
		)
		(stroke
			(width 0)
			(type solid)
		)
		(fill yes)
		(layer "In2.Cu")
		(net "M_I_CPU0_SB_DQ<28>")
	)
	(gr_poly
		(pts
			(xy 392.093958 -293.327328) (xy 392.130534 -293.19093) (xy 391.993882 -293.1541) (xy 391.952734 -293.177976)
			(xy 392.052556 -293.351204)
		)
		(stroke
			(width 0)
			(type solid)
		)
		(fill yes)
		(layer "In2.Cu")
		(net "M_I_CPU0_SB_DQS_DN<8>")
	)
	(gr_poly
		(pts
			(xy 392.093958 -290.088066) (xy 392.130534 -289.951414) (xy 391.994136 -289.914838) (xy 391.955528 -289.93719)
			(xy 392.055604 -290.110418)
		)
		(stroke
			(width 0)
			(type solid)
		)
		(fill yes)
		(layer "In2.Cu")
		(net "M_I_CPU0_SB_DQ<25>")
	)
	(gr_poly
		(pts
			(xy 392.164062 -227.935536) (xy 392.125454 -227.913184) (xy 391.988802 -227.94976) (xy 392.025632 -228.086412)
			(xy 392.063986 -228.108764)
		)
		(stroke
			(width 0)
			(type solid)
		)
		(fill yes)
		(layer "In2.Cu")
		(net "M_I_CPU0_SA_DQ<9>")
	)
	(gr_poly
		(pts
			(xy 392.164062 -226.315524) (xy 392.125454 -226.293172) (xy 391.988802 -226.329748) (xy 392.025632 -226.4664)
			(xy 392.063986 -226.488752)
		)
		(stroke
			(width 0)
			(type solid)
		)
		(fill yes)
		(layer "In2.Cu")
		(net "M_I_CPU0_SA_DQ<8>")
	)
	(gr_poly
		(pts
			(xy 392.164062 -224.695512) (xy 392.125454 -224.67316) (xy 391.988802 -224.709736) (xy 392.025632 -224.846388)
			(xy 392.063986 -224.86874)
		)
		(stroke
			(width 0)
			(type solid)
		)
		(fill yes)
		(layer "In2.Cu")
		(net "M_I_CPU0_SA_DQ<5>")
	)
	(gr_poly
		(pts
			(xy 392.164062 -223.0755) (xy 392.125454 -223.053148) (xy 391.988802 -223.089724) (xy 392.025632 -223.226376)
			(xy 392.063986 -223.248728)
		)
		(stroke
			(width 0)
			(type solid)
		)
		(fill yes)
		(layer "In2.Cu")
		(net "M_I_CPU0_SA_DQ<4>")
	)
	(gr_poly
		(pts
			(xy 392.166348 -231.177338) (xy 392.124946 -231.153716) (xy 391.988548 -231.190292) (xy 392.025124 -231.326944)
			(xy 392.066272 -231.350566)
		)
		(stroke
			(width 0)
			(type solid)
		)
		(fill yes)
		(layer "In2.Cu")
		(net "M_I_CPU0_SA_DQS_DN<6>")
	)
	(gr_poly
		(pts
			(xy 392.166348 -229.557326) (xy 392.124946 -229.533704) (xy 391.988548 -229.57028) (xy 392.025124 -229.706932)
			(xy 392.066272 -229.730554)
		)
		(stroke
			(width 0)
			(type solid)
		)
		(fill yes)
		(layer "In2.Cu")
		(net "M_I_CPU0_SA_DQS_DP<1>")
	)
	(gr_poly
		(pts
			(xy 392.23696 -255.622552) (xy 392.23696 -255.578102) (xy 392.037062 -255.578102) (xy 392.037062 -255.622552)
			(xy 392.137138 -255.722628)
		)
		(stroke
			(width 0)
			(type solid)
		)
		(fill yes)
		(layer "In2.Cu")
		(net "M_I_CPU0_SA_PAR")
	)
	(gr_poly
		(pts
			(xy 392.23696 -249.142504) (xy 392.23696 -249.098054) (xy 392.037062 -249.098054) (xy 392.037062 -249.142504)
			(xy 392.137138 -249.24258)
		)
		(stroke
			(width 0)
			(type solid)
		)
		(fill yes)
		(layer "In2.Cu")
		(net "M_I_CPU0_SA_CB<7>")
	)
	(gr_poly
		(pts
			(xy 392.23696 -247.522746) (xy 392.23696 -247.474994) (xy 392.037062 -247.474994) (xy 392.037062 -247.522746)
			(xy 392.137138 -247.622568)
		)
		(stroke
			(width 0)
			(type solid)
		)
		(fill yes)
		(layer "In2.Cu")
		(net "M_I_CPU0_SA_DQS_DP<9>")
	)
	(gr_poly
		(pts
			(xy 392.239246 -242.662456) (xy 392.239246 -242.614958) (xy 392.039348 -242.614958) (xy 392.039348 -242.662456)
			(xy 392.139424 -242.762532)
		)
		(stroke
			(width 0)
			(type solid)
		)
		(fill yes)
		(layer "In2.Cu")
		(net "M_I_CPU0_SA_DQS_DP<8>")
	)
	(gr_poly
		(pts
			(xy 392.244834 -250.762262) (xy 392.244834 -250.717812) (xy 392.044682 -250.717812) (xy 392.044682 -250.762262)
			(xy 392.144758 -250.862338)
		)
		(stroke
			(width 0)
			(type solid)
		)
		(fill yes)
		(layer "In2.Cu")
		(net "M_I_CPU0_RESET_N")
	)
	(gr_poly
		(pts
			(xy 392.245088 -254.002286) (xy 392.245088 -253.957836) (xy 392.044936 -253.957836) (xy 392.044936 -254.002286)
			(xy 392.145012 -254.102362)
		)
		(stroke
			(width 0)
			(type solid)
		)
		(fill yes)
		(layer "In2.Cu")
		(net "M_I_CPU0_SA_CA<3>")
	)
	(gr_poly
		(pts
			(xy 392.245088 -245.902226) (xy 392.245088 -245.857776) (xy 392.044936 -245.857776) (xy 392.044936 -245.902226)
			(xy 392.145012 -246.002302)
		)
		(stroke
			(width 0)
			(type solid)
		)
		(fill yes)
		(layer "In2.Cu")
		(net "M_I_CPU0_SA_CB<3>")
	)
	(gr_poly
		(pts
			(xy 392.245088 -244.282214) (xy 392.245088 -244.237764) (xy 392.044936 -244.237764) (xy 392.044936 -244.282214)
			(xy 392.145012 -244.38229)
		)
		(stroke
			(width 0)
			(type solid)
		)
		(fill yes)
		(layer "In2.Cu")
		(net "M_I_CPU0_SA_DQ<31>")
	)
	(gr_poly
		(pts
			(xy 392.250676 -243.066062) (xy 392.1506 -242.965986) (xy 392.050778 -243.066062) (xy 392.050778 -243.110512)
			(xy 392.250676 -243.110512)
		)
		(stroke
			(width 0)
			(type solid)
		)
		(fill yes)
		(layer "In2.Cu")
		(net "M_I_CPU0_SA_DQ<28>")
	)
	(gr_poly
		(pts
			(xy 392.250676 -241.445796) (xy 392.1506 -241.345974) (xy 392.050778 -241.445796) (xy 392.050778 -241.493548)
			(xy 392.250676 -241.493548)
		)
		(stroke
			(width 0)
			(type solid)
		)
		(fill yes)
		(layer "In2.Cu")
		(net "M_I_CPU0_SA_DQS_DP<3>")
	)
	(gr_poly
		(pts
			(xy 392.250676 -241.04219) (xy 392.250676 -240.99774) (xy 392.050778 -240.99774) (xy 392.050778 -241.04219)
			(xy 392.1506 -241.142266)
		)
		(stroke
			(width 0)
			(type solid)
		)
		(fill yes)
		(layer "In2.Cu")
		(net "M_I_CPU0_SA_DQ<27>")
	)
	(gr_poly
		(pts
			(xy 392.250676 -239.826038) (xy 392.1506 -239.725962) (xy 392.050778 -239.826038) (xy 392.050778 -239.870488)
			(xy 392.250676 -239.870488)
		)
		(stroke
			(width 0)
			(type solid)
		)
		(fill yes)
		(layer "In2.Cu")
		(net "M_I_CPU0_SA_DQ<24>")
	)
	(gr_poly
		(pts
			(xy 392.256264 -254.4064) (xy 392.156442 -254.306324) (xy 392.056366 -254.4064) (xy 392.056366 -254.450596)
			(xy 392.256264 -254.450596)
		)
		(stroke
			(width 0)
			(type solid)
		)
		(fill yes)
		(layer "In2.Cu")
		(net "M_I_CPU0_SA_CA<4>")
	)
	(gr_poly
		(pts
			(xy 392.256264 -252.786134) (xy 392.156442 -252.686312) (xy 392.056366 -252.786134) (xy 392.056366 -252.830584)
			(xy 392.256264 -252.830584)
		)
		(stroke
			(width 0)
			(type solid)
		)
		(fill yes)
		(layer "In2.Cu")
		(net "M_I_CPU0_SA_CA<0>")
	)
	(gr_poly
		(pts
			(xy 392.256264 -251.166376) (xy 392.156442 -251.0663) (xy 392.056366 -251.166376) (xy 392.056366 -251.210572)
			(xy 392.256264 -251.210572)
		)
		(stroke
			(width 0)
			(type solid)
		)
		(fill yes)
		(layer "In2.Cu")
		(net "M_I_CPU0_SA_CS_N<0>")
	)
	(gr_poly
		(pts
			(xy 392.256264 -247.926352) (xy 392.156442 -247.826276) (xy 392.056366 -247.926352) (xy 392.056366 -247.970802)
			(xy 392.256264 -247.970802)
		)
		(stroke
			(width 0)
			(type solid)
		)
		(fill yes)
		(layer "In2.Cu")
		(net "M_I_CPU0_SA_CB<4>")
	)
	(gr_poly
		(pts
			(xy 392.256264 -244.686328) (xy 392.156442 -244.586252) (xy 392.056366 -244.686328) (xy 392.056366 -244.730524)
			(xy 392.256264 -244.730524)
		)
		(stroke
			(width 0)
			(type solid)
		)
		(fill yes)
		(layer "In2.Cu")
		(net "M_I_CPU0_SA_CB<0>")
	)
	(gr_poly
		(pts
			(xy 392.299952 -230.240586) (xy 392.263376 -230.103934) (xy 392.222228 -230.080058) (xy 392.122152 -230.253286)
			(xy 392.1633 -230.277162)
		)
		(stroke
			(width 0)
			(type solid)
		)
		(fill yes)
		(layer "In2.Cu")
		(net "M_I_CPU0_SA_DQS_DN<1>")
	)
	(gr_poly
		(pts
			(xy 392.300714 -231.859074) (xy 392.264138 -231.722676) (xy 392.222736 -231.6988) (xy 392.122914 -231.872028)
			(xy 392.164062 -231.895904)
		)
		(stroke
			(width 0)
			(type solid)
		)
		(fill yes)
		(layer "In2.Cu")
		(net "M_I_CPU0_SA_DQS_DP<6>")
	)
	(gr_poly
		(pts
			(xy 392.300714 -228.618796) (xy 392.264138 -228.482144) (xy 392.225784 -228.459792) (xy 392.125708 -228.63302)
			(xy 392.164316 -228.655372)
		)
		(stroke
			(width 0)
			(type solid)
		)
		(fill yes)
		(layer "In2.Cu")
		(net "M_I_CPU0_SA_DQ<11>")
	)
	(gr_poly
		(pts
			(xy 392.300714 -226.998784) (xy 392.264138 -226.862132) (xy 392.225784 -226.83978) (xy 392.125708 -227.013008)
			(xy 392.164316 -227.03536)
		)
		(stroke
			(width 0)
			(type solid)
		)
		(fill yes)
		(layer "In2.Cu")
		(net "M_I_CPU0_SA_DQ<10>")
	)
	(gr_poly
		(pts
			(xy 392.300714 -225.378772) (xy 392.264138 -225.24212) (xy 392.225784 -225.219768) (xy 392.125708 -225.392996)
			(xy 392.164316 -225.415348)
		)
		(stroke
			(width 0)
			(type solid)
		)
		(fill yes)
		(layer "In2.Cu")
		(net "M_I_CPU0_SA_DQ<7>")
	)
	(gr_poly
		(pts
			(xy 392.300714 -223.75876) (xy 392.264138 -223.622108) (xy 392.225784 -223.599756) (xy 392.125708 -223.772984)
			(xy 392.164316 -223.795336)
		)
		(stroke
			(width 0)
			(type solid)
		)
		(fill yes)
		(layer "In2.Cu")
		(net "M_I_CPU0_SA_DQ<6>")
	)
	(gr_poly
		(pts
			(xy 392.301476 -222.137478) (xy 392.2649 -222.000826) (xy 392.223498 -221.97695) (xy 392.123676 -222.150178)
			(xy 392.164824 -222.174054)
		)
		(stroke
			(width 0)
			(type solid)
		)
		(fill yes)
		(layer "In2.Cu")
		(net "M_I_CPU0_SA_DQS_DP<5>")
	)
	(gr_poly
		(pts
			(xy 392.467592 -294.685212) (xy 392.367516 -294.511984) (xy 392.326368 -294.53586) (xy 392.289538 -294.672512)
			(xy 392.42619 -294.709088)
		)
		(stroke
			(width 0)
			(type solid)
		)
		(fill yes)
		(layer "In2.Cu")
		(net "M_I_CPU0_SB_DQS_DP<8>")
	)
	(gr_poly
		(pts
			(xy 392.53541 -270.23822) (xy 392.435334 -270.138144) (xy 392.335258 -270.23822) (xy 392.335258 -270.282416)
			(xy 392.53541 -270.282416)
		)
		(stroke
			(width 0)
			(type solid)
		)
		(fill yes)
		(layer "In2.Cu")
		(net "M_I_CPU0_SB_CB<5>")
	)
	(gr_poly
		(pts
			(xy 392.538458 -269.834106) (xy 392.538458 -269.789656) (xy 392.33856 -269.789656) (xy 392.33856 -269.834106)
			(xy 392.438636 -269.934182)
		)
		(stroke
			(width 0)
			(type solid)
		)
		(fill yes)
		(layer "In2.Cu")
		(net "M_I_CPU0_SB_CB<6>")
	)
	(gr_poly
		(pts
			(xy 392.544808 -286.03448) (xy 392.544808 -285.986728) (xy 392.344656 -285.986728) (xy 392.344656 -286.03448)
			(xy 392.444732 -286.134302)
		)
		(stroke
			(width 0)
			(type solid)
		)
		(fill yes)
		(layer "In2.Cu")
		(net "M_I_CPU0_SB_DQS_DN<2>")
	)
	(gr_poly
		(pts
			(xy 392.545062 -271.454372) (xy 392.545062 -271.40662) (xy 392.34491 -271.40662) (xy 392.34491 -271.454372)
			(xy 392.444986 -271.554194)
		)
		(stroke
			(width 0)
			(type solid)
		)
		(fill yes)
		(layer "In2.Cu")
		(net "M_I_CPU0_SB_DQS_DN<9>")
	)
	(gr_poly
		(pts
			(xy 392.553444 -284.414468) (xy 392.553444 -284.370018) (xy 392.353546 -284.370018) (xy 392.353546 -284.414468)
			(xy 392.453368 -284.514544)
		)
		(stroke
			(width 0)
			(type solid)
		)
		(fill yes)
		(layer "In2.Cu")
		(net "M_I_CPU0_SB_DQ<18>")
	)
	(gr_poly
		(pts
			(xy 392.553444 -282.794456) (xy 392.553444 -282.750006) (xy 392.353546 -282.750006) (xy 392.353546 -282.794456)
			(xy 392.453368 -282.894532)
		)
		(stroke
			(width 0)
			(type solid)
		)
		(fill yes)
		(layer "In2.Cu")
		(net "M_I_CPU0_SB_DQ<14>")
	)
	(gr_poly
		(pts
			(xy 392.553444 -279.554432) (xy 392.553444 -279.509982) (xy 392.353546 -279.509982) (xy 392.353546 -279.554432)
			(xy 392.453368 -279.654508)
		)
		(stroke
			(width 0)
			(type solid)
		)
		(fill yes)
		(layer "In2.Cu")
		(net "M_I_CPU0_SB_DQ<10>")
	)
	(gr_poly
		(pts
			(xy 392.553444 -277.93442) (xy 392.553444 -277.88997) (xy 392.353546 -277.88997) (xy 392.353546 -277.93442)
			(xy 392.453368 -278.034496)
		)
		(stroke
			(width 0)
			(type solid)
		)
		(fill yes)
		(layer "In2.Cu")
		(net "M_I_CPU0_SB_DQ<6>")
	)
	(gr_poly
		(pts
			(xy 392.553444 -274.694396) (xy 392.553444 -274.649946) (xy 392.353546 -274.649946) (xy 392.353546 -274.694396)
			(xy 392.453368 -274.794472)
		)
		(stroke
			(width 0)
			(type solid)
		)
		(fill yes)
		(layer "In2.Cu")
		(net "M_I_CPU0_SB_DQ<2>")
	)
	(gr_poly
		(pts
			(xy 392.553444 -273.074384) (xy 392.553444 -273.029934) (xy 392.353546 -273.029934) (xy 392.353546 -273.074384)
			(xy 392.453368 -273.17446)
		)
		(stroke
			(width 0)
			(type solid)
		)
		(fill yes)
		(layer "In2.Cu")
		(net "M_I_CPU0_SB_CB<2>")
	)
	(gr_poly
		(pts
			(xy 392.553444 -266.594336) (xy 392.553444 -266.549886) (xy 392.353546 -266.549886) (xy 392.353546 -266.594336)
			(xy 392.453368 -266.694412)
		)
		(stroke
			(width 0)
			(type solid)
		)
		(fill yes)
		(layer "In2.Cu")
		(net "M_I_CPU0_SB_CS_N<1>")
	)
	(gr_poly
		(pts
			(xy 392.557254 -281.57805) (xy 392.457432 -281.477974) (xy 392.357356 -281.57805) (xy 392.357356 -281.625548)
			(xy 392.557254 -281.625548)
		)
		(stroke
			(width 0)
			(type solid)
		)
		(fill yes)
		(layer "In2.Cu")
		(net "M_I_CPU0_SB_DQS_DN<6>")
	)
	(gr_poly
		(pts
			(xy 392.557254 -276.718014) (xy 392.457432 -276.617938) (xy 392.357356 -276.718014) (xy 392.357356 -276.765512)
			(xy 392.557254 -276.765512)
		)
		(stroke
			(width 0)
			(type solid)
		)
		(fill yes)
		(layer "In2.Cu")
		(net "M_I_CPU0_SB_DQS_DN<5>")
	)
	(gr_poly
		(pts
			(xy 392.557254 -271.857978) (xy 392.457432 -271.757902) (xy 392.357356 -271.857978) (xy 392.357356 -271.905476)
			(xy 392.557254 -271.905476)
		)
		(stroke
			(width 0)
			(type solid)
		)
		(fill yes)
		(layer "In2.Cu")
		(net "M_I_CPU0_SB_DQS_DN<4>")
	)
	(gr_poly
		(pts
			(xy 392.557508 -284.818328) (xy 392.457432 -284.718252) (xy 392.357356 -284.818328) (xy 392.357356 -284.862778)
			(xy 392.557508 -284.862778)
		)
		(stroke
			(width 0)
			(type solid)
		)
		(fill yes)
		(layer "In2.Cu")
		(net "M_I_CPU0_SB_DQ<17>")
	)
	(gr_poly
		(pts
			(xy 392.557508 -283.198316) (xy 392.457432 -283.09824) (xy 392.357356 -283.198316) (xy 392.357356 -283.242766)
			(xy 392.557508 -283.242766)
		)
		(stroke
			(width 0)
			(type solid)
		)
		(fill yes)
		(layer "In2.Cu")
		(net "M_I_CPU0_SB_DQ<13>")
	)
	(gr_poly
		(pts
			(xy 392.557508 -279.958292) (xy 392.457432 -279.858216) (xy 392.357356 -279.958292) (xy 392.357356 -280.002742)
			(xy 392.557508 -280.002742)
		)
		(stroke
			(width 0)
			(type solid)
		)
		(fill yes)
		(layer "In2.Cu")
		(net "M_I_CPU0_SB_DQ<9>")
	)
	(gr_poly
		(pts
			(xy 392.557508 -278.33828) (xy 392.457432 -278.238204) (xy 392.357356 -278.33828) (xy 392.357356 -278.38273)
			(xy 392.557508 -278.38273)
		)
		(stroke
			(width 0)
			(type solid)
		)
		(fill yes)
		(layer "In2.Cu")
		(net "M_I_CPU0_SB_DQ<5>")
	)
	(gr_poly
		(pts
			(xy 392.557508 -275.098256) (xy 392.457432 -274.99818) (xy 392.357356 -275.098256) (xy 392.357356 -275.142706)
			(xy 392.557508 -275.142706)
		)
		(stroke
			(width 0)
			(type solid)
		)
		(fill yes)
		(layer "In2.Cu")
		(net "M_I_CPU0_SB_DQ<1>")
	)
	(gr_poly
		(pts
			(xy 392.557508 -273.478244) (xy 392.457432 -273.378168) (xy 392.357356 -273.478244) (xy 392.357356 -273.522694)
			(xy 392.557508 -273.522694)
		)
		(stroke
			(width 0)
			(type solid)
		)
		(fill yes)
		(layer "In2.Cu")
		(net "M_I_CPU0_SB_CB<1>")
	)
	(gr_poly
		(pts
			(xy 392.557508 -266.998196) (xy 392.457432 -266.89812) (xy 392.357356 -266.998196) (xy 392.357356 -267.042646)
			(xy 392.557508 -267.042646)
		)
		(stroke
			(width 0)
			(type solid)
		)
		(fill yes)
		(layer "In2.Cu")
		(net "M_I_CPU0_SA_RSP<0>")
	)
	(gr_poly
		(pts
			(xy 392.557508 -265.378184) (xy 392.457432 -265.278108) (xy 392.357356 -265.378184) (xy 392.357356 -265.422634)
			(xy 392.557508 -265.422634)
		)
		(stroke
			(width 0)
			(type solid)
		)
		(fill yes)
		(layer "In2.Cu")
		(net "M_I_CPU0_SB_PAR")
	)
	(gr_poly
		(pts
			(xy 392.557508 -263.758172) (xy 392.457432 -263.658096) (xy 392.357356 -263.758172) (xy 392.357356 -263.802622)
			(xy 392.557508 -263.802622)
		)
		(stroke
			(width 0)
			(type solid)
		)
		(fill yes)
		(layer "In2.Cu")
		(net "M_I_CPU0_SB_CA<4>")
	)
	(gr_poly
		(pts
			(xy 392.557508 -262.13816) (xy 392.457432 -262.038084) (xy 392.357356 -262.13816) (xy 392.357356 -262.18261)
			(xy 392.557508 -262.18261)
		)
		(stroke
			(width 0)
			(type solid)
		)
		(fill yes)
		(layer "In2.Cu")
		(net "M_I_CPU0_SB_CA<0>")
	)
	(gr_poly
		(pts
			(xy 392.558778 -295.766744) (xy 392.607038 -295.633902) (xy 392.474196 -295.585642) (xy 392.43381 -295.604438)
			(xy 392.518392 -295.78554)
		)
		(stroke
			(width 0)
			(type solid)
		)
		(fill yes)
		(layer "In2.Cu")
		(net "M_I_CPU0_SB_DQ<28>")
	)
	(gr_poly
		(pts
			(xy 392.562588 -294.136064) (xy 392.599418 -293.999412) (xy 392.462766 -293.962836) (xy 392.421364 -293.986712)
			(xy 392.52144 -294.15994)
		)
		(stroke
			(width 0)
			(type solid)
		)
		(fill yes)
		(layer "In2.Cu")
		(net "M_I_CPU0_SB_DQS_DN<8>")
	)
	(gr_poly
		(pts
			(xy 392.564112 -292.517322) (xy 392.600688 -292.380924) (xy 392.464036 -292.344348) (xy 392.422888 -292.36797)
			(xy 392.52271 -292.541198)
		)
		(stroke
			(width 0)
			(type solid)
		)
		(fill yes)
		(layer "In2.Cu")
		(net "M_I_CPU0_SB_DQS_DP<3>")
	)
	(gr_poly
		(pts
			(xy 392.564112 -290.898072) (xy 392.600942 -290.76142) (xy 392.46429 -290.724844) (xy 392.425682 -290.747196)
			(xy 392.525758 -290.920424)
		)
		(stroke
			(width 0)
			(type solid)
		)
		(fill yes)
		(layer "In2.Cu")
		(net "M_I_CPU0_SB_DQ<25>")
	)
	(gr_poly
		(pts
			(xy 392.633962 -227.12553) (xy 392.595354 -227.103178) (xy 392.458702 -227.139754) (xy 392.495532 -227.276406)
			(xy 392.533886 -227.298758)
		)
		(stroke
			(width 0)
			(type solid)
		)
		(fill yes)
		(layer "In2.Cu")
		(net "M_I_CPU0_SA_DQ<9>")
	)
	(gr_poly
		(pts
			(xy 392.633962 -225.505518) (xy 392.595354 -225.483166) (xy 392.458702 -225.519742) (xy 392.495532 -225.656394)
			(xy 392.533886 -225.678746)
		)
		(stroke
			(width 0)
			(type solid)
		)
		(fill yes)
		(layer "In2.Cu")
		(net "M_I_CPU0_SA_DQ<8>")
	)
	(gr_poly
		(pts
			(xy 392.633962 -223.885506) (xy 392.595354 -223.863154) (xy 392.458702 -223.89973) (xy 392.495532 -224.036382)
			(xy 392.533886 -224.058734)
		)
		(stroke
			(width 0)
			(type solid)
		)
		(fill yes)
		(layer "In2.Cu")
		(net "M_I_CPU0_SA_DQ<5>")
	)
	(gr_poly
		(pts
			(xy 392.635232 -222.262446) (xy 392.596878 -222.240348) (xy 392.460226 -222.276924) (xy 392.496802 -222.413576)
			(xy 392.535156 -222.435674)
		)
		(stroke
			(width 0)
			(type solid)
		)
		(fill yes)
		(layer "In2.Cu")
		(net "M_I_CPU0_SA_DQ<4>")
	)
	(gr_poly
		(pts
			(xy 392.636756 -228.746304) (xy 392.595608 -228.722428) (xy 392.458956 -228.759258) (xy 392.495532 -228.895656)
			(xy 392.536934 -228.919532)
		)
		(stroke
			(width 0)
			(type solid)
		)
		(fill yes)
		(layer "In2.Cu")
		(net "M_I_CPU0_SA_DQS_DP<1>")
	)
	(gr_poly
		(pts
			(xy 392.637518 -230.365046) (xy 392.59637 -230.34117) (xy 392.459718 -230.377746) (xy 392.496294 -230.514398)
			(xy 392.537442 -230.538274)
		)
		(stroke
			(width 0)
			(type solid)
		)
		(fill yes)
		(layer "In2.Cu")
		(net "M_I_CPU0_SA_DQS_DN<6>")
	)
	(gr_poly
		(pts
			(xy 392.70686 -247.115838) (xy 392.607038 -247.016016) (xy 392.506962 -247.115838) (xy 392.506962 -247.16359)
			(xy 392.70686 -247.16359)
		)
		(stroke
			(width 0)
			(type solid)
		)
		(fill yes)
		(layer "In2.Cu")
		(net "M_I_CPU0_SA_DQS_DN<9>")
	)
	(gr_poly
		(pts
			(xy 392.70686 -242.255802) (xy 392.607038 -242.15598) (xy 392.506962 -242.255802) (xy 392.506962 -242.303554)
			(xy 392.70686 -242.303554)
		)
		(stroke
			(width 0)
			(type solid)
		)
		(fill yes)
		(layer "In2.Cu")
		(net "M_I_CPU0_SA_DQS_DN<8>")
	)
	(gr_poly
		(pts
			(xy 392.712194 -255.216152) (xy 392.612118 -255.116076) (xy 392.512042 -255.216152) (xy 392.512042 -255.260602)
			(xy 392.712194 -255.260602)
		)
		(stroke
			(width 0)
			(type solid)
		)
		(fill yes)
		(layer "In2.Cu")
		(net "M_I_CPU0_SA_CA<6>")
	)
	(gr_poly
		(pts
			(xy 392.712194 -251.976128) (xy 392.612118 -251.876052) (xy 392.512042 -251.976128) (xy 392.512042 -252.020578)
			(xy 392.712194 -252.020578)
		)
		(stroke
			(width 0)
			(type solid)
		)
		(fill yes)
		(layer "In2.Cu")
		(net "M_I_CPU0_SA_CS_N<1>")
	)
	(gr_poly
		(pts
			(xy 392.712194 -248.736104) (xy 392.612118 -248.636028) (xy 392.512042 -248.736104) (xy 392.512042 -248.780554)
			(xy 392.712194 -248.780554)
		)
		(stroke
			(width 0)
			(type solid)
		)
		(fill yes)
		(layer "In2.Cu")
		(net "M_I_CPU0_SA_CB<5>")
	)
	(gr_poly
		(pts
			(xy 392.714988 -253.59614) (xy 392.614912 -253.496064) (xy 392.514836 -253.59614) (xy 392.514836 -253.64059)
			(xy 392.714988 -253.64059)
		)
		(stroke
			(width 0)
			(type solid)
		)
		(fill yes)
		(layer "In2.Cu")
		(net "M_I_CPU0_SA_CA<2>")
	)
	(gr_poly
		(pts
			(xy 392.714988 -250.356116) (xy 392.614912 -250.25604) (xy 392.514836 -250.356116) (xy 392.514836 -250.400566)
			(xy 392.714988 -250.400566)
		)
		(stroke
			(width 0)
			(type solid)
		)
		(fill yes)
		(layer "In2.Cu")
		(net "M_I_CPU0_ALERT_R_N")
	)
	(gr_poly
		(pts
			(xy 392.714988 -245.49608) (xy 392.614912 -245.396004) (xy 392.514836 -245.49608) (xy 392.514836 -245.54053)
			(xy 392.714988 -245.54053)
		)
		(stroke
			(width 0)
			(type solid)
		)
		(fill yes)
		(layer "In2.Cu")
		(net "M_I_CPU0_SA_CB<1>")
	)
	(gr_poly
		(pts
			(xy 392.714988 -243.876068) (xy 392.614912 -243.775992) (xy 392.514836 -243.876068) (xy 392.514836 -243.920518)
			(xy 392.714988 -243.920518)
		)
		(stroke
			(width 0)
			(type solid)
		)
		(fill yes)
		(layer "In2.Cu")
		(net "M_I_CPU0_SA_DQ<29>")
	)
	(gr_poly
		(pts
			(xy 392.720576 -243.472208) (xy 392.720576 -243.427758) (xy 392.520678 -243.427758) (xy 392.520678 -243.472208)
			(xy 392.6205 -243.572284)
		)
		(stroke
			(width 0)
			(type solid)
		)
		(fill yes)
		(layer "In2.Cu")
		(net "M_I_CPU0_SA_DQ<30>")
	)
	(gr_poly
		(pts
			(xy 392.720576 -241.85245) (xy 392.720576 -241.804952) (xy 392.520678 -241.804952) (xy 392.520678 -241.85245)
			(xy 392.6205 -241.952526)
		)
		(stroke
			(width 0)
			(type solid)
		)
		(fill yes)
		(layer "In2.Cu")
		(net "M_I_CPU0_SA_DQS_DN<3>")
	)
	(gr_poly
		(pts
			(xy 392.720576 -240.636044) (xy 392.6205 -240.535968) (xy 392.520678 -240.636044) (xy 392.520678 -240.680494)
			(xy 392.720576 -240.680494)
		)
		(stroke
			(width 0)
			(type solid)
		)
		(fill yes)
		(layer "In2.Cu")
		(net "M_I_CPU0_SA_DQ<25>")
	)
	(gr_poly
		(pts
			(xy 392.720576 -240.232184) (xy 392.720576 -240.187734) (xy 392.520678 -240.187734) (xy 392.520678 -240.232184)
			(xy 392.6205 -240.33226)
		)
		(stroke
			(width 0)
			(type solid)
		)
		(fill yes)
		(layer "In2.Cu")
		(net "M_I_CPU0_SA_DQ<26>")
	)
	(gr_poly
		(pts
			(xy 392.726164 -246.712994) (xy 392.726164 -246.665242) (xy 392.526266 -246.665242) (xy 392.526266 -246.712994)
			(xy 392.626342 -246.81307)
		)
		(stroke
			(width 0)
			(type solid)
		)
		(fill yes)
		(layer "In2.Cu")
		(net "M_I_CPU0_SA_DQS_DN<4>")
	)
	(gr_poly
		(pts
			(xy 392.72845 -254.8128) (xy 392.72845 -254.76835) (xy 392.528298 -254.76835) (xy 392.528298 -254.8128)
			(xy 392.628374 -254.912876)
		)
		(stroke
			(width 0)
			(type solid)
		)
		(fill yes)
		(layer "In2.Cu")
		(net "M_I_CPU0_SA_CA<5>")
	)
	(gr_poly
		(pts
			(xy 392.72845 -253.192788) (xy 392.72845 -253.148338) (xy 392.528298 -253.148338) (xy 392.528298 -253.192788)
			(xy 392.628374 -253.292864)
		)
		(stroke
			(width 0)
			(type solid)
		)
		(fill yes)
		(layer "In2.Cu")
		(net "M_I_CPU0_SA_CA<1>")
	)
	(gr_poly
		(pts
			(xy 392.72845 -248.332752) (xy 392.72845 -248.288302) (xy 392.528298 -248.288302) (xy 392.528298 -248.332752)
			(xy 392.628374 -248.432828)
		)
		(stroke
			(width 0)
			(type solid)
		)
		(fill yes)
		(layer "In2.Cu")
		(net "M_I_CPU0_SA_CB<6>")
	)
	(gr_poly
		(pts
			(xy 392.72845 -245.092728) (xy 392.72845 -245.048278) (xy 392.528298 -245.048278) (xy 392.528298 -245.092728)
			(xy 392.628374 -245.192804)
		)
		(stroke
			(width 0)
			(type solid)
		)
		(fill yes)
		(layer "In2.Cu")
		(net "M_I_CPU0_SA_CB<2>")
	)
	(gr_poly
		(pts
			(xy 392.732768 -256.432812) (xy 392.732768 -256.38506) (xy 392.53287 -256.38506) (xy 392.53287 -256.432812)
			(xy 392.632692 -256.532888)
		)
		(stroke
			(width 0)
			(type solid)
		)
		(fill yes)
		(layer "In2.Cu")
		(net "M_I_CPU0_CLK_DN<0>")
	)
	(gr_poly
		(pts
			(xy 392.768836 -222.951548) (xy 392.732006 -222.814896) (xy 392.693652 -222.792544) (xy 392.593576 -222.965772)
			(xy 392.632184 -222.988124)
		)
		(stroke
			(width 0)
			(type solid)
		)
		(fill yes)
		(layer "In2.Cu")
		(net "M_I_CPU0_SA_DQ<6>")
	)
	(gr_poly
		(pts
			(xy 392.770614 -227.80879) (xy 392.734038 -227.672138) (xy 392.695684 -227.649786) (xy 392.595608 -227.823014)
			(xy 392.634216 -227.845366)
		)
		(stroke
			(width 0)
			(type solid)
		)
		(fill yes)
		(layer "In2.Cu")
		(net "M_I_CPU0_SA_DQ<11>")
	)
	(gr_poly
		(pts
			(xy 392.770614 -226.188778) (xy 392.734038 -226.052126) (xy 392.695684 -226.029774) (xy 392.595608 -226.203002)
			(xy 392.634216 -226.225354)
		)
		(stroke
			(width 0)
			(type solid)
		)
		(fill yes)
		(layer "In2.Cu")
		(net "M_I_CPU0_SA_DQ<10>")
	)
	(gr_poly
		(pts
			(xy 392.770614 -224.568766) (xy 392.734038 -224.432114) (xy 392.695684 -224.409762) (xy 392.595608 -224.58299)
			(xy 392.634216 -224.605342)
		)
		(stroke
			(width 0)
			(type solid)
		)
		(fill yes)
		(layer "In2.Cu")
		(net "M_I_CPU0_SA_DQ<7>")
	)
	(gr_poly
		(pts
			(xy 392.771122 -231.048052) (xy 392.734546 -230.9114) (xy 392.693398 -230.887778) (xy 392.593322 -231.061006)
			(xy 392.63447 -231.084628)
		)
		(stroke
			(width 0)
			(type solid)
		)
		(fill yes)
		(layer "In2.Cu")
		(net "M_I_CPU0_SA_DQS_DP<6>")
	)
	(gr_poly
		(pts
			(xy 392.771122 -229.42804) (xy 392.734546 -229.291388) (xy 392.693398 -229.267766) (xy 392.593322 -229.440994)
			(xy 392.63447 -229.464616)
		)
		(stroke
			(width 0)
			(type solid)
		)
		(fill yes)
		(layer "In2.Cu")
		(net "M_I_CPU0_SA_DQS_DN<1>")
	)
	(gr_poly
		(pts
			(xy 392.933936 -268.877288) (xy 392.895328 -268.854936) (xy 392.75893 -268.891512) (xy 392.795506 -269.028164)
			(xy 392.83386 -269.050516)
		)
		(stroke
			(width 0)
			(type solid)
		)
		(fill yes)
		(layer "In2.Cu")
		(net "M_I_CPU0_SB_CB<4>")
	)
	(gr_poly
		(pts
			(xy 392.93673 -295.493948) (xy 392.836908 -295.32072) (xy 392.795506 -295.344596) (xy 392.75893 -295.480994)
			(xy 392.895582 -295.517824)
		)
		(stroke
			(width 0)
			(type solid)
		)
		(fill yes)
		(layer "In2.Cu")
		(net "M_I_CPU0_SB_DQS_DP<8>")
	)
	(gr_poly
		(pts
			(xy 392.93673 -293.873936) (xy 392.836908 -293.700708) (xy 392.795506 -293.724584) (xy 392.75893 -293.860982)
			(xy 392.895582 -293.897812)
		)
		(stroke
			(width 0)
			(type solid)
		)
		(fill yes)
		(layer "In2.Cu")
		(net "M_I_CPU0_SB_DQS_DN<3>")
	)
	(gr_poly
		(pts
			(xy 393.006072 -284.007814) (xy 392.905996 -283.907992) (xy 392.806174 -284.007814) (xy 392.806174 -284.052264)
			(xy 393.006072 -284.052264)
		)
		(stroke
			(width 0)
			(type solid)
		)
		(fill yes)
		(layer "In2.Cu")
		(net "M_I_CPU0_SB_DQ<16>")
	)
	(gr_poly
		(pts
			(xy 393.006072 -282.387802) (xy 392.905996 -282.28798) (xy 392.806174 -282.387802) (xy 392.806174 -282.432252)
			(xy 393.006072 -282.432252)
		)
		(stroke
			(width 0)
			(type solid)
		)
		(fill yes)
		(layer "In2.Cu")
		(net "M_I_CPU0_SB_DQ<12>")
	)
	(gr_poly
		(pts
			(xy 393.006072 -279.147778) (xy 392.905996 -279.047956) (xy 392.806174 -279.147778) (xy 392.806174 -279.192228)
			(xy 393.006072 -279.192228)
		)
		(stroke
			(width 0)
			(type solid)
		)
		(fill yes)
		(layer "In2.Cu")
		(net "M_I_CPU0_SB_DQ<8>")
	)
	(gr_poly
		(pts
			(xy 393.006072 -277.527766) (xy 392.905996 -277.427944) (xy 392.806174 -277.527766) (xy 392.806174 -277.572216)
			(xy 393.006072 -277.572216)
		)
		(stroke
			(width 0)
			(type solid)
		)
		(fill yes)
		(layer "In2.Cu")
		(net "M_I_CPU0_SB_DQ<4>")
	)
	(gr_poly
		(pts
			(xy 393.006072 -274.287742) (xy 392.905996 -274.18792) (xy 392.806174 -274.287742) (xy 392.806174 -274.332192)
			(xy 393.006072 -274.332192)
		)
		(stroke
			(width 0)
			(type solid)
		)
		(fill yes)
		(layer "In2.Cu")
		(net "M_I_CPU0_SB_DQ<0>")
	)
	(gr_poly
		(pts
			(xy 393.006072 -272.66773) (xy 392.905996 -272.567908) (xy 392.806174 -272.66773) (xy 392.806174 -272.71218)
			(xy 393.006072 -272.71218)
		)
		(stroke
			(width 0)
			(type solid)
		)
		(fill yes)
		(layer "In2.Cu")
		(net "M_I_CPU0_SB_CB<0>")
	)
	(gr_poly
		(pts
			(xy 393.006072 -264.56767) (xy 392.905996 -264.467848) (xy 392.806174 -264.56767) (xy 392.806174 -264.61212)
			(xy 393.006072 -264.61212)
		)
		(stroke
			(width 0)
			(type solid)
		)
		(fill yes)
		(layer "In2.Cu")
		(net "M_I_CPU0_SB_CA<6>")
	)
	(gr_poly
		(pts
			(xy 393.012168 -262.947912) (xy 392.912092 -262.847836) (xy 392.812016 -262.947912) (xy 392.812016 -262.992362)
			(xy 393.012168 -262.992362)
		)
		(stroke
			(width 0)
			(type solid)
		)
		(fill yes)
		(layer "In2.Cu")
		(net "M_I_CPU0_SB_CA<2>")
	)
	(gr_poly
		(pts
			(xy 393.014962 -285.627826) (xy 392.914886 -285.528004) (xy 392.81481 -285.627826) (xy 392.81481 -285.675578)
			(xy 393.014962 -285.675578)
		)
		(stroke
			(width 0)
			(type solid)
		)
		(fill yes)
		(layer "In2.Cu")
		(net "M_I_CPU0_SB_DQS_DP<2>")
	)
	(gr_poly
		(pts
			(xy 393.014962 -271.047718) (xy 392.914886 -270.947896) (xy 392.81481 -271.047718) (xy 392.81481 -271.09547)
			(xy 393.014962 -271.09547)
		)
		(stroke
			(width 0)
			(type solid)
		)
		(fill yes)
		(layer "In2.Cu")
		(net "M_I_CPU0_SB_DQS_DP<9>")
	)
	(gr_poly
		(pts
			(xy 393.02055 -270.644874) (xy 393.02055 -270.600424) (xy 392.820398 -270.600424) (xy 392.820398 -270.644874)
			(xy 392.920474 -270.744696)
		)
		(stroke
			(width 0)
			(type solid)
		)
		(fill yes)
		(layer "In2.Cu")
		(net "M_I_CPU0_SB_CB<7>")
	)
	(gr_poly
		(pts
			(xy 393.027408 -281.984958) (xy 393.027408 -281.93746) (xy 392.82751 -281.93746) (xy 392.82751 -281.984958)
			(xy 392.927332 -282.085034)
		)
		(stroke
			(width 0)
			(type solid)
		)
		(fill yes)
		(layer "In2.Cu")
		(net "M_I_CPU0_SB_DQS_DP<6>")
	)
	(gr_poly
		(pts
			(xy 393.027408 -277.124922) (xy 393.027408 -277.077424) (xy 392.82751 -277.077424) (xy 392.82751 -277.124922)
			(xy 392.927332 -277.224998)
		)
		(stroke
			(width 0)
			(type solid)
		)
		(fill yes)
		(layer "In2.Cu")
		(net "M_I_CPU0_SB_DQS_DP<5>")
	)
	(gr_poly
		(pts
			(xy 393.027408 -272.264886) (xy 393.027408 -272.217388) (xy 392.82751 -272.217388) (xy 392.82751 -272.264886)
			(xy 392.927332 -272.364962)
		)
		(stroke
			(width 0)
			(type solid)
		)
		(fill yes)
		(layer "In2.Cu")
		(net "M_I_CPU0_SB_DQS_DP<4>")
	)
	(gr_poly
		(pts
			(xy 393.029186 -285.224982) (xy 393.029186 -285.180532) (xy 392.829288 -285.180532) (xy 392.829288 -285.224982)
			(xy 392.929364 -285.325058)
		)
		(stroke
			(width 0)
			(type solid)
		)
		(fill yes)
		(layer "In2.Cu")
		(net "M_I_CPU0_SB_DQ<19>")
	)
	(gr_poly
		(pts
			(xy 393.029186 -283.60497) (xy 393.029186 -283.56052) (xy 392.829288 -283.56052) (xy 392.829288 -283.60497)
			(xy 392.929364 -283.705046)
		)
		(stroke
			(width 0)
			(type solid)
		)
		(fill yes)
		(layer "In2.Cu")
		(net "M_I_CPU0_SB_DQ<15>")
	)
	(gr_poly
		(pts
			(xy 393.029186 -280.364946) (xy 393.029186 -280.320496) (xy 392.829288 -280.320496) (xy 392.829288 -280.364946)
			(xy 392.929364 -280.465022)
		)
		(stroke
			(width 0)
			(type solid)
		)
		(fill yes)
		(layer "In2.Cu")
		(net "M_I_CPU0_SB_DQ<11>")
	)
	(gr_poly
		(pts
			(xy 393.029186 -278.744934) (xy 393.029186 -278.700484) (xy 392.829288 -278.700484) (xy 392.829288 -278.744934)
			(xy 392.929364 -278.84501)
		)
		(stroke
			(width 0)
			(type solid)
		)
		(fill yes)
		(layer "In2.Cu")
		(net "M_I_CPU0_SB_DQ<7>")
	)
	(gr_poly
		(pts
			(xy 393.029186 -275.50491) (xy 393.029186 -275.46046) (xy 392.829288 -275.46046) (xy 392.829288 -275.50491)
			(xy 392.929364 -275.604986)
		)
		(stroke
			(width 0)
			(type solid)
		)
		(fill yes)
		(layer "In2.Cu")
		(net "M_I_CPU0_SB_DQ<3>")
	)
	(gr_poly
		(pts
			(xy 393.029186 -273.884898) (xy 393.029186 -273.840448) (xy 392.829288 -273.840448) (xy 392.829288 -273.884898)
			(xy 392.929364 -273.984974)
		)
		(stroke
			(width 0)
			(type solid)
		)
		(fill yes)
		(layer "In2.Cu")
		(net "M_I_CPU0_SB_CB<3>")
	)
	(gr_poly
		(pts
			(xy 393.029186 -267.40485) (xy 393.029186 -267.3604) (xy 392.829288 -267.3604) (xy 392.829288 -267.40485)
			(xy 392.929364 -267.504926)
		)
		(stroke
			(width 0)
			(type solid)
		)
		(fill yes)
		(layer "In2.Cu")
		(net "M_I_CPU0_SB_RSP<0>")
	)
	(gr_poly
		(pts
			(xy 393.029186 -265.784838) (xy 393.029186 -265.740388) (xy 392.829288 -265.740388) (xy 392.829288 -265.784838)
			(xy 392.929364 -265.884914)
		)
		(stroke
			(width 0)
			(type solid)
		)
		(fill yes)
		(layer "In2.Cu")
		(net "M_I_CPU0_SB_CS_N<0>")
	)
	(gr_poly
		(pts
			(xy 393.029186 -264.164826) (xy 393.029186 -264.120376) (xy 392.829288 -264.120376) (xy 392.829288 -264.164826)
			(xy 392.929364 -264.264902)
		)
		(stroke
			(width 0)
			(type solid)
		)
		(fill yes)
		(layer "In2.Cu")
		(net "M_I_CPU0_SB_CA<5>")
	)
	(gr_poly
		(pts
			(xy 393.029186 -262.544814) (xy 393.029186 -262.500364) (xy 392.829288 -262.500364) (xy 392.829288 -262.544814)
			(xy 392.929364 -262.64489)
		)
		(stroke
			(width 0)
			(type solid)
		)
		(fill yes)
		(layer "In2.Cu")
		(net "M_I_CPU0_SB_CA<1>")
	)
	(gr_poly
		(pts
			(xy 393.033758 -294.94734) (xy 393.070334 -294.810942) (xy 392.933682 -294.774112) (xy 392.892534 -294.797988)
			(xy 392.992356 -294.971216)
		)
		(stroke
			(width 0)
			(type solid)
		)
		(fill yes)
		(layer "In2.Cu")
		(net "M_I_CPU0_SB_DQS_DN<8>")
	)
	(gr_poly
		(pts
			(xy 393.070842 -269.560548) (xy 393.034012 -269.423896) (xy 392.995658 -269.401544) (xy 392.895582 -269.574772)
			(xy 392.93419 -269.597124)
		)
		(stroke
			(width 0)
			(type solid)
		)
		(fill yes)
		(layer "In2.Cu")
		(net "M_I_CPU0_SB_CB<6>")
	)
	(gr_poly
		(pts
			(xy 393.093702 -224.695512) (xy 393.05357 -224.676716) (xy 392.920474 -224.724976) (xy 392.968988 -224.857818)
			(xy 393.00912 -224.876614)
		)
		(stroke
			(width 0)
			(type solid)
		)
		(fill yes)
		(layer "In2.Cu")
		(net "M_I_CPU0_SA_DQ<8>")
	)
	(gr_poly
		(pts
			(xy 393.094972 -223.073976) (xy 393.05484 -223.05518) (xy 392.921998 -223.10344) (xy 392.970258 -223.236536)
			(xy 393.01039 -223.255078)
		)
		(stroke
			(width 0)
			(type solid)
		)
		(fill yes)
		(layer "In2.Cu")
		(net "M_I_CPU0_SA_DQ<5>")
	)
	(gr_poly
		(pts
			(xy 393.104116 -226.315524) (xy 393.065508 -226.293172) (xy 392.92911 -226.329748) (xy 392.965686 -226.4664)
			(xy 393.00404 -226.488752)
		)
		(stroke
			(width 0)
			(type solid)
		)
		(fill yes)
		(layer "In2.Cu")
		(net "M_I_CPU0_SA_DQ<9>")
	)
	(gr_poly
		(pts
			(xy 393.106402 -229.557326) (xy 393.065254 -229.533704) (xy 392.928602 -229.57028) (xy 392.965178 -229.706932)
			(xy 393.006326 -229.730554)
		)
		(stroke
			(width 0)
			(type solid)
		)
		(fill yes)
		(layer "In2.Cu")
		(net "M_I_CPU0_SA_DQS_DN<6>")
	)
	(gr_poly
		(pts
			(xy 393.10691 -227.936298) (xy 393.065762 -227.912676) (xy 392.92911 -227.949252) (xy 392.965686 -228.08565)
			(xy 393.007088 -228.109526)
		)
		(stroke
			(width 0)
			(type solid)
		)
		(fill yes)
		(layer "In2.Cu")
		(net "M_I_CPU0_SA_DQS_DP<1>")
	)
	(gr_poly
		(pts
			(xy 393.161266 -254.405638) (xy 393.06119 -254.305816) (xy 392.961114 -254.405638) (xy 392.961114 -254.450088)
			(xy 393.161266 -254.450088)
		)
		(stroke
			(width 0)
			(type solid)
		)
		(fill yes)
		(layer "In2.Cu")
		(net "M_I_CPU0_SA_CA<4>")
	)
	(gr_poly
		(pts
			(xy 393.161266 -252.785626) (xy 393.06119 -252.685804) (xy 392.961114 -252.785626) (xy 392.961114 -252.830076)
			(xy 393.161266 -252.830076)
		)
		(stroke
			(width 0)
			(type solid)
		)
		(fill yes)
		(layer "In2.Cu")
		(net "M_I_CPU0_SA_CA<0>")
	)
	(gr_poly
		(pts
			(xy 393.161266 -247.92559) (xy 393.06119 -247.825768) (xy 392.961114 -247.92559) (xy 392.961114 -247.97004)
			(xy 393.161266 -247.97004)
		)
		(stroke
			(width 0)
			(type solid)
		)
		(fill yes)
		(layer "In2.Cu")
		(net "M_I_CPU0_SA_CB<4>")
	)
	(gr_poly
		(pts
			(xy 393.161266 -244.685566) (xy 393.06119 -244.585744) (xy 392.961114 -244.685566) (xy 392.961114 -244.730016)
			(xy 393.161266 -244.730016)
		)
		(stroke
			(width 0)
			(type solid)
		)
		(fill yes)
		(layer "In2.Cu")
		(net "M_I_CPU0_SA_CB<0>")
	)
	(gr_poly
		(pts
			(xy 393.16279 -256.02565) (xy 393.062714 -255.925828) (xy 392.962638 -256.02565) (xy 392.962638 -256.073402)
			(xy 393.16279 -256.073402)
		)
		(stroke
			(width 0)
			(type solid)
		)
		(fill yes)
		(layer "In2.Cu")
		(net "M_I_CPU0_CLK_DP<0>")
	)
	(gr_poly
		(pts
			(xy 393.16279 -246.305578) (xy 393.062714 -246.205756) (xy 392.962638 -246.305578) (xy 392.962638 -246.35333)
			(xy 393.16279 -246.35333)
		)
		(stroke
			(width 0)
			(type solid)
		)
		(fill yes)
		(layer "In2.Cu")
		(net "M_I_CPU0_SA_DQS_DP<4>")
	)
	(gr_poly
		(pts
			(xy 393.175998 -241.04219) (xy 393.175998 -240.99774) (xy 392.9761 -240.99774) (xy 392.9761 -241.04219)
			(xy 393.076176 -241.142266)
		)
		(stroke
			(width 0)
			(type solid)
		)
		(fill yes)
		(layer "In2.Cu")
		(net "M_I_CPU0_SA_DQ<27>")
	)
	(gr_poly
		(pts
			(xy 393.184888 -254.002286) (xy 393.184888 -253.957836) (xy 392.984736 -253.957836) (xy 392.984736 -254.002286)
			(xy 393.084812 -254.102362)
		)
		(stroke
			(width 0)
			(type solid)
		)
		(fill yes)
		(layer "In2.Cu")
		(net "M_I_CPU0_SA_CA<3>")
	)
	(gr_poly
		(pts
			(xy 393.184888 -250.762262) (xy 393.184888 -250.717812) (xy 392.984736 -250.717812) (xy 392.984736 -250.762262)
			(xy 393.084812 -250.862338)
		)
		(stroke
			(width 0)
			(type solid)
		)
		(fill yes)
		(layer "In2.Cu")
		(net "M_I_CPU0_RESET_N")
	)
	(gr_poly
		(pts
			(xy 393.184888 -245.902226) (xy 393.184888 -245.857776) (xy 392.984736 -245.857776) (xy 392.984736 -245.902226)
			(xy 393.084812 -246.002302)
		)
		(stroke
			(width 0)
			(type solid)
		)
		(fill yes)
		(layer "In2.Cu")
		(net "M_I_CPU0_SA_CB<3>")
	)
	(gr_poly
		(pts
			(xy 393.184888 -244.282214) (xy 393.184888 -244.237764) (xy 392.984736 -244.237764) (xy 392.984736 -244.282214)
			(xy 393.084812 -244.38229)
		)
		(stroke
			(width 0)
			(type solid)
		)
		(fill yes)
		(layer "In2.Cu")
		(net "M_I_CPU0_SA_DQ<31>")
	)
	(gr_poly
		(pts
			(xy 393.197334 -247.522492) (xy 393.197334 -247.474994) (xy 392.997182 -247.474994) (xy 392.997182 -247.522492)
			(xy 393.097258 -247.622568)
		)
		(stroke
			(width 0)
			(type solid)
		)
		(fill yes)
		(layer "In2.Cu")
		(net "M_I_CPU0_SA_DQS_DP<9>")
	)
	(gr_poly
		(pts
			(xy 393.198858 -242.662456) (xy 393.198858 -242.614958) (xy 392.99896 -242.614958) (xy 392.99896 -242.662456)
			(xy 393.098782 -242.762532)
		)
		(stroke
			(width 0)
			(type solid)
		)
		(fill yes)
		(layer "In2.Cu")
		(net "M_I_CPU0_SA_DQS_DP<8>")
	)
	(gr_poly
		(pts
			(xy 393.240006 -230.240586) (xy 393.20343 -230.103934) (xy 393.162282 -230.080058) (xy 393.062206 -230.253286)
			(xy 393.103354 -230.277162)
		)
		(stroke
			(width 0)
			(type solid)
		)
		(fill yes)
		(layer "In2.Cu")
		(net "M_I_CPU0_SA_DQS_DP<6>")
	)
	(gr_poly
		(pts
			(xy 393.240006 -223.76003) (xy 393.20343 -223.623378) (xy 393.164822 -223.60128) (xy 393.064746 -223.774508)
			(xy 393.103354 -223.796606)
		)
		(stroke
			(width 0)
			(type solid)
		)
		(fill yes)
		(layer "In2.Cu")
		(net "M_I_CPU0_SA_DQ<7>")
	)
	(gr_poly
		(pts
			(xy 393.240768 -228.619304) (xy 393.204192 -228.482906) (xy 393.16279 -228.45903) (xy 393.062968 -228.632258)
			(xy 393.104116 -228.656134)
		)
		(stroke
			(width 0)
			(type solid)
		)
		(fill yes)
		(layer "In2.Cu")
		(net "M_I_CPU0_SA_DQS_DN<1>")
	)
	(gr_poly
		(pts
			(xy 393.241022 -226.998784) (xy 393.204192 -226.862132) (xy 393.165838 -226.83978) (xy 393.065762 -227.013008)
			(xy 393.10437 -227.03536)
		)
		(stroke
			(width 0)
			(type solid)
		)
		(fill yes)
		(layer "In2.Cu")
		(net "M_I_CPU0_SA_DQ<11>")
	)
	(gr_poly
		(pts
			(xy 393.3952 -269.684754) (xy 393.354814 -269.665958) (xy 393.221972 -269.714472) (xy 393.270486 -269.847314)
			(xy 393.310618 -269.86611)
		)
		(stroke
			(width 0)
			(type solid)
		)
		(fill yes)
		(layer "In2.Cu")
		(net "M_I_CPU0_SB_CB<5>")
	)
	(gr_poly
		(pts
			(xy 393.40663 -294.683942) (xy 393.306808 -294.510714) (xy 393.265406 -294.53459) (xy 393.22883 -294.670988)
			(xy 393.365482 -294.707564)
		)
		(stroke
			(width 0)
			(type solid)
		)
		(fill yes)
		(layer "In2.Cu")
		(net "M_I_CPU0_SB_DQS_DN<3>")
	)
	(gr_poly
		(pts
			(xy 393.484608 -271.454372) (xy 393.484608 -271.40662) (xy 393.28471 -271.40662) (xy 393.28471 -271.454372)
			(xy 393.384532 -271.554448)
		)
		(stroke
			(width 0)
			(type solid)
		)
		(fill yes)
		(layer "In2.Cu")
		(net "M_I_CPU0_SB_DQS_DN<9>")
	)
	(gr_poly
		(pts
			(xy 393.497308 -276.314408) (xy 393.497308 -276.26691) (xy 393.29741 -276.26691) (xy 393.29741 -276.314408)
			(xy 393.397232 -276.414484)
		)
		(stroke
			(width 0)
			(type solid)
		)
		(fill yes)
		(layer "In2.Cu")
		(net "M_I_CPU0_SB_DQS_DN<0>")
	)
	(gr_poly
		(pts
			(xy 393.503912 -294.137334) (xy 393.540488 -294.000936) (xy 393.403836 -293.96436) (xy 393.362688 -293.987982)
			(xy 393.46251 -294.16121)
		)
		(stroke
			(width 0)
			(type solid)
		)
		(fill yes)
		(layer "In2.Cu")
		(net "M_I_CPU0_SB_DQS_DP<3>")
	)
	(gr_poly
		(pts
			(xy 393.548108 -270.357092) (xy 393.499848 -270.223996) (xy 393.459462 -270.2052) (xy 393.37488 -270.386556)
			(xy 393.415266 -270.405352)
		)
		(stroke
			(width 0)
			(type solid)
		)
		(fill yes)
		(layer "In2.Cu")
		(net "M_I_CPU0_SB_CB<7>")
	)
	(gr_poly
		(pts
			(xy 393.574016 -223.885506) (xy 393.535408 -223.863154) (xy 393.39901 -223.89973) (xy 393.435586 -224.036382)
			(xy 393.47394 -224.058734)
		)
		(stroke
			(width 0)
			(type solid)
		)
		(fill yes)
		(layer "In2.Cu")
		(net "M_I_CPU0_SA_DQ<8>")
	)
	(gr_poly
		(pts
			(xy 393.57681 -228.746304) (xy 393.535662 -228.722428) (xy 393.39901 -228.759258) (xy 393.435586 -228.895656)
			(xy 393.476988 -228.919532)
		)
		(stroke
			(width 0)
			(type solid)
		)
		(fill yes)
		(layer "In2.Cu")
		(net "M_I_CPU0_SA_DQS_DN<6>")
	)
	(gr_poly
		(pts
			(xy 393.577572 -227.124768) (xy 393.53617 -227.100892) (xy 393.399518 -227.137468) (xy 393.436094 -227.27412)
			(xy 393.477496 -227.297996)
		)
		(stroke
			(width 0)
			(type solid)
		)
		(fill yes)
		(layer "In2.Cu")
		(net "M_I_CPU0_SA_DQS_DP<1>")
	)
	(gr_poly
		(pts
			(xy 393.632436 -251.970794) (xy 393.53236 -251.870972) (xy 393.432538 -251.970794) (xy 393.432538 -252.015244)
			(xy 393.632436 -252.015244)
		)
		(stroke
			(width 0)
			(type solid)
		)
		(fill yes)
		(layer "In2.Cu")
		(net "M_I_CPU0_SA_CS_N<1>")
	)
	(gr_poly
		(pts
			(xy 393.646914 -247.115584) (xy 393.547092 -247.015762) (xy 393.447016 -247.115584) (xy 393.447016 -247.163336)
			(xy 393.646914 -247.163336)
		)
		(stroke
			(width 0)
			(type solid)
		)
		(fill yes)
		(layer "In2.Cu")
		(net "M_I_CPU0_SA_DQS_DN<9>")
	)
	(gr_poly
		(pts
			(xy 393.655042 -253.59614) (xy 393.554966 -253.496064) (xy 393.45489 -253.59614) (xy 393.45489 -253.64059)
			(xy 393.655042 -253.64059)
		)
		(stroke
			(width 0)
			(type solid)
		)
		(fill yes)
		(layer "In2.Cu")
		(net "M_I_CPU0_SA_CA<2>")
	)
	(gr_poly
		(pts
			(xy 393.655042 -245.49608) (xy 393.554966 -245.396004) (xy 393.45489 -245.49608) (xy 393.45489 -245.54053)
			(xy 393.655042 -245.54053)
		)
		(stroke
			(width 0)
			(type solid)
		)
		(fill yes)
		(layer "In2.Cu")
		(net "M_I_CPU0_SA_CB<1>")
	)
	(gr_poly
		(pts
			(xy 393.708636 -227.812092) (xy 393.67206 -227.67544) (xy 393.630658 -227.651818) (xy 393.530836 -227.825046)
			(xy 393.571984 -227.848668)
		)
		(stroke
			(width 0)
			(type solid)
		)
		(fill yes)
		(layer "In2.Cu")
		(net "M_I_CPU0_SA_DQS_DN<1>")
	)
	(gr_poly
		(pts
			(xy 393.711176 -229.42804) (xy 393.6746 -229.291388) (xy 393.633452 -229.267766) (xy 393.533376 -229.440994)
			(xy 393.574778 -229.464616)
		)
		(stroke
			(width 0)
			(type solid)
		)
		(fill yes)
		(layer "In2.Cu")
		(net "M_I_CPU0_SA_DQS_DP<6>")
	)
	(gr_poly
		(pts
			(xy 393.718288 -224.554542) (xy 393.669774 -224.4217) (xy 393.629642 -224.402904) (xy 393.54506 -224.584006)
			(xy 393.585446 -224.602802)
		)
		(stroke
			(width 0)
			(type solid)
		)
		(fill yes)
		(layer "In2.Cu")
		(net "M_I_CPU0_SA_DQ<10>")
	)
	(gr_poly
		(pts
			(xy 393.974066 -294.948356) (xy 394.010642 -294.811704) (xy 393.87399 -294.775128) (xy 393.832842 -294.79875)
			(xy 393.932664 -294.971978)
		)
		(stroke
			(width 0)
			(type solid)
		)
		(fill yes)
		(layer "In2.Cu")
		(net "M_I_CPU0_SB_DQS_DP<3>")
	)
	(gr_poly
		(pts
			(xy 394.046964 -223.069404) (xy 394.00861 -223.047306) (xy 393.871958 -223.083882) (xy 393.908534 -223.220534)
			(xy 393.946888 -223.242632)
		)
		(stroke
			(width 0)
			(type solid)
		)
		(fill yes)
		(layer "In2.Cu")
		(net "M_I_CPU0_SA_DQ<8>")
	)
	(gr_poly
		(pts
			(xy 394.180822 -223.75876) (xy 394.143992 -223.622108) (xy 394.105638 -223.599756) (xy 394.005562 -223.772984)
			(xy 394.04417 -223.795336)
		)
		(stroke
			(width 0)
			(type solid)
		)
		(fill yes)
		(layer "In2.Cu")
		(net "M_I_CPU0_SA_DQ<10>")
	)
	(gr_poly
		(pts
			(xy 77.964284 -226.20986) (xy 77.864208 -226.036632) (xy 77.825854 -226.058984) (xy 77.789278 -226.195382)
			(xy 77.789278 -226.195636) (xy 77.925676 -226.232212)
		)
		(stroke
			(width 0)
			(type solid)
		)
		(fill yes)
		(layer "In2.Cu")
		(net "M_C_CPU1_SA_DQ<11>")
	)
	(gr_poly
		(pts
			(xy 78.059026 -225.65487) (xy 78.095602 -225.518472) (xy 78.095602 -225.518218) (xy 77.95895 -225.481642)
			(xy 77.920342 -225.503994) (xy 78.020418 -225.677222)
		)
		(stroke
			(width 0)
			(type solid)
		)
		(fill yes)
		(layer "In2.Cu")
		(net "M_C_CPU1_SA_DQ<9>")
	)
	(gr_poly
		(pts
			(xy 78.430628 -227.014024) (xy 78.330552 -226.840796) (xy 78.292198 -226.863148) (xy 78.255368 -226.999546)
			(xy 78.255368 -226.9998) (xy 78.39202 -227.036376)
		)
		(stroke
			(width 0)
			(type solid)
		)
		(fill yes)
		(layer "In2.Cu")
		(net "M_C_CPU1_SA_DQ<11>")
	)
	(gr_poly
		(pts
			(xy 79.261462 -269.427706) (xy 79.16164 -269.327884) (xy 79.161386 -269.327884) (xy 79.061564 -269.427706)
			(xy 79.061564 -269.472156) (xy 79.261462 -269.472156)
		)
		(stroke
			(width 0)
			(type solid)
		)
		(fill yes)
		(layer "In2.Cu")
		(net "M_C_CPU1_SB_CB<4>")
	)
	(gr_poly
		(pts
			(xy 79.371698 -228.63556) (xy 79.271622 -228.462332) (xy 79.233014 -228.484684) (xy 79.196438 -228.621082)
			(xy 79.196438 -228.621336) (xy 79.33309 -228.657912)
		)
		(stroke
			(width 0)
			(type solid)
		)
		(fill yes)
		(layer "In2.Cu")
		(net "M_C_CPU1_SA_DQ<11>")
	)
	(gr_poly
		(pts
			(xy 79.73949 -286.03448) (xy 79.73949 -285.986728) (xy 79.539592 -285.986728) (xy 79.539592 -286.03448)
			(xy 79.639414 -286.134556) (xy 79.639668 -286.134556)
		)
		(stroke
			(width 0)
			(type solid)
		)
		(fill yes)
		(layer "In2.Cu")
		(net "M_C_CPU1_SB_DQS_DN<2>")
	)
	(gr_poly
		(pts
			(xy 79.73949 -271.454372) (xy 79.73949 -271.40662) (xy 79.539592 -271.40662) (xy 79.539592 -271.454372)
			(xy 79.639414 -271.554448) (xy 79.639668 -271.554448)
		)
		(stroke
			(width 0)
			(type solid)
		)
		(fill yes)
		(layer "In2.Cu")
		(net "M_C_CPU1_SB_DQS_DN<9>")
	)
	(gr_poly
		(pts
			(xy 80.235552 -290.488116) (xy 80.13573 -290.38804) (xy 80.135476 -290.38804) (xy 80.035654 -290.488116)
			(xy 80.035654 -290.535868) (xy 80.235552 -290.535868)
		)
		(stroke
			(width 0)
			(type solid)
		)
		(fill yes)
		(layer "In2.Cu")
		(net "M_C_CPU1_SB_DQS_DP<3>")
	)
	(gr_poly
		(pts
			(xy 80.235552 -285.628334) (xy 80.13573 -285.528258) (xy 80.135476 -285.528258) (xy 80.035654 -285.628334)
			(xy 80.035654 -285.676086) (xy 80.235552 -285.676086)
		)
		(stroke
			(width 0)
			(type solid)
		)
		(fill yes)
		(layer "In2.Cu")
		(net "M_C_CPU1_SB_DQS_DP<2>")
	)
	(gr_poly
		(pts
			(xy 80.235552 -280.768298) (xy 80.13573 -280.668222) (xy 80.135476 -280.668222) (xy 80.035654 -280.768298)
			(xy 80.035654 -280.81605) (xy 80.235552 -280.81605)
		)
		(stroke
			(width 0)
			(type solid)
		)
		(fill yes)
		(layer "In2.Cu")
		(net "M_C_CPU1_SB_DQS_DP<1>")
	)
	(gr_poly
		(pts
			(xy 80.235552 -271.048226) (xy 80.13573 -270.94815) (xy 80.135476 -270.94815) (xy 80.035654 -271.048226)
			(xy 80.035654 -271.095978) (xy 80.235552 -271.095978)
		)
		(stroke
			(width 0)
			(type solid)
		)
		(fill yes)
		(layer "In2.Cu")
		(net "M_C_CPU1_SB_DQS_DP<9>")
	)
	(gr_poly
		(pts
			(xy 142.81785 -223.885252) (xy 142.776448 -223.861376) (xy 142.64005 -223.897952) (xy 142.639796 -223.897952)
			(xy 142.676626 -224.034604) (xy 142.717774 -224.05848)
		)
		(stroke
			(width 0)
			(type solid)
		)
		(fill yes)
		(layer "In2.Cu")
		(net "M_I_CPU1_SA_DQS_DN<5>")
	)
	(gr_poly
		(pts
			(xy 142.949422 -224.571052) (xy 142.949676 -224.571052) (xy 142.912846 -224.4344) (xy 142.871698 -224.410524)
			(xy 142.771622 -224.583752) (xy 142.813024 -224.607628)
		)
		(stroke
			(width 0)
			(type solid)
		)
		(fill yes)
		(layer "In2.Cu")
		(net "M_I_CPU1_SA_DQS_DP<5>")
	)
	(gr_poly
		(pts
			(xy 143.820134 -246.712486) (xy 143.820134 -246.664734) (xy 143.620236 -246.664734) (xy 143.620236 -246.712486)
			(xy 143.720058 -246.812562) (xy 143.720312 -246.812562)
		)
		(stroke
			(width 0)
			(type solid)
		)
		(fill yes)
		(layer "In2.Cu")
		(net "M_I_CPU1_SA_DQS_DN<4>")
	)
	(gr_poly
		(pts
			(xy 144.116806 -288.464244) (xy 144.116806 -288.419794) (xy 143.916908 -288.419794) (xy 143.916908 -288.464244)
			(xy 144.01673 -288.56432) (xy 144.016984 -288.56432)
		)
		(stroke
			(width 0)
			(type solid)
		)
		(fill yes)
		(layer "In2.Cu")
		(net "M_I_CPU1_SB_DQ<23>")
	)
	(gr_poly
		(pts
			(xy 144.290034 -256.026412) (xy 144.190212 -255.926336) (xy 144.189958 -255.926336) (xy 144.090136 -256.026412)
			(xy 144.090136 -256.074164) (xy 144.290034 -256.074164)
		)
		(stroke
			(width 0)
			(type solid)
		)
		(fill yes)
		(layer "In2.Cu")
		(net "M_I_CPU1_CLK_DP<0>")
	)
	(gr_poly
		(pts
			(xy 144.316196 -246.30634) (xy 144.216374 -246.206264) (xy 144.21612 -246.206264) (xy 144.116298 -246.30634)
			(xy 144.116298 -246.354092) (xy 144.316196 -246.354092)
		)
		(stroke
			(width 0)
			(type solid)
		)
		(fill yes)
		(layer "In2.Cu")
		(net "M_I_CPU1_SA_DQS_DP<4>")
	)
	(gr_poly
		(pts
			(xy 144.527524 -293.064692) (xy 144.427448 -292.891464) (xy 144.3863 -292.91534) (xy 144.34947 -293.051992)
			(xy 144.349724 -293.051992) (xy 144.486122 -293.088568)
		)
		(stroke
			(width 0)
			(type solid)
		)
		(fill yes)
		(layer "In2.Cu")
		(net "M_I_CPU1_SB_DQS_DN<3>")
	)
	(gr_poly
		(pts
			(xy 145.093436 -293.327074) (xy 145.130266 -293.190422) (xy 145.130012 -293.190422) (xy 144.993614 -293.153846)
			(xy 144.952212 -293.177722) (xy 145.052288 -293.35095)
		)
		(stroke
			(width 0)
			(type solid)
		)
		(fill yes)
		(layer "In2.Cu")
		(net "M_I_CPU1_SB_DQS_DP<3>")
	)
	(gr_poly
		(pts
			(xy 145.60804 -270.357346) (xy 145.60804 -270.357092) (xy 145.55978 -270.22425) (xy 145.519394 -270.205454)
			(xy 145.434812 -270.38681) (xy 145.475198 -270.405606)
		)
		(stroke
			(width 0)
			(type solid)
		)
		(fill yes)
		(layer "In2.Cu")
		(net "M_I_CPU1_SB_CB<7>")
	)
	(gr_poly
		(pts
			(xy 326.371966 -225.395282) (xy 326.27189 -225.222054) (xy 326.233282 -225.244406) (xy 326.196706 -225.380804)
			(xy 326.196706 -225.381058) (xy 326.333358 -225.417634)
		)
		(stroke
			(width 0)
			(type solid)
		)
		(fill yes)
		(layer "In2.Cu")
		(net "M_C_CPU0_SA_DQ<10>")
	)
	(gr_poly
		(pts
			(xy 326.94118 -225.657156) (xy 326.977756 -225.520758) (xy 326.977756 -225.520504) (xy 326.841358 -225.483928)
			(xy 326.80275 -225.50628) (xy 326.902826 -225.679508)
		)
		(stroke
			(width 0)
			(type solid)
		)
		(fill yes)
		(layer "In2.Cu")
		(net "M_C_CPU0_SA_DQ<8>")
	)
	(gr_poly
		(pts
			(xy 327.20153 -269.427452) (xy 327.101708 -269.32763) (xy 327.101454 -269.32763) (xy 327.001632 -269.427452)
			(xy 327.001632 -269.471902) (xy 327.20153 -269.471902)
		)
		(stroke
			(width 0)
			(type solid)
		)
		(fill yes)
		(layer "In2.Cu")
		(net "M_C_CPU0_SB_CB<4>")
	)
	(gr_poly
		(pts
			(xy 327.679558 -286.034226) (xy 327.679558 -285.986474) (xy 327.47966 -285.986474) (xy 327.47966 -286.034226)
			(xy 327.579482 -286.134302) (xy 327.579736 -286.134302)
		)
		(stroke
			(width 0)
			(type solid)
		)
		(fill yes)
		(layer "In2.Cu")
		(net "M_C_CPU0_SB_DQS_DN<2>")
	)
	(gr_poly
		(pts
			(xy 327.679558 -271.454118) (xy 327.679558 -271.406366) (xy 327.47966 -271.406366) (xy 327.47966 -271.454118)
			(xy 327.579482 -271.554194) (xy 327.579736 -271.554194)
		)
		(stroke
			(width 0)
			(type solid)
		)
		(fill yes)
		(layer "In2.Cu")
		(net "M_C_CPU0_SB_DQS_DN<9>")
	)
	(gr_poly
		(pts
			(xy 327.879456 -228.89464) (xy 327.916032 -228.758242) (xy 327.916032 -228.757988) (xy 327.77938 -228.721412)
			(xy 327.740772 -228.743764) (xy 327.840848 -228.916992)
		)
		(stroke
			(width 0)
			(type solid)
		)
		(fill yes)
		(layer "In2.Cu")
		(net "M_C_CPU0_SA_DQ<9>")
	)
	(gr_poly
		(pts
			(xy 328.17562 -290.487862) (xy 328.075798 -290.387786) (xy 328.075544 -290.387786) (xy 327.975722 -290.487862)
			(xy 327.975722 -290.535614) (xy 328.17562 -290.535614)
		)
		(stroke
			(width 0)
			(type solid)
		)
		(fill yes)
		(layer "In2.Cu")
		(net "M_C_CPU0_SB_DQS_DP<3>")
	)
	(gr_poly
		(pts
			(xy 328.17562 -285.62808) (xy 328.075798 -285.528004) (xy 328.075544 -285.528004) (xy 327.975722 -285.62808)
			(xy 327.975722 -285.675832) (xy 328.17562 -285.675832)
		)
		(stroke
			(width 0)
			(type solid)
		)
		(fill yes)
		(layer "In2.Cu")
		(net "M_C_CPU0_SB_DQS_DP<2>")
	)
	(gr_poly
		(pts
			(xy 328.17562 -280.768044) (xy 328.075798 -280.667968) (xy 328.075544 -280.667968) (xy 327.975722 -280.768044)
			(xy 327.975722 -280.815796) (xy 328.17562 -280.815796)
		)
		(stroke
			(width 0)
			(type solid)
		)
		(fill yes)
		(layer "In2.Cu")
		(net "M_C_CPU0_SB_DQS_DP<1>")
	)
	(gr_poly
		(pts
			(xy 328.17562 -271.047972) (xy 328.075798 -270.947896) (xy 328.075544 -270.947896) (xy 327.975722 -271.047972)
			(xy 327.975722 -271.095724) (xy 328.17562 -271.095724)
		)
		(stroke
			(width 0)
			(type solid)
		)
		(fill yes)
		(layer "In2.Cu")
		(net "M_C_CPU0_SB_DQS_DP<9>")
	)
	(gr_poly
		(pts
			(xy 390.757918 -223.884998) (xy 390.716516 -223.861122) (xy 390.580118 -223.897952) (xy 390.579864 -223.897952)
			(xy 390.616694 -224.03435) (xy 390.657842 -224.058226)
		)
		(stroke
			(width 0)
			(type solid)
		)
		(fill yes)
		(layer "In2.Cu")
		(net "M_I_CPU0_SA_DQS_DN<5>")
	)
	(gr_poly
		(pts
			(xy 390.88949 -224.570544) (xy 390.889744 -224.570544) (xy 390.852914 -224.434146) (xy 390.811766 -224.41027)
			(xy 390.71169 -224.583498) (xy 390.753092 -224.607374)
		)
		(stroke
			(width 0)
			(type solid)
		)
		(fill yes)
		(layer "In2.Cu")
		(net "M_I_CPU0_SA_DQS_DP<5>")
	)
	(gr_poly
		(pts
			(xy 391.760202 -246.712232) (xy 391.760202 -246.66448) (xy 391.560304 -246.66448) (xy 391.560304 -246.712232)
			(xy 391.660126 -246.812308) (xy 391.66038 -246.812308)
		)
		(stroke
			(width 0)
			(type solid)
		)
		(fill yes)
		(layer "In2.Cu")
		(net "M_I_CPU0_SA_DQS_DN<4>")
	)
	(gr_poly
		(pts
			(xy 392.056874 -288.46399) (xy 392.056874 -288.41954) (xy 391.856976 -288.41954) (xy 391.856976 -288.46399)
			(xy 391.956798 -288.564066) (xy 391.957052 -288.564066)
		)
		(stroke
			(width 0)
			(type solid)
		)
		(fill yes)
		(layer "In2.Cu")
		(net "M_I_CPU0_SB_DQ<23>")
	)
	(gr_poly
		(pts
			(xy 392.230102 -256.026158) (xy 392.13028 -255.926082) (xy 392.130026 -255.926082) (xy 392.030204 -256.026158)
			(xy 392.030204 -256.07391) (xy 392.230102 -256.07391)
		)
		(stroke
			(width 0)
			(type solid)
		)
		(fill yes)
		(layer "In2.Cu")
		(net "M_I_CPU0_CLK_DP<0>")
	)
	(gr_poly
		(pts
			(xy 392.256264 -246.306086) (xy 392.156442 -246.20601) (xy 392.156188 -246.20601) (xy 392.056366 -246.306086)
			(xy 392.056366 -246.353838) (xy 392.256264 -246.353838)
		)
		(stroke
			(width 0)
			(type solid)
		)
		(fill yes)
		(layer "In2.Cu")
		(net "M_I_CPU0_SA_DQS_DP<4>")
	)
	(gr_poly
		(pts
			(xy 392.467592 -293.064438) (xy 392.367516 -292.89121) (xy 392.326368 -292.915086) (xy 392.289538 -293.051738)
			(xy 392.289792 -293.051738) (xy 392.42619 -293.088314)
		)
		(stroke
			(width 0)
			(type solid)
		)
		(fill yes)
		(layer "In2.Cu")
		(net "M_I_CPU0_SB_DQS_DN<3>")
	)
	(gr_poly
		(pts
			(xy 392.536934 -281.174698) (xy 392.536934 -281.126946) (xy 392.337036 -281.126946) (xy 392.337036 -281.174698)
			(xy 392.436858 -281.27452) (xy 392.437112 -281.27452)
		)
		(stroke
			(width 0)
			(type solid)
		)
		(fill yes)
		(layer "In2.Cu")
		(net "M_I_CPU0_SB_DQS_DN<1>")
	)
	(gr_poly
		(pts
			(xy 392.536934 -276.314662) (xy 392.536934 -276.26691) (xy 392.337036 -276.26691) (xy 392.337036 -276.314662)
			(xy 392.436858 -276.414484) (xy 392.437112 -276.414484)
		)
		(stroke
			(width 0)
			(type solid)
		)
		(fill yes)
		(layer "In2.Cu")
		(net "M_I_CPU0_SB_DQS_DN<0>")
	)
	(gr_poly
		(pts
			(xy 392.536934 -263.354312) (xy 392.536934 -263.309862) (xy 392.337036 -263.309862) (xy 392.337036 -263.354312)
			(xy 392.436858 -263.454388) (xy 392.437112 -263.454388)
		)
		(stroke
			(width 0)
			(type solid)
		)
		(fill yes)
		(layer "In2.Cu")
		(net "M_I_CPU0_SB_CA<3>")
	)
	(gr_poly
		(pts
			(xy 393.006834 -280.76779) (xy 392.907012 -280.667968) (xy 392.906758 -280.667968) (xy 392.806936 -280.76779)
			(xy 392.806936 -280.815542) (xy 393.006834 -280.815542)
		)
		(stroke
			(width 0)
			(type solid)
		)
		(fill yes)
		(layer "In2.Cu")
		(net "M_I_CPU0_SB_DQS_DP<1>")
	)
	(gr_poly
		(pts
			(xy 393.006834 -275.907754) (xy 392.907012 -275.807932) (xy 392.906758 -275.807932) (xy 392.806936 -275.907754)
			(xy 392.806936 -275.955506) (xy 393.006834 -275.955506)
		)
		(stroke
			(width 0)
			(type solid)
		)
		(fill yes)
		(layer "In2.Cu")
		(net "M_I_CPU0_SB_DQS_DP<0>")
	)
	(gr_poly
		(pts
			(xy 393.033504 -293.32682) (xy 393.070334 -293.190168) (xy 393.07008 -293.190168) (xy 392.933682 -293.153592)
			(xy 392.89228 -293.177468) (xy 392.992356 -293.350696)
		)
		(stroke
			(width 0)
			(type solid)
		)
		(fill yes)
		(layer "In2.Cu")
		(net "M_I_CPU0_SB_DQS_DP<3>")
	)
	(gr_poly
		(pts
			(xy 393.248896 -225.364802) (xy 393.248896 -225.364548) (xy 393.200382 -225.231706) (xy 393.16025 -225.21291)
			(xy 393.075668 -225.394266) (xy 393.116054 -225.413062)
		)
		(stroke
			(width 0)
			(type solid)
		)
		(fill yes)
		(layer "In2.Cu")
		(net "M_I_CPU0_SA_DQ<10>")
	)
	(gr_poly
		(pts
			(xy 125.9078 -30.366462) (xy 125.9078 -26.797) (xy 125.7808 -26.67) (xy 123.685046 -26.67) (xy 123.079764 -27.275282)
			(xy 123.079764 -30.34919) (xy 123.1646 -30.434026) (xy 125.840236 -30.434026)
		)
		(stroke
			(width 0)
			(type solid)
		)
		(fill yes)
		(layer "In2.Cu")
		(net "GND")
	)
	(gr_poly
		(pts
			(xy 404.143972 -318.199008) (xy 404.143972 -316.039246) (xy 403.091142 -314.986416) (xy 394.941552 -314.986416)
			(xy 394.802106 -315.125862) (xy 394.802106 -317.75654) (xy 395.678406 -318.63284) (xy 403.71014 -318.63284)
		)
		(stroke
			(width 0)
			(type solid)
		)
		(fill yes)
		(layer "In2.Cu")
		(net "GND")
	)
	(gr_poly
		(pts
			(xy 8.851646 -101.886258) (xy 8.851646 -97.412556) (xy 8.706104 -97.267014) (xy 5.948934 -97.267014)
			(xy 5.494782 -97.721166) (xy 5.36956 -97.846388) (xy 5.130038 -98.08591) (xy 5.130038 -101.852984)
			(xy 5.394198 -102.117144) (xy 8.62076 -102.117144)
		)
		(stroke
			(width 0)
			(type solid)
		)
		(fill yes)
		(layer "In2.Cu")
		(net "GND")
	)
	(gr_poly
		(pts
			(xy 32.7152 -366.31753) (xy 32.7152 -362.1024) (xy 32.7152 -361.8992) (xy 32.6898 -361.8738) (xy 28.2956 -361.8738)
			(xy 28.245308 -361.924092) (xy 28.245308 -362.086144) (xy 28.245308 -366.318292) (xy 28.2702 -366.34293)
			(xy 32.6898 -366.34293)
		)
		(stroke
			(width 0)
			(type solid)
		)
		(fill yes)
		(layer "In2.Cu")
		(net "GND")
	)
	(gr_poly
		(pts
			(xy 312.3692 -362.88853) (xy 312.3692 -358.6734) (xy 312.3692 -358.4702) (xy 312.3438 -358.4448)
			(xy 307.9496 -358.4448) (xy 307.899308 -358.495092) (xy 307.899308 -358.657144) (xy 307.899308 -362.889292)
			(xy 307.9242 -362.91393) (xy 312.3438 -362.91393)
		)
		(stroke
			(width 0)
			(type solid)
		)
		(fill yes)
		(layer "In2.Cu")
		(net "GND")
	)
	(gr_poly
		(pts
			(xy 441.045092 -43.578018) (xy 441.045092 -43.451018) (xy 441.045092 -38.853618) (xy 440.918092 -38.726618)
			(xy 434.288692 -38.726618) (xy 433.780692 -38.726618) (xy 433.628292 -38.879018) (xy 433.628292 -43.001946)
			(xy 433.628292 -43.618658) (xy 433.780692 -43.771058) (xy 438.893458 -43.771058) (xy 440.852052 -43.771058)
		)
		(stroke
			(width 0)
			(type solid)
		)
		(fill yes)
		(layer "In2.Cu")
		(net "P12V_AUX")
	)
	(gr_poly
		(pts
			(xy 155.926282 -319.847468) (xy 155.926282 -316.880748) (xy 155.693364 -316.64783) (xy 151.944832 -316.64783)
			(xy 151.40559 -316.108588) (xy 151.40559 -315.483494) (xy 151.140414 -315.218318) (xy 147.148804 -315.218318)
			(xy 147.023582 -315.34354) (xy 146.703796 -315.663326) (xy 146.575272 -315.79185) (xy 146.575272 -318.34455)
			(xy 146.703796 -318.473074) (xy 147.209256 -318.978534) (xy 147.291806 -319.061084) (xy 150.393654 -319.061084)
			(xy 151.29002 -319.95745) (xy 151.382476 -319.95745) (xy 151.549608 -319.95745) (xy 155.8163 -319.95745)
		)
		(stroke
			(width 0)
			(type solid)
		)
		(fill yes)
		(layer "In2.Cu")
		(net "GND")
	)
	(gr_poly
		(pts
			(arc
				(start 61.1251 -410.030168)
				(mid 60.919868 -410.030168)
				(end 61.1251 -410.030168)
			)
		)
		(stroke
			(width 0)
			(type solid)
		)
		(fill yes)
		(layer "In2.Cu")
		(net "GND")
	)
	(gr_poly
		(pts
			(arc
				(start 58.521854 -412.570168)
				(mid 58.290714 -412.570168)
				(end 58.521854 -412.570168)
			)
		)
		(stroke
			(width 0)
			(type solid)
		)
		(fill yes)
		(layer "In2.Cu")
		(net "GND")
	)
	(gr_poly
		(pts
			(arc
				(start 59.606688 -412.570168)
				(mid 59.36996 -412.570168)
				(end 59.606688 -412.570168)
			)
		)
		(stroke
			(width 0)
			(type solid)
		)
		(fill yes)
		(layer "In2.Cu")
		(net "GND")
	)
	(gr_poly
		(pts
			(arc
				(start 71.945246 -410.664152)
				(mid 71.714106 -410.664152)
				(end 71.945246 -410.664152)
			)
		)
		(stroke
			(width 0)
			(type solid)
		)
		(fill yes)
		(layer "In2.Cu")
		(net "GND")
	)
	(gr_poly
		(pts
			(arc
				(start 73.749662 -410.664152)
				(mid 73.518522 -410.664152)
				(end 73.749662 -410.664152)
			)
		)
		(stroke
			(width 0)
			(type solid)
		)
		(fill yes)
		(layer "In2.Cu")
		(net "GND")
	)
	(gr_poly
		(pts
			(arc
				(start 75.008486 -410.664152)
				(mid 74.777346 -410.664152)
				(end 75.008486 -410.664152)
			)
		)
		(stroke
			(width 0)
			(type solid)
		)
		(fill yes)
		(layer "In2.Cu")
		(net "GND")
	)
	(gr_poly
		(pts
			(arc
				(start 76.812902 -410.664152)
				(mid 76.581762 -410.664152)
				(end 76.812902 -410.664152)
			)
		)
		(stroke
			(width 0)
			(type solid)
		)
		(fill yes)
		(layer "In2.Cu")
		(net "GND")
	)
	(gr_poly
		(pts
			(arc
				(start 78.071726 -410.664152)
				(mid 77.840586 -410.664152)
				(end 78.071726 -410.664152)
			)
		)
		(stroke
			(width 0)
			(type solid)
		)
		(fill yes)
		(layer "In2.Cu")
		(net "GND")
	)
	(gr_poly
		(pts
			(arc
				(start 79.876142 -410.664152)
				(mid 79.645002 -410.664152)
				(end 79.876142 -410.664152)
			)
		)
		(stroke
			(width 0)
			(type solid)
		)
		(fill yes)
		(layer "In2.Cu")
		(net "GND")
	)
	(gr_poly
		(pts
			(arc
				(start 81.134966 -410.664152)
				(mid 80.903826 -410.664152)
				(end 81.134966 -410.664152)
			)
		)
		(stroke
			(width 0)
			(type solid)
		)
		(fill yes)
		(layer "In2.Cu")
		(net "GND")
	)
	(gr_poly
		(pts
			(arc
				(start 82.939382 -410.664152)
				(mid 82.708242 -410.664152)
				(end 82.939382 -410.664152)
			)
		)
		(stroke
			(width 0)
			(type solid)
		)
		(fill yes)
		(layer "In2.Cu")
		(net "GND")
	)
	(gr_poly
		(pts
			(arc
				(start 84.198206 -410.664152)
				(mid 83.967066 -410.664152)
				(end 84.198206 -410.664152)
			)
		)
		(stroke
			(width 0)
			(type solid)
		)
		(fill yes)
		(layer "In2.Cu")
		(net "GND")
	)
	(gr_poly
		(pts
			(arc
				(start 86.002622 -410.664152)
				(mid 85.771482 -410.664152)
				(end 86.002622 -410.664152)
			)
		)
		(stroke
			(width 0)
			(type solid)
		)
		(fill yes)
		(layer "In2.Cu")
		(net "GND")
	)
	(gr_poly
		(pts
			(arc
				(start 87.261446 -410.664152)
				(mid 87.030306 -410.664152)
				(end 87.261446 -410.664152)
			)
		)
		(stroke
			(width 0)
			(type solid)
		)
		(fill yes)
		(layer "In2.Cu")
		(net "GND")
	)
	(gr_poly
		(pts
			(arc
				(start 89.065862 -410.664152)
				(mid 88.834722 -410.664152)
				(end 89.065862 -410.664152)
			)
		)
		(stroke
			(width 0)
			(type solid)
		)
		(fill yes)
		(layer "In2.Cu")
		(net "GND")
	)
	(gr_poly
		(pts
			(arc
				(start 90.324686 -410.664152)
				(mid 90.093546 -410.664152)
				(end 90.324686 -410.664152)
			)
		)
		(stroke
			(width 0)
			(type solid)
		)
		(fill yes)
		(layer "In2.Cu")
		(net "GND")
	)
	(gr_poly
		(pts
			(arc
				(start 92.129102 -410.664152)
				(mid 91.897962 -410.664152)
				(end 92.129102 -410.664152)
			)
		)
		(stroke
			(width 0)
			(type solid)
		)
		(fill yes)
		(layer "In2.Cu")
		(net "GND")
	)
	(gr_poly
		(pts
			(arc
				(start 93.387926 -410.664152)
				(mid 93.156786 -410.664152)
				(end 93.387926 -410.664152)
			)
		)
		(stroke
			(width 0)
			(type solid)
		)
		(fill yes)
		(layer "In2.Cu")
		(net "GND")
	)
	(gr_poly
		(pts
			(arc
				(start 95.192342 -410.664152)
				(mid 94.961202 -410.664152)
				(end 95.192342 -410.664152)
			)
		)
		(stroke
			(width 0)
			(type solid)
		)
		(fill yes)
		(layer "In2.Cu")
		(net "GND")
	)
	(gr_poly
		(pts
			(arc
				(start 60.05957 -410.030168)
				(mid 59.811158 -410.030168)
				(end 60.05957 -410.030168)
			)
		)
		(stroke
			(width 0)
			(type solid)
		)
		(fill yes)
		(layer "In2.Cu")
		(net "GND")
	)
	(gr_poly
		(pts
			(arc
				(start 64.662304 -412.570168)
				(mid 64.403224 -412.570168)
				(end 64.662304 -412.570168)
			)
		)
		(stroke
			(width 0)
			(type solid)
		)
		(fill yes)
		(layer "In2.Cu")
		(net "GND")
	)
	(gr_poly
		(pts
			(arc
				(start 65.744344 -412.570168)
				(mid 65.485264 -412.570168)
				(end 65.744344 -412.570168)
			)
		)
		(stroke
			(width 0)
			(type solid)
		)
		(fill yes)
		(layer "In2.Cu")
		(net "GND")
	)
	(gr_poly
		(pts
			(arc
				(start 114.464846 -412.570168)
				(mid 114.205766 -412.570168)
				(end 114.464846 -412.570168)
			)
		)
		(stroke
			(width 0)
			(type solid)
		)
		(fill yes)
		(layer "In2.Cu")
		(net "GND")
	)
	(gr_poly
		(pts
			(arc
				(start 114.464846 -404.46452)
				(mid 114.205766 -404.46452)
				(end 114.464846 -404.46452)
			)
		)
		(stroke
			(width 0)
			(type solid)
		)
		(fill yes)
		(layer "In2.Cu")
		(net "GND")
	)
	(gr_poly
		(pts
			(arc
				(start 114.826034 -413.204152)
				(mid 114.566954 -413.204152)
				(end 114.826034 -413.204152)
			)
		)
		(stroke
			(width 0)
			(type solid)
		)
		(fill yes)
		(layer "In2.Cu")
		(net "GND")
	)
	(gr_poly
		(pts
			(arc
				(start 114.826034 -411.936184)
				(mid 114.566954 -411.936184)
				(end 114.826034 -411.936184)
			)
		)
		(stroke
			(width 0)
			(type solid)
		)
		(fill yes)
		(layer "In2.Cu")
		(net "GND")
	)
	(gr_poly
		(pts
			(arc
				(start 114.826034 -405.098504)
				(mid 114.566954 -405.098504)
				(end 114.826034 -405.098504)
			)
		)
		(stroke
			(width 0)
			(type solid)
		)
		(fill yes)
		(layer "In2.Cu")
		(net "GND")
	)
	(gr_poly
		(pts
			(arc
				(start 114.826034 -403.830536)
				(mid 114.566954 -403.830536)
				(end 114.826034 -403.830536)
			)
		)
		(stroke
			(width 0)
			(type solid)
		)
		(fill yes)
		(layer "In2.Cu")
		(net "GND")
	)
	(gr_poly
		(pts
			(arc
				(start 115.996466 -410.030168)
				(mid 115.737386 -410.030168)
				(end 115.996466 -410.030168)
			)
		)
		(stroke
			(width 0)
			(type solid)
		)
		(fill yes)
		(layer "In2.Cu")
		(net "GND")
	)
	(gr_poly
		(pts
			(arc
				(start 115.996466 -407.00452)
				(mid 115.737386 -407.00452)
				(end 115.996466 -407.00452)
			)
		)
		(stroke
			(width 0)
			(type solid)
		)
		(fill yes)
		(layer "In2.Cu")
		(net "GND")
	)
	(gr_poly
		(pts
			(arc
				(start 116.084858 -413.204152)
				(mid 115.825778 -413.204152)
				(end 116.084858 -413.204152)
			)
		)
		(stroke
			(width 0)
			(type solid)
		)
		(fill yes)
		(layer "In2.Cu")
		(net "GND")
	)
	(gr_poly
		(pts
			(arc
				(start 116.084858 -411.936184)
				(mid 115.825778 -411.936184)
				(end 116.084858 -411.936184)
			)
		)
		(stroke
			(width 0)
			(type solid)
		)
		(fill yes)
		(layer "In2.Cu")
		(net "GND")
	)
	(gr_poly
		(pts
			(arc
				(start 116.084858 -405.098504)
				(mid 115.825778 -405.098504)
				(end 116.084858 -405.098504)
			)
		)
		(stroke
			(width 0)
			(type solid)
		)
		(fill yes)
		(layer "In2.Cu")
		(net "GND")
	)
	(gr_poly
		(pts
			(arc
				(start 116.084858 -403.830536)
				(mid 115.825778 -403.830536)
				(end 116.084858 -403.830536)
			)
		)
		(stroke
			(width 0)
			(type solid)
		)
		(fill yes)
		(layer "In2.Cu")
		(net "GND")
	)
	(gr_poly
		(pts
			(arc
				(start 116.357654 -410.664152)
				(mid 116.098574 -410.664152)
				(end 116.357654 -410.664152)
			)
		)
		(stroke
			(width 0)
			(type solid)
		)
		(fill yes)
		(layer "In2.Cu")
		(net "GND")
	)
	(gr_poly
		(pts
			(arc
				(start 116.357654 -409.396184)
				(mid 116.098574 -409.396184)
				(end 116.357654 -409.396184)
			)
		)
		(stroke
			(width 0)
			(type solid)
		)
		(fill yes)
		(layer "In2.Cu")
		(net "GND")
	)
	(gr_poly
		(pts
			(arc
				(start 116.357654 -407.638504)
				(mid 116.098574 -407.638504)
				(end 116.357654 -407.638504)
			)
		)
		(stroke
			(width 0)
			(type solid)
		)
		(fill yes)
		(layer "In2.Cu")
		(net "GND")
	)
	(gr_poly
		(pts
			(arc
				(start 116.357654 -406.370536)
				(mid 116.098574 -406.370536)
				(end 116.357654 -406.370536)
			)
		)
		(stroke
			(width 0)
			(type solid)
		)
		(fill yes)
		(layer "In2.Cu")
		(net "GND")
	)
	(gr_poly
		(pts
			(arc
				(start 116.446046 -412.570168)
				(mid 116.186966 -412.570168)
				(end 116.446046 -412.570168)
			)
		)
		(stroke
			(width 0)
			(type solid)
		)
		(fill yes)
		(layer "In2.Cu")
		(net "GND")
	)
	(gr_poly
		(pts
			(arc
				(start 116.446046 -404.46452)
				(mid 116.186966 -404.46452)
				(end 116.446046 -404.46452)
			)
		)
		(stroke
			(width 0)
			(type solid)
		)
		(fill yes)
		(layer "In2.Cu")
		(net "GND")
	)
	(gr_poly
		(pts
			(arc
				(start 117.528086 -412.570168)
				(mid 117.269006 -412.570168)
				(end 117.528086 -412.570168)
			)
		)
		(stroke
			(width 0)
			(type solid)
		)
		(fill yes)
		(layer "In2.Cu")
		(net "GND")
	)
	(gr_poly
		(pts
			(arc
				(start 117.528086 -404.46452)
				(mid 117.269006 -404.46452)
				(end 117.528086 -404.46452)
			)
		)
		(stroke
			(width 0)
			(type solid)
		)
		(fill yes)
		(layer "In2.Cu")
		(net "GND")
	)
	(gr_poly
		(pts
			(arc
				(start 117.616478 -410.664152)
				(mid 117.357398 -410.664152)
				(end 117.616478 -410.664152)
			)
		)
		(stroke
			(width 0)
			(type solid)
		)
		(fill yes)
		(layer "In2.Cu")
		(net "GND")
	)
	(gr_poly
		(pts
			(arc
				(start 117.616478 -409.396184)
				(mid 117.357398 -409.396184)
				(end 117.616478 -409.396184)
			)
		)
		(stroke
			(width 0)
			(type solid)
		)
		(fill yes)
		(layer "In2.Cu")
		(net "GND")
	)
	(gr_poly
		(pts
			(arc
				(start 117.616478 -407.638504)
				(mid 117.357398 -407.638504)
				(end 117.616478 -407.638504)
			)
		)
		(stroke
			(width 0)
			(type solid)
		)
		(fill yes)
		(layer "In2.Cu")
		(net "GND")
	)
	(gr_poly
		(pts
			(arc
				(start 117.616478 -406.370536)
				(mid 117.357398 -406.370536)
				(end 117.616478 -406.370536)
			)
		)
		(stroke
			(width 0)
			(type solid)
		)
		(fill yes)
		(layer "In2.Cu")
		(net "GND")
	)
	(gr_poly
		(pts
			(arc
				(start 117.889274 -413.204152)
				(mid 117.630194 -413.204152)
				(end 117.889274 -413.204152)
			)
		)
		(stroke
			(width 0)
			(type solid)
		)
		(fill yes)
		(layer "In2.Cu")
		(net "GND")
	)
	(gr_poly
		(pts
			(arc
				(start 117.889274 -411.936184)
				(mid 117.630194 -411.936184)
				(end 117.889274 -411.936184)
			)
		)
		(stroke
			(width 0)
			(type solid)
		)
		(fill yes)
		(layer "In2.Cu")
		(net "GND")
	)
	(gr_poly
		(pts
			(arc
				(start 117.889274 -405.098504)
				(mid 117.630194 -405.098504)
				(end 117.889274 -405.098504)
			)
		)
		(stroke
			(width 0)
			(type solid)
		)
		(fill yes)
		(layer "In2.Cu")
		(net "GND")
	)
	(gr_poly
		(pts
			(arc
				(start 117.889274 -403.830536)
				(mid 117.630194 -403.830536)
				(end 117.889274 -403.830536)
			)
		)
		(stroke
			(width 0)
			(type solid)
		)
		(fill yes)
		(layer "In2.Cu")
		(net "GND")
	)
	(gr_poly
		(pts
			(arc
				(start 117.977666 -410.030168)
				(mid 117.718586 -410.030168)
				(end 117.977666 -410.030168)
			)
		)
		(stroke
			(width 0)
			(type solid)
		)
		(fill yes)
		(layer "In2.Cu")
		(net "GND")
	)
	(gr_poly
		(pts
			(arc
				(start 117.977666 -407.00452)
				(mid 117.718586 -407.00452)
				(end 117.977666 -407.00452)
			)
		)
		(stroke
			(width 0)
			(type solid)
		)
		(fill yes)
		(layer "In2.Cu")
		(net "GND")
	)
	(gr_poly
		(pts
			(arc
				(start 119.059706 -410.030168)
				(mid 118.800626 -410.030168)
				(end 119.059706 -410.030168)
			)
		)
		(stroke
			(width 0)
			(type solid)
		)
		(fill yes)
		(layer "In2.Cu")
		(net "GND")
	)
	(gr_poly
		(pts
			(arc
				(start 119.059706 -407.00452)
				(mid 118.800626 -407.00452)
				(end 119.059706 -407.00452)
			)
		)
		(stroke
			(width 0)
			(type solid)
		)
		(fill yes)
		(layer "In2.Cu")
		(net "GND")
	)
	(gr_poly
		(pts
			(arc
				(start 119.148098 -413.204152)
				(mid 118.889018 -413.204152)
				(end 119.148098 -413.204152)
			)
		)
		(stroke
			(width 0)
			(type solid)
		)
		(fill yes)
		(layer "In2.Cu")
		(net "GND")
	)
	(gr_poly
		(pts
			(arc
				(start 119.148098 -411.936184)
				(mid 118.889018 -411.936184)
				(end 119.148098 -411.936184)
			)
		)
		(stroke
			(width 0)
			(type solid)
		)
		(fill yes)
		(layer "In2.Cu")
		(net "GND")
	)
	(gr_poly
		(pts
			(arc
				(start 119.148098 -405.098504)
				(mid 118.889018 -405.098504)
				(end 119.148098 -405.098504)
			)
		)
		(stroke
			(width 0)
			(type solid)
		)
		(fill yes)
		(layer "In2.Cu")
		(net "GND")
	)
	(gr_poly
		(pts
			(arc
				(start 119.148098 -403.830536)
				(mid 118.889018 -403.830536)
				(end 119.148098 -403.830536)
			)
		)
		(stroke
			(width 0)
			(type solid)
		)
		(fill yes)
		(layer "In2.Cu")
		(net "GND")
	)
	(gr_poly
		(pts
			(arc
				(start 119.420894 -410.664152)
				(mid 119.161814 -410.664152)
				(end 119.420894 -410.664152)
			)
		)
		(stroke
			(width 0)
			(type solid)
		)
		(fill yes)
		(layer "In2.Cu")
		(net "GND")
	)
	(gr_poly
		(pts
			(arc
				(start 119.420894 -409.396184)
				(mid 119.161814 -409.396184)
				(end 119.420894 -409.396184)
			)
		)
		(stroke
			(width 0)
			(type solid)
		)
		(fill yes)
		(layer "In2.Cu")
		(net "GND")
	)
	(gr_poly
		(pts
			(arc
				(start 119.420894 -407.638504)
				(mid 119.161814 -407.638504)
				(end 119.420894 -407.638504)
			)
		)
		(stroke
			(width 0)
			(type solid)
		)
		(fill yes)
		(layer "In2.Cu")
		(net "GND")
	)
	(gr_poly
		(pts
			(arc
				(start 119.420894 -406.370536)
				(mid 119.161814 -406.370536)
				(end 119.420894 -406.370536)
			)
		)
		(stroke
			(width 0)
			(type solid)
		)
		(fill yes)
		(layer "In2.Cu")
		(net "GND")
	)
	(gr_poly
		(pts
			(arc
				(start 119.509286 -412.570168)
				(mid 119.250206 -412.570168)
				(end 119.509286 -412.570168)
			)
		)
		(stroke
			(width 0)
			(type solid)
		)
		(fill yes)
		(layer "In2.Cu")
		(net "GND")
	)
	(gr_poly
		(pts
			(arc
				(start 119.509286 -404.46452)
				(mid 119.250206 -404.46452)
				(end 119.509286 -404.46452)
			)
		)
		(stroke
			(width 0)
			(type solid)
		)
		(fill yes)
		(layer "In2.Cu")
		(net "GND")
	)
	(gr_poly
		(pts
			(arc
				(start 120.591326 -412.570168)
				(mid 120.332246 -412.570168)
				(end 120.591326 -412.570168)
			)
		)
		(stroke
			(width 0)
			(type solid)
		)
		(fill yes)
		(layer "In2.Cu")
		(net "GND")
	)
	(gr_poly
		(pts
			(arc
				(start 120.591326 -404.46452)
				(mid 120.332246 -404.46452)
				(end 120.591326 -404.46452)
			)
		)
		(stroke
			(width 0)
			(type solid)
		)
		(fill yes)
		(layer "In2.Cu")
		(net "GND")
	)
	(gr_poly
		(pts
			(arc
				(start 120.679718 -410.664152)
				(mid 120.420638 -410.664152)
				(end 120.679718 -410.664152)
			)
		)
		(stroke
			(width 0)
			(type solid)
		)
		(fill yes)
		(layer "In2.Cu")
		(net "GND")
	)
	(gr_poly
		(pts
			(arc
				(start 120.679718 -409.396184)
				(mid 120.420638 -409.396184)
				(end 120.679718 -409.396184)
			)
		)
		(stroke
			(width 0)
			(type solid)
		)
		(fill yes)
		(layer "In2.Cu")
		(net "GND")
	)
	(gr_poly
		(pts
			(arc
				(start 120.679718 -407.638504)
				(mid 120.420638 -407.638504)
				(end 120.679718 -407.638504)
			)
		)
		(stroke
			(width 0)
			(type solid)
		)
		(fill yes)
		(layer "In2.Cu")
		(net "GND")
	)
	(gr_poly
		(pts
			(arc
				(start 120.679718 -406.370536)
				(mid 120.420638 -406.370536)
				(end 120.679718 -406.370536)
			)
		)
		(stroke
			(width 0)
			(type solid)
		)
		(fill yes)
		(layer "In2.Cu")
		(net "GND")
	)
	(gr_poly
		(pts
			(arc
				(start 120.952514 -413.204152)
				(mid 120.693434 -413.204152)
				(end 120.952514 -413.204152)
			)
		)
		(stroke
			(width 0)
			(type solid)
		)
		(fill yes)
		(layer "In2.Cu")
		(net "GND")
	)
	(gr_poly
		(pts
			(arc
				(start 120.952514 -411.936184)
				(mid 120.693434 -411.936184)
				(end 120.952514 -411.936184)
			)
		)
		(stroke
			(width 0)
			(type solid)
		)
		(fill yes)
		(layer "In2.Cu")
		(net "GND")
	)
	(gr_poly
		(pts
			(arc
				(start 120.952514 -405.098504)
				(mid 120.693434 -405.098504)
				(end 120.952514 -405.098504)
			)
		)
		(stroke
			(width 0)
			(type solid)
		)
		(fill yes)
		(layer "In2.Cu")
		(net "GND")
	)
	(gr_poly
		(pts
			(arc
				(start 120.952514 -403.830536)
				(mid 120.693434 -403.830536)
				(end 120.952514 -403.830536)
			)
		)
		(stroke
			(width 0)
			(type solid)
		)
		(fill yes)
		(layer "In2.Cu")
		(net "GND")
	)
	(gr_poly
		(pts
			(arc
				(start 121.040906 -410.030168)
				(mid 120.781826 -410.030168)
				(end 121.040906 -410.030168)
			)
		)
		(stroke
			(width 0)
			(type solid)
		)
		(fill yes)
		(layer "In2.Cu")
		(net "GND")
	)
	(gr_poly
		(pts
			(arc
				(start 121.040906 -407.00452)
				(mid 120.781826 -407.00452)
				(end 121.040906 -407.00452)
			)
		)
		(stroke
			(width 0)
			(type solid)
		)
		(fill yes)
		(layer "In2.Cu")
		(net "GND")
	)
	(gr_poly
		(pts
			(arc
				(start 122.122946 -410.030168)
				(mid 121.863866 -410.030168)
				(end 122.122946 -410.030168)
			)
		)
		(stroke
			(width 0)
			(type solid)
		)
		(fill yes)
		(layer "In2.Cu")
		(net "GND")
	)
	(gr_poly
		(pts
			(arc
				(start 122.122946 -407.00452)
				(mid 121.863866 -407.00452)
				(end 122.122946 -407.00452)
			)
		)
		(stroke
			(width 0)
			(type solid)
		)
		(fill yes)
		(layer "In2.Cu")
		(net "GND")
	)
	(gr_poly
		(pts
			(arc
				(start 122.211338 -413.204152)
				(mid 121.952258 -413.204152)
				(end 122.211338 -413.204152)
			)
		)
		(stroke
			(width 0)
			(type solid)
		)
		(fill yes)
		(layer "In2.Cu")
		(net "GND")
	)
	(gr_poly
		(pts
			(arc
				(start 122.211338 -411.936184)
				(mid 121.952258 -411.936184)
				(end 122.211338 -411.936184)
			)
		)
		(stroke
			(width 0)
			(type solid)
		)
		(fill yes)
		(layer "In2.Cu")
		(net "GND")
	)
	(gr_poly
		(pts
			(arc
				(start 122.211338 -405.098504)
				(mid 121.952258 -405.098504)
				(end 122.211338 -405.098504)
			)
		)
		(stroke
			(width 0)
			(type solid)
		)
		(fill yes)
		(layer "In2.Cu")
		(net "GND")
	)
	(gr_poly
		(pts
			(arc
				(start 122.211338 -403.830536)
				(mid 121.952258 -403.830536)
				(end 122.211338 -403.830536)
			)
		)
		(stroke
			(width 0)
			(type solid)
		)
		(fill yes)
		(layer "In2.Cu")
		(net "GND")
	)
	(gr_poly
		(pts
			(arc
				(start 122.484134 -410.664152)
				(mid 122.225054 -410.664152)
				(end 122.484134 -410.664152)
			)
		)
		(stroke
			(width 0)
			(type solid)
		)
		(fill yes)
		(layer "In2.Cu")
		(net "GND")
	)
	(gr_poly
		(pts
			(arc
				(start 122.484134 -409.396184)
				(mid 122.225054 -409.396184)
				(end 122.484134 -409.396184)
			)
		)
		(stroke
			(width 0)
			(type solid)
		)
		(fill yes)
		(layer "In2.Cu")
		(net "GND")
	)
	(gr_poly
		(pts
			(arc
				(start 122.484134 -407.638504)
				(mid 122.225054 -407.638504)
				(end 122.484134 -407.638504)
			)
		)
		(stroke
			(width 0)
			(type solid)
		)
		(fill yes)
		(layer "In2.Cu")
		(net "GND")
	)
	(gr_poly
		(pts
			(arc
				(start 122.484134 -406.370536)
				(mid 122.225054 -406.370536)
				(end 122.484134 -406.370536)
			)
		)
		(stroke
			(width 0)
			(type solid)
		)
		(fill yes)
		(layer "In2.Cu")
		(net "GND")
	)
	(gr_poly
		(pts
			(arc
				(start 122.572526 -412.570168)
				(mid 122.313446 -412.570168)
				(end 122.572526 -412.570168)
			)
		)
		(stroke
			(width 0)
			(type solid)
		)
		(fill yes)
		(layer "In2.Cu")
		(net "GND")
	)
	(gr_poly
		(pts
			(arc
				(start 122.572526 -404.46452)
				(mid 122.313446 -404.46452)
				(end 122.572526 -404.46452)
			)
		)
		(stroke
			(width 0)
			(type solid)
		)
		(fill yes)
		(layer "In2.Cu")
		(net "GND")
	)
	(gr_poly
		(pts
			(arc
				(start 123.654566 -412.570168)
				(mid 123.395486 -412.570168)
				(end 123.654566 -412.570168)
			)
		)
		(stroke
			(width 0)
			(type solid)
		)
		(fill yes)
		(layer "In2.Cu")
		(net "GND")
	)
	(gr_poly
		(pts
			(arc
				(start 123.654566 -404.46452)
				(mid 123.395486 -404.46452)
				(end 123.654566 -404.46452)
			)
		)
		(stroke
			(width 0)
			(type solid)
		)
		(fill yes)
		(layer "In2.Cu")
		(net "GND")
	)
	(gr_poly
		(pts
			(arc
				(start 123.742958 -410.664152)
				(mid 123.483878 -410.664152)
				(end 123.742958 -410.664152)
			)
		)
		(stroke
			(width 0)
			(type solid)
		)
		(fill yes)
		(layer "In2.Cu")
		(net "GND")
	)
	(gr_poly
		(pts
			(arc
				(start 123.742958 -409.396184)
				(mid 123.483878 -409.396184)
				(end 123.742958 -409.396184)
			)
		)
		(stroke
			(width 0)
			(type solid)
		)
		(fill yes)
		(layer "In2.Cu")
		(net "GND")
	)
	(gr_poly
		(pts
			(arc
				(start 123.742958 -407.638504)
				(mid 123.483878 -407.638504)
				(end 123.742958 -407.638504)
			)
		)
		(stroke
			(width 0)
			(type solid)
		)
		(fill yes)
		(layer "In2.Cu")
		(net "GND")
	)
	(gr_poly
		(pts
			(arc
				(start 123.742958 -406.370536)
				(mid 123.483878 -406.370536)
				(end 123.742958 -406.370536)
			)
		)
		(stroke
			(width 0)
			(type solid)
		)
		(fill yes)
		(layer "In2.Cu")
		(net "GND")
	)
	(gr_poly
		(pts
			(arc
				(start 124.015754 -413.204152)
				(mid 123.756674 -413.204152)
				(end 124.015754 -413.204152)
			)
		)
		(stroke
			(width 0)
			(type solid)
		)
		(fill yes)
		(layer "In2.Cu")
		(net "GND")
	)
	(gr_poly
		(pts
			(arc
				(start 124.015754 -411.936184)
				(mid 123.756674 -411.936184)
				(end 124.015754 -411.936184)
			)
		)
		(stroke
			(width 0)
			(type solid)
		)
		(fill yes)
		(layer "In2.Cu")
		(net "GND")
	)
	(gr_poly
		(pts
			(arc
				(start 124.015754 -405.098504)
				(mid 123.756674 -405.098504)
				(end 124.015754 -405.098504)
			)
		)
		(stroke
			(width 0)
			(type solid)
		)
		(fill yes)
		(layer "In2.Cu")
		(net "GND")
	)
	(gr_poly
		(pts
			(arc
				(start 124.015754 -403.830536)
				(mid 123.756674 -403.830536)
				(end 124.015754 -403.830536)
			)
		)
		(stroke
			(width 0)
			(type solid)
		)
		(fill yes)
		(layer "In2.Cu")
		(net "GND")
	)
	(gr_poly
		(pts
			(arc
				(start 124.104146 -410.030168)
				(mid 123.845066 -410.030168)
				(end 124.104146 -410.030168)
			)
		)
		(stroke
			(width 0)
			(type solid)
		)
		(fill yes)
		(layer "In2.Cu")
		(net "GND")
	)
	(gr_poly
		(pts
			(arc
				(start 124.104146 -407.00452)
				(mid 123.845066 -407.00452)
				(end 124.104146 -407.00452)
			)
		)
		(stroke
			(width 0)
			(type solid)
		)
		(fill yes)
		(layer "In2.Cu")
		(net "GND")
	)
	(gr_poly
		(pts
			(arc
				(start 125.186186 -410.030168)
				(mid 124.927106 -410.030168)
				(end 125.186186 -410.030168)
			)
		)
		(stroke
			(width 0)
			(type solid)
		)
		(fill yes)
		(layer "In2.Cu")
		(net "GND")
	)
	(gr_poly
		(pts
			(arc
				(start 125.186186 -407.00452)
				(mid 124.927106 -407.00452)
				(end 125.186186 -407.00452)
			)
		)
		(stroke
			(width 0)
			(type solid)
		)
		(fill yes)
		(layer "In2.Cu")
		(net "GND")
	)
	(gr_poly
		(pts
			(arc
				(start 125.274578 -413.204152)
				(mid 125.015498 -413.204152)
				(end 125.274578 -413.204152)
			)
		)
		(stroke
			(width 0)
			(type solid)
		)
		(fill yes)
		(layer "In2.Cu")
		(net "GND")
	)
	(gr_poly
		(pts
			(arc
				(start 125.274578 -411.936184)
				(mid 125.015498 -411.936184)
				(end 125.274578 -411.936184)
			)
		)
		(stroke
			(width 0)
			(type solid)
		)
		(fill yes)
		(layer "In2.Cu")
		(net "GND")
	)
	(gr_poly
		(pts
			(arc
				(start 125.274578 -405.098504)
				(mid 125.015498 -405.098504)
				(end 125.274578 -405.098504)
			)
		)
		(stroke
			(width 0)
			(type solid)
		)
		(fill yes)
		(layer "In2.Cu")
		(net "GND")
	)
	(gr_poly
		(pts
			(arc
				(start 125.274578 -403.830536)
				(mid 125.015498 -403.830536)
				(end 125.274578 -403.830536)
			)
		)
		(stroke
			(width 0)
			(type solid)
		)
		(fill yes)
		(layer "In2.Cu")
		(net "GND")
	)
	(gr_poly
		(pts
			(arc
				(start 125.547374 -410.664152)
				(mid 125.288294 -410.664152)
				(end 125.547374 -410.664152)
			)
		)
		(stroke
			(width 0)
			(type solid)
		)
		(fill yes)
		(layer "In2.Cu")
		(net "GND")
	)
	(gr_poly
		(pts
			(arc
				(start 125.547374 -409.396184)
				(mid 125.288294 -409.396184)
				(end 125.547374 -409.396184)
			)
		)
		(stroke
			(width 0)
			(type solid)
		)
		(fill yes)
		(layer "In2.Cu")
		(net "GND")
	)
	(gr_poly
		(pts
			(arc
				(start 125.547374 -407.638504)
				(mid 125.288294 -407.638504)
				(end 125.547374 -407.638504)
			)
		)
		(stroke
			(width 0)
			(type solid)
		)
		(fill yes)
		(layer "In2.Cu")
		(net "GND")
	)
	(gr_poly
		(pts
			(arc
				(start 125.547374 -406.370536)
				(mid 125.288294 -406.370536)
				(end 125.547374 -406.370536)
			)
		)
		(stroke
			(width 0)
			(type solid)
		)
		(fill yes)
		(layer "In2.Cu")
		(net "GND")
	)
	(gr_poly
		(pts
			(arc
				(start 125.635766 -412.570168)
				(mid 125.376686 -412.570168)
				(end 125.635766 -412.570168)
			)
		)
		(stroke
			(width 0)
			(type solid)
		)
		(fill yes)
		(layer "In2.Cu")
		(net "GND")
	)
	(gr_poly
		(pts
			(arc
				(start 125.635766 -404.46452)
				(mid 125.376686 -404.46452)
				(end 125.635766 -404.46452)
			)
		)
		(stroke
			(width 0)
			(type solid)
		)
		(fill yes)
		(layer "In2.Cu")
		(net "GND")
	)
	(gr_poly
		(pts
			(arc
				(start 126.717806 -412.570168)
				(mid 126.458726 -412.570168)
				(end 126.717806 -412.570168)
			)
		)
		(stroke
			(width 0)
			(type solid)
		)
		(fill yes)
		(layer "In2.Cu")
		(net "GND")
	)
	(gr_poly
		(pts
			(arc
				(start 126.717806 -404.46452)
				(mid 126.458726 -404.46452)
				(end 126.717806 -404.46452)
			)
		)
		(stroke
			(width 0)
			(type solid)
		)
		(fill yes)
		(layer "In2.Cu")
		(net "GND")
	)
	(gr_poly
		(pts
			(arc
				(start 126.806198 -410.664152)
				(mid 126.547118 -410.664152)
				(end 126.806198 -410.664152)
			)
		)
		(stroke
			(width 0)
			(type solid)
		)
		(fill yes)
		(layer "In2.Cu")
		(net "GND")
	)
	(gr_poly
		(pts
			(arc
				(start 126.806198 -409.396184)
				(mid 126.547118 -409.396184)
				(end 126.806198 -409.396184)
			)
		)
		(stroke
			(width 0)
			(type solid)
		)
		(fill yes)
		(layer "In2.Cu")
		(net "GND")
	)
	(gr_poly
		(pts
			(arc
				(start 126.806198 -407.638504)
				(mid 126.547118 -407.638504)
				(end 126.806198 -407.638504)
			)
		)
		(stroke
			(width 0)
			(type solid)
		)
		(fill yes)
		(layer "In2.Cu")
		(net "GND")
	)
	(gr_poly
		(pts
			(arc
				(start 126.806198 -406.370536)
				(mid 126.547118 -406.370536)
				(end 126.806198 -406.370536)
			)
		)
		(stroke
			(width 0)
			(type solid)
		)
		(fill yes)
		(layer "In2.Cu")
		(net "GND")
	)
	(gr_poly
		(pts
			(arc
				(start 127.078994 -413.204152)
				(mid 126.819914 -413.204152)
				(end 127.078994 -413.204152)
			)
		)
		(stroke
			(width 0)
			(type solid)
		)
		(fill yes)
		(layer "In2.Cu")
		(net "GND")
	)
	(gr_poly
		(pts
			(arc
				(start 127.078994 -411.936184)
				(mid 126.819914 -411.936184)
				(end 127.078994 -411.936184)
			)
		)
		(stroke
			(width 0)
			(type solid)
		)
		(fill yes)
		(layer "In2.Cu")
		(net "GND")
	)
	(gr_poly
		(pts
			(arc
				(start 127.078994 -405.098504)
				(mid 126.819914 -405.098504)
				(end 127.078994 -405.098504)
			)
		)
		(stroke
			(width 0)
			(type solid)
		)
		(fill yes)
		(layer "In2.Cu")
		(net "GND")
	)
	(gr_poly
		(pts
			(arc
				(start 127.078994 -403.830536)
				(mid 126.819914 -403.830536)
				(end 127.078994 -403.830536)
			)
		)
		(stroke
			(width 0)
			(type solid)
		)
		(fill yes)
		(layer "In2.Cu")
		(net "GND")
	)
	(gr_poly
		(pts
			(arc
				(start 127.167386 -410.030168)
				(mid 126.908306 -410.030168)
				(end 127.167386 -410.030168)
			)
		)
		(stroke
			(width 0)
			(type solid)
		)
		(fill yes)
		(layer "In2.Cu")
		(net "GND")
	)
	(gr_poly
		(pts
			(arc
				(start 127.167386 -407.00452)
				(mid 126.908306 -407.00452)
				(end 127.167386 -407.00452)
			)
		)
		(stroke
			(width 0)
			(type solid)
		)
		(fill yes)
		(layer "In2.Cu")
		(net "GND")
	)
	(gr_poly
		(pts
			(arc
				(start 128.249426 -410.030168)
				(mid 127.990346 -410.030168)
				(end 128.249426 -410.030168)
			)
		)
		(stroke
			(width 0)
			(type solid)
		)
		(fill yes)
		(layer "In2.Cu")
		(net "GND")
	)
	(gr_poly
		(pts
			(arc
				(start 128.249426 -407.00452)
				(mid 127.990346 -407.00452)
				(end 128.249426 -407.00452)
			)
		)
		(stroke
			(width 0)
			(type solid)
		)
		(fill yes)
		(layer "In2.Cu")
		(net "GND")
	)
	(gr_poly
		(pts
			(arc
				(start 128.337818 -413.204152)
				(mid 128.078738 -413.204152)
				(end 128.337818 -413.204152)
			)
		)
		(stroke
			(width 0)
			(type solid)
		)
		(fill yes)
		(layer "In2.Cu")
		(net "GND")
	)
	(gr_poly
		(pts
			(arc
				(start 128.337818 -411.936184)
				(mid 128.078738 -411.936184)
				(end 128.337818 -411.936184)
			)
		)
		(stroke
			(width 0)
			(type solid)
		)
		(fill yes)
		(layer "In2.Cu")
		(net "GND")
	)
	(gr_poly
		(pts
			(arc
				(start 128.337818 -405.098504)
				(mid 128.078738 -405.098504)
				(end 128.337818 -405.098504)
			)
		)
		(stroke
			(width 0)
			(type solid)
		)
		(fill yes)
		(layer "In2.Cu")
		(net "GND")
	)
	(gr_poly
		(pts
			(arc
				(start 128.337818 -403.830536)
				(mid 128.078738 -403.830536)
				(end 128.337818 -403.830536)
			)
		)
		(stroke
			(width 0)
			(type solid)
		)
		(fill yes)
		(layer "In2.Cu")
		(net "GND")
	)
	(gr_poly
		(pts
			(arc
				(start 128.610614 -410.664152)
				(mid 128.351534 -410.664152)
				(end 128.610614 -410.664152)
			)
		)
		(stroke
			(width 0)
			(type solid)
		)
		(fill yes)
		(layer "In2.Cu")
		(net "GND")
	)
	(gr_poly
		(pts
			(arc
				(start 128.610614 -409.396184)
				(mid 128.351534 -409.396184)
				(end 128.610614 -409.396184)
			)
		)
		(stroke
			(width 0)
			(type solid)
		)
		(fill yes)
		(layer "In2.Cu")
		(net "GND")
	)
	(gr_poly
		(pts
			(arc
				(start 128.610614 -407.638504)
				(mid 128.351534 -407.638504)
				(end 128.610614 -407.638504)
			)
		)
		(stroke
			(width 0)
			(type solid)
		)
		(fill yes)
		(layer "In2.Cu")
		(net "GND")
	)
	(gr_poly
		(pts
			(arc
				(start 128.610614 -406.370536)
				(mid 128.351534 -406.370536)
				(end 128.610614 -406.370536)
			)
		)
		(stroke
			(width 0)
			(type solid)
		)
		(fill yes)
		(layer "In2.Cu")
		(net "GND")
	)
	(gr_poly
		(pts
			(arc
				(start 128.699006 -412.570168)
				(mid 128.439926 -412.570168)
				(end 128.699006 -412.570168)
			)
		)
		(stroke
			(width 0)
			(type solid)
		)
		(fill yes)
		(layer "In2.Cu")
		(net "GND")
	)
	(gr_poly
		(pts
			(arc
				(start 128.699006 -404.46452)
				(mid 128.439926 -404.46452)
				(end 128.699006 -404.46452)
			)
		)
		(stroke
			(width 0)
			(type solid)
		)
		(fill yes)
		(layer "In2.Cu")
		(net "GND")
	)
	(gr_poly
		(pts
			(arc
				(start 129.781046 -412.570168)
				(mid 129.521966 -412.570168)
				(end 129.781046 -412.570168)
			)
		)
		(stroke
			(width 0)
			(type solid)
		)
		(fill yes)
		(layer "In2.Cu")
		(net "GND")
	)
	(gr_poly
		(pts
			(arc
				(start 129.781046 -404.46452)
				(mid 129.521966 -404.46452)
				(end 129.781046 -404.46452)
			)
		)
		(stroke
			(width 0)
			(type solid)
		)
		(fill yes)
		(layer "In2.Cu")
		(net "GND")
	)
	(gr_poly
		(pts
			(arc
				(start 129.869438 -410.664152)
				(mid 129.610358 -410.664152)
				(end 129.869438 -410.664152)
			)
		)
		(stroke
			(width 0)
			(type solid)
		)
		(fill yes)
		(layer "In2.Cu")
		(net "GND")
	)
	(gr_poly
		(pts
			(arc
				(start 129.869438 -409.396184)
				(mid 129.610358 -409.396184)
				(end 129.869438 -409.396184)
			)
		)
		(stroke
			(width 0)
			(type solid)
		)
		(fill yes)
		(layer "In2.Cu")
		(net "GND")
	)
	(gr_poly
		(pts
			(arc
				(start 129.869438 -407.638504)
				(mid 129.610358 -407.638504)
				(end 129.869438 -407.638504)
			)
		)
		(stroke
			(width 0)
			(type solid)
		)
		(fill yes)
		(layer "In2.Cu")
		(net "GND")
	)
	(gr_poly
		(pts
			(arc
				(start 129.869438 -406.370536)
				(mid 129.610358 -406.370536)
				(end 129.869438 -406.370536)
			)
		)
		(stroke
			(width 0)
			(type solid)
		)
		(fill yes)
		(layer "In2.Cu")
		(net "GND")
	)
	(gr_poly
		(pts
			(arc
				(start 130.142234 -413.204152)
				(mid 129.883154 -413.204152)
				(end 130.142234 -413.204152)
			)
		)
		(stroke
			(width 0)
			(type solid)
		)
		(fill yes)
		(layer "In2.Cu")
		(net "GND")
	)
	(gr_poly
		(pts
			(arc
				(start 130.142234 -411.936184)
				(mid 129.883154 -411.936184)
				(end 130.142234 -411.936184)
			)
		)
		(stroke
			(width 0)
			(type solid)
		)
		(fill yes)
		(layer "In2.Cu")
		(net "GND")
	)
	(gr_poly
		(pts
			(arc
				(start 130.142234 -405.098504)
				(mid 129.883154 -405.098504)
				(end 130.142234 -405.098504)
			)
		)
		(stroke
			(width 0)
			(type solid)
		)
		(fill yes)
		(layer "In2.Cu")
		(net "GND")
	)
	(gr_poly
		(pts
			(arc
				(start 130.142234 -403.830536)
				(mid 129.883154 -403.830536)
				(end 130.142234 -403.830536)
			)
		)
		(stroke
			(width 0)
			(type solid)
		)
		(fill yes)
		(layer "In2.Cu")
		(net "GND")
	)
	(gr_poly
		(pts
			(arc
				(start 130.230626 -410.030168)
				(mid 129.971546 -410.030168)
				(end 130.230626 -410.030168)
			)
		)
		(stroke
			(width 0)
			(type solid)
		)
		(fill yes)
		(layer "In2.Cu")
		(net "GND")
	)
	(gr_poly
		(pts
			(arc
				(start 130.230626 -407.00452)
				(mid 129.971546 -407.00452)
				(end 130.230626 -407.00452)
			)
		)
		(stroke
			(width 0)
			(type solid)
		)
		(fill yes)
		(layer "In2.Cu")
		(net "GND")
	)
	(gr_poly
		(pts
			(arc
				(start 131.312666 -410.030168)
				(mid 131.053586 -410.030168)
				(end 131.312666 -410.030168)
			)
		)
		(stroke
			(width 0)
			(type solid)
		)
		(fill yes)
		(layer "In2.Cu")
		(net "GND")
	)
	(gr_poly
		(pts
			(arc
				(start 131.312666 -407.00452)
				(mid 131.053586 -407.00452)
				(end 131.312666 -407.00452)
			)
		)
		(stroke
			(width 0)
			(type solid)
		)
		(fill yes)
		(layer "In2.Cu")
		(net "GND")
	)
	(gr_poly
		(pts
			(arc
				(start 131.401058 -413.204152)
				(mid 131.141978 -413.204152)
				(end 131.401058 -413.204152)
			)
		)
		(stroke
			(width 0)
			(type solid)
		)
		(fill yes)
		(layer "In2.Cu")
		(net "GND")
	)
	(gr_poly
		(pts
			(arc
				(start 131.401058 -411.936184)
				(mid 131.141978 -411.936184)
				(end 131.401058 -411.936184)
			)
		)
		(stroke
			(width 0)
			(type solid)
		)
		(fill yes)
		(layer "In2.Cu")
		(net "GND")
	)
	(gr_poly
		(pts
			(arc
				(start 131.401058 -405.098504)
				(mid 131.141978 -405.098504)
				(end 131.401058 -405.098504)
			)
		)
		(stroke
			(width 0)
			(type solid)
		)
		(fill yes)
		(layer "In2.Cu")
		(net "GND")
	)
	(gr_poly
		(pts
			(arc
				(start 131.401058 -403.830536)
				(mid 131.141978 -403.830536)
				(end 131.401058 -403.830536)
			)
		)
		(stroke
			(width 0)
			(type solid)
		)
		(fill yes)
		(layer "In2.Cu")
		(net "GND")
	)
	(gr_poly
		(pts
			(arc
				(start 131.673854 -410.664152)
				(mid 131.414774 -410.664152)
				(end 131.673854 -410.664152)
			)
		)
		(stroke
			(width 0)
			(type solid)
		)
		(fill yes)
		(layer "In2.Cu")
		(net "GND")
	)
	(gr_poly
		(pts
			(arc
				(start 131.673854 -409.396184)
				(mid 131.414774 -409.396184)
				(end 131.673854 -409.396184)
			)
		)
		(stroke
			(width 0)
			(type solid)
		)
		(fill yes)
		(layer "In2.Cu")
		(net "GND")
	)
	(gr_poly
		(pts
			(arc
				(start 131.673854 -407.638504)
				(mid 131.414774 -407.638504)
				(end 131.673854 -407.638504)
			)
		)
		(stroke
			(width 0)
			(type solid)
		)
		(fill yes)
		(layer "In2.Cu")
		(net "GND")
	)
	(gr_poly
		(pts
			(arc
				(start 131.673854 -406.370536)
				(mid 131.414774 -406.370536)
				(end 131.673854 -406.370536)
			)
		)
		(stroke
			(width 0)
			(type solid)
		)
		(fill yes)
		(layer "In2.Cu")
		(net "GND")
	)
	(gr_poly
		(pts
			(arc
				(start 131.762246 -412.570168)
				(mid 131.503166 -412.570168)
				(end 131.762246 -412.570168)
			)
		)
		(stroke
			(width 0)
			(type solid)
		)
		(fill yes)
		(layer "In2.Cu")
		(net "GND")
	)
	(gr_poly
		(pts
			(arc
				(start 131.762246 -404.46452)
				(mid 131.503166 -404.46452)
				(end 131.762246 -404.46452)
			)
		)
		(stroke
			(width 0)
			(type solid)
		)
		(fill yes)
		(layer "In2.Cu")
		(net "GND")
	)
	(gr_poly
		(pts
			(arc
				(start 132.844286 -412.570168)
				(mid 132.585206 -412.570168)
				(end 132.844286 -412.570168)
			)
		)
		(stroke
			(width 0)
			(type solid)
		)
		(fill yes)
		(layer "In2.Cu")
		(net "GND")
	)
	(gr_poly
		(pts
			(arc
				(start 132.844286 -404.46452)
				(mid 132.585206 -404.46452)
				(end 132.844286 -404.46452)
			)
		)
		(stroke
			(width 0)
			(type solid)
		)
		(fill yes)
		(layer "In2.Cu")
		(net "GND")
	)
	(gr_poly
		(pts
			(arc
				(start 132.932678 -410.664152)
				(mid 132.673598 -410.664152)
				(end 132.932678 -410.664152)
			)
		)
		(stroke
			(width 0)
			(type solid)
		)
		(fill yes)
		(layer "In2.Cu")
		(net "GND")
	)
	(gr_poly
		(pts
			(arc
				(start 132.932678 -409.396184)
				(mid 132.673598 -409.396184)
				(end 132.932678 -409.396184)
			)
		)
		(stroke
			(width 0)
			(type solid)
		)
		(fill yes)
		(layer "In2.Cu")
		(net "GND")
	)
	(gr_poly
		(pts
			(arc
				(start 132.932678 -407.638504)
				(mid 132.673598 -407.638504)
				(end 132.932678 -407.638504)
			)
		)
		(stroke
			(width 0)
			(type solid)
		)
		(fill yes)
		(layer "In2.Cu")
		(net "GND")
	)
	(gr_poly
		(pts
			(arc
				(start 132.932678 -406.370536)
				(mid 132.673598 -406.370536)
				(end 132.932678 -406.370536)
			)
		)
		(stroke
			(width 0)
			(type solid)
		)
		(fill yes)
		(layer "In2.Cu")
		(net "GND")
	)
	(gr_poly
		(pts
			(arc
				(start 133.205474 -413.204152)
				(mid 132.946394 -413.204152)
				(end 133.205474 -413.204152)
			)
		)
		(stroke
			(width 0)
			(type solid)
		)
		(fill yes)
		(layer "In2.Cu")
		(net "GND")
	)
	(gr_poly
		(pts
			(arc
				(start 133.205474 -411.936184)
				(mid 132.946394 -411.936184)
				(end 133.205474 -411.936184)
			)
		)
		(stroke
			(width 0)
			(type solid)
		)
		(fill yes)
		(layer "In2.Cu")
		(net "GND")
	)
	(gr_poly
		(pts
			(arc
				(start 133.205474 -405.098504)
				(mid 132.946394 -405.098504)
				(end 133.205474 -405.098504)
			)
		)
		(stroke
			(width 0)
			(type solid)
		)
		(fill yes)
		(layer "In2.Cu")
		(net "GND")
	)
	(gr_poly
		(pts
			(arc
				(start 133.205474 -403.830536)
				(mid 132.946394 -403.830536)
				(end 133.205474 -403.830536)
			)
		)
		(stroke
			(width 0)
			(type solid)
		)
		(fill yes)
		(layer "In2.Cu")
		(net "GND")
	)
	(gr_poly
		(pts
			(arc
				(start 133.293866 -410.030168)
				(mid 133.034786 -410.030168)
				(end 133.293866 -410.030168)
			)
		)
		(stroke
			(width 0)
			(type solid)
		)
		(fill yes)
		(layer "In2.Cu")
		(net "GND")
	)
	(gr_poly
		(pts
			(arc
				(start 133.293866 -407.00452)
				(mid 133.034786 -407.00452)
				(end 133.293866 -407.00452)
			)
		)
		(stroke
			(width 0)
			(type solid)
		)
		(fill yes)
		(layer "In2.Cu")
		(net "GND")
	)
	(gr_poly
		(pts
			(arc
				(start 134.375906 -410.030168)
				(mid 134.116826 -410.030168)
				(end 134.375906 -410.030168)
			)
		)
		(stroke
			(width 0)
			(type solid)
		)
		(fill yes)
		(layer "In2.Cu")
		(net "GND")
	)
	(gr_poly
		(pts
			(arc
				(start 134.375906 -407.00452)
				(mid 134.116826 -407.00452)
				(end 134.375906 -407.00452)
			)
		)
		(stroke
			(width 0)
			(type solid)
		)
		(fill yes)
		(layer "In2.Cu")
		(net "GND")
	)
	(gr_poly
		(pts
			(arc
				(start 134.464298 -413.204152)
				(mid 134.205218 -413.204152)
				(end 134.464298 -413.204152)
			)
		)
		(stroke
			(width 0)
			(type solid)
		)
		(fill yes)
		(layer "In2.Cu")
		(net "GND")
	)
	(gr_poly
		(pts
			(arc
				(start 134.464298 -411.936184)
				(mid 134.205218 -411.936184)
				(end 134.464298 -411.936184)
			)
		)
		(stroke
			(width 0)
			(type solid)
		)
		(fill yes)
		(layer "In2.Cu")
		(net "GND")
	)
	(gr_poly
		(pts
			(arc
				(start 134.464298 -405.098504)
				(mid 134.205218 -405.098504)
				(end 134.464298 -405.098504)
			)
		)
		(stroke
			(width 0)
			(type solid)
		)
		(fill yes)
		(layer "In2.Cu")
		(net "GND")
	)
	(gr_poly
		(pts
			(arc
				(start 134.464298 -403.830536)
				(mid 134.205218 -403.830536)
				(end 134.464298 -403.830536)
			)
		)
		(stroke
			(width 0)
			(type solid)
		)
		(fill yes)
		(layer "In2.Cu")
		(net "GND")
	)
	(gr_poly
		(pts
			(arc
				(start 134.737094 -410.664152)
				(mid 134.478014 -410.664152)
				(end 134.737094 -410.664152)
			)
		)
		(stroke
			(width 0)
			(type solid)
		)
		(fill yes)
		(layer "In2.Cu")
		(net "GND")
	)
	(gr_poly
		(pts
			(arc
				(start 134.737094 -409.396184)
				(mid 134.478014 -409.396184)
				(end 134.737094 -409.396184)
			)
		)
		(stroke
			(width 0)
			(type solid)
		)
		(fill yes)
		(layer "In2.Cu")
		(net "GND")
	)
	(gr_poly
		(pts
			(arc
				(start 134.737094 -407.638504)
				(mid 134.478014 -407.638504)
				(end 134.737094 -407.638504)
			)
		)
		(stroke
			(width 0)
			(type solid)
		)
		(fill yes)
		(layer "In2.Cu")
		(net "GND")
	)
	(gr_poly
		(pts
			(arc
				(start 134.737094 -406.370536)
				(mid 134.478014 -406.370536)
				(end 134.737094 -406.370536)
			)
		)
		(stroke
			(width 0)
			(type solid)
		)
		(fill yes)
		(layer "In2.Cu")
		(net "GND")
	)
	(gr_poly
		(pts
			(arc
				(start 134.825486 -412.570168)
				(mid 134.566406 -412.570168)
				(end 134.825486 -412.570168)
			)
		)
		(stroke
			(width 0)
			(type solid)
		)
		(fill yes)
		(layer "In2.Cu")
		(net "GND")
	)
	(gr_poly
		(pts
			(arc
				(start 134.825486 -404.46452)
				(mid 134.566406 -404.46452)
				(end 134.825486 -404.46452)
			)
		)
		(stroke
			(width 0)
			(type solid)
		)
		(fill yes)
		(layer "In2.Cu")
		(net "GND")
	)
	(gr_poly
		(pts
			(arc
				(start 135.907526 -412.570168)
				(mid 135.648446 -412.570168)
				(end 135.907526 -412.570168)
			)
		)
		(stroke
			(width 0)
			(type solid)
		)
		(fill yes)
		(layer "In2.Cu")
		(net "GND")
	)
	(gr_poly
		(pts
			(arc
				(start 135.907526 -404.46452)
				(mid 135.648446 -404.46452)
				(end 135.907526 -404.46452)
			)
		)
		(stroke
			(width 0)
			(type solid)
		)
		(fill yes)
		(layer "In2.Cu")
		(net "GND")
	)
	(gr_poly
		(pts
			(arc
				(start 135.995918 -410.664152)
				(mid 135.736838 -410.664152)
				(end 135.995918 -410.664152)
			)
		)
		(stroke
			(width 0)
			(type solid)
		)
		(fill yes)
		(layer "In2.Cu")
		(net "GND")
	)
	(gr_poly
		(pts
			(arc
				(start 135.995918 -409.396184)
				(mid 135.736838 -409.396184)
				(end 135.995918 -409.396184)
			)
		)
		(stroke
			(width 0)
			(type solid)
		)
		(fill yes)
		(layer "In2.Cu")
		(net "GND")
	)
	(gr_poly
		(pts
			(arc
				(start 135.995918 -407.638504)
				(mid 135.736838 -407.638504)
				(end 135.995918 -407.638504)
			)
		)
		(stroke
			(width 0)
			(type solid)
		)
		(fill yes)
		(layer "In2.Cu")
		(net "GND")
	)
	(gr_poly
		(pts
			(arc
				(start 135.995918 -406.370536)
				(mid 135.736838 -406.370536)
				(end 135.995918 -406.370536)
			)
		)
		(stroke
			(width 0)
			(type solid)
		)
		(fill yes)
		(layer "In2.Cu")
		(net "GND")
	)
	(gr_poly
		(pts
			(arc
				(start 136.268714 -413.204152)
				(mid 136.009634 -413.204152)
				(end 136.268714 -413.204152)
			)
		)
		(stroke
			(width 0)
			(type solid)
		)
		(fill yes)
		(layer "In2.Cu")
		(net "GND")
	)
	(gr_poly
		(pts
			(arc
				(start 136.268714 -411.936184)
				(mid 136.009634 -411.936184)
				(end 136.268714 -411.936184)
			)
		)
		(stroke
			(width 0)
			(type solid)
		)
		(fill yes)
		(layer "In2.Cu")
		(net "GND")
	)
	(gr_poly
		(pts
			(arc
				(start 136.268714 -405.098504)
				(mid 136.009634 -405.098504)
				(end 136.268714 -405.098504)
			)
		)
		(stroke
			(width 0)
			(type solid)
		)
		(fill yes)
		(layer "In2.Cu")
		(net "GND")
	)
	(gr_poly
		(pts
			(arc
				(start 136.268714 -403.830536)
				(mid 136.009634 -403.830536)
				(end 136.268714 -403.830536)
			)
		)
		(stroke
			(width 0)
			(type solid)
		)
		(fill yes)
		(layer "In2.Cu")
		(net "GND")
	)
	(gr_poly
		(pts
			(arc
				(start 136.357106 -410.030168)
				(mid 136.098026 -410.030168)
				(end 136.357106 -410.030168)
			)
		)
		(stroke
			(width 0)
			(type solid)
		)
		(fill yes)
		(layer "In2.Cu")
		(net "GND")
	)
	(gr_poly
		(pts
			(arc
				(start 136.357106 -407.00452)
				(mid 136.098026 -407.00452)
				(end 136.357106 -407.00452)
			)
		)
		(stroke
			(width 0)
			(type solid)
		)
		(fill yes)
		(layer "In2.Cu")
		(net "GND")
	)
	(gr_poly
		(pts
			(arc
				(start 136.938512 -23.695406)
				(mid 136.680448 -23.695406)
				(end 136.938512 -23.695406)
			)
		)
		(stroke
			(width 0)
			(type solid)
		)
		(fill yes)
		(layer "In2.Cu")
		(net "GND")
	)
	(gr_poly
		(pts
			(arc
				(start 137.439146 -410.030168)
				(mid 137.180066 -410.030168)
				(end 137.439146 -410.030168)
			)
		)
		(stroke
			(width 0)
			(type solid)
		)
		(fill yes)
		(layer "In2.Cu")
		(net "GND")
	)
	(gr_poly
		(pts
			(arc
				(start 137.439146 -407.00452)
				(mid 137.180066 -407.00452)
				(end 137.439146 -407.00452)
			)
		)
		(stroke
			(width 0)
			(type solid)
		)
		(fill yes)
		(layer "In2.Cu")
		(net "GND")
	)
	(gr_poly
		(pts
			(arc
				(start 137.527538 -413.204152)
				(mid 137.268458 -413.204152)
				(end 137.527538 -413.204152)
			)
		)
		(stroke
			(width 0)
			(type solid)
		)
		(fill yes)
		(layer "In2.Cu")
		(net "GND")
	)
	(gr_poly
		(pts
			(arc
				(start 137.527538 -411.936184)
				(mid 137.268458 -411.936184)
				(end 137.527538 -411.936184)
			)
		)
		(stroke
			(width 0)
			(type solid)
		)
		(fill yes)
		(layer "In2.Cu")
		(net "GND")
	)
	(gr_poly
		(pts
			(arc
				(start 137.527538 -405.098504)
				(mid 137.268458 -405.098504)
				(end 137.527538 -405.098504)
			)
		)
		(stroke
			(width 0)
			(type solid)
		)
		(fill yes)
		(layer "In2.Cu")
		(net "GND")
	)
	(gr_poly
		(pts
			(arc
				(start 137.527538 -403.830536)
				(mid 137.268458 -403.830536)
				(end 137.527538 -403.830536)
			)
		)
		(stroke
			(width 0)
			(type solid)
		)
		(fill yes)
		(layer "In2.Cu")
		(net "GND")
	)
	(gr_poly
		(pts
			(arc
				(start 137.800334 -410.664152)
				(mid 137.541254 -410.664152)
				(end 137.800334 -410.664152)
			)
		)
		(stroke
			(width 0)
			(type solid)
		)
		(fill yes)
		(layer "In2.Cu")
		(net "GND")
	)
	(gr_poly
		(pts
			(arc
				(start 137.800334 -409.396184)
				(mid 137.541254 -409.396184)
				(end 137.800334 -409.396184)
			)
		)
		(stroke
			(width 0)
			(type solid)
		)
		(fill yes)
		(layer "In2.Cu")
		(net "GND")
	)
	(gr_poly
		(pts
			(arc
				(start 137.800334 -407.638504)
				(mid 137.541254 -407.638504)
				(end 137.800334 -407.638504)
			)
		)
		(stroke
			(width 0)
			(type solid)
		)
		(fill yes)
		(layer "In2.Cu")
		(net "GND")
	)
	(gr_poly
		(pts
			(arc
				(start 137.800334 -406.370536)
				(mid 137.541254 -406.370536)
				(end 137.800334 -406.370536)
			)
		)
		(stroke
			(width 0)
			(type solid)
		)
		(fill yes)
		(layer "In2.Cu")
		(net "GND")
	)
	(gr_poly
		(pts
			(arc
				(start 137.888726 -412.570168)
				(mid 137.629646 -412.570168)
				(end 137.888726 -412.570168)
			)
		)
		(stroke
			(width 0)
			(type solid)
		)
		(fill yes)
		(layer "In2.Cu")
		(net "GND")
	)
	(gr_poly
		(pts
			(arc
				(start 137.888726 -404.46452)
				(mid 137.629646 -404.46452)
				(end 137.888726 -404.46452)
			)
		)
		(stroke
			(width 0)
			(type solid)
		)
		(fill yes)
		(layer "In2.Cu")
		(net "GND")
	)
	(gr_poly
		(pts
			(arc
				(start 138.79068 -19.689064)
				(mid 138.5443 -19.689064)
				(end 138.79068 -19.689064)
			)
		)
		(stroke
			(width 0)
			(type solid)
		)
		(fill yes)
		(layer "In2.Cu")
		(net "GND")
	)
	(gr_poly
		(pts
			(arc
				(start 138.970766 -412.570168)
				(mid 138.711686 -412.570168)
				(end 138.970766 -412.570168)
			)
		)
		(stroke
			(width 0)
			(type solid)
		)
		(fill yes)
		(layer "In2.Cu")
		(net "GND")
	)
	(gr_poly
		(pts
			(arc
				(start 138.970766 -404.46452)
				(mid 138.711686 -404.46452)
				(end 138.970766 -404.46452)
			)
		)
		(stroke
			(width 0)
			(type solid)
		)
		(fill yes)
		(layer "In2.Cu")
		(net "GND")
	)
	(gr_poly
		(pts
			(arc
				(start 139.059158 -410.664152)
				(mid 138.800078 -410.664152)
				(end 139.059158 -410.664152)
			)
		)
		(stroke
			(width 0)
			(type solid)
		)
		(fill yes)
		(layer "In2.Cu")
		(net "GND")
	)
	(gr_poly
		(pts
			(arc
				(start 139.059158 -409.396184)
				(mid 138.800078 -409.396184)
				(end 139.059158 -409.396184)
			)
		)
		(stroke
			(width 0)
			(type solid)
		)
		(fill yes)
		(layer "In2.Cu")
		(net "GND")
	)
	(gr_poly
		(pts
			(arc
				(start 139.059158 -407.638504)
				(mid 138.800078 -407.638504)
				(end 139.059158 -407.638504)
			)
		)
		(stroke
			(width 0)
			(type solid)
		)
		(fill yes)
		(layer "In2.Cu")
		(net "GND")
	)
	(gr_poly
		(pts
			(arc
				(start 139.059158 -406.370536)
				(mid 138.800078 -406.370536)
				(end 139.059158 -406.370536)
			)
		)
		(stroke
			(width 0)
			(type solid)
		)
		(fill yes)
		(layer "In2.Cu")
		(net "GND")
	)
	(gr_poly
		(pts
			(arc
				(start 139.331954 -413.204152)
				(mid 139.072874 -413.204152)
				(end 139.331954 -413.204152)
			)
		)
		(stroke
			(width 0)
			(type solid)
		)
		(fill yes)
		(layer "In2.Cu")
		(net "GND")
	)
	(gr_poly
		(pts
			(arc
				(start 139.331954 -411.936184)
				(mid 139.072874 -411.936184)
				(end 139.331954 -411.936184)
			)
		)
		(stroke
			(width 0)
			(type solid)
		)
		(fill yes)
		(layer "In2.Cu")
		(net "GND")
	)
	(gr_poly
		(pts
			(arc
				(start 139.331954 -405.098504)
				(mid 139.072874 -405.098504)
				(end 139.331954 -405.098504)
			)
		)
		(stroke
			(width 0)
			(type solid)
		)
		(fill yes)
		(layer "In2.Cu")
		(net "GND")
	)
	(gr_poly
		(pts
			(arc
				(start 139.331954 -403.830536)
				(mid 139.072874 -403.830536)
				(end 139.331954 -403.830536)
			)
		)
		(stroke
			(width 0)
			(type solid)
		)
		(fill yes)
		(layer "In2.Cu")
		(net "GND")
	)
	(gr_poly
		(pts
			(arc
				(start 139.420346 -410.030168)
				(mid 139.161266 -410.030168)
				(end 139.420346 -410.030168)
			)
		)
		(stroke
			(width 0)
			(type solid)
		)
		(fill yes)
		(layer "In2.Cu")
		(net "GND")
	)
	(gr_poly
		(pts
			(arc
				(start 139.420346 -407.00452)
				(mid 139.161266 -407.00452)
				(end 139.420346 -407.00452)
			)
		)
		(stroke
			(width 0)
			(type solid)
		)
		(fill yes)
		(layer "In2.Cu")
		(net "GND")
	)
	(gr_poly
		(pts
			(arc
				(start 140.502386 -410.030168)
				(mid 140.243306 -410.030168)
				(end 140.502386 -410.030168)
			)
		)
		(stroke
			(width 0)
			(type solid)
		)
		(fill yes)
		(layer "In2.Cu")
		(net "GND")
	)
	(gr_poly
		(pts
			(arc
				(start 140.502386 -407.00452)
				(mid 140.243306 -407.00452)
				(end 140.502386 -407.00452)
			)
		)
		(stroke
			(width 0)
			(type solid)
		)
		(fill yes)
		(layer "In2.Cu")
		(net "GND")
	)
	(gr_poly
		(pts
			(arc
				(start 140.590778 -413.204152)
				(mid 140.331698 -413.204152)
				(end 140.590778 -413.204152)
			)
		)
		(stroke
			(width 0)
			(type solid)
		)
		(fill yes)
		(layer "In2.Cu")
		(net "GND")
	)
	(gr_poly
		(pts
			(arc
				(start 140.590778 -411.936184)
				(mid 140.331698 -411.936184)
				(end 140.590778 -411.936184)
			)
		)
		(stroke
			(width 0)
			(type solid)
		)
		(fill yes)
		(layer "In2.Cu")
		(net "GND")
	)
	(gr_poly
		(pts
			(arc
				(start 140.590778 -405.098504)
				(mid 140.331698 -405.098504)
				(end 140.590778 -405.098504)
			)
		)
		(stroke
			(width 0)
			(type solid)
		)
		(fill yes)
		(layer "In2.Cu")
		(net "GND")
	)
	(gr_poly
		(pts
			(arc
				(start 140.590778 -403.830536)
				(mid 140.331698 -403.830536)
				(end 140.590778 -403.830536)
			)
		)
		(stroke
			(width 0)
			(type solid)
		)
		(fill yes)
		(layer "In2.Cu")
		(net "GND")
	)
	(gr_poly
		(pts
			(arc
				(start 140.793978 -19.689064)
				(mid 140.54709 -19.689064)
				(end 140.793978 -19.689064)
			)
		)
		(stroke
			(width 0)
			(type solid)
		)
		(fill yes)
		(layer "In2.Cu")
		(net "GND")
	)
	(gr_poly
		(pts
			(arc
				(start 140.863574 -410.664152)
				(mid 140.604494 -410.664152)
				(end 140.863574 -410.664152)
			)
		)
		(stroke
			(width 0)
			(type solid)
		)
		(fill yes)
		(layer "In2.Cu")
		(net "GND")
	)
	(gr_poly
		(pts
			(arc
				(start 140.863574 -409.396184)
				(mid 140.604494 -409.396184)
				(end 140.863574 -409.396184)
			)
		)
		(stroke
			(width 0)
			(type solid)
		)
		(fill yes)
		(layer "In2.Cu")
		(net "GND")
	)
	(gr_poly
		(pts
			(arc
				(start 140.863574 -407.638504)
				(mid 140.604494 -407.638504)
				(end 140.863574 -407.638504)
			)
		)
		(stroke
			(width 0)
			(type solid)
		)
		(fill yes)
		(layer "In2.Cu")
		(net "GND")
	)
	(gr_poly
		(pts
			(arc
				(start 140.863574 -406.370536)
				(mid 140.604494 -406.370536)
				(end 140.863574 -406.370536)
			)
		)
		(stroke
			(width 0)
			(type solid)
		)
		(fill yes)
		(layer "In2.Cu")
		(net "GND")
	)
	(gr_poly
		(pts
			(arc
				(start 140.951966 -412.570168)
				(mid 140.692886 -412.570168)
				(end 140.951966 -412.570168)
			)
		)
		(stroke
			(width 0)
			(type solid)
		)
		(fill yes)
		(layer "In2.Cu")
		(net "GND")
	)
	(gr_poly
		(pts
			(arc
				(start 140.951966 -404.46452)
				(mid 140.692886 -404.46452)
				(end 140.951966 -404.46452)
			)
		)
		(stroke
			(width 0)
			(type solid)
		)
		(fill yes)
		(layer "In2.Cu")
		(net "GND")
	)
	(gr_poly
		(pts
			(arc
				(start 142.034006 -412.570168)
				(mid 141.774926 -412.570168)
				(end 142.034006 -412.570168)
			)
		)
		(stroke
			(width 0)
			(type solid)
		)
		(fill yes)
		(layer "In2.Cu")
		(net "GND")
	)
	(gr_poly
		(pts
			(arc
				(start 142.034006 -404.46452)
				(mid 141.774926 -404.46452)
				(end 142.034006 -404.46452)
			)
		)
		(stroke
			(width 0)
			(type solid)
		)
		(fill yes)
		(layer "In2.Cu")
		(net "GND")
	)
	(gr_poly
		(pts
			(arc
				(start 142.122398 -410.664152)
				(mid 141.863318 -410.664152)
				(end 142.122398 -410.664152)
			)
		)
		(stroke
			(width 0)
			(type solid)
		)
		(fill yes)
		(layer "In2.Cu")
		(net "GND")
	)
	(gr_poly
		(pts
			(arc
				(start 142.122398 -409.396184)
				(mid 141.863318 -409.396184)
				(end 142.122398 -409.396184)
			)
		)
		(stroke
			(width 0)
			(type solid)
		)
		(fill yes)
		(layer "In2.Cu")
		(net "GND")
	)
	(gr_poly
		(pts
			(arc
				(start 142.122398 -407.638504)
				(mid 141.863318 -407.638504)
				(end 142.122398 -407.638504)
			)
		)
		(stroke
			(width 0)
			(type solid)
		)
		(fill yes)
		(layer "In2.Cu")
		(net "GND")
	)
	(gr_poly
		(pts
			(arc
				(start 142.122398 -406.370536)
				(mid 141.863318 -406.370536)
				(end 142.122398 -406.370536)
			)
		)
		(stroke
			(width 0)
			(type solid)
		)
		(fill yes)
		(layer "In2.Cu")
		(net "GND")
	)
	(gr_poly
		(pts
			(arc
				(start 142.395194 -413.204152)
				(mid 142.136114 -413.204152)
				(end 142.395194 -413.204152)
			)
		)
		(stroke
			(width 0)
			(type solid)
		)
		(fill yes)
		(layer "In2.Cu")
		(net "GND")
	)
	(gr_poly
		(pts
			(arc
				(start 142.395194 -411.936184)
				(mid 142.136114 -411.936184)
				(end 142.395194 -411.936184)
			)
		)
		(stroke
			(width 0)
			(type solid)
		)
		(fill yes)
		(layer "In2.Cu")
		(net "GND")
	)
	(gr_poly
		(pts
			(arc
				(start 142.395194 -405.098504)
				(mid 142.136114 -405.098504)
				(end 142.395194 -405.098504)
			)
		)
		(stroke
			(width 0)
			(type solid)
		)
		(fill yes)
		(layer "In2.Cu")
		(net "GND")
	)
	(gr_poly
		(pts
			(arc
				(start 142.395194 -403.830536)
				(mid 142.136114 -403.830536)
				(end 142.395194 -403.830536)
			)
		)
		(stroke
			(width 0)
			(type solid)
		)
		(fill yes)
		(layer "In2.Cu")
		(net "GND")
	)
	(gr_poly
		(pts
			(arc
				(start 142.483586 -410.030168)
				(mid 142.224506 -410.030168)
				(end 142.483586 -410.030168)
			)
		)
		(stroke
			(width 0)
			(type solid)
		)
		(fill yes)
		(layer "In2.Cu")
		(net "GND")
	)
	(gr_poly
		(pts
			(arc
				(start 142.483586 -407.00452)
				(mid 142.224506 -407.00452)
				(end 142.483586 -407.00452)
			)
		)
		(stroke
			(width 0)
			(type solid)
		)
		(fill yes)
		(layer "In2.Cu")
		(net "GND")
	)
	(gr_poly
		(pts
			(arc
				(start 143.565626 -410.030168)
				(mid 143.306546 -410.030168)
				(end 143.565626 -410.030168)
			)
		)
		(stroke
			(width 0)
			(type solid)
		)
		(fill yes)
		(layer "In2.Cu")
		(net "GND")
	)
	(gr_poly
		(pts
			(arc
				(start 143.565626 -407.00452)
				(mid 143.306546 -407.00452)
				(end 143.565626 -407.00452)
			)
		)
		(stroke
			(width 0)
			(type solid)
		)
		(fill yes)
		(layer "In2.Cu")
		(net "GND")
	)
	(gr_poly
		(pts
			(arc
				(start 143.654018 -413.204152)
				(mid 143.394938 -413.204152)
				(end 143.654018 -413.204152)
			)
		)
		(stroke
			(width 0)
			(type solid)
		)
		(fill yes)
		(layer "In2.Cu")
		(net "GND")
	)
	(gr_poly
		(pts
			(arc
				(start 143.654018 -411.936184)
				(mid 143.394938 -411.936184)
				(end 143.654018 -411.936184)
			)
		)
		(stroke
			(width 0)
			(type solid)
		)
		(fill yes)
		(layer "In2.Cu")
		(net "GND")
	)
	(gr_poly
		(pts
			(arc
				(start 143.654018 -405.098504)
				(mid 143.394938 -405.098504)
				(end 143.654018 -405.098504)
			)
		)
		(stroke
			(width 0)
			(type solid)
		)
		(fill yes)
		(layer "In2.Cu")
		(net "GND")
	)
	(gr_poly
		(pts
			(arc
				(start 143.654018 -403.830536)
				(mid 143.394938 -403.830536)
				(end 143.654018 -403.830536)
			)
		)
		(stroke
			(width 0)
			(type solid)
		)
		(fill yes)
		(layer "In2.Cu")
		(net "GND")
	)
	(gr_poly
		(pts
			(arc
				(start 143.926814 -410.664152)
				(mid 143.667734 -410.664152)
				(end 143.926814 -410.664152)
			)
		)
		(stroke
			(width 0)
			(type solid)
		)
		(fill yes)
		(layer "In2.Cu")
		(net "GND")
	)
	(gr_poly
		(pts
			(arc
				(start 143.926814 -409.396184)
				(mid 143.667734 -409.396184)
				(end 143.926814 -409.396184)
			)
		)
		(stroke
			(width 0)
			(type solid)
		)
		(fill yes)
		(layer "In2.Cu")
		(net "GND")
	)
	(gr_poly
		(pts
			(arc
				(start 143.926814 -407.638504)
				(mid 143.667734 -407.638504)
				(end 143.926814 -407.638504)
			)
		)
		(stroke
			(width 0)
			(type solid)
		)
		(fill yes)
		(layer "In2.Cu")
		(net "GND")
	)
	(gr_poly
		(pts
			(arc
				(start 143.926814 -406.370536)
				(mid 143.667734 -406.370536)
				(end 143.926814 -406.370536)
			)
		)
		(stroke
			(width 0)
			(type solid)
		)
		(fill yes)
		(layer "In2.Cu")
		(net "GND")
	)
	(gr_poly
		(pts
			(arc
				(start 144.015206 -412.570168)
				(mid 143.756126 -412.570168)
				(end 144.015206 -412.570168)
			)
		)
		(stroke
			(width 0)
			(type solid)
		)
		(fill yes)
		(layer "In2.Cu")
		(net "GND")
	)
	(gr_poly
		(pts
			(arc
				(start 144.015206 -404.46452)
				(mid 143.756126 -404.46452)
				(end 144.015206 -404.46452)
			)
		)
		(stroke
			(width 0)
			(type solid)
		)
		(fill yes)
		(layer "In2.Cu")
		(net "GND")
	)
	(gr_poly
		(pts
			(arc
				(start 145.097246 -412.570168)
				(mid 144.838166 -412.570168)
				(end 145.097246 -412.570168)
			)
		)
		(stroke
			(width 0)
			(type solid)
		)
		(fill yes)
		(layer "In2.Cu")
		(net "GND")
	)
	(gr_poly
		(pts
			(arc
				(start 145.097246 -404.46452)
				(mid 144.838166 -404.46452)
				(end 145.097246 -404.46452)
			)
		)
		(stroke
			(width 0)
			(type solid)
		)
		(fill yes)
		(layer "In2.Cu")
		(net "GND")
	)
	(gr_poly
		(pts
			(arc
				(start 145.185638 -410.664152)
				(mid 144.926558 -410.664152)
				(end 145.185638 -410.664152)
			)
		)
		(stroke
			(width 0)
			(type solid)
		)
		(fill yes)
		(layer "In2.Cu")
		(net "GND")
	)
	(gr_poly
		(pts
			(arc
				(start 145.185638 -409.396184)
				(mid 144.926558 -409.396184)
				(end 145.185638 -409.396184)
			)
		)
		(stroke
			(width 0)
			(type solid)
		)
		(fill yes)
		(layer "In2.Cu")
		(net "GND")
	)
	(gr_poly
		(pts
			(arc
				(start 145.185638 -407.638504)
				(mid 144.926558 -407.638504)
				(end 145.185638 -407.638504)
			)
		)
		(stroke
			(width 0)
			(type solid)
		)
		(fill yes)
		(layer "In2.Cu")
		(net "GND")
	)
	(gr_poly
		(pts
			(arc
				(start 145.185638 -406.370536)
				(mid 144.926558 -406.370536)
				(end 145.185638 -406.370536)
			)
		)
		(stroke
			(width 0)
			(type solid)
		)
		(fill yes)
		(layer "In2.Cu")
		(net "GND")
	)
	(gr_poly
		(pts
			(arc
				(start 145.458434 -413.204152)
				(mid 145.199354 -413.204152)
				(end 145.458434 -413.204152)
			)
		)
		(stroke
			(width 0)
			(type solid)
		)
		(fill yes)
		(layer "In2.Cu")
		(net "GND")
	)
	(gr_poly
		(pts
			(arc
				(start 145.458434 -411.936184)
				(mid 145.199354 -411.936184)
				(end 145.458434 -411.936184)
			)
		)
		(stroke
			(width 0)
			(type solid)
		)
		(fill yes)
		(layer "In2.Cu")
		(net "GND")
	)
	(gr_poly
		(pts
			(arc
				(start 145.458434 -405.098504)
				(mid 145.199354 -405.098504)
				(end 145.458434 -405.098504)
			)
		)
		(stroke
			(width 0)
			(type solid)
		)
		(fill yes)
		(layer "In2.Cu")
		(net "GND")
	)
	(gr_poly
		(pts
			(arc
				(start 145.458434 -403.830536)
				(mid 145.199354 -403.830536)
				(end 145.458434 -403.830536)
			)
		)
		(stroke
			(width 0)
			(type solid)
		)
		(fill yes)
		(layer "In2.Cu")
		(net "GND")
	)
	(gr_poly
		(pts
			(arc
				(start 145.546826 -410.030168)
				(mid 145.287746 -410.030168)
				(end 145.546826 -410.030168)
			)
		)
		(stroke
			(width 0)
			(type solid)
		)
		(fill yes)
		(layer "In2.Cu")
		(net "GND")
	)
	(gr_poly
		(pts
			(arc
				(start 145.546826 -407.00452)
				(mid 145.287746 -407.00452)
				(end 145.546826 -407.00452)
			)
		)
		(stroke
			(width 0)
			(type solid)
		)
		(fill yes)
		(layer "In2.Cu")
		(net "GND")
	)
	(gr_poly
		(pts
			(arc
				(start 146.628866 -410.030168)
				(mid 146.369786 -410.030168)
				(end 146.628866 -410.030168)
			)
		)
		(stroke
			(width 0)
			(type solid)
		)
		(fill yes)
		(layer "In2.Cu")
		(net "GND")
	)
	(gr_poly
		(pts
			(arc
				(start 146.628866 -407.00452)
				(mid 146.369786 -407.00452)
				(end 146.628866 -407.00452)
			)
		)
		(stroke
			(width 0)
			(type solid)
		)
		(fill yes)
		(layer "In2.Cu")
		(net "GND")
	)
	(gr_poly
		(pts
			(arc
				(start 146.717258 -413.204152)
				(mid 146.458178 -413.204152)
				(end 146.717258 -413.204152)
			)
		)
		(stroke
			(width 0)
			(type solid)
		)
		(fill yes)
		(layer "In2.Cu")
		(net "GND")
	)
	(gr_poly
		(pts
			(arc
				(start 146.717258 -411.936184)
				(mid 146.458178 -411.936184)
				(end 146.717258 -411.936184)
			)
		)
		(stroke
			(width 0)
			(type solid)
		)
		(fill yes)
		(layer "In2.Cu")
		(net "GND")
	)
	(gr_poly
		(pts
			(arc
				(start 146.717258 -405.098504)
				(mid 146.458178 -405.098504)
				(end 146.717258 -405.098504)
			)
		)
		(stroke
			(width 0)
			(type solid)
		)
		(fill yes)
		(layer "In2.Cu")
		(net "GND")
	)
	(gr_poly
		(pts
			(arc
				(start 146.717258 -403.830536)
				(mid 146.458178 -403.830536)
				(end 146.717258 -403.830536)
			)
		)
		(stroke
			(width 0)
			(type solid)
		)
		(fill yes)
		(layer "In2.Cu")
		(net "GND")
	)
	(gr_poly
		(pts
			(arc
				(start 146.990054 -410.664152)
				(mid 146.730974 -410.664152)
				(end 146.990054 -410.664152)
			)
		)
		(stroke
			(width 0)
			(type solid)
		)
		(fill yes)
		(layer "In2.Cu")
		(net "GND")
	)
	(gr_poly
		(pts
			(arc
				(start 146.990054 -409.396184)
				(mid 146.730974 -409.396184)
				(end 146.990054 -409.396184)
			)
		)
		(stroke
			(width 0)
			(type solid)
		)
		(fill yes)
		(layer "In2.Cu")
		(net "GND")
	)
	(gr_poly
		(pts
			(arc
				(start 146.990054 -407.638504)
				(mid 146.730974 -407.638504)
				(end 146.990054 -407.638504)
			)
		)
		(stroke
			(width 0)
			(type solid)
		)
		(fill yes)
		(layer "In2.Cu")
		(net "GND")
	)
	(gr_poly
		(pts
			(arc
				(start 146.990054 -406.370536)
				(mid 146.730974 -406.370536)
				(end 146.990054 -406.370536)
			)
		)
		(stroke
			(width 0)
			(type solid)
		)
		(fill yes)
		(layer "In2.Cu")
		(net "GND")
	)
	(gr_poly
		(pts
			(arc
				(start 147.078446 -412.570168)
				(mid 146.819366 -412.570168)
				(end 147.078446 -412.570168)
			)
		)
		(stroke
			(width 0)
			(type solid)
		)
		(fill yes)
		(layer "In2.Cu")
		(net "GND")
	)
	(gr_poly
		(pts
			(arc
				(start 147.078446 -404.46452)
				(mid 146.819366 -404.46452)
				(end 147.078446 -404.46452)
			)
		)
		(stroke
			(width 0)
			(type solid)
		)
		(fill yes)
		(layer "In2.Cu")
		(net "GND")
	)
	(gr_poly
		(pts
			(arc
				(start 148.160486 -412.570168)
				(mid 147.901406 -412.570168)
				(end 148.160486 -412.570168)
			)
		)
		(stroke
			(width 0)
			(type solid)
		)
		(fill yes)
		(layer "In2.Cu")
		(net "GND")
	)
	(gr_poly
		(pts
			(arc
				(start 148.160486 -404.46452)
				(mid 147.901406 -404.46452)
				(end 148.160486 -404.46452)
			)
		)
		(stroke
			(width 0)
			(type solid)
		)
		(fill yes)
		(layer "In2.Cu")
		(net "GND")
	)
	(gr_poly
		(pts
			(arc
				(start 148.248878 -410.664152)
				(mid 147.989798 -410.664152)
				(end 148.248878 -410.664152)
			)
		)
		(stroke
			(width 0)
			(type solid)
		)
		(fill yes)
		(layer "In2.Cu")
		(net "GND")
	)
	(gr_poly
		(pts
			(arc
				(start 148.248878 -409.396184)
				(mid 147.989798 -409.396184)
				(end 148.248878 -409.396184)
			)
		)
		(stroke
			(width 0)
			(type solid)
		)
		(fill yes)
		(layer "In2.Cu")
		(net "GND")
	)
	(gr_poly
		(pts
			(arc
				(start 148.248878 -407.638504)
				(mid 147.989798 -407.638504)
				(end 148.248878 -407.638504)
			)
		)
		(stroke
			(width 0)
			(type solid)
		)
		(fill yes)
		(layer "In2.Cu")
		(net "GND")
	)
	(gr_poly
		(pts
			(arc
				(start 148.248878 -406.370536)
				(mid 147.989798 -406.370536)
				(end 148.248878 -406.370536)
			)
		)
		(stroke
			(width 0)
			(type solid)
		)
		(fill yes)
		(layer "In2.Cu")
		(net "GND")
	)
	(gr_poly
		(pts
			(arc
				(start 148.521674 -413.204152)
				(mid 148.262594 -413.204152)
				(end 148.521674 -413.204152)
			)
		)
		(stroke
			(width 0)
			(type solid)
		)
		(fill yes)
		(layer "In2.Cu")
		(net "GND")
	)
	(gr_poly
		(pts
			(arc
				(start 148.521674 -411.936184)
				(mid 148.262594 -411.936184)
				(end 148.521674 -411.936184)
			)
		)
		(stroke
			(width 0)
			(type solid)
		)
		(fill yes)
		(layer "In2.Cu")
		(net "GND")
	)
	(gr_poly
		(pts
			(arc
				(start 148.521674 -405.098504)
				(mid 148.262594 -405.098504)
				(end 148.521674 -405.098504)
			)
		)
		(stroke
			(width 0)
			(type solid)
		)
		(fill yes)
		(layer "In2.Cu")
		(net "GND")
	)
	(gr_poly
		(pts
			(arc
				(start 148.521674 -403.830536)
				(mid 148.262594 -403.830536)
				(end 148.521674 -403.830536)
			)
		)
		(stroke
			(width 0)
			(type solid)
		)
		(fill yes)
		(layer "In2.Cu")
		(net "GND")
	)
	(gr_poly
		(pts
			(arc
				(start 148.610066 -410.030168)
				(mid 148.350986 -410.030168)
				(end 148.610066 -410.030168)
			)
		)
		(stroke
			(width 0)
			(type solid)
		)
		(fill yes)
		(layer "In2.Cu")
		(net "GND")
	)
	(gr_poly
		(pts
			(arc
				(start 148.610066 -407.00452)
				(mid 148.350986 -407.00452)
				(end 148.610066 -407.00452)
			)
		)
		(stroke
			(width 0)
			(type solid)
		)
		(fill yes)
		(layer "In2.Cu")
		(net "GND")
	)
	(gr_poly
		(pts
			(arc
				(start 149.692106 -410.030168)
				(mid 149.433026 -410.030168)
				(end 149.692106 -410.030168)
			)
		)
		(stroke
			(width 0)
			(type solid)
		)
		(fill yes)
		(layer "In2.Cu")
		(net "GND")
	)
	(gr_poly
		(pts
			(arc
				(start 149.692106 -407.00452)
				(mid 149.433026 -407.00452)
				(end 149.692106 -407.00452)
			)
		)
		(stroke
			(width 0)
			(type solid)
		)
		(fill yes)
		(layer "In2.Cu")
		(net "GND")
	)
	(gr_poly
		(pts
			(arc
				(start 149.780498 -413.204152)
				(mid 149.521418 -413.204152)
				(end 149.780498 -413.204152)
			)
		)
		(stroke
			(width 0)
			(type solid)
		)
		(fill yes)
		(layer "In2.Cu")
		(net "GND")
	)
	(gr_poly
		(pts
			(arc
				(start 149.780498 -411.936184)
				(mid 149.521418 -411.936184)
				(end 149.780498 -411.936184)
			)
		)
		(stroke
			(width 0)
			(type solid)
		)
		(fill yes)
		(layer "In2.Cu")
		(net "GND")
	)
	(gr_poly
		(pts
			(arc
				(start 149.780498 -405.098504)
				(mid 149.521418 -405.098504)
				(end 149.780498 -405.098504)
			)
		)
		(stroke
			(width 0)
			(type solid)
		)
		(fill yes)
		(layer "In2.Cu")
		(net "GND")
	)
	(gr_poly
		(pts
			(arc
				(start 149.780498 -403.830536)
				(mid 149.521418 -403.830536)
				(end 149.780498 -403.830536)
			)
		)
		(stroke
			(width 0)
			(type solid)
		)
		(fill yes)
		(layer "In2.Cu")
		(net "GND")
	)
	(gr_poly
		(pts
			(arc
				(start 150.053294 -410.664152)
				(mid 149.794214 -410.664152)
				(end 150.053294 -410.664152)
			)
		)
		(stroke
			(width 0)
			(type solid)
		)
		(fill yes)
		(layer "In2.Cu")
		(net "GND")
	)
	(gr_poly
		(pts
			(arc
				(start 150.053294 -409.396184)
				(mid 149.794214 -409.396184)
				(end 150.053294 -409.396184)
			)
		)
		(stroke
			(width 0)
			(type solid)
		)
		(fill yes)
		(layer "In2.Cu")
		(net "GND")
	)
	(gr_poly
		(pts
			(arc
				(start 150.053294 -407.638504)
				(mid 149.794214 -407.638504)
				(end 150.053294 -407.638504)
			)
		)
		(stroke
			(width 0)
			(type solid)
		)
		(fill yes)
		(layer "In2.Cu")
		(net "GND")
	)
	(gr_poly
		(pts
			(arc
				(start 150.053294 -406.370536)
				(mid 149.794214 -406.370536)
				(end 150.053294 -406.370536)
			)
		)
		(stroke
			(width 0)
			(type solid)
		)
		(fill yes)
		(layer "In2.Cu")
		(net "GND")
	)
	(gr_poly
		(pts
			(arc
				(start 150.141686 -412.570168)
				(mid 149.882606 -412.570168)
				(end 150.141686 -412.570168)
			)
		)
		(stroke
			(width 0)
			(type solid)
		)
		(fill yes)
		(layer "In2.Cu")
		(net "GND")
	)
	(gr_poly
		(pts
			(arc
				(start 150.141686 -404.46452)
				(mid 149.882606 -404.46452)
				(end 150.141686 -404.46452)
			)
		)
		(stroke
			(width 0)
			(type solid)
		)
		(fill yes)
		(layer "In2.Cu")
		(net "GND")
	)
	(gr_poly
		(pts
			(arc
				(start 151.223726 -412.570168)
				(mid 150.964646 -412.570168)
				(end 151.223726 -412.570168)
			)
		)
		(stroke
			(width 0)
			(type solid)
		)
		(fill yes)
		(layer "In2.Cu")
		(net "GND")
	)
	(gr_poly
		(pts
			(arc
				(start 151.223726 -404.46452)
				(mid 150.964646 -404.46452)
				(end 151.223726 -404.46452)
			)
		)
		(stroke
			(width 0)
			(type solid)
		)
		(fill yes)
		(layer "In2.Cu")
		(net "GND")
	)
	(gr_poly
		(pts
			(arc
				(start 151.312118 -410.664152)
				(mid 151.053038 -410.664152)
				(end 151.312118 -410.664152)
			)
		)
		(stroke
			(width 0)
			(type solid)
		)
		(fill yes)
		(layer "In2.Cu")
		(net "GND")
	)
	(gr_poly
		(pts
			(arc
				(start 151.312118 -409.396184)
				(mid 151.053038 -409.396184)
				(end 151.312118 -409.396184)
			)
		)
		(stroke
			(width 0)
			(type solid)
		)
		(fill yes)
		(layer "In2.Cu")
		(net "GND")
	)
	(gr_poly
		(pts
			(arc
				(start 151.312118 -407.638504)
				(mid 151.053038 -407.638504)
				(end 151.312118 -407.638504)
			)
		)
		(stroke
			(width 0)
			(type solid)
		)
		(fill yes)
		(layer "In2.Cu")
		(net "GND")
	)
	(gr_poly
		(pts
			(arc
				(start 151.312118 -406.370536)
				(mid 151.053038 -406.370536)
				(end 151.312118 -406.370536)
			)
		)
		(stroke
			(width 0)
			(type solid)
		)
		(fill yes)
		(layer "In2.Cu")
		(net "GND")
	)
	(gr_poly
		(pts
			(arc
				(start 151.584914 -413.204152)
				(mid 151.325834 -413.204152)
				(end 151.584914 -413.204152)
			)
		)
		(stroke
			(width 0)
			(type solid)
		)
		(fill yes)
		(layer "In2.Cu")
		(net "GND")
	)
	(gr_poly
		(pts
			(arc
				(start 151.584914 -411.936184)
				(mid 151.325834 -411.936184)
				(end 151.584914 -411.936184)
			)
		)
		(stroke
			(width 0)
			(type solid)
		)
		(fill yes)
		(layer "In2.Cu")
		(net "GND")
	)
	(gr_poly
		(pts
			(arc
				(start 151.584914 -405.098504)
				(mid 151.325834 -405.098504)
				(end 151.584914 -405.098504)
			)
		)
		(stroke
			(width 0)
			(type solid)
		)
		(fill yes)
		(layer "In2.Cu")
		(net "GND")
	)
	(gr_poly
		(pts
			(arc
				(start 151.584914 -403.830536)
				(mid 151.325834 -403.830536)
				(end 151.584914 -403.830536)
			)
		)
		(stroke
			(width 0)
			(type solid)
		)
		(fill yes)
		(layer "In2.Cu")
		(net "GND")
	)
	(gr_poly
		(pts
			(arc
				(start 151.673306 -410.030168)
				(mid 151.414226 -410.030168)
				(end 151.673306 -410.030168)
			)
		)
		(stroke
			(width 0)
			(type solid)
		)
		(fill yes)
		(layer "In2.Cu")
		(net "GND")
	)
	(gr_poly
		(pts
			(arc
				(start 151.673306 -407.00452)
				(mid 151.414226 -407.00452)
				(end 151.673306 -407.00452)
			)
		)
		(stroke
			(width 0)
			(type solid)
		)
		(fill yes)
		(layer "In2.Cu")
		(net "GND")
	)
	(gr_poly
		(pts
			(arc
				(start 152.755346 -410.030168)
				(mid 152.496266 -410.030168)
				(end 152.755346 -410.030168)
			)
		)
		(stroke
			(width 0)
			(type solid)
		)
		(fill yes)
		(layer "In2.Cu")
		(net "GND")
	)
	(gr_poly
		(pts
			(arc
				(start 152.755346 -407.00452)
				(mid 152.496266 -407.00452)
				(end 152.755346 -407.00452)
			)
		)
		(stroke
			(width 0)
			(type solid)
		)
		(fill yes)
		(layer "In2.Cu")
		(net "GND")
	)
	(gr_poly
		(pts
			(arc
				(start 152.843738 -411.936184)
				(mid 152.584658 -411.936184)
				(end 152.843738 -411.936184)
			)
		)
		(stroke
			(width 0)
			(type solid)
		)
		(fill yes)
		(layer "In2.Cu")
		(net "GND")
	)
	(gr_poly
		(pts
			(arc
				(start 152.843738 -405.098504)
				(mid 152.584658 -405.098504)
				(end 152.843738 -405.098504)
			)
		)
		(stroke
			(width 0)
			(type solid)
		)
		(fill yes)
		(layer "In2.Cu")
		(net "GND")
	)
	(gr_poly
		(pts
			(arc
				(start 152.843738 -403.830536)
				(mid 152.584658 -403.830536)
				(end 152.843738 -403.830536)
			)
		)
		(stroke
			(width 0)
			(type solid)
		)
		(fill yes)
		(layer "In2.Cu")
		(net "GND")
	)
	(gr_poly
		(pts
			(arc
				(start 153.116534 -410.664152)
				(mid 152.857454 -410.664152)
				(end 153.116534 -410.664152)
			)
		)
		(stroke
			(width 0)
			(type solid)
		)
		(fill yes)
		(layer "In2.Cu")
		(net "GND")
	)
	(gr_poly
		(pts
			(arc
				(start 153.116534 -409.396184)
				(mid 152.857454 -409.396184)
				(end 153.116534 -409.396184)
			)
		)
		(stroke
			(width 0)
			(type solid)
		)
		(fill yes)
		(layer "In2.Cu")
		(net "GND")
	)
	(gr_poly
		(pts
			(arc
				(start 153.116534 -407.638504)
				(mid 152.857454 -407.638504)
				(end 153.116534 -407.638504)
			)
		)
		(stroke
			(width 0)
			(type solid)
		)
		(fill yes)
		(layer "In2.Cu")
		(net "GND")
	)
	(gr_poly
		(pts
			(arc
				(start 153.116534 -406.370536)
				(mid 152.857454 -406.370536)
				(end 153.116534 -406.370536)
			)
		)
		(stroke
			(width 0)
			(type solid)
		)
		(fill yes)
		(layer "In2.Cu")
		(net "GND")
	)
	(gr_poly
		(pts
			(arc
				(start 153.204926 -412.570168)
				(mid 152.945846 -412.570168)
				(end 153.204926 -412.570168)
			)
		)
		(stroke
			(width 0)
			(type solid)
		)
		(fill yes)
		(layer "In2.Cu")
		(net "GND")
	)
	(gr_poly
		(pts
			(arc
				(start 153.204926 -404.46452)
				(mid 152.945846 -404.46452)
				(end 153.204926 -404.46452)
			)
		)
		(stroke
			(width 0)
			(type solid)
		)
		(fill yes)
		(layer "In2.Cu")
		(net "GND")
	)
	(gr_poly
		(pts
			(arc
				(start 154.286966 -404.46452)
				(mid 154.027886 -404.46452)
				(end 154.286966 -404.46452)
			)
		)
		(stroke
			(width 0)
			(type solid)
		)
		(fill yes)
		(layer "In2.Cu")
		(net "GND")
	)
	(gr_poly
		(pts
			(arc
				(start 154.375358 -410.664152)
				(mid 154.116278 -410.664152)
				(end 154.375358 -410.664152)
			)
		)
		(stroke
			(width 0)
			(type solid)
		)
		(fill yes)
		(layer "In2.Cu")
		(net "GND")
	)
	(gr_poly
		(pts
			(arc
				(start 154.375358 -409.396184)
				(mid 154.116278 -409.396184)
				(end 154.375358 -409.396184)
			)
		)
		(stroke
			(width 0)
			(type solid)
		)
		(fill yes)
		(layer "In2.Cu")
		(net "GND")
	)
	(gr_poly
		(pts
			(arc
				(start 154.375358 -407.638504)
				(mid 154.116278 -407.638504)
				(end 154.375358 -407.638504)
			)
		)
		(stroke
			(width 0)
			(type solid)
		)
		(fill yes)
		(layer "In2.Cu")
		(net "GND")
	)
	(gr_poly
		(pts
			(arc
				(start 154.375358 -406.370536)
				(mid 154.116278 -406.370536)
				(end 154.375358 -406.370536)
			)
		)
		(stroke
			(width 0)
			(type solid)
		)
		(fill yes)
		(layer "In2.Cu")
		(net "GND")
	)
	(gr_poly
		(pts
			(arc
				(start 154.648154 -405.098504)
				(mid 154.389074 -405.098504)
				(end 154.648154 -405.098504)
			)
		)
		(stroke
			(width 0)
			(type solid)
		)
		(fill yes)
		(layer "In2.Cu")
		(net "GND")
	)
	(gr_poly
		(pts
			(arc
				(start 154.648154 -403.830536)
				(mid 154.389074 -403.830536)
				(end 154.648154 -403.830536)
			)
		)
		(stroke
			(width 0)
			(type solid)
		)
		(fill yes)
		(layer "In2.Cu")
		(net "GND")
	)
	(gr_poly
		(pts
			(arc
				(start 154.736546 -410.030168)
				(mid 154.477466 -410.030168)
				(end 154.736546 -410.030168)
			)
		)
		(stroke
			(width 0)
			(type solid)
		)
		(fill yes)
		(layer "In2.Cu")
		(net "GND")
	)
	(gr_poly
		(pts
			(arc
				(start 154.736546 -407.00452)
				(mid 154.477466 -407.00452)
				(end 154.736546 -407.00452)
			)
		)
		(stroke
			(width 0)
			(type solid)
		)
		(fill yes)
		(layer "In2.Cu")
		(net "GND")
	)
	(gr_poly
		(pts
			(arc
				(start 155.818586 -410.030168)
				(mid 155.559506 -410.030168)
				(end 155.818586 -410.030168)
			)
		)
		(stroke
			(width 0)
			(type solid)
		)
		(fill yes)
		(layer "In2.Cu")
		(net "GND")
	)
	(gr_poly
		(pts
			(arc
				(start 155.818586 -407.00452)
				(mid 155.559506 -407.00452)
				(end 155.818586 -407.00452)
			)
		)
		(stroke
			(width 0)
			(type solid)
		)
		(fill yes)
		(layer "In2.Cu")
		(net "GND")
	)
	(gr_poly
		(pts
			(arc
				(start 155.906978 -405.098504)
				(mid 155.647898 -405.098504)
				(end 155.906978 -405.098504)
			)
		)
		(stroke
			(width 0)
			(type solid)
		)
		(fill yes)
		(layer "In2.Cu")
		(net "GND")
	)
	(gr_poly
		(pts
			(arc
				(start 155.906978 -403.830536)
				(mid 155.647898 -403.830536)
				(end 155.906978 -403.830536)
			)
		)
		(stroke
			(width 0)
			(type solid)
		)
		(fill yes)
		(layer "In2.Cu")
		(net "GND")
	)
	(gr_poly
		(pts
			(arc
				(start 156.179774 -410.664152)
				(mid 155.920694 -410.664152)
				(end 156.179774 -410.664152)
			)
		)
		(stroke
			(width 0)
			(type solid)
		)
		(fill yes)
		(layer "In2.Cu")
		(net "GND")
	)
	(gr_poly
		(pts
			(arc
				(start 156.179774 -409.396184)
				(mid 155.920694 -409.396184)
				(end 156.179774 -409.396184)
			)
		)
		(stroke
			(width 0)
			(type solid)
		)
		(fill yes)
		(layer "In2.Cu")
		(net "GND")
	)
	(gr_poly
		(pts
			(arc
				(start 156.179774 -407.638504)
				(mid 155.920694 -407.638504)
				(end 156.179774 -407.638504)
			)
		)
		(stroke
			(width 0)
			(type solid)
		)
		(fill yes)
		(layer "In2.Cu")
		(net "GND")
	)
	(gr_poly
		(pts
			(arc
				(start 156.179774 -406.370536)
				(mid 155.920694 -406.370536)
				(end 156.179774 -406.370536)
			)
		)
		(stroke
			(width 0)
			(type solid)
		)
		(fill yes)
		(layer "In2.Cu")
		(net "GND")
	)
	(gr_poly
		(pts
			(arc
				(start 156.268166 -404.46452)
				(mid 156.009086 -404.46452)
				(end 156.268166 -404.46452)
			)
		)
		(stroke
			(width 0)
			(type solid)
		)
		(fill yes)
		(layer "In2.Cu")
		(net "GND")
	)
	(gr_poly
		(pts
			(arc
				(start 157.350206 -404.46452)
				(mid 157.091126 -404.46452)
				(end 157.350206 -404.46452)
			)
		)
		(stroke
			(width 0)
			(type solid)
		)
		(fill yes)
		(layer "In2.Cu")
		(net "GND")
	)
	(gr_poly
		(pts
			(arc
				(start 157.438598 -410.664152)
				(mid 157.179518 -410.664152)
				(end 157.438598 -410.664152)
			)
		)
		(stroke
			(width 0)
			(type solid)
		)
		(fill yes)
		(layer "In2.Cu")
		(net "GND")
	)
	(gr_poly
		(pts
			(arc
				(start 157.438598 -409.396184)
				(mid 157.179518 -409.396184)
				(end 157.438598 -409.396184)
			)
		)
		(stroke
			(width 0)
			(type solid)
		)
		(fill yes)
		(layer "In2.Cu")
		(net "GND")
	)
	(gr_poly
		(pts
			(arc
				(start 157.438598 -407.638504)
				(mid 157.179518 -407.638504)
				(end 157.438598 -407.638504)
			)
		)
		(stroke
			(width 0)
			(type solid)
		)
		(fill yes)
		(layer "In2.Cu")
		(net "GND")
	)
	(gr_poly
		(pts
			(arc
				(start 157.438598 -406.370536)
				(mid 157.179518 -406.370536)
				(end 157.438598 -406.370536)
			)
		)
		(stroke
			(width 0)
			(type solid)
		)
		(fill yes)
		(layer "In2.Cu")
		(net "GND")
	)
	(gr_poly
		(pts
			(arc
				(start 157.711394 -405.098504)
				(mid 157.452314 -405.098504)
				(end 157.711394 -405.098504)
			)
		)
		(stroke
			(width 0)
			(type solid)
		)
		(fill yes)
		(layer "In2.Cu")
		(net "GND")
	)
	(gr_poly
		(pts
			(arc
				(start 157.711394 -403.830536)
				(mid 157.452314 -403.830536)
				(end 157.711394 -403.830536)
			)
		)
		(stroke
			(width 0)
			(type solid)
		)
		(fill yes)
		(layer "In2.Cu")
		(net "GND")
	)
	(gr_poly
		(pts
			(arc
				(start 157.799786 -410.030168)
				(mid 157.540706 -410.030168)
				(end 157.799786 -410.030168)
			)
		)
		(stroke
			(width 0)
			(type solid)
		)
		(fill yes)
		(layer "In2.Cu")
		(net "GND")
	)
	(gr_poly
		(pts
			(arc
				(start 157.799786 -407.00452)
				(mid 157.540706 -407.00452)
				(end 157.799786 -407.00452)
			)
		)
		(stroke
			(width 0)
			(type solid)
		)
		(fill yes)
		(layer "In2.Cu")
		(net "GND")
	)
	(gr_poly
		(pts
			(arc
				(start 158.881826 -410.030168)
				(mid 158.622746 -410.030168)
				(end 158.881826 -410.030168)
			)
		)
		(stroke
			(width 0)
			(type solid)
		)
		(fill yes)
		(layer "In2.Cu")
		(net "GND")
	)
	(gr_poly
		(pts
			(arc
				(start 158.881826 -407.00452)
				(mid 158.622746 -407.00452)
				(end 158.881826 -407.00452)
			)
		)
		(stroke
			(width 0)
			(type solid)
		)
		(fill yes)
		(layer "In2.Cu")
		(net "GND")
	)
	(gr_poly
		(pts
			(arc
				(start 158.970218 -405.098504)
				(mid 158.711138 -405.098504)
				(end 158.970218 -405.098504)
			)
		)
		(stroke
			(width 0)
			(type solid)
		)
		(fill yes)
		(layer "In2.Cu")
		(net "GND")
	)
	(gr_poly
		(pts
			(arc
				(start 158.970218 -403.830536)
				(mid 158.711138 -403.830536)
				(end 158.970218 -403.830536)
			)
		)
		(stroke
			(width 0)
			(type solid)
		)
		(fill yes)
		(layer "In2.Cu")
		(net "GND")
	)
	(gr_poly
		(pts
			(arc
				(start 159.243014 -410.664152)
				(mid 158.983934 -410.664152)
				(end 159.243014 -410.664152)
			)
		)
		(stroke
			(width 0)
			(type solid)
		)
		(fill yes)
		(layer "In2.Cu")
		(net "GND")
	)
	(gr_poly
		(pts
			(arc
				(start 159.243014 -409.396184)
				(mid 158.983934 -409.396184)
				(end 159.243014 -409.396184)
			)
		)
		(stroke
			(width 0)
			(type solid)
		)
		(fill yes)
		(layer "In2.Cu")
		(net "GND")
	)
	(gr_poly
		(pts
			(arc
				(start 159.243014 -407.638504)
				(mid 158.983934 -407.638504)
				(end 159.243014 -407.638504)
			)
		)
		(stroke
			(width 0)
			(type solid)
		)
		(fill yes)
		(layer "In2.Cu")
		(net "GND")
	)
	(gr_poly
		(pts
			(arc
				(start 159.243014 -406.370536)
				(mid 158.983934 -406.370536)
				(end 159.243014 -406.370536)
			)
		)
		(stroke
			(width 0)
			(type solid)
		)
		(fill yes)
		(layer "In2.Cu")
		(net "GND")
	)
	(gr_poly
		(pts
			(arc
				(start 159.331406 -404.46452)
				(mid 159.072326 -404.46452)
				(end 159.331406 -404.46452)
			)
		)
		(stroke
			(width 0)
			(type solid)
		)
		(fill yes)
		(layer "In2.Cu")
		(net "GND")
	)
	(gr_poly
		(pts
			(arc
				(start 160.413446 -404.46452)
				(mid 160.154366 -404.46452)
				(end 160.413446 -404.46452)
			)
		)
		(stroke
			(width 0)
			(type solid)
		)
		(fill yes)
		(layer "In2.Cu")
		(net "GND")
	)
	(gr_poly
		(pts
			(arc
				(start 160.501838 -410.664152)
				(mid 160.242758 -410.664152)
				(end 160.501838 -410.664152)
			)
		)
		(stroke
			(width 0)
			(type solid)
		)
		(fill yes)
		(layer "In2.Cu")
		(net "GND")
	)
	(gr_poly
		(pts
			(arc
				(start 160.501838 -409.396184)
				(mid 160.242758 -409.396184)
				(end 160.501838 -409.396184)
			)
		)
		(stroke
			(width 0)
			(type solid)
		)
		(fill yes)
		(layer "In2.Cu")
		(net "GND")
	)
	(gr_poly
		(pts
			(arc
				(start 160.501838 -407.638504)
				(mid 160.242758 -407.638504)
				(end 160.501838 -407.638504)
			)
		)
		(stroke
			(width 0)
			(type solid)
		)
		(fill yes)
		(layer "In2.Cu")
		(net "GND")
	)
	(gr_poly
		(pts
			(arc
				(start 160.501838 -406.370536)
				(mid 160.242758 -406.370536)
				(end 160.501838 -406.370536)
			)
		)
		(stroke
			(width 0)
			(type solid)
		)
		(fill yes)
		(layer "In2.Cu")
		(net "GND")
	)
	(gr_poly
		(pts
			(arc
				(start 160.774634 -405.098504)
				(mid 160.515554 -405.098504)
				(end 160.774634 -405.098504)
			)
		)
		(stroke
			(width 0)
			(type solid)
		)
		(fill yes)
		(layer "In2.Cu")
		(net "GND")
	)
	(gr_poly
		(pts
			(arc
				(start 160.774634 -403.830536)
				(mid 160.515554 -403.830536)
				(end 160.774634 -403.830536)
			)
		)
		(stroke
			(width 0)
			(type solid)
		)
		(fill yes)
		(layer "In2.Cu")
		(net "GND")
	)
	(gr_poly
		(pts
			(arc
				(start 160.863026 -410.030168)
				(mid 160.603946 -410.030168)
				(end 160.863026 -410.030168)
			)
		)
		(stroke
			(width 0)
			(type solid)
		)
		(fill yes)
		(layer "In2.Cu")
		(net "GND")
	)
	(gr_poly
		(pts
			(arc
				(start 161.945066 -410.030168)
				(mid 161.685986 -410.030168)
				(end 161.945066 -410.030168)
			)
		)
		(stroke
			(width 0)
			(type solid)
		)
		(fill yes)
		(layer "In2.Cu")
		(net "GND")
	)
	(gr_poly
		(pts
			(arc
				(start 161.945066 -407.00452)
				(mid 161.685986 -407.00452)
				(end 161.945066 -407.00452)
			)
		)
		(stroke
			(width 0)
			(type solid)
		)
		(fill yes)
		(layer "In2.Cu")
		(net "GND")
	)
	(gr_poly
		(pts
			(arc
				(start 162.033458 -405.098504)
				(mid 161.774378 -405.098504)
				(end 162.033458 -405.098504)
			)
		)
		(stroke
			(width 0)
			(type solid)
		)
		(fill yes)
		(layer "In2.Cu")
		(net "GND")
	)
	(gr_poly
		(pts
			(arc
				(start 162.033458 -403.830536)
				(mid 161.774378 -403.830536)
				(end 162.033458 -403.830536)
			)
		)
		(stroke
			(width 0)
			(type solid)
		)
		(fill yes)
		(layer "In2.Cu")
		(net "GND")
	)
	(gr_poly
		(pts
			(arc
				(start 162.306254 -410.664152)
				(mid 162.047174 -410.664152)
				(end 162.306254 -410.664152)
			)
		)
		(stroke
			(width 0)
			(type solid)
		)
		(fill yes)
		(layer "In2.Cu")
		(net "GND")
	)
	(gr_poly
		(pts
			(arc
				(start 162.306254 -409.396184)
				(mid 162.047174 -409.396184)
				(end 162.306254 -409.396184)
			)
		)
		(stroke
			(width 0)
			(type solid)
		)
		(fill yes)
		(layer "In2.Cu")
		(net "GND")
	)
	(gr_poly
		(pts
			(arc
				(start 162.306254 -407.638504)
				(mid 162.047174 -407.638504)
				(end 162.306254 -407.638504)
			)
		)
		(stroke
			(width 0)
			(type solid)
		)
		(fill yes)
		(layer "In2.Cu")
		(net "GND")
	)
	(gr_poly
		(pts
			(arc
				(start 162.306254 -406.370536)
				(mid 162.047174 -406.370536)
				(end 162.306254 -406.370536)
			)
		)
		(stroke
			(width 0)
			(type solid)
		)
		(fill yes)
		(layer "In2.Cu")
		(net "GND")
	)
	(gr_poly
		(pts
			(arc
				(start 162.394646 -404.46452)
				(mid 162.135566 -404.46452)
				(end 162.394646 -404.46452)
			)
		)
		(stroke
			(width 0)
			(type solid)
		)
		(fill yes)
		(layer "In2.Cu")
		(net "GND")
	)
	(gr_poly
		(pts
			(arc
				(start 163.565078 -410.664152)
				(mid 163.305998 -410.664152)
				(end 163.565078 -410.664152)
			)
		)
		(stroke
			(width 0)
			(type solid)
		)
		(fill yes)
		(layer "In2.Cu")
		(net "GND")
	)
	(gr_poly
		(pts
			(arc
				(start 163.565078 -409.396184)
				(mid 163.305998 -409.396184)
				(end 163.565078 -409.396184)
			)
		)
		(stroke
			(width 0)
			(type solid)
		)
		(fill yes)
		(layer "In2.Cu")
		(net "GND")
	)
	(gr_poly
		(pts
			(arc
				(start 163.565078 -407.638504)
				(mid 163.305998 -407.638504)
				(end 163.565078 -407.638504)
			)
		)
		(stroke
			(width 0)
			(type solid)
		)
		(fill yes)
		(layer "In2.Cu")
		(net "GND")
	)
	(gr_poly
		(pts
			(arc
				(start 163.565078 -406.370536)
				(mid 163.305998 -406.370536)
				(end 163.565078 -406.370536)
			)
		)
		(stroke
			(width 0)
			(type solid)
		)
		(fill yes)
		(layer "In2.Cu")
		(net "GND")
	)
	(gr_poly
		(pts
			(arc
				(start 163.926266 -410.030168)
				(mid 163.667186 -410.030168)
				(end 163.926266 -410.030168)
			)
		)
		(stroke
			(width 0)
			(type solid)
		)
		(fill yes)
		(layer "In2.Cu")
		(net "GND")
	)
	(gr_poly
		(pts
			(arc
				(start 163.926266 -407.00452)
				(mid 163.667186 -407.00452)
				(end 163.926266 -407.00452)
			)
		)
		(stroke
			(width 0)
			(type solid)
		)
		(fill yes)
		(layer "In2.Cu")
		(net "GND")
	)
	(gr_poly
		(pts
			(arc
				(start 303.364646 -420.952168)
				(mid 303.105566 -420.952168)
				(end 303.364646 -420.952168)
			)
		)
		(stroke
			(width 0)
			(type solid)
		)
		(fill yes)
		(layer "In2.Cu")
		(net "GND")
	)
	(gr_poly
		(pts
			(arc
				(start 303.725834 -421.586152)
				(mid 303.466754 -421.586152)
				(end 303.725834 -421.586152)
			)
		)
		(stroke
			(width 0)
			(type solid)
		)
		(fill yes)
		(layer "In2.Cu")
		(net "GND")
	)
	(gr_poly
		(pts
			(arc
				(start 303.725834 -420.318184)
				(mid 303.466754 -420.318184)
				(end 303.725834 -420.318184)
			)
		)
		(stroke
			(width 0)
			(type solid)
		)
		(fill yes)
		(layer "In2.Cu")
		(net "GND")
	)
	(gr_poly
		(pts
			(arc
				(start 304.896266 -418.412168)
				(mid 304.637186 -418.412168)
				(end 304.896266 -418.412168)
			)
		)
		(stroke
			(width 0)
			(type solid)
		)
		(fill yes)
		(layer "In2.Cu")
		(net "GND")
	)
	(gr_poly
		(pts
			(arc
				(start 304.984658 -421.586152)
				(mid 304.725578 -421.586152)
				(end 304.984658 -421.586152)
			)
		)
		(stroke
			(width 0)
			(type solid)
		)
		(fill yes)
		(layer "In2.Cu")
		(net "GND")
	)
	(gr_poly
		(pts
			(arc
				(start 304.984658 -420.318184)
				(mid 304.725578 -420.318184)
				(end 304.984658 -420.318184)
			)
		)
		(stroke
			(width 0)
			(type solid)
		)
		(fill yes)
		(layer "In2.Cu")
		(net "GND")
	)
	(gr_poly
		(pts
			(arc
				(start 305.257454 -419.046152)
				(mid 304.998374 -419.046152)
				(end 305.257454 -419.046152)
			)
		)
		(stroke
			(width 0)
			(type solid)
		)
		(fill yes)
		(layer "In2.Cu")
		(net "GND")
	)
	(gr_poly
		(pts
			(arc
				(start 305.345846 -420.952168)
				(mid 305.086766 -420.952168)
				(end 305.345846 -420.952168)
			)
		)
		(stroke
			(width 0)
			(type solid)
		)
		(fill yes)
		(layer "In2.Cu")
		(net "GND")
	)
	(gr_poly
		(pts
			(arc
				(start 306.427886 -420.952168)
				(mid 306.168806 -420.952168)
				(end 306.427886 -420.952168)
			)
		)
		(stroke
			(width 0)
			(type solid)
		)
		(fill yes)
		(layer "In2.Cu")
		(net "GND")
	)
	(gr_poly
		(pts
			(arc
				(start 306.516278 -419.046152)
				(mid 306.257198 -419.046152)
				(end 306.516278 -419.046152)
			)
		)
		(stroke
			(width 0)
			(type solid)
		)
		(fill yes)
		(layer "In2.Cu")
		(net "GND")
	)
	(gr_poly
		(pts
			(arc
				(start 306.789074 -421.586152)
				(mid 306.529994 -421.586152)
				(end 306.789074 -421.586152)
			)
		)
		(stroke
			(width 0)
			(type solid)
		)
		(fill yes)
		(layer "In2.Cu")
		(net "GND")
	)
	(gr_poly
		(pts
			(arc
				(start 306.789074 -420.318184)
				(mid 306.529994 -420.318184)
				(end 306.789074 -420.318184)
			)
		)
		(stroke
			(width 0)
			(type solid)
		)
		(fill yes)
		(layer "In2.Cu")
		(net "GND")
	)
	(gr_poly
		(pts
			(arc
				(start 306.877466 -418.412168)
				(mid 306.618386 -418.412168)
				(end 306.877466 -418.412168)
			)
		)
		(stroke
			(width 0)
			(type solid)
		)
		(fill yes)
		(layer "In2.Cu")
		(net "GND")
	)
	(gr_poly
		(pts
			(arc
				(start 307.959506 -418.412168)
				(mid 307.700426 -418.412168)
				(end 307.959506 -418.412168)
			)
		)
		(stroke
			(width 0)
			(type solid)
		)
		(fill yes)
		(layer "In2.Cu")
		(net "GND")
	)
	(gr_poly
		(pts
			(arc
				(start 308.047898 -421.586152)
				(mid 307.788818 -421.586152)
				(end 308.047898 -421.586152)
			)
		)
		(stroke
			(width 0)
			(type solid)
		)
		(fill yes)
		(layer "In2.Cu")
		(net "GND")
	)
	(gr_poly
		(pts
			(arc
				(start 308.047898 -420.318184)
				(mid 307.788818 -420.318184)
				(end 308.047898 -420.318184)
			)
		)
		(stroke
			(width 0)
			(type solid)
		)
		(fill yes)
		(layer "In2.Cu")
		(net "GND")
	)
	(gr_poly
		(pts
			(arc
				(start 308.320694 -419.046152)
				(mid 308.061614 -419.046152)
				(end 308.320694 -419.046152)
			)
		)
		(stroke
			(width 0)
			(type solid)
		)
		(fill yes)
		(layer "In2.Cu")
		(net "GND")
	)
	(gr_poly
		(pts
			(arc
				(start 308.409086 -420.952168)
				(mid 308.150006 -420.952168)
				(end 308.409086 -420.952168)
			)
		)
		(stroke
			(width 0)
			(type solid)
		)
		(fill yes)
		(layer "In2.Cu")
		(net "GND")
	)
	(gr_poly
		(pts
			(arc
				(start 309.491126 -420.952168)
				(mid 309.232046 -420.952168)
				(end 309.491126 -420.952168)
			)
		)
		(stroke
			(width 0)
			(type solid)
		)
		(fill yes)
		(layer "In2.Cu")
		(net "GND")
	)
	(gr_poly
		(pts
			(arc
				(start 309.579518 -419.046152)
				(mid 309.320438 -419.046152)
				(end 309.579518 -419.046152)
			)
		)
		(stroke
			(width 0)
			(type solid)
		)
		(fill yes)
		(layer "In2.Cu")
		(net "GND")
	)
	(gr_poly
		(pts
			(arc
				(start 309.579518 -417.778184)
				(mid 309.320438 -417.778184)
				(end 309.579518 -417.778184)
			)
		)
		(stroke
			(width 0)
			(type solid)
		)
		(fill yes)
		(layer "In2.Cu")
		(net "GND")
	)
	(gr_poly
		(pts
			(arc
				(start 309.852314 -421.586152)
				(mid 309.593234 -421.586152)
				(end 309.852314 -421.586152)
			)
		)
		(stroke
			(width 0)
			(type solid)
		)
		(fill yes)
		(layer "In2.Cu")
		(net "GND")
	)
	(gr_poly
		(pts
			(arc
				(start 309.852314 -420.318184)
				(mid 309.593234 -420.318184)
				(end 309.852314 -420.318184)
			)
		)
		(stroke
			(width 0)
			(type solid)
		)
		(fill yes)
		(layer "In2.Cu")
		(net "GND")
	)
	(gr_poly
		(pts
			(arc
				(start 309.940706 -418.412168)
				(mid 309.681626 -418.412168)
				(end 309.940706 -418.412168)
			)
		)
		(stroke
			(width 0)
			(type solid)
		)
		(fill yes)
		(layer "In2.Cu")
		(net "GND")
	)
	(gr_poly
		(pts
			(arc
				(start 311.022746 -418.412168)
				(mid 310.763666 -418.412168)
				(end 311.022746 -418.412168)
			)
		)
		(stroke
			(width 0)
			(type solid)
		)
		(fill yes)
		(layer "In2.Cu")
		(net "GND")
	)
	(gr_poly
		(pts
			(arc
				(start 311.111138 -421.586152)
				(mid 310.852058 -421.586152)
				(end 311.111138 -421.586152)
			)
		)
		(stroke
			(width 0)
			(type solid)
		)
		(fill yes)
		(layer "In2.Cu")
		(net "GND")
	)
	(gr_poly
		(pts
			(arc
				(start 311.111138 -420.318184)
				(mid 310.852058 -420.318184)
				(end 311.111138 -420.318184)
			)
		)
		(stroke
			(width 0)
			(type solid)
		)
		(fill yes)
		(layer "In2.Cu")
		(net "GND")
	)
	(gr_poly
		(pts
			(arc
				(start 311.383934 -419.046152)
				(mid 311.124854 -419.046152)
				(end 311.383934 -419.046152)
			)
		)
		(stroke
			(width 0)
			(type solid)
		)
		(fill yes)
		(layer "In2.Cu")
		(net "GND")
	)
	(gr_poly
		(pts
			(arc
				(start 311.383934 -417.778184)
				(mid 311.124854 -417.778184)
				(end 311.383934 -417.778184)
			)
		)
		(stroke
			(width 0)
			(type solid)
		)
		(fill yes)
		(layer "In2.Cu")
		(net "GND")
	)
	(gr_poly
		(pts
			(arc
				(start 311.472326 -420.952168)
				(mid 311.213246 -420.952168)
				(end 311.472326 -420.952168)
			)
		)
		(stroke
			(width 0)
			(type solid)
		)
		(fill yes)
		(layer "In2.Cu")
		(net "GND")
	)
	(gr_poly
		(pts
			(arc
				(start 312.554366 -420.952168)
				(mid 312.295286 -420.952168)
				(end 312.554366 -420.952168)
			)
		)
		(stroke
			(width 0)
			(type solid)
		)
		(fill yes)
		(layer "In2.Cu")
		(net "GND")
	)
	(gr_poly
		(pts
			(arc
				(start 312.642758 -419.046152)
				(mid 312.383678 -419.046152)
				(end 312.642758 -419.046152)
			)
		)
		(stroke
			(width 0)
			(type solid)
		)
		(fill yes)
		(layer "In2.Cu")
		(net "GND")
	)
	(gr_poly
		(pts
			(arc
				(start 312.642758 -417.778184)
				(mid 312.383678 -417.778184)
				(end 312.642758 -417.778184)
			)
		)
		(stroke
			(width 0)
			(type solid)
		)
		(fill yes)
		(layer "In2.Cu")
		(net "GND")
	)
	(gr_poly
		(pts
			(arc
				(start 312.915554 -421.586152)
				(mid 312.656474 -421.586152)
				(end 312.915554 -421.586152)
			)
		)
		(stroke
			(width 0)
			(type solid)
		)
		(fill yes)
		(layer "In2.Cu")
		(net "GND")
	)
	(gr_poly
		(pts
			(arc
				(start 312.915554 -420.318184)
				(mid 312.656474 -420.318184)
				(end 312.915554 -420.318184)
			)
		)
		(stroke
			(width 0)
			(type solid)
		)
		(fill yes)
		(layer "In2.Cu")
		(net "GND")
	)
	(gr_poly
		(pts
			(arc
				(start 313.003946 -418.412168)
				(mid 312.744866 -418.412168)
				(end 313.003946 -418.412168)
			)
		)
		(stroke
			(width 0)
			(type solid)
		)
		(fill yes)
		(layer "In2.Cu")
		(net "GND")
	)
	(gr_poly
		(pts
			(arc
				(start 314.085986 -418.412168)
				(mid 313.826906 -418.412168)
				(end 314.085986 -418.412168)
			)
		)
		(stroke
			(width 0)
			(type solid)
		)
		(fill yes)
		(layer "In2.Cu")
		(net "GND")
	)
	(gr_poly
		(pts
			(arc
				(start 314.174378 -421.586152)
				(mid 313.915298 -421.586152)
				(end 314.174378 -421.586152)
			)
		)
		(stroke
			(width 0)
			(type solid)
		)
		(fill yes)
		(layer "In2.Cu")
		(net "GND")
	)
	(gr_poly
		(pts
			(arc
				(start 314.174378 -420.318184)
				(mid 313.915298 -420.318184)
				(end 314.174378 -420.318184)
			)
		)
		(stroke
			(width 0)
			(type solid)
		)
		(fill yes)
		(layer "In2.Cu")
		(net "GND")
	)
	(gr_poly
		(pts
			(arc
				(start 314.447174 -419.046152)
				(mid 314.188094 -419.046152)
				(end 314.447174 -419.046152)
			)
		)
		(stroke
			(width 0)
			(type solid)
		)
		(fill yes)
		(layer "In2.Cu")
		(net "GND")
	)
	(gr_poly
		(pts
			(arc
				(start 314.447174 -417.778184)
				(mid 314.188094 -417.778184)
				(end 314.447174 -417.778184)
			)
		)
		(stroke
			(width 0)
			(type solid)
		)
		(fill yes)
		(layer "In2.Cu")
		(net "GND")
	)
	(gr_poly
		(pts
			(arc
				(start 314.535566 -420.952168)
				(mid 314.276486 -420.952168)
				(end 314.535566 -420.952168)
			)
		)
		(stroke
			(width 0)
			(type solid)
		)
		(fill yes)
		(layer "In2.Cu")
		(net "GND")
	)
	(gr_poly
		(pts
			(arc
				(start 315.617606 -420.952168)
				(mid 315.358526 -420.952168)
				(end 315.617606 -420.952168)
			)
		)
		(stroke
			(width 0)
			(type solid)
		)
		(fill yes)
		(layer "In2.Cu")
		(net "GND")
	)
	(gr_poly
		(pts
			(arc
				(start 315.705998 -419.046152)
				(mid 315.446918 -419.046152)
				(end 315.705998 -419.046152)
			)
		)
		(stroke
			(width 0)
			(type solid)
		)
		(fill yes)
		(layer "In2.Cu")
		(net "GND")
	)
	(gr_poly
		(pts
			(arc
				(start 315.705998 -417.778184)
				(mid 315.446918 -417.778184)
				(end 315.705998 -417.778184)
			)
		)
		(stroke
			(width 0)
			(type solid)
		)
		(fill yes)
		(layer "In2.Cu")
		(net "GND")
	)
	(gr_poly
		(pts
			(arc
				(start 315.978794 -421.586152)
				(mid 315.719714 -421.586152)
				(end 315.978794 -421.586152)
			)
		)
		(stroke
			(width 0)
			(type solid)
		)
		(fill yes)
		(layer "In2.Cu")
		(net "GND")
	)
	(gr_poly
		(pts
			(arc
				(start 315.978794 -420.318184)
				(mid 315.719714 -420.318184)
				(end 315.978794 -420.318184)
			)
		)
		(stroke
			(width 0)
			(type solid)
		)
		(fill yes)
		(layer "In2.Cu")
		(net "GND")
	)
	(gr_poly
		(pts
			(arc
				(start 316.067186 -418.412168)
				(mid 315.808106 -418.412168)
				(end 316.067186 -418.412168)
			)
		)
		(stroke
			(width 0)
			(type solid)
		)
		(fill yes)
		(layer "In2.Cu")
		(net "GND")
	)
	(gr_poly
		(pts
			(arc
				(start 317.149226 -418.412168)
				(mid 316.890146 -418.412168)
				(end 317.149226 -418.412168)
			)
		)
		(stroke
			(width 0)
			(type solid)
		)
		(fill yes)
		(layer "In2.Cu")
		(net "GND")
	)
	(gr_poly
		(pts
			(arc
				(start 317.237618 -420.318184)
				(mid 316.978538 -420.318184)
				(end 317.237618 -420.318184)
			)
		)
		(stroke
			(width 0)
			(type solid)
		)
		(fill yes)
		(layer "In2.Cu")
		(net "GND")
	)
	(gr_poly
		(pts
			(arc
				(start 317.288418 -421.535352)
				(mid 317.029338 -421.535352)
				(end 317.288418 -421.535352)
			)
		)
		(stroke
			(width 0)
			(type solid)
		)
		(fill yes)
		(layer "In2.Cu")
		(net "GND")
	)
	(gr_poly
		(pts
			(arc
				(start 317.510414 -419.046152)
				(mid 317.251334 -419.046152)
				(end 317.510414 -419.046152)
			)
		)
		(stroke
			(width 0)
			(type solid)
		)
		(fill yes)
		(layer "In2.Cu")
		(net "GND")
	)
	(gr_poly
		(pts
			(arc
				(start 317.510414 -417.778184)
				(mid 317.251334 -417.778184)
				(end 317.510414 -417.778184)
			)
		)
		(stroke
			(width 0)
			(type solid)
		)
		(fill yes)
		(layer "In2.Cu")
		(net "GND")
	)
	(gr_poly
		(pts
			(arc
				(start 317.598806 -420.952168)
				(mid 317.339726 -420.952168)
				(end 317.598806 -420.952168)
			)
		)
		(stroke
			(width 0)
			(type solid)
		)
		(fill yes)
		(layer "In2.Cu")
		(net "GND")
	)
	(gr_poly
		(pts
			(arc
				(start 318.680846 -420.952168)
				(mid 318.421766 -420.952168)
				(end 318.680846 -420.952168)
			)
		)
		(stroke
			(width 0)
			(type solid)
		)
		(fill yes)
		(layer "In2.Cu")
		(net "GND")
	)
	(gr_poly
		(pts
			(arc
				(start 318.769238 -419.046152)
				(mid 318.510158 -419.046152)
				(end 318.769238 -419.046152)
			)
		)
		(stroke
			(width 0)
			(type solid)
		)
		(fill yes)
		(layer "In2.Cu")
		(net "GND")
	)
	(gr_poly
		(pts
			(arc
				(start 318.769238 -417.778184)
				(mid 318.510158 -417.778184)
				(end 318.769238 -417.778184)
			)
		)
		(stroke
			(width 0)
			(type solid)
		)
		(fill yes)
		(layer "In2.Cu")
		(net "GND")
	)
	(gr_poly
		(pts
			(arc
				(start 319.042034 -421.586152)
				(mid 318.782954 -421.586152)
				(end 319.042034 -421.586152)
			)
		)
		(stroke
			(width 0)
			(type solid)
		)
		(fill yes)
		(layer "In2.Cu")
		(net "GND")
	)
	(gr_poly
		(pts
			(arc
				(start 319.042034 -420.318184)
				(mid 318.782954 -420.318184)
				(end 319.042034 -420.318184)
			)
		)
		(stroke
			(width 0)
			(type solid)
		)
		(fill yes)
		(layer "In2.Cu")
		(net "GND")
	)
	(gr_poly
		(pts
			(arc
				(start 319.130426 -418.412168)
				(mid 318.871346 -418.412168)
				(end 319.130426 -418.412168)
			)
		)
		(stroke
			(width 0)
			(type solid)
		)
		(fill yes)
		(layer "In2.Cu")
		(net "GND")
	)
	(gr_poly
		(pts
			(arc
				(start 320.212466 -418.412168)
				(mid 319.953386 -418.412168)
				(end 320.212466 -418.412168)
			)
		)
		(stroke
			(width 0)
			(type solid)
		)
		(fill yes)
		(layer "In2.Cu")
		(net "GND")
	)
	(gr_poly
		(pts
			(arc
				(start 320.300858 -421.586152)
				(mid 320.041778 -421.586152)
				(end 320.300858 -421.586152)
			)
		)
		(stroke
			(width 0)
			(type solid)
		)
		(fill yes)
		(layer "In2.Cu")
		(net "GND")
	)
	(gr_poly
		(pts
			(arc
				(start 320.300858 -420.318184)
				(mid 320.041778 -420.318184)
				(end 320.300858 -420.318184)
			)
		)
		(stroke
			(width 0)
			(type solid)
		)
		(fill yes)
		(layer "In2.Cu")
		(net "GND")
	)
	(gr_poly
		(pts
			(arc
				(start 320.573654 -419.046152)
				(mid 320.314574 -419.046152)
				(end 320.573654 -419.046152)
			)
		)
		(stroke
			(width 0)
			(type solid)
		)
		(fill yes)
		(layer "In2.Cu")
		(net "GND")
	)
	(gr_poly
		(pts
			(arc
				(start 320.573654 -417.778184)
				(mid 320.314574 -417.778184)
				(end 320.573654 -417.778184)
			)
		)
		(stroke
			(width 0)
			(type solid)
		)
		(fill yes)
		(layer "In2.Cu")
		(net "GND")
	)
	(gr_poly
		(pts
			(arc
				(start 320.662046 -420.952168)
				(mid 320.402966 -420.952168)
				(end 320.662046 -420.952168)
			)
		)
		(stroke
			(width 0)
			(type solid)
		)
		(fill yes)
		(layer "In2.Cu")
		(net "GND")
	)
	(gr_poly
		(pts
			(arc
				(start 321.744086 -420.952168)
				(mid 321.485006 -420.952168)
				(end 321.744086 -420.952168)
			)
		)
		(stroke
			(width 0)
			(type solid)
		)
		(fill yes)
		(layer "In2.Cu")
		(net "GND")
	)
	(gr_poly
		(pts
			(arc
				(start 321.832478 -419.046152)
				(mid 321.573398 -419.046152)
				(end 321.832478 -419.046152)
			)
		)
		(stroke
			(width 0)
			(type solid)
		)
		(fill yes)
		(layer "In2.Cu")
		(net "GND")
	)
	(gr_poly
		(pts
			(arc
				(start 321.832478 -417.778184)
				(mid 321.573398 -417.778184)
				(end 321.832478 -417.778184)
			)
		)
		(stroke
			(width 0)
			(type solid)
		)
		(fill yes)
		(layer "In2.Cu")
		(net "GND")
	)
	(gr_poly
		(pts
			(arc
				(start 322.105274 -421.586152)
				(mid 321.846194 -421.586152)
				(end 322.105274 -421.586152)
			)
		)
		(stroke
			(width 0)
			(type solid)
		)
		(fill yes)
		(layer "In2.Cu")
		(net "GND")
	)
	(gr_poly
		(pts
			(arc
				(start 322.105274 -420.318184)
				(mid 321.846194 -420.318184)
				(end 322.105274 -420.318184)
			)
		)
		(stroke
			(width 0)
			(type solid)
		)
		(fill yes)
		(layer "In2.Cu")
		(net "GND")
	)
	(gr_poly
		(pts
			(arc
				(start 322.193666 -418.412168)
				(mid 321.934586 -418.412168)
				(end 322.193666 -418.412168)
			)
		)
		(stroke
			(width 0)
			(type solid)
		)
		(fill yes)
		(layer "In2.Cu")
		(net "GND")
	)
	(gr_poly
		(pts
			(arc
				(start 323.275706 -418.412168)
				(mid 323.016626 -418.412168)
				(end 323.275706 -418.412168)
			)
		)
		(stroke
			(width 0)
			(type solid)
		)
		(fill yes)
		(layer "In2.Cu")
		(net "GND")
	)
	(gr_poly
		(pts
			(arc
				(start 323.364098 -421.586152)
				(mid 323.105018 -421.586152)
				(end 323.364098 -421.586152)
			)
		)
		(stroke
			(width 0)
			(type solid)
		)
		(fill yes)
		(layer "In2.Cu")
		(net "GND")
	)
	(gr_poly
		(pts
			(arc
				(start 323.364098 -420.318184)
				(mid 323.105018 -420.318184)
				(end 323.364098 -420.318184)
			)
		)
		(stroke
			(width 0)
			(type solid)
		)
		(fill yes)
		(layer "In2.Cu")
		(net "GND")
	)
	(gr_poly
		(pts
			(arc
				(start 323.636894 -419.046152)
				(mid 323.377814 -419.046152)
				(end 323.636894 -419.046152)
			)
		)
		(stroke
			(width 0)
			(type solid)
		)
		(fill yes)
		(layer "In2.Cu")
		(net "GND")
	)
	(gr_poly
		(pts
			(arc
				(start 323.636894 -417.778184)
				(mid 323.377814 -417.778184)
				(end 323.636894 -417.778184)
			)
		)
		(stroke
			(width 0)
			(type solid)
		)
		(fill yes)
		(layer "In2.Cu")
		(net "GND")
	)
	(gr_poly
		(pts
			(arc
				(start 323.725286 -420.952168)
				(mid 323.466206 -420.952168)
				(end 323.725286 -420.952168)
			)
		)
		(stroke
			(width 0)
			(type solid)
		)
		(fill yes)
		(layer "In2.Cu")
		(net "GND")
	)
	(gr_poly
		(pts
			(arc
				(start 324.807326 -420.952168)
				(mid 324.548246 -420.952168)
				(end 324.807326 -420.952168)
			)
		)
		(stroke
			(width 0)
			(type solid)
		)
		(fill yes)
		(layer "In2.Cu")
		(net "GND")
	)
	(gr_poly
		(pts
			(arc
				(start 324.895718 -419.046152)
				(mid 324.636638 -419.046152)
				(end 324.895718 -419.046152)
			)
		)
		(stroke
			(width 0)
			(type solid)
		)
		(fill yes)
		(layer "In2.Cu")
		(net "GND")
	)
	(gr_poly
		(pts
			(arc
				(start 324.895718 -417.778184)
				(mid 324.636638 -417.778184)
				(end 324.895718 -417.778184)
			)
		)
		(stroke
			(width 0)
			(type solid)
		)
		(fill yes)
		(layer "In2.Cu")
		(net "GND")
	)
	(gr_poly
		(pts
			(arc
				(start 325.168514 -421.586152)
				(mid 324.909434 -421.586152)
				(end 325.168514 -421.586152)
			)
		)
		(stroke
			(width 0)
			(type solid)
		)
		(fill yes)
		(layer "In2.Cu")
		(net "GND")
	)
	(gr_poly
		(pts
			(arc
				(start 325.168514 -420.318184)
				(mid 324.909434 -420.318184)
				(end 325.168514 -420.318184)
			)
		)
		(stroke
			(width 0)
			(type solid)
		)
		(fill yes)
		(layer "In2.Cu")
		(net "GND")
	)
	(gr_poly
		(pts
			(arc
				(start 325.256906 -418.412168)
				(mid 324.997826 -418.412168)
				(end 325.256906 -418.412168)
			)
		)
		(stroke
			(width 0)
			(type solid)
		)
		(fill yes)
		(layer "In2.Cu")
		(net "GND")
	)
	(gr_poly
		(pts
			(arc
				(start 326.338946 -418.412168)
				(mid 326.079866 -418.412168)
				(end 326.338946 -418.412168)
			)
		)
		(stroke
			(width 0)
			(type solid)
		)
		(fill yes)
		(layer "In2.Cu")
		(net "GND")
	)
	(gr_poly
		(pts
			(arc
				(start 326.427338 -421.586152)
				(mid 326.168258 -421.586152)
				(end 326.427338 -421.586152)
			)
		)
		(stroke
			(width 0)
			(type solid)
		)
		(fill yes)
		(layer "In2.Cu")
		(net "GND")
	)
	(gr_poly
		(pts
			(arc
				(start 326.427338 -420.318184)
				(mid 326.168258 -420.318184)
				(end 326.427338 -420.318184)
			)
		)
		(stroke
			(width 0)
			(type solid)
		)
		(fill yes)
		(layer "In2.Cu")
		(net "GND")
	)
	(gr_poly
		(pts
			(arc
				(start 326.700134 -419.046152)
				(mid 326.441054 -419.046152)
				(end 326.700134 -419.046152)
			)
		)
		(stroke
			(width 0)
			(type solid)
		)
		(fill yes)
		(layer "In2.Cu")
		(net "GND")
	)
	(gr_poly
		(pts
			(arc
				(start 326.700134 -417.778184)
				(mid 326.441054 -417.778184)
				(end 326.700134 -417.778184)
			)
		)
		(stroke
			(width 0)
			(type solid)
		)
		(fill yes)
		(layer "In2.Cu")
		(net "GND")
	)
	(gr_poly
		(pts
			(arc
				(start 326.788526 -420.952168)
				(mid 326.529446 -420.952168)
				(end 326.788526 -420.952168)
			)
		)
		(stroke
			(width 0)
			(type solid)
		)
		(fill yes)
		(layer "In2.Cu")
		(net "GND")
	)
	(gr_poly
		(pts
			(arc
				(start 327.870566 -420.952168)
				(mid 327.611486 -420.952168)
				(end 327.870566 -420.952168)
			)
		)
		(stroke
			(width 0)
			(type solid)
		)
		(fill yes)
		(layer "In2.Cu")
		(net "GND")
	)
	(gr_poly
		(pts
			(arc
				(start 327.958958 -419.046152)
				(mid 327.699878 -419.046152)
				(end 327.958958 -419.046152)
			)
		)
		(stroke
			(width 0)
			(type solid)
		)
		(fill yes)
		(layer "In2.Cu")
		(net "GND")
	)
	(gr_poly
		(pts
			(arc
				(start 327.958958 -417.778184)
				(mid 327.699878 -417.778184)
				(end 327.958958 -417.778184)
			)
		)
		(stroke
			(width 0)
			(type solid)
		)
		(fill yes)
		(layer "In2.Cu")
		(net "GND")
	)
	(gr_poly
		(pts
			(arc
				(start 328.231754 -421.586152)
				(mid 327.972674 -421.586152)
				(end 328.231754 -421.586152)
			)
		)
		(stroke
			(width 0)
			(type solid)
		)
		(fill yes)
		(layer "In2.Cu")
		(net "GND")
	)
	(gr_poly
		(pts
			(arc
				(start 328.231754 -420.318184)
				(mid 327.972674 -420.318184)
				(end 328.231754 -420.318184)
			)
		)
		(stroke
			(width 0)
			(type solid)
		)
		(fill yes)
		(layer "In2.Cu")
		(net "GND")
	)
	(gr_poly
		(pts
			(arc
				(start 328.320146 -418.412168)
				(mid 328.061066 -418.412168)
				(end 328.320146 -418.412168)
			)
		)
		(stroke
			(width 0)
			(type solid)
		)
		(fill yes)
		(layer "In2.Cu")
		(net "GND")
	)
	(gr_poly
		(pts
			(arc
				(start 329.402186 -418.412168)
				(mid 329.143106 -418.412168)
				(end 329.402186 -418.412168)
			)
		)
		(stroke
			(width 0)
			(type solid)
		)
		(fill yes)
		(layer "In2.Cu")
		(net "GND")
	)
	(gr_poly
		(pts
			(arc
				(start 329.490578 -421.586152)
				(mid 329.231498 -421.586152)
				(end 329.490578 -421.586152)
			)
		)
		(stroke
			(width 0)
			(type solid)
		)
		(fill yes)
		(layer "In2.Cu")
		(net "GND")
	)
	(gr_poly
		(pts
			(arc
				(start 329.490578 -420.318184)
				(mid 329.231498 -420.318184)
				(end 329.490578 -420.318184)
			)
		)
		(stroke
			(width 0)
			(type solid)
		)
		(fill yes)
		(layer "In2.Cu")
		(net "GND")
	)
	(gr_poly
		(pts
			(arc
				(start 329.763374 -419.046152)
				(mid 329.504294 -419.046152)
				(end 329.763374 -419.046152)
			)
		)
		(stroke
			(width 0)
			(type solid)
		)
		(fill yes)
		(layer "In2.Cu")
		(net "GND")
	)
	(gr_poly
		(pts
			(arc
				(start 329.763374 -417.778184)
				(mid 329.504294 -417.778184)
				(end 329.763374 -417.778184)
			)
		)
		(stroke
			(width 0)
			(type solid)
		)
		(fill yes)
		(layer "In2.Cu")
		(net "GND")
	)
	(gr_poly
		(pts
			(arc
				(start 329.851766 -420.952168)
				(mid 329.592686 -420.952168)
				(end 329.851766 -420.952168)
			)
		)
		(stroke
			(width 0)
			(type solid)
		)
		(fill yes)
		(layer "In2.Cu")
		(net "GND")
	)
	(gr_poly
		(pts
			(arc
				(start 330.933806 -420.952168)
				(mid 330.674726 -420.952168)
				(end 330.933806 -420.952168)
			)
		)
		(stroke
			(width 0)
			(type solid)
		)
		(fill yes)
		(layer "In2.Cu")
		(net "GND")
	)
	(gr_poly
		(pts
			(arc
				(start 331.022198 -419.046152)
				(mid 330.763118 -419.046152)
				(end 331.022198 -419.046152)
			)
		)
		(stroke
			(width 0)
			(type solid)
		)
		(fill yes)
		(layer "In2.Cu")
		(net "GND")
	)
	(gr_poly
		(pts
			(arc
				(start 331.022198 -417.778184)
				(mid 330.763118 -417.778184)
				(end 331.022198 -417.778184)
			)
		)
		(stroke
			(width 0)
			(type solid)
		)
		(fill yes)
		(layer "In2.Cu")
		(net "GND")
	)
	(gr_poly
		(pts
			(arc
				(start 331.294994 -421.586152)
				(mid 331.035914 -421.586152)
				(end 331.294994 -421.586152)
			)
		)
		(stroke
			(width 0)
			(type solid)
		)
		(fill yes)
		(layer "In2.Cu")
		(net "GND")
	)
	(gr_poly
		(pts
			(arc
				(start 331.294994 -420.318184)
				(mid 331.035914 -420.318184)
				(end 331.294994 -420.318184)
			)
		)
		(stroke
			(width 0)
			(type solid)
		)
		(fill yes)
		(layer "In2.Cu")
		(net "GND")
	)
	(gr_poly
		(pts
			(arc
				(start 331.383386 -418.412168)
				(mid 331.124306 -418.412168)
				(end 331.383386 -418.412168)
			)
		)
		(stroke
			(width 0)
			(type solid)
		)
		(fill yes)
		(layer "In2.Cu")
		(net "GND")
	)
	(gr_poly
		(pts
			(arc
				(start 332.465426 -418.412168)
				(mid 332.206346 -418.412168)
				(end 332.465426 -418.412168)
			)
		)
		(stroke
			(width 0)
			(type solid)
		)
		(fill yes)
		(layer "In2.Cu")
		(net "GND")
	)
	(gr_poly
		(pts
			(arc
				(start 332.553818 -421.586152)
				(mid 332.294738 -421.586152)
				(end 332.553818 -421.586152)
			)
		)
		(stroke
			(width 0)
			(type solid)
		)
		(fill yes)
		(layer "In2.Cu")
		(net "GND")
	)
	(gr_poly
		(pts
			(arc
				(start 332.553818 -420.318184)
				(mid 332.294738 -420.318184)
				(end 332.553818 -420.318184)
			)
		)
		(stroke
			(width 0)
			(type solid)
		)
		(fill yes)
		(layer "In2.Cu")
		(net "GND")
	)
	(gr_poly
		(pts
			(arc
				(start 332.826614 -419.046152)
				(mid 332.567534 -419.046152)
				(end 332.826614 -419.046152)
			)
		)
		(stroke
			(width 0)
			(type solid)
		)
		(fill yes)
		(layer "In2.Cu")
		(net "GND")
	)
	(gr_poly
		(pts
			(arc
				(start 332.826614 -417.778184)
				(mid 332.567534 -417.778184)
				(end 332.826614 -417.778184)
			)
		)
		(stroke
			(width 0)
			(type solid)
		)
		(fill yes)
		(layer "In2.Cu")
		(net "GND")
	)
	(gr_poly
		(pts
			(arc
				(start 332.915006 -420.952168)
				(mid 332.655926 -420.952168)
				(end 332.915006 -420.952168)
			)
		)
		(stroke
			(width 0)
			(type solid)
		)
		(fill yes)
		(layer "In2.Cu")
		(net "GND")
	)
	(gr_poly
		(pts
			(arc
				(start 333.997046 -420.952168)
				(mid 333.737966 -420.952168)
				(end 333.997046 -420.952168)
			)
		)
		(stroke
			(width 0)
			(type solid)
		)
		(fill yes)
		(layer "In2.Cu")
		(net "GND")
	)
	(gr_poly
		(pts
			(arc
				(start 334.085438 -419.046152)
				(mid 333.826358 -419.046152)
				(end 334.085438 -419.046152)
			)
		)
		(stroke
			(width 0)
			(type solid)
		)
		(fill yes)
		(layer "In2.Cu")
		(net "GND")
	)
	(gr_poly
		(pts
			(arc
				(start 334.085438 -417.778184)
				(mid 333.826358 -417.778184)
				(end 334.085438 -417.778184)
			)
		)
		(stroke
			(width 0)
			(type solid)
		)
		(fill yes)
		(layer "In2.Cu")
		(net "GND")
	)
	(gr_poly
		(pts
			(arc
				(start 334.358234 -421.586152)
				(mid 334.099154 -421.586152)
				(end 334.358234 -421.586152)
			)
		)
		(stroke
			(width 0)
			(type solid)
		)
		(fill yes)
		(layer "In2.Cu")
		(net "GND")
	)
	(gr_poly
		(pts
			(arc
				(start 334.358234 -420.318184)
				(mid 334.099154 -420.318184)
				(end 334.358234 -420.318184)
			)
		)
		(stroke
			(width 0)
			(type solid)
		)
		(fill yes)
		(layer "In2.Cu")
		(net "GND")
	)
	(gr_poly
		(pts
			(arc
				(start 334.446626 -418.412168)
				(mid 334.187546 -418.412168)
				(end 334.446626 -418.412168)
			)
		)
		(stroke
			(width 0)
			(type solid)
		)
		(fill yes)
		(layer "In2.Cu")
		(net "GND")
	)
	(gr_poly
		(pts
			(arc
				(start 335.528666 -418.412168)
				(mid 335.269586 -418.412168)
				(end 335.528666 -418.412168)
			)
		)
		(stroke
			(width 0)
			(type solid)
		)
		(fill yes)
		(layer "In2.Cu")
		(net "GND")
	)
	(gr_poly
		(pts
			(arc
				(start 335.617058 -421.586152)
				(mid 335.357978 -421.586152)
				(end 335.617058 -421.586152)
			)
		)
		(stroke
			(width 0)
			(type solid)
		)
		(fill yes)
		(layer "In2.Cu")
		(net "GND")
	)
	(gr_poly
		(pts
			(arc
				(start 335.617058 -420.318184)
				(mid 335.357978 -420.318184)
				(end 335.617058 -420.318184)
			)
		)
		(stroke
			(width 0)
			(type solid)
		)
		(fill yes)
		(layer "In2.Cu")
		(net "GND")
	)
	(gr_poly
		(pts
			(arc
				(start 335.889854 -419.046152)
				(mid 335.630774 -419.046152)
				(end 335.889854 -419.046152)
			)
		)
		(stroke
			(width 0)
			(type solid)
		)
		(fill yes)
		(layer "In2.Cu")
		(net "GND")
	)
	(gr_poly
		(pts
			(arc
				(start 335.889854 -417.778184)
				(mid 335.630774 -417.778184)
				(end 335.889854 -417.778184)
			)
		)
		(stroke
			(width 0)
			(type solid)
		)
		(fill yes)
		(layer "In2.Cu")
		(net "GND")
	)
	(gr_poly
		(pts
			(arc
				(start 335.978246 -420.952168)
				(mid 335.719166 -420.952168)
				(end 335.978246 -420.952168)
			)
		)
		(stroke
			(width 0)
			(type solid)
		)
		(fill yes)
		(layer "In2.Cu")
		(net "GND")
	)
	(gr_poly
		(pts
			(arc
				(start 337.060286 -420.952168)
				(mid 336.801206 -420.952168)
				(end 337.060286 -420.952168)
			)
		)
		(stroke
			(width 0)
			(type solid)
		)
		(fill yes)
		(layer "In2.Cu")
		(net "GND")
	)
	(gr_poly
		(pts
			(arc
				(start 337.148678 -419.046152)
				(mid 336.889598 -419.046152)
				(end 337.148678 -419.046152)
			)
		)
		(stroke
			(width 0)
			(type solid)
		)
		(fill yes)
		(layer "In2.Cu")
		(net "GND")
	)
	(gr_poly
		(pts
			(arc
				(start 337.148678 -417.778184)
				(mid 336.889598 -417.778184)
				(end 337.148678 -417.778184)
			)
		)
		(stroke
			(width 0)
			(type solid)
		)
		(fill yes)
		(layer "In2.Cu")
		(net "GND")
	)
	(gr_poly
		(pts
			(arc
				(start 337.421474 -421.586152)
				(mid 337.162394 -421.586152)
				(end 337.421474 -421.586152)
			)
		)
		(stroke
			(width 0)
			(type solid)
		)
		(fill yes)
		(layer "In2.Cu")
		(net "GND")
	)
	(gr_poly
		(pts
			(arc
				(start 337.421474 -420.318184)
				(mid 337.162394 -420.318184)
				(end 337.421474 -420.318184)
			)
		)
		(stroke
			(width 0)
			(type solid)
		)
		(fill yes)
		(layer "In2.Cu")
		(net "GND")
	)
	(gr_poly
		(pts
			(arc
				(start 337.509866 -418.412168)
				(mid 337.250786 -418.412168)
				(end 337.509866 -418.412168)
			)
		)
		(stroke
			(width 0)
			(type solid)
		)
		(fill yes)
		(layer "In2.Cu")
		(net "GND")
	)
	(gr_poly
		(pts
			(arc
				(start 338.591906 -418.412168)
				(mid 338.332826 -418.412168)
				(end 338.591906 -418.412168)
			)
		)
		(stroke
			(width 0)
			(type solid)
		)
		(fill yes)
		(layer "In2.Cu")
		(net "GND")
	)
	(gr_poly
		(pts
			(arc
				(start 338.680298 -421.586152)
				(mid 338.421218 -421.586152)
				(end 338.680298 -421.586152)
			)
		)
		(stroke
			(width 0)
			(type solid)
		)
		(fill yes)
		(layer "In2.Cu")
		(net "GND")
	)
	(gr_poly
		(pts
			(arc
				(start 338.680298 -420.318184)
				(mid 338.421218 -420.318184)
				(end 338.680298 -420.318184)
			)
		)
		(stroke
			(width 0)
			(type solid)
		)
		(fill yes)
		(layer "In2.Cu")
		(net "GND")
	)
	(gr_poly
		(pts
			(arc
				(start 338.953094 -419.046152)
				(mid 338.694014 -419.046152)
				(end 338.953094 -419.046152)
			)
		)
		(stroke
			(width 0)
			(type solid)
		)
		(fill yes)
		(layer "In2.Cu")
		(net "GND")
	)
	(gr_poly
		(pts
			(arc
				(start 338.953094 -417.778184)
				(mid 338.694014 -417.778184)
				(end 338.953094 -417.778184)
			)
		)
		(stroke
			(width 0)
			(type solid)
		)
		(fill yes)
		(layer "In2.Cu")
		(net "GND")
	)
	(gr_poly
		(pts
			(arc
				(start 339.041486 -420.952168)
				(mid 338.782406 -420.952168)
				(end 339.041486 -420.952168)
			)
		)
		(stroke
			(width 0)
			(type solid)
		)
		(fill yes)
		(layer "In2.Cu")
		(net "GND")
	)
	(gr_poly
		(pts
			(arc
				(start 340.123526 -420.952168)
				(mid 339.864446 -420.952168)
				(end 340.123526 -420.952168)
			)
		)
		(stroke
			(width 0)
			(type solid)
		)
		(fill yes)
		(layer "In2.Cu")
		(net "GND")
	)
	(gr_poly
		(pts
			(arc
				(start 340.211918 -419.046152)
				(mid 339.952838 -419.046152)
				(end 340.211918 -419.046152)
			)
		)
		(stroke
			(width 0)
			(type solid)
		)
		(fill yes)
		(layer "In2.Cu")
		(net "GND")
	)
	(gr_poly
		(pts
			(arc
				(start 340.211918 -417.778184)
				(mid 339.952838 -417.778184)
				(end 340.211918 -417.778184)
			)
		)
		(stroke
			(width 0)
			(type solid)
		)
		(fill yes)
		(layer "In2.Cu")
		(net "GND")
	)
	(gr_poly
		(pts
			(arc
				(start 340.484714 -421.586152)
				(mid 340.225634 -421.586152)
				(end 340.484714 -421.586152)
			)
		)
		(stroke
			(width 0)
			(type solid)
		)
		(fill yes)
		(layer "In2.Cu")
		(net "GND")
	)
	(gr_poly
		(pts
			(arc
				(start 340.484714 -420.318184)
				(mid 340.225634 -420.318184)
				(end 340.484714 -420.318184)
			)
		)
		(stroke
			(width 0)
			(type solid)
		)
		(fill yes)
		(layer "In2.Cu")
		(net "GND")
	)
	(gr_poly
		(pts
			(arc
				(start 340.573106 -418.412168)
				(mid 340.314026 -418.412168)
				(end 340.573106 -418.412168)
			)
		)
		(stroke
			(width 0)
			(type solid)
		)
		(fill yes)
		(layer "In2.Cu")
		(net "GND")
	)
	(gr_poly
		(pts
			(arc
				(start 341.655146 -418.412168)
				(mid 341.396066 -418.412168)
				(end 341.655146 -418.412168)
			)
		)
		(stroke
			(width 0)
			(type solid)
		)
		(fill yes)
		(layer "In2.Cu")
		(net "GND")
	)
	(gr_poly
		(pts
			(arc
				(start 341.743538 -421.586152)
				(mid 341.484458 -421.586152)
				(end 341.743538 -421.586152)
			)
		)
		(stroke
			(width 0)
			(type solid)
		)
		(fill yes)
		(layer "In2.Cu")
		(net "GND")
	)
	(gr_poly
		(pts
			(arc
				(start 341.743538 -420.318184)
				(mid 341.484458 -420.318184)
				(end 341.743538 -420.318184)
			)
		)
		(stroke
			(width 0)
			(type solid)
		)
		(fill yes)
		(layer "In2.Cu")
		(net "GND")
	)
	(gr_poly
		(pts
			(arc
				(start 342.016334 -419.046152)
				(mid 341.757254 -419.046152)
				(end 342.016334 -419.046152)
			)
		)
		(stroke
			(width 0)
			(type solid)
		)
		(fill yes)
		(layer "In2.Cu")
		(net "GND")
	)
	(gr_poly
		(pts
			(arc
				(start 342.016334 -417.778184)
				(mid 341.757254 -417.778184)
				(end 342.016334 -417.778184)
			)
		)
		(stroke
			(width 0)
			(type solid)
		)
		(fill yes)
		(layer "In2.Cu")
		(net "GND")
	)
	(gr_poly
		(pts
			(arc
				(start 342.104726 -420.952168)
				(mid 341.845646 -420.952168)
				(end 342.104726 -420.952168)
			)
		)
		(stroke
			(width 0)
			(type solid)
		)
		(fill yes)
		(layer "In2.Cu")
		(net "GND")
	)
	(gr_poly
		(pts
			(arc
				(start 343.186766 -420.952168)
				(mid 342.927686 -420.952168)
				(end 343.186766 -420.952168)
			)
		)
		(stroke
			(width 0)
			(type solid)
		)
		(fill yes)
		(layer "In2.Cu")
		(net "GND")
	)
	(gr_poly
		(pts
			(arc
				(start 343.275158 -419.046152)
				(mid 343.016078 -419.046152)
				(end 343.275158 -419.046152)
			)
		)
		(stroke
			(width 0)
			(type solid)
		)
		(fill yes)
		(layer "In2.Cu")
		(net "GND")
	)
	(gr_poly
		(pts
			(arc
				(start 343.275158 -417.778184)
				(mid 343.016078 -417.778184)
				(end 343.275158 -417.778184)
			)
		)
		(stroke
			(width 0)
			(type solid)
		)
		(fill yes)
		(layer "In2.Cu")
		(net "GND")
	)
	(gr_poly
		(pts
			(arc
				(start 343.547954 -421.586152)
				(mid 343.288874 -421.586152)
				(end 343.547954 -421.586152)
			)
		)
		(stroke
			(width 0)
			(type solid)
		)
		(fill yes)
		(layer "In2.Cu")
		(net "GND")
	)
	(gr_poly
		(pts
			(arc
				(start 343.547954 -420.318184)
				(mid 343.288874 -420.318184)
				(end 343.547954 -420.318184)
			)
		)
		(stroke
			(width 0)
			(type solid)
		)
		(fill yes)
		(layer "In2.Cu")
		(net "GND")
	)
	(gr_poly
		(pts
			(arc
				(start 343.636346 -418.412168)
				(mid 343.377266 -418.412168)
				(end 343.636346 -418.412168)
			)
		)
		(stroke
			(width 0)
			(type solid)
		)
		(fill yes)
		(layer "In2.Cu")
		(net "GND")
	)
	(gr_poly
		(pts
			(arc
				(start 344.718386 -418.412168)
				(mid 344.459306 -418.412168)
				(end 344.718386 -418.412168)
			)
		)
		(stroke
			(width 0)
			(type solid)
		)
		(fill yes)
		(layer "In2.Cu")
		(net "GND")
	)
	(gr_poly
		(pts
			(arc
				(start 344.806778 -421.586152)
				(mid 344.547698 -421.586152)
				(end 344.806778 -421.586152)
			)
		)
		(stroke
			(width 0)
			(type solid)
		)
		(fill yes)
		(layer "In2.Cu")
		(net "GND")
	)
	(gr_poly
		(pts
			(arc
				(start 344.806778 -420.318184)
				(mid 344.547698 -420.318184)
				(end 344.806778 -420.318184)
			)
		)
		(stroke
			(width 0)
			(type solid)
		)
		(fill yes)
		(layer "In2.Cu")
		(net "GND")
	)
	(gr_poly
		(pts
			(arc
				(start 345.079574 -419.046152)
				(mid 344.820494 -419.046152)
				(end 345.079574 -419.046152)
			)
		)
		(stroke
			(width 0)
			(type solid)
		)
		(fill yes)
		(layer "In2.Cu")
		(net "GND")
	)
	(gr_poly
		(pts
			(arc
				(start 345.079574 -417.778184)
				(mid 344.820494 -417.778184)
				(end 345.079574 -417.778184)
			)
		)
		(stroke
			(width 0)
			(type solid)
		)
		(fill yes)
		(layer "In2.Cu")
		(net "GND")
	)
	(gr_poly
		(pts
			(arc
				(start 346.250006 -420.952168)
				(mid 345.990926 -420.952168)
				(end 346.250006 -420.952168)
			)
		)
		(stroke
			(width 0)
			(type solid)
		)
		(fill yes)
		(layer "In2.Cu")
		(net "GND")
	)
	(gr_poly
		(pts
			(arc
				(start 346.338398 -419.046152)
				(mid 346.079318 -419.046152)
				(end 346.338398 -419.046152)
			)
		)
		(stroke
			(width 0)
			(type solid)
		)
		(fill yes)
		(layer "In2.Cu")
		(net "GND")
	)
	(gr_poly
		(pts
			(arc
				(start 346.338398 -417.778184)
				(mid 346.079318 -417.778184)
				(end 346.338398 -417.778184)
			)
		)
		(stroke
			(width 0)
			(type solid)
		)
		(fill yes)
		(layer "In2.Cu")
		(net "GND")
	)
	(gr_poly
		(pts
			(arc
				(start 346.611194 -421.586152)
				(mid 346.352114 -421.586152)
				(end 346.611194 -421.586152)
			)
		)
		(stroke
			(width 0)
			(type solid)
		)
		(fill yes)
		(layer "In2.Cu")
		(net "GND")
	)
	(gr_poly
		(pts
			(arc
				(start 346.611194 -420.318184)
				(mid 346.352114 -420.318184)
				(end 346.611194 -420.318184)
			)
		)
		(stroke
			(width 0)
			(type solid)
		)
		(fill yes)
		(layer "In2.Cu")
		(net "GND")
	)
	(gr_poly
		(pts
			(arc
				(start 346.699586 -418.412168)
				(mid 346.440506 -418.412168)
				(end 346.699586 -418.412168)
			)
		)
		(stroke
			(width 0)
			(type solid)
		)
		(fill yes)
		(layer "In2.Cu")
		(net "GND")
	)
	(gr_poly
		(pts
			(arc
				(start 347.781626 -418.412168)
				(mid 347.522546 -418.412168)
				(end 347.781626 -418.412168)
			)
		)
		(stroke
			(width 0)
			(type solid)
		)
		(fill yes)
		(layer "In2.Cu")
		(net "GND")
	)
	(gr_poly
		(pts
			(arc
				(start 347.870018 -421.586152)
				(mid 347.610938 -421.586152)
				(end 347.870018 -421.586152)
			)
		)
		(stroke
			(width 0)
			(type solid)
		)
		(fill yes)
		(layer "In2.Cu")
		(net "GND")
	)
	(gr_poly
		(pts
			(arc
				(start 347.870018 -420.318184)
				(mid 347.610938 -420.318184)
				(end 347.870018 -420.318184)
			)
		)
		(stroke
			(width 0)
			(type solid)
		)
		(fill yes)
		(layer "In2.Cu")
		(net "GND")
	)
	(gr_poly
		(pts
			(arc
				(start 348.142814 -419.046152)
				(mid 347.883734 -419.046152)
				(end 348.142814 -419.046152)
			)
		)
		(stroke
			(width 0)
			(type solid)
		)
		(fill yes)
		(layer "In2.Cu")
		(net "GND")
	)
	(gr_poly
		(pts
			(arc
				(start 348.142814 -417.778184)
				(mid 347.883734 -417.778184)
				(end 348.142814 -417.778184)
			)
		)
		(stroke
			(width 0)
			(type solid)
		)
		(fill yes)
		(layer "In2.Cu")
		(net "GND")
	)
	(gr_poly
		(pts
			(arc
				(start 348.231206 -420.952168)
				(mid 347.972126 -420.952168)
				(end 348.231206 -420.952168)
			)
		)
		(stroke
			(width 0)
			(type solid)
		)
		(fill yes)
		(layer "In2.Cu")
		(net "GND")
	)
	(gr_poly
		(pts
			(arc
				(start 349.313246 -420.952168)
				(mid 349.054166 -420.952168)
				(end 349.313246 -420.952168)
			)
		)
		(stroke
			(width 0)
			(type solid)
		)
		(fill yes)
		(layer "In2.Cu")
		(net "GND")
	)
	(gr_poly
		(pts
			(arc
				(start 349.401638 -419.046152)
				(mid 349.142558 -419.046152)
				(end 349.401638 -419.046152)
			)
		)
		(stroke
			(width 0)
			(type solid)
		)
		(fill yes)
		(layer "In2.Cu")
		(net "GND")
	)
	(gr_poly
		(pts
			(arc
				(start 349.401638 -417.778184)
				(mid 349.142558 -417.778184)
				(end 349.401638 -417.778184)
			)
		)
		(stroke
			(width 0)
			(type solid)
		)
		(fill yes)
		(layer "In2.Cu")
		(net "GND")
	)
	(gr_poly
		(pts
			(arc
				(start 349.674434 -421.586152)
				(mid 349.415354 -421.586152)
				(end 349.674434 -421.586152)
			)
		)
		(stroke
			(width 0)
			(type solid)
		)
		(fill yes)
		(layer "In2.Cu")
		(net "GND")
	)
	(gr_poly
		(pts
			(arc
				(start 349.674434 -420.318184)
				(mid 349.415354 -420.318184)
				(end 349.674434 -420.318184)
			)
		)
		(stroke
			(width 0)
			(type solid)
		)
		(fill yes)
		(layer "In2.Cu")
		(net "GND")
	)
	(gr_poly
		(pts
			(arc
				(start 349.762826 -418.412168)
				(mid 349.503746 -418.412168)
				(end 349.762826 -418.412168)
			)
		)
		(stroke
			(width 0)
			(type solid)
		)
		(fill yes)
		(layer "In2.Cu")
		(net "GND")
	)
	(gr_poly
		(pts
			(arc
				(start 350.844866 -418.412168)
				(mid 350.585786 -418.412168)
				(end 350.844866 -418.412168)
			)
		)
		(stroke
			(width 0)
			(type solid)
		)
		(fill yes)
		(layer "In2.Cu")
		(net "GND")
	)
	(gr_poly
		(pts
			(arc
				(start 350.933258 -421.586152)
				(mid 350.674178 -421.586152)
				(end 350.933258 -421.586152)
			)
		)
		(stroke
			(width 0)
			(type solid)
		)
		(fill yes)
		(layer "In2.Cu")
		(net "GND")
	)
	(gr_poly
		(pts
			(arc
				(start 350.933258 -420.318184)
				(mid 350.674178 -420.318184)
				(end 350.933258 -420.318184)
			)
		)
		(stroke
			(width 0)
			(type solid)
		)
		(fill yes)
		(layer "In2.Cu")
		(net "GND")
	)
	(gr_poly
		(pts
			(arc
				(start 351.206054 -419.046152)
				(mid 350.946974 -419.046152)
				(end 351.206054 -419.046152)
			)
		)
		(stroke
			(width 0)
			(type solid)
		)
		(fill yes)
		(layer "In2.Cu")
		(net "GND")
	)
	(gr_poly
		(pts
			(arc
				(start 351.206054 -417.778184)
				(mid 350.946974 -417.778184)
				(end 351.206054 -417.778184)
			)
		)
		(stroke
			(width 0)
			(type solid)
		)
		(fill yes)
		(layer "In2.Cu")
		(net "GND")
	)
	(gr_poly
		(pts
			(arc
				(start 351.294446 -420.952168)
				(mid 351.035366 -420.952168)
				(end 351.294446 -420.952168)
			)
		)
		(stroke
			(width 0)
			(type solid)
		)
		(fill yes)
		(layer "In2.Cu")
		(net "GND")
	)
	(gr_poly
		(pts
			(arc
				(start 352.464878 -419.046152)
				(mid 352.205798 -419.046152)
				(end 352.464878 -419.046152)
			)
		)
		(stroke
			(width 0)
			(type solid)
		)
		(fill yes)
		(layer "In2.Cu")
		(net "GND")
	)
	(gr_poly
		(pts
			(arc
				(start 352.464878 -417.778184)
				(mid 352.205798 -417.778184)
				(end 352.464878 -417.778184)
			)
		)
		(stroke
			(width 0)
			(type solid)
		)
		(fill yes)
		(layer "In2.Cu")
		(net "GND")
	)
	(gr_poly
		(pts
			(arc
				(start 352.826066 -418.412168)
				(mid 352.566986 -418.412168)
				(end 352.826066 -418.412168)
			)
		)
		(stroke
			(width 0)
			(type solid)
		)
		(fill yes)
		(layer "In2.Cu")
		(net "GND")
	)
	(gr_poly
		(pts
			(arc
				(start 370.464842 -420.952168)
				(mid 370.205762 -420.952168)
				(end 370.464842 -420.952168)
			)
		)
		(stroke
			(width 0)
			(type solid)
		)
		(fill yes)
		(layer "In2.Cu")
		(net "GND")
	)
	(gr_poly
		(pts
			(arc
				(start 370.464842 -412.84652)
				(mid 370.205762 -412.84652)
				(end 370.464842 -412.84652)
			)
		)
		(stroke
			(width 0)
			(type solid)
		)
		(fill yes)
		(layer "In2.Cu")
		(net "GND")
	)
	(gr_poly
		(pts
			(arc
				(start 370.82603 -421.586152)
				(mid 370.56695 -421.586152)
				(end 370.82603 -421.586152)
			)
		)
		(stroke
			(width 0)
			(type solid)
		)
		(fill yes)
		(layer "In2.Cu")
		(net "GND")
	)
	(gr_poly
		(pts
			(arc
				(start 370.82603 -420.318184)
				(mid 370.56695 -420.318184)
				(end 370.82603 -420.318184)
			)
		)
		(stroke
			(width 0)
			(type solid)
		)
		(fill yes)
		(layer "In2.Cu")
		(net "GND")
	)
	(gr_poly
		(pts
			(arc
				(start 370.82603 -413.480504)
				(mid 370.56695 -413.480504)
				(end 370.82603 -413.480504)
			)
		)
		(stroke
			(width 0)
			(type solid)
		)
		(fill yes)
		(layer "In2.Cu")
		(net "GND")
	)
	(gr_poly
		(pts
			(arc
				(start 370.82603 -412.212536)
				(mid 370.56695 -412.212536)
				(end 370.82603 -412.212536)
			)
		)
		(stroke
			(width 0)
			(type solid)
		)
		(fill yes)
		(layer "In2.Cu")
		(net "GND")
	)
	(gr_poly
		(pts
			(arc
				(start 371.996462 -418.412168)
				(mid 371.737382 -418.412168)
				(end 371.996462 -418.412168)
			)
		)
		(stroke
			(width 0)
			(type solid)
		)
		(fill yes)
		(layer "In2.Cu")
		(net "GND")
	)
	(gr_poly
		(pts
			(arc
				(start 371.996462 -415.38652)
				(mid 371.737382 -415.38652)
				(end 371.996462 -415.38652)
			)
		)
		(stroke
			(width 0)
			(type solid)
		)
		(fill yes)
		(layer "In2.Cu")
		(net "GND")
	)
	(gr_poly
		(pts
			(arc
				(start 372.084854 -421.586152)
				(mid 371.825774 -421.586152)
				(end 372.084854 -421.586152)
			)
		)
		(stroke
			(width 0)
			(type solid)
		)
		(fill yes)
		(layer "In2.Cu")
		(net "GND")
	)
	(gr_poly
		(pts
			(arc
				(start 372.084854 -420.318184)
				(mid 371.825774 -420.318184)
				(end 372.084854 -420.318184)
			)
		)
		(stroke
			(width 0)
			(type solid)
		)
		(fill yes)
		(layer "In2.Cu")
		(net "GND")
	)
	(gr_poly
		(pts
			(arc
				(start 372.084854 -413.480504)
				(mid 371.825774 -413.480504)
				(end 372.084854 -413.480504)
			)
		)
		(stroke
			(width 0)
			(type solid)
		)
		(fill yes)
		(layer "In2.Cu")
		(net "GND")
	)
	(gr_poly
		(pts
			(arc
				(start 372.084854 -412.212536)
				(mid 371.825774 -412.212536)
				(end 372.084854 -412.212536)
			)
		)
		(stroke
			(width 0)
			(type solid)
		)
		(fill yes)
		(layer "In2.Cu")
		(net "GND")
	)
	(gr_poly
		(pts
			(arc
				(start 372.35765 -419.046152)
				(mid 372.09857 -419.046152)
				(end 372.35765 -419.046152)
			)
		)
		(stroke
			(width 0)
			(type solid)
		)
		(fill yes)
		(layer "In2.Cu")
		(net "GND")
	)
	(gr_poly
		(pts
			(arc
				(start 372.35765 -417.778184)
				(mid 372.09857 -417.778184)
				(end 372.35765 -417.778184)
			)
		)
		(stroke
			(width 0)
			(type solid)
		)
		(fill yes)
		(layer "In2.Cu")
		(net "GND")
	)
	(gr_poly
		(pts
			(arc
				(start 372.35765 -416.020504)
				(mid 372.09857 -416.020504)
				(end 372.35765 -416.020504)
			)
		)
		(stroke
			(width 0)
			(type solid)
		)
		(fill yes)
		(layer "In2.Cu")
		(net "GND")
	)
	(gr_poly
		(pts
			(arc
				(start 372.35765 -414.752536)
				(mid 372.09857 -414.752536)
				(end 372.35765 -414.752536)
			)
		)
		(stroke
			(width 0)
			(type solid)
		)
		(fill yes)
		(layer "In2.Cu")
		(net "GND")
	)
	(gr_poly
		(pts
			(arc
				(start 372.446042 -420.952168)
				(mid 372.186962 -420.952168)
				(end 372.446042 -420.952168)
			)
		)
		(stroke
			(width 0)
			(type solid)
		)
		(fill yes)
		(layer "In2.Cu")
		(net "GND")
	)
	(gr_poly
		(pts
			(arc
				(start 372.446042 -412.84652)
				(mid 372.186962 -412.84652)
				(end 372.446042 -412.84652)
			)
		)
		(stroke
			(width 0)
			(type solid)
		)
		(fill yes)
		(layer "In2.Cu")
		(net "GND")
	)
	(gr_poly
		(pts
			(arc
				(start 373.528082 -420.952168)
				(mid 373.269002 -420.952168)
				(end 373.528082 -420.952168)
			)
		)
		(stroke
			(width 0)
			(type solid)
		)
		(fill yes)
		(layer "In2.Cu")
		(net "GND")
	)
	(gr_poly
		(pts
			(arc
				(start 373.528082 -412.84652)
				(mid 373.269002 -412.84652)
				(end 373.528082 -412.84652)
			)
		)
		(stroke
			(width 0)
			(type solid)
		)
		(fill yes)
		(layer "In2.Cu")
		(net "GND")
	)
	(gr_poly
		(pts
			(arc
				(start 373.616474 -419.046152)
				(mid 373.357394 -419.046152)
				(end 373.616474 -419.046152)
			)
		)
		(stroke
			(width 0)
			(type solid)
		)
		(fill yes)
		(layer "In2.Cu")
		(net "GND")
	)
	(gr_poly
		(pts
			(arc
				(start 373.616474 -417.778184)
				(mid 373.357394 -417.778184)
				(end 373.616474 -417.778184)
			)
		)
		(stroke
			(width 0)
			(type solid)
		)
		(fill yes)
		(layer "In2.Cu")
		(net "GND")
	)
	(gr_poly
		(pts
			(arc
				(start 373.616474 -416.020504)
				(mid 373.357394 -416.020504)
				(end 373.616474 -416.020504)
			)
		)
		(stroke
			(width 0)
			(type solid)
		)
		(fill yes)
		(layer "In2.Cu")
		(net "GND")
	)
	(gr_poly
		(pts
			(arc
				(start 373.616474 -414.752536)
				(mid 373.357394 -414.752536)
				(end 373.616474 -414.752536)
			)
		)
		(stroke
			(width 0)
			(type solid)
		)
		(fill yes)
		(layer "In2.Cu")
		(net "GND")
	)
	(gr_poly
		(pts
			(arc
				(start 373.88927 -421.586152)
				(mid 373.63019 -421.586152)
				(end 373.88927 -421.586152)
			)
		)
		(stroke
			(width 0)
			(type solid)
		)
		(fill yes)
		(layer "In2.Cu")
		(net "GND")
	)
	(gr_poly
		(pts
			(arc
				(start 373.88927 -420.318184)
				(mid 373.63019 -420.318184)
				(end 373.88927 -420.318184)
			)
		)
		(stroke
			(width 0)
			(type solid)
		)
		(fill yes)
		(layer "In2.Cu")
		(net "GND")
	)
	(gr_poly
		(pts
			(arc
				(start 373.88927 -413.480504)
				(mid 373.63019 -413.480504)
				(end 373.88927 -413.480504)
			)
		)
		(stroke
			(width 0)
			(type solid)
		)
		(fill yes)
		(layer "In2.Cu")
		(net "GND")
	)
	(gr_poly
		(pts
			(arc
				(start 373.88927 -412.212536)
				(mid 373.63019 -412.212536)
				(end 373.88927 -412.212536)
			)
		)
		(stroke
			(width 0)
			(type solid)
		)
		(fill yes)
		(layer "In2.Cu")
		(net "GND")
	)
	(gr_poly
		(pts
			(arc
				(start 373.977662 -418.412168)
				(mid 373.718582 -418.412168)
				(end 373.977662 -418.412168)
			)
		)
		(stroke
			(width 0)
			(type solid)
		)
		(fill yes)
		(layer "In2.Cu")
		(net "GND")
	)
	(gr_poly
		(pts
			(arc
				(start 373.977662 -415.38652)
				(mid 373.718582 -415.38652)
				(end 373.977662 -415.38652)
			)
		)
		(stroke
			(width 0)
			(type solid)
		)
		(fill yes)
		(layer "In2.Cu")
		(net "GND")
	)
	(gr_poly
		(pts
			(arc
				(start 375.059702 -418.412168)
				(mid 374.800622 -418.412168)
				(end 375.059702 -418.412168)
			)
		)
		(stroke
			(width 0)
			(type solid)
		)
		(fill yes)
		(layer "In2.Cu")
		(net "GND")
	)
	(gr_poly
		(pts
			(arc
				(start 375.059702 -415.38652)
				(mid 374.800622 -415.38652)
				(end 375.059702 -415.38652)
			)
		)
		(stroke
			(width 0)
			(type solid)
		)
		(fill yes)
		(layer "In2.Cu")
		(net "GND")
	)
	(gr_poly
		(pts
			(arc
				(start 375.148094 -421.586152)
				(mid 374.889014 -421.586152)
				(end 375.148094 -421.586152)
			)
		)
		(stroke
			(width 0)
			(type solid)
		)
		(fill yes)
		(layer "In2.Cu")
		(net "GND")
	)
	(gr_poly
		(pts
			(arc
				(start 375.148094 -420.318184)
				(mid 374.889014 -420.318184)
				(end 375.148094 -420.318184)
			)
		)
		(stroke
			(width 0)
			(type solid)
		)
		(fill yes)
		(layer "In2.Cu")
		(net "GND")
	)
	(gr_poly
		(pts
			(arc
				(start 375.148094 -413.480504)
				(mid 374.889014 -413.480504)
				(end 375.148094 -413.480504)
			)
		)
		(stroke
			(width 0)
			(type solid)
		)
		(fill yes)
		(layer "In2.Cu")
		(net "GND")
	)
	(gr_poly
		(pts
			(arc
				(start 375.148094 -412.212536)
				(mid 374.889014 -412.212536)
				(end 375.148094 -412.212536)
			)
		)
		(stroke
			(width 0)
			(type solid)
		)
		(fill yes)
		(layer "In2.Cu")
		(net "GND")
	)
	(gr_poly
		(pts
			(arc
				(start 375.42089 -419.046152)
				(mid 375.16181 -419.046152)
				(end 375.42089 -419.046152)
			)
		)
		(stroke
			(width 0)
			(type solid)
		)
		(fill yes)
		(layer "In2.Cu")
		(net "GND")
	)
	(gr_poly
		(pts
			(arc
				(start 375.42089 -417.778184)
				(mid 375.16181 -417.778184)
				(end 375.42089 -417.778184)
			)
		)
		(stroke
			(width 0)
			(type solid)
		)
		(fill yes)
		(layer "In2.Cu")
		(net "GND")
	)
	(gr_poly
		(pts
			(arc
				(start 375.42089 -416.020504)
				(mid 375.16181 -416.020504)
				(end 375.42089 -416.020504)
			)
		)
		(stroke
			(width 0)
			(type solid)
		)
		(fill yes)
		(layer "In2.Cu")
		(net "GND")
	)
	(gr_poly
		(pts
			(arc
				(start 375.42089 -414.752536)
				(mid 375.16181 -414.752536)
				(end 375.42089 -414.752536)
			)
		)
		(stroke
			(width 0)
			(type solid)
		)
		(fill yes)
		(layer "In2.Cu")
		(net "GND")
	)
	(gr_poly
		(pts
			(arc
				(start 375.509282 -420.952168)
				(mid 375.250202 -420.952168)
				(end 375.509282 -420.952168)
			)
		)
		(stroke
			(width 0)
			(type solid)
		)
		(fill yes)
		(layer "In2.Cu")
		(net "GND")
	)
	(gr_poly
		(pts
			(arc
				(start 375.509282 -412.84652)
				(mid 375.250202 -412.84652)
				(end 375.509282 -412.84652)
			)
		)
		(stroke
			(width 0)
			(type solid)
		)
		(fill yes)
		(layer "In2.Cu")
		(net "GND")
	)
	(gr_poly
		(pts
			(arc
				(start 376.591322 -420.952168)
				(mid 376.332242 -420.952168)
				(end 376.591322 -420.952168)
			)
		)
		(stroke
			(width 0)
			(type solid)
		)
		(fill yes)
		(layer "In2.Cu")
		(net "GND")
	)
	(gr_poly
		(pts
			(arc
				(start 376.591322 -412.84652)
				(mid 376.332242 -412.84652)
				(end 376.591322 -412.84652)
			)
		)
		(stroke
			(width 0)
			(type solid)
		)
		(fill yes)
		(layer "In2.Cu")
		(net "GND")
	)
	(gr_poly
		(pts
			(arc
				(start 376.679714 -419.046152)
				(mid 376.420634 -419.046152)
				(end 376.679714 -419.046152)
			)
		)
		(stroke
			(width 0)
			(type solid)
		)
		(fill yes)
		(layer "In2.Cu")
		(net "GND")
	)
	(gr_poly
		(pts
			(arc
				(start 376.679714 -417.778184)
				(mid 376.420634 -417.778184)
				(end 376.679714 -417.778184)
			)
		)
		(stroke
			(width 0)
			(type solid)
		)
		(fill yes)
		(layer "In2.Cu")
		(net "GND")
	)
	(gr_poly
		(pts
			(arc
				(start 376.679714 -416.020504)
				(mid 376.420634 -416.020504)
				(end 376.679714 -416.020504)
			)
		)
		(stroke
			(width 0)
			(type solid)
		)
		(fill yes)
		(layer "In2.Cu")
		(net "GND")
	)
	(gr_poly
		(pts
			(arc
				(start 376.679714 -414.752536)
				(mid 376.420634 -414.752536)
				(end 376.679714 -414.752536)
			)
		)
		(stroke
			(width 0)
			(type solid)
		)
		(fill yes)
		(layer "In2.Cu")
		(net "GND")
	)
	(gr_poly
		(pts
			(arc
				(start 376.95251 -421.586152)
				(mid 376.69343 -421.586152)
				(end 376.95251 -421.586152)
			)
		)
		(stroke
			(width 0)
			(type solid)
		)
		(fill yes)
		(layer "In2.Cu")
		(net "GND")
	)
	(gr_poly
		(pts
			(arc
				(start 376.95251 -420.318184)
				(mid 376.69343 -420.318184)
				(end 376.95251 -420.318184)
			)
		)
		(stroke
			(width 0)
			(type solid)
		)
		(fill yes)
		(layer "In2.Cu")
		(net "GND")
	)
	(gr_poly
		(pts
			(arc
				(start 376.95251 -413.480504)
				(mid 376.69343 -413.480504)
				(end 376.95251 -413.480504)
			)
		)
		(stroke
			(width 0)
			(type solid)
		)
		(fill yes)
		(layer "In2.Cu")
		(net "GND")
	)
	(gr_poly
		(pts
			(arc
				(start 376.95251 -412.212536)
				(mid 376.69343 -412.212536)
				(end 376.95251 -412.212536)
			)
		)
		(stroke
			(width 0)
			(type solid)
		)
		(fill yes)
		(layer "In2.Cu")
		(net "GND")
	)
	(gr_poly
		(pts
			(arc
				(start 377.040902 -418.412168)
				(mid 376.781822 -418.412168)
				(end 377.040902 -418.412168)
			)
		)
		(stroke
			(width 0)
			(type solid)
		)
		(fill yes)
		(layer "In2.Cu")
		(net "GND")
	)
	(gr_poly
		(pts
			(arc
				(start 377.040902 -415.38652)
				(mid 376.781822 -415.38652)
				(end 377.040902 -415.38652)
			)
		)
		(stroke
			(width 0)
			(type solid)
		)
		(fill yes)
		(layer "In2.Cu")
		(net "GND")
	)
	(gr_poly
		(pts
			(arc
				(start 378.122942 -418.412168)
				(mid 377.863862 -418.412168)
				(end 378.122942 -418.412168)
			)
		)
		(stroke
			(width 0)
			(type solid)
		)
		(fill yes)
		(layer "In2.Cu")
		(net "GND")
	)
	(gr_poly
		(pts
			(arc
				(start 378.122942 -415.38652)
				(mid 377.863862 -415.38652)
				(end 378.122942 -415.38652)
			)
		)
		(stroke
			(width 0)
			(type solid)
		)
		(fill yes)
		(layer "In2.Cu")
		(net "GND")
	)
	(gr_poly
		(pts
			(arc
				(start 378.211334 -421.586152)
				(mid 377.952254 -421.586152)
				(end 378.211334 -421.586152)
			)
		)
		(stroke
			(width 0)
			(type solid)
		)
		(fill yes)
		(layer "In2.Cu")
		(net "GND")
	)
	(gr_poly
		(pts
			(arc
				(start 378.211334 -420.318184)
				(mid 377.952254 -420.318184)
				(end 378.211334 -420.318184)
			)
		)
		(stroke
			(width 0)
			(type solid)
		)
		(fill yes)
		(layer "In2.Cu")
		(net "GND")
	)
	(gr_poly
		(pts
			(arc
				(start 378.211334 -413.480504)
				(mid 377.952254 -413.480504)
				(end 378.211334 -413.480504)
			)
		)
		(stroke
			(width 0)
			(type solid)
		)
		(fill yes)
		(layer "In2.Cu")
		(net "GND")
	)
	(gr_poly
		(pts
			(arc
				(start 378.211334 -412.212536)
				(mid 377.952254 -412.212536)
				(end 378.211334 -412.212536)
			)
		)
		(stroke
			(width 0)
			(type solid)
		)
		(fill yes)
		(layer "In2.Cu")
		(net "GND")
	)
	(gr_poly
		(pts
			(arc
				(start 378.48413 -419.046152)
				(mid 378.22505 -419.046152)
				(end 378.48413 -419.046152)
			)
		)
		(stroke
			(width 0)
			(type solid)
		)
		(fill yes)
		(layer "In2.Cu")
		(net "GND")
	)
	(gr_poly
		(pts
			(arc
				(start 378.48413 -417.778184)
				(mid 378.22505 -417.778184)
				(end 378.48413 -417.778184)
			)
		)
		(stroke
			(width 0)
			(type solid)
		)
		(fill yes)
		(layer "In2.Cu")
		(net "GND")
	)
	(gr_poly
		(pts
			(arc
				(start 378.48413 -416.020504)
				(mid 378.22505 -416.020504)
				(end 378.48413 -416.020504)
			)
		)
		(stroke
			(width 0)
			(type solid)
		)
		(fill yes)
		(layer "In2.Cu")
		(net "GND")
	)
	(gr_poly
		(pts
			(arc
				(start 378.48413 -414.752536)
				(mid 378.22505 -414.752536)
				(end 378.48413 -414.752536)
			)
		)
		(stroke
			(width 0)
			(type solid)
		)
		(fill yes)
		(layer "In2.Cu")
		(net "GND")
	)
	(gr_poly
		(pts
			(arc
				(start 378.572522 -420.952168)
				(mid 378.313442 -420.952168)
				(end 378.572522 -420.952168)
			)
		)
		(stroke
			(width 0)
			(type solid)
		)
		(fill yes)
		(layer "In2.Cu")
		(net "GND")
	)
	(gr_poly
		(pts
			(arc
				(start 378.572522 -412.84652)
				(mid 378.313442 -412.84652)
				(end 378.572522 -412.84652)
			)
		)
		(stroke
			(width 0)
			(type solid)
		)
		(fill yes)
		(layer "In2.Cu")
		(net "GND")
	)
	(gr_poly
		(pts
			(arc
				(start 379.654562 -420.952168)
				(mid 379.395482 -420.952168)
				(end 379.654562 -420.952168)
			)
		)
		(stroke
			(width 0)
			(type solid)
		)
		(fill yes)
		(layer "In2.Cu")
		(net "GND")
	)
	(gr_poly
		(pts
			(arc
				(start 379.654562 -412.84652)
				(mid 379.395482 -412.84652)
				(end 379.654562 -412.84652)
			)
		)
		(stroke
			(width 0)
			(type solid)
		)
		(fill yes)
		(layer "In2.Cu")
		(net "GND")
	)
	(gr_poly
		(pts
			(arc
				(start 379.742954 -419.046152)
				(mid 379.483874 -419.046152)
				(end 379.742954 -419.046152)
			)
		)
		(stroke
			(width 0)
			(type solid)
		)
		(fill yes)
		(layer "In2.Cu")
		(net "GND")
	)
	(gr_poly
		(pts
			(arc
				(start 379.742954 -417.778184)
				(mid 379.483874 -417.778184)
				(end 379.742954 -417.778184)
			)
		)
		(stroke
			(width 0)
			(type solid)
		)
		(fill yes)
		(layer "In2.Cu")
		(net "GND")
	)
	(gr_poly
		(pts
			(arc
				(start 379.742954 -416.020504)
				(mid 379.483874 -416.020504)
				(end 379.742954 -416.020504)
			)
		)
		(stroke
			(width 0)
			(type solid)
		)
		(fill yes)
		(layer "In2.Cu")
		(net "GND")
	)
	(gr_poly
		(pts
			(arc
				(start 379.742954 -414.752536)
				(mid 379.483874 -414.752536)
				(end 379.742954 -414.752536)
			)
		)
		(stroke
			(width 0)
			(type solid)
		)
		(fill yes)
		(layer "In2.Cu")
		(net "GND")
	)
	(gr_poly
		(pts
			(arc
				(start 380.01575 -421.586152)
				(mid 379.75667 -421.586152)
				(end 380.01575 -421.586152)
			)
		)
		(stroke
			(width 0)
			(type solid)
		)
		(fill yes)
		(layer "In2.Cu")
		(net "GND")
	)
	(gr_poly
		(pts
			(arc
				(start 380.01575 -420.318184)
				(mid 379.75667 -420.318184)
				(end 380.01575 -420.318184)
			)
		)
		(stroke
			(width 0)
			(type solid)
		)
		(fill yes)
		(layer "In2.Cu")
		(net "GND")
	)
	(gr_poly
		(pts
			(arc
				(start 380.01575 -413.480504)
				(mid 379.75667 -413.480504)
				(end 380.01575 -413.480504)
			)
		)
		(stroke
			(width 0)
			(type solid)
		)
		(fill yes)
		(layer "In2.Cu")
		(net "GND")
	)
	(gr_poly
		(pts
			(arc
				(start 380.01575 -412.212536)
				(mid 379.75667 -412.212536)
				(end 380.01575 -412.212536)
			)
		)
		(stroke
			(width 0)
			(type solid)
		)
		(fill yes)
		(layer "In2.Cu")
		(net "GND")
	)
	(gr_poly
		(pts
			(arc
				(start 380.104142 -418.412168)
				(mid 379.845062 -418.412168)
				(end 380.104142 -418.412168)
			)
		)
		(stroke
			(width 0)
			(type solid)
		)
		(fill yes)
		(layer "In2.Cu")
		(net "GND")
	)
	(gr_poly
		(pts
			(arc
				(start 380.104142 -415.38652)
				(mid 379.845062 -415.38652)
				(end 380.104142 -415.38652)
			)
		)
		(stroke
			(width 0)
			(type solid)
		)
		(fill yes)
		(layer "In2.Cu")
		(net "GND")
	)
	(gr_poly
		(pts
			(arc
				(start 381.186182 -418.412168)
				(mid 380.927102 -418.412168)
				(end 381.186182 -418.412168)
			)
		)
		(stroke
			(width 0)
			(type solid)
		)
		(fill yes)
		(layer "In2.Cu")
		(net "GND")
	)
	(gr_poly
		(pts
			(arc
				(start 381.186182 -415.38652)
				(mid 380.927102 -415.38652)
				(end 381.186182 -415.38652)
			)
		)
		(stroke
			(width 0)
			(type solid)
		)
		(fill yes)
		(layer "In2.Cu")
		(net "GND")
	)
	(gr_poly
		(pts
			(arc
				(start 381.274574 -421.586152)
				(mid 381.015494 -421.586152)
				(end 381.274574 -421.586152)
			)
		)
		(stroke
			(width 0)
			(type solid)
		)
		(fill yes)
		(layer "In2.Cu")
		(net "GND")
	)
	(gr_poly
		(pts
			(arc
				(start 381.274574 -420.318184)
				(mid 381.015494 -420.318184)
				(end 381.274574 -420.318184)
			)
		)
		(stroke
			(width 0)
			(type solid)
		)
		(fill yes)
		(layer "In2.Cu")
		(net "GND")
	)
	(gr_poly
		(pts
			(arc
				(start 381.274574 -413.480504)
				(mid 381.015494 -413.480504)
				(end 381.274574 -413.480504)
			)
		)
		(stroke
			(width 0)
			(type solid)
		)
		(fill yes)
		(layer "In2.Cu")
		(net "GND")
	)
	(gr_poly
		(pts
			(arc
				(start 381.274574 -412.212536)
				(mid 381.015494 -412.212536)
				(end 381.274574 -412.212536)
			)
		)
		(stroke
			(width 0)
			(type solid)
		)
		(fill yes)
		(layer "In2.Cu")
		(net "GND")
	)
	(gr_poly
		(pts
			(arc
				(start 381.54737 -419.046152)
				(mid 381.28829 -419.046152)
				(end 381.54737 -419.046152)
			)
		)
		(stroke
			(width 0)
			(type solid)
		)
		(fill yes)
		(layer "In2.Cu")
		(net "GND")
	)
	(gr_poly
		(pts
			(arc
				(start 381.54737 -417.778184)
				(mid 381.28829 -417.778184)
				(end 381.54737 -417.778184)
			)
		)
		(stroke
			(width 0)
			(type solid)
		)
		(fill yes)
		(layer "In2.Cu")
		(net "GND")
	)
	(gr_poly
		(pts
			(arc
				(start 381.54737 -416.020504)
				(mid 381.28829 -416.020504)
				(end 381.54737 -416.020504)
			)
		)
		(stroke
			(width 0)
			(type solid)
		)
		(fill yes)
		(layer "In2.Cu")
		(net "GND")
	)
	(gr_poly
		(pts
			(arc
				(start 381.54737 -414.752536)
				(mid 381.28829 -414.752536)
				(end 381.54737 -414.752536)
			)
		)
		(stroke
			(width 0)
			(type solid)
		)
		(fill yes)
		(layer "In2.Cu")
		(net "GND")
	)
	(gr_poly
		(pts
			(arc
				(start 381.635762 -420.952168)
				(mid 381.376682 -420.952168)
				(end 381.635762 -420.952168)
			)
		)
		(stroke
			(width 0)
			(type solid)
		)
		(fill yes)
		(layer "In2.Cu")
		(net "GND")
	)
	(gr_poly
		(pts
			(arc
				(start 381.635762 -412.84652)
				(mid 381.376682 -412.84652)
				(end 381.635762 -412.84652)
			)
		)
		(stroke
			(width 0)
			(type solid)
		)
		(fill yes)
		(layer "In2.Cu")
		(net "GND")
	)
	(gr_poly
		(pts
			(arc
				(start 382.717802 -420.952168)
				(mid 382.458722 -420.952168)
				(end 382.717802 -420.952168)
			)
		)
		(stroke
			(width 0)
			(type solid)
		)
		(fill yes)
		(layer "In2.Cu")
		(net "GND")
	)
	(gr_poly
		(pts
			(arc
				(start 382.717802 -412.84652)
				(mid 382.458722 -412.84652)
				(end 382.717802 -412.84652)
			)
		)
		(stroke
			(width 0)
			(type solid)
		)
		(fill yes)
		(layer "In2.Cu")
		(net "GND")
	)
	(gr_poly
		(pts
			(arc
				(start 382.806194 -419.046152)
				(mid 382.547114 -419.046152)
				(end 382.806194 -419.046152)
			)
		)
		(stroke
			(width 0)
			(type solid)
		)
		(fill yes)
		(layer "In2.Cu")
		(net "GND")
	)
	(gr_poly
		(pts
			(arc
				(start 382.806194 -417.778184)
				(mid 382.547114 -417.778184)
				(end 382.806194 -417.778184)
			)
		)
		(stroke
			(width 0)
			(type solid)
		)
		(fill yes)
		(layer "In2.Cu")
		(net "GND")
	)
	(gr_poly
		(pts
			(arc
				(start 382.806194 -416.020504)
				(mid 382.547114 -416.020504)
				(end 382.806194 -416.020504)
			)
		)
		(stroke
			(width 0)
			(type solid)
		)
		(fill yes)
		(layer "In2.Cu")
		(net "GND")
	)
	(gr_poly
		(pts
			(arc
				(start 382.806194 -414.752536)
				(mid 382.547114 -414.752536)
				(end 382.806194 -414.752536)
			)
		)
		(stroke
			(width 0)
			(type solid)
		)
		(fill yes)
		(layer "In2.Cu")
		(net "GND")
	)
	(gr_poly
		(pts
			(arc
				(start 383.07899 -421.586152)
				(mid 382.81991 -421.586152)
				(end 383.07899 -421.586152)
			)
		)
		(stroke
			(width 0)
			(type solid)
		)
		(fill yes)
		(layer "In2.Cu")
		(net "GND")
	)
	(gr_poly
		(pts
			(arc
				(start 383.07899 -420.318184)
				(mid 382.81991 -420.318184)
				(end 383.07899 -420.318184)
			)
		)
		(stroke
			(width 0)
			(type solid)
		)
		(fill yes)
		(layer "In2.Cu")
		(net "GND")
	)
	(gr_poly
		(pts
			(arc
				(start 383.07899 -413.480504)
				(mid 382.81991 -413.480504)
				(end 383.07899 -413.480504)
			)
		)
		(stroke
			(width 0)
			(type solid)
		)
		(fill yes)
		(layer "In2.Cu")
		(net "GND")
	)
	(gr_poly
		(pts
			(arc
				(start 383.07899 -412.212536)
				(mid 382.81991 -412.212536)
				(end 383.07899 -412.212536)
			)
		)
		(stroke
			(width 0)
			(type solid)
		)
		(fill yes)
		(layer "In2.Cu")
		(net "GND")
	)
	(gr_poly
		(pts
			(arc
				(start 383.167382 -418.412168)
				(mid 382.908302 -418.412168)
				(end 383.167382 -418.412168)
			)
		)
		(stroke
			(width 0)
			(type solid)
		)
		(fill yes)
		(layer "In2.Cu")
		(net "GND")
	)
	(gr_poly
		(pts
			(arc
				(start 383.167382 -415.38652)
				(mid 382.908302 -415.38652)
				(end 383.167382 -415.38652)
			)
		)
		(stroke
			(width 0)
			(type solid)
		)
		(fill yes)
		(layer "In2.Cu")
		(net "GND")
	)
	(gr_poly
		(pts
			(arc
				(start 384.249422 -418.412168)
				(mid 383.990342 -418.412168)
				(end 384.249422 -418.412168)
			)
		)
		(stroke
			(width 0)
			(type solid)
		)
		(fill yes)
		(layer "In2.Cu")
		(net "GND")
	)
	(gr_poly
		(pts
			(arc
				(start 384.249422 -415.38652)
				(mid 383.990342 -415.38652)
				(end 384.249422 -415.38652)
			)
		)
		(stroke
			(width 0)
			(type solid)
		)
		(fill yes)
		(layer "In2.Cu")
		(net "GND")
	)
	(gr_poly
		(pts
			(arc
				(start 384.337814 -420.318184)
				(mid 384.078734 -420.318184)
				(end 384.337814 -420.318184)
			)
		)
		(stroke
			(width 0)
			(type solid)
		)
		(fill yes)
		(layer "In2.Cu")
		(net "GND")
	)
	(gr_poly
		(pts
			(arc
				(start 384.337814 -413.480504)
				(mid 384.078734 -413.480504)
				(end 384.337814 -413.480504)
			)
		)
		(stroke
			(width 0)
			(type solid)
		)
		(fill yes)
		(layer "In2.Cu")
		(net "GND")
	)
	(gr_poly
		(pts
			(arc
				(start 384.337814 -412.212536)
				(mid 384.078734 -412.212536)
				(end 384.337814 -412.212536)
			)
		)
		(stroke
			(width 0)
			(type solid)
		)
		(fill yes)
		(layer "In2.Cu")
		(net "GND")
	)
	(gr_poly
		(pts
			(arc
				(start 384.388614 -421.535352)
				(mid 384.129534 -421.535352)
				(end 384.388614 -421.535352)
			)
		)
		(stroke
			(width 0)
			(type solid)
		)
		(fill yes)
		(layer "In2.Cu")
		(net "GND")
	)
	(gr_poly
		(pts
			(arc
				(start 384.61061 -419.046152)
				(mid 384.35153 -419.046152)
				(end 384.61061 -419.046152)
			)
		)
		(stroke
			(width 0)
			(type solid)
		)
		(fill yes)
		(layer "In2.Cu")
		(net "GND")
	)
	(gr_poly
		(pts
			(arc
				(start 384.61061 -417.778184)
				(mid 384.35153 -417.778184)
				(end 384.61061 -417.778184)
			)
		)
		(stroke
			(width 0)
			(type solid)
		)
		(fill yes)
		(layer "In2.Cu")
		(net "GND")
	)
	(gr_poly
		(pts
			(arc
				(start 384.61061 -416.020504)
				(mid 384.35153 -416.020504)
				(end 384.61061 -416.020504)
			)
		)
		(stroke
			(width 0)
			(type solid)
		)
		(fill yes)
		(layer "In2.Cu")
		(net "GND")
	)
	(gr_poly
		(pts
			(arc
				(start 384.61061 -414.752536)
				(mid 384.35153 -414.752536)
				(end 384.61061 -414.752536)
			)
		)
		(stroke
			(width 0)
			(type solid)
		)
		(fill yes)
		(layer "In2.Cu")
		(net "GND")
	)
	(gr_poly
		(pts
			(arc
				(start 384.699002 -420.952168)
				(mid 384.439922 -420.952168)
				(end 384.699002 -420.952168)
			)
		)
		(stroke
			(width 0)
			(type solid)
		)
		(fill yes)
		(layer "In2.Cu")
		(net "GND")
	)
	(gr_poly
		(pts
			(arc
				(start 384.699002 -412.84652)
				(mid 384.439922 -412.84652)
				(end 384.699002 -412.84652)
			)
		)
		(stroke
			(width 0)
			(type solid)
		)
		(fill yes)
		(layer "In2.Cu")
		(net "GND")
	)
	(gr_poly
		(pts
			(arc
				(start 385.781042 -420.952168)
				(mid 385.521962 -420.952168)
				(end 385.781042 -420.952168)
			)
		)
		(stroke
			(width 0)
			(type solid)
		)
		(fill yes)
		(layer "In2.Cu")
		(net "GND")
	)
	(gr_poly
		(pts
			(arc
				(start 385.781042 -412.84652)
				(mid 385.521962 -412.84652)
				(end 385.781042 -412.84652)
			)
		)
		(stroke
			(width 0)
			(type solid)
		)
		(fill yes)
		(layer "In2.Cu")
		(net "GND")
	)
	(gr_poly
		(pts
			(arc
				(start 385.869434 -419.046152)
				(mid 385.610354 -419.046152)
				(end 385.869434 -419.046152)
			)
		)
		(stroke
			(width 0)
			(type solid)
		)
		(fill yes)
		(layer "In2.Cu")
		(net "GND")
	)
	(gr_poly
		(pts
			(arc
				(start 385.869434 -417.778184)
				(mid 385.610354 -417.778184)
				(end 385.869434 -417.778184)
			)
		)
		(stroke
			(width 0)
			(type solid)
		)
		(fill yes)
		(layer "In2.Cu")
		(net "GND")
	)
	(gr_poly
		(pts
			(arc
				(start 385.869434 -416.020504)
				(mid 385.610354 -416.020504)
				(end 385.869434 -416.020504)
			)
		)
		(stroke
			(width 0)
			(type solid)
		)
		(fill yes)
		(layer "In2.Cu")
		(net "GND")
	)
	(gr_poly
		(pts
			(arc
				(start 385.869434 -414.752536)
				(mid 385.610354 -414.752536)
				(end 385.869434 -414.752536)
			)
		)
		(stroke
			(width 0)
			(type solid)
		)
		(fill yes)
		(layer "In2.Cu")
		(net "GND")
	)
	(gr_poly
		(pts
			(arc
				(start 386.14223 -421.586152)
				(mid 385.88315 -421.586152)
				(end 386.14223 -421.586152)
			)
		)
		(stroke
			(width 0)
			(type solid)
		)
		(fill yes)
		(layer "In2.Cu")
		(net "GND")
	)
	(gr_poly
		(pts
			(arc
				(start 386.14223 -420.318184)
				(mid 385.88315 -420.318184)
				(end 386.14223 -420.318184)
			)
		)
		(stroke
			(width 0)
			(type solid)
		)
		(fill yes)
		(layer "In2.Cu")
		(net "GND")
	)
	(gr_poly
		(pts
			(arc
				(start 386.14223 -413.480504)
				(mid 385.88315 -413.480504)
				(end 386.14223 -413.480504)
			)
		)
		(stroke
			(width 0)
			(type solid)
		)
		(fill yes)
		(layer "In2.Cu")
		(net "GND")
	)
	(gr_poly
		(pts
			(arc
				(start 386.14223 -412.212536)
				(mid 385.88315 -412.212536)
				(end 386.14223 -412.212536)
			)
		)
		(stroke
			(width 0)
			(type solid)
		)
		(fill yes)
		(layer "In2.Cu")
		(net "GND")
	)
	(gr_poly
		(pts
			(arc
				(start 386.230622 -418.412168)
				(mid 385.971542 -418.412168)
				(end 386.230622 -418.412168)
			)
		)
		(stroke
			(width 0)
			(type solid)
		)
		(fill yes)
		(layer "In2.Cu")
		(net "GND")
	)
	(gr_poly
		(pts
			(arc
				(start 386.230622 -415.38652)
				(mid 385.971542 -415.38652)
				(end 386.230622 -415.38652)
			)
		)
		(stroke
			(width 0)
			(type solid)
		)
		(fill yes)
		(layer "In2.Cu")
		(net "GND")
	)
	(gr_poly
		(pts
			(arc
				(start 387.312662 -418.412168)
				(mid 387.053582 -418.412168)
				(end 387.312662 -418.412168)
			)
		)
		(stroke
			(width 0)
			(type solid)
		)
		(fill yes)
		(layer "In2.Cu")
		(net "GND")
	)
	(gr_poly
		(pts
			(arc
				(start 387.312662 -415.38652)
				(mid 387.053582 -415.38652)
				(end 387.312662 -415.38652)
			)
		)
		(stroke
			(width 0)
			(type solid)
		)
		(fill yes)
		(layer "In2.Cu")
		(net "GND")
	)
	(gr_poly
		(pts
			(arc
				(start 387.401054 -421.586152)
				(mid 387.141974 -421.586152)
				(end 387.401054 -421.586152)
			)
		)
		(stroke
			(width 0)
			(type solid)
		)
		(fill yes)
		(layer "In2.Cu")
		(net "GND")
	)
	(gr_poly
		(pts
			(arc
				(start 387.401054 -420.318184)
				(mid 387.141974 -420.318184)
				(end 387.401054 -420.318184)
			)
		)
		(stroke
			(width 0)
			(type solid)
		)
		(fill yes)
		(layer "In2.Cu")
		(net "GND")
	)
	(gr_poly
		(pts
			(arc
				(start 387.401054 -413.480504)
				(mid 387.141974 -413.480504)
				(end 387.401054 -413.480504)
			)
		)
		(stroke
			(width 0)
			(type solid)
		)
		(fill yes)
		(layer "In2.Cu")
		(net "GND")
	)
	(gr_poly
		(pts
			(arc
				(start 387.401054 -412.212536)
				(mid 387.141974 -412.212536)
				(end 387.401054 -412.212536)
			)
		)
		(stroke
			(width 0)
			(type solid)
		)
		(fill yes)
		(layer "In2.Cu")
		(net "GND")
	)
	(gr_poly
		(pts
			(arc
				(start 387.67385 -419.046152)
				(mid 387.41477 -419.046152)
				(end 387.67385 -419.046152)
			)
		)
		(stroke
			(width 0)
			(type solid)
		)
		(fill yes)
		(layer "In2.Cu")
		(net "GND")
	)
	(gr_poly
		(pts
			(arc
				(start 387.67385 -417.778184)
				(mid 387.41477 -417.778184)
				(end 387.67385 -417.778184)
			)
		)
		(stroke
			(width 0)
			(type solid)
		)
		(fill yes)
		(layer "In2.Cu")
		(net "GND")
	)
	(gr_poly
		(pts
			(arc
				(start 387.67385 -416.020504)
				(mid 387.41477 -416.020504)
				(end 387.67385 -416.020504)
			)
		)
		(stroke
			(width 0)
			(type solid)
		)
		(fill yes)
		(layer "In2.Cu")
		(net "GND")
	)
	(gr_poly
		(pts
			(arc
				(start 387.67385 -414.752536)
				(mid 387.41477 -414.752536)
				(end 387.67385 -414.752536)
			)
		)
		(stroke
			(width 0)
			(type solid)
		)
		(fill yes)
		(layer "In2.Cu")
		(net "GND")
	)
	(gr_poly
		(pts
			(arc
				(start 387.762242 -420.952168)
				(mid 387.503162 -420.952168)
				(end 387.762242 -420.952168)
			)
		)
		(stroke
			(width 0)
			(type solid)
		)
		(fill yes)
		(layer "In2.Cu")
		(net "GND")
	)
	(gr_poly
		(pts
			(arc
				(start 387.762242 -412.84652)
				(mid 387.503162 -412.84652)
				(end 387.762242 -412.84652)
			)
		)
		(stroke
			(width 0)
			(type solid)
		)
		(fill yes)
		(layer "In2.Cu")
		(net "GND")
	)
	(gr_poly
		(pts
			(arc
				(start 388.844282 -420.952168)
				(mid 388.585202 -420.952168)
				(end 388.844282 -420.952168)
			)
		)
		(stroke
			(width 0)
			(type solid)
		)
		(fill yes)
		(layer "In2.Cu")
		(net "GND")
	)
	(gr_poly
		(pts
			(arc
				(start 388.844282 -412.84652)
				(mid 388.585202 -412.84652)
				(end 388.844282 -412.84652)
			)
		)
		(stroke
			(width 0)
			(type solid)
		)
		(fill yes)
		(layer "In2.Cu")
		(net "GND")
	)
	(gr_poly
		(pts
			(arc
				(start 388.932674 -419.046152)
				(mid 388.673594 -419.046152)
				(end 388.932674 -419.046152)
			)
		)
		(stroke
			(width 0)
			(type solid)
		)
		(fill yes)
		(layer "In2.Cu")
		(net "GND")
	)
	(gr_poly
		(pts
			(arc
				(start 388.932674 -417.778184)
				(mid 388.673594 -417.778184)
				(end 388.932674 -417.778184)
			)
		)
		(stroke
			(width 0)
			(type solid)
		)
		(fill yes)
		(layer "In2.Cu")
		(net "GND")
	)
	(gr_poly
		(pts
			(arc
				(start 388.932674 -416.020504)
				(mid 388.673594 -416.020504)
				(end 388.932674 -416.020504)
			)
		)
		(stroke
			(width 0)
			(type solid)
		)
		(fill yes)
		(layer "In2.Cu")
		(net "GND")
	)
	(gr_poly
		(pts
			(arc
				(start 388.932674 -414.752536)
				(mid 388.673594 -414.752536)
				(end 388.932674 -414.752536)
			)
		)
		(stroke
			(width 0)
			(type solid)
		)
		(fill yes)
		(layer "In2.Cu")
		(net "GND")
	)
	(gr_poly
		(pts
			(arc
				(start 389.20547 -421.586152)
				(mid 388.94639 -421.586152)
				(end 389.20547 -421.586152)
			)
		)
		(stroke
			(width 0)
			(type solid)
		)
		(fill yes)
		(layer "In2.Cu")
		(net "GND")
	)
	(gr_poly
		(pts
			(arc
				(start 389.20547 -420.318184)
				(mid 388.94639 -420.318184)
				(end 389.20547 -420.318184)
			)
		)
		(stroke
			(width 0)
			(type solid)
		)
		(fill yes)
		(layer "In2.Cu")
		(net "GND")
	)
	(gr_poly
		(pts
			(arc
				(start 389.20547 -413.480504)
				(mid 388.94639 -413.480504)
				(end 389.20547 -413.480504)
			)
		)
		(stroke
			(width 0)
			(type solid)
		)
		(fill yes)
		(layer "In2.Cu")
		(net "GND")
	)
	(gr_poly
		(pts
			(arc
				(start 389.20547 -412.212536)
				(mid 388.94639 -412.212536)
				(end 389.20547 -412.212536)
			)
		)
		(stroke
			(width 0)
			(type solid)
		)
		(fill yes)
		(layer "In2.Cu")
		(net "GND")
	)
	(gr_poly
		(pts
			(arc
				(start 389.293862 -418.412168)
				(mid 389.034782 -418.412168)
				(end 389.293862 -418.412168)
			)
		)
		(stroke
			(width 0)
			(type solid)
		)
		(fill yes)
		(layer "In2.Cu")
		(net "GND")
	)
	(gr_poly
		(pts
			(arc
				(start 389.293862 -415.38652)
				(mid 389.034782 -415.38652)
				(end 389.293862 -415.38652)
			)
		)
		(stroke
			(width 0)
			(type solid)
		)
		(fill yes)
		(layer "In2.Cu")
		(net "GND")
	)
	(gr_poly
		(pts
			(arc
				(start 390.375902 -418.412168)
				(mid 390.116822 -418.412168)
				(end 390.375902 -418.412168)
			)
		)
		(stroke
			(width 0)
			(type solid)
		)
		(fill yes)
		(layer "In2.Cu")
		(net "GND")
	)
	(gr_poly
		(pts
			(arc
				(start 390.375902 -415.38652)
				(mid 390.116822 -415.38652)
				(end 390.375902 -415.38652)
			)
		)
		(stroke
			(width 0)
			(type solid)
		)
		(fill yes)
		(layer "In2.Cu")
		(net "GND")
	)
	(gr_poly
		(pts
			(arc
				(start 390.464294 -421.586152)
				(mid 390.205214 -421.586152)
				(end 390.464294 -421.586152)
			)
		)
		(stroke
			(width 0)
			(type solid)
		)
		(fill yes)
		(layer "In2.Cu")
		(net "GND")
	)
	(gr_poly
		(pts
			(arc
				(start 390.464294 -420.318184)
				(mid 390.205214 -420.318184)
				(end 390.464294 -420.318184)
			)
		)
		(stroke
			(width 0)
			(type solid)
		)
		(fill yes)
		(layer "In2.Cu")
		(net "GND")
	)
	(gr_poly
		(pts
			(arc
				(start 390.464294 -413.480504)
				(mid 390.205214 -413.480504)
				(end 390.464294 -413.480504)
			)
		)
		(stroke
			(width 0)
			(type solid)
		)
		(fill yes)
		(layer "In2.Cu")
		(net "GND")
	)
	(gr_poly
		(pts
			(arc
				(start 390.464294 -412.212536)
				(mid 390.205214 -412.212536)
				(end 390.464294 -412.212536)
			)
		)
		(stroke
			(width 0)
			(type solid)
		)
		(fill yes)
		(layer "In2.Cu")
		(net "GND")
	)
	(gr_poly
		(pts
			(arc
				(start 390.73709 -419.046152)
				(mid 390.47801 -419.046152)
				(end 390.73709 -419.046152)
			)
		)
		(stroke
			(width 0)
			(type solid)
		)
		(fill yes)
		(layer "In2.Cu")
		(net "GND")
	)
	(gr_poly
		(pts
			(arc
				(start 390.73709 -417.778184)
				(mid 390.47801 -417.778184)
				(end 390.73709 -417.778184)
			)
		)
		(stroke
			(width 0)
			(type solid)
		)
		(fill yes)
		(layer "In2.Cu")
		(net "GND")
	)
	(gr_poly
		(pts
			(arc
				(start 390.73709 -416.020504)
				(mid 390.47801 -416.020504)
				(end 390.73709 -416.020504)
			)
		)
		(stroke
			(width 0)
			(type solid)
		)
		(fill yes)
		(layer "In2.Cu")
		(net "GND")
	)
	(gr_poly
		(pts
			(arc
				(start 390.73709 -414.752536)
				(mid 390.47801 -414.752536)
				(end 390.73709 -414.752536)
			)
		)
		(stroke
			(width 0)
			(type solid)
		)
		(fill yes)
		(layer "In2.Cu")
		(net "GND")
	)
	(gr_poly
		(pts
			(arc
				(start 390.825482 -420.952168)
				(mid 390.566402 -420.952168)
				(end 390.825482 -420.952168)
			)
		)
		(stroke
			(width 0)
			(type solid)
		)
		(fill yes)
		(layer "In2.Cu")
		(net "GND")
	)
	(gr_poly
		(pts
			(arc
				(start 390.825482 -412.84652)
				(mid 390.566402 -412.84652)
				(end 390.825482 -412.84652)
			)
		)
		(stroke
			(width 0)
			(type solid)
		)
		(fill yes)
		(layer "In2.Cu")
		(net "GND")
	)
	(gr_poly
		(pts
			(arc
				(start 391.907522 -420.952168)
				(mid 391.648442 -420.952168)
				(end 391.907522 -420.952168)
			)
		)
		(stroke
			(width 0)
			(type solid)
		)
		(fill yes)
		(layer "In2.Cu")
		(net "GND")
	)
	(gr_poly
		(pts
			(arc
				(start 391.907522 -412.84652)
				(mid 391.648442 -412.84652)
				(end 391.907522 -412.84652)
			)
		)
		(stroke
			(width 0)
			(type solid)
		)
		(fill yes)
		(layer "In2.Cu")
		(net "GND")
	)
	(gr_poly
		(pts
			(arc
				(start 391.995914 -419.046152)
				(mid 391.736834 -419.046152)
				(end 391.995914 -419.046152)
			)
		)
		(stroke
			(width 0)
			(type solid)
		)
		(fill yes)
		(layer "In2.Cu")
		(net "GND")
	)
	(gr_poly
		(pts
			(arc
				(start 391.995914 -417.778184)
				(mid 391.736834 -417.778184)
				(end 391.995914 -417.778184)
			)
		)
		(stroke
			(width 0)
			(type solid)
		)
		(fill yes)
		(layer "In2.Cu")
		(net "GND")
	)
	(gr_poly
		(pts
			(arc
				(start 391.995914 -416.020504)
				(mid 391.736834 -416.020504)
				(end 391.995914 -416.020504)
			)
		)
		(stroke
			(width 0)
			(type solid)
		)
		(fill yes)
		(layer "In2.Cu")
		(net "GND")
	)
	(gr_poly
		(pts
			(arc
				(start 391.995914 -414.752536)
				(mid 391.736834 -414.752536)
				(end 391.995914 -414.752536)
			)
		)
		(stroke
			(width 0)
			(type solid)
		)
		(fill yes)
		(layer "In2.Cu")
		(net "GND")
	)
	(gr_poly
		(pts
			(arc
				(start 392.26871 -421.586152)
				(mid 392.00963 -421.586152)
				(end 392.26871 -421.586152)
			)
		)
		(stroke
			(width 0)
			(type solid)
		)
		(fill yes)
		(layer "In2.Cu")
		(net "GND")
	)
	(gr_poly
		(pts
			(arc
				(start 392.26871 -420.318184)
				(mid 392.00963 -420.318184)
				(end 392.26871 -420.318184)
			)
		)
		(stroke
			(width 0)
			(type solid)
		)
		(fill yes)
		(layer "In2.Cu")
		(net "GND")
	)
	(gr_poly
		(pts
			(arc
				(start 392.26871 -413.480504)
				(mid 392.00963 -413.480504)
				(end 392.26871 -413.480504)
			)
		)
		(stroke
			(width 0)
			(type solid)
		)
		(fill yes)
		(layer "In2.Cu")
		(net "GND")
	)
	(gr_poly
		(pts
			(arc
				(start 392.26871 -412.212536)
				(mid 392.00963 -412.212536)
				(end 392.26871 -412.212536)
			)
		)
		(stroke
			(width 0)
			(type solid)
		)
		(fill yes)
		(layer "In2.Cu")
		(net "GND")
	)
	(gr_poly
		(pts
			(arc
				(start 392.357102 -418.412168)
				(mid 392.098022 -418.412168)
				(end 392.357102 -418.412168)
			)
		)
		(stroke
			(width 0)
			(type solid)
		)
		(fill yes)
		(layer "In2.Cu")
		(net "GND")
	)
	(gr_poly
		(pts
			(arc
				(start 392.357102 -415.38652)
				(mid 392.098022 -415.38652)
				(end 392.357102 -415.38652)
			)
		)
		(stroke
			(width 0)
			(type solid)
		)
		(fill yes)
		(layer "In2.Cu")
		(net "GND")
	)
	(gr_poly
		(pts
			(arc
				(start 393.439142 -418.412168)
				(mid 393.180062 -418.412168)
				(end 393.439142 -418.412168)
			)
		)
		(stroke
			(width 0)
			(type solid)
		)
		(fill yes)
		(layer "In2.Cu")
		(net "GND")
	)
	(gr_poly
		(pts
			(arc
				(start 393.439142 -415.38652)
				(mid 393.180062 -415.38652)
				(end 393.439142 -415.38652)
			)
		)
		(stroke
			(width 0)
			(type solid)
		)
		(fill yes)
		(layer "In2.Cu")
		(net "GND")
	)
	(gr_poly
		(pts
			(arc
				(start 393.527534 -421.586152)
				(mid 393.268454 -421.586152)
				(end 393.527534 -421.586152)
			)
		)
		(stroke
			(width 0)
			(type solid)
		)
		(fill yes)
		(layer "In2.Cu")
		(net "GND")
	)
	(gr_poly
		(pts
			(arc
				(start 393.527534 -420.318184)
				(mid 393.268454 -420.318184)
				(end 393.527534 -420.318184)
			)
		)
		(stroke
			(width 0)
			(type solid)
		)
		(fill yes)
		(layer "In2.Cu")
		(net "GND")
	)
	(gr_poly
		(pts
			(arc
				(start 393.527534 -413.480504)
				(mid 393.268454 -413.480504)
				(end 393.527534 -413.480504)
			)
		)
		(stroke
			(width 0)
			(type solid)
		)
		(fill yes)
		(layer "In2.Cu")
		(net "GND")
	)
	(gr_poly
		(pts
			(arc
				(start 393.527534 -412.212536)
				(mid 393.268454 -412.212536)
				(end 393.527534 -412.212536)
			)
		)
		(stroke
			(width 0)
			(type solid)
		)
		(fill yes)
		(layer "In2.Cu")
		(net "GND")
	)
	(gr_poly
		(pts
			(arc
				(start 393.80033 -419.046152)
				(mid 393.54125 -419.046152)
				(end 393.80033 -419.046152)
			)
		)
		(stroke
			(width 0)
			(type solid)
		)
		(fill yes)
		(layer "In2.Cu")
		(net "GND")
	)
	(gr_poly
		(pts
			(arc
				(start 393.80033 -417.778184)
				(mid 393.54125 -417.778184)
				(end 393.80033 -417.778184)
			)
		)
		(stroke
			(width 0)
			(type solid)
		)
		(fill yes)
		(layer "In2.Cu")
		(net "GND")
	)
	(gr_poly
		(pts
			(arc
				(start 393.80033 -416.020504)
				(mid 393.54125 -416.020504)
				(end 393.80033 -416.020504)
			)
		)
		(stroke
			(width 0)
			(type solid)
		)
		(fill yes)
		(layer "In2.Cu")
		(net "GND")
	)
	(gr_poly
		(pts
			(arc
				(start 393.80033 -414.752536)
				(mid 393.54125 -414.752536)
				(end 393.80033 -414.752536)
			)
		)
		(stroke
			(width 0)
			(type solid)
		)
		(fill yes)
		(layer "In2.Cu")
		(net "GND")
	)
	(gr_poly
		(pts
			(arc
				(start 393.888722 -420.952168)
				(mid 393.629642 -420.952168)
				(end 393.888722 -420.952168)
			)
		)
		(stroke
			(width 0)
			(type solid)
		)
		(fill yes)
		(layer "In2.Cu")
		(net "GND")
	)
	(gr_poly
		(pts
			(arc
				(start 393.888722 -412.84652)
				(mid 393.629642 -412.84652)
				(end 393.888722 -412.84652)
			)
		)
		(stroke
			(width 0)
			(type solid)
		)
		(fill yes)
		(layer "In2.Cu")
		(net "GND")
	)
	(gr_poly
		(pts
			(arc
				(start 394.970762 -420.952168)
				(mid 394.711682 -420.952168)
				(end 394.970762 -420.952168)
			)
		)
		(stroke
			(width 0)
			(type solid)
		)
		(fill yes)
		(layer "In2.Cu")
		(net "GND")
	)
	(gr_poly
		(pts
			(arc
				(start 394.970762 -412.84652)
				(mid 394.711682 -412.84652)
				(end 394.970762 -412.84652)
			)
		)
		(stroke
			(width 0)
			(type solid)
		)
		(fill yes)
		(layer "In2.Cu")
		(net "GND")
	)
	(gr_poly
		(pts
			(arc
				(start 395.059154 -419.046152)
				(mid 394.800074 -419.046152)
				(end 395.059154 -419.046152)
			)
		)
		(stroke
			(width 0)
			(type solid)
		)
		(fill yes)
		(layer "In2.Cu")
		(net "GND")
	)
	(gr_poly
		(pts
			(arc
				(start 395.059154 -417.778184)
				(mid 394.800074 -417.778184)
				(end 395.059154 -417.778184)
			)
		)
		(stroke
			(width 0)
			(type solid)
		)
		(fill yes)
		(layer "In2.Cu")
		(net "GND")
	)
	(gr_poly
		(pts
			(arc
				(start 395.059154 -416.020504)
				(mid 394.800074 -416.020504)
				(end 395.059154 -416.020504)
			)
		)
		(stroke
			(width 0)
			(type solid)
		)
		(fill yes)
		(layer "In2.Cu")
		(net "GND")
	)
	(gr_poly
		(pts
			(arc
				(start 395.059154 -414.752536)
				(mid 394.800074 -414.752536)
				(end 395.059154 -414.752536)
			)
		)
		(stroke
			(width 0)
			(type solid)
		)
		(fill yes)
		(layer "In2.Cu")
		(net "GND")
	)
	(gr_poly
		(pts
			(arc
				(start 395.33195 -421.586152)
				(mid 395.07287 -421.586152)
				(end 395.33195 -421.586152)
			)
		)
		(stroke
			(width 0)
			(type solid)
		)
		(fill yes)
		(layer "In2.Cu")
		(net "GND")
	)
	(gr_poly
		(pts
			(arc
				(start 395.33195 -420.318184)
				(mid 395.07287 -420.318184)
				(end 395.33195 -420.318184)
			)
		)
		(stroke
			(width 0)
			(type solid)
		)
		(fill yes)
		(layer "In2.Cu")
		(net "GND")
	)
	(gr_poly
		(pts
			(arc
				(start 395.33195 -413.480504)
				(mid 395.07287 -413.480504)
				(end 395.33195 -413.480504)
			)
		)
		(stroke
			(width 0)
			(type solid)
		)
		(fill yes)
		(layer "In2.Cu")
		(net "GND")
	)
	(gr_poly
		(pts
			(arc
				(start 395.33195 -412.212536)
				(mid 395.07287 -412.212536)
				(end 395.33195 -412.212536)
			)
		)
		(stroke
			(width 0)
			(type solid)
		)
		(fill yes)
		(layer "In2.Cu")
		(net "GND")
	)
	(gr_poly
		(pts
			(arc
				(start 395.420342 -418.412168)
				(mid 395.161262 -418.412168)
				(end 395.420342 -418.412168)
			)
		)
		(stroke
			(width 0)
			(type solid)
		)
		(fill yes)
		(layer "In2.Cu")
		(net "GND")
	)
	(gr_poly
		(pts
			(arc
				(start 395.420342 -415.38652)
				(mid 395.161262 -415.38652)
				(end 395.420342 -415.38652)
			)
		)
		(stroke
			(width 0)
			(type solid)
		)
		(fill yes)
		(layer "In2.Cu")
		(net "GND")
	)
	(gr_poly
		(pts
			(arc
				(start 396.502382 -418.412168)
				(mid 396.243302 -418.412168)
				(end 396.502382 -418.412168)
			)
		)
		(stroke
			(width 0)
			(type solid)
		)
		(fill yes)
		(layer "In2.Cu")
		(net "GND")
	)
	(gr_poly
		(pts
			(arc
				(start 396.502382 -415.38652)
				(mid 396.243302 -415.38652)
				(end 396.502382 -415.38652)
			)
		)
		(stroke
			(width 0)
			(type solid)
		)
		(fill yes)
		(layer "In2.Cu")
		(net "GND")
	)
	(gr_poly
		(pts
			(arc
				(start 396.590774 -421.586152)
				(mid 396.331694 -421.586152)
				(end 396.590774 -421.586152)
			)
		)
		(stroke
			(width 0)
			(type solid)
		)
		(fill yes)
		(layer "In2.Cu")
		(net "GND")
	)
	(gr_poly
		(pts
			(arc
				(start 396.590774 -420.318184)
				(mid 396.331694 -420.318184)
				(end 396.590774 -420.318184)
			)
		)
		(stroke
			(width 0)
			(type solid)
		)
		(fill yes)
		(layer "In2.Cu")
		(net "GND")
	)
	(gr_poly
		(pts
			(arc
				(start 396.590774 -413.480504)
				(mid 396.331694 -413.480504)
				(end 396.590774 -413.480504)
			)
		)
		(stroke
			(width 0)
			(type solid)
		)
		(fill yes)
		(layer "In2.Cu")
		(net "GND")
	)
	(gr_poly
		(pts
			(arc
				(start 396.590774 -412.212536)
				(mid 396.331694 -412.212536)
				(end 396.590774 -412.212536)
			)
		)
		(stroke
			(width 0)
			(type solid)
		)
		(fill yes)
		(layer "In2.Cu")
		(net "GND")
	)
	(gr_poly
		(pts
			(arc
				(start 396.86357 -419.046152)
				(mid 396.60449 -419.046152)
				(end 396.86357 -419.046152)
			)
		)
		(stroke
			(width 0)
			(type solid)
		)
		(fill yes)
		(layer "In2.Cu")
		(net "GND")
	)
	(gr_poly
		(pts
			(arc
				(start 396.86357 -417.778184)
				(mid 396.60449 -417.778184)
				(end 396.86357 -417.778184)
			)
		)
		(stroke
			(width 0)
			(type solid)
		)
		(fill yes)
		(layer "In2.Cu")
		(net "GND")
	)
	(gr_poly
		(pts
			(arc
				(start 396.86357 -416.020504)
				(mid 396.60449 -416.020504)
				(end 396.86357 -416.020504)
			)
		)
		(stroke
			(width 0)
			(type solid)
		)
		(fill yes)
		(layer "In2.Cu")
		(net "GND")
	)
	(gr_poly
		(pts
			(arc
				(start 396.86357 -414.752536)
				(mid 396.60449 -414.752536)
				(end 396.86357 -414.752536)
			)
		)
		(stroke
			(width 0)
			(type solid)
		)
		(fill yes)
		(layer "In2.Cu")
		(net "GND")
	)
	(gr_poly
		(pts
			(arc
				(start 396.951962 -420.952168)
				(mid 396.692882 -420.952168)
				(end 396.951962 -420.952168)
			)
		)
		(stroke
			(width 0)
			(type solid)
		)
		(fill yes)
		(layer "In2.Cu")
		(net "GND")
	)
	(gr_poly
		(pts
			(arc
				(start 396.951962 -412.84652)
				(mid 396.692882 -412.84652)
				(end 396.951962 -412.84652)
			)
		)
		(stroke
			(width 0)
			(type solid)
		)
		(fill yes)
		(layer "In2.Cu")
		(net "GND")
	)
	(gr_poly
		(pts
			(arc
				(start 398.034002 -420.952168)
				(mid 397.774922 -420.952168)
				(end 398.034002 -420.952168)
			)
		)
		(stroke
			(width 0)
			(type solid)
		)
		(fill yes)
		(layer "In2.Cu")
		(net "GND")
	)
	(gr_poly
		(pts
			(arc
				(start 398.034002 -412.84652)
				(mid 397.774922 -412.84652)
				(end 398.034002 -412.84652)
			)
		)
		(stroke
			(width 0)
			(type solid)
		)
		(fill yes)
		(layer "In2.Cu")
		(net "GND")
	)
	(gr_poly
		(pts
			(arc
				(start 398.122394 -419.046152)
				(mid 397.863314 -419.046152)
				(end 398.122394 -419.046152)
			)
		)
		(stroke
			(width 0)
			(type solid)
		)
		(fill yes)
		(layer "In2.Cu")
		(net "GND")
	)
	(gr_poly
		(pts
			(arc
				(start 398.122394 -417.778184)
				(mid 397.863314 -417.778184)
				(end 398.122394 -417.778184)
			)
		)
		(stroke
			(width 0)
			(type solid)
		)
		(fill yes)
		(layer "In2.Cu")
		(net "GND")
	)
	(gr_poly
		(pts
			(arc
				(start 398.122394 -416.020504)
				(mid 397.863314 -416.020504)
				(end 398.122394 -416.020504)
			)
		)
		(stroke
			(width 0)
			(type solid)
		)
		(fill yes)
		(layer "In2.Cu")
		(net "GND")
	)
	(gr_poly
		(pts
			(arc
				(start 398.122394 -414.752536)
				(mid 397.863314 -414.752536)
				(end 398.122394 -414.752536)
			)
		)
		(stroke
			(width 0)
			(type solid)
		)
		(fill yes)
		(layer "In2.Cu")
		(net "GND")
	)
	(gr_poly
		(pts
			(arc
				(start 398.39519 -421.586152)
				(mid 398.13611 -421.586152)
				(end 398.39519 -421.586152)
			)
		)
		(stroke
			(width 0)
			(type solid)
		)
		(fill yes)
		(layer "In2.Cu")
		(net "GND")
	)
	(gr_poly
		(pts
			(arc
				(start 398.39519 -420.318184)
				(mid 398.13611 -420.318184)
				(end 398.39519 -420.318184)
			)
		)
		(stroke
			(width 0)
			(type solid)
		)
		(fill yes)
		(layer "In2.Cu")
		(net "GND")
	)
	(gr_poly
		(pts
			(arc
				(start 398.39519 -413.480504)
				(mid 398.13611 -413.480504)
				(end 398.39519 -413.480504)
			)
		)
		(stroke
			(width 0)
			(type solid)
		)
		(fill yes)
		(layer "In2.Cu")
		(net "GND")
	)
	(gr_poly
		(pts
			(arc
				(start 398.39519 -412.212536)
				(mid 398.13611 -412.212536)
				(end 398.39519 -412.212536)
			)
		)
		(stroke
			(width 0)
			(type solid)
		)
		(fill yes)
		(layer "In2.Cu")
		(net "GND")
	)
	(gr_poly
		(pts
			(arc
				(start 398.483582 -418.412168)
				(mid 398.224502 -418.412168)
				(end 398.483582 -418.412168)
			)
		)
		(stroke
			(width 0)
			(type solid)
		)
		(fill yes)
		(layer "In2.Cu")
		(net "GND")
	)
	(gr_poly
		(pts
			(arc
				(start 398.483582 -415.38652)
				(mid 398.224502 -415.38652)
				(end 398.483582 -415.38652)
			)
		)
		(stroke
			(width 0)
			(type solid)
		)
		(fill yes)
		(layer "In2.Cu")
		(net "GND")
	)
	(gr_poly
		(pts
			(arc
				(start 399.565622 -418.412168)
				(mid 399.306542 -418.412168)
				(end 399.565622 -418.412168)
			)
		)
		(stroke
			(width 0)
			(type solid)
		)
		(fill yes)
		(layer "In2.Cu")
		(net "GND")
	)
	(gr_poly
		(pts
			(arc
				(start 399.565622 -415.38652)
				(mid 399.306542 -415.38652)
				(end 399.565622 -415.38652)
			)
		)
		(stroke
			(width 0)
			(type solid)
		)
		(fill yes)
		(layer "In2.Cu")
		(net "GND")
	)
	(gr_poly
		(pts
			(arc
				(start 399.654014 -421.586152)
				(mid 399.394934 -421.586152)
				(end 399.654014 -421.586152)
			)
		)
		(stroke
			(width 0)
			(type solid)
		)
		(fill yes)
		(layer "In2.Cu")
		(net "GND")
	)
	(gr_poly
		(pts
			(arc
				(start 399.654014 -420.318184)
				(mid 399.394934 -420.318184)
				(end 399.654014 -420.318184)
			)
		)
		(stroke
			(width 0)
			(type solid)
		)
		(fill yes)
		(layer "In2.Cu")
		(net "GND")
	)
	(gr_poly
		(pts
			(arc
				(start 399.654014 -413.480504)
				(mid 399.394934 -413.480504)
				(end 399.654014 -413.480504)
			)
		)
		(stroke
			(width 0)
			(type solid)
		)
		(fill yes)
		(layer "In2.Cu")
		(net "GND")
	)
	(gr_poly
		(pts
			(arc
				(start 399.654014 -412.212536)
				(mid 399.394934 -412.212536)
				(end 399.654014 -412.212536)
			)
		)
		(stroke
			(width 0)
			(type solid)
		)
		(fill yes)
		(layer "In2.Cu")
		(net "GND")
	)
	(gr_poly
		(pts
			(arc
				(start 399.92681 -419.046152)
				(mid 399.66773 -419.046152)
				(end 399.92681 -419.046152)
			)
		)
		(stroke
			(width 0)
			(type solid)
		)
		(fill yes)
		(layer "In2.Cu")
		(net "GND")
	)
	(gr_poly
		(pts
			(arc
				(start 399.92681 -417.778184)
				(mid 399.66773 -417.778184)
				(end 399.92681 -417.778184)
			)
		)
		(stroke
			(width 0)
			(type solid)
		)
		(fill yes)
		(layer "In2.Cu")
		(net "GND")
	)
	(gr_poly
		(pts
			(arc
				(start 399.92681 -416.020504)
				(mid 399.66773 -416.020504)
				(end 399.92681 -416.020504)
			)
		)
		(stroke
			(width 0)
			(type solid)
		)
		(fill yes)
		(layer "In2.Cu")
		(net "GND")
	)
	(gr_poly
		(pts
			(arc
				(start 399.92681 -414.752536)
				(mid 399.66773 -414.752536)
				(end 399.92681 -414.752536)
			)
		)
		(stroke
			(width 0)
			(type solid)
		)
		(fill yes)
		(layer "In2.Cu")
		(net "GND")
	)
	(gr_poly
		(pts
			(arc
				(start 400.015202 -420.952168)
				(mid 399.756122 -420.952168)
				(end 400.015202 -420.952168)
			)
		)
		(stroke
			(width 0)
			(type solid)
		)
		(fill yes)
		(layer "In2.Cu")
		(net "GND")
	)
	(gr_poly
		(pts
			(arc
				(start 400.015202 -412.84652)
				(mid 399.756122 -412.84652)
				(end 400.015202 -412.84652)
			)
		)
		(stroke
			(width 0)
			(type solid)
		)
		(fill yes)
		(layer "In2.Cu")
		(net "GND")
	)
	(gr_poly
		(pts
			(arc
				(start 401.097242 -420.952168)
				(mid 400.838162 -420.952168)
				(end 401.097242 -420.952168)
			)
		)
		(stroke
			(width 0)
			(type solid)
		)
		(fill yes)
		(layer "In2.Cu")
		(net "GND")
	)
	(gr_poly
		(pts
			(arc
				(start 401.097242 -412.84652)
				(mid 400.838162 -412.84652)
				(end 401.097242 -412.84652)
			)
		)
		(stroke
			(width 0)
			(type solid)
		)
		(fill yes)
		(layer "In2.Cu")
		(net "GND")
	)
	(gr_poly
		(pts
			(arc
				(start 401.185634 -419.046152)
				(mid 400.926554 -419.046152)
				(end 401.185634 -419.046152)
			)
		)
		(stroke
			(width 0)
			(type solid)
		)
		(fill yes)
		(layer "In2.Cu")
		(net "GND")
	)
	(gr_poly
		(pts
			(arc
				(start 401.185634 -417.778184)
				(mid 400.926554 -417.778184)
				(end 401.185634 -417.778184)
			)
		)
		(stroke
			(width 0)
			(type solid)
		)
		(fill yes)
		(layer "In2.Cu")
		(net "GND")
	)
	(gr_poly
		(pts
			(arc
				(start 401.185634 -416.020504)
				(mid 400.926554 -416.020504)
				(end 401.185634 -416.020504)
			)
		)
		(stroke
			(width 0)
			(type solid)
		)
		(fill yes)
		(layer "In2.Cu")
		(net "GND")
	)
	(gr_poly
		(pts
			(arc
				(start 401.185634 -414.752536)
				(mid 400.926554 -414.752536)
				(end 401.185634 -414.752536)
			)
		)
		(stroke
			(width 0)
			(type solid)
		)
		(fill yes)
		(layer "In2.Cu")
		(net "GND")
	)
	(gr_poly
		(pts
			(arc
				(start 401.45843 -421.586152)
				(mid 401.19935 -421.586152)
				(end 401.45843 -421.586152)
			)
		)
		(stroke
			(width 0)
			(type solid)
		)
		(fill yes)
		(layer "In2.Cu")
		(net "GND")
	)
	(gr_poly
		(pts
			(arc
				(start 401.45843 -420.318184)
				(mid 401.19935 -420.318184)
				(end 401.45843 -420.318184)
			)
		)
		(stroke
			(width 0)
			(type solid)
		)
		(fill yes)
		(layer "In2.Cu")
		(net "GND")
	)
	(gr_poly
		(pts
			(arc
				(start 401.45843 -413.480504)
				(mid 401.19935 -413.480504)
				(end 401.45843 -413.480504)
			)
		)
		(stroke
			(width 0)
			(type solid)
		)
		(fill yes)
		(layer "In2.Cu")
		(net "GND")
	)
	(gr_poly
		(pts
			(arc
				(start 401.45843 -412.212536)
				(mid 401.19935 -412.212536)
				(end 401.45843 -412.212536)
			)
		)
		(stroke
			(width 0)
			(type solid)
		)
		(fill yes)
		(layer "In2.Cu")
		(net "GND")
	)
	(gr_poly
		(pts
			(arc
				(start 401.546822 -418.412168)
				(mid 401.287742 -418.412168)
				(end 401.546822 -418.412168)
			)
		)
		(stroke
			(width 0)
			(type solid)
		)
		(fill yes)
		(layer "In2.Cu")
		(net "GND")
	)
	(gr_poly
		(pts
			(arc
				(start 401.546822 -415.38652)
				(mid 401.287742 -415.38652)
				(end 401.546822 -415.38652)
			)
		)
		(stroke
			(width 0)
			(type solid)
		)
		(fill yes)
		(layer "In2.Cu")
		(net "GND")
	)
	(gr_poly
		(pts
			(arc
				(start 402.628862 -418.412168)
				(mid 402.369782 -418.412168)
				(end 402.628862 -418.412168)
			)
		)
		(stroke
			(width 0)
			(type solid)
		)
		(fill yes)
		(layer "In2.Cu")
		(net "GND")
	)
	(gr_poly
		(pts
			(arc
				(start 402.628862 -415.38652)
				(mid 402.369782 -415.38652)
				(end 402.628862 -415.38652)
			)
		)
		(stroke
			(width 0)
			(type solid)
		)
		(fill yes)
		(layer "In2.Cu")
		(net "GND")
	)
	(gr_poly
		(pts
			(arc
				(start 402.717254 -421.586152)
				(mid 402.458174 -421.586152)
				(end 402.717254 -421.586152)
			)
		)
		(stroke
			(width 0)
			(type solid)
		)
		(fill yes)
		(layer "In2.Cu")
		(net "GND")
	)
	(gr_poly
		(pts
			(arc
				(start 402.717254 -420.318184)
				(mid 402.458174 -420.318184)
				(end 402.717254 -420.318184)
			)
		)
		(stroke
			(width 0)
			(type solid)
		)
		(fill yes)
		(layer "In2.Cu")
		(net "GND")
	)
	(gr_poly
		(pts
			(arc
				(start 402.717254 -413.480504)
				(mid 402.458174 -413.480504)
				(end 402.717254 -413.480504)
			)
		)
		(stroke
			(width 0)
			(type solid)
		)
		(fill yes)
		(layer "In2.Cu")
		(net "GND")
	)
	(gr_poly
		(pts
			(arc
				(start 402.717254 -412.212536)
				(mid 402.458174 -412.212536)
				(end 402.717254 -412.212536)
			)
		)
		(stroke
			(width 0)
			(type solid)
		)
		(fill yes)
		(layer "In2.Cu")
		(net "GND")
	)
	(gr_poly
		(pts
			(arc
				(start 402.99005 -419.046152)
				(mid 402.73097 -419.046152)
				(end 402.99005 -419.046152)
			)
		)
		(stroke
			(width 0)
			(type solid)
		)
		(fill yes)
		(layer "In2.Cu")
		(net "GND")
	)
	(gr_poly
		(pts
			(arc
				(start 402.99005 -417.778184)
				(mid 402.73097 -417.778184)
				(end 402.99005 -417.778184)
			)
		)
		(stroke
			(width 0)
			(type solid)
		)
		(fill yes)
		(layer "In2.Cu")
		(net "GND")
	)
	(gr_poly
		(pts
			(arc
				(start 402.99005 -416.020504)
				(mid 402.73097 -416.020504)
				(end 402.99005 -416.020504)
			)
		)
		(stroke
			(width 0)
			(type solid)
		)
		(fill yes)
		(layer "In2.Cu")
		(net "GND")
	)
	(gr_poly
		(pts
			(arc
				(start 402.99005 -414.752536)
				(mid 402.73097 -414.752536)
				(end 402.99005 -414.752536)
			)
		)
		(stroke
			(width 0)
			(type solid)
		)
		(fill yes)
		(layer "In2.Cu")
		(net "GND")
	)
	(gr_poly
		(pts
			(arc
				(start 403.078442 -420.952168)
				(mid 402.819362 -420.952168)
				(end 403.078442 -420.952168)
			)
		)
		(stroke
			(width 0)
			(type solid)
		)
		(fill yes)
		(layer "In2.Cu")
		(net "GND")
	)
	(gr_poly
		(pts
			(arc
				(start 403.078442 -412.84652)
				(mid 402.819362 -412.84652)
				(end 403.078442 -412.84652)
			)
		)
		(stroke
			(width 0)
			(type solid)
		)
		(fill yes)
		(layer "In2.Cu")
		(net "GND")
	)
	(gr_poly
		(pts
			(arc
				(start 404.160482 -420.952168)
				(mid 403.901402 -420.952168)
				(end 404.160482 -420.952168)
			)
		)
		(stroke
			(width 0)
			(type solid)
		)
		(fill yes)
		(layer "In2.Cu")
		(net "GND")
	)
	(gr_poly
		(pts
			(arc
				(start 404.160482 -412.84652)
				(mid 403.901402 -412.84652)
				(end 404.160482 -412.84652)
			)
		)
		(stroke
			(width 0)
			(type solid)
		)
		(fill yes)
		(layer "In2.Cu")
		(net "GND")
	)
	(gr_poly
		(pts
			(arc
				(start 404.248874 -419.046152)
				(mid 403.989794 -419.046152)
				(end 404.248874 -419.046152)
			)
		)
		(stroke
			(width 0)
			(type solid)
		)
		(fill yes)
		(layer "In2.Cu")
		(net "GND")
	)
	(gr_poly
		(pts
			(arc
				(start 404.248874 -417.778184)
				(mid 403.989794 -417.778184)
				(end 404.248874 -417.778184)
			)
		)
		(stroke
			(width 0)
			(type solid)
		)
		(fill yes)
		(layer "In2.Cu")
		(net "GND")
	)
	(gr_poly
		(pts
			(arc
				(start 404.248874 -416.020504)
				(mid 403.989794 -416.020504)
				(end 404.248874 -416.020504)
			)
		)
		(stroke
			(width 0)
			(type solid)
		)
		(fill yes)
		(layer "In2.Cu")
		(net "GND")
	)
	(gr_poly
		(pts
			(arc
				(start 404.248874 -414.752536)
				(mid 403.989794 -414.752536)
				(end 404.248874 -414.752536)
			)
		)
		(stroke
			(width 0)
			(type solid)
		)
		(fill yes)
		(layer "In2.Cu")
		(net "GND")
	)
	(gr_poly
		(pts
			(arc
				(start 404.52167 -421.586152)
				(mid 404.26259 -421.586152)
				(end 404.52167 -421.586152)
			)
		)
		(stroke
			(width 0)
			(type solid)
		)
		(fill yes)
		(layer "In2.Cu")
		(net "GND")
	)
	(gr_poly
		(pts
			(arc
				(start 404.52167 -420.318184)
				(mid 404.26259 -420.318184)
				(end 404.52167 -420.318184)
			)
		)
		(stroke
			(width 0)
			(type solid)
		)
		(fill yes)
		(layer "In2.Cu")
		(net "GND")
	)
	(gr_poly
		(pts
			(arc
				(start 404.52167 -413.480504)
				(mid 404.26259 -413.480504)
				(end 404.52167 -413.480504)
			)
		)
		(stroke
			(width 0)
			(type solid)
		)
		(fill yes)
		(layer "In2.Cu")
		(net "GND")
	)
	(gr_poly
		(pts
			(arc
				(start 404.52167 -412.212536)
				(mid 404.26259 -412.212536)
				(end 404.52167 -412.212536)
			)
		)
		(stroke
			(width 0)
			(type solid)
		)
		(fill yes)
		(layer "In2.Cu")
		(net "GND")
	)
	(gr_poly
		(pts
			(arc
				(start 404.610062 -418.412168)
				(mid 404.350982 -418.412168)
				(end 404.610062 -418.412168)
			)
		)
		(stroke
			(width 0)
			(type solid)
		)
		(fill yes)
		(layer "In2.Cu")
		(net "GND")
	)
	(gr_poly
		(pts
			(arc
				(start 404.610062 -415.38652)
				(mid 404.350982 -415.38652)
				(end 404.610062 -415.38652)
			)
		)
		(stroke
			(width 0)
			(type solid)
		)
		(fill yes)
		(layer "In2.Cu")
		(net "GND")
	)
	(gr_poly
		(pts
			(arc
				(start 405.692102 -418.412168)
				(mid 405.433022 -418.412168)
				(end 405.692102 -418.412168)
			)
		)
		(stroke
			(width 0)
			(type solid)
		)
		(fill yes)
		(layer "In2.Cu")
		(net "GND")
	)
	(gr_poly
		(pts
			(arc
				(start 405.692102 -415.38652)
				(mid 405.433022 -415.38652)
				(end 405.692102 -415.38652)
			)
		)
		(stroke
			(width 0)
			(type solid)
		)
		(fill yes)
		(layer "In2.Cu")
		(net "GND")
	)
	(gr_poly
		(pts
			(arc
				(start 405.780494 -421.586152)
				(mid 405.521414 -421.586152)
				(end 405.780494 -421.586152)
			)
		)
		(stroke
			(width 0)
			(type solid)
		)
		(fill yes)
		(layer "In2.Cu")
		(net "GND")
	)
	(gr_poly
		(pts
			(arc
				(start 405.780494 -420.318184)
				(mid 405.521414 -420.318184)
				(end 405.780494 -420.318184)
			)
		)
		(stroke
			(width 0)
			(type solid)
		)
		(fill yes)
		(layer "In2.Cu")
		(net "GND")
	)
	(gr_poly
		(pts
			(arc
				(start 405.780494 -413.480504)
				(mid 405.521414 -413.480504)
				(end 405.780494 -413.480504)
			)
		)
		(stroke
			(width 0)
			(type solid)
		)
		(fill yes)
		(layer "In2.Cu")
		(net "GND")
	)
	(gr_poly
		(pts
			(arc
				(start 405.780494 -412.212536)
				(mid 405.521414 -412.212536)
				(end 405.780494 -412.212536)
			)
		)
		(stroke
			(width 0)
			(type solid)
		)
		(fill yes)
		(layer "In2.Cu")
		(net "GND")
	)
	(gr_poly
		(pts
			(arc
				(start 406.05329 -419.046152)
				(mid 405.79421 -419.046152)
				(end 406.05329 -419.046152)
			)
		)
		(stroke
			(width 0)
			(type solid)
		)
		(fill yes)
		(layer "In2.Cu")
		(net "GND")
	)
	(gr_poly
		(pts
			(arc
				(start 406.05329 -417.778184)
				(mid 405.79421 -417.778184)
				(end 406.05329 -417.778184)
			)
		)
		(stroke
			(width 0)
			(type solid)
		)
		(fill yes)
		(layer "In2.Cu")
		(net "GND")
	)
	(gr_poly
		(pts
			(arc
				(start 406.05329 -416.020504)
				(mid 405.79421 -416.020504)
				(end 406.05329 -416.020504)
			)
		)
		(stroke
			(width 0)
			(type solid)
		)
		(fill yes)
		(layer "In2.Cu")
		(net "GND")
	)
	(gr_poly
		(pts
			(arc
				(start 406.05329 -414.752536)
				(mid 405.79421 -414.752536)
				(end 406.05329 -414.752536)
			)
		)
		(stroke
			(width 0)
			(type solid)
		)
		(fill yes)
		(layer "In2.Cu")
		(net "GND")
	)
	(gr_poly
		(pts
			(arc
				(start 406.141682 -420.952168)
				(mid 405.882602 -420.952168)
				(end 406.141682 -420.952168)
			)
		)
		(stroke
			(width 0)
			(type solid)
		)
		(fill yes)
		(layer "In2.Cu")
		(net "GND")
	)
	(gr_poly
		(pts
			(arc
				(start 406.141682 -412.84652)
				(mid 405.882602 -412.84652)
				(end 406.141682 -412.84652)
			)
		)
		(stroke
			(width 0)
			(type solid)
		)
		(fill yes)
		(layer "In2.Cu")
		(net "GND")
	)
	(gr_poly
		(pts
			(arc
				(start 407.223722 -420.952168)
				(mid 406.964642 -420.952168)
				(end 407.223722 -420.952168)
			)
		)
		(stroke
			(width 0)
			(type solid)
		)
		(fill yes)
		(layer "In2.Cu")
		(net "GND")
	)
	(gr_poly
		(pts
			(arc
				(start 407.223722 -412.84652)
				(mid 406.964642 -412.84652)
				(end 407.223722 -412.84652)
			)
		)
		(stroke
			(width 0)
			(type solid)
		)
		(fill yes)
		(layer "In2.Cu")
		(net "GND")
	)
	(gr_poly
		(pts
			(arc
				(start 407.312114 -419.046152)
				(mid 407.053034 -419.046152)
				(end 407.312114 -419.046152)
			)
		)
		(stroke
			(width 0)
			(type solid)
		)
		(fill yes)
		(layer "In2.Cu")
		(net "GND")
	)
	(gr_poly
		(pts
			(arc
				(start 407.312114 -417.778184)
				(mid 407.053034 -417.778184)
				(end 407.312114 -417.778184)
			)
		)
		(stroke
			(width 0)
			(type solid)
		)
		(fill yes)
		(layer "In2.Cu")
		(net "GND")
	)
	(gr_poly
		(pts
			(arc
				(start 407.312114 -416.020504)
				(mid 407.053034 -416.020504)
				(end 407.312114 -416.020504)
			)
		)
		(stroke
			(width 0)
			(type solid)
		)
		(fill yes)
		(layer "In2.Cu")
		(net "GND")
	)
	(gr_poly
		(pts
			(arc
				(start 407.312114 -414.752536)
				(mid 407.053034 -414.752536)
				(end 407.312114 -414.752536)
			)
		)
		(stroke
			(width 0)
			(type solid)
		)
		(fill yes)
		(layer "In2.Cu")
		(net "GND")
	)
	(gr_poly
		(pts
			(arc
				(start 407.58491 -421.586152)
				(mid 407.32583 -421.586152)
				(end 407.58491 -421.586152)
			)
		)
		(stroke
			(width 0)
			(type solid)
		)
		(fill yes)
		(layer "In2.Cu")
		(net "GND")
	)
	(gr_poly
		(pts
			(arc
				(start 407.58491 -420.318184)
				(mid 407.32583 -420.318184)
				(end 407.58491 -420.318184)
			)
		)
		(stroke
			(width 0)
			(type solid)
		)
		(fill yes)
		(layer "In2.Cu")
		(net "GND")
	)
	(gr_poly
		(pts
			(arc
				(start 407.58491 -413.480504)
				(mid 407.32583 -413.480504)
				(end 407.58491 -413.480504)
			)
		)
		(stroke
			(width 0)
			(type solid)
		)
		(fill yes)
		(layer "In2.Cu")
		(net "GND")
	)
	(gr_poly
		(pts
			(arc
				(start 407.58491 -412.212536)
				(mid 407.32583 -412.212536)
				(end 407.58491 -412.212536)
			)
		)
		(stroke
			(width 0)
			(type solid)
		)
		(fill yes)
		(layer "In2.Cu")
		(net "GND")
	)
	(gr_poly
		(pts
			(arc
				(start 407.673302 -418.412168)
				(mid 407.414222 -418.412168)
				(end 407.673302 -418.412168)
			)
		)
		(stroke
			(width 0)
			(type solid)
		)
		(fill yes)
		(layer "In2.Cu")
		(net "GND")
	)
	(gr_poly
		(pts
			(arc
				(start 407.673302 -415.38652)
				(mid 407.414222 -415.38652)
				(end 407.673302 -415.38652)
			)
		)
		(stroke
			(width 0)
			(type solid)
		)
		(fill yes)
		(layer "In2.Cu")
		(net "GND")
	)
	(gr_poly
		(pts
			(arc
				(start 408.755342 -418.412168)
				(mid 408.496262 -418.412168)
				(end 408.755342 -418.412168)
			)
		)
		(stroke
			(width 0)
			(type solid)
		)
		(fill yes)
		(layer "In2.Cu")
		(net "GND")
	)
	(gr_poly
		(pts
			(arc
				(start 408.755342 -415.38652)
				(mid 408.496262 -415.38652)
				(end 408.755342 -415.38652)
			)
		)
		(stroke
			(width 0)
			(type solid)
		)
		(fill yes)
		(layer "In2.Cu")
		(net "GND")
	)
	(gr_poly
		(pts
			(arc
				(start 408.843734 -421.586152)
				(mid 408.584654 -421.586152)
				(end 408.843734 -421.586152)
			)
		)
		(stroke
			(width 0)
			(type solid)
		)
		(fill yes)
		(layer "In2.Cu")
		(net "GND")
	)
	(gr_poly
		(pts
			(arc
				(start 408.843734 -420.318184)
				(mid 408.584654 -420.318184)
				(end 408.843734 -420.318184)
			)
		)
		(stroke
			(width 0)
			(type solid)
		)
		(fill yes)
		(layer "In2.Cu")
		(net "GND")
	)
	(gr_poly
		(pts
			(arc
				(start 408.843734 -413.480504)
				(mid 408.584654 -413.480504)
				(end 408.843734 -413.480504)
			)
		)
		(stroke
			(width 0)
			(type solid)
		)
		(fill yes)
		(layer "In2.Cu")
		(net "GND")
	)
	(gr_poly
		(pts
			(arc
				(start 408.843734 -412.212536)
				(mid 408.584654 -412.212536)
				(end 408.843734 -412.212536)
			)
		)
		(stroke
			(width 0)
			(type solid)
		)
		(fill yes)
		(layer "In2.Cu")
		(net "GND")
	)
	(gr_poly
		(pts
			(arc
				(start 409.11653 -419.046152)
				(mid 408.85745 -419.046152)
				(end 409.11653 -419.046152)
			)
		)
		(stroke
			(width 0)
			(type solid)
		)
		(fill yes)
		(layer "In2.Cu")
		(net "GND")
	)
	(gr_poly
		(pts
			(arc
				(start 409.11653 -417.778184)
				(mid 408.85745 -417.778184)
				(end 409.11653 -417.778184)
			)
		)
		(stroke
			(width 0)
			(type solid)
		)
		(fill yes)
		(layer "In2.Cu")
		(net "GND")
	)
	(gr_poly
		(pts
			(arc
				(start 409.11653 -416.020504)
				(mid 408.85745 -416.020504)
				(end 409.11653 -416.020504)
			)
		)
		(stroke
			(width 0)
			(type solid)
		)
		(fill yes)
		(layer "In2.Cu")
		(net "GND")
	)
	(gr_poly
		(pts
			(arc
				(start 409.11653 -414.752536)
				(mid 408.85745 -414.752536)
				(end 409.11653 -414.752536)
			)
		)
		(stroke
			(width 0)
			(type solid)
		)
		(fill yes)
		(layer "In2.Cu")
		(net "GND")
	)
	(gr_poly
		(pts
			(arc
				(start 409.204922 -420.952168)
				(mid 408.945842 -420.952168)
				(end 409.204922 -420.952168)
			)
		)
		(stroke
			(width 0)
			(type solid)
		)
		(fill yes)
		(layer "In2.Cu")
		(net "GND")
	)
	(gr_poly
		(pts
			(arc
				(start 409.204922 -412.84652)
				(mid 408.945842 -412.84652)
				(end 409.204922 -412.84652)
			)
		)
		(stroke
			(width 0)
			(type solid)
		)
		(fill yes)
		(layer "In2.Cu")
		(net "GND")
	)
	(gr_poly
		(pts
			(arc
				(start 410.286962 -420.952168)
				(mid 410.027882 -420.952168)
				(end 410.286962 -420.952168)
			)
		)
		(stroke
			(width 0)
			(type solid)
		)
		(fill yes)
		(layer "In2.Cu")
		(net "GND")
	)
	(gr_poly
		(pts
			(arc
				(start 410.286962 -412.84652)
				(mid 410.027882 -412.84652)
				(end 410.286962 -412.84652)
			)
		)
		(stroke
			(width 0)
			(type solid)
		)
		(fill yes)
		(layer "In2.Cu")
		(net "GND")
	)
	(gr_poly
		(pts
			(arc
				(start 410.375354 -419.046152)
				(mid 410.116274 -419.046152)
				(end 410.375354 -419.046152)
			)
		)
		(stroke
			(width 0)
			(type solid)
		)
		(fill yes)
		(layer "In2.Cu")
		(net "GND")
	)
	(gr_poly
		(pts
			(arc
				(start 410.375354 -417.778184)
				(mid 410.116274 -417.778184)
				(end 410.375354 -417.778184)
			)
		)
		(stroke
			(width 0)
			(type solid)
		)
		(fill yes)
		(layer "In2.Cu")
		(net "GND")
	)
	(gr_poly
		(pts
			(arc
				(start 410.375354 -416.020504)
				(mid 410.116274 -416.020504)
				(end 410.375354 -416.020504)
			)
		)
		(stroke
			(width 0)
			(type solid)
		)
		(fill yes)
		(layer "In2.Cu")
		(net "GND")
	)
	(gr_poly
		(pts
			(arc
				(start 410.375354 -414.752536)
				(mid 410.116274 -414.752536)
				(end 410.375354 -414.752536)
			)
		)
		(stroke
			(width 0)
			(type solid)
		)
		(fill yes)
		(layer "In2.Cu")
		(net "GND")
	)
	(gr_poly
		(pts
			(arc
				(start 410.64815 -421.586152)
				(mid 410.38907 -421.586152)
				(end 410.64815 -421.586152)
			)
		)
		(stroke
			(width 0)
			(type solid)
		)
		(fill yes)
		(layer "In2.Cu")
		(net "GND")
	)
	(gr_poly
		(pts
			(arc
				(start 410.64815 -420.318184)
				(mid 410.38907 -420.318184)
				(end 410.64815 -420.318184)
			)
		)
		(stroke
			(width 0)
			(type solid)
		)
		(fill yes)
		(layer "In2.Cu")
		(net "GND")
	)
	(gr_poly
		(pts
			(arc
				(start 410.64815 -413.480504)
				(mid 410.38907 -413.480504)
				(end 410.64815 -413.480504)
			)
		)
		(stroke
			(width 0)
			(type solid)
		)
		(fill yes)
		(layer "In2.Cu")
		(net "GND")
	)
	(gr_poly
		(pts
			(arc
				(start 410.64815 -412.212536)
				(mid 410.38907 -412.212536)
				(end 410.64815 -412.212536)
			)
		)
		(stroke
			(width 0)
			(type solid)
		)
		(fill yes)
		(layer "In2.Cu")
		(net "GND")
	)
	(gr_poly
		(pts
			(arc
				(start 410.736542 -418.412168)
				(mid 410.477462 -418.412168)
				(end 410.736542 -418.412168)
			)
		)
		(stroke
			(width 0)
			(type solid)
		)
		(fill yes)
		(layer "In2.Cu")
		(net "GND")
	)
	(gr_poly
		(pts
			(arc
				(start 410.736542 -415.38652)
				(mid 410.477462 -415.38652)
				(end 410.736542 -415.38652)
			)
		)
		(stroke
			(width 0)
			(type solid)
		)
		(fill yes)
		(layer "In2.Cu")
		(net "GND")
	)
	(gr_poly
		(pts
			(arc
				(start 411.818582 -418.412168)
				(mid 411.559502 -418.412168)
				(end 411.818582 -418.412168)
			)
		)
		(stroke
			(width 0)
			(type solid)
		)
		(fill yes)
		(layer "In2.Cu")
		(net "GND")
	)
	(gr_poly
		(pts
			(arc
				(start 411.818582 -415.38652)
				(mid 411.559502 -415.38652)
				(end 411.818582 -415.38652)
			)
		)
		(stroke
			(width 0)
			(type solid)
		)
		(fill yes)
		(layer "In2.Cu")
		(net "GND")
	)
	(gr_poly
		(pts
			(arc
				(start 411.906974 -421.586152)
				(mid 411.647894 -421.586152)
				(end 411.906974 -421.586152)
			)
		)
		(stroke
			(width 0)
			(type solid)
		)
		(fill yes)
		(layer "In2.Cu")
		(net "GND")
	)
	(gr_poly
		(pts
			(arc
				(start 411.906974 -420.318184)
				(mid 411.647894 -420.318184)
				(end 411.906974 -420.318184)
			)
		)
		(stroke
			(width 0)
			(type solid)
		)
		(fill yes)
		(layer "In2.Cu")
		(net "GND")
	)
	(gr_poly
		(pts
			(arc
				(start 411.906974 -413.480504)
				(mid 411.647894 -413.480504)
				(end 411.906974 -413.480504)
			)
		)
		(stroke
			(width 0)
			(type solid)
		)
		(fill yes)
		(layer "In2.Cu")
		(net "GND")
	)
	(gr_poly
		(pts
			(arc
				(start 411.906974 -412.212536)
				(mid 411.647894 -412.212536)
				(end 411.906974 -412.212536)
			)
		)
		(stroke
			(width 0)
			(type solid)
		)
		(fill yes)
		(layer "In2.Cu")
		(net "GND")
	)
	(gr_poly
		(pts
			(arc
				(start 412.17977 -419.046152)
				(mid 411.92069 -419.046152)
				(end 412.17977 -419.046152)
			)
		)
		(stroke
			(width 0)
			(type solid)
		)
		(fill yes)
		(layer "In2.Cu")
		(net "GND")
	)
	(gr_poly
		(pts
			(arc
				(start 412.17977 -417.778184)
				(mid 411.92069 -417.778184)
				(end 412.17977 -417.778184)
			)
		)
		(stroke
			(width 0)
			(type solid)
		)
		(fill yes)
		(layer "In2.Cu")
		(net "GND")
	)
	(gr_poly
		(pts
			(arc
				(start 412.17977 -416.020504)
				(mid 411.92069 -416.020504)
				(end 412.17977 -416.020504)
			)
		)
		(stroke
			(width 0)
			(type solid)
		)
		(fill yes)
		(layer "In2.Cu")
		(net "GND")
	)
	(gr_poly
		(pts
			(arc
				(start 412.17977 -414.752536)
				(mid 411.92069 -414.752536)
				(end 412.17977 -414.752536)
			)
		)
		(stroke
			(width 0)
			(type solid)
		)
		(fill yes)
		(layer "In2.Cu")
		(net "GND")
	)
	(gr_poly
		(pts
			(arc
				(start 412.268162 -420.952168)
				(mid 412.009082 -420.952168)
				(end 412.268162 -420.952168)
			)
		)
		(stroke
			(width 0)
			(type solid)
		)
		(fill yes)
		(layer "In2.Cu")
		(net "GND")
	)
	(gr_poly
		(pts
			(arc
				(start 412.268162 -412.84652)
				(mid 412.009082 -412.84652)
				(end 412.268162 -412.84652)
			)
		)
		(stroke
			(width 0)
			(type solid)
		)
		(fill yes)
		(layer "In2.Cu")
		(net "GND")
	)
	(gr_poly
		(pts
			(arc
				(start 413.350202 -420.952168)
				(mid 413.091122 -420.952168)
				(end 413.350202 -420.952168)
			)
		)
		(stroke
			(width 0)
			(type solid)
		)
		(fill yes)
		(layer "In2.Cu")
		(net "GND")
	)
	(gr_poly
		(pts
			(arc
				(start 413.350202 -412.84652)
				(mid 413.091122 -412.84652)
				(end 413.350202 -412.84652)
			)
		)
		(stroke
			(width 0)
			(type solid)
		)
		(fill yes)
		(layer "In2.Cu")
		(net "GND")
	)
	(gr_poly
		(pts
			(arc
				(start 413.438594 -419.046152)
				(mid 413.179514 -419.046152)
				(end 413.438594 -419.046152)
			)
		)
		(stroke
			(width 0)
			(type solid)
		)
		(fill yes)
		(layer "In2.Cu")
		(net "GND")
	)
	(gr_poly
		(pts
			(arc
				(start 413.438594 -417.778184)
				(mid 413.179514 -417.778184)
				(end 413.438594 -417.778184)
			)
		)
		(stroke
			(width 0)
			(type solid)
		)
		(fill yes)
		(layer "In2.Cu")
		(net "GND")
	)
	(gr_poly
		(pts
			(arc
				(start 413.438594 -416.020504)
				(mid 413.179514 -416.020504)
				(end 413.438594 -416.020504)
			)
		)
		(stroke
			(width 0)
			(type solid)
		)
		(fill yes)
		(layer "In2.Cu")
		(net "GND")
	)
	(gr_poly
		(pts
			(arc
				(start 413.438594 -414.752536)
				(mid 413.179514 -414.752536)
				(end 413.438594 -414.752536)
			)
		)
		(stroke
			(width 0)
			(type solid)
		)
		(fill yes)
		(layer "In2.Cu")
		(net "GND")
	)
	(gr_poly
		(pts
			(arc
				(start 413.71139 -421.586152)
				(mid 413.45231 -421.586152)
				(end 413.71139 -421.586152)
			)
		)
		(stroke
			(width 0)
			(type solid)
		)
		(fill yes)
		(layer "In2.Cu")
		(net "GND")
	)
	(gr_poly
		(pts
			(arc
				(start 413.71139 -420.318184)
				(mid 413.45231 -420.318184)
				(end 413.71139 -420.318184)
			)
		)
		(stroke
			(width 0)
			(type solid)
		)
		(fill yes)
		(layer "In2.Cu")
		(net "GND")
	)
	(gr_poly
		(pts
			(arc
				(start 413.71139 -413.480504)
				(mid 413.45231 -413.480504)
				(end 413.71139 -413.480504)
			)
		)
		(stroke
			(width 0)
			(type solid)
		)
		(fill yes)
		(layer "In2.Cu")
		(net "GND")
	)
	(gr_poly
		(pts
			(arc
				(start 413.71139 -412.212536)
				(mid 413.45231 -412.212536)
				(end 413.71139 -412.212536)
			)
		)
		(stroke
			(width 0)
			(type solid)
		)
		(fill yes)
		(layer "In2.Cu")
		(net "GND")
	)
	(gr_poly
		(pts
			(arc
				(start 413.799782 -418.412168)
				(mid 413.540702 -418.412168)
				(end 413.799782 -418.412168)
			)
		)
		(stroke
			(width 0)
			(type solid)
		)
		(fill yes)
		(layer "In2.Cu")
		(net "GND")
	)
	(gr_poly
		(pts
			(arc
				(start 413.799782 -415.38652)
				(mid 413.540702 -415.38652)
				(end 413.799782 -415.38652)
			)
		)
		(stroke
			(width 0)
			(type solid)
		)
		(fill yes)
		(layer "In2.Cu")
		(net "GND")
	)
	(gr_poly
		(pts
			(arc
				(start 414.881822 -418.412168)
				(mid 414.622742 -418.412168)
				(end 414.881822 -418.412168)
			)
		)
		(stroke
			(width 0)
			(type solid)
		)
		(fill yes)
		(layer "In2.Cu")
		(net "GND")
	)
	(gr_poly
		(pts
			(arc
				(start 414.881822 -415.38652)
				(mid 414.622742 -415.38652)
				(end 414.881822 -415.38652)
			)
		)
		(stroke
			(width 0)
			(type solid)
		)
		(fill yes)
		(layer "In2.Cu")
		(net "GND")
	)
	(gr_poly
		(pts
			(arc
				(start 414.970214 -421.586152)
				(mid 414.711134 -421.586152)
				(end 414.970214 -421.586152)
			)
		)
		(stroke
			(width 0)
			(type solid)
		)
		(fill yes)
		(layer "In2.Cu")
		(net "GND")
	)
	(gr_poly
		(pts
			(arc
				(start 414.970214 -420.318184)
				(mid 414.711134 -420.318184)
				(end 414.970214 -420.318184)
			)
		)
		(stroke
			(width 0)
			(type solid)
		)
		(fill yes)
		(layer "In2.Cu")
		(net "GND")
	)
	(gr_poly
		(pts
			(arc
				(start 414.970214 -413.480504)
				(mid 414.711134 -413.480504)
				(end 414.970214 -413.480504)
			)
		)
		(stroke
			(width 0)
			(type solid)
		)
		(fill yes)
		(layer "In2.Cu")
		(net "GND")
	)
	(gr_poly
		(pts
			(arc
				(start 414.970214 -412.212536)
				(mid 414.711134 -412.212536)
				(end 414.970214 -412.212536)
			)
		)
		(stroke
			(width 0)
			(type solid)
		)
		(fill yes)
		(layer "In2.Cu")
		(net "GND")
	)
	(gr_poly
		(pts
			(arc
				(start 415.24301 -419.046152)
				(mid 414.98393 -419.046152)
				(end 415.24301 -419.046152)
			)
		)
		(stroke
			(width 0)
			(type solid)
		)
		(fill yes)
		(layer "In2.Cu")
		(net "GND")
	)
	(gr_poly
		(pts
			(arc
				(start 415.24301 -417.778184)
				(mid 414.98393 -417.778184)
				(end 415.24301 -417.778184)
			)
		)
		(stroke
			(width 0)
			(type solid)
		)
		(fill yes)
		(layer "In2.Cu")
		(net "GND")
	)
	(gr_poly
		(pts
			(arc
				(start 415.24301 -416.020504)
				(mid 414.98393 -416.020504)
				(end 415.24301 -416.020504)
			)
		)
		(stroke
			(width 0)
			(type solid)
		)
		(fill yes)
		(layer "In2.Cu")
		(net "GND")
	)
	(gr_poly
		(pts
			(arc
				(start 415.24301 -414.752536)
				(mid 414.98393 -414.752536)
				(end 415.24301 -414.752536)
			)
		)
		(stroke
			(width 0)
			(type solid)
		)
		(fill yes)
		(layer "In2.Cu")
		(net "GND")
	)
	(gr_poly
		(pts
			(arc
				(start 415.331402 -420.952168)
				(mid 415.072322 -420.952168)
				(end 415.331402 -420.952168)
			)
		)
		(stroke
			(width 0)
			(type solid)
		)
		(fill yes)
		(layer "In2.Cu")
		(net "GND")
	)
	(gr_poly
		(pts
			(arc
				(start 415.331402 -412.84652)
				(mid 415.072322 -412.84652)
				(end 415.331402 -412.84652)
			)
		)
		(stroke
			(width 0)
			(type solid)
		)
		(fill yes)
		(layer "In2.Cu")
		(net "GND")
	)
	(gr_poly
		(pts
			(arc
				(start 416.413442 -420.952168)
				(mid 416.154362 -420.952168)
				(end 416.413442 -420.952168)
			)
		)
		(stroke
			(width 0)
			(type solid)
		)
		(fill yes)
		(layer "In2.Cu")
		(net "GND")
	)
	(gr_poly
		(pts
			(arc
				(start 416.415982 -412.84652)
				(mid 416.156902 -412.84652)
				(end 416.415982 -412.84652)
			)
		)
		(stroke
			(width 0)
			(type solid)
		)
		(fill yes)
		(layer "In2.Cu")
		(net "GND")
	)
	(gr_poly
		(pts
			(arc
				(start 416.501834 -419.046152)
				(mid 416.242754 -419.046152)
				(end 416.501834 -419.046152)
			)
		)
		(stroke
			(width 0)
			(type solid)
		)
		(fill yes)
		(layer "In2.Cu")
		(net "GND")
	)
	(gr_poly
		(pts
			(arc
				(start 416.501834 -417.778184)
				(mid 416.242754 -417.778184)
				(end 416.501834 -417.778184)
			)
		)
		(stroke
			(width 0)
			(type solid)
		)
		(fill yes)
		(layer "In2.Cu")
		(net "GND")
	)
	(gr_poly
		(pts
			(arc
				(start 416.501834 -416.020504)
				(mid 416.242754 -416.020504)
				(end 416.501834 -416.020504)
			)
		)
		(stroke
			(width 0)
			(type solid)
		)
		(fill yes)
		(layer "In2.Cu")
		(net "GND")
	)
	(gr_poly
		(pts
			(arc
				(start 416.501834 -414.752536)
				(mid 416.242754 -414.752536)
				(end 416.501834 -414.752536)
			)
		)
		(stroke
			(width 0)
			(type solid)
		)
		(fill yes)
		(layer "In2.Cu")
		(net "GND")
	)
	(gr_poly
		(pts
			(arc
				(start 416.77463 -421.586152)
				(mid 416.51555 -421.586152)
				(end 416.77463 -421.586152)
			)
		)
		(stroke
			(width 0)
			(type solid)
		)
		(fill yes)
		(layer "In2.Cu")
		(net "GND")
	)
	(gr_poly
		(pts
			(arc
				(start 416.77463 -420.318184)
				(mid 416.51555 -420.318184)
				(end 416.77463 -420.318184)
			)
		)
		(stroke
			(width 0)
			(type solid)
		)
		(fill yes)
		(layer "In2.Cu")
		(net "GND")
	)
	(gr_poly
		(pts
			(arc
				(start 416.77463 -413.480504)
				(mid 416.51555 -413.480504)
				(end 416.77463 -413.480504)
			)
		)
		(stroke
			(width 0)
			(type solid)
		)
		(fill yes)
		(layer "In2.Cu")
		(net "GND")
	)
	(gr_poly
		(pts
			(arc
				(start 416.77463 -412.212536)
				(mid 416.51555 -412.212536)
				(end 416.77463 -412.212536)
			)
		)
		(stroke
			(width 0)
			(type solid)
		)
		(fill yes)
		(layer "In2.Cu")
		(net "GND")
	)
	(gr_poly
		(pts
			(arc
				(start 416.863022 -418.412168)
				(mid 416.603942 -418.412168)
				(end 416.863022 -418.412168)
			)
		)
		(stroke
			(width 0)
			(type solid)
		)
		(fill yes)
		(layer "In2.Cu")
		(net "GND")
	)
	(gr_poly
		(pts
			(arc
				(start 416.863022 -415.38652)
				(mid 416.603942 -415.38652)
				(end 416.863022 -415.38652)
			)
		)
		(stroke
			(width 0)
			(type solid)
		)
		(fill yes)
		(layer "In2.Cu")
		(net "GND")
	)
	(gr_poly
		(pts
			(arc
				(start 417.945062 -418.412168)
				(mid 417.685982 -418.412168)
				(end 417.945062 -418.412168)
			)
		)
		(stroke
			(width 0)
			(type solid)
		)
		(fill yes)
		(layer "In2.Cu")
		(net "GND")
	)
	(gr_poly
		(pts
			(arc
				(start 417.945062 -415.38652)
				(mid 417.685982 -415.38652)
				(end 417.945062 -415.38652)
			)
		)
		(stroke
			(width 0)
			(type solid)
		)
		(fill yes)
		(layer "In2.Cu")
		(net "GND")
	)
	(gr_poly
		(pts
			(arc
				(start 418.033454 -421.586152)
				(mid 417.774374 -421.586152)
				(end 418.033454 -421.586152)
			)
		)
		(stroke
			(width 0)
			(type solid)
		)
		(fill yes)
		(layer "In2.Cu")
		(net "GND")
	)
	(gr_poly
		(pts
			(arc
				(start 418.033454 -420.318184)
				(mid 417.774374 -420.318184)
				(end 418.033454 -420.318184)
			)
		)
		(stroke
			(width 0)
			(type solid)
		)
		(fill yes)
		(layer "In2.Cu")
		(net "GND")
	)
	(gr_poly
		(pts
			(arc
				(start 418.033454 -413.480504)
				(mid 417.774374 -413.480504)
				(end 418.033454 -413.480504)
			)
		)
		(stroke
			(width 0)
			(type solid)
		)
		(fill yes)
		(layer "In2.Cu")
		(net "GND")
	)
	(gr_poly
		(pts
			(arc
				(start 418.033454 -412.212536)
				(mid 417.774374 -412.212536)
				(end 418.033454 -412.212536)
			)
		)
		(stroke
			(width 0)
			(type solid)
		)
		(fill yes)
		(layer "In2.Cu")
		(net "GND")
	)
	(gr_poly
		(pts
			(arc
				(start 418.30625 -419.046152)
				(mid 418.04717 -419.046152)
				(end 418.30625 -419.046152)
			)
		)
		(stroke
			(width 0)
			(type solid)
		)
		(fill yes)
		(layer "In2.Cu")
		(net "GND")
	)
	(gr_poly
		(pts
			(arc
				(start 418.30625 -417.778184)
				(mid 418.04717 -417.778184)
				(end 418.30625 -417.778184)
			)
		)
		(stroke
			(width 0)
			(type solid)
		)
		(fill yes)
		(layer "In2.Cu")
		(net "GND")
	)
	(gr_poly
		(pts
			(arc
				(start 418.30625 -416.020504)
				(mid 418.04717 -416.020504)
				(end 418.30625 -416.020504)
			)
		)
		(stroke
			(width 0)
			(type solid)
		)
		(fill yes)
		(layer "In2.Cu")
		(net "GND")
	)
	(gr_poly
		(pts
			(arc
				(start 418.30625 -414.752536)
				(mid 418.04717 -414.752536)
				(end 418.30625 -414.752536)
			)
		)
		(stroke
			(width 0)
			(type solid)
		)
		(fill yes)
		(layer "In2.Cu")
		(net "GND")
	)
	(gr_poly
		(pts
			(arc
				(start 418.394642 -420.952168)
				(mid 418.135562 -420.952168)
				(end 418.394642 -420.952168)
			)
		)
		(stroke
			(width 0)
			(type solid)
		)
		(fill yes)
		(layer "In2.Cu")
		(net "GND")
	)
	(gr_poly
		(pts
			(arc
				(start 418.394642 -412.84652)
				(mid 418.135562 -412.84652)
				(end 418.394642 -412.84652)
			)
		)
		(stroke
			(width 0)
			(type solid)
		)
		(fill yes)
		(layer "In2.Cu")
		(net "GND")
	)
	(gr_poly
		(pts
			(arc
				(start 419.565074 -419.046152)
				(mid 419.305994 -419.046152)
				(end 419.565074 -419.046152)
			)
		)
		(stroke
			(width 0)
			(type solid)
		)
		(fill yes)
		(layer "In2.Cu")
		(net "GND")
	)
	(gr_poly
		(pts
			(arc
				(start 419.565074 -417.778184)
				(mid 419.305994 -417.778184)
				(end 419.565074 -417.778184)
			)
		)
		(stroke
			(width 0)
			(type solid)
		)
		(fill yes)
		(layer "In2.Cu")
		(net "GND")
	)
	(gr_poly
		(pts
			(arc
				(start 419.565074 -416.020504)
				(mid 419.305994 -416.020504)
				(end 419.565074 -416.020504)
			)
		)
		(stroke
			(width 0)
			(type solid)
		)
		(fill yes)
		(layer "In2.Cu")
		(net "GND")
	)
	(gr_poly
		(pts
			(arc
				(start 419.565074 -414.752536)
				(mid 419.305994 -414.752536)
				(end 419.565074 -414.752536)
			)
		)
		(stroke
			(width 0)
			(type solid)
		)
		(fill yes)
		(layer "In2.Cu")
		(net "GND")
	)
	(gr_poly
		(pts
			(arc
				(start 419.926262 -418.412168)
				(mid 419.667182 -418.412168)
				(end 419.926262 -418.412168)
			)
		)
		(stroke
			(width 0)
			(type solid)
		)
		(fill yes)
		(layer "In2.Cu")
		(net "GND")
	)
	(gr_poly
		(pts
			(arc
				(start 419.926262 -415.38652)
				(mid 419.667182 -415.38652)
				(end 419.926262 -415.38652)
			)
		)
		(stroke
			(width 0)
			(type solid)
		)
		(fill yes)
		(layer "In2.Cu")
		(net "GND")
	)
	(gr_poly
		(pts
			(arc
				(start 100.4443 -403.864572)
				(mid 100.17252 -403.864572)
				(end 100.4443 -403.864572)
			)
		)
		(stroke
			(width 0)
			(type solid)
		)
		(fill yes)
		(layer "In2.Cu")
		(net "GND")
	)
	(gr_poly
		(pts
			(arc
				(start 105.420414 -32.405066)
				(mid 105.138474 -32.405066)
				(end 105.420414 -32.405066)
			)
		)
		(stroke
			(width 0)
			(type solid)
		)
		(fill yes)
		(layer "In2.Cu")
		(net "GND")
	)
	(gr_poly
		(pts
			(arc
				(start 107.084876 -398.568672)
				(mid 106.813096 -398.568672)
				(end 107.084876 -398.568672)
			)
		)
		(stroke
			(width 0)
			(type solid)
		)
		(fill yes)
		(layer "In2.Cu")
		(net "GND")
	)
	(gr_poly
		(pts
			(arc
				(start 109.416596 -401.758404)
				(mid 109.144816 -401.758404)
				(end 109.416596 -401.758404)
			)
		)
		(stroke
			(width 0)
			(type solid)
		)
		(fill yes)
		(layer "In2.Cu")
		(net "GND")
	)
	(gr_poly
		(pts
			(xy 229.6795 -435.74208) (xy 229.6795 -422.049194) (xy 234.763056 -416.965638) (xy 272.06448 -416.965638)
			(xy 280.05024 -408.979878) (xy 280.05024 -398.554956) (xy 279.280874 -397.78559) (xy 240.059718 -397.78559)
			(xy 239.91189 -397.933418) (xy 239.91189 -404.086822) (xy 239.91189 -405.227536) (xy 239.91189 -405.609298)
			(xy 234.87634 -410.644848) (xy 229.69855 -410.644848) (xy 229.676198 -410.6672) (xy 227.067872 -413.275526)
			(xy 196.769482 -413.275526) (xy 196.26072 -413.784288) (xy 196.26072 -414.072832) (xy 196.26072 -421.757602)
			(arc
				(start 206.039974 -431.536856)
				(mid 206.051085 -431.55339)
				(end 206.05496 -431.572924)
			)
			(xy 206.05496 -435.09946) (xy 207.43418 -436.47868) (xy 228.9429 -436.47868)
		)
		(stroke
			(width 0)
			(type solid)
		)
		(fill yes)
		(layer "In2.Cu")
		(net "P12V_PSU")
	)
	(gr_poly
		(pts
			(arc
				(start 169.257472 -419.693598)
				(mid 168.969944 -419.693598)
				(end 169.257472 -419.693598)
			)
		)
		(stroke
			(width 0)
			(type solid)
		)
		(fill yes)
		(layer "In2.Cu")
		(net "GND")
	)
	(gr_poly
		(pts
			(arc
				(start 67.054984 -8.79475)
				(mid 66.689224 -8.79475)
				(end 67.054984 -8.79475)
			)
		)
		(stroke
			(width 0)
			(type solid)
		)
		(fill yes)
		(layer "In2.Cu")
		(net "GND")
	)
	(gr_poly
		(pts
			(arc
				(start 172.563536 -22.37232)
				(mid 172.197776 -22.37232)
				(end 172.563536 -22.37232)
			)
		)
		(stroke
			(width 0)
			(type solid)
		)
		(fill yes)
		(layer "In2.Cu")
		(net "GND")
	)
	(gr_poly
		(pts
			(arc
				(start 172.831506 -15.002764)
				(mid 172.465746 -15.002764)
				(end 172.831506 -15.002764)
			)
		)
		(stroke
			(width 0)
			(type solid)
		)
		(fill yes)
		(layer "In2.Cu")
		(net "GND")
	)
	(gr_poly
		(pts
			(arc
				(start 174.64405 -11.100054)
				(mid 174.27829 -11.100054)
				(end 174.64405 -11.100054)
			)
		)
		(stroke
			(width 0)
			(type solid)
		)
		(fill yes)
		(layer "In2.Cu")
		(net "GND")
	)
	(gr_poly
		(pts
			(arc
				(start 217.707718 -87.545926)
				(mid 217.341958 -87.545926)
				(end 217.707718 -87.545926)
			)
		)
		(stroke
			(width 0)
			(type solid)
		)
		(fill yes)
		(layer "In2.Cu")
		(net "GND")
	)
	(gr_poly
		(pts
			(arc
				(start 217.707718 -86.296754)
				(mid 217.341958 -86.296754)
				(end 217.707718 -86.296754)
			)
		)
		(stroke
			(width 0)
			(type solid)
		)
		(fill yes)
		(layer "In2.Cu")
		(net "GND")
	)
	(gr_poly
		(pts
			(arc
				(start 218.661488 -84.662518)
				(mid 218.295728 -84.662518)
				(end 218.661488 -84.662518)
			)
		)
		(stroke
			(width 0)
			(type solid)
		)
		(fill yes)
		(layer "In2.Cu")
		(net "GND")
	)
	(gr_poly
		(pts
			(arc
				(start 218.661488 -83.413346)
				(mid 218.295728 -83.413346)
				(end 218.661488 -83.413346)
			)
		)
		(stroke
			(width 0)
			(type solid)
		)
		(fill yes)
		(layer "In2.Cu")
		(net "GND")
	)
	(gr_poly
		(pts
			(arc
				(start 218.972638 -87.545926)
				(mid 218.606878 -87.545926)
				(end 218.972638 -87.545926)
			)
		)
		(stroke
			(width 0)
			(type solid)
		)
		(fill yes)
		(layer "In2.Cu")
		(net "GND")
	)
	(gr_poly
		(pts
			(arc
				(start 218.972638 -86.296754)
				(mid 218.606878 -86.296754)
				(end 218.972638 -86.296754)
			)
		)
		(stroke
			(width 0)
			(type solid)
		)
		(fill yes)
		(layer "In2.Cu")
		(net "GND")
	)
	(gr_poly
		(pts
			(arc
				(start 219.926408 -84.662518)
				(mid 219.560648 -84.662518)
				(end 219.926408 -84.662518)
			)
		)
		(stroke
			(width 0)
			(type solid)
		)
		(fill yes)
		(layer "In2.Cu")
		(net "GND")
	)
	(gr_poly
		(pts
			(arc
				(start 219.926408 -83.413346)
				(mid 219.560648 -83.413346)
				(end 219.926408 -83.413346)
			)
		)
		(stroke
			(width 0)
			(type solid)
		)
		(fill yes)
		(layer "In2.Cu")
		(net "GND")
	)
	(gr_poly
		(pts
			(arc
				(start 426.411898 -4.32943)
				(mid 426.056806 -4.32943)
				(end 426.411898 -4.32943)
			)
		)
		(stroke
			(width 0)
			(type solid)
		)
		(fill yes)
		(layer "In2.Cu")
		(net "GND")
	)
	(gr_poly
		(pts
			(arc
				(start 427.676818 -4.32943)
				(mid 427.321726 -4.32943)
				(end 427.676818 -4.32943)
			)
		)
		(stroke
			(width 0)
			(type solid)
		)
		(fill yes)
		(layer "In2.Cu")
		(net "GND")
	)
	(gr_poly
		(pts
			(arc
				(start 430.012094 -4.32943)
				(mid 429.657002 -4.32943)
				(end 430.012094 -4.32943)
			)
		)
		(stroke
			(width 0)
			(type solid)
		)
		(fill yes)
		(layer "In2.Cu")
		(net "GND")
	)
	(gr_poly
		(pts
			(arc
				(start 431.277014 -4.32943)
				(mid 430.921922 -4.32943)
				(end 431.277014 -4.32943)
			)
		)
		(stroke
			(width 0)
			(type solid)
		)
		(fill yes)
		(layer "In2.Cu")
		(net "GND")
	)
	(gr_poly
		(pts
			(arc
				(start 431.79238 -4.963414)
				(mid 431.42662 -4.963414)
				(end 431.79238 -4.963414)
			)
		)
		(stroke
			(width 0)
			(type solid)
		)
		(fill yes)
		(layer "In2.Cu")
		(net "GND")
	)
	(gr_poly
		(pts
			(arc
				(start 432.267614 -162.981132)
				(mid 431.901854 -162.981132)
				(end 432.267614 -162.981132)
			)
		)
		(stroke
			(width 0)
			(type solid)
		)
		(fill yes)
		(layer "In2.Cu")
		(net "GND")
	)
	(gr_poly
		(pts
			(arc
				(start 433.532534 -162.981132)
				(mid 433.166774 -162.981132)
				(end 433.532534 -162.981132)
			)
		)
		(stroke
			(width 0)
			(type solid)
		)
		(fill yes)
		(layer "In2.Cu")
		(net "GND")
	)
	(gr_poly
		(pts
			(arc
				(start 108.136436 -24.151082)
				(mid 108.155959 -24.147181)
				(end 108.172504 -24.136096)
			)
			(arc
				(start 108.316014 -23.992586)
				(mid 108.327125 -23.976052)
				(end 108.331 -23.956518)
			)
			(arc
				(start 108.331 -20.722082)
				(mid 108.327099 -20.702559)
				(end 108.316014 -20.686014)
			)
			(arc
				(start 108.218986 -20.588986)
				(mid 108.202452 -20.577875)
				(end 108.182918 -20.574)
			)
			(xy 107.849416 -20.574) (xy 107.8484 -20.575016) (xy 105.122472 -20.575016) (xy 105.096564 -20.592542)
			(arc
				(start 105.090976 -20.60702)
				(mid 105.007062 -20.751843)
				(end 104.885236 -20.866608)
			)
			(arc
				(start 104.748076 -20.96262)
				(mid 104.73215 -20.980799)
				(end 104.726486 -21.004276)
			)
			(arc
				(start 104.726486 -24.005286)
				(mid 104.730387 -24.024809)
				(end 104.741472 -24.041354)
			)
			(arc
				(start 104.836214 -24.136096)
				(mid 104.852748 -24.147207)
				(end 104.872282 -24.151082)
			)
		)
		(stroke
			(width 0)
			(type solid)
		)
		(fill yes)
		(layer "In2.Cu")
		(net "GND")
	)
	(gr_poly
		(pts
			(arc
				(start 81.154778 -2.750312)
				(mid 81.182917 -2.732466)
				(end 81.193894 -2.701036)
			)
			(arc
				(start 81.193894 -0.5588)
				(mid 81.179015 -0.522879)
				(end 81.143094 -0.508)
			)
			(arc
				(start 13.660882 -0.508)
				(mid 13.624961 -0.522879)
				(end 13.610082 -0.5588)
			)
			(arc
				(start 13.610082 -2.701036)
				(mid 13.621129 -2.732411)
				(end 13.649198 -2.750312)
			)
			(xy 13.762482 -2.77749) (xy 13.794486 -2.762504)
			(arc
				(start 13.80236 -2.746756)
				(mid 13.928356 -2.557713)
				(end 14.095984 -2.404364)
			)
			(xy 14.11732 -2.363216) (xy 14.11732 -1.014984) (xy 80.686656 -1.014984) (xy 80.686656 -2.363216)
			(arc
				(start 80.707992 -2.404364)
				(mid 80.875659 -2.55768)
				(end 81.001616 -2.746756)
			)
			(xy 81.00949 -2.762504) (xy 81.041494 -2.77749)
		)
		(stroke
			(width 0)
			(type solid)
		)
		(fill yes)
		(layer "In2.Cu")
		(net "GND")
	)
	(gr_poly
		(pts
			(arc
				(start 194.154806 -8.03021)
				(mid 194.182945 -8.012364)
				(end 194.193922 -7.980934)
			)
			(arc
				(start 194.193922 -5.838698)
				(mid 194.179043 -5.802777)
				(end 194.143122 -5.787898)
			)
			(arc
				(start 126.66091 -5.787898)
				(mid 126.624989 -5.802777)
				(end 126.61011 -5.838698)
			)
			(arc
				(start 126.61011 -7.980934)
				(mid 126.621157 -8.012309)
				(end 126.649226 -8.03021)
			)
			(xy 126.76251 -8.057388) (xy 126.794514 -8.042402)
			(arc
				(start 126.802388 -8.026654)
				(mid 126.928384 -7.837611)
				(end 127.096012 -7.684262)
			)
			(xy 127.117348 -7.643114) (xy 127.117348 -6.295136) (xy 193.686684 -6.295136) (xy 193.686684 -7.643114)
			(arc
				(start 193.70802 -7.684262)
				(mid 193.875687 -7.837578)
				(end 194.001644 -8.026654)
			)
			(xy 194.009518 -8.042402) (xy 194.041522 -8.057388)
		)
		(stroke
			(width 0)
			(type solid)
		)
		(fill yes)
		(layer "In2.Cu")
		(net "GND")
	)
	(gr_poly
		(pts
			(arc
				(start 455.654918 -2.75082)
				(mid 455.683057 -2.732974)
				(end 455.694034 -2.701544)
			)
			(arc
				(start 455.694034 -0.5588)
				(mid 455.679155 -0.522879)
				(end 455.643234 -0.508)
			)
			(arc
				(start 388.160768 -0.508)
				(mid 388.124847 -0.522879)
				(end 388.109968 -0.5588)
			)
			(arc
				(start 388.109968 -2.701036)
				(mid 388.121015 -2.732411)
				(end 388.149084 -2.750312)
			)
			(xy 388.262368 -2.77749) (xy 388.294372 -2.762504)
			(arc
				(start 388.302246 -2.746756)
				(mid 388.428345 -2.557672)
				(end 388.596124 -2.404364)
			)
			(arc
				(start 388.596124 -2.404364)
				(mid 388.610195 -2.388884)
				(end 388.616952 -2.369058)
			)
			(xy 388.616952 -1.014984) (xy 455.186796 -1.014984) (xy 455.186796 -2.36347)
			(arc
				(start 455.208132 -2.404618)
				(mid 455.3758 -2.558068)
				(end 455.501756 -2.747264)
			)
			(xy 455.50963 -2.763012) (xy 455.54138 -2.777744)
		)
		(stroke
			(width 0)
			(type solid)
		)
		(fill yes)
		(layer "In2.Cu")
		(net "GND")
	)
	(gr_poly
		(pts
			(arc
				(start 7.548626 -137.9601)
				(mid 7.568149 -137.956199)
				(end 7.584694 -137.945114)
			)
			(arc
				(start 7.679944 -137.849864)
				(mid 7.691055 -137.83333)
				(end 7.69493 -137.813796)
			)
			(xy 7.69493 -135.794496) (xy 7.67461 -135.767572)
			(arc
				(start 7.6581 -135.762746)
				(mid 7.381151 -135.39597)
				(end 7.6581 -135.029194)
			)
			(xy 7.67461 -135.024368) (xy 7.69493 -134.997444)
			(arc
				(start 7.69493 -132.962396)
				(mid 7.691029 -132.942873)
				(end 7.679944 -132.926328)
			)
			(arc
				(start 7.584694 -132.831078)
				(mid 7.56816 -132.819967)
				(end 7.548626 -132.816092)
			)
			(arc
				(start 4.00177 -132.816092)
				(mid 3.982247 -132.819993)
				(end 3.965702 -132.831078)
			)
			(arc
				(start 3.870452 -132.926328)
				(mid 3.859341 -132.942862)
				(end 3.855466 -132.962396)
			)
			(arc
				(start 3.855466 -137.813796)
				(mid 3.859367 -137.833319)
				(end 3.870452 -137.849864)
			)
			(arc
				(start 3.965702 -137.945114)
				(mid 3.982236 -137.956225)
				(end 4.00177 -137.9601)
			)
		)
		(stroke
			(width 0)
			(type solid)
		)
		(fill yes)
		(layer "In2.Cu")
		(net "GND")
	)
	(gr_poly
		(pts
			(xy 400.068796 -322.802758)
			(arc
				(start 400.07032 -322.782692)
				(mid 400.230726 -322.446186)
				(end 400.577558 -322.30949)
			)
			(arc
				(start 400.577558 -322.30949)
				(mid 400.779434 -322.351279)
				(end 400.948144 -322.469764)
			)
			(xy 400.955256 -322.477384) (xy 400.97456 -322.485766) (xy 401.069556 -322.485766) (xy 401.08886 -322.477384)
			(arc
				(start 401.095972 -322.469764)
				(mid 401.264674 -322.351261)
				(end 401.466558 -322.30949)
			)
			(arc
				(start 401.466558 -322.30949)
				(mid 401.685708 -322.359164)
				(end 401.862036 -322.498466)
			)
			(xy 401.86864 -322.506594) (xy 401.887182 -322.516246) (xy 401.982178 -322.523358) (xy 402.00199 -322.5165)
			(arc
				(start 402.00961 -322.509388)
				(mid 402.168911 -322.410354)
				(end 402.353272 -322.375784)
			)
			(arc
				(start 402.353272 -322.375784)
				(mid 402.620272 -322.45152)
				(end 402.807678 -322.6562)
			)
			(xy 402.811996 -322.664582) (xy 402.825204 -322.676774) (xy 402.904706 -322.709032) (xy 402.92274 -322.70954)
			(arc
				(start 402.93163 -322.706492)
				(mid 402.992991 -322.690876)
				(end 403.05609 -322.685664)
			)
			(arc
				(start 403.05609 -322.685664)
				(mid 403.191383 -322.710477)
				(end 403.309074 -322.781676)
			)
			(xy 403.31644 -322.788026) (xy 403.334474 -322.79463)
			(arc
				(start 403.413976 -322.792344)
				(mid 403.432551 -322.788122)
				(end 403.448266 -322.777358)
			)
			(xy 403.574758 -322.650866) (xy 403.582632 -322.640706)
			(arc
				(start 403.5933 -322.623688)
				(mid 403.599403 -322.610439)
				(end 403.601428 -322.596002)
			)
			(arc
				(start 403.601428 -321.535806)
				(mid 403.586549 -321.499885)
				(end 403.550628 -321.485006)
			)
			(arc
				(start 398.77746 -321.485006)
				(mid 398.741539 -321.499885)
				(end 398.72666 -321.535806)
			)
			(arc
				(start 398.72666 -322.779136)
				(mid 398.741539 -322.815057)
				(end 398.77746 -322.829936)
			)
			(xy 400.03984 -322.829936)
		)
		(stroke
			(width 0)
			(type solid)
		)
		(fill yes)
		(layer "In2.Cu")
		(net "PVDD18_S5_P0")
	)
	(gr_poly
		(pts
			(xy 333.993236 -27.130248) (xy 334.003302 -27.129817) (xy 334.021892 -27.122087) (xy 334.029304 -27.115262)
			(xy 334.234282 -26.910284) (xy 334.241128 -26.902885) (xy 334.248859 -26.884287) (xy 334.249268 -26.874216)
			(xy 334.249268 -25.693878) (xy 334.24884 -25.68381) (xy 334.241117 -25.665215) (xy 334.234282 -25.65781)
			(xy 333.68996 -25.113234) (xy 333.682561 -25.10639) (xy 333.663962 -25.098665) (xy 333.653892 -25.098248)
			(xy 306.448206 -25.098248) (xy 306.438136 -25.097825) (xy 306.419535 -25.090106) (xy 306.412138 -25.083262)
			(xy 304.69459 -23.365714) (xy 304.687191 -23.358868) (xy 304.668593 -23.351135) (xy 304.658522 -23.350728)
			(xy 303.611026 -23.350728) (xy 303.600962 -23.351165) (xy 303.58238 -23.358902) (xy 303.574958 -23.365714)
			(xy 303.188624 -23.752048) (xy 303.181782 -23.759448) (xy 303.174062 -23.778046) (xy 303.173638 -23.788116)
			(xy 303.173638 -24.696928) (xy 303.174067 -24.706995) (xy 303.181793 -24.725589) (xy 303.188624 -24.732996)
			(xy 304.077878 -25.62225) (xy 304.549554 -25.62225) (xy 304.553625 -25.566628) (xy 304.565751 -25.512191)
			(xy 304.585674 -25.4601) (xy 304.61297 -25.411465) (xy 304.647056 -25.367322) (xy 304.687205 -25.328613)
			(xy 304.732563 -25.296162) (xy 304.782163 -25.270661) (xy 304.834947 -25.252654) (xy 304.88979 -25.242524)
			(xy 304.945524 -25.240487) (xy 305.000961 -25.246587) (xy 305.054918 -25.260693) (xy 305.106247 -25.282505)
			(xy 305.153853 -25.311559) (xy 305.196721 -25.347234) (xy 305.233938 -25.388771) (xy 305.264711 -25.435284)
			(xy 305.288383 -25.485781) (xy 305.304451 -25.539188) (xy 305.312571 -25.594364) (xy 305.31308 -25.62225)
			(xy 305.312571 -25.650136) (xy 305.308264 -25.6794) (xy 318.658238 -25.6794) (xy 318.662309 -25.623778)
			(xy 318.674435 -25.569341) (xy 318.694358 -25.51725) (xy 318.721654 -25.468615) (xy 318.75574 -25.424472)
			(xy 318.795889 -25.385763) (xy 318.841247 -25.353312) (xy 318.890847 -25.327811) (xy 318.943631 -25.309804)
			(xy 318.998474 -25.299674) (xy 319.054208 -25.297637) (xy 319.109645 -25.303737) (xy 319.163602 -25.317843)
			(xy 319.214931 -25.339655) (xy 319.262537 -25.368709) (xy 319.305405 -25.404384) (xy 319.342622 -25.445921)
			(xy 319.373395 -25.492434) (xy 319.397067 -25.542931) (xy 319.413135 -25.596338) (xy 319.421255 -25.651514)
			(xy 319.421764 -25.6794) (xy 319.421255 -25.707286) (xy 319.413135 -25.762462) (xy 319.397067 -25.815869)
			(xy 319.373395 -25.866366) (xy 319.342622 -25.912879) (xy 319.305405 -25.954416) (xy 319.262537 -25.990091)
			(xy 319.214931 -26.019145) (xy 319.163602 -26.040957) (xy 319.109645 -26.055063) (xy 319.054208 -26.061163)
			(xy 318.998474 -26.059126) (xy 318.943631 -26.048996) (xy 318.890847 -26.030989) (xy 318.841247 -26.005488)
			(xy 318.795889 -25.973037) (xy 318.75574 -25.934328) (xy 318.721654 -25.890185) (xy 318.694358 -25.84155)
			(xy 318.674435 -25.789459) (xy 318.662309 -25.735022) (xy 318.658238 -25.6794) (xy 305.308264 -25.6794)
			(xy 305.304451 -25.705312) (xy 305.288383 -25.758719) (xy 305.264711 -25.809216) (xy 305.233938 -25.855729)
			(xy 305.196721 -25.897266) (xy 305.153853 -25.932941) (xy 305.106247 -25.961995) (xy 305.054918 -25.983807)
			(xy 305.000961 -25.997913) (xy 304.945524 -26.004013) (xy 304.88979 -26.001976) (xy 304.834947 -25.991846)
			(xy 304.782163 -25.973839) (xy 304.732563 -25.948338) (xy 304.687205 -25.915887) (xy 304.647056 -25.877178)
			(xy 304.61297 -25.833035) (xy 304.585674 -25.7844) (xy 304.565751 -25.732309) (xy 304.553625 -25.677872)
			(xy 304.549554 -25.62225) (xy 304.077878 -25.62225) (xy 305.275742 -26.820114) (xy 305.307585 -26.852361)
			(xy 305.376111 -26.911679) (xy 305.449647 -26.964657) (xy 305.527611 -27.010876) (xy 305.60938 -27.049966)
			(xy 305.694307 -27.081618) (xy 305.781715 -27.10558) (xy 305.87091 -27.121661) (xy 305.961183 -27.129734)
			(xy 306.0065 -27.130248)
		)
		(stroke
			(width 0)
			(type solid)
		)
		(fill yes)
		(layer "In2.Cu")
		(net "P1V5_BAT")
	)
	(gr_poly
		(pts
			(arc
				(start 124.102114 -12.795504)
				(mid 125.962166 -12.153421)
				(end 127.029972 -10.500614)
			)
			(xy 127.031496 -10.488422)
			(arc
				(start 127.031496 -9.830816)
				(mid 127.045732 -9.759718)
				(end 127.086106 -9.699498)
			)
			(arc
				(start 127.102616 -9.682734)
				(mid 127.113493 -9.666406)
				(end 127.117348 -9.647174)
			)
			(arc
				(start 127.117348 -9.256776)
				(mid 127.111697 -9.233491)
				(end 127.096012 -9.215374)
			)
			(arc
				(start 127.096012 -9.215374)
				(mid 126.928345 -9.062058)
				(end 126.802388 -8.872982)
			)
			(xy 126.794514 -8.857234) (xy 126.76251 -8.842248)
			(arc
				(start 126.649226 -8.869426)
				(mid 126.621087 -8.887272)
				(end 126.61011 -8.918702)
			)
			(arc
				(start 126.61011 -9.780016)
				(mid 125.875535 -11.553437)
				(end 124.102114 -12.288012)
			)
			(arc
				(start 83.70189 -12.288012)
				(mid 81.928469 -11.553437)
				(end 81.193894 -9.780016)
			)
			(arc
				(start 81.193894 -3.638804)
				(mid 81.182847 -3.607429)
				(end 81.154778 -3.589528)
			)
			(xy 81.041494 -3.56235) (xy 81.00949 -3.577336)
			(arc
				(start 81.001616 -3.593084)
				(mid 80.87562 -3.782127)
				(end 80.707992 -3.935476)
			)
			(arc
				(start 80.707992 -3.935476)
				(mid 80.692292 -3.953586)
				(end 80.686656 -3.976878)
			)
			(arc
				(start 80.686656 -9.780524)
				(mid 81.569887 -11.912452)
				(end 83.70189 -12.795504)
			)
		)
		(stroke
			(width 0)
			(type solid)
		)
		(fill yes)
		(layer "In2.Cu")
		(net "GND")
	)
	(gr_poly
		(pts
			(xy 363.869478 -19.11604) (xy 363.879541 -19.115601) (xy 363.898119 -19.10786) (xy 363.905546 -19.101054)
			(xy 366.722914 -16.283686) (xy 366.729768 -16.276291) (xy 366.73751 -16.257692) (xy 366.7379 -16.247618)
			(xy 366.7379 -13.254482) (xy 366.737473 -13.244413) (xy 366.729754 -13.225814) (xy 366.722914 -13.218414)
			(xy 366.615726 -13.111226) (xy 366.608325 -13.104388) (xy 366.589726 -13.096677) (xy 366.579658 -13.09624)
			(xy 365.151162 -13.09624) (xy 365.141096 -13.096671) (xy 365.122505 -13.1044) (xy 365.115094 -13.111226)
			(xy 365.007906 -13.218414) (xy 365.001061 -13.225813) (xy 364.993331 -13.244411) (xy 364.99292 -13.254482)
			(xy 364.99292 -13.639546) (xy 365.667796 -13.639546) (xy 365.671867 -13.583924) (xy 365.683993 -13.529487)
			(xy 365.703916 -13.477396) (xy 365.731212 -13.428761) (xy 365.765298 -13.384618) (xy 365.805447 -13.345909)
			(xy 365.850805 -13.313458) (xy 365.900405 -13.287957) (xy 365.953189 -13.26995) (xy 366.008032 -13.25982)
			(xy 366.063766 -13.257783) (xy 366.119203 -13.263883) (xy 366.17316 -13.277989) (xy 366.224489 -13.299801)
			(xy 366.272095 -13.328855) (xy 366.314963 -13.36453) (xy 366.35218 -13.406067) (xy 366.382953 -13.45258)
			(xy 366.406625 -13.503077) (xy 366.422693 -13.556484) (xy 366.430813 -13.61166) (xy 366.431322 -13.639546)
			(xy 366.430813 -13.667432) (xy 366.422693 -13.722608) (xy 366.406625 -13.776015) (xy 366.382953 -13.826512)
			(xy 366.35218 -13.873025) (xy 366.314963 -13.914562) (xy 366.272095 -13.950237) (xy 366.224489 -13.979291)
			(xy 366.17316 -14.001103) (xy 366.119203 -14.015209) (xy 366.063766 -14.021309) (xy 366.008032 -14.019272)
			(xy 365.953189 -14.009142) (xy 365.900405 -13.991135) (xy 365.850805 -13.965634) (xy 365.805447 -13.933183)
			(xy 365.765298 -13.894474) (xy 365.731212 -13.850331) (xy 365.703916 -13.801696) (xy 365.683993 -13.749605)
			(xy 365.671867 -13.695168) (xy 365.667796 -13.639546) (xy 364.99292 -13.639546) (xy 364.99292 -14.177518)
			(xy 364.992494 -14.187587) (xy 364.984777 -14.206189) (xy 364.977934 -14.213586) (xy 363.946186 -15.245334)
			(xy 363.943138 -15.282418) (xy 363.95406 -15.297658) (xy 363.972068 -15.323625) (xy 364.002208 -15.379166)
			(xy 364.025228 -15.438016) (xy 364.040772 -15.499266) (xy 364.0486 -15.561972) (xy 364.049056 -15.593568)
			(xy 364.048594 -15.624301) (xy 364.041189 -15.68532) (xy 364.026483 -15.745002) (xy 364.004691 -15.802476)
			(xy 363.97613 -15.856904) (xy 363.941217 -15.907492) (xy 363.900461 -15.953504) (xy 363.854455 -15.994267)
			(xy 363.803872 -16.029189) (xy 363.749449 -16.057758) (xy 363.691978 -16.07956) (xy 363.632299 -16.094275)
			(xy 363.571281 -16.101689) (xy 363.540548 -16.102076) (xy 363.508954 -16.101594) (xy 363.446253 -16.093758)
			(xy 363.385006 -16.078213) (xy 363.326158 -16.055199) (xy 363.270614 -16.025071) (xy 363.244638 -16.00708)
			(xy 363.229398 -15.996158) (xy 363.192314 -15.999206) (xy 363.077506 -16.114014) (xy 363.070112 -16.120871)
			(xy 363.051513 -16.128621) (xy 363.041438 -16.129) (xy 349.616522 -16.129) (xy 349.606458 -16.128562)
			(xy 349.587874 -16.120828) (xy 349.580454 -16.114014) (xy 349.518986 -16.052546) (xy 349.511589 -16.045697)
			(xy 349.49299 -16.03796) (xy 349.482918 -16.03756) (xy 343.779602 -16.03756) (xy 343.769533 -16.037984)
			(xy 343.750934 -16.045705) (xy 343.743534 -16.052546) (xy 343.359486 -16.436594) (xy 343.352629 -16.443988)
			(xy 343.344879 -16.462587) (xy 343.3445 -16.472662) (xy 343.3445 -17.085056) (xy 345.451682 -17.085056)
			(xy 345.455753 -17.029434) (xy 345.467879 -16.974997) (xy 345.487802 -16.922906) (xy 345.515098 -16.874271)
			(xy 345.549184 -16.830128) (xy 345.589333 -16.791419) (xy 345.634691 -16.758968) (xy 345.684291 -16.733467)
			(xy 345.737075 -16.71546) (xy 345.791918 -16.70533) (xy 345.847652 -16.703293) (xy 345.903089 -16.709393)
			(xy 345.957046 -16.723499) (xy 346.008375 -16.745311) (xy 346.055981 -16.774365) (xy 346.098849 -16.81004)
			(xy 346.136066 -16.851577) (xy 346.166839 -16.89809) (xy 346.190511 -16.948587) (xy 346.206579 -17.001994)
			(xy 346.214699 -17.05717) (xy 346.215208 -17.085056) (xy 346.214699 -17.112942) (xy 346.206579 -17.168118)
			(xy 346.190511 -17.221525) (xy 346.166839 -17.272022) (xy 346.136066 -17.318535) (xy 346.098849 -17.360072)
			(xy 346.055981 -17.395747) (xy 346.008375 -17.424801) (xy 345.957046 -17.446613) (xy 345.903089 -17.460719)
			(xy 345.847652 -17.466819) (xy 345.791918 -17.464782) (xy 345.737075 -17.454652) (xy 345.684291 -17.436645)
			(xy 345.634691 -17.411144) (xy 345.589333 -17.378693) (xy 345.549184 -17.339984) (xy 345.515098 -17.295841)
			(xy 345.487802 -17.247206) (xy 345.467879 -17.195115) (xy 345.455753 -17.140678) (xy 345.451682 -17.085056)
			(xy 343.3445 -17.085056) (xy 343.3445 -17.672558) (xy 343.344934 -17.682623) (xy 343.352663 -17.701213)
			(xy 343.359486 -17.708626) (xy 344.751914 -19.101054) (xy 344.759311 -19.107903) (xy 344.77791 -19.11564)
			(xy 344.787982 -19.11604)
		)
		(stroke
			(width 0)
			(type solid)
		)
		(fill yes)
		(layer "In2.Cu")
		(net "P5V_AUX")
	)
	(gr_poly
		(pts
			(arc
				(start 467.792054 -82.82813)
				(mid 467.983012 -81.868498)
				(end 468.526622 -81.054956)
			)
			(arc
				(start 470.85504 -78.726538)
				(mid 471.178373 -78.242681)
				(end 471.29192 -77.67193)
			)
			(arc
				(start 471.29192 -13.780008)
				(mid 470.854924 -12.725008)
				(end 469.799924 -12.288012)
			)
			(arc
				(start 458.20203 -12.288012)
				(mid 456.428609 -11.553437)
				(end 455.694034 -9.780016)
			)
			(arc
				(start 455.694034 -3.638042)
				(mid 455.682987 -3.606667)
				(end 455.654918 -3.588766)
			)
			(xy 455.541634 -3.561842) (xy 455.50963 -3.576828)
			(arc
				(start 455.501756 -3.592576)
				(mid 455.375805 -3.781776)
				(end 455.208132 -3.935222)
			)
			(arc
				(start 455.208132 -3.935222)
				(mid 455.192432 -3.953332)
				(end 455.186796 -3.976624)
			)
			(arc
				(start 455.186796 -9.780524)
				(mid 456.070027 -11.912452)
				(end 458.20203 -12.795504)
			)
			(arc
				(start 469.799924 -12.795504)
				(mid 470.496073 -13.083859)
				(end 470.784428 -13.780008)
			)
			(arc
				(start 470.784428 -77.672184)
				(mid 470.70959 -78.048688)
				(end 470.496392 -78.36789)
			)
			(arc
				(start 468.167974 -80.696308)
				(mid 467.514407 -81.674395)
				(end 467.284816 -82.82813)
			)
			(arc
				(start 467.284816 -357.040688)
				(mid 467.554494 -357.44994)
				(end 467.792054 -357.878634)
			)
		)
		(stroke
			(width 0)
			(type solid)
		)
		(fill yes)
		(layer "In2.Cu")
		(net "GND")
	)
	(gr_poly
		(pts
			(xy 154.429206 -40.572182) (xy 154.439275 -40.571757) (xy 154.457877 -40.564039) (xy 154.465274 -40.557196)
			(xy 154.816048 -40.206422) (xy 154.822888 -40.199022) (xy 154.830602 -40.180423) (xy 154.831034 -40.170354)
			(xy 154.831034 -37.456872) (xy 154.830604 -37.446805) (xy 154.822875 -37.428215) (xy 154.816048 -37.420804)
			(xy 154.577288 -37.182044) (xy 154.569891 -37.175195) (xy 154.551292 -37.167458) (xy 154.54122 -37.167058)
			(xy 154.255724 -37.167058) (xy 154.247029 -37.16742) (xy 154.230644 -37.173251) (xy 154.217146 -37.184219)
			(xy 154.21229 -37.191442) (xy 154.197324 -37.21497) (xy 154.161644 -37.257819) (xy 154.120106 -37.295019)
			(xy 154.073596 -37.325776) (xy 154.023105 -37.349436) (xy 153.969708 -37.365495) (xy 153.914542 -37.373611)
			(xy 153.858782 -37.373611) (xy 153.803616 -37.365495) (xy 153.750219 -37.349436) (xy 153.699728 -37.325776)
			(xy 153.653218 -37.295019) (xy 153.61168 -37.257819) (xy 153.576 -37.21497) (xy 153.561034 -37.191442)
			(xy 153.55621 -37.184193) (xy 153.542704 -37.173222) (xy 153.526301 -37.167417) (xy 153.5176 -37.167058)
			(xy 151.559006 -37.167058) (xy 151.548937 -37.167482) (xy 151.530336 -37.175201) (xy 151.522938 -37.182044)
			(xy 151.328882 -37.3761) (xy 151.322027 -37.383495) (xy 151.314279 -37.402094) (xy 151.313896 -37.412168)
			(xy 151.313896 -37.75456) (xy 151.451308 -37.75456) (xy 151.455379 -37.698938) (xy 151.467505 -37.644501)
			(xy 151.487428 -37.59241) (xy 151.514724 -37.543775) (xy 151.54881 -37.499632) (xy 151.588959 -37.460923)
			(xy 151.634317 -37.428472) (xy 151.683917 -37.402971) (xy 151.736701 -37.384964) (xy 151.791544 -37.374834)
			(xy 151.847278 -37.372797) (xy 151.902715 -37.378897) (xy 151.956672 -37.393003) (xy 152.008001 -37.414815)
			(xy 152.055607 -37.443869) (xy 152.098475 -37.479544) (xy 152.135692 -37.521081) (xy 152.166465 -37.567594)
			(xy 152.190137 -37.618091) (xy 152.206205 -37.671498) (xy 152.214325 -37.726674) (xy 152.214834 -37.75456)
			(xy 152.214325 -37.782446) (xy 152.206205 -37.837622) (xy 152.190137 -37.891029) (xy 152.166465 -37.941526)
			(xy 152.135692 -37.988039) (xy 152.098475 -38.029576) (xy 152.055607 -38.065251) (xy 152.008001 -38.094305)
			(xy 151.956672 -38.116117) (xy 151.902715 -38.130223) (xy 151.847278 -38.136323) (xy 151.791544 -38.134286)
			(xy 151.736701 -38.124156) (xy 151.683917 -38.106149) (xy 151.634317 -38.080648) (xy 151.588959 -38.048197)
			(xy 151.54881 -38.009488) (xy 151.514724 -37.965345) (xy 151.487428 -37.91671) (xy 151.467505 -37.864619)
			(xy 151.455379 -37.810182) (xy 151.451308 -37.75456) (xy 151.313896 -37.75456) (xy 151.313896 -39.02456)
			(xy 151.451308 -39.02456) (xy 151.455379 -38.968938) (xy 151.467505 -38.914501) (xy 151.487428 -38.86241)
			(xy 151.514724 -38.813775) (xy 151.54881 -38.769632) (xy 151.588959 -38.730923) (xy 151.634317 -38.698472)
			(xy 151.683917 -38.672971) (xy 151.736701 -38.654964) (xy 151.791544 -38.644834) (xy 151.847278 -38.642797)
			(xy 151.902715 -38.648897) (xy 151.956672 -38.663003) (xy 152.008001 -38.684815) (xy 152.055607 -38.713869)
			(xy 152.098475 -38.749544) (xy 152.135692 -38.791081) (xy 152.166465 -38.837594) (xy 152.190137 -38.888091)
			(xy 152.206205 -38.941498) (xy 152.214325 -38.996674) (xy 152.214834 -39.02456) (xy 152.214325 -39.052446)
			(xy 152.206205 -39.107622) (xy 152.190137 -39.161029) (xy 152.166465 -39.211526) (xy 152.135692 -39.258039)
			(xy 152.098475 -39.299576) (xy 152.055607 -39.335251) (xy 152.008001 -39.364305) (xy 151.956672 -39.386117)
			(xy 151.902715 -39.400223) (xy 151.874987 -39.403274) (xy 153.504644 -39.403274) (xy 153.508715 -39.347652)
			(xy 153.520841 -39.293215) (xy 153.540764 -39.241124) (xy 153.56806 -39.192489) (xy 153.602146 -39.148346)
			(xy 153.642295 -39.109637) (xy 153.687653 -39.077186) (xy 153.737253 -39.051685) (xy 153.790037 -39.033678)
			(xy 153.84488 -39.023548) (xy 153.900614 -39.021511) (xy 153.956051 -39.027611) (xy 154.010008 -39.041717)
			(xy 154.061337 -39.063529) (xy 154.108943 -39.092583) (xy 154.151811 -39.128258) (xy 154.189028 -39.169795)
			(xy 154.219801 -39.216308) (xy 154.243473 -39.266805) (xy 154.259541 -39.320212) (xy 154.267661 -39.375388)
			(xy 154.26817 -39.403274) (xy 154.267661 -39.43116) (xy 154.259541 -39.486336) (xy 154.243473 -39.539743)
			(xy 154.219801 -39.59024) (xy 154.189028 -39.636753) (xy 154.151811 -39.67829) (xy 154.108943 -39.713965)
			(xy 154.061337 -39.743019) (xy 154.010008 -39.764831) (xy 153.956051 -39.778937) (xy 153.900614 -39.785037)
			(xy 153.84488 -39.783) (xy 153.790037 -39.77287) (xy 153.737253 -39.754863) (xy 153.687653 -39.729362)
			(xy 153.642295 -39.696911) (xy 153.602146 -39.658202) (xy 153.56806 -39.614059) (xy 153.540764 -39.565424)
			(xy 153.520841 -39.513333) (xy 153.508715 -39.458896) (xy 153.504644 -39.403274) (xy 151.874987 -39.403274)
			(xy 151.847278 -39.406323) (xy 151.791544 -39.404286) (xy 151.736701 -39.394156) (xy 151.683917 -39.376149)
			(xy 151.634317 -39.350648) (xy 151.588959 -39.318197) (xy 151.54881 -39.279488) (xy 151.514724 -39.235345)
			(xy 151.487428 -39.18671) (xy 151.467505 -39.134619) (xy 151.455379 -39.080182) (xy 151.451308 -39.02456)
			(xy 151.313896 -39.02456) (xy 151.313896 -40.349424) (xy 151.314324 -40.359492) (xy 151.322044 -40.378091)
			(xy 151.328882 -40.385492) (xy 151.500586 -40.557196) (xy 151.507989 -40.564029) (xy 151.526587 -40.571733)
			(xy 151.536654 -40.572182)
		)
		(stroke
			(width 0)
			(type solid)
		)
		(fill yes)
		(layer "In2.Cu")
		(net "P3V3_OCP_V3_2")
	)
	(gr_poly
		(pts
			(arc
				(start 453.286114 -30.026102)
				(mid 453.305305 -30.022337)
				(end 453.321674 -30.011624)
			)
			(xy 453.321928 -30.01137) (xy 454.64603 -28.687268)
			(arc
				(start 454.646538 -28.68676)
				(mid 454.65728 -28.670403)
				(end 454.661016 -28.6512)
			)
			(xy 454.661016 -23.692358) (xy 454.653396 -23.673562) (xy 454.64603 -23.66645)
			(arc
				(start 454.288906 -23.309326)
				(mid 454.272372 -23.298215)
				(end 454.252838 -23.29434)
			)
			(xy 452.604886 -23.29434)
			(arc
				(start 452.601584 -23.294848)
				(mid 452.545182 -23.300205)
				(end 452.488554 -23.30196)
			)
			(arc
				(start 452.488554 -23.30196)
				(mid 452.000393 -23.15599)
				(end 451.672452 -22.76602)
			)
			(arc
				(start 451.672452 -22.76602)
				(mid 451.653637 -22.743819)
				(end 451.625716 -22.73554)
			)
			(arc
				(start 451.362064 -22.73554)
				(mid 451.333545 -22.744301)
				(end 451.31482 -22.767544)
			)
			(arc
				(start 451.31482 -22.767544)
				(mid 450.987656 -23.174407)
				(end 450.488558 -23.327614)
			)
			(arc
				(start 450.488558 -23.327614)
				(mid 450.150219 -23.260776)
				(end 449.862702 -23.070312)
			)
			(xy 449.847716 -23.05558) (xy 449.80606 -23.05558)
			(arc
				(start 449.537074 -23.324566)
				(mid 449.522313 -23.36038)
				(end 449.537074 -23.396194)
			)
			(xy 449.54444 -23.40356)
			(arc
				(start 449.54825 -23.412704)
				(mid 449.551099 -23.42217)
				(end 449.55206 -23.432008)
			)
			(arc
				(start 449.55206 -24.025098)
				(mid 449.548159 -24.044621)
				(end 449.537074 -24.061166)
			)
			(arc
				(start 449.422266 -24.175974)
				(mid 449.405732 -24.187085)
				(end 449.386198 -24.19096)
			)
			(xy 446.675002 -24.19096) (xy 446.656206 -24.19858) (xy 446.649094 -24.205946)
			(arc
				(start 446.348866 -24.506174)
				(mid 446.337755 -24.522708)
				(end 446.33388 -24.542242)
			)
			(arc
				(start 446.33388 -26.033476)
				(mid 446.329979 -26.052999)
				(end 446.318894 -26.069544)
			)
			(arc
				(start 445.890904 -26.497534)
				(mid 445.87437 -26.508645)
				(end 445.854836 -26.51252)
			)
			(arc
				(start 444.927736 -26.51252)
				(mid 444.908349 -26.51647)
				(end 444.891922 -26.527506)
			)
			(arc
				(start 444.760604 -26.658824)
				(mid 444.538564 -26.806523)
				(end 444.276988 -26.858468)
			)
			(xy 443.062614 -26.858468)
			(arc
				(start 443.058296 -26.858976)
				(mid 442.98326 -26.868648)
				(end 442.907674 -26.87193)
			)
			(arc
				(start 442.907674 -26.87193)
				(mid 442.832086 -26.868669)
				(end 442.757052 -26.858976)
			)
			(xy 442.752734 -26.858468) (xy 442.173614 -26.858468)
			(arc
				(start 442.169296 -26.858976)
				(mid 442.09426 -26.868648)
				(end 442.018674 -26.87193)
			)
			(arc
				(start 442.018674 -26.87193)
				(mid 441.943086 -26.868669)
				(end 441.868052 -26.858976)
			)
			(xy 441.863734 -26.858468) (xy 441.284614 -26.858468)
			(arc
				(start 441.280296 -26.858976)
				(mid 441.20526 -26.868648)
				(end 441.129674 -26.87193)
			)
			(arc
				(start 441.129674 -26.87193)
				(mid 441.054086 -26.868669)
				(end 440.979052 -26.858976)
			)
			(xy 440.974734 -26.858468)
			(arc
				(start 440.764676 -26.858468)
				(mid 440.432235 -26.772578)
				(end 440.183016 -26.536396)
			)
			(arc
				(start 440.183016 -26.536396)
				(mid 440.164639 -26.518888)
				(end 440.14009 -26.51252)
			)
			(arc
				(start 438.858914 -26.51252)
				(mid 438.845039 -26.514452)
				(end 438.832244 -26.52014)
			)
			(arc
				(start 438.832244 -26.52014)
				(mid 438.63133 -26.577286)
				(end 438.430416 -26.52014)
			)
			(arc
				(start 438.430416 -26.52014)
				(mid 438.417608 -26.514497)
				(end 438.403746 -26.51252)
			)
			(arc
				(start 438.214262 -26.51252)
				(mid 438.194739 -26.508619)
				(end 438.178194 -26.497534)
			)
			(arc
				(start 437.906922 -26.226262)
				(mid 437.895811 -26.209728)
				(end 437.891936 -26.190194)
			)
			(arc
				(start 437.891936 -24.433784)
				(mid 437.895837 -24.414261)
				(end 437.906922 -24.397716)
			)
			(arc
				(start 438.08015 -24.224488)
				(mid 438.096684 -24.213377)
				(end 438.116218 -24.209502)
			)
			(arc
				(start 438.937654 -24.209502)
				(mid 438.956845 -24.205737)
				(end 438.973214 -24.195024)
			)
			(xy 438.973468 -24.19477) (xy 439.01995 -24.148288)
			(arc
				(start 439.020458 -24.14778)
				(mid 439.0312 -24.131423)
				(end 439.034936 -24.11222)
			)
			(xy 439.034936 -23.382224) (xy 439.027316 -23.363428) (xy 439.01995 -23.356316)
			(arc
				(start 438.922922 -23.259288)
				(mid 438.906388 -23.248177)
				(end 438.886854 -23.244302)
			)
			(xy 437.674258 -23.244302) (xy 437.655462 -23.251922) (xy 437.64835 -23.259288)
			(arc
				(start 437.195722 -23.711916)
				(mid 437.184611 -23.72845)
				(end 437.180736 -23.747984)
			)
			(arc
				(start 437.180736 -26.160476)
				(mid 437.179774 -26.170314)
				(end 437.176926 -26.17978)
			)
			(arc
				(start 437.17083 -26.194512)
				(mid 437.167981 -26.203978)
				(end 437.16702 -26.213816)
			)
			(arc
				(start 437.16702 -27.76093)
				(mid 437.175627 -27.788969)
				(end 437.198262 -27.807666)
			)
			(arc
				(start 437.198262 -27.807666)
				(mid 437.423085 -27.943016)
				(end 437.598566 -28.13812)
			)
			(arc
				(start 437.598566 -28.13812)
				(mid 437.616893 -28.154896)
				(end 437.640984 -28.16098)
			)
			(arc
				(start 438.414414 -28.16098)
				(mid 438.436723 -28.155819)
				(end 438.454546 -28.141422)
			)
			(arc
				(start 438.454546 -28.141422)
				(mid 439.15711 -27.797482)
				(end 439.859674 -28.141422)
			)
			(xy 439.866786 -28.15082) (xy 439.887868 -28.16098)
			(arc
				(start 439.917332 -28.16098)
				(mid 439.936855 -28.164881)
				(end 439.9534 -28.175966)
			)
			(xy 440.64555 -28.868116)
			(arc
				(start 440.646058 -28.868624)
				(mid 440.662415 -28.879366)
				(end 440.681618 -28.883102)
			)
			(arc
				(start 445.131698 -28.883102)
				(mid 445.151221 -28.887003)
				(end 445.167766 -28.898088)
			)
			(xy 446.280794 -30.011116)
			(arc
				(start 446.281302 -30.011624)
				(mid 446.297659 -30.022366)
				(end 446.316862 -30.026102)
			)
		)
		(stroke
			(width 0)
			(type solid)
		)
		(fill yes)
		(layer "In2.Cu")
		(net "P12V_AUX")
	)
	(gr_poly
		(pts
			(arc
				(start 289.935412 -422.202102)
				(mid 289.954935 -422.198201)
				(end 289.97148 -422.187116)
			)
			(xy 290.82238 -421.336216) (xy 290.829746 -421.313356)
			(arc
				(start 290.827968 -421.301418)
				(mid 290.824731 -421.272797)
				(end 290.82365 -421.244014)
			)
			(arc
				(start 290.82365 -421.244014)
				(mid 290.854773 -421.092833)
				(end 290.943284 -420.966392)
			)
			(arc
				(start 290.943284 -420.966392)
				(mid 290.955103 -420.94963)
				(end 290.959286 -420.929562)
			)
			(arc
				(start 290.959286 -420.833296)
				(mid 290.955315 -420.813607)
				(end 290.944046 -420.796974)
			)
			(arc
				(start 290.944046 -420.796974)
				(mid 290.859299 -420.67225)
				(end 290.829492 -420.524432)
			)
			(arc
				(start 290.829492 -419.660832)
				(mid 290.859293 -419.513012)
				(end 290.944046 -419.38829)
			)
			(xy 290.951412 -419.381178) (xy 290.959286 -419.362382)
			(arc
				(start 290.959286 -419.301676)
				(mid 290.953797 -419.278708)
				(end 290.938458 -419.260782)
			)
			(arc
				(start 290.938458 -419.260782)
				(mid 290.871759 -419.198091)
				(end 290.821872 -419.121336)
			)
			(xy 290.81603 -419.109652) (xy 290.794948 -419.094666) (xy 290.683696 -419.082474) (xy 290.65982 -419.092126)
			(arc
				(start 290.651438 -419.10254)
				(mid 290.518996 -419.207404)
				(end 290.354258 -419.24478)
			)
			(arc
				(start 290.354258 -419.24478)
				(mid 290.084491 -419.133039)
				(end 289.97275 -418.863272)
			)
			(arc
				(start 289.97275 -418.863272)
				(mid 289.976195 -418.812137)
				(end 289.986466 -418.761926)
			)
			(xy 289.989768 -418.749734) (xy 289.984434 -418.725096) (xy 289.913314 -418.641784) (xy 289.889946 -418.63264)
			(arc
				(start 289.877246 -418.63391)
				(mid 289.856322 -418.635627)
				(end 289.835336 -418.636196)
			)
			(arc
				(start 289.835336 -418.636196)
				(mid 289.565569 -418.524455)
				(end 289.453828 -418.254688)
			)
			(arc
				(start 289.453828 -417.391088)
				(mid 289.522886 -417.172174)
				(end 289.705034 -417.03244)
			)
			(xy 289.717988 -417.027614) (xy 289.735514 -417.006786) (xy 289.755072 -416.89274) (xy 289.745674 -416.86734)
			(arc
				(start 289.735006 -416.85845)
				(mid 289.632732 -416.726912)
				(end 289.596322 -416.564318)
			)
			(arc
				(start 289.596322 -416.564318)
				(mid 289.97783 -416.18281)
				(end 290.359338 -416.564318)
			)
			(arc
				(start 290.359338 -416.564318)
				(mid 290.29028 -416.783232)
				(end 290.108132 -416.922966)
			)
			(xy 290.095178 -416.927538) (xy 290.077906 -416.948366) (xy 290.058094 -417.062412) (xy 290.067746 -417.088066)
			(arc
				(start 290.07816 -417.096702)
				(mid 290.180444 -417.228377)
				(end 290.216844 -417.391088)
			)
			(arc
				(start 290.216844 -418.254688)
				(mid 290.213399 -418.305823)
				(end 290.203128 -418.356034)
			)
			(xy 290.199826 -418.368226) (xy 290.205414 -418.392864) (xy 290.27628 -418.476176) (xy 290.299648 -418.485574)
			(arc
				(start 290.312348 -418.48405)
				(mid 290.333272 -418.482333)
				(end 290.354258 -418.481764)
			)
			(arc
				(start 290.354258 -418.481764)
				(mid 290.555987 -418.539461)
				(end 290.69665 -418.695124)
			)
			(xy 290.702492 -418.706808) (xy 290.723574 -418.721794) (xy 290.834826 -418.733986) (xy 290.858702 -418.724334)
			(arc
				(start 290.867084 -418.71392)
				(mid 290.90055 -418.677437)
				(end 290.938458 -418.645594)
			)
			(arc
				(start 290.938458 -418.645594)
				(mid 290.953709 -418.627624)
				(end 290.959286 -418.6047)
			)
			(arc
				(start 290.959286 -414.268666)
				(mid 290.955385 -414.249143)
				(end 290.9443 -414.232598)
			)
			(arc
				(start 289.68192 -412.970218)
				(mid 289.665386 -412.959107)
				(end 289.645852 -412.955232)
			)
			(arc
				(start 289.495738 -412.955232)
				(mid 289.480108 -412.957696)
				(end 289.46602 -412.964884)
			)
			(arc
				(start 289.46602 -412.964884)
				(mid 289.360174 -413.018404)
				(end 289.243008 -413.036766)
			)
			(arc
				(start 289.243008 -413.036766)
				(mid 289.125864 -413.018336)
				(end 289.019996 -412.964884)
			)
			(arc
				(start 289.019996 -412.964884)
				(mid 289.005895 -412.957737)
				(end 288.990278 -412.955232)
			)
			(arc
				(start 283.576776 -412.955232)
				(mid 283.557389 -412.959182)
				(end 283.540962 -412.970218)
			)
			(arc
				(start 282.6893 -413.82188)
				(mid 282.678374 -413.838326)
				(end 282.674568 -413.857694)
			)
			(arc
				(start 282.674568 -415.729166)
				(mid 282.678401 -415.748523)
				(end 282.6893 -415.76498)
			)
			(arc
				(start 282.827984 -415.903664)
				(mid 282.844518 -415.914775)
				(end 282.864052 -415.91865)
			)
			(arc
				(start 287.350708 -415.91865)
				(mid 287.370231 -415.922551)
				(end 287.386776 -415.933636)
			)
			(arc
				(start 287.95853 -416.50539)
				(mid 287.969641 -416.521924)
				(end 287.973516 -416.541458)
			)
			(arc
				(start 287.973516 -419.72992)
				(mid 287.969615 -419.749443)
				(end 287.95853 -419.765988)
			)
			(arc
				(start 287.409128 -420.31539)
				(mid 287.392594 -420.326501)
				(end 287.37306 -420.330376)
			)
			(arc
				(start 285.721806 -420.330376)
				(mid 285.702283 -420.334277)
				(end 285.685738 -420.345362)
			)
			(arc
				(start 285.292292 -420.738808)
				(mid 285.281181 -420.755342)
				(end 285.277306 -420.774876)
			)
			(arc
				(start 285.277306 -421.846756)
				(mid 285.281207 -421.866279)
				(end 285.292292 -421.882824)
			)
			(arc
				(start 285.502858 -422.09339)
				(mid 285.520602 -422.10483)
				(end 285.541466 -422.108122)
			)
			(xy 285.627572 -422.103804) (xy 285.646622 -422.094152)
			(arc
				(start 285.65348 -422.08577)
				(mid 285.785485 -421.982217)
				(end 285.949136 -421.945308)
			)
			(arc
				(start 286.812736 -421.945308)
				(mid 287.020688 -422.006916)
				(end 287.161478 -422.171876)
			)
			(xy 287.167574 -422.185846) (xy 287.19272 -422.202102)
		)
		(stroke
			(width 0)
			(type solid)
		)
		(fill yes)
		(layer "In2.Cu")
		(net "P3V3_9ZXL045_P0_VDD")
	)
	(gr_poly
		(pts
			(xy 370.294408 -147.643596) (xy 370.304436 -147.643148) (xy 370.322996 -147.635559) (xy 370.330476 -147.628864)
			(xy 371.455188 -146.504152) (xy 371.462842 -146.495523) (xy 371.470373 -146.473754) (xy 371.469666 -146.462242)
			(xy 371.459252 -146.37131) (xy 371.44706 -146.352006) (xy 371.4369 -146.34591) (xy 371.41924 -146.334583)
			(xy 371.386389 -146.308487) (xy 371.371368 -146.29384) (xy 371.005862 -145.928334) (xy 370.986073 -145.907731)
			(xy 370.952516 -145.861502) (xy 370.926595 -145.810598) (xy 370.908948 -145.756268) (xy 370.900008 -145.699848)
			(xy 370.899436 -145.671286) (xy 370.899436 -144.900142) (xy 370.899993 -144.871578) (xy 370.908921 -144.815152)
			(xy 370.926566 -144.760818) (xy 370.952491 -144.709911) (xy 370.986059 -144.663686) (xy 371.005862 -144.643094)
			(xy 371.385846 -144.26311) (xy 371.40645 -144.243322) (xy 371.452679 -144.209767) (xy 371.503584 -144.183848)
			(xy 371.557913 -144.1662) (xy 371.614332 -144.157258) (xy 371.642894 -144.156684) (xy 371.805454 -144.156684)
			(xy 371.812566 -144.154398) (xy 371.839013 -144.147054) (xy 371.893327 -144.139148) (xy 371.92077 -144.13865)
			(xy 371.921278 -144.13865) (xy 371.943063 -144.138959) (xy 371.986349 -144.143923) (xy 372.007638 -144.148556)
			(xy 372.441216 -144.148556) (xy 372.622572 -143.9672) (xy 372.622572 -139.565126) (xy 372.623117 -139.536549)
			(xy 372.632088 -139.480102) (xy 372.649782 -139.425755) (xy 372.675761 -139.374845) (xy 372.709388 -139.328629)
			(xy 372.729252 -139.308078) (xy 376.437652 -135.599424) (xy 376.444473 -135.592058) (xy 376.452207 -135.573549)
			(xy 376.452254 -135.553489) (xy 376.448828 -135.544052) (xy 376.442732 -135.529828) (xy 376.417586 -135.51281)
			(xy 375.711466 -135.51281) (xy 375.701482 -135.513354) (xy 375.683059 -135.521077) (xy 375.675652 -135.527796)
			(xy 375.363486 -135.839962) (xy 375.345785 -135.85704) (xy 375.30601 -135.885971) (xy 375.262196 -135.908317)
			(xy 375.215422 -135.923525) (xy 375.166844 -135.93122) (xy 375.142252 -135.931656) (xy 373.56288 -135.931656)
			(xy 373.53829 -135.931196) (xy 373.489717 -135.923496) (xy 373.442947 -135.908289) (xy 373.399133 -135.885949)
			(xy 373.359356 -135.857027) (xy 373.341646 -135.839962) (xy 373.244364 -135.74268) (xy 373.237005 -135.736039)
			(xy 373.218704 -135.728475) (xy 373.208804 -135.727948) (xy 372.096792 -135.727948) (xy 371.95252 -135.87222)
			(xy 371.95252 -136.29894) (xy 372.23446 -136.58088) (xy 372.23446 -137.027412) (xy 373.67032 -137.027412)
			(xy 373.674391 -136.97179) (xy 373.686517 -136.917353) (xy 373.70644 -136.865262) (xy 373.733736 -136.816627)
			(xy 373.767822 -136.772484) (xy 373.807971 -136.733775) (xy 373.853329 -136.701324) (xy 373.902929 -136.675823)
			(xy 373.955713 -136.657816) (xy 374.010556 -136.647686) (xy 374.06629 -136.645649) (xy 374.121727 -136.651749)
			(xy 374.175684 -136.665855) (xy 374.227013 -136.687667) (xy 374.274619 -136.716721) (xy 374.317487 -136.752396)
			(xy 374.354704 -136.793933) (xy 374.385477 -136.840446) (xy 374.409149 -136.890943) (xy 374.425217 -136.94435)
			(xy 374.433337 -136.999526) (xy 374.433846 -137.027412) (xy 374.433337 -137.055298) (xy 374.425217 -137.110474)
			(xy 374.409149 -137.163881) (xy 374.385477 -137.214378) (xy 374.354704 -137.260891) (xy 374.317487 -137.302428)
			(xy 374.274619 -137.338103) (xy 374.227013 -137.367157) (xy 374.175684 -137.388969) (xy 374.121727 -137.403075)
			(xy 374.06629 -137.409175) (xy 374.010556 -137.407138) (xy 373.955713 -137.397008) (xy 373.902929 -137.379001)
			(xy 373.853329 -137.3535) (xy 373.807971 -137.321049) (xy 373.767822 -137.28234) (xy 373.733736 -137.238197)
			(xy 373.70644 -137.189562) (xy 373.686517 -137.137471) (xy 373.674391 -137.083034) (xy 373.67032 -137.027412)
			(xy 372.23446 -137.027412) (xy 372.23446 -138.61288) (xy 372.03507 -138.81227) (xy 371.747288 -138.81227)
			(xy 371.73408 -138.812524) (xy 370.510308 -138.812524) (xy 370.50032 -138.813061) (xy 370.481888 -138.820775)
			(xy 370.474494 -138.82751) (xy 368.423698 -140.878306) (xy 368.32667 -140.975334) (xy 371.09273 -140.975334)
			(xy 371.093216 -140.948083) (xy 371.100972 -140.894135) (xy 371.116327 -140.84184) (xy 371.138969 -140.792263)
			(xy 371.168435 -140.746413) (xy 371.204126 -140.705222) (xy 371.245317 -140.669531) (xy 371.291167 -140.640065)
			(xy 371.340744 -140.617423) (xy 371.393039 -140.602068) (xy 371.446987 -140.594312) (xy 371.501489 -140.594312)
			(xy 371.555437 -140.602068) (xy 371.607732 -140.617423) (xy 371.657309 -140.640065) (xy 371.703159 -140.669531)
			(xy 371.74435 -140.705222) (xy 371.780041 -140.746413) (xy 371.809507 -140.792263) (xy 371.832149 -140.84184)
			(xy 371.847504 -140.894135) (xy 371.85526 -140.948083) (xy 371.855746 -140.975334) (xy 371.855239 -141.004699)
			(xy 371.846308 -141.062744) (xy 371.837966 -141.090904) (xy 371.834337 -141.103868) (xy 371.833141 -141.130748)
			(xy 371.839019 -141.157005) (xy 371.851561 -141.18081) (xy 371.869893 -141.200504) (xy 371.89274 -141.214717)
			(xy 371.918509 -141.222459) (xy 371.931946 -141.223238) (xy 371.958688 -141.224443) (xy 372.011468 -141.233379)
			(xy 372.062478 -141.24961) (xy 372.110717 -141.272817) (xy 372.155236 -141.302542) (xy 372.195159 -141.338202)
			(xy 372.229702 -141.379096) (xy 372.258186 -141.424419) (xy 372.28005 -141.473281) (xy 372.294866 -141.52472)
			(xy 372.30234 -141.577727) (xy 372.302786 -141.604492) (xy 372.3023 -141.631743) (xy 372.294544 -141.685691)
			(xy 372.279189 -141.737986) (xy 372.256547 -141.787563) (xy 372.227081 -141.833413) (xy 372.19139 -141.874604)
			(xy 372.150199 -141.910295) (xy 372.104349 -141.939761) (xy 372.054772 -141.962403) (xy 372.002477 -141.977758)
			(xy 371.948529 -141.985514) (xy 371.894027 -141.985514) (xy 371.840079 -141.977758) (xy 371.787784 -141.962403)
			(xy 371.738207 -141.939761) (xy 371.692357 -141.910295) (xy 371.651166 -141.874604) (xy 371.615475 -141.833413)
			(xy 371.586009 -141.787563) (xy 371.563367 -141.737986) (xy 371.548012 -141.685691) (xy 371.540256 -141.631743)
			(xy 371.53977 -141.604492) (xy 371.540286 -141.575128) (xy 371.549211 -141.517082) (xy 371.55755 -141.488922)
			(xy 371.561249 -141.475977) (xy 371.562429 -141.449089) (xy 371.556537 -141.422828) (xy 371.543983 -141.399022)
			(xy 371.52564 -141.379326) (xy 371.502786 -141.365112) (xy 371.477011 -141.357369) (xy 371.46357 -141.356588)
			(xy 371.436825 -141.355433) (xy 371.384046 -141.346486) (xy 371.333036 -141.330246) (xy 371.284799 -141.307032)
			(xy 371.240282 -141.277301) (xy 371.200361 -141.241636) (xy 371.165819 -141.200739) (xy 371.137336 -141.155413)
			(xy 371.115471 -141.106549) (xy 371.100655 -141.055108) (xy 371.093178 -141.0021) (xy 371.09273 -140.975334)
			(xy 368.32667 -140.975334) (xy 366.813846 -142.488158) (xy 371.53926 -142.488158) (xy 371.543331 -142.432536)
			(xy 371.555457 -142.378099) (xy 371.57538 -142.326008) (xy 371.602676 -142.277373) (xy 371.636762 -142.23323)
			(xy 371.676911 -142.194521) (xy 371.722269 -142.16207) (xy 371.771869 -142.136569) (xy 371.824653 -142.118562)
			(xy 371.879496 -142.108432) (xy 371.93523 -142.106395) (xy 371.990667 -142.112495) (xy 372.044624 -142.126601)
			(xy 372.095953 -142.148413) (xy 372.143559 -142.177467) (xy 372.186427 -142.213142) (xy 372.223644 -142.254679)
			(xy 372.254417 -142.301192) (xy 372.278089 -142.351689) (xy 372.294157 -142.405096) (xy 372.302277 -142.460272)
			(xy 372.302786 -142.488158) (xy 372.302277 -142.516044) (xy 372.294157 -142.57122) (xy 372.278089 -142.624627)
			(xy 372.254417 -142.675124) (xy 372.223644 -142.721637) (xy 372.186427 -142.763174) (xy 372.143559 -142.798849)
			(xy 372.095953 -142.827903) (xy 372.044624 -142.849715) (xy 371.990667 -142.863821) (xy 371.93523 -142.869921)
			(xy 371.879496 -142.867884) (xy 371.824653 -142.857754) (xy 371.771869 -142.839747) (xy 371.722269 -142.814246)
			(xy 371.676911 -142.781795) (xy 371.636762 -142.743086) (xy 371.602676 -142.698943) (xy 371.57538 -142.650308)
			(xy 371.555457 -142.598217) (xy 371.543331 -142.54378) (xy 371.53926 -142.488158) (xy 366.813846 -142.488158)
			(xy 366.649 -142.653004) (xy 366.649 -147.297902) (xy 366.97793 -147.626832) (xy 367.00333 -147.643596)
		)
		(stroke
			(width 0)
			(type solid)
		)
		(fill yes)
		(layer "In2.Cu")
		(net "GND")
	)
	(gr_poly
		(pts
			(arc
				(start 256.800604 -37.135308)
				(mid 258.932532 -36.252077)
				(end 259.815584 -34.120074)
			)
			(arc
				(start 259.815584 -13.780008)
				(mid 260.103939 -13.083859)
				(end 260.800088 -12.795504)
			)
			(arc
				(start 385.601972 -12.795504)
				(mid 387.734244 -11.912288)
				(end 388.61746 -9.780016)
			)
			(arc
				(start 388.61746 -3.976878)
				(mid 388.611809 -3.953593)
				(end 388.596124 -3.935476)
			)
			(arc
				(start 388.596124 -3.935476)
				(mid 388.428347 -3.782165)
				(end 388.302246 -3.593084)
			)
			(xy 388.294372 -3.577336) (xy 388.262368 -3.56235)
			(arc
				(start 388.149084 -3.589528)
				(mid 388.120945 -3.607374)
				(end 388.109968 -3.638804)
			)
			(arc
				(start 388.109968 -9.780016)
				(mid 387.375393 -11.553437)
				(end 385.601972 -12.288012)
			)
			(arc
				(start 260.800088 -12.288012)
				(mid 259.745088 -12.725008)
				(end 259.308092 -13.780008)
			)
			(arc
				(start 259.308092 -34.120074)
				(mid 258.573517 -35.893495)
				(end 256.800096 -36.62807)
			)
			(arc
				(start 225.300032 -36.62807)
				(mid 223.526611 -35.893495)
				(end 222.792036 -34.120074)
			)
			(arc
				(start 222.792036 -13.780008)
				(mid 222.35504 -12.725008)
				(end 221.30004 -12.288012)
			)
			(xy 197.117208 -12.288012) (xy 197.0405 -12.36472) (xy 197.0405 -12.716764) (xy 197.11924 -12.795504)
			(arc
				(start 221.30004 -12.795504)
				(mid 221.996189 -13.083859)
				(end 222.284544 -13.780008)
			)
			(arc
				(start 222.284544 -34.120074)
				(mid 223.16785 -36.252182)
				(end 225.300032 -37.135308)
			)
		)
		(stroke
			(width 0)
			(type solid)
		)
		(fill yes)
		(layer "In2.Cu")
		(net "GND")
	)
	(gr_poly
		(pts
			(xy 71.1454 -441.396628) (xy 71.1454 -441.25388) (xy 70.866 -440.97448) (xy 70.810882 -440.97448)
			(arc
				(start 70.803262 -440.976766)
				(mid 70.727582 -440.99441)
				(end 70.6501 -441.000388)
			)
			(arc
				(start 70.649592 -441.000388)
				(mid 70.572107 -440.994435)
				(end 70.49643 -440.976766)
			)
			(xy 70.48881 -440.97448) (xy 66.81089 -440.97448)
			(arc
				(start 66.80327 -440.976766)
				(mid 66.72759 -440.99441)
				(end 66.650108 -441.000388)
			)
			(arc
				(start 66.6496 -441.000388)
				(mid 66.572115 -440.994435)
				(end 66.496438 -440.976766)
			)
			(xy 66.488818 -440.97448) (xy 62.810898 -440.97448)
			(arc
				(start 62.803278 -440.976766)
				(mid 62.727598 -440.99441)
				(end 62.650116 -441.000388)
			)
			(arc
				(start 62.649608 -441.000388)
				(mid 62.572123 -440.994435)
				(end 62.496446 -440.976766)
			)
			(xy 62.488826 -440.97448) (xy 58.810906 -440.97448)
			(arc
				(start 58.803286 -440.976766)
				(mid 58.727606 -440.99441)
				(end 58.650124 -441.000388)
			)
			(arc
				(start 58.649616 -441.000388)
				(mid 58.572131 -440.994435)
				(end 58.496454 -440.976766)
			)
			(xy 58.488834 -440.97448)
			(arc
				(start 8.50011 -440.97448)
				(mid 7.803871 -440.686141)
				(end 7.515352 -439.989976)
			)
			(arc
				(start 7.515352 -409.528518)
				(mid 7.285694 -408.374511)
				(end 6.63194 -407.396188)
			)
			(arc
				(start 3.303778 -404.068026)
				(mid 3.090447 -403.748703)
				(end 3.015488 -403.372066)
			)
			(arc
				(start 3.015488 -81.32826)
				(mid 2.785816 -80.174473)
				(end 2.132076 -79.196438)
			)
			(arc
				(start 1.303528 -78.36789)
				(mid 1.090411 -78.048655)
				(end 1.015492 -77.672184)
			)
			(arc
				(start 1.015492 -13.780008)
				(mid 1.303847 -13.083859)
				(end 1.999996 -12.795504)
			)
			(arc
				(start 11.102086 -12.795504)
				(mid 13.234194 -11.912198)
				(end 14.11732 -9.780016)
			)
			(xy 14.11732 -3.976878)
			(arc
				(start 14.095984 -3.935476)
				(mid 13.928317 -3.78216)
				(end 13.80236 -3.593084)
			)
			(xy 13.794486 -3.577336) (xy 13.762482 -3.56235)
			(arc
				(start 13.649198 -3.589274)
				(mid 13.621059 -3.60712)
				(end 13.610082 -3.63855)
			)
			(arc
				(start 13.610082 -9.780016)
				(mid 12.875507 -11.553437)
				(end 11.102086 -12.288012)
			)
			(arc
				(start 1.999996 -12.288012)
				(mid 0.944996 -12.725008)
				(end 0.508 -13.780008)
			)
			(arc
				(start 0.508 -77.67193)
				(mid 0.621601 -78.242658)
				(end 0.94488 -78.726538)
			)
			(arc
				(start 1.773428 -79.555086)
				(mid 2.317047 -80.368624)
				(end 2.507996 -81.32826)
			)
			(arc
				(start 2.507996 -403.371812)
				(mid 2.621533 -403.942691)
				(end 2.944876 -404.426674)
			)
			(arc
				(start 6.273292 -407.75509)
				(mid 6.817042 -408.568731)
				(end 7.008114 -409.528518)
			)
			(arc
				(start 7.008114 -439.989976)
				(mid 7.44511 -441.044976)
				(end 8.50011 -441.481972)
			)
			(xy 71.060056 -441.481972)
		)
		(stroke
			(width 0)
			(type solid)
		)
		(fill yes)
		(layer "In2.Cu")
		(net "GND")
	)
	(gr_poly
		(pts
			(xy 310.922162 -335.09331) (xy 310.932227 -335.092876) (xy 310.950817 -335.085147) (xy 310.95823 -335.078324)
			(xy 311.055258 -334.981296) (xy 311.062108 -334.973899) (xy 311.069848 -334.955301) (xy 311.070244 -334.945228)
			(xy 311.070244 -328.057764) (xy 311.070675 -328.047698) (xy 311.078404 -328.029107) (xy 311.08523 -328.021696)
			(xy 315.80582 -323.301106) (xy 315.813219 -323.294262) (xy 315.831817 -323.286534) (xy 315.841888 -323.28612)
			(xy 345.865704 -323.28612) (xy 345.875773 -323.286544) (xy 345.894375 -323.294262) (xy 345.901772 -323.301106)
			(xy 347.924374 -325.323708) (xy 347.931222 -325.331106) (xy 347.938958 -325.349704) (xy 347.93936 -325.359776)
			(xy 347.93936 -325.370952) (xy 347.939794 -325.381017) (xy 347.947529 -325.399602) (xy 347.954346 -325.40702)
			(xy 348.886526 -326.3392) (xy 348.89338 -326.346595) (xy 348.901126 -326.365194) (xy 348.901512 -326.375268)
			(xy 348.901512 -328.087228) (xy 348.901941 -328.097296) (xy 348.909663 -328.115892) (xy 348.916498 -328.123296)
			(xy 349.013526 -328.220324) (xy 349.020922 -328.227175) (xy 349.039521 -328.234912) (xy 349.049594 -328.23531)
			(xy 354.81133 -328.23531) (xy 354.821398 -328.234882) (xy 354.839996 -328.227161) (xy 354.847398 -328.220324)
			(xy 355.369114 -327.698608) (xy 355.375971 -327.691214) (xy 355.383722 -327.672615) (xy 355.3841 -327.66254)
			(xy 355.3841 -325.88962) (xy 355.384538 -325.879556) (xy 355.392273 -325.860973) (xy 355.399086 -325.853552)
			(xy 356.062534 -325.190104) (xy 356.069934 -325.183263) (xy 356.088532 -325.17554) (xy 356.098602 -325.175118)
			(xy 376.658886 -325.175118) (xy 376.66895 -325.17468) (xy 376.687533 -325.166945) (xy 376.694954 -325.160132)
			(xy 377.209812 -324.645274) (xy 377.216664 -324.637878) (xy 377.224403 -324.619279) (xy 377.224798 -324.609206)
			(xy 377.224798 -298.668694) (xy 377.224374 -298.658624) (xy 377.216657 -298.640022) (xy 377.209812 -298.632626)
			(xy 374.94972 -296.372534) (xy 374.944386 -296.369232) (xy 374.923323 -296.356004) (xy 374.885409 -296.323814)
			(xy 374.853216 -296.285904) (xy 374.839992 -296.264838) (xy 374.83669 -296.259504) (xy 374.374918 -295.797732)
			(xy 374.36808 -295.790331) (xy 374.360368 -295.771732) (xy 374.359932 -295.761664) (xy 374.359932 -295.668192)
			(xy 374.359508 -295.658122) (xy 374.351795 -295.639516) (xy 374.344946 -295.632124) (xy 374.318022 -295.6052)
			(xy 374.310619 -295.598366) (xy 374.292021 -295.59066) (xy 374.281954 -295.590214) (xy 371.604286 -295.590214)
			(xy 371.594637 -295.590627) (xy 371.576716 -295.597782) (xy 371.562748 -295.611097) (xy 371.558312 -295.619678)
			(xy 371.513354 -295.717214) (xy 371.517418 -295.746424) (xy 371.52707 -295.757854) (xy 371.544161 -295.778734)
			(xy 371.571462 -295.825271) (xy 371.590151 -295.875885) (xy 371.599645 -295.928997) (xy 371.600222 -295.955974)
			(xy 371.5997 -295.981229) (xy 371.591387 -296.031051) (xy 371.574986 -296.078825) (xy 371.550945 -296.123248)
			(xy 371.519921 -296.163108) (xy 371.482759 -296.197318) (xy 371.440473 -296.224944) (xy 371.394217 -296.245234)
			(xy 371.345252 -296.257634) (xy 371.294914 -296.261805) (xy 371.244576 -296.257634) (xy 371.195611 -296.245234)
			(xy 371.149355 -296.224944) (xy 371.107069 -296.197318) (xy 371.069907 -296.163108) (xy 371.038883 -296.123248)
			(xy 371.014842 -296.078825) (xy 370.998441 -296.031051) (xy 370.990128 -295.981229) (xy 370.989606 -295.955974)
			(xy 370.990206 -295.929) (xy 370.999725 -295.875898) (xy 371.018408 -295.825288) (xy 371.045679 -295.77874)
			(xy 371.062758 -295.757854) (xy 371.07241 -295.746424) (xy 371.076474 -295.717214) (xy 371.031516 -295.619678)
			(xy 371.027068 -295.611115) (xy 371.013069 -295.597855) (xy 370.99518 -295.590659) (xy 370.985542 -295.590214)
			(xy 366.90427 -295.590214) (xy 366.894623 -295.59063) (xy 366.876706 -295.597789) (xy 366.862743 -295.611103)
			(xy 366.858296 -295.619678) (xy 366.813338 -295.717214) (xy 366.817402 -295.746424) (xy 366.827054 -295.757854)
			(xy 366.844146 -295.778734) (xy 366.871448 -295.825271) (xy 366.890138 -295.875885) (xy 366.899633 -295.928997)
			(xy 366.900206 -295.955974) (xy 366.899684 -295.981229) (xy 366.891371 -296.031051) (xy 366.87497 -296.078825)
			(xy 366.850929 -296.123248) (xy 366.819905 -296.163108) (xy 366.782743 -296.197318) (xy 366.740457 -296.224944)
			(xy 366.694201 -296.245234) (xy 366.645236 -296.257634) (xy 366.594898 -296.261805) (xy 366.54456 -296.257634)
			(xy 366.495595 -296.245234) (xy 366.449339 -296.224944) (xy 366.407053 -296.197318) (xy 366.369891 -296.163108)
			(xy 366.338867 -296.123248) (xy 366.314826 -296.078825) (xy 366.298425 -296.031051) (xy 366.290112 -295.981229)
			(xy 366.28959 -295.955974) (xy 366.29019 -295.929) (xy 366.299708 -295.875898) (xy 366.318391 -295.825287)
			(xy 366.34566 -295.778738) (xy 366.362742 -295.757854) (xy 366.372394 -295.746424) (xy 366.376458 -295.717214)
			(xy 366.3315 -295.619678) (xy 366.327052 -295.611116) (xy 366.313051 -295.597861) (xy 366.295163 -295.590671)
			(xy 366.285526 -295.590214) (xy 358.001824 -295.590214) (xy 357.99176 -295.589778) (xy 357.973174 -295.582045)
			(xy 357.965756 -295.575228) (xy 356.995984 -294.605456) (xy 356.988587 -294.598606) (xy 356.969989 -294.590868)
			(xy 356.959916 -294.59047) (xy 356.528624 -294.59047) (xy 356.518573 -294.590975) (xy 356.500011 -294.598695)
			(xy 356.492556 -294.605456) (xy 356.399592 -294.69842) (xy 356.39275 -294.70582) (xy 356.385024 -294.724418)
			(xy 356.384606 -294.734488) (xy 356.384606 -297.106848) (xy 356.384857 -297.114495) (xy 356.389367 -297.129109)
			(xy 356.393496 -297.13555) (xy 356.412878 -297.164644) (xy 356.445291 -297.226586) (xy 356.470017 -297.291977)
			(xy 356.486699 -297.359867) (xy 356.495093 -297.429271) (xy 356.495604 -297.464226) (xy 356.495604 -298.518537)
			(xy 359.913422 -298.518537) (xy 359.913422 -298.454615) (xy 359.921433 -298.391197) (xy 359.93733 -298.329283)
			(xy 359.960862 -298.26985) (xy 359.991656 -298.213835) (xy 360.029229 -298.16212) (xy 360.072986 -298.115523)
			(xy 360.122239 -298.074778) (xy 360.17621 -298.040527) (xy 360.234049 -298.01331) (xy 360.294842 -297.993557)
			(xy 360.357632 -297.981579) (xy 360.421428 -297.977566) (xy 360.485224 -297.981579) (xy 360.548014 -297.993557)
			(xy 360.608807 -298.01331) (xy 360.666646 -298.040527) (xy 360.720617 -298.074778) (xy 360.76987 -298.115523)
			(xy 360.813627 -298.16212) (xy 360.8512 -298.213835) (xy 360.881994 -298.26985) (xy 360.905526 -298.329283)
			(xy 360.921423 -298.391197) (xy 360.929434 -298.454615) (xy 360.929936 -298.486576) (xy 360.929434 -298.518537)
			(xy 360.921423 -298.581955) (xy 360.905526 -298.643869) (xy 360.881994 -298.703302) (xy 360.8512 -298.759317)
			(xy 360.813627 -298.811032) (xy 360.76987 -298.857629) (xy 360.720617 -298.898374) (xy 360.666646 -298.932625)
			(xy 360.608807 -298.959842) (xy 360.548014 -298.979595) (xy 360.485224 -298.991573) (xy 360.421428 -298.995587)
			(xy 360.357632 -298.991573) (xy 360.294842 -298.979595) (xy 360.234049 -298.959842) (xy 360.17621 -298.932625)
			(xy 360.122239 -298.898374) (xy 360.072986 -298.857629) (xy 360.029229 -298.811032) (xy 359.991656 -298.759317)
			(xy 359.960862 -298.703302) (xy 359.93733 -298.643869) (xy 359.921433 -298.581955) (xy 359.913422 -298.518537)
			(xy 356.495604 -298.518537) (xy 356.495604 -301.226474) (xy 356.495116 -301.260626) (xy 356.487108 -301.32846)
			(xy 356.471187 -301.394883) (xy 356.447575 -301.458977) (xy 356.416598 -301.519853) (xy 356.398068 -301.548546)
			(xy 352.715322 -307.059584) (xy 352.714814 -307.060092) (xy 352.7044 -307.076602) (xy 349.800672 -311.422034)
			(xy 349.780473 -311.451287) (xy 349.734037 -311.505116) (xy 349.68136 -311.552854) (xy 349.623235 -311.593785)
			(xy 349.592138 -311.61101) (xy 349.3643 -311.73293) (xy 349.337094 -311.747013) (xy 349.280315 -311.770026)
			(xy 349.221428 -311.786932) (xy 349.191326 -311.79262) (xy 349.183706 -311.79389) (xy 349.169736 -311.801256)
			(xy 348.788736 -312.182256) (xy 348.781336 -312.189097) (xy 348.762737 -312.196815) (xy 348.752668 -312.197242)
			(xy 347.692726 -312.197242) (xy 347.68155 -312.199782) (xy 347.676216 -312.202576) (xy 347.649752 -312.215102)
			(xy 347.593936 -312.232777) (xy 347.536072 -312.241697) (xy 347.506798 -312.2422) (xy 347.477529 -312.241635)
			(xy 347.419677 -312.2327) (xy 347.363861 -312.215055) (xy 347.33738 -312.202576) (xy 347.332046 -312.199782)
			(xy 347.32087 -312.197242) (xy 345.164918 -312.197242) (xy 345.154855 -312.197681) (xy 345.136277 -312.205421)
			(xy 345.12885 -312.212228) (xy 344.20556 -313.135518) (xy 344.198163 -313.142367) (xy 344.179564 -313.1501)
			(xy 344.169492 -313.150504) (xy 343.069164 -313.150504) (xy 343.063518 -313.150629) (xy 343.052494 -313.153068)
			(xy 343.04732 -313.15533) (xy 342.644222 -313.346084) (xy 342.614051 -313.359856) (xy 342.551252 -313.381191)
			(xy 342.486426 -313.395209) (xy 342.453468 -313.398916) (xy 324.472808 -315.170058) (xy 324.463918 -315.171836)
			(xy 319.705736 -316.547246) (xy 319.700402 -316.549024) (xy 319.273936 -316.7253) (xy 319.269348 -316.727346)
			(xy 319.261029 -316.732976) (xy 319.257426 -316.736476) (xy 313.247278 -322.74637) (xy 313.22004 -322.772799)
			(xy 313.159853 -322.819033) (xy 313.094142 -322.85701) (xy 313.059318 -322.8721) (xy 311.082436 -323.69125)
			(xy 311.047141 -323.70516) (xy 310.973847 -323.724738) (xy 310.898626 -323.734597) (xy 310.860694 -323.735192)
			(xy 310.856884 -323.735192) (xy 307.013356 -323.709284) (xy 307.003562 -323.709668) (xy 306.985371 -323.716918)
			(xy 306.971251 -323.730487) (xy 306.966874 -323.739256) (xy 306.92217 -323.837554) (xy 306.926488 -323.867018)
			(xy 306.936648 -323.878194) (xy 306.966019 -323.912139) (xy 307.019191 -323.984467) (xy 307.065605 -324.061308)
			(xy 307.10488 -324.14203) (xy 307.136694 -324.225974) (xy 307.160787 -324.31245) (xy 307.176962 -324.400751)
			(xy 307.185085 -324.490153) (xy 307.185568 -324.535038) (xy 307.185053 -324.580831) (xy 307.176598 -324.672025)
			(xy 307.159764 -324.76205) (xy 307.134693 -324.850138) (xy 307.101602 -324.935536) (xy 307.06077 -325.017516)
			(xy 307.012548 -325.095379) (xy 306.957346 -325.168459) (xy 306.895637 -325.236133) (xy 306.827945 -325.297824)
			(xy 306.754849 -325.353005) (xy 306.676973 -325.401206) (xy 306.594982 -325.442014) (xy 306.509574 -325.475082)
			(xy 306.42148 -325.500127) (xy 306.33145 -325.516936) (xy 306.240253 -325.525366) (xy 306.19446 -325.525892)
			(xy 304.44186 -325.525892) (xy 304.428144 -325.525892) (xy 304.409602 -325.533766) (xy 304.351436 -325.591678)
			(xy 304.344634 -325.599026) (xy 304.336924 -325.617489) (xy 304.33645 -325.627492) (xy 304.33645 -334.700372)
			(xy 304.336888 -334.710435) (xy 304.344626 -334.729016) (xy 304.351436 -334.73644) (xy 304.69332 -335.078324)
			(xy 304.700716 -335.085175) (xy 304.719315 -335.092915) (xy 304.729388 -335.09331)
		)
		(stroke
			(width 0)
			(type solid)
		)
		(fill yes)
		(layer "In2.Cu")
		(net "PVDDCR_CPU1_P0")
	)
	(gr_poly
		(pts
			(xy 398.079976 -66.973704) (xy 398.09004 -66.973267) (xy 398.108625 -66.965534) (xy 398.116044 -66.958718)
			(xy 400.851624 -64.223138) (xy 400.858469 -64.21574) (xy 400.866193 -64.197141) (xy 400.86661 -64.18707)
			(xy 400.86661 -46.630844) (xy 400.866177 -46.620778) (xy 400.85845 -46.602187) (xy 400.851624 -46.594776)
			(xy 398.116298 -43.85945) (xy 398.108902 -43.852598) (xy 398.090303 -43.844857) (xy 398.08023 -43.844464)
			(xy 368.769646 -43.844464) (xy 368.760754 -43.844797) (xy 368.744042 -43.85088) (xy 368.730429 -43.862324)
			(xy 368.725704 -43.869864) (xy 368.674904 -43.958002) (xy 368.674904 -43.984926) (xy 368.681762 -43.996864)
			(xy 368.697928 -44.025972) (xy 368.723392 -44.087493) (xy 368.740608 -44.151811) (xy 368.749283 -44.217827)
			(xy 368.749834 -44.251118) (xy 368.749332 -44.283079) (xy 368.741321 -44.346497) (xy 368.725424 -44.408411)
			(xy 368.701892 -44.467844) (xy 368.671098 -44.523859) (xy 368.633525 -44.575574) (xy 368.589768 -44.622171)
			(xy 368.540515 -44.662916) (xy 368.486544 -44.697167) (xy 368.428705 -44.724384) (xy 368.367912 -44.744137)
			(xy 368.305122 -44.756115) (xy 368.241326 -44.760129) (xy 368.17753 -44.756115) (xy 368.11474 -44.744137)
			(xy 368.053947 -44.724384) (xy 367.996108 -44.697167) (xy 367.942137 -44.662916) (xy 367.892884 -44.622171)
			(xy 367.849127 -44.575574) (xy 367.811554 -44.523859) (xy 367.78076 -44.467844) (xy 367.757228 -44.408411)
			(xy 367.741331 -44.346497) (xy 367.73332 -44.283079) (xy 367.732818 -44.251118) (xy 367.73336 -44.217826)
			(xy 367.74204 -44.15181) (xy 367.759254 -44.08749) (xy 367.784709 -44.025964) (xy 367.80089 -43.996864)
			(xy 367.807748 -43.984926) (xy 367.807748 -43.958002) (xy 367.756948 -43.869864) (xy 367.752166 -43.862376)
			(xy 367.73856 -43.85097) (xy 367.721882 -43.844885) (xy 367.713006 -43.844464) (xy 366.529112 -43.844464)
			(xy 366.519042 -43.844887) (xy 366.500441 -43.852605) (xy 366.493044 -43.85945) (xy 366.210088 -44.142406)
			(xy 366.202722 -44.165012) (xy 366.2045 -44.17695) (xy 366.207015 -44.195388) (xy 366.209682 -44.232509)
			(xy 366.209834 -44.251118) (xy 366.209369 -44.281849) (xy 366.201959 -44.342862) (xy 366.187249 -44.402538)
			(xy 366.165453 -44.460005) (xy 366.13689 -44.514427) (xy 366.101976 -44.565008) (xy 366.061219 -44.611013)
			(xy 366.015215 -44.651771) (xy 365.964633 -44.686686) (xy 365.910212 -44.71525) (xy 365.852745 -44.737046)
			(xy 365.79307 -44.751757) (xy 365.759653 -44.755816) (xy 366.13795 -44.755816) (xy 366.142023 -44.700157)
			(xy 366.154158 -44.645684) (xy 366.174094 -44.593558) (xy 366.201408 -44.54489) (xy 366.235516 -44.500718)
			(xy 366.275693 -44.461983) (xy 366.321081 -44.429511) (xy 366.370713 -44.403993) (xy 366.423533 -44.385974)
			(xy 366.478412 -44.375837) (xy 366.534183 -44.373799) (xy 366.589657 -44.379902) (xy 366.64365 -44.394018)
			(xy 366.695013 -44.415845) (xy 366.742651 -44.444918) (xy 366.785547 -44.480617) (xy 366.822789 -44.522181)
			(xy 366.853583 -44.568725) (xy 366.877271 -44.619256) (xy 366.893349 -44.672698) (xy 366.901475 -44.727912)
			(xy 366.901984 -44.755816) (xy 366.901475 -44.78372) (xy 366.893349 -44.838934) (xy 366.877271 -44.892376)
			(xy 366.853583 -44.942907) (xy 366.822789 -44.989451) (xy 366.785547 -45.031015) (xy 366.742651 -45.066714)
			(xy 366.695013 -45.095787) (xy 366.64365 -45.117614) (xy 366.589657 -45.13173) (xy 366.534183 -45.137833)
			(xy 366.478412 -45.135795) (xy 366.423533 -45.125658) (xy 366.370713 -45.107639) (xy 366.321081 -45.082121)
			(xy 366.275693 -45.049649) (xy 366.235516 -45.010914) (xy 366.201408 -44.966742) (xy 366.174094 -44.918074)
			(xy 366.154158 -44.865948) (xy 366.142023 -44.811475) (xy 366.13795 -44.755816) (xy 365.759653 -44.755816)
			(xy 365.732057 -44.759168) (xy 365.701326 -44.759626) (xy 365.682717 -44.759488) (xy 365.645595 -44.756818)
			(xy 365.627158 -44.754292) (xy 365.61522 -44.752514) (xy 365.592614 -44.75988) (xy 365.26597 -45.086524)
			(xy 365.25912 -45.09392) (xy 365.251383 -45.112519) (xy 365.250984 -45.122592) (xy 365.250984 -51.113944)
			(xy 365.251082 -51.11623) (xy 388.081518 -51.11623) (xy 388.085589 -51.060608) (xy 388.097715 -51.006171)
			(xy 388.117638 -50.95408) (xy 388.144934 -50.905445) (xy 388.17902 -50.861302) (xy 388.219169 -50.822593)
			(xy 388.264527 -50.790142) (xy 388.314127 -50.764641) (xy 388.366911 -50.746634) (xy 388.421754 -50.736504)
			(xy 388.477488 -50.734467) (xy 388.532925 -50.740567) (xy 388.586882 -50.754673) (xy 388.638211 -50.776485)
			(xy 388.685817 -50.805539) (xy 388.728685 -50.841214) (xy 388.765902 -50.882751) (xy 388.796675 -50.929264)
			(xy 388.820347 -50.979761) (xy 388.836415 -51.033168) (xy 388.844535 -51.088344) (xy 388.845044 -51.11623)
			(xy 388.844535 -51.144116) (xy 388.836415 -51.199292) (xy 388.820347 -51.252699) (xy 388.796675 -51.303196)
			(xy 388.765902 -51.349709) (xy 388.728685 -51.391246) (xy 388.685817 -51.426921) (xy 388.638211 -51.455975)
			(xy 388.586882 -51.477787) (xy 388.532925 -51.491893) (xy 388.477488 -51.497993) (xy 388.421754 -51.495956)
			(xy 388.366911 -51.485826) (xy 388.314127 -51.467819) (xy 388.264527 -51.442318) (xy 388.219169 -51.409867)
			(xy 388.17902 -51.371158) (xy 388.144934 -51.327015) (xy 388.117638 -51.27838) (xy 388.097715 -51.226289)
			(xy 388.085589 -51.171852) (xy 388.081518 -51.11623) (xy 365.251082 -51.11623) (xy 365.251415 -51.124011)
			(xy 365.259138 -51.142605) (xy 365.26597 -51.150012) (xy 369.927378 -55.81142) (xy 384.320286 -55.81142)
			(xy 384.324357 -55.755798) (xy 384.336483 -55.701361) (xy 384.356406 -55.64927) (xy 384.383702 -55.600635)
			(xy 384.417788 -55.556492) (xy 384.457937 -55.517783) (xy 384.503295 -55.485332) (xy 384.552895 -55.459831)
			(xy 384.605679 -55.441824) (xy 384.660522 -55.431694) (xy 384.716256 -55.429657) (xy 384.771693 -55.435757)
			(xy 384.82565 -55.449863) (xy 384.837277 -55.454804) (xy 394.710156 -55.454804) (xy 394.714227 -55.399182)
			(xy 394.726353 -55.344745) (xy 394.746276 -55.292654) (xy 394.773572 -55.244019) (xy 394.807658 -55.199876)
			(xy 394.847807 -55.161167) (xy 394.893165 -55.128716) (xy 394.942765 -55.103215) (xy 394.995549 -55.085208)
			(xy 395.050392 -55.075078) (xy 395.106126 -55.073041) (xy 395.161563 -55.079141) (xy 395.21552 -55.093247)
			(xy 395.266849 -55.115059) (xy 395.314455 -55.144113) (xy 395.357323 -55.179788) (xy 395.39454 -55.221325)
			(xy 395.425313 -55.267838) (xy 395.448985 -55.318335) (xy 395.465053 -55.371742) (xy 395.473173 -55.426918)
			(xy 395.473682 -55.454804) (xy 395.473173 -55.48269) (xy 395.465053 -55.537866) (xy 395.448985 -55.591273)
			(xy 395.425313 -55.64177) (xy 395.39454 -55.688283) (xy 395.357323 -55.72982) (xy 395.314455 -55.765495)
			(xy 395.266849 -55.794549) (xy 395.21552 -55.816361) (xy 395.161563 -55.830467) (xy 395.106126 -55.836567)
			(xy 395.050392 -55.83453) (xy 394.995549 -55.8244) (xy 394.942765 -55.806393) (xy 394.893165 -55.780892)
			(xy 394.847807 -55.748441) (xy 394.807658 -55.709732) (xy 394.773572 -55.665589) (xy 394.746276 -55.616954)
			(xy 394.726353 -55.564863) (xy 394.714227 -55.510426) (xy 394.710156 -55.454804) (xy 384.837277 -55.454804)
			(xy 384.876979 -55.471675) (xy 384.924585 -55.500729) (xy 384.967453 -55.536404) (xy 385.00467 -55.577941)
			(xy 385.035443 -55.624454) (xy 385.059115 -55.674951) (xy 385.075183 -55.728358) (xy 385.083303 -55.783534)
			(xy 385.083812 -55.81142) (xy 385.083303 -55.839306) (xy 385.075183 -55.894482) (xy 385.059115 -55.947889)
			(xy 385.035443 -55.998386) (xy 385.00467 -56.044899) (xy 384.967453 -56.086436) (xy 384.963406 -56.089804)
			(xy 394.075156 -56.089804) (xy 394.079227 -56.034182) (xy 394.091353 -55.979745) (xy 394.111276 -55.927654)
			(xy 394.138572 -55.879019) (xy 394.172658 -55.834876) (xy 394.212807 -55.796167) (xy 394.258165 -55.763716)
			(xy 394.307765 -55.738215) (xy 394.360549 -55.720208) (xy 394.415392 -55.710078) (xy 394.471126 -55.708041)
			(xy 394.526563 -55.714141) (xy 394.58052 -55.728247) (xy 394.631849 -55.750059) (xy 394.679455 -55.779113)
			(xy 394.722323 -55.814788) (xy 394.75954 -55.856325) (xy 394.790313 -55.902838) (xy 394.813985 -55.953335)
			(xy 394.830053 -56.006742) (xy 394.838173 -56.061918) (xy 394.838682 -56.089804) (xy 394.838173 -56.11769)
			(xy 394.830053 -56.172866) (xy 394.813985 -56.226273) (xy 394.790313 -56.27677) (xy 394.75954 -56.323283)
			(xy 394.722323 -56.36482) (xy 394.679455 -56.400495) (xy 394.631849 -56.429549) (xy 394.58052 -56.451361)
			(xy 394.526563 -56.465467) (xy 394.471126 -56.471567) (xy 394.415392 -56.46953) (xy 394.360549 -56.4594)
			(xy 394.307765 -56.441393) (xy 394.258165 -56.415892) (xy 394.212807 -56.383441) (xy 394.172658 -56.344732)
			(xy 394.138572 -56.300589) (xy 394.111276 -56.251954) (xy 394.091353 -56.199863) (xy 394.079227 -56.145426)
			(xy 394.075156 -56.089804) (xy 384.963406 -56.089804) (xy 384.924585 -56.122111) (xy 384.876979 -56.151165)
			(xy 384.82565 -56.172977) (xy 384.771693 -56.187083) (xy 384.716256 -56.193183) (xy 384.660522 -56.191146)
			(xy 384.605679 -56.181016) (xy 384.552895 -56.163009) (xy 384.503295 -56.137508) (xy 384.457937 -56.105057)
			(xy 384.417788 -56.066348) (xy 384.383702 -56.022205) (xy 384.356406 -55.97357) (xy 384.336483 -55.921479)
			(xy 384.324357 -55.867042) (xy 384.320286 -55.81142) (xy 369.927378 -55.81142) (xy 378.620274 -64.504316)
			(xy 384.008884 -64.504316) (xy 384.009373 -64.477707) (xy 384.016742 -64.425001) (xy 384.031368 -64.373832)
			(xy 384.052966 -64.325193) (xy 384.081116 -64.28003) (xy 384.115273 -64.239219) (xy 384.154771 -64.203553)
			(xy 384.198845 -64.173726) (xy 384.246638 -64.150316) (xy 384.297221 -64.133778) (xy 384.323336 -64.12865)
			(xy 384.332988 -64.127126) (xy 384.349498 -64.116712) (xy 384.402584 -64.044322) (xy 384.40741 -64.025526)
			(xy 384.40614 -64.015874) (xy 384.4047 -64.003734) (xy 384.403176 -63.979331) (xy 384.403092 -63.967106)
			(xy 384.403565 -63.940496) (xy 384.410936 -63.887789) (xy 384.425563 -63.83662) (xy 384.447163 -63.78798)
			(xy 384.475315 -63.742817) (xy 384.509473 -63.702006) (xy 384.548974 -63.666341) (xy 384.593049 -63.636513)
			(xy 384.640844 -63.613104) (xy 384.691429 -63.596567) (xy 384.717544 -63.59144) (xy 384.727196 -63.589916)
			(xy 384.743706 -63.579502) (xy 384.796792 -63.507112) (xy 384.801618 -63.488316) (xy 384.800348 -63.478664)
			(xy 384.798907 -63.466524) (xy 384.797384 -63.442121) (xy 384.7973 -63.429896) (xy 384.797786 -63.402645)
			(xy 384.805542 -63.348697) (xy 384.820897 -63.296402) (xy 384.843539 -63.246825) (xy 384.873005 -63.200975)
			(xy 384.908696 -63.159784) (xy 384.949887 -63.124093) (xy 384.995737 -63.094627) (xy 385.045314 -63.071985)
			(xy 385.097609 -63.05663) (xy 385.151557 -63.048874) (xy 385.206059 -63.048874) (xy 385.260007 -63.05663)
			(xy 385.312302 -63.071985) (xy 385.361879 -63.094627) (xy 385.407729 -63.124093) (xy 385.44892 -63.159784)
			(xy 385.484611 -63.200975) (xy 385.514077 -63.246825) (xy 385.536719 -63.296402) (xy 385.552074 -63.348697)
			(xy 385.55983 -63.402645) (xy 385.560316 -63.429896) (xy 385.559838 -63.456506) (xy 385.552467 -63.509212)
			(xy 385.53784 -63.560381) (xy 385.516241 -63.60902) (xy 385.488089 -63.654183) (xy 385.453931 -63.694994)
			(xy 385.414432 -63.73066) (xy 385.370357 -63.760487) (xy 385.322563 -63.783897) (xy 385.271979 -63.800434)
			(xy 385.245864 -63.805562) (xy 385.236212 -63.807086) (xy 385.219702 -63.8175) (xy 385.211506 -63.828676)
			(xy 399.552666 -63.828676) (xy 399.556737 -63.773054) (xy 399.568863 -63.718617) (xy 399.588786 -63.666526)
			(xy 399.616082 -63.617891) (xy 399.650168 -63.573748) (xy 399.690317 -63.535039) (xy 399.735675 -63.502588)
			(xy 399.785275 -63.477087) (xy 399.838059 -63.45908) (xy 399.892902 -63.44895) (xy 399.948636 -63.446913)
			(xy 400.004073 -63.453013) (xy 400.05803 -63.467119) (xy 400.109359 -63.488931) (xy 400.156965 -63.517985)
			(xy 400.199833 -63.55366) (xy 400.23705 -63.595197) (xy 400.267823 -63.64171) (xy 400.291495 -63.692207)
			(xy 400.307563 -63.745614) (xy 400.315683 -63.80079) (xy 400.316192 -63.828676) (xy 400.315683 -63.856562)
			(xy 400.307563 -63.911738) (xy 400.291495 -63.965145) (xy 400.267823 -64.015642) (xy 400.23705 -64.062155)
			(xy 400.199833 -64.103692) (xy 400.156965 -64.139367) (xy 400.109359 -64.168421) (xy 400.05803 -64.190233)
			(xy 400.004073 -64.204339) (xy 399.948636 -64.210439) (xy 399.892902 -64.208402) (xy 399.838059 -64.198272)
			(xy 399.785275 -64.180265) (xy 399.735675 -64.154764) (xy 399.690317 -64.122313) (xy 399.650168 -64.083604)
			(xy 399.616082 -64.039461) (xy 399.588786 -63.990826) (xy 399.568863 -63.938735) (xy 399.556737 -63.884298)
			(xy 399.552666 -63.828676) (xy 385.211506 -63.828676) (xy 385.166616 -63.88989) (xy 385.16179 -63.908686)
			(xy 385.16306 -63.918338) (xy 385.164501 -63.930478) (xy 385.166024 -63.954881) (xy 385.166108 -63.967106)
			(xy 385.165646 -63.993716) (xy 385.158273 -64.046423) (xy 385.143645 -64.097593) (xy 385.122044 -64.146233)
			(xy 385.09389 -64.191396) (xy 385.059731 -64.232207) (xy 385.020229 -64.267872) (xy 384.976153 -64.297699)
			(xy 384.928357 -64.321108) (xy 384.877772 -64.337645) (xy 384.851656 -64.342772) (xy 384.842004 -64.344296)
			(xy 384.825494 -64.35471) (xy 384.772408 -64.4271) (xy 384.767582 -64.445896) (xy 384.768852 -64.455548)
			(xy 384.770294 -64.467688) (xy 384.771816 -64.492091) (xy 384.7719 -64.504316) (xy 384.771414 -64.531567)
			(xy 384.763658 -64.585515) (xy 384.748303 -64.63781) (xy 384.725661 -64.687387) (xy 384.696195 -64.733237)
			(xy 384.660504 -64.774428) (xy 384.619313 -64.810119) (xy 384.573463 -64.839585) (xy 384.523886 -64.862227)
			(xy 384.471591 -64.877582) (xy 384.417643 -64.885338) (xy 384.363141 -64.885338) (xy 384.309193 -64.877582)
			(xy 384.256898 -64.862227) (xy 384.207321 -64.839585) (xy 384.161471 -64.810119) (xy 384.12028 -64.774428)
			(xy 384.084589 -64.733237) (xy 384.055123 -64.687387) (xy 384.032481 -64.63781) (xy 384.017126 -64.585515)
			(xy 384.00937 -64.531567) (xy 384.008884 -64.504316) (xy 378.620274 -64.504316) (xy 381.074676 -66.958718)
			(xy 381.082075 -66.965561) (xy 381.100674 -66.973281) (xy 381.110744 -66.973704)
		)
		(stroke
			(width 0)
			(type solid)
		)
		(fill yes)
		(layer "In2.Cu")
		(net "PVDD18_S5_P0")
	)
	(gr_poly
		(pts
			(arc
				(start 194.446144 -441.481972)
				(mid 194.482065 -441.467093)
				(end 194.496944 -441.431172)
			)
			(arc
				(start 194.496944 -441.17006)
				(mid 194.792217 -440.457207)
				(end 195.50507 -440.161934)
			)
			(arc
				(start 276.314916 -440.161934)
				(mid 277.027769 -440.457207)
				(end 277.323042 -441.17006)
			)
			(arc
				(start 277.323042 -441.431172)
				(mid 277.337921 -441.467093)
				(end 277.373842 -441.481972)
			)
			(arc
				(start 463.300064 -441.481972)
				(mid 464.355064 -441.044976)
				(end 464.79206 -439.989976)
			)
			(arc
				(start 464.79206 -409.528264)
				(mid 464.983018 -408.568632)
				(end 465.526628 -407.75509)
			)
			(arc
				(start 467.355174 -405.926544)
				(mid 467.678507 -405.442687)
				(end 467.792054 -404.871936)
			)
			(arc
				(start 467.792054 -363.649514)
				(mid 467.554484 -364.078202)
				(end 467.284816 -364.48746)
			)
			(arc
				(start 467.284816 -404.871936)
				(mid 467.209909 -405.248606)
				(end 466.996526 -405.567896)
			)
			(arc
				(start 465.16798 -407.396442)
				(mid 464.51433 -408.374514)
				(end 464.284568 -409.528264)
			)
			(arc
				(start 464.284568 -439.989976)
				(mid 463.996213 -440.686125)
				(end 463.300064 -440.97448)
			)
			(xy 410.910278 -440.97448) (xy 410.905198 -440.976258)
			(arc
				(start 410.90342 -440.976766)
				(mid 410.82774 -440.99441)
				(end 410.750258 -441.000388)
			)
			(arc
				(start 410.74975 -441.000388)
				(mid 410.672265 -440.994435)
				(end 410.596588 -440.976766)
			)
			(xy 410.59481 -440.976258) (xy 410.58973 -440.97448) (xy 406.910286 -440.97448) (xy 406.905206 -440.976258)
			(arc
				(start 406.903428 -440.976766)
				(mid 406.827748 -440.99441)
				(end 406.750266 -441.000388)
			)
			(arc
				(start 406.749758 -441.000388)
				(mid 406.672273 -440.994435)
				(end 406.596596 -440.976766)
			)
			(xy 406.594818 -440.976258) (xy 406.589738 -440.97448) (xy 402.910294 -440.97448) (xy 402.905214 -440.976258)
			(arc
				(start 402.903436 -440.976766)
				(mid 402.827756 -440.99441)
				(end 402.750274 -441.000388)
			)
			(arc
				(start 402.749766 -441.000388)
				(mid 402.672281 -440.994435)
				(end 402.596604 -440.976766)
			)
			(xy 402.594826 -440.976258) (xy 402.589746 -440.97448) (xy 398.910302 -440.97448)
			(arc
				(start 398.902936 -440.97702)
				(mid 398.827623 -440.994485)
				(end 398.750536 -441.000388)
			)
			(arc
				(start 398.74952 -441.000388)
				(mid 398.672432 -440.994496)
				(end 398.59712 -440.97702)
			)
			(xy 398.589754 -440.97448) (xy 393.910058 -440.97448) (xy 393.904978 -440.976258)
			(arc
				(start 393.9032 -440.976766)
				(mid 393.82752 -440.99441)
				(end 393.750038 -441.000388)
			)
			(arc
				(start 393.74953 -441.000388)
				(mid 393.672045 -440.994435)
				(end 393.596368 -440.976766)
			)
			(xy 393.59459 -440.976258) (xy 393.58951 -440.97448) (xy 389.910066 -440.97448) (xy 389.904986 -440.976258)
			(arc
				(start 389.903208 -440.976766)
				(mid 389.827528 -440.99441)
				(end 389.750046 -441.000388)
			)
			(arc
				(start 389.749538 -441.000388)
				(mid 389.672053 -440.994435)
				(end 389.596376 -440.976766)
			)
			(xy 389.594598 -440.976258) (xy 389.589518 -440.97448) (xy 385.910074 -440.97448) (xy 385.904994 -440.976258)
			(arc
				(start 385.903216 -440.976766)
				(mid 385.827536 -440.99441)
				(end 385.750054 -441.000388)
			)
			(arc
				(start 385.749546 -441.000388)
				(mid 385.672061 -440.994435)
				(end 385.596384 -440.976766)
			)
			(xy 385.594606 -440.976258) (xy 385.589526 -440.97448) (xy 381.910082 -440.97448)
			(arc
				(start 381.902716 -440.97702)
				(mid 381.827403 -440.994485)
				(end 381.750316 -441.000388)
			)
			(arc
				(start 381.7493 -441.000388)
				(mid 381.672212 -440.994496)
				(end 381.5969 -440.97702)
			)
			(xy 381.589534 -440.97448) (xy 343.810082 -440.97448) (xy 343.805002 -440.976258)
			(arc
				(start 343.803224 -440.976766)
				(mid 343.727544 -440.99441)
				(end 343.650062 -441.000388)
			)
			(arc
				(start 343.649554 -441.000388)
				(mid 343.572069 -440.994435)
				(end 343.496392 -440.976766)
			)
			(xy 343.494614 -440.976258) (xy 343.489534 -440.97448) (xy 339.81009 -440.97448) (xy 339.80501 -440.976258)
			(arc
				(start 339.803232 -440.976766)
				(mid 339.727552 -440.99441)
				(end 339.65007 -441.000388)
			)
			(arc
				(start 339.649562 -441.000388)
				(mid 339.572077 -440.994435)
				(end 339.4964 -440.976766)
			)
			(xy 339.494622 -440.976258) (xy 339.489542 -440.97448) (xy 335.810098 -440.97448) (xy 335.805018 -440.976258)
			(arc
				(start 335.80324 -440.976766)
				(mid 335.72756 -440.99441)
				(end 335.650078 -441.000388)
			)
			(arc
				(start 335.64957 -441.000388)
				(mid 335.572085 -440.994435)
				(end 335.496408 -440.976766)
			)
			(xy 335.49463 -440.976258) (xy 335.48955 -440.97448) (xy 331.810106 -440.97448)
			(arc
				(start 331.80274 -440.97702)
				(mid 331.727427 -440.994485)
				(end 331.65034 -441.000388)
			)
			(arc
				(start 331.649324 -441.000388)
				(mid 331.572236 -440.994496)
				(end 331.496924 -440.97702)
			)
			(xy 331.489558 -440.97448) (xy 326.810116 -440.97448) (xy 326.805036 -440.976258)
			(arc
				(start 326.803258 -440.976766)
				(mid 326.727578 -440.99441)
				(end 326.650096 -441.000388)
			)
			(arc
				(start 326.649588 -441.000388)
				(mid 326.572103 -440.994435)
				(end 326.496426 -440.976766)
			)
			(xy 326.494648 -440.976258) (xy 326.489568 -440.97448) (xy 322.810124 -440.97448) (xy 322.805044 -440.976258)
			(arc
				(start 322.803266 -440.976766)
				(mid 322.727586 -440.99441)
				(end 322.650104 -441.000388)
			)
			(arc
				(start 322.649596 -441.000388)
				(mid 322.572111 -440.994435)
				(end 322.496434 -440.976766)
			)
			(xy 322.494656 -440.976258) (xy 322.489576 -440.97448) (xy 318.810132 -440.97448) (xy 318.805052 -440.976258)
			(arc
				(start 318.803274 -440.976766)
				(mid 318.727594 -440.99441)
				(end 318.650112 -441.000388)
			)
			(arc
				(start 318.649604 -441.000388)
				(mid 318.572119 -440.994435)
				(end 318.496442 -440.976766)
			)
			(xy 318.494664 -440.976258) (xy 318.489584 -440.97448) (xy 314.81014 -440.97448)
			(arc
				(start 314.802774 -440.97702)
				(mid 314.727461 -440.994485)
				(end 314.650374 -441.000388)
			)
			(arc
				(start 314.649358 -441.000388)
				(mid 314.57227 -440.994496)
				(end 314.496958 -440.97702)
			)
			(xy 314.489592 -440.97448)
			(arc
				(start 277.817834 -440.97448)
				(mid 277.314992 -440.031472)
				(end 276.314916 -439.654696)
			)
			(arc
				(start 195.50507 -439.654696)
				(mid 194.504998 -440.031475)
				(end 194.002152 -440.97448)
			)
			(xy 154.910282 -440.97448) (xy 154.905202 -440.976258)
			(arc
				(start 154.903424 -440.976766)
				(mid 154.827744 -440.99441)
				(end 154.750262 -441.000388)
			)
			(arc
				(start 154.749754 -441.000388)
				(mid 154.672269 -440.994435)
				(end 154.596592 -440.976766)
			)
			(xy 154.594814 -440.976258) (xy 154.589734 -440.97448) (xy 150.91029 -440.97448) (xy 150.90521 -440.976258)
			(arc
				(start 150.903432 -440.976766)
				(mid 150.827752 -440.99441)
				(end 150.75027 -441.000388)
			)
			(arc
				(start 150.749762 -441.000388)
				(mid 150.672277 -440.994435)
				(end 150.5966 -440.976766)
			)
			(xy 150.594822 -440.976258) (xy 150.589742 -440.97448) (xy 146.910298 -440.97448) (xy 146.905218 -440.976258)
			(arc
				(start 146.90344 -440.976766)
				(mid 146.82776 -440.99441)
				(end 146.750278 -441.000388)
			)
			(arc
				(start 146.74977 -441.000388)
				(mid 146.672285 -440.994435)
				(end 146.596608 -440.976766)
			)
			(xy 146.59483 -440.976258) (xy 146.58975 -440.97448) (xy 142.910306 -440.97448)
			(arc
				(start 142.90294 -440.97702)
				(mid 142.827627 -440.994485)
				(end 142.75054 -441.000388)
			)
			(arc
				(start 142.749524 -441.000388)
				(mid 142.672436 -440.994496)
				(end 142.597124 -440.97702)
			)
			(xy 142.589758 -440.97448) (xy 137.910062 -440.97448) (xy 137.904982 -440.976258)
			(arc
				(start 137.903204 -440.976766)
				(mid 137.827524 -440.99441)
				(end 137.750042 -441.000388)
			)
			(arc
				(start 137.749534 -441.000388)
				(mid 137.672049 -440.994435)
				(end 137.596372 -440.976766)
			)
			(xy 137.594594 -440.976258) (xy 137.589514 -440.97448) (xy 133.91007 -440.97448) (xy 133.90499 -440.976258)
			(arc
				(start 133.903212 -440.976766)
				(mid 133.827532 -440.99441)
				(end 133.75005 -441.000388)
			)
			(arc
				(start 133.749542 -441.000388)
				(mid 133.672057 -440.994435)
				(end 133.59638 -440.976766)
			)
			(xy 133.594602 -440.976258) (xy 133.589522 -440.97448) (xy 129.910078 -440.97448) (xy 129.904998 -440.976258)
			(arc
				(start 129.90322 -440.976766)
				(mid 129.82754 -440.99441)
				(end 129.750058 -441.000388)
			)
			(arc
				(start 129.74955 -441.000388)
				(mid 129.672065 -440.994435)
				(end 129.596388 -440.976766)
			)
			(xy 129.59461 -440.976258) (xy 129.58953 -440.97448) (xy 125.910086 -440.97448)
			(arc
				(start 125.90272 -440.97702)
				(mid 125.827407 -440.994485)
				(end 125.75032 -441.000388)
			)
			(arc
				(start 125.749304 -441.000388)
				(mid 125.672216 -440.994496)
				(end 125.596904 -440.97702)
			)
			(xy 125.589538 -440.97448) (xy 87.81034 -440.97448) (xy 87.80526 -440.976258)
			(arc
				(start 87.803482 -440.976766)
				(mid 87.727802 -440.99441)
				(end 87.65032 -441.000388)
			)
			(arc
				(start 87.649812 -441.000388)
				(mid 87.572327 -440.994435)
				(end 87.49665 -440.976766)
			)
			(xy 87.494872 -440.976258) (xy 87.489792 -440.97448) (xy 83.810348 -440.97448) (xy 83.805268 -440.976258)
			(arc
				(start 83.80349 -440.976766)
				(mid 83.72781 -440.99441)
				(end 83.650328 -441.000388)
			)
			(arc
				(start 83.64982 -441.000388)
				(mid 83.572335 -440.994435)
				(end 83.496658 -440.976766)
			)
			(xy 83.49488 -440.976258) (xy 83.4898 -440.97448) (xy 79.810356 -440.97448) (xy 79.805276 -440.976258)
			(arc
				(start 79.803498 -440.976766)
				(mid 79.727818 -440.99441)
				(end 79.650336 -441.000388)
			)
			(arc
				(start 79.649828 -441.000388)
				(mid 79.572343 -440.994435)
				(end 79.496666 -440.976766)
			)
			(xy 79.494888 -440.976258) (xy 79.489808 -440.97448) (xy 75.810364 -440.97448)
			(arc
				(start 75.802998 -440.97702)
				(mid 75.727685 -440.994485)
				(end 75.650598 -441.000388)
			)
			(arc
				(start 75.649582 -441.000388)
				(mid 75.572494 -440.994496)
				(end 75.497182 -440.97702)
			)
			(xy 75.489816 -440.97448) (xy 73.931272 -440.97448) (xy 73.66508 -441.240672) (xy 73.66508 -441.384944)
			(xy 73.762108 -441.481972)
		)
		(stroke
			(width 0)
			(type solid)
		)
		(fill yes)
		(layer "In2.Cu")
		(net "GND")
	)
	(gr_poly
		(pts
			(xy 328.91222 -144.37868) (xy 328.922205 -144.378138) (xy 328.94063 -144.370418) (xy 328.948034 -144.363694)
			(xy 329.422506 -143.889476) (xy 329.429348 -143.882076) (xy 329.437073 -143.863478) (xy 329.437492 -143.853408)
			(xy 329.437492 -141.148054) (xy 329.43706 -141.137988) (xy 329.429333 -141.119396) (xy 329.422506 -141.111986)
			(xy 329.360276 -141.049756) (xy 329.352848 -141.042987) (xy 329.334252 -141.035409) (xy 329.324208 -141.035024)
			(xy 329.284838 -141.035024) (xy 329.276228 -141.035364) (xy 329.259975 -141.041053) (xy 329.246501 -141.051775)
			(xy 329.241658 -141.0589) (xy 329.17638 -141.163802) (xy 329.172853 -141.169966) (xy 329.168991 -141.183628)
			(xy 329.16876 -141.190726) (xy 329.16876 -142.272004) (xy 329.169234 -142.281972) (xy 329.176801 -142.300416)
			(xy 329.183492 -142.307818) (xy 329.204384 -142.329427) (xy 329.239787 -142.377998) (xy 329.26714 -142.431518)
			(xy 329.285767 -142.488664) (xy 329.295207 -142.548022) (xy 329.29576 -142.578074) (xy 329.295274 -142.605325)
			(xy 329.287518 -142.659273) (xy 329.272163 -142.711568) (xy 329.249521 -142.761145) (xy 329.220055 -142.806995)
			(xy 329.184364 -142.848186) (xy 329.143173 -142.883877) (xy 329.097323 -142.913343) (xy 329.047746 -142.935985)
			(xy 328.995451 -142.95134) (xy 328.941503 -142.959096) (xy 328.887001 -142.959096) (xy 328.833053 -142.95134)
			(xy 328.780758 -142.935985) (xy 328.731181 -142.913343) (xy 328.685331 -142.883877) (xy 328.64414 -142.848186)
			(xy 328.608449 -142.806995) (xy 328.578983 -142.761145) (xy 328.556341 -142.711568) (xy 328.540986 -142.659273)
			(xy 328.53323 -142.605325) (xy 328.532744 -142.578074) (xy 328.533302 -142.54802) (xy 328.54272 -142.488654)
			(xy 328.561334 -142.4315) (xy 328.588684 -142.377974) (xy 328.624091 -142.329402) (xy 328.645012 -142.307818)
			(xy 328.651698 -142.300409) (xy 328.659284 -142.281973) (xy 328.659744 -142.272004) (xy 328.659744 -141.10335)
			(xy 328.660293 -141.079686) (xy 328.669075 -141.033179) (xy 328.686273 -140.989086) (xy 328.698352 -140.96873)
			(xy 328.892154 -140.657834) (xy 328.885804 -140.619988) (xy 328.870564 -140.607796) (xy 328.849736 -140.589)
			(xy 328.389742 -140.129006) (xy 328.372519 -140.110896) (xy 328.344777 -140.069336) (xy 328.325664 -140.023167)
			(xy 328.315913 -139.974158) (xy 328.31532 -139.949174) (xy 328.31532 -138.155934) (xy 328.314789 -138.145943)
			(xy 328.307087 -138.1275) (xy 328.300334 -138.12012) (xy 328.279444 -138.09851) (xy 328.244047 -138.049938)
			(xy 328.216701 -137.996417) (xy 328.198082 -137.939272) (xy 328.188651 -137.879915) (xy 328.188066 -137.849864)
			(xy 328.188552 -137.822613) (xy 328.196308 -137.768665) (xy 328.211663 -137.71637) (xy 328.234305 -137.666793)
			(xy 328.263771 -137.620943) (xy 328.299462 -137.579752) (xy 328.340653 -137.544061) (xy 328.386503 -137.514595)
			(xy 328.43608 -137.491953) (xy 328.488375 -137.476598) (xy 328.542323 -137.468842) (xy 328.596825 -137.468842)
			(xy 328.650773 -137.476598) (xy 328.703068 -137.491953) (xy 328.752645 -137.514595) (xy 328.798495 -137.544061)
			(xy 328.839686 -137.579752) (xy 328.875377 -137.620943) (xy 328.904843 -137.666793) (xy 328.927485 -137.71637)
			(xy 328.94284 -137.768665) (xy 328.950596 -137.822613) (xy 328.951082 -137.849864) (xy 328.950521 -137.879917)
			(xy 328.941099 -137.939281) (xy 328.922481 -137.996431) (xy 328.895129 -138.049954) (xy 328.859721 -138.098524)
			(xy 328.838814 -138.12012) (xy 328.832005 -138.127466) (xy 328.824278 -138.145928) (xy 328.823828 -138.155934)
			(xy 328.823828 -139.822682) (xy 328.824267 -139.832745) (xy 328.832005 -139.851325) (xy 328.838814 -139.85875)
			(xy 329.11034 -140.130276) (xy 329.11776 -140.137066) (xy 329.136357 -140.144685) (xy 329.146408 -140.145008)
			(xy 329.608688 -140.145008) (xy 329.633683 -140.145648) (xy 329.682704 -140.155453) (xy 329.728871 -140.17463)
			(xy 329.770412 -140.202442) (xy 329.78852 -140.219684) (xy 329.976988 -140.408152) (xy 332.324962 -140.408152)
			(xy 332.329033 -140.35253) (xy 332.341159 -140.298093) (xy 332.361082 -140.246002) (xy 332.388378 -140.197367)
			(xy 332.422464 -140.153224) (xy 332.462613 -140.114515) (xy 332.507971 -140.082064) (xy 332.557571 -140.056563)
			(xy 332.610355 -140.038556) (xy 332.665198 -140.028426) (xy 332.720932 -140.026389) (xy 332.776369 -140.032489)
			(xy 332.830326 -140.046595) (xy 332.881655 -140.068407) (xy 332.929261 -140.097461) (xy 332.972129 -140.133136)
			(xy 333.009346 -140.174673) (xy 333.040119 -140.221186) (xy 333.063791 -140.271683) (xy 333.079859 -140.32509)
			(xy 333.087979 -140.380266) (xy 333.088488 -140.408152) (xy 333.087979 -140.436038) (xy 333.079859 -140.491214)
			(xy 333.063791 -140.544621) (xy 333.040119 -140.595118) (xy 333.009346 -140.641631) (xy 332.972129 -140.683168)
			(xy 332.929261 -140.718843) (xy 332.881655 -140.747897) (xy 332.830326 -140.769709) (xy 332.776369 -140.783815)
			(xy 332.720932 -140.789915) (xy 332.665198 -140.787878) (xy 332.610355 -140.777748) (xy 332.557571 -140.759741)
			(xy 332.507971 -140.73424) (xy 332.462613 -140.701789) (xy 332.422464 -140.66308) (xy 332.388378 -140.618937)
			(xy 332.361082 -140.570302) (xy 332.341159 -140.518211) (xy 332.329033 -140.463774) (xy 332.324962 -140.408152)
			(xy 329.976988 -140.408152) (xy 330.134214 -140.565378) (xy 330.134722 -140.565886) (xy 330.141326 -140.572236)
			(xy 330.252832 -140.683996) (xy 330.269996 -140.702097) (xy 330.297635 -140.743614) (xy 330.316671 -140.789714)
			(xy 330.326377 -140.838636) (xy 330.327 -140.863574) (xy 330.327 -142.197074) (xy 332.301086 -142.197074)
			(xy 332.305157 -142.141452) (xy 332.317283 -142.087015) (xy 332.337206 -142.034924) (xy 332.364502 -141.986289)
			(xy 332.398588 -141.942146) (xy 332.438737 -141.903437) (xy 332.484095 -141.870986) (xy 332.533695 -141.845485)
			(xy 332.586479 -141.827478) (xy 332.641322 -141.817348) (xy 332.697056 -141.815311) (xy 332.752493 -141.821411)
			(xy 332.80645 -141.835517) (xy 332.857779 -141.857329) (xy 332.905385 -141.886383) (xy 332.948253 -141.922058)
			(xy 332.98547 -141.963595) (xy 333.016243 -142.010108) (xy 333.039915 -142.060605) (xy 333.055983 -142.114012)
			(xy 333.064103 -142.169188) (xy 333.064612 -142.197074) (xy 333.064103 -142.22496) (xy 333.055983 -142.280136)
			(xy 333.039915 -142.333543) (xy 333.016243 -142.38404) (xy 332.98547 -142.430553) (xy 332.948253 -142.47209)
			(xy 332.905385 -142.507765) (xy 332.857779 -142.536819) (xy 332.80645 -142.558631) (xy 332.752493 -142.572737)
			(xy 332.697056 -142.578837) (xy 332.641322 -142.5768) (xy 332.586479 -142.56667) (xy 332.533695 -142.548663)
			(xy 332.484095 -142.523162) (xy 332.438737 -142.490711) (xy 332.398588 -142.452002) (xy 332.364502 -142.407859)
			(xy 332.337206 -142.359224) (xy 332.317283 -142.307133) (xy 332.305157 -142.252696) (xy 332.301086 -142.197074)
			(xy 330.327 -142.197074) (xy 330.327 -142.698724) (xy 337.332572 -142.698724) (xy 337.336643 -142.643102)
			(xy 337.348769 -142.588665) (xy 337.368692 -142.536574) (xy 337.395988 -142.487939) (xy 337.430074 -142.443796)
			(xy 337.470223 -142.405087) (xy 337.515581 -142.372636) (xy 337.565181 -142.347135) (xy 337.617965 -142.329128)
			(xy 337.672808 -142.318998) (xy 337.728542 -142.316961) (xy 337.783979 -142.323061) (xy 337.837936 -142.337167)
			(xy 337.889265 -142.358979) (xy 337.936871 -142.388033) (xy 337.979739 -142.423708) (xy 338.016956 -142.465245)
			(xy 338.047729 -142.511758) (xy 338.071401 -142.562255) (xy 338.087469 -142.615662) (xy 338.095589 -142.670838)
			(xy 338.096098 -142.698724) (xy 338.095589 -142.72661) (xy 338.087469 -142.781786) (xy 338.071401 -142.835193)
			(xy 338.047729 -142.88569) (xy 338.016956 -142.932203) (xy 337.979739 -142.97374) (xy 337.936871 -143.009415)
			(xy 337.889265 -143.038469) (xy 337.837936 -143.060281) (xy 337.783979 -143.074387) (xy 337.728542 -143.080487)
			(xy 337.672808 -143.07845) (xy 337.617965 -143.06832) (xy 337.565181 -143.050313) (xy 337.515581 -143.024812)
			(xy 337.470223 -142.992361) (xy 337.430074 -142.953652) (xy 337.395988 -142.909509) (xy 337.368692 -142.860874)
			(xy 337.348769 -142.808783) (xy 337.336643 -142.754346) (xy 337.332572 -142.698724) (xy 330.327 -142.698724)
			(xy 330.327 -144.137888) (xy 330.326414 -144.163475) (xy 330.316296 -144.213636) (xy 330.306934 -144.237456)
			(xy 330.301854 -144.24914) (xy 330.30414 -144.27454) (xy 330.357988 -144.35582) (xy 330.365504 -144.366009)
			(xy 330.387763 -144.378003) (xy 330.400406 -144.37868) (xy 339.780118 -144.37868) (xy 339.790084 -144.378202)
			(xy 339.808519 -144.370625) (xy 339.815932 -144.363948) (xy 340.482174 -143.697706) (xy 340.489024 -143.690309)
			(xy 340.496765 -143.671711) (xy 340.49716 -143.661638) (xy 340.49716 -132.503418) (xy 340.496721 -132.493355)
			(xy 340.488981 -132.474776) (xy 340.482174 -132.46735) (xy 340.202266 -132.187442) (xy 340.194868 -132.180597)
			(xy 340.176269 -132.172868) (xy 340.166198 -132.172456) (xy 328.32929 -132.172456) (xy 328.319222 -132.172882)
			(xy 328.300625 -132.180606) (xy 328.293222 -132.187442) (xy 327.758806 -132.721858) (xy 327.758806 -132.727954)
			(xy 327.751967 -132.735355) (xy 327.744252 -132.753953) (xy 327.74382 -132.764022) (xy 327.74382 -133.355957)
			(xy 330.367519 -133.355957) (xy 330.367519 -133.301443) (xy 330.375278 -133.247483) (xy 330.390637 -133.195177)
			(xy 330.413285 -133.14559) (xy 330.442759 -133.09973) (xy 330.478461 -133.058533) (xy 330.519662 -133.022835)
			(xy 330.565525 -132.993366) (xy 330.615115 -132.970723) (xy 330.667422 -132.955369) (xy 330.721383 -132.947616)
			(xy 330.74864 -132.947156) (xy 330.763497 -132.947282) (xy 330.793122 -132.949572) (xy 330.807822 -132.951728)
			(xy 330.81849 -132.953506) (xy 330.838302 -132.948426) (xy 330.913486 -132.890514) (xy 330.923646 -132.872734)
			(xy 330.924662 -132.862066) (xy 330.92807 -132.834301) (xy 330.942037 -132.780133) (xy 330.96376 -132.728583)
			(xy 330.992775 -132.680757) (xy 331.028459 -132.637677) (xy 331.070049 -132.600266) (xy 331.116654 -132.569327)
			(xy 331.167275 -132.545521) (xy 331.220829 -132.529358) (xy 331.276168 -132.521184) (xy 331.304138 -132.52069)
			(xy 331.328938 -132.521109) (xy 331.378116 -132.527578) (xy 331.426042 -132.540362) (xy 331.471908 -132.559246)
			(xy 331.493622 -132.571236) (xy 331.50175 -132.575808) (xy 331.520038 -132.578602) (xy 331.604366 -132.56133)
			(xy 331.61986 -132.551424) (xy 331.625448 -132.543804) (xy 331.64358 -132.520479) (xy 331.68586 -132.479218)
			(xy 331.733991 -132.444961) (xy 331.786824 -132.418526) (xy 331.843099 -132.400546) (xy 331.901471 -132.391447)
			(xy 331.93101 -132.390896) (xy 331.958721 -132.391366) (xy 332.013559 -132.399387) (xy 332.06666 -132.415257)
			(xy 332.116906 -132.438643) (xy 332.163239 -132.469052) (xy 332.204686 -132.505846) (xy 332.240372 -132.548249)
			(xy 332.269548 -132.595369) (xy 332.2916 -132.646215) (xy 332.29931 -132.672836) (xy 332.301596 -132.681726)
			(xy 332.312518 -132.696712) (xy 332.384654 -132.743956) (xy 332.402688 -132.74802) (xy 332.412086 -132.74675)
			(xy 332.425788 -132.744864) (xy 332.453374 -132.742831) (xy 332.467204 -132.742686) (xy 332.494455 -132.743174)
			(xy 332.548402 -132.750931) (xy 332.600697 -132.766286) (xy 332.650274 -132.788927) (xy 332.696124 -132.818394)
			(xy 332.737314 -132.854085) (xy 332.773005 -132.895275) (xy 332.802472 -132.941125) (xy 332.825113 -132.990701)
			(xy 332.840469 -133.042996) (xy 332.848226 -133.096943) (xy 332.848712 -133.124194) (xy 332.848263 -133.150619)
			(xy 332.840943 -133.202961) (xy 332.826471 -133.253792) (xy 332.805124 -133.30214) (xy 332.777308 -133.347079)
			(xy 332.743558 -133.387751) (xy 332.704519 -133.423376) (xy 332.660937 -133.453273) (xy 332.613646 -133.476871)
			(xy 332.563552 -133.493717) (xy 332.511612 -133.50349) (xy 332.485238 -133.505194) (xy 332.475586 -133.505702)
			(xy 332.458568 -133.513068) (xy 332.396846 -133.574282) (xy 332.389226 -133.591046) (xy 332.388464 -133.600698)
			(xy 332.386225 -133.62945) (xy 332.374164 -133.685843) (xy 332.353749 -133.739777) (xy 332.325446 -133.790023)
			(xy 332.289901 -133.835434) (xy 332.247922 -133.874975) (xy 332.200469 -133.907745) (xy 332.148623 -133.932996)
			(xy 332.093565 -133.950152) (xy 332.036552 -133.958823) (xy 332.007718 -133.959346) (xy 331.98238 -133.958906)
			(xy 331.932151 -133.9522) (xy 331.883252 -133.938903) (xy 331.836543 -133.91925) (xy 331.792847 -133.893586)
			(xy 331.752933 -133.862364) (xy 331.734922 -133.844538) (xy 331.728064 -133.837426) (xy 331.7113 -133.829806)
			(xy 331.62367 -133.824472) (xy 331.606144 -133.83006) (xy 331.598524 -133.836156) (xy 331.578119 -133.851968)
			(xy 331.533876 -133.878562) (xy 331.486454 -133.898957) (xy 331.436718 -133.91278) (xy 331.385574 -133.91978)
			(xy 331.359764 -133.92023) (xy 331.330759 -133.919685) (xy 331.27342 -133.910885) (xy 331.218073 -133.893508)
			(xy 331.165993 -133.867956) (xy 331.118381 -133.834815) (xy 331.076333 -133.794851) (xy 331.040817 -133.748983)
			(xy 331.026262 -133.723888) (xy 331.02169 -133.715506) (xy 331.007466 -133.703822) (xy 330.92517 -133.675374)
			(xy 330.906628 -133.676136) (xy 330.897738 -133.679946) (xy 330.874067 -133.689537) (xy 330.8248 -133.703004)
			(xy 330.774177 -133.709781) (xy 330.74864 -133.710172) (xy 330.721383 -133.709784) (xy 330.667422 -133.702031)
			(xy 330.615115 -133.686677) (xy 330.565525 -133.664034) (xy 330.519662 -133.634565) (xy 330.478461 -133.598867)
			(xy 330.442759 -133.55767) (xy 330.413285 -133.51181) (xy 330.390637 -133.462223) (xy 330.375278 -133.409917)
			(xy 330.367519 -133.355957) (xy 327.74382 -133.355957) (xy 327.74382 -136.473946) (xy 330.23505 -136.473946)
			(xy 330.239121 -136.418324) (xy 330.251247 -136.363887) (xy 330.27117 -136.311796) (xy 330.298466 -136.263161)
			(xy 330.332552 -136.219018) (xy 330.372701 -136.180309) (xy 330.418059 -136.147858) (xy 330.467659 -136.122357)
			(xy 330.520443 -136.10435) (xy 330.575286 -136.09422) (xy 330.63102 -136.092183) (xy 330.686457 -136.098283)
			(xy 330.740414 -136.112389) (xy 330.791743 -136.134201) (xy 330.839349 -136.163255) (xy 330.882217 -136.19893)
			(xy 330.919434 -136.240467) (xy 330.950207 -136.28698) (xy 330.973879 -136.337477) (xy 330.989947 -136.390884)
			(xy 330.998067 -136.44606) (xy 330.998576 -136.473946) (xy 330.998067 -136.501832) (xy 330.989947 -136.557008)
			(xy 330.973879 -136.610415) (xy 330.950207 -136.660912) (xy 330.919434 -136.707425) (xy 330.882217 -136.748962)
			(xy 330.839349 -136.784637) (xy 330.791743 -136.813691) (xy 330.740414 -136.835503) (xy 330.686457 -136.849609)
			(xy 330.63102 -136.855709) (xy 330.575286 -136.853672) (xy 330.520443 -136.843542) (xy 330.467659 -136.825535)
			(xy 330.418059 -136.800034) (xy 330.372701 -136.767583) (xy 330.332552 -136.728874) (xy 330.298466 -136.684731)
			(xy 330.27117 -136.636096) (xy 330.251247 -136.584005) (xy 330.239121 -136.529568) (xy 330.23505 -136.473946)
			(xy 327.74382 -136.473946) (xy 327.74382 -143.826738) (xy 327.744251 -143.836805) (xy 327.751977 -143.855397)
			(xy 327.758806 -143.862806) (xy 328.259694 -144.363694) (xy 328.267092 -144.370542) (xy 328.28569 -144.37828)
			(xy 328.295762 -144.37868)
		)
		(stroke
			(width 0)
			(type solid)
		)
		(fill yes)
		(layer "In2.Cu")
		(net "GND")
	)
	(gr_poly
		(pts
			(xy 92.29852 -76.551536) (xy 92.308587 -76.551108) (xy 92.32718 -76.543381) (xy 92.334588 -76.53655)
			(xy 92.705174 -76.165964) (xy 92.712018 -76.158565) (xy 92.719743 -76.139966) (xy 92.72016 -76.129896)
			(xy 92.72016 -75.30846) (xy 92.720592 -75.298394) (xy 92.728323 -75.279806) (xy 92.735146 -75.272392)
			(xy 93.415358 -74.591926) (xy 93.422197 -74.584526) (xy 93.429912 -74.565927) (xy 93.430344 -74.555858)
			(xy 93.430344 -74.063606) (xy 93.430767 -74.053536) (xy 93.438485 -74.034934) (xy 93.44533 -74.027538)
			(xy 94.44863 -73.024238) (xy 94.455474 -73.01684) (xy 94.463197 -72.998241) (xy 94.463616 -72.98817)
			(xy 94.463616 -66.548) (xy 94.46404 -66.53793) (xy 94.471756 -66.519327) (xy 94.478602 -66.511932)
			(xy 97.66808 -63.322454) (xy 97.674922 -63.315054) (xy 97.682642 -63.296456) (xy 97.683066 -63.286386)
			(xy 97.683066 -56.746648) (xy 97.65792 -56.717946) (xy 97.63887 -56.715406) (xy 97.61168 -56.711355)
			(xy 97.558765 -56.696457) (xy 97.508536 -56.674118) (xy 97.462033 -56.644803) (xy 97.420218 -56.609117)
			(xy 97.383958 -56.5678) (xy 97.354002 -56.521706) (xy 97.330971 -56.471791) (xy 97.315343 -56.419087)
			(xy 97.307439 -56.364686) (xy 97.306892 -56.3372) (xy 97.307395 -56.309054) (xy 97.315662 -56.253371)
			(xy 97.332018 -56.199507) (xy 97.356108 -56.148629) (xy 97.387409 -56.101841) (xy 97.405952 -56.08066)
			(xy 97.412556 -56.073548) (xy 97.41916 -56.056276) (xy 97.41916 -56.01589) (xy 97.418734 -56.005822)
			(xy 97.411012 -55.987224) (xy 97.404174 -55.979822) (xy 96.600518 -55.176166) (xy 96.593406 -55.1688)
			(xy 96.57461 -55.16118) (xy 90.216228 -55.16118) (xy 90.206163 -55.161616) (xy 90.187576 -55.169346)
			(xy 90.18016 -55.176166) (xy 88.471974 -56.884352) (xy 90.020093 -56.884352) (xy 90.020093 -56.829848)
			(xy 90.027851 -56.775899) (xy 90.043207 -56.723603) (xy 90.06585 -56.674025) (xy 90.095319 -56.628175)
			(xy 90.131014 -56.586985) (xy 90.172207 -56.551295) (xy 90.21806 -56.521831) (xy 90.267641 -56.499193)
			(xy 90.319938 -56.483842) (xy 90.373888 -56.476091) (xy 90.40114 -56.47563) (xy 90.428272 -56.476087)
			(xy 90.481991 -56.48376) (xy 90.534082 -56.49896) (xy 90.583498 -56.521381) (xy 90.606626 -56.535574)
			(xy 90.61577 -56.541416) (xy 90.636344 -56.544718) (xy 90.729816 -56.52008) (xy 90.746072 -56.506872)
			(xy 90.751152 -56.49722) (xy 90.763029 -56.47547) (xy 90.791567 -56.434955) (xy 90.808048 -56.416448)
			(xy 90.814398 -56.40959) (xy 90.821256 -56.392572) (xy 90.823288 -56.30672) (xy 90.816938 -56.289194)
			(xy 90.811096 -56.282082) (xy 90.794181 -56.261331) (xy 90.765678 -56.216014) (xy 90.743784 -56.16716)
			(xy 90.728928 -56.115727) (xy 90.721402 -56.062723) (xy 90.720926 -56.035956) (xy 90.721337 -56.008702)
			(xy 90.7291 -55.95475) (xy 90.744463 -55.902452) (xy 90.767112 -55.852872) (xy 90.796586 -55.80702)
			(xy 90.832285 -55.76583) (xy 90.873483 -55.730139) (xy 90.919341 -55.700674) (xy 90.968925 -55.678036)
			(xy 91.021226 -55.662684) (xy 91.07518 -55.654931) (xy 91.102434 -55.654448) (xy 91.129806 -55.654882)
			(xy 91.183986 -55.662706) (xy 91.23649 -55.678202) (xy 91.286237 -55.701051) (xy 91.332202 -55.730783)
			(xy 91.353132 -55.748428) (xy 91.360244 -55.754524) (xy 91.377262 -55.760874) (xy 91.462606 -55.760874)
			(xy 91.479624 -55.754524) (xy 91.486736 -55.748428) (xy 91.507685 -55.73081) (xy 91.553653 -55.701094)
			(xy 91.603396 -55.678253) (xy 91.655893 -55.662758) (xy 91.710066 -55.654924) (xy 91.737434 -55.654448)
			(xy 91.764684 -55.654946) (xy 91.818629 -55.662706) (xy 91.870921 -55.678063) (xy 91.920495 -55.700705)
			(xy 91.966343 -55.730171) (xy 92.007532 -55.765861) (xy 92.043223 -55.807049) (xy 92.07269 -55.852896)
			(xy 92.095333 -55.90247) (xy 92.110692 -55.954761) (xy 92.118453 -56.008706) (xy 92.118942 -56.035956)
			(xy 92.118464 -56.063326) (xy 92.110651 -56.117505) (xy 92.095166 -56.170009) (xy 92.072326 -56.219756)
			(xy 92.042603 -56.265723) (xy 92.024962 -56.286654) (xy 92.018866 -56.293766) (xy 92.012516 -56.310784)
			(xy 92.012516 -56.355234) (xy 92.515688 -56.355234) (xy 92.519759 -56.299612) (xy 92.531885 -56.245175)
			(xy 92.551808 -56.193084) (xy 92.579104 -56.144449) (xy 92.61319 -56.100306) (xy 92.653339 -56.061597)
			(xy 92.698697 -56.029146) (xy 92.748297 -56.003645) (xy 92.801081 -55.985638) (xy 92.855924 -55.975508)
			(xy 92.911658 -55.973471) (xy 92.967095 -55.979571) (xy 93.021052 -55.993677) (xy 93.072381 -56.015489)
			(xy 93.119987 -56.044543) (xy 93.162855 -56.080218) (xy 93.200072 -56.121755) (xy 93.230845 -56.168268)
			(xy 93.254517 -56.218765) (xy 93.270585 -56.272172) (xy 93.278705 -56.327348) (xy 93.279214 -56.355234)
			(xy 93.278705 -56.38312) (xy 93.270585 -56.438296) (xy 93.268217 -56.446166) (xy 95.405954 -56.446166)
			(xy 95.410025 -56.390544) (xy 95.422151 -56.336107) (xy 95.442074 -56.284016) (xy 95.46937 -56.235381)
			(xy 95.503456 -56.191238) (xy 95.543605 -56.152529) (xy 95.588963 -56.120078) (xy 95.638563 -56.094577)
			(xy 95.691347 -56.07657) (xy 95.74619 -56.06644) (xy 95.801924 -56.064403) (xy 95.857361 -56.070503)
			(xy 95.911318 -56.084609) (xy 95.962647 -56.106421) (xy 96.010253 -56.135475) (xy 96.053121 -56.17115)
			(xy 96.090338 -56.212687) (xy 96.121111 -56.2592) (xy 96.144783 -56.309697) (xy 96.160851 -56.363104)
			(xy 96.168971 -56.41828) (xy 96.16948 -56.446166) (xy 96.168971 -56.474052) (xy 96.160851 -56.529228)
			(xy 96.144783 -56.582635) (xy 96.121111 -56.633132) (xy 96.090338 -56.679645) (xy 96.053121 -56.721182)
			(xy 96.010253 -56.756857) (xy 95.962647 -56.785911) (xy 95.911318 -56.807723) (xy 95.857361 -56.821829)
			(xy 95.801924 -56.827929) (xy 95.74619 -56.825892) (xy 95.691347 -56.815762) (xy 95.638563 -56.797755)
			(xy 95.588963 -56.772254) (xy 95.543605 -56.739803) (xy 95.503456 -56.701094) (xy 95.46937 -56.656951)
			(xy 95.442074 -56.608316) (xy 95.422151 -56.556225) (xy 95.410025 -56.501788) (xy 95.405954 -56.446166)
			(xy 93.268217 -56.446166) (xy 93.254517 -56.491703) (xy 93.230845 -56.5422) (xy 93.200072 -56.588713)
			(xy 93.162855 -56.63025) (xy 93.119987 -56.665925) (xy 93.072381 -56.694979) (xy 93.021052 -56.716791)
			(xy 92.967095 -56.730897) (xy 92.911658 -56.736997) (xy 92.855924 -56.73496) (xy 92.801081 -56.72483)
			(xy 92.748297 -56.706823) (xy 92.698697 -56.681322) (xy 92.653339 -56.648871) (xy 92.61319 -56.610162)
			(xy 92.579104 -56.566019) (xy 92.551808 -56.517384) (xy 92.531885 -56.465293) (xy 92.519759 -56.410856)
			(xy 92.515688 -56.355234) (xy 92.012516 -56.355234) (xy 92.012516 -56.396128) (xy 92.018866 -56.413146)
			(xy 92.024962 -56.420258) (xy 92.042589 -56.4412) (xy 92.072304 -56.487169) (xy 92.095143 -56.536914)
			(xy 92.110637 -56.589413) (xy 92.118467 -56.643587) (xy 92.118942 -56.670956) (xy 92.118404 -56.698206)
			(xy 92.110654 -56.752153) (xy 92.095305 -56.804447) (xy 92.07267 -56.854025) (xy 92.04321 -56.899876)
			(xy 92.007524 -56.941069) (xy 91.966339 -56.976763) (xy 91.920493 -57.006233) (xy 91.87092 -57.028878)
			(xy 91.818629 -57.044237) (xy 91.764684 -57.051998) (xy 91.737434 -57.052464) (xy 91.709558 -57.051985)
			(xy 91.6544 -57.043873) (xy 91.601011 -57.027817) (xy 91.550529 -57.004159) (xy 91.504029 -56.973402)
			(xy 91.482926 -56.955182) (xy 91.475814 -56.948832) (xy 91.458542 -56.942228) (xy 91.370912 -56.942736)
			(xy 91.353894 -56.949594) (xy 91.346782 -56.956198) (xy 91.325525 -56.974907) (xy 91.278569 -57.006553)
			(xy 91.22745 -57.030907) (xy 91.173291 -57.047436) (xy 91.117284 -57.055775) (xy 91.088972 -57.056274)
			(xy 91.06184 -57.055811) (xy 91.008122 -57.04814) (xy 90.95603 -57.032942) (xy 90.906614 -57.010523)
			(xy 90.883486 -56.99633) (xy 90.874342 -56.990488) (xy 90.853768 -56.987186) (xy 90.760296 -57.011824)
			(xy 90.74404 -57.025032) (xy 90.73896 -57.034684) (xy 90.726471 -57.057411) (xy 90.696332 -57.099611)
			(xy 90.660759 -57.137343) (xy 90.620405 -57.169911) (xy 90.576014 -57.196717) (xy 90.528402 -57.217268)
			(xy 90.478447 -57.231183) (xy 90.427068 -57.238209) (xy 90.40114 -57.238646) (xy 90.373888 -57.238109)
			(xy 90.319938 -57.230358) (xy 90.267641 -57.215007) (xy 90.21806 -57.192369) (xy 90.172207 -57.162905)
			(xy 90.131014 -57.127215) (xy 90.095319 -57.086025) (xy 90.06585 -57.040175) (xy 90.043207 -56.990597)
			(xy 90.027851 -56.938301) (xy 90.020093 -56.884352) (xy 88.471974 -56.884352) (xy 87.551768 -57.804558)
			(xy 87.544402 -57.81167) (xy 87.536782 -57.830466) (xy 87.536782 -58.21172) (xy 88.173812 -58.21172)
			(xy 88.177883 -58.156098) (xy 88.190009 -58.101661) (xy 88.209932 -58.04957) (xy 88.237228 -58.000935)
			(xy 88.271314 -57.956792) (xy 88.311463 -57.918083) (xy 88.356821 -57.885632) (xy 88.406421 -57.860131)
			(xy 88.459205 -57.842124) (xy 88.514048 -57.831994) (xy 88.569782 -57.829957) (xy 88.625219 -57.836057)
			(xy 88.679176 -57.850163) (xy 88.730505 -57.871975) (xy 88.778111 -57.901029) (xy 88.820979 -57.936704)
			(xy 88.858196 -57.978241) (xy 88.888969 -58.024754) (xy 88.912641 -58.075251) (xy 88.928709 -58.128658)
			(xy 88.932373 -58.153554) (xy 93.68104 -58.153554) (xy 93.685111 -58.097932) (xy 93.697237 -58.043495)
			(xy 93.71716 -57.991404) (xy 93.744456 -57.942769) (xy 93.778542 -57.898626) (xy 93.818691 -57.859917)
			(xy 93.864049 -57.827466) (xy 93.913649 -57.801965) (xy 93.966433 -57.783958) (xy 94.021276 -57.773828)
			(xy 94.07701 -57.771791) (xy 94.132447 -57.777891) (xy 94.186404 -57.791997) (xy 94.237733 -57.813809)
			(xy 94.285339 -57.842863) (xy 94.328207 -57.878538) (xy 94.365424 -57.920075) (xy 94.396197 -57.966588)
			(xy 94.419869 -58.017085) (xy 94.435937 -58.070492) (xy 94.444057 -58.125668) (xy 94.444566 -58.153554)
			(xy 94.444057 -58.18144) (xy 94.435937 -58.236616) (xy 94.419869 -58.290023) (xy 94.396197 -58.34052)
			(xy 94.365424 -58.387033) (xy 94.328207 -58.42857) (xy 94.285339 -58.464245) (xy 94.237733 -58.493299)
			(xy 94.186404 -58.515111) (xy 94.132447 -58.529217) (xy 94.07701 -58.535317) (xy 94.021276 -58.53328)
			(xy 93.966433 -58.52315) (xy 93.913649 -58.505143) (xy 93.864049 -58.479642) (xy 93.818691 -58.447191)
			(xy 93.778542 -58.408482) (xy 93.744456 -58.364339) (xy 93.71716 -58.315704) (xy 93.697237 -58.263613)
			(xy 93.685111 -58.209176) (xy 93.68104 -58.153554) (xy 88.932373 -58.153554) (xy 88.936829 -58.183834)
			(xy 88.937338 -58.21172) (xy 88.936829 -58.239606) (xy 88.928709 -58.294782) (xy 88.912641 -58.348189)
			(xy 88.888969 -58.398686) (xy 88.858196 -58.445199) (xy 88.820979 -58.486736) (xy 88.778111 -58.522411)
			(xy 88.730505 -58.551465) (xy 88.679176 -58.573277) (xy 88.640753 -58.583322) (xy 89.025982 -58.583322)
			(xy 89.030053 -58.5277) (xy 89.042179 -58.473263) (xy 89.062102 -58.421172) (xy 89.089398 -58.372537)
			(xy 89.123484 -58.328394) (xy 89.163633 -58.289685) (xy 89.208991 -58.257234) (xy 89.258591 -58.231733)
			(xy 89.311375 -58.213726) (xy 89.366218 -58.203596) (xy 89.421952 -58.201559) (xy 89.477389 -58.207659)
			(xy 89.531346 -58.221765) (xy 89.582675 -58.243577) (xy 89.630281 -58.272631) (xy 89.673149 -58.308306)
			(xy 89.710366 -58.349843) (xy 89.741139 -58.396356) (xy 89.764811 -58.446853) (xy 89.780879 -58.50026)
			(xy 89.788999 -58.555436) (xy 89.789508 -58.583322) (xy 89.788999 -58.611208) (xy 89.780879 -58.666384)
			(xy 89.764811 -58.719791) (xy 89.741139 -58.770288) (xy 89.710366 -58.816801) (xy 89.673149 -58.858338)
			(xy 89.630281 -58.894013) (xy 89.582675 -58.923067) (xy 89.531346 -58.944879) (xy 89.477389 -58.958985)
			(xy 89.421952 -58.965085) (xy 89.366218 -58.963048) (xy 89.311375 -58.952918) (xy 89.258591 -58.934911)
			(xy 89.208991 -58.90941) (xy 89.163633 -58.876959) (xy 89.123484 -58.83825) (xy 89.089398 -58.794107)
			(xy 89.062102 -58.745472) (xy 89.042179 -58.693381) (xy 89.030053 -58.638944) (xy 89.025982 -58.583322)
			(xy 88.640753 -58.583322) (xy 88.625219 -58.587383) (xy 88.569782 -58.593483) (xy 88.514048 -58.591446)
			(xy 88.459205 -58.581316) (xy 88.406421 -58.563309) (xy 88.356821 -58.537808) (xy 88.311463 -58.505357)
			(xy 88.271314 -58.466648) (xy 88.237228 -58.422505) (xy 88.209932 -58.37387) (xy 88.190009 -58.321779)
			(xy 88.177883 -58.267342) (xy 88.173812 -58.21172) (xy 87.536782 -58.21172) (xy 87.536782 -59.853322)
			(xy 89.025982 -59.853322) (xy 89.030053 -59.7977) (xy 89.042179 -59.743263) (xy 89.062102 -59.691172)
			(xy 89.089398 -59.642537) (xy 89.123484 -59.598394) (xy 89.163633 -59.559685) (xy 89.208991 -59.527234)
			(xy 89.258591 -59.501733) (xy 89.311375 -59.483726) (xy 89.366218 -59.473596) (xy 89.421952 -59.471559)
			(xy 89.477389 -59.477659) (xy 89.531346 -59.491765) (xy 89.582675 -59.513577) (xy 89.630281 -59.542631)
			(xy 89.673149 -59.578306) (xy 89.710366 -59.619843) (xy 89.741139 -59.666356) (xy 89.764811 -59.716853)
			(xy 89.780879 -59.77026) (xy 89.786075 -59.80557) (xy 93.68739 -59.80557) (xy 93.691461 -59.749948)
			(xy 93.703587 -59.695511) (xy 93.72351 -59.64342) (xy 93.750806 -59.594785) (xy 93.784892 -59.550642)
			(xy 93.825041 -59.511933) (xy 93.870399 -59.479482) (xy 93.919999 -59.453981) (xy 93.972783 -59.435974)
			(xy 94.027626 -59.425844) (xy 94.08336 -59.423807) (xy 94.138797 -59.429907) (xy 94.192754 -59.444013)
			(xy 94.244083 -59.465825) (xy 94.291689 -59.494879) (xy 94.334557 -59.530554) (xy 94.371774 -59.572091)
			(xy 94.402547 -59.618604) (xy 94.426219 -59.669101) (xy 94.442287 -59.722508) (xy 94.450407 -59.777684)
			(xy 94.450916 -59.80557) (xy 94.450407 -59.833456) (xy 94.442287 -59.888632) (xy 94.426219 -59.942039)
			(xy 94.402547 -59.992536) (xy 94.371774 -60.039049) (xy 94.334557 -60.080586) (xy 94.291689 -60.116261)
			(xy 94.244083 -60.145315) (xy 94.192754 -60.167127) (xy 94.138797 -60.181233) (xy 94.08336 -60.187333)
			(xy 94.027626 -60.185296) (xy 93.972783 -60.175166) (xy 93.919999 -60.157159) (xy 93.870399 -60.131658)
			(xy 93.825041 -60.099207) (xy 93.784892 -60.060498) (xy 93.750806 -60.016355) (xy 93.72351 -59.96772)
			(xy 93.703587 -59.915629) (xy 93.691461 -59.861192) (xy 93.68739 -59.80557) (xy 89.786075 -59.80557)
			(xy 89.788999 -59.825436) (xy 89.789508 -59.853322) (xy 89.788999 -59.881208) (xy 89.780879 -59.936384)
			(xy 89.764811 -59.989791) (xy 89.741139 -60.040288) (xy 89.710366 -60.086801) (xy 89.673149 -60.128338)
			(xy 89.630281 -60.164013) (xy 89.582675 -60.193067) (xy 89.531346 -60.214879) (xy 89.477389 -60.228985)
			(xy 89.421952 -60.235085) (xy 89.366218 -60.233048) (xy 89.311375 -60.222918) (xy 89.258591 -60.204911)
			(xy 89.208991 -60.17941) (xy 89.163633 -60.146959) (xy 89.123484 -60.10825) (xy 89.089398 -60.064107)
			(xy 89.062102 -60.015472) (xy 89.042179 -59.963381) (xy 89.030053 -59.908944) (xy 89.025982 -59.853322)
			(xy 87.536782 -59.853322) (xy 87.536782 -60.679584) (xy 92.469968 -60.679584) (xy 92.474039 -60.623962)
			(xy 92.486165 -60.569525) (xy 92.506088 -60.517434) (xy 92.533384 -60.468799) (xy 92.56747 -60.424656)
			(xy 92.607619 -60.385947) (xy 92.652977 -60.353496) (xy 92.702577 -60.327995) (xy 92.755361 -60.309988)
			(xy 92.810204 -60.299858) (xy 92.865938 -60.297821) (xy 92.921375 -60.303921) (xy 92.975332 -60.318027)
			(xy 93.026661 -60.339839) (xy 93.074267 -60.368893) (xy 93.117135 -60.404568) (xy 93.154352 -60.446105)
			(xy 93.185125 -60.492618) (xy 93.208797 -60.543115) (xy 93.224865 -60.596522) (xy 93.232985 -60.651698)
			(xy 93.233494 -60.679584) (xy 93.232985 -60.70747) (xy 93.224865 -60.762646) (xy 93.208797 -60.816053)
			(xy 93.18716 -60.86221) (xy 96.14103 -60.86221) (xy 96.145101 -60.806588) (xy 96.157227 -60.752151)
			(xy 96.17715 -60.70006) (xy 96.204446 -60.651425) (xy 96.238532 -60.607282) (xy 96.278681 -60.568573)
			(xy 96.324039 -60.536122) (xy 96.373639 -60.510621) (xy 96.426423 -60.492614) (xy 96.481266 -60.482484)
			(xy 96.537 -60.480447) (xy 96.592437 -60.486547) (xy 96.646394 -60.500653) (xy 96.697723 -60.522465)
			(xy 96.745329 -60.551519) (xy 96.788197 -60.587194) (xy 96.825414 -60.628731) (xy 96.856187 -60.675244)
			(xy 96.879859 -60.725741) (xy 96.895927 -60.779148) (xy 96.904047 -60.834324) (xy 96.904556 -60.86221)
			(xy 96.904047 -60.890096) (xy 96.895927 -60.945272) (xy 96.879859 -60.998679) (xy 96.856187 -61.049176)
			(xy 96.825414 -61.095689) (xy 96.788197 -61.137226) (xy 96.745329 -61.172901) (xy 96.697723 -61.201955)
			(xy 96.646394 -61.223767) (xy 96.592437 -61.237873) (xy 96.537 -61.243973) (xy 96.481266 -61.241936)
			(xy 96.426423 -61.231806) (xy 96.373639 -61.213799) (xy 96.324039 -61.188298) (xy 96.278681 -61.155847)
			(xy 96.238532 -61.117138) (xy 96.204446 -61.072995) (xy 96.17715 -61.02436) (xy 96.157227 -60.972269)
			(xy 96.145101 -60.917832) (xy 96.14103 -60.86221) (xy 93.18716 -60.86221) (xy 93.185125 -60.86655)
			(xy 93.154352 -60.913063) (xy 93.117135 -60.9546) (xy 93.074267 -60.990275) (xy 93.026661 -61.019329)
			(xy 92.975332 -61.041141) (xy 92.921375 -61.055247) (xy 92.865938 -61.061347) (xy 92.810204 -61.05931)
			(xy 92.755361 -61.04918) (xy 92.702577 -61.031173) (xy 92.652977 -61.005672) (xy 92.607619 -60.973221)
			(xy 92.56747 -60.934512) (xy 92.533384 -60.890369) (xy 92.506088 -60.841734) (xy 92.486165 -60.789643)
			(xy 92.474039 -60.735206) (xy 92.469968 -60.679584) (xy 87.536782 -60.679584) (xy 87.536782 -71.415148)
			(xy 87.55126 -71.439024) (xy 87.563706 -71.445882) (xy 87.587787 -71.459235) (xy 87.632182 -71.491808)
			(xy 87.671432 -71.530426) (xy 87.704722 -71.574286) (xy 87.731361 -71.622476) (xy 87.750794 -71.673996)
			(xy 87.762618 -71.727774) (xy 87.766588 -71.782693) (xy 87.76262 -71.837613) (xy 87.750798 -71.891392)
			(xy 87.731366 -71.942912) (xy 87.704729 -71.991103) (xy 87.671441 -72.034964) (xy 87.632192 -72.073583)
			(xy 87.587798 -72.106158) (xy 87.563706 -72.11949) (xy 87.55126 -72.126348) (xy 87.536782 -72.150224)
			(xy 87.536782 -75.018138) (xy 87.537211 -75.028206) (xy 87.544934 -75.046802) (xy 87.551768 -75.054206)
			(xy 89.034112 -76.53655) (xy 89.041509 -76.5434) (xy 89.060107 -76.551138) (xy 89.07018 -76.551536)
		)
		(stroke
			(width 0)
			(type solid)
		)
		(fill yes)
		(layer "In2.Cu")
		(net "GND")
	)
	(gr_poly
		(pts
			(xy 444.285116 -26.222198) (xy 444.29272 -26.220681) (xy 444.30655 -26.213691) (xy 444.312294 -26.208482)
			(xy 444.46825 -26.052526) (xy 444.468758 -26.052018) (xy 444.475335 -26.044635) (xy 444.482775 -26.026336)
			(xy 444.483236 -26.016458) (xy 444.483236 -25.193244) (xy 444.48367 -25.183179) (xy 444.491403 -25.164593)
			(xy 444.498222 -25.157176) (xy 445.08547 -24.569928) (xy 445.092871 -24.56309) (xy 445.11147 -24.555376)
			(xy 445.121538 -24.554942) (xy 445.158622 -24.554942) (xy 445.167004 -24.55418) (xy 445.174608 -24.552664)
			(xy 445.188439 -24.545674) (xy 445.194182 -24.540464) (xy 445.681608 -24.053038) (xy 445.689005 -24.046189)
			(xy 445.707604 -24.038451) (xy 445.717676 -24.038052) (xy 445.740282 -24.038052) (xy 445.748664 -24.03729)
			(xy 445.756271 -24.03578) (xy 445.770111 -24.028799) (xy 445.775842 -24.023574) (xy 445.835278 -23.964138)
			(xy 445.835786 -23.96363) (xy 445.842362 -23.956246) (xy 445.849801 -23.937948) (xy 445.850264 -23.92807)
			(xy 445.850264 -19.062954) (xy 445.849938 -19.053873) (xy 445.843686 -19.036826) (xy 445.838072 -19.02968)
			(xy 445.809056 -18.995106) (xy 445.757418 -18.92107) (xy 445.713548 -18.842183) (xy 445.677898 -18.759256)
			(xy 445.650834 -18.673143) (xy 445.632635 -18.584731) (xy 445.623489 -18.494931) (xy 445.622934 -18.449798)
			(xy 445.623503 -18.404667) (xy 445.63267 -18.314871) (xy 445.65088 -18.226465) (xy 445.677945 -18.140356)
			(xy 445.713587 -18.057429) (xy 445.757441 -17.978536) (xy 445.809055 -17.904487) (xy 445.838072 -17.869916)
			(xy 445.843694 -17.862776) (xy 445.849946 -17.845724) (xy 445.850264 -17.836642) (xy 445.850264 -17.183354)
			(xy 445.850697 -17.173289) (xy 445.858431 -17.154703) (xy 445.86525 -17.147286) (xy 446.037208 -16.975328)
			(xy 446.044606 -16.96848) (xy 446.063204 -16.960744) (xy 446.073276 -16.960342) (xy 450.688964 -16.960342)
			(xy 450.688964 -16.966692) (xy 451.362318 -17.640046) (xy 451.369166 -17.647443) (xy 451.376897 -17.666042)
			(xy 451.377304 -17.676114) (xy 451.377304 -18.602198) (xy 451.377761 -18.612077) (xy 451.385199 -18.63038)
			(xy 451.391782 -18.637758) (xy 451.392036 -18.638012) (xy 451.720458 -18.966434) (xy 451.720966 -18.966942)
			(xy 451.728347 -18.973524) (xy 451.746646 -18.980971) (xy 451.756526 -18.98142) (xy 452.519542 -18.98142)
			(xy 452.527924 -18.980658) (xy 452.535529 -18.979142) (xy 452.549363 -18.972157) (xy 452.555102 -18.966942)
			(xy 452.604378 -18.917666) (xy 452.604886 -18.917158) (xy 452.611467 -18.909776) (xy 452.618916 -18.891477)
			(xy 452.619364 -18.881598) (xy 452.619364 -18.623534) (xy 452.619801 -18.613471) (xy 452.627539 -18.59489)
			(xy 452.63435 -18.587466) (xy 454.246488 -16.975328) (xy 454.253885 -16.968477) (xy 454.272483 -16.960734)
			(xy 454.282556 -16.960342) (xy 455.233024 -16.960342) (xy 455.241406 -16.95958) (xy 455.24901 -16.958064)
			(xy 455.262841 -16.951074) (xy 455.268584 -16.945864) (xy 455.41819 -16.796258) (xy 455.418698 -16.79575)
			(xy 455.425287 -16.788371) (xy 455.432746 -16.770072) (xy 455.433176 -16.76019) (xy 455.433176 -14.434566)
			(xy 455.432746 -14.424499) (xy 455.42502 -14.405906) (xy 455.41819 -14.398498) (xy 454.97623 -13.956538)
			(xy 454.96883 -13.949698) (xy 454.950231 -13.941984) (xy 454.940162 -13.941552) (xy 453.10171 -13.941552)
			(xy 453.07377 -13.964666) (xy 453.070214 -13.982954) (xy 453.062122 -14.023189) (xy 453.0395 -14.102087)
			(xy 453.009706 -14.178565) (xy 452.972993 -14.251973) (xy 452.929674 -14.321687) (xy 452.880116 -14.387114)
			(xy 452.824742 -14.447697) (xy 452.764023 -14.502921) (xy 452.698474 -14.552317) (xy 452.628653 -14.595464)
			(xy 452.555154 -14.631995) (xy 452.478603 -14.6616) (xy 452.39965 -14.684027) (xy 452.318966 -14.699085)
			(xy 452.237238 -14.706646) (xy 452.1962 -14.707108) (xy 452.15523 -14.70664) (xy 452.073638 -14.699104)
			(xy 451.993084 -14.684098) (xy 451.914251 -14.661747) (xy 451.837808 -14.632241) (xy 451.764403 -14.595831)
			(xy 451.694656 -14.552824) (xy 451.62916 -14.503586) (xy 451.56847 -14.448533) (xy 451.5131 -14.388133)
			(xy 451.463518 -14.322896) (xy 451.420146 -14.253376) (xy 451.383351 -14.180163) (xy 451.367906 -14.142212)
			(xy 451.364676 -14.134734) (xy 451.354304 -14.122184) (xy 451.347586 -14.117574) (xy 451.326122 -14.103672)
			(xy 451.286766 -14.071018) (xy 451.25212 -14.033403) (xy 451.222805 -13.9915) (xy 451.21068 -13.968984)
			(xy 451.204076 -13.956284) (xy 451.179946 -13.941552) (xy 450.277484 -13.941552) (xy 450.249798 -13.963904)
			(xy 450.245988 -13.98143) (xy 450.236326 -14.023439) (xy 450.209931 -14.105505) (xy 450.175721 -14.184632)
			(xy 450.134015 -14.260078) (xy 450.085205 -14.331134) (xy 450.02975 -14.397136) (xy 449.968169 -14.457462)
			(xy 449.90104 -14.511547) (xy 449.828994 -14.558883) (xy 449.752705 -14.599027) (xy 449.672891 -14.631602)
			(xy 449.590299 -14.656302) (xy 449.505705 -14.672895) (xy 449.419903 -14.681226) (xy 449.3768 -14.681708)
			(xy 449.332888 -14.681174) (xy 449.245491 -14.672516) (xy 449.159371 -14.655293) (xy 449.075366 -14.629673)
			(xy 448.994292 -14.595906) (xy 448.916938 -14.554318) (xy 448.844055 -14.505316) (xy 448.809872 -14.477746)
			(xy 448.802736 -14.472372) (xy 448.785909 -14.466416) (xy 448.76806 -14.466562) (xy 448.75958 -14.469364)
			(xy 448.7186 -14.484381) (xy 448.634374 -14.507284) (xy 448.591432 -14.515084) (xy 448.58226 -14.517053)
			(xy 448.566103 -14.526557) (xy 448.559936 -14.533626) (xy 448.54114 -14.557502) (xy 448.535826 -14.564815)
			(xy 448.530229 -14.581991) (xy 448.530218 -14.59103) (xy 448.530472 -14.607032) (xy 448.529986 -14.634283)
			(xy 448.52223 -14.688231) (xy 448.506875 -14.740526) (xy 448.484233 -14.790103) (xy 448.454767 -14.835953)
			(xy 448.419076 -14.877144) (xy 448.377885 -14.912835) (xy 448.332035 -14.942301) (xy 448.282458 -14.964943)
			(xy 448.230163 -14.980298) (xy 448.176215 -14.988054) (xy 448.121713 -14.988054) (xy 448.067765 -14.980298)
			(xy 448.01547 -14.964943) (xy 447.965893 -14.942301) (xy 447.920043 -14.912835) (xy 447.878852 -14.877144)
			(xy 447.843161 -14.835953) (xy 447.813695 -14.790103) (xy 447.791053 -14.740526) (xy 447.775698 -14.688231)
			(xy 447.767942 -14.634283) (xy 447.767456 -14.607032) (xy 447.768023 -14.576842) (xy 447.777532 -14.517216)
			(xy 447.796332 -14.459838) (xy 447.823953 -14.406146) (xy 447.84137 -14.38148) (xy 447.846407 -14.37394)
			(xy 447.851353 -14.356506) (xy 447.851022 -14.347444) (xy 447.848482 -14.317218) (xy 447.847402 -14.307878)
			(xy 447.839308 -14.290921) (xy 447.832734 -14.284198) (xy 447.798686 -14.251142) (xy 447.73708 -14.178954)
			(xy 447.683507 -14.100619) (xy 447.638575 -14.017028) (xy 447.620136 -13.973302) (xy 447.615926 -13.964093)
			(xy 447.601683 -13.949725) (xy 447.583008 -13.941943) (xy 447.572892 -13.941552) (xy 445.889126 -13.941552)
			(xy 445.879063 -13.941114) (xy 445.860483 -13.933375) (xy 445.853058 -13.926566) (xy 445.671448 -13.744956)
			(xy 445.658748 -13.738098) (xy 445.651128 -13.736574) (xy 445.608845 -13.727387) (xy 445.526157 -13.701875)
			(xy 445.446337 -13.668458) (xy 445.370137 -13.62745) (xy 445.298278 -13.579239) (xy 445.231438 -13.524281)
			(xy 445.170248 -13.463094) (xy 445.115286 -13.396256) (xy 445.067072 -13.324399) (xy 445.026061 -13.248201)
			(xy 444.992639 -13.168383) (xy 444.967124 -13.085696) (xy 444.957962 -13.043408) (xy 444.956438 -13.035788)
			(xy 444.94958 -13.023088) (xy 444.16853 -12.242038) (xy 444.16169 -12.234638) (xy 444.153974 -12.216039)
			(xy 444.153544 -12.20597) (xy 444.153544 -10.602976) (xy 444.153455 -10.597956) (xy 444.151541 -10.588102)
			(xy 444.149734 -10.583418) (xy 444.138558 -10.557002) (xy 444.131446 -10.54989) (xy 444.101074 -10.518643)
			(xy 444.04591 -10.45118) (xy 443.997605 -10.378647) (xy 443.956623 -10.30174) (xy 443.923356 -10.221194)
			(xy 443.898123 -10.137782) (xy 443.881165 -10.052302) (xy 443.872645 -9.965575) (xy 443.872112 -9.922002)
			(xy 443.872112 -9.92124) (xy 443.874144 -9.86155) (xy 443.874906 -9.850374) (xy 443.867286 -9.830054)
			(xy 443.78499 -9.747758) (xy 443.777878 -9.740392) (xy 443.759082 -9.732772) (xy 441.562236 -9.732772)
			(xy 441.552172 -9.732337) (xy 441.533587 -9.724603) (xy 441.526168 -9.717786) (xy 441.476892 -9.66851)
			(xy 441.46978 -9.661144) (xy 441.450984 -9.653524) (xy 441.417202 -9.653524) (xy 441.416694 -9.653524)
			(xy 441.401779 -9.654164) (xy 441.373281 -9.663014) (xy 441.348557 -9.679721) (xy 441.329715 -9.70286)
			(xy 441.318364 -9.730456) (xy 441.315472 -9.760156) (xy 441.321286 -9.789424) (xy 441.33531 -9.815763)
			(xy 441.356347 -9.836926) (xy 441.369196 -9.844532) (xy 441.40717 -9.865681) (xy 441.479218 -9.914315)
			(xy 441.546177 -9.969746) (xy 441.607409 -10.031446) (xy 441.662328 -10.098826) (xy 441.710412 -10.171242)
			(xy 441.751201 -10.248004) (xy 441.784307 -10.32838) (xy 441.809412 -10.411602) (xy 441.826279 -10.496876)
			(xy 441.834745 -10.583389) (xy 441.835286 -10.626852) (xy 441.834848 -10.66514) (xy 441.828221 -10.741429)
			(xy 441.815071 -10.816867) (xy 441.795496 -10.890899) (xy 441.782962 -10.92708) (xy 441.780275 -10.935444)
			(xy 441.780283 -10.953002) (xy 441.782962 -10.96137) (xy 441.79554 -10.997571) (xy 441.815146 -11.071664)
			(xy 441.828297 -11.147171) (xy 441.834895 -11.22353) (xy 441.835286 -11.261852) (xy 441.834828 -11.302969)
			(xy 441.827244 -11.384852) (xy 441.812138 -11.465686) (xy 441.789638 -11.544781) (xy 441.759935 -11.621463)
			(xy 441.723284 -11.695077) (xy 441.679997 -11.764995) (xy 441.630443 -11.830621) (xy 441.575045 -11.891394)
			(xy 441.514276 -11.946797) (xy 441.448654 -11.996356) (xy 441.37874 -12.039649) (xy 441.305129 -12.076306)
			(xy 441.228449 -12.106015) (xy 441.149356 -12.128522) (xy 441.068523 -12.143635) (xy 440.986641 -12.151224)
			(xy 440.945524 -12.151614) (xy 440.904807 -12.151162) (xy 440.823713 -12.143727) (xy 440.743639 -12.128907)
			(xy 440.665256 -12.106827) (xy 440.589221 -12.077672) (xy 440.51617 -12.041685) (xy 440.481212 -12.020804)
			(xy 440.469296 -12.014026) (xy 440.442964 -12.006438) (xy 440.415562 -12.006123) (xy 440.389062 -12.013104)
			(xy 440.365372 -12.026879) (xy 440.346196 -12.046456) (xy 440.332915 -12.070427) (xy 440.326485 -12.097065)
			(xy 440.327368 -12.124455) (xy 440.331098 -12.137644) (xy 440.343762 -12.180344) (xy 440.361495 -12.267631)
			(xy 440.370416 -12.356253) (xy 440.370976 -12.400788) (xy 440.370433 -12.444263) (xy 440.361923 -12.530796)
			(xy 440.345022 -12.616089) (xy 440.319891 -12.699329) (xy 440.286768 -12.779724) (xy 440.266836 -12.818364)
			(xy 440.262961 -12.826487) (xy 440.260604 -12.844318) (xy 440.262264 -12.853162) (xy 440.271915 -12.900258)
			(xy 440.282225 -12.995845) (xy 440.282838 -13.043916) (xy 440.282346 -13.087058) (xy 440.274023 -13.172938)
			(xy 440.257418 -13.257608) (xy 440.232688 -13.340271) (xy 440.200065 -13.420149) (xy 440.159856 -13.49649)
			(xy 440.112439 -13.568576) (xy 440.085734 -13.602462) (xy 440.080146 -13.60932) (xy 440.074304 -13.625576)
			(xy 440.074304 -13.685012) (xy 440.079638 -13.685012) (xy 440.079638 -14.123162) (xy 440.586114 -14.123162)
			(xy 440.586548 -14.084874) (xy 440.593169 -14.008584) (xy 440.606317 -13.933144) (xy 440.625894 -13.859112)
			(xy 440.638438 -13.822934) (xy 440.641097 -13.814501) (xy 440.641085 -13.796828) (xy 440.638438 -13.78839)
			(xy 440.625872 -13.752219) (xy 440.606278 -13.678188) (xy 440.593129 -13.602746) (xy 440.586523 -13.526452)
			(xy 440.586114 -13.488162) (xy 440.586618 -13.445814) (xy 440.594669 -13.3615) (xy 440.610698 -13.278334)
			(xy 440.634559 -13.197067) (xy 440.666038 -13.118437) (xy 440.704849 -13.043156) (xy 440.750639 -12.971904)
			(xy 440.802995 -12.905328) (xy 440.861443 -12.84403) (xy 440.925453 -12.788565) (xy 440.994445 -12.739436)
			(xy 441.067795 -12.697087) (xy 441.144838 -12.661903) (xy 441.224877 -12.634201) (xy 441.307186 -12.614233)
			(xy 441.391021 -12.60218) (xy 441.475622 -12.59815) (xy 441.560223 -12.60218) (xy 441.644058 -12.614233)
			(xy 441.726367 -12.634201) (xy 441.806406 -12.661903) (xy 441.883449 -12.697087) (xy 441.956799 -12.739436)
			(xy 442.025791 -12.788565) (xy 442.089801 -12.84403) (xy 442.148249 -12.905328) (xy 442.200605 -12.971904)
			(xy 442.246395 -13.043156) (xy 442.285206 -13.118437) (xy 442.316685 -13.197067) (xy 442.340546 -13.278334)
			(xy 442.356575 -13.3615) (xy 442.364626 -13.445814) (xy 442.36513 -13.488162) (xy 442.364701 -13.52645)
			(xy 442.358077 -13.60274) (xy 442.344928 -13.67818) (xy 442.325351 -13.752212) (xy 442.312806 -13.78839)
			(xy 442.310183 -13.796833) (xy 442.310171 -13.814496) (xy 442.312806 -13.822934) (xy 442.325381 -13.859102)
			(xy 442.344972 -13.933134) (xy 442.358118 -14.008577) (xy 442.364722 -14.084872) (xy 442.36513 -14.123162)
			(xy 442.364626 -14.16551) (xy 442.356575 -14.249824) (xy 442.340546 -14.33299) (xy 442.316685 -14.414257)
			(xy 442.285206 -14.492887) (xy 442.246395 -14.568168) (xy 442.200605 -14.63942) (xy 442.186126 -14.657832)
			(xy 446.573146 -14.657832) (xy 446.577217 -14.60221) (xy 446.589343 -14.547773) (xy 446.609266 -14.495682)
			(xy 446.636562 -14.447047) (xy 446.670648 -14.402904) (xy 446.710797 -14.364195) (xy 446.756155 -14.331744)
			(xy 446.805755 -14.306243) (xy 446.858539 -14.288236) (xy 446.913382 -14.278106) (xy 446.969116 -14.276069)
			(xy 447.024553 -14.282169) (xy 447.07851 -14.296275) (xy 447.129839 -14.318087) (xy 447.177445 -14.347141)
			(xy 447.220313 -14.382816) (xy 447.25753 -14.424353) (xy 447.288303 -14.470866) (xy 447.311975 -14.521363)
			(xy 447.328043 -14.57477) (xy 447.336163 -14.629946) (xy 447.336672 -14.657832) (xy 447.336163 -14.685718)
			(xy 447.328043 -14.740894) (xy 447.311975 -14.794301) (xy 447.288303 -14.844798) (xy 447.25753 -14.891311)
			(xy 447.220313 -14.932848) (xy 447.177445 -14.968523) (xy 447.129839 -14.997577) (xy 447.07851 -15.019389)
			(xy 447.024553 -15.033495) (xy 446.969116 -15.039595) (xy 446.913382 -15.037558) (xy 446.858539 -15.027428)
			(xy 446.805755 -15.009421) (xy 446.756155 -14.98392) (xy 446.710797 -14.951469) (xy 446.670648 -14.91276)
			(xy 446.636562 -14.868617) (xy 446.609266 -14.819982) (xy 446.589343 -14.767891) (xy 446.577217 -14.713454)
			(xy 446.573146 -14.657832) (xy 442.186126 -14.657832) (xy 442.148249 -14.705996) (xy 442.089801 -14.767294)
			(xy 442.025791 -14.822759) (xy 441.956799 -14.871888) (xy 441.883449 -14.914237) (xy 441.806406 -14.949421)
			(xy 441.726367 -14.977123) (xy 441.644058 -14.997091) (xy 441.560223 -15.009144) (xy 441.475622 -15.013175)
			(xy 441.391021 -15.009144) (xy 441.307186 -14.997091) (xy 441.224877 -14.977123) (xy 441.144838 -14.949421)
			(xy 441.067795 -14.914237) (xy 440.994445 -14.871888) (xy 440.925453 -14.822759) (xy 440.861443 -14.767294)
			(xy 440.802995 -14.705996) (xy 440.750639 -14.63942) (xy 440.704849 -14.568168) (xy 440.666038 -14.492887)
			(xy 440.634559 -14.414257) (xy 440.610698 -14.33299) (xy 440.594669 -14.249824) (xy 440.586618 -14.16551)
			(xy 440.586114 -14.123162) (xy 440.079638 -14.123162) (xy 440.079638 -19.21256) (xy 440.97321 -19.21256)
			(xy 440.973709 -19.185191) (xy 440.981518 -19.131013) (xy 440.997 -19.07851) (xy 441.019834 -19.028763)
			(xy 441.049552 -18.982795) (xy 441.06719 -18.961862) (xy 441.073286 -18.95475) (xy 441.079636 -18.937732)
			(xy 441.079636 -18.852388) (xy 441.073286 -18.83537) (xy 441.06719 -18.828258) (xy 441.049563 -18.807316)
			(xy 441.01985 -18.761346) (xy 440.997012 -18.711601) (xy 440.981518 -18.659102) (xy 440.973686 -18.604928)
			(xy 440.97321 -18.57756) (xy 440.973696 -18.550309) (xy 440.981452 -18.496361) (xy 440.996807 -18.444066)
			(xy 441.019449 -18.394489) (xy 441.048915 -18.348639) (xy 441.084606 -18.307448) (xy 441.125797 -18.271757)
			(xy 441.171647 -18.242291) (xy 441.221224 -18.219649) (xy 441.273519 -18.204294) (xy 441.327467 -18.196538)
			(xy 441.381969 -18.196538) (xy 441.435917 -18.204294) (xy 441.488212 -18.219649) (xy 441.537789 -18.242291)
			(xy 441.583639 -18.271757) (xy 441.62483 -18.307448) (xy 441.660521 -18.348639) (xy 441.689987 -18.394489)
			(xy 441.712629 -18.444066) (xy 441.727984 -18.496361) (xy 441.73574 -18.550309) (xy 441.736226 -18.57756)
			(xy 441.735755 -18.60493) (xy 441.727941 -18.65911) (xy 441.712454 -18.711614) (xy 441.689613 -18.761361)
			(xy 441.659888 -18.807327) (xy 441.642246 -18.828258) (xy 441.63615 -18.83537) (xy 441.6298 -18.852388)
			(xy 441.6298 -18.937732) (xy 441.63615 -18.95475) (xy 441.642246 -18.961862) (xy 441.659872 -18.982805)
			(xy 441.689588 -19.028774) (xy 441.712427 -19.078518) (xy 441.727921 -19.131017) (xy 441.735751 -19.185191)
			(xy 441.736226 -19.21256) (xy 441.73574 -19.239811) (xy 441.727984 -19.293759) (xy 441.712629 -19.346054)
			(xy 441.689987 -19.395631) (xy 441.660521 -19.441481) (xy 441.62483 -19.482672) (xy 441.583639 -19.518363)
			(xy 441.537789 -19.547829) (xy 441.488212 -19.570471) (xy 441.435917 -19.585826) (xy 441.381969 -19.593582)
			(xy 441.327467 -19.593582) (xy 441.273519 -19.585826) (xy 441.221224 -19.570471) (xy 441.171647 -19.547829)
			(xy 441.125797 -19.518363) (xy 441.084606 -19.482672) (xy 441.048915 -19.441481) (xy 441.019449 -19.395631)
			(xy 440.996807 -19.346054) (xy 440.981452 -19.293759) (xy 440.973696 -19.239811) (xy 440.97321 -19.21256)
			(xy 440.079638 -19.21256) (xy 440.079638 -20.73656) (xy 440.97321 -20.73656) (xy 440.973709 -20.709191)
			(xy 440.981518 -20.655013) (xy 440.997 -20.60251) (xy 441.019834 -20.552763) (xy 441.049552 -20.506795)
			(xy 441.06719 -20.485862) (xy 441.073286 -20.47875) (xy 441.079636 -20.461732) (xy 441.079636 -20.376388)
			(xy 441.073286 -20.35937) (xy 441.06719 -20.352258) (xy 441.049563 -20.331316) (xy 441.01985 -20.285346)
			(xy 440.997012 -20.235601) (xy 440.981518 -20.183102) (xy 440.973686 -20.128928) (xy 440.97321 -20.10156)
			(xy 440.973696 -20.074309) (xy 440.981452 -20.020361) (xy 440.996807 -19.968066) (xy 441.019449 -19.918489)
			(xy 441.048915 -19.872639) (xy 441.084606 -19.831448) (xy 441.125797 -19.795757) (xy 441.171647 -19.766291)
			(xy 441.221224 -19.743649) (xy 441.273519 -19.728294) (xy 441.327467 -19.720538) (xy 441.381969 -19.720538)
			(xy 441.435917 -19.728294) (xy 441.488212 -19.743649) (xy 441.537789 -19.766291) (xy 441.583639 -19.795757)
			(xy 441.62483 -19.831448) (xy 441.660521 -19.872639) (xy 441.689987 -19.918489) (xy 441.712629 -19.968066)
			(xy 441.727984 -20.020361) (xy 441.73574 -20.074309) (xy 441.736226 -20.10156) (xy 441.735755 -20.12893)
			(xy 441.727941 -20.18311) (xy 441.712454 -20.235614) (xy 441.689613 -20.285361) (xy 441.659888 -20.331327)
			(xy 441.642246 -20.352258) (xy 441.63615 -20.35937) (xy 441.6298 -20.376388) (xy 441.6298 -20.461732)
			(xy 441.63615 -20.47875) (xy 441.642246 -20.485862) (xy 441.659872 -20.506805) (xy 441.689588 -20.552774)
			(xy 441.712427 -20.602518) (xy 441.727921 -20.655017) (xy 441.735751 -20.709191) (xy 441.736226 -20.73656)
			(xy 441.73574 -20.763811) (xy 441.727984 -20.817759) (xy 441.712629 -20.870054) (xy 441.689987 -20.919631)
			(xy 441.660521 -20.965481) (xy 441.62483 -21.006672) (xy 441.583639 -21.042363) (xy 441.537789 -21.071829)
			(xy 441.488212 -21.094471) (xy 441.435917 -21.109826) (xy 441.381969 -21.117582) (xy 441.327467 -21.117582)
			(xy 441.273519 -21.109826) (xy 441.221224 -21.094471) (xy 441.171647 -21.071829) (xy 441.125797 -21.042363)
			(xy 441.084606 -21.006672) (xy 441.048915 -20.965481) (xy 441.019449 -20.919631) (xy 440.996807 -20.870054)
			(xy 440.981452 -20.817759) (xy 440.973696 -20.763811) (xy 440.97321 -20.73656) (xy 440.079638 -20.73656)
			(xy 440.079638 -22.414992) (xy 440.08006 -22.425062) (xy 440.087777 -22.443665) (xy 440.094624 -22.45106)
			(xy 440.69889 -23.055326) (xy 440.705733 -23.062726) (xy 440.71346 -23.081324) (xy 440.713876 -23.091394)
			(xy 440.713876 -23.5781) (xy 441.09303 -23.5781) (xy 441.09706 -23.493493) (xy 441.109115 -23.409651)
			(xy 441.129085 -23.327336) (xy 441.156789 -23.247291) (xy 441.191976 -23.170243) (xy 441.234328 -23.096888)
			(xy 441.283461 -23.027891) (xy 441.338931 -22.963876) (xy 441.400234 -22.905425) (xy 441.466816 -22.853065)
			(xy 441.538073 -22.807272) (xy 441.613361 -22.76846) (xy 441.691997 -22.73698) (xy 441.77327 -22.713117)
			(xy 441.856442 -22.697088) (xy 441.940762 -22.689038) (xy 441.983114 -22.68855) (xy 442.025557 -22.689042)
			(xy 442.110058 -22.69713) (xy 442.193403 -22.713231) (xy 442.274836 -22.737198) (xy 442.353615 -22.768813)
			(xy 442.391546 -22.787864) (xy 442.40271 -22.792845) (xy 442.427118 -22.792845) (xy 442.438282 -22.787864)
			(xy 442.476212 -22.768812) (xy 442.554991 -22.737195) (xy 442.636424 -22.713228) (xy 442.71977 -22.697128)
			(xy 442.804271 -22.689042) (xy 442.846714 -22.68855) (xy 442.88906 -22.689138) (xy 442.973369 -22.69719)
			(xy 443.05653 -22.713219) (xy 443.137791 -22.737081) (xy 443.216416 -22.768559) (xy 443.291693 -22.807368)
			(xy 443.36294 -22.853156) (xy 443.429513 -22.90551) (xy 443.490807 -22.963955) (xy 443.546268 -23.027961)
			(xy 443.595394 -23.09695) (xy 443.637739 -23.170296) (xy 443.672921 -23.247335) (xy 443.700621 -23.327369)
			(xy 443.720588 -23.409674) (xy 443.732641 -23.493504) (xy 443.736671 -23.5781) (xy 443.732641 -23.662696)
			(xy 443.720588 -23.746526) (xy 443.700621 -23.828831) (xy 443.672921 -23.908865) (xy 443.637739 -23.985904)
			(xy 443.595394 -24.05925) (xy 443.546268 -24.128239) (xy 443.490807 -24.192245) (xy 443.429513 -24.25069)
			(xy 443.36294 -24.303044) (xy 443.291693 -24.348832) (xy 443.216416 -24.387641) (xy 443.137791 -24.419119)
			(xy 443.05653 -24.442981) (xy 442.973369 -24.45901) (xy 442.88906 -24.467062) (xy 442.846714 -24.467566)
			(xy 442.804271 -24.467061) (xy 442.719771 -24.458976) (xy 442.636426 -24.442878) (xy 442.554993 -24.418914)
			(xy 442.476213 -24.387301) (xy 442.438282 -24.368252) (xy 442.427118 -24.363271) (xy 442.40271 -24.363271)
			(xy 442.391546 -24.368252) (xy 442.353611 -24.387295) (xy 442.274834 -24.418913) (xy 442.193402 -24.442882)
			(xy 442.110057 -24.458984) (xy 442.025557 -24.467073) (xy 441.983114 -24.467566) (xy 441.940762 -24.467162)
			(xy 441.856442 -24.459112) (xy 441.77327 -24.443083) (xy 441.691997 -24.41922) (xy 441.613361 -24.38774)
			(xy 441.538073 -24.348928) (xy 441.466816 -24.303135) (xy 441.400234 -24.250775) (xy 441.338931 -24.192324)
			(xy 441.283461 -24.128309) (xy 441.234328 -24.059312) (xy 441.191976 -23.985957) (xy 441.156789 -23.908909)
			(xy 441.129085 -23.828864) (xy 441.109115 -23.746549) (xy 441.09706 -23.662707) (xy 441.09303 -23.5781)
			(xy 440.713876 -23.5781) (xy 440.713876 -26.17216) (xy 440.714288 -26.182188) (xy 440.72195 -26.200723)
			(xy 440.736123 -26.214914) (xy 440.754648 -26.222599) (xy 440.764676 -26.22296) (xy 444.276734 -26.22296)
		)
		(stroke
			(width 0)
			(type solid)
		)
		(fill yes)
		(layer "In2.Cu")
		(net "P12V_OCP_SFF")
	)
	(gr_poly
		(pts
			(xy 294.642794 -393.57427) (xy 294.649906 -393.568428) (xy 294.651938 -393.56665) (xy 294.658967 -393.560093)
			(xy 294.667971 -393.543126) (xy 294.669464 -393.53363) (xy 294.67302 -393.502642) (xy 294.673618 -393.493219)
			(xy 294.668791 -393.474984) (xy 294.663622 -393.467082) (xy 294.646636 -393.442557) (xy 294.619685 -393.389338)
			(xy 294.601349 -393.332572) (xy 294.592074 -393.273643) (xy 294.591486 -393.243816) (xy 294.591931 -393.217448)
			(xy 294.599196 -393.165215) (xy 294.61359 -393.114481) (xy 294.634837 -393.066215) (xy 294.662533 -393.021337)
			(xy 294.696149 -392.980703) (xy 294.735044 -392.94509) (xy 294.778475 -392.915177) (xy 294.825614 -392.891533)
			(xy 294.875561 -392.874611) (xy 294.901366 -392.869166) (xy 294.910478 -392.86697) (xy 294.926383 -392.857084)
			(xy 294.932354 -392.849862) (xy 294.95115 -392.825224) (xy 294.956548 -392.817345) (xy 294.961619 -392.798946)
			(xy 294.961056 -392.78941) (xy 294.959819 -392.775474) (xy 294.958548 -392.747521) (xy 294.958516 -392.73353)
			(xy 294.958933 -392.701726) (xy 294.966031 -392.638515) (xy 294.980164 -392.576497) (xy 295.001154 -392.516453)
			(xy 295.028737 -392.459136) (xy 295.062565 -392.40527) (xy 295.102214 -392.355531) (xy 295.124378 -392.332718)
			(xy 295.67886 -391.778236) (xy 295.685554 -391.77083) (xy 295.693156 -391.752394) (xy 295.693592 -391.742422)
			(xy 295.693592 -389.37692) (xy 295.694022 -389.345108) (xy 295.701148 -389.281885) (xy 295.715313 -389.219858)
			(xy 295.736338 -389.159808) (xy 295.763959 -389.102493) (xy 295.797827 -389.048633) (xy 295.837517 -388.998906)
			(xy 295.859708 -388.976108) (xy 296.636948 -388.198868) (xy 296.65974 -388.176672) (xy 296.709472 -388.136991)
			(xy 296.763336 -388.103131) (xy 296.820652 -388.075515) (xy 296.880701 -388.054492) (xy 296.942727 -388.040327)
			(xy 297.005949 -388.033197) (xy 297.03776 -388.032752) (xy 297.565826 -388.032752) (xy 297.57579 -388.032272)
			(xy 297.594221 -388.024689) (xy 297.60164 -388.01802) (xy 297.660314 -387.959346) (xy 297.667161 -387.951949)
			(xy 297.674889 -387.933349) (xy 297.6753 -387.923278) (xy 297.6753 -386.335524) (xy 297.674651 -386.323591)
			(xy 297.663911 -386.302278) (xy 297.654726 -386.29463) (xy 297.579034 -386.239004) (xy 297.555158 -386.23494)
			(xy 297.543474 -386.238496) (xy 297.515911 -386.246542) (xy 297.459152 -386.25521) (xy 297.430444 -386.255768)
			(xy 297.40319 -386.255308) (xy 297.349237 -386.247556) (xy 297.296936 -386.232203) (xy 297.247353 -386.209562)
			(xy 297.201497 -386.180095) (xy 297.160302 -386.144401) (xy 297.124607 -386.103206) (xy 297.09514 -386.057351)
			(xy 297.072498 -386.007768) (xy 297.057145 -385.955467) (xy 297.049393 -385.901514) (xy 297.048936 -385.87426)
			(xy 297.049952 -385.845558) (xy 297.050968 -385.83235) (xy 297.040046 -385.808728) (xy 296.949368 -385.741926)
			(xy 296.92346 -385.738624) (xy 296.911014 -385.743704) (xy 296.888504 -385.752242) (xy 296.841878 -385.764233)
			(xy 296.794116 -385.770273) (xy 296.770044 -385.770628) (xy 296.742788 -385.770168) (xy 296.688829 -385.762416)
			(xy 296.636523 -385.747063) (xy 296.586935 -385.724422) (xy 296.541074 -385.694953) (xy 296.499874 -385.659258)
			(xy 296.464173 -385.618062) (xy 296.4347 -385.572204) (xy 296.412053 -385.522618) (xy 296.396694 -385.470314)
			(xy 296.388935 -385.416356) (xy 296.388935 -385.361844) (xy 296.396694 -385.307886) (xy 296.412053 -385.255582)
			(xy 296.4347 -385.205996) (xy 296.464173 -385.160138) (xy 296.499874 -385.118942) (xy 296.541074 -385.083247)
			(xy 296.586935 -385.053778) (xy 296.636523 -385.031137) (xy 296.688829 -385.015784) (xy 296.742788 -385.008032)
			(xy 296.770044 -385.007612) (xy 296.799482 -385.008159) (xy 296.857656 -385.017222) (xy 296.885868 -385.025646)
			(xy 296.894485 -385.027949) (xy 296.91229 -385.027183) (xy 296.920666 -385.024122) (xy 296.94886 -385.012184)
			(xy 296.957093 -385.008359) (xy 296.97037 -384.995996) (xy 296.974768 -384.988054) (xy 296.987951 -384.962369)
			(xy 297.01927 -384.913867) (xy 297.037252 -384.89128) (xy 297.04259 -384.884302) (xy 297.048578 -384.867799)
			(xy 297.048936 -384.859022) (xy 297.048936 -384.705098) (xy 297.048531 -384.696327) (xy 297.042569 -384.679825)
			(xy 297.037252 -384.67284) (xy 297.019255 -384.650264) (xy 296.987942 -384.601756) (xy 296.974768 -384.576066)
			(xy 296.970359 -384.568136) (xy 296.957076 -384.555792) (xy 296.94886 -384.551936) (xy 296.920666 -384.539998)
			(xy 296.9123 -384.536882) (xy 296.894475 -384.536104) (xy 296.885868 -384.538474) (xy 296.857654 -384.546889)
			(xy 296.799481 -384.555945) (xy 296.770044 -384.556508) (xy 296.742789 -384.556048) (xy 296.688833 -384.548296)
			(xy 296.63653 -384.532944) (xy 296.586945 -384.510304) (xy 296.541086 -384.480837) (xy 296.499888 -384.445143)
			(xy 296.46419 -384.403949) (xy 296.434718 -384.358094) (xy 296.412072 -384.308511) (xy 296.396714 -384.25621)
			(xy 296.388955 -384.202255) (xy 296.388955 -384.147745) (xy 296.396714 -384.09379) (xy 296.412072 -384.041489)
			(xy 296.434718 -383.991906) (xy 296.46419 -383.946051) (xy 296.499888 -383.904857) (xy 296.541086 -383.869163)
			(xy 296.586945 -383.839696) (xy 296.63653 -383.817056) (xy 296.688833 -383.801704) (xy 296.742789 -383.793952)
			(xy 296.770044 -383.793492) (xy 296.794117 -383.793838) (xy 296.841884 -383.799862) (xy 296.888511 -383.811859)
			(xy 296.911014 -383.820416) (xy 296.92346 -383.825496) (xy 296.949368 -383.822194) (xy 297.040046 -383.755392)
			(xy 297.050968 -383.73177) (xy 297.049952 -383.718562) (xy 297.048936 -383.68986) (xy 297.049402 -383.66261)
			(xy 297.057164 -383.608666) (xy 297.072524 -383.556375) (xy 297.095169 -383.506803) (xy 297.124639 -383.460958)
			(xy 297.160333 -383.419774) (xy 297.201525 -383.384089) (xy 297.247377 -383.354629) (xy 297.296954 -383.331994)
			(xy 297.349248 -383.316646) (xy 297.403194 -383.308896) (xy 297.430444 -383.308352) (xy 297.459152 -383.308909)
			(xy 297.515911 -383.317579) (xy 297.543474 -383.325624) (xy 297.555158 -383.32918) (xy 297.579034 -383.325116)
			(xy 297.654726 -383.26949) (xy 297.663946 -383.261876) (xy 297.674665 -383.240538) (xy 297.6753 -383.228596)
			(xy 297.6753 -381.635762) (xy 297.674756 -381.625778) (xy 297.667033 -381.607356) (xy 297.660314 -381.599948)
			(xy 297.550586 -381.49022) (xy 297.533515 -381.472516) (xy 297.504596 -381.432738) (xy 297.482264 -381.388923)
			(xy 297.467068 -381.34215) (xy 297.459384 -381.293576) (xy 297.458892 -381.268986) (xy 297.458892 -378.826522)
			(xy 297.458403 -378.816561) (xy 297.450812 -378.79814) (xy 297.44416 -378.790708) (xy 296.475912 -377.82246)
			(xy 296.468501 -377.815778) (xy 296.450066 -377.808198) (xy 296.440098 -377.807728) (xy 289.35172 -377.807728)
			(xy 289.327128 -377.807272) (xy 289.27855 -377.799579) (xy 289.231774 -377.784379) (xy 289.187953 -377.762046)
			(xy 289.148167 -377.733132) (xy 289.130486 -377.716034) (xy 288.635186 -377.220734) (xy 288.627228 -377.213469)
			(xy 288.607098 -377.205836) (xy 288.596324 -377.206002) (xy 288.509456 -377.211336) (xy 288.490152 -377.221496)
			(xy 288.483294 -377.230132) (xy 288.462579 -377.255811) (xy 288.415591 -377.302126) (xy 288.363007 -377.341975)
			(xy 288.30571 -377.374687) (xy 288.244664 -377.399714) (xy 288.180894 -377.416636) (xy 288.115471 -377.425167)
			(xy 288.082482 -377.425712) (xy 288.052671 -377.425272) (xy 287.993462 -377.418272) (xy 287.964372 -377.411742)
			(xy 287.955116 -377.409936) (xy 287.936452 -377.41254) (xy 287.92805 -377.416822) (xy 287.901126 -377.431808)
			(xy 287.893018 -377.436682) (xy 287.880866 -377.451161) (xy 287.877504 -377.460002) (xy 287.866957 -377.489924)
			(xy 287.839461 -377.5471) (xy 287.805066 -377.600412) (xy 287.764308 -377.649033) (xy 287.717819 -377.692206)
			(xy 287.66632 -377.729262) (xy 287.610613 -377.759625) (xy 287.551562 -377.782823) (xy 287.490084 -377.798496)
			(xy 287.427134 -377.806401) (xy 287.395412 -377.806966) (xy 287.363452 -377.806486) (xy 287.300035 -377.798476)
			(xy 287.238123 -377.782581) (xy 287.178691 -377.759051) (xy 287.122676 -377.728258) (xy 287.070963 -377.690687)
			(xy 287.024367 -377.646931) (xy 286.983622 -377.59768) (xy 286.949371 -377.543711) (xy 286.922155 -377.485874)
			(xy 286.902402 -377.425082) (xy 286.890424 -377.362294) (xy 286.88641 -377.2985) (xy 286.890424 -377.234706)
			(xy 286.902402 -377.171918) (xy 286.922155 -377.111126) (xy 286.949371 -377.053289) (xy 286.983622 -376.99932)
			(xy 287.024367 -376.950069) (xy 287.070963 -376.906313) (xy 287.122676 -376.868742) (xy 287.178691 -376.837949)
			(xy 287.238123 -376.814419) (xy 287.300035 -376.798524) (xy 287.363452 -376.790514) (xy 287.395412 -376.78995)
			(xy 287.425223 -376.79039) (xy 287.484432 -376.797389) (xy 287.513522 -376.80392) (xy 287.522778 -376.805728)
			(xy 287.541443 -376.803123) (xy 287.549844 -376.79884) (xy 287.576768 -376.783854) (xy 287.584873 -376.778979)
			(xy 287.597017 -376.764496) (xy 287.60039 -376.75566) (xy 287.610063 -376.728034) (xy 287.634883 -376.675021)
			(xy 287.665627 -376.62521) (xy 287.683448 -376.60199) (xy 287.692592 -376.59056) (xy 287.69564 -376.561858)
			(xy 287.649412 -376.4661) (xy 287.644903 -376.457723) (xy 287.630922 -376.444841) (xy 287.613199 -376.437964)
			(xy 287.603692 -376.437652) (xy 283.36367 -376.437652) (xy 283.353706 -376.438133) (xy 283.335277 -376.445717)
			(xy 283.327856 -376.452384) (xy 283.0195 -376.76074) (xy 283.012896 -376.788934) (xy 283.017722 -376.80265)
			(xy 283.0273 -376.83209) (xy 283.040736 -376.892526) (xy 283.04751 -376.954066) (xy 283.047948 -376.985022)
			(xy 283.047948 -378.470668) (xy 285.209742 -378.470668) (xy 285.210303 -378.437329) (xy 285.219017 -378.371223)
			(xy 285.23629 -378.306822) (xy 285.261827 -378.245228) (xy 285.295191 -378.187497) (xy 285.335809 -378.134619)
			(xy 285.382986 -378.0875) (xy 285.409132 -378.066808) (xy 285.415944 -378.061125) (xy 285.425558 -378.046236)
			(xy 285.429504 -378.028958) (xy 285.427306 -378.011371) (xy 285.42361 -378.003308) (xy 285.410334 -377.976396)
			(xy 285.389515 -377.920113) (xy 285.375477 -377.861767) (xy 285.368417 -377.802173) (xy 285.367984 -377.772168)
			(xy 285.368487 -377.741122) (xy 285.376047 -377.679492) (xy 285.391052 -377.619241) (xy 285.413277 -377.561263)
			(xy 285.442393 -377.506421) (xy 285.477967 -377.45553) (xy 285.51947 -377.409346) (xy 285.566284 -377.368557)
			(xy 285.617715 -377.333768) (xy 285.672997 -377.305496) (xy 285.701994 -377.294394) (xy 285.710478 -377.290954)
			(xy 285.724409 -377.279099) (xy 285.729172 -377.27128) (xy 285.743904 -377.24461) (xy 285.747965 -377.23641)
			(xy 285.750575 -377.218314) (xy 285.748984 -377.209304) (xy 285.743398 -377.182345) (xy 285.737417 -377.127613)
			(xy 285.737046 -377.100084) (xy 285.737548 -377.068123) (xy 285.745559 -377.004705) (xy 285.761456 -376.942791)
			(xy 285.784988 -376.883358) (xy 285.815782 -376.827343) (xy 285.853355 -376.775628) (xy 285.897112 -376.729031)
			(xy 285.946365 -376.688286) (xy 286.000336 -376.654035) (xy 286.058175 -376.626818) (xy 286.118968 -376.607065)
			(xy 286.181758 -376.595087) (xy 286.245554 -376.591074) (xy 286.30935 -376.595087) (xy 286.37214 -376.607065)
			(xy 286.432933 -376.626818) (xy 286.490772 -376.654035) (xy 286.544743 -376.688286) (xy 286.593996 -376.729031)
			(xy 286.637753 -376.775628) (xy 286.675326 -376.827343) (xy 286.70612 -376.883358) (xy 286.729652 -376.942791)
			(xy 286.745549 -377.004705) (xy 286.75356 -377.068123) (xy 286.754062 -377.100084) (xy 286.753575 -377.13113)
			(xy 286.746009 -377.192759) (xy 286.731 -377.25301) (xy 286.708771 -377.310987) (xy 286.679653 -377.365828)
			(xy 286.644078 -377.416718) (xy 286.602574 -377.462901) (xy 286.55576 -377.503691) (xy 286.50433 -377.538481)
			(xy 286.449048 -377.566754) (xy 286.420052 -377.577858) (xy 286.411568 -377.581296) (xy 286.397638 -377.593154)
			(xy 286.392874 -377.600972) (xy 286.378142 -377.627642) (xy 286.374053 -377.63583) (xy 286.371462 -377.653936)
			(xy 286.373062 -377.662948) (xy 286.378641 -377.689908) (xy 286.384627 -377.744639) (xy 286.385 -377.772168)
			(xy 286.384448 -377.805507) (xy 286.375731 -377.871613) (xy 286.358455 -377.936014) (xy 286.332916 -377.997607)
			(xy 286.299551 -378.055337) (xy 286.258932 -378.108215) (xy 286.211756 -378.155336) (xy 286.18561 -378.176028)
			(xy 286.178764 -378.181672) (xy 286.169161 -378.196579) (xy 286.165226 -378.213868) (xy 286.167432 -378.231462)
			(xy 286.171132 -378.239528) (xy 286.18438 -378.266453) (xy 286.205208 -378.322731) (xy 286.219253 -378.381073)
			(xy 286.226322 -378.440664) (xy 286.226758 -378.470668) (xy 286.226256 -378.502629) (xy 286.218245 -378.566047)
			(xy 286.202348 -378.627961) (xy 286.178816 -378.687394) (xy 286.148022 -378.743409) (xy 286.110449 -378.795124)
			(xy 286.066692 -378.841721) (xy 286.017439 -378.882466) (xy 285.963468 -378.916717) (xy 285.905629 -378.943934)
			(xy 285.844836 -378.963687) (xy 285.782046 -378.975665) (xy 285.71825 -378.979679) (xy 285.654454 -378.975665)
			(xy 285.591664 -378.963687) (xy 285.530871 -378.943934) (xy 285.473032 -378.916717) (xy 285.419061 -378.882466)
			(xy 285.369808 -378.841721) (xy 285.326051 -378.795124) (xy 285.288478 -378.743409) (xy 285.257684 -378.687394)
			(xy 285.234152 -378.627961) (xy 285.218255 -378.566047) (xy 285.210244 -378.502629) (xy 285.209742 -378.470668)
			(xy 283.047948 -378.470668) (xy 283.047948 -384.973576) (xy 283.18841 -384.973576) (xy 283.188829 -384.94336)
			(xy 283.19602 -384.883357) (xy 283.210272 -384.824629) (xy 283.231387 -384.768005) (xy 283.259065 -384.714283)
			(xy 283.292916 -384.664222) (xy 283.312362 -384.64109) (xy 283.317999 -384.633961) (xy 283.324235 -384.6169)
			(xy 283.324554 -384.607816) (xy 283.324554 -384.577336) (xy 283.324249 -384.568252) (xy 283.317989 -384.551201)
			(xy 283.312362 -384.544062) (xy 283.292914 -384.520934) (xy 283.259077 -384.470866) (xy 283.231409 -384.417141)
			(xy 283.210301 -384.360517) (xy 283.196051 -384.301791) (xy 283.188859 -384.241791) (xy 283.18841 -384.211576)
			(xy 283.189016 -384.177336) (xy 283.198238 -384.109479) (xy 283.216472 -384.04347) (xy 283.243389 -383.980501)
			(xy 283.278504 -383.921709) (xy 283.299408 -383.894584) (xy 283.306024 -383.88519) (xy 283.311131 -383.862827)
			(xy 283.306047 -383.840458) (xy 283.299408 -383.831084) (xy 283.278483 -383.80397) (xy 283.243325 -383.745193)
			(xy 283.216386 -383.682225) (xy 283.198155 -383.616206) (xy 283.188964 -383.548337) (xy 283.18841 -383.514092)
			(xy 283.188894 -383.482926) (xy 283.19651 -383.42106) (xy 283.211627 -383.360587) (xy 283.234019 -383.302415)
			(xy 283.26335 -383.247414) (xy 283.299181 -383.196409) (xy 283.319728 -383.17297) (xy 283.325708 -383.165756)
			(xy 283.332469 -383.148294) (xy 283.332936 -383.138934) (xy 283.332936 -383.1082) (xy 283.332563 -383.098822)
			(xy 283.325782 -383.081336) (xy 283.319728 -383.074164) (xy 283.299156 -383.050745) (xy 283.263323 -382.999737)
			(xy 283.233992 -382.944733) (xy 283.211602 -382.886557) (xy 283.196488 -382.82608) (xy 283.188878 -382.76421)
			(xy 283.18841 -382.733042) (xy 283.188877 -382.70231) (xy 283.196281 -382.641294) (xy 283.210987 -382.581615)
			(xy 283.232779 -382.524144) (xy 283.26134 -382.46972) (xy 283.296253 -382.419135) (xy 283.33701 -382.373127)
			(xy 283.383016 -382.332368) (xy 283.433599 -382.297452) (xy 283.488022 -382.268889) (xy 283.545492 -382.247094)
			(xy 283.60517 -382.232386) (xy 283.666186 -382.224979) (xy 283.696918 -382.224534) (xy 283.728695 -382.225057)
			(xy 283.791753 -382.232982) (xy 283.853332 -382.248705) (xy 283.91247 -382.271982) (xy 283.968245 -382.30245)
			(xy 284.019787 -382.339632) (xy 284.043374 -382.360932) (xy 284.050303 -382.366802) (xy 284.067086 -382.373703)
			(xy 284.07614 -382.374394) (xy 284.106366 -382.375664) (xy 284.11549 -382.375638) (xy 284.132798 -382.369897)
			(xy 284.140148 -382.364488) (xy 284.167295 -382.343512) (xy 284.226164 -382.308281) (xy 284.289235 -382.281285)
			(xy 284.355362 -382.263012) (xy 284.423345 -382.253796) (xy 284.457648 -382.253236) (xy 284.488382 -382.253611)
			(xy 284.5494 -382.261025) (xy 284.60908 -382.275741) (xy 284.666552 -382.297543) (xy 284.720976 -382.326114)
			(xy 284.771559 -382.361036) (xy 284.817565 -382.4018) (xy 284.858321 -382.447813) (xy 284.893234 -382.498403)
			(xy 284.921795 -382.552832) (xy 284.943586 -382.610307) (xy 284.958291 -382.66999) (xy 284.965695 -382.73101)
			(xy 284.966156 -382.761744) (xy 284.965734 -382.791403) (xy 284.958803 -382.850314) (xy 284.945065 -382.90802)
			(xy 284.924705 -382.963734) (xy 284.898001 -383.016701) (xy 284.865315 -383.066201) (xy 284.846522 -383.08915)
			(xy 284.841106 -383.096247) (xy 284.834985 -383.112999) (xy 284.834584 -383.121916) (xy 284.834584 -383.152142)
			(xy 284.834911 -383.161075) (xy 284.841025 -383.17786) (xy 284.846522 -383.184908) (xy 284.865303 -383.207866)
			(xy 284.897986 -383.257365) (xy 284.924689 -383.310331) (xy 284.945048 -383.366044) (xy 284.958788 -383.423747)
			(xy 284.965722 -383.482656) (xy 284.966156 -383.512314) (xy 284.965586 -383.546651) (xy 284.956343 -383.614699)
			(xy 284.938026 -383.680885) (xy 284.910969 -383.744003) (xy 284.875664 -383.802907) (xy 284.85465 -383.830068)
			(xy 284.847826 -383.839404) (xy 284.842698 -383.861936) (xy 284.847857 -383.88446) (xy 284.85465 -383.893822)
			(xy 284.875648 -383.920995) (xy 284.91096 -383.979894) (xy 284.938022 -384.043009) (xy 284.956343 -384.109193)
			(xy 284.965589 -384.17724) (xy 284.966156 -384.211576) (xy 284.965717 -384.241792) (xy 284.958531 -384.301794)
			(xy 284.944283 -384.360522) (xy 284.923172 -384.417146) (xy 284.895498 -384.470868) (xy 284.861649 -384.52093)
			(xy 284.842204 -384.544062) (xy 284.836595 -384.551211) (xy 284.830341 -384.568256) (xy 284.830012 -384.577336)
			(xy 284.830012 -384.607816) (xy 284.830348 -384.616897) (xy 284.836588 -384.633948) (xy 284.842204 -384.64109)
			(xy 284.861623 -384.664241) (xy 284.895466 -384.714303) (xy 284.923138 -384.768023) (xy 284.944251 -384.824642)
			(xy 284.957345 -384.87858) (xy 286.799027 -384.87858) (xy 286.803034 -384.693676) (xy 286.815047 -384.509118)
			(xy 286.835043 -384.325254) (xy 286.862985 -384.14243) (xy 286.898821 -383.960987) (xy 286.942483 -383.781266)
			(xy 286.99389 -383.603606) (xy 287.052944 -383.42834) (xy 287.119535 -383.255796) (xy 287.193538 -383.086299)
			(xy 287.274814 -382.920167) (xy 287.36321 -382.757711) (xy 287.458561 -382.599237) (xy 287.560687 -382.445042)
			(xy 287.669396 -382.295416) (xy 287.784485 -382.15064) (xy 287.905738 -382.010985) (xy 288.032927 -381.876714)
			(xy 288.165812 -381.748078) (xy 288.304146 -381.625319) (xy 288.447667 -381.508669) (xy 288.596106 -381.398345)
			(xy 288.749186 -381.294554) (xy 288.906617 -381.197492) (xy 289.068106 -381.107342) (xy 289.233348 -381.024271)
			(xy 289.402034 -380.948436) (xy 289.573846 -380.87998) (xy 289.748462 -380.81903) (xy 289.925555 -380.765703)
			(xy 290.104792 -380.720096) (xy 290.285836 -380.682297) (xy 290.468347 -380.652376) (xy 290.651984 -380.630389)
			(xy 290.8364 -380.616377) (xy 291.02125 -380.610367) (xy 291.206187 -380.612371) (xy 291.390864 -380.622384)
			(xy 291.574934 -380.640387) (xy 291.75805 -380.666348) (xy 291.939871 -380.700216) (xy 292.120054 -380.741928)
			(xy 292.29826 -380.791407) (xy 292.474156 -380.848559) (xy 292.647411 -380.913277) (xy 292.8177 -380.98544)
			(xy 292.984703 -381.064911) (xy 293.148107 -381.151542) (xy 293.307604 -381.245171) (xy 293.462896 -381.34562)
			(xy 293.613691 -381.452703) (xy 293.759706 -381.566217) (xy 293.900666 -381.685949) (xy 294.036307 -381.811676)
			(xy 294.166375 -381.94316) (xy 294.290625 -382.080156) (xy 294.408823 -382.222405) (xy 294.520749 -382.36964)
			(xy 294.626192 -382.521586) (xy 294.724953 -382.677957) (xy 294.816848 -382.83846) (xy 294.901704 -383.002792)
			(xy 294.979362 -383.170647) (xy 295.049675 -383.341707) (xy 295.112512 -383.515653) (xy 295.167756 -383.692158)
			(xy 295.215301 -383.87089) (xy 295.255059 -384.051514) (xy 295.286956 -384.233691) (xy 295.310931 -384.417078)
			(xy 295.326939 -384.601332) (xy 295.334951 -384.786106) (xy 295.335452 -384.87858) (xy 295.334951 -384.971054)
			(xy 295.326939 -385.155828) (xy 295.310931 -385.340082) (xy 295.286956 -385.523469) (xy 295.255059 -385.705646)
			(xy 295.215301 -385.88627) (xy 295.167756 -386.065002) (xy 295.112512 -386.241507) (xy 295.049675 -386.415453)
			(xy 294.979362 -386.586513) (xy 294.901704 -386.754368) (xy 294.816848 -386.9187) (xy 294.724953 -387.079203)
			(xy 294.626192 -387.235574) (xy 294.520749 -387.38752) (xy 294.408823 -387.534755) (xy 294.290625 -387.677004)
			(xy 294.166375 -387.814) (xy 294.036307 -387.945484) (xy 293.900666 -388.071211) (xy 293.759706 -388.190943)
			(xy 293.613691 -388.304457) (xy 293.462896 -388.41154) (xy 293.307604 -388.511989) (xy 293.148107 -388.605618)
			(xy 292.984703 -388.692249) (xy 292.8177 -388.77172) (xy 292.647411 -388.843883) (xy 292.474156 -388.908601)
			(xy 292.29826 -388.965753) (xy 292.120054 -389.015232) (xy 291.939871 -389.056944) (xy 291.75805 -389.090812)
			(xy 291.574934 -389.116773) (xy 291.390864 -389.134776) (xy 291.206187 -389.144789) (xy 291.02125 -389.146793)
			(xy 290.8364 -389.140783) (xy 290.651984 -389.126771) (xy 290.468347 -389.104784) (xy 290.285836 -389.074863)
			(xy 290.104792 -389.037064) (xy 289.925555 -388.991457) (xy 289.748462 -388.93813) (xy 289.573846 -388.87718)
			(xy 289.402034 -388.808724) (xy 289.233348 -388.732889) (xy 289.068106 -388.649818) (xy 288.906617 -388.559668)
			(xy 288.749186 -388.462606) (xy 288.596106 -388.358815) (xy 288.447667 -388.248491) (xy 288.304146 -388.131841)
			(xy 288.165812 -388.009082) (xy 288.032927 -387.880446) (xy 287.905738 -387.746175) (xy 287.784485 -387.60652)
			(xy 287.669396 -387.461744) (xy 287.560687 -387.312118) (xy 287.458561 -387.157923) (xy 287.36321 -386.999449)
			(xy 287.274814 -386.836993) (xy 287.193538 -386.670861) (xy 287.119535 -386.501364) (xy 287.052944 -386.32882)
			(xy 286.99389 -386.153554) (xy 286.942483 -385.975894) (xy 286.898821 -385.796173) (xy 286.862985 -385.61473)
			(xy 286.835043 -385.431906) (xy 286.815047 -385.248042) (xy 286.803034 -385.063484) (xy 286.799027 -384.87858)
			(xy 284.957345 -384.87858) (xy 284.958507 -384.883365) (xy 284.965704 -384.943362) (xy 284.966156 -384.973576)
			(xy 284.965621 -385.004305) (xy 284.958217 -385.065314) (xy 284.943512 -385.124986) (xy 284.921723 -385.182451)
			(xy 284.893165 -385.236871) (xy 284.858257 -385.287451) (xy 284.817506 -385.333455) (xy 284.771508 -385.374212)
			(xy 284.720932 -385.409128) (xy 284.666517 -385.437693) (xy 284.609055 -385.459491) (xy 284.549385 -385.474204)
			(xy 284.488377 -385.481617) (xy 284.457648 -385.482084) (xy 284.427489 -385.481656) (xy 284.367596 -385.474519)
			(xy 284.30897 -385.46034) (xy 284.252435 -385.439317) (xy 284.198787 -385.411748) (xy 284.148781 -385.37802)
			(xy 284.12567 -385.35864) (xy 284.118518 -385.353037) (xy 284.101475 -385.346781) (xy 284.092396 -385.346448)
			(xy 284.06217 -385.346448) (xy 284.053088 -385.346769) (xy 284.036036 -385.353018) (xy 284.028896 -385.35864)
			(xy 284.005779 -385.378008) (xy 283.955758 -385.411703) (xy 283.902106 -385.439251) (xy 283.845575 -385.460267)
			(xy 283.786957 -385.474456) (xy 283.727073 -385.48162) (xy 283.696918 -385.482084) (xy 283.666185 -385.481645)
			(xy 283.605168 -385.474238) (xy 283.545488 -385.45953) (xy 283.488017 -385.437735) (xy 283.433592 -385.409171)
			(xy 283.383007 -385.374255) (xy 283.337 -385.333496) (xy 283.296241 -385.287488) (xy 283.261326 -385.236903)
			(xy 283.232762 -385.182477) (xy 283.210968 -385.125006) (xy 283.196261 -385.065326) (xy 283.188854 -385.004309)
			(xy 283.18841 -384.973576) (xy 283.047948 -384.973576) (xy 283.047948 -386.493766) (xy 283.048435 -386.503727)
			(xy 283.056028 -386.522147) (xy 283.06268 -386.52958) (xy 283.934154 -387.401054) (xy 283.940997 -387.408453)
			(xy 283.948719 -387.427052) (xy 283.94914 -387.437122) (xy 283.94914 -390.151366) (xy 283.949576 -390.16143)
			(xy 283.957312 -390.180013) (xy 283.964126 -390.187434) (xy 286.750252 -392.97356) (xy 286.757657 -392.980256)
			(xy 286.776094 -392.987862) (xy 286.786066 -392.988292) (xy 293.714678 -392.988292) (xy 293.74649 -392.988721)
			(xy 293.809714 -392.995847) (xy 293.871741 -393.010012) (xy 293.93179 -393.031037) (xy 293.989106 -393.058658)
			(xy 294.042966 -393.092526) (xy 294.092693 -393.132216) (xy 294.11549 -393.154408) (xy 294.526716 -393.565634)
			(xy 294.534112 -393.572485) (xy 294.552711 -393.580224) (xy 294.562784 -393.58062) (xy 294.625776 -393.58062)
		)
		(stroke
			(width 0)
			(type solid)
		)
		(fill yes)
		(layer "In2.Cu")
		(net "P1V8_CPU0_RT_1D")
	)
	(gr_poly
		(pts
			(xy 251.944886 -52.876958) (xy 251.954759 -52.876487) (xy 251.973045 -52.869033) (xy 251.980446 -52.86248)
			(xy 251.9807 -52.862226) (xy 252.546358 -52.296568) (xy 252.546866 -52.29606) (xy 252.553449 -52.288679)
			(xy 252.560902 -52.27038) (xy 252.561344 -52.2605) (xy 252.561344 -47.194978) (xy 252.560874 -47.18467)
			(xy 252.55276 -47.165721) (xy 252.53782 -47.151518) (xy 252.528324 -47.14748) (xy 252.424438 -47.108364)
			(xy 252.393958 -47.115984) (xy 252.38329 -47.127922) (xy 252.3651 -47.147961) (xy 252.324036 -47.183211)
			(xy 252.278401 -47.212301) (xy 252.229111 -47.234646) (xy 252.177157 -47.249799) (xy 252.123583 -47.257454)
			(xy 252.096524 -47.25797) (xy 252.069273 -47.257508) (xy 252.015325 -47.249755) (xy 251.963029 -47.234403)
			(xy 251.913451 -47.211764) (xy 251.867599 -47.182299) (xy 251.826408 -47.146609) (xy 251.790715 -47.10542)
			(xy 251.761248 -47.05957) (xy 251.738606 -47.009993) (xy 251.72325 -46.957699) (xy 251.715493 -46.903751)
			(xy 251.715493 -46.849249) (xy 251.72325 -46.795301) (xy 251.738606 -46.743007) (xy 251.761248 -46.69343)
			(xy 251.790715 -46.64758) (xy 251.826408 -46.606391) (xy 251.867599 -46.570701) (xy 251.913451 -46.541236)
			(xy 251.963029 -46.518597) (xy 252.015325 -46.503245) (xy 252.069273 -46.495492) (xy 252.096524 -46.494954)
			(xy 252.123584 -46.495429) (xy 252.17716 -46.503088) (xy 252.229114 -46.518249) (xy 252.278401 -46.540607)
			(xy 252.324029 -46.569711) (xy 252.365082 -46.604977) (xy 252.38329 -46.625002) (xy 252.393958 -46.63694)
			(xy 252.424438 -46.64456) (xy 252.528324 -46.605444) (xy 252.537793 -46.601378) (xy 252.55268 -46.587157)
			(xy 252.560803 -46.568239) (xy 252.561344 -46.557946) (xy 252.561344 -45.671486) (xy 252.560697 -45.658934)
			(xy 252.548832 -45.636812) (xy 252.538738 -45.629322) (xy 252.457712 -45.57522) (xy 252.43282 -45.57268)
			(xy 252.420882 -45.57776) (xy 252.397568 -45.587007) (xy 252.349127 -45.60001) (xy 252.299402 -45.606569)
			(xy 252.274324 -45.60697) (xy 252.269752 -45.60697) (xy 252.242582 -45.606159) (xy 252.188875 -45.597793)
			(xy 252.136897 -45.581893) (xy 252.087701 -45.558781) (xy 252.042281 -45.528922) (xy 252.001556 -45.492923)
			(xy 251.96635 -45.45151) (xy 251.937375 -45.405522) (xy 251.925836 -45.38091) (xy 251.921518 -45.371004)
			(xy 251.906024 -45.357034) (xy 251.814838 -45.326046) (xy 251.79401 -45.327824) (xy 251.784612 -45.333158)
			(xy 251.745416 -45.353829) (xy 251.663729 -45.388187) (xy 251.57903 -45.414255) (xy 251.492161 -45.431773)
			(xy 251.403979 -45.44057) (xy 251.35967 -45.441108) (xy 251.317834 -45.440631) (xy 251.234532 -45.432779)
			(xy 251.152336 -45.417136) (xy 251.071972 -45.393843) (xy 250.994152 -45.363103) (xy 250.919563 -45.325191)
			(xy 250.848865 -45.280439) (xy 250.782683 -45.229245) (xy 250.721602 -45.172061) (xy 250.666162 -45.109393)
			(xy 250.616854 -45.041794) (xy 250.574113 -44.969863) (xy 250.538318 -44.894235) (xy 250.509785 -44.815579)
			(xy 250.488765 -44.734591) (xy 250.475446 -44.651986) (xy 250.472194 -44.610274) (xy 250.471221 -44.600884)
			(xy 250.463272 -44.583776) (xy 250.4567 -44.577) (xy 250.434856 -44.556172) (xy 250.427792 -44.549953)
			(xy 250.41046 -44.542658) (xy 250.401074 -44.541948) (xy 250.358152 -44.540314) (xy 250.272897 -44.529813)
			(xy 250.189052 -44.511141) (xy 250.107397 -44.484473) (xy 250.028694 -44.450057) (xy 249.953675 -44.408214)
			(xy 249.883039 -44.359333) (xy 249.817445 -44.30387) (xy 249.757504 -44.242342) (xy 249.703773 -44.175322)
			(xy 249.656754 -44.103434) (xy 249.616884 -44.027348) (xy 249.584536 -43.947772) (xy 249.56001 -43.865448)
			(xy 249.543534 -43.781144) (xy 249.535263 -43.695644) (xy 249.53468 -43.652694) (xy 249.535183 -43.610457)
			(xy 249.543203 -43.526364) (xy 249.55916 -43.44341) (xy 249.58291 -43.362343) (xy 249.61424 -43.283893)
			(xy 249.652867 -43.208767) (xy 249.698443 -43.137642) (xy 249.750558 -43.071159) (xy 249.808741 -43.009917)
			(xy 249.872469 -42.954467) (xy 249.941168 -42.905309) (xy 250.014218 -42.862887) (xy 250.090961 -42.827582)
			(xy 250.170706 -42.799713) (xy 250.21159 -42.789094) (xy 250.220743 -42.78637) (xy 250.236274 -42.775281)
			(xy 250.241816 -42.767504) (xy 250.25858 -42.742104) (xy 250.26334 -42.733862) (xy 250.267126 -42.715226)
			(xy 250.265946 -42.705782) (xy 250.259966 -42.668479) (xy 250.253609 -42.593192) (xy 250.253246 -42.555414)
			(xy 250.25375 -42.513066) (xy 250.261801 -42.428752) (xy 250.27783 -42.345586) (xy 250.301691 -42.264319)
			(xy 250.33317 -42.185689) (xy 250.371981 -42.110408) (xy 250.417771 -42.039156) (xy 250.470127 -41.97258)
			(xy 250.528575 -41.911282) (xy 250.592585 -41.855817) (xy 250.661577 -41.806688) (xy 250.734927 -41.764339)
			(xy 250.81197 -41.729155) (xy 250.892009 -41.701453) (xy 250.974318 -41.681485) (xy 251.058153 -41.669432)
			(xy 251.142754 -41.665402) (xy 251.227355 -41.669432) (xy 251.31119 -41.681485) (xy 251.393499 -41.701453)
			(xy 251.473538 -41.729155) (xy 251.550581 -41.764339) (xy 251.623931 -41.806688) (xy 251.692923 -41.855817)
			(xy 251.756933 -41.911282) (xy 251.815381 -41.97258) (xy 251.867737 -42.039156) (xy 251.913527 -42.110408)
			(xy 251.952338 -42.185689) (xy 251.983817 -42.264319) (xy 252.007678 -42.345586) (xy 252.023707 -42.428752)
			(xy 252.031758 -42.513066) (xy 252.032262 -42.555414) (xy 252.031763 -42.597654) (xy 252.023751 -42.681754)
			(xy 252.007801 -42.764715) (xy 251.984057 -42.845791) (xy 251.952733 -42.924249) (xy 251.91411 -42.999384)
			(xy 251.868537 -43.070518) (xy 251.816424 -43.137011) (xy 251.758242 -43.198262) (xy 251.694513 -43.253721)
			(xy 251.625814 -43.302888) (xy 251.552762 -43.345319) (xy 251.476016 -43.380632) (xy 251.396267 -43.408509)
			(xy 251.355352 -43.419014) (xy 251.346195 -43.421732) (xy 251.330655 -43.432816) (xy 251.325126 -43.440604)
			(xy 251.308362 -43.466004) (xy 251.303608 -43.474248) (xy 251.299829 -43.492881) (xy 251.300996 -43.502326)
			(xy 251.304708 -43.525116) (xy 251.310044 -43.570987) (xy 251.311664 -43.59402) (xy 251.312655 -43.603401)
			(xy 251.320632 -43.62048) (xy 251.327158 -43.627294) (xy 251.349002 -43.648122) (xy 251.356064 -43.654348)
			(xy 251.373395 -43.661658) (xy 251.382784 -43.662346) (xy 251.425576 -43.663968) (xy 251.510576 -43.674407)
			(xy 251.594179 -43.692967) (xy 251.675612 -43.719476) (xy 251.75412 -43.753688) (xy 251.828976 -43.795286)
			(xy 251.899489 -43.843886) (xy 251.965005 -43.899038) (xy 252.024916 -43.96023) (xy 252.07867 -44.026898)
			(xy 252.10262 -44.062396) (xy 252.109407 -44.071715) (xy 252.129182 -44.083522) (xy 252.152123 -44.085557)
			(xy 252.163072 -44.081954) (xy 252.184948 -44.073917) (xy 252.230165 -44.062618) (xy 252.276421 -44.056915)
			(xy 252.299724 -44.056554) (xy 252.331977 -44.05723) (xy 252.395564 -44.068084) (xy 252.426216 -44.078144)
			(xy 252.4379 -44.082208) (xy 252.46203 -44.078906) (xy 252.539754 -44.023788) (xy 252.545264 -44.019693)
			(xy 252.554031 -44.009136) (xy 252.557026 -44.00296) (xy 252.561344 -43.9928) (xy 252.561344 -42.283634)
			(xy 252.561781 -42.27357) (xy 252.569517 -42.254987) (xy 252.57633 -42.247566) (xy 253.49581 -41.328086)
			(xy 253.503205 -41.321232) (xy 253.521804 -41.313487) (xy 253.531878 -41.3131) (xy 253.96444 -41.3131)
			(xy 253.975685 -41.312527) (xy 253.996011 -41.302912) (xy 254.003556 -41.294558) (xy 254.031663 -41.261131)
			(xy 254.093426 -41.199377) (xy 254.160945 -41.143975) (xy 254.23357 -41.095458) (xy 254.310602 -41.054294)
			(xy 254.391297 -41.020879) (xy 254.474879 -40.995536) (xy 254.560543 -40.978508) (xy 254.647464 -40.969959)
			(xy 254.691134 -40.969438) (xy 254.734931 -40.969956) (xy 254.8221 -40.978559) (xy 254.908 -40.995697)
			(xy 254.991797 -41.021204) (xy 255.072677 -41.054833) (xy 255.111504 -41.075102) (xy 255.12297 -41.08052)
			(xy 255.148298 -41.08052) (xy 255.159764 -41.075102) (xy 255.193705 -41.057353) (xy 255.264074 -41.02709)
			(xy 255.336785 -41.002995) (xy 255.411301 -40.985246) (xy 255.487067 -40.973976) (xy 255.52527 -40.971216)
			(xy 255.534668 -40.970454) (xy 255.551686 -40.962834) (xy 255.648714 -40.865806) (xy 255.649222 -40.865298)
			(xy 255.6558 -40.857916) (xy 255.663238 -40.839616) (xy 255.6637 -40.829738) (xy 255.6637 -39.251382)
			(xy 255.663273 -39.241313) (xy 255.655554 -39.222714) (xy 255.648714 -39.215314) (xy 255.544574 -39.111174)
			(xy 255.537178 -39.104324) (xy 255.518579 -39.096587) (xy 255.508506 -39.096188) (xy 254.87376 -39.096188)
			(xy 254.862767 -39.096669) (xy 254.842751 -39.105756) (xy 254.835152 -39.113714) (xy 254.777494 -39.18077)
			(xy 254.771398 -39.201598) (xy 254.773176 -39.212774) (xy 254.777687 -39.245225) (xy 254.782518 -39.310569)
			(xy 254.782828 -39.34333) (xy 254.782203 -39.390758) (xy 254.772074 -39.485073) (xy 254.751958 -39.577772)
			(xy 254.737616 -39.622984) (xy 254.734314 -39.63289) (xy 254.736092 -39.652956) (xy 254.779272 -39.736268)
			(xy 254.794766 -39.749222) (xy 254.804926 -39.75227) (xy 254.83074 -39.760541) (xy 254.879907 -39.78336)
			(xy 254.92535 -39.812909) (xy 254.966153 -39.848592) (xy 255.001496 -39.88969) (xy 255.030666 -39.935377)
			(xy 255.053076 -39.984732) (xy 255.068275 -40.036762) (xy 255.075958 -40.09042) (xy 255.076452 -40.117522)
			(xy 255.075965 -40.144773) (xy 255.068206 -40.198721) (xy 255.052849 -40.251016) (xy 255.030208 -40.300593)
			(xy 255.000741 -40.346444) (xy 254.965051 -40.387635) (xy 254.923861 -40.423328) (xy 254.878012 -40.452797)
			(xy 254.828436 -40.475442) (xy 254.776143 -40.490801) (xy 254.722195 -40.498563) (xy 254.694944 -40.49903)
			(xy 254.66603 -40.498492) (xy 254.608865 -40.489756) (xy 254.553673 -40.472494) (xy 254.501719 -40.4471)
			(xy 254.454191 -40.414157) (xy 254.41218 -40.374418) (xy 254.393954 -40.351964) (xy 254.387672 -40.344577)
			(xy 254.370957 -40.334779) (xy 254.361442 -40.332914) (xy 254.353822 -40.332406) (xy 254.274066 -40.332406)
			(xy 254.266446 -40.332914) (xy 254.256925 -40.334774) (xy 254.240191 -40.344553) (xy 254.233934 -40.351964)
			(xy 254.215744 -40.374449) (xy 254.173728 -40.41419) (xy 254.126194 -40.447133) (xy 254.074232 -40.472522)
			(xy 254.019032 -40.489775) (xy 253.961861 -40.498498) (xy 253.932944 -40.49903) (xy 253.903619 -40.498495)
			(xy 253.845659 -40.489519) (xy 253.789757 -40.471772) (xy 253.737233 -40.445673) (xy 253.71298 -40.42918)
			(xy 253.703836 -40.42283) (xy 253.6825 -40.418766) (xy 253.586488 -40.44188) (xy 253.56947 -40.455342)
			(xy 253.56439 -40.464994) (xy 253.543515 -40.503793) (xy 253.495196 -40.577472) (xy 253.439828 -40.646012)
			(xy 253.377953 -40.70874) (xy 253.310178 -40.765043) (xy 253.237169 -40.814368) (xy 253.159639 -40.856231)
			(xy 253.07835 -40.890222) (xy 252.994097 -40.916008) (xy 252.907708 -40.933336) (xy 252.820029 -40.942037)
			(xy 252.775974 -40.942514) (xy 252.733356 -40.942012) (xy 252.64851 -40.933855) (xy 252.564833 -40.917618)
			(xy 252.483094 -40.89345) (xy 252.404042 -40.861574) (xy 252.328402 -40.822281) (xy 252.256868 -40.775931)
			(xy 252.190097 -40.722951) (xy 252.1287 -40.663826) (xy 252.073242 -40.599098) (xy 252.02423 -40.529361)
			(xy 251.982115 -40.455255) (xy 251.947282 -40.37746) (xy 251.933202 -40.337232) (xy 251.929714 -40.328191)
			(xy 251.917175 -40.313436) (xy 251.908818 -40.30853) (xy 251.881894 -40.294306) (xy 251.873171 -40.290148)
			(xy 251.853974 -40.288072) (xy 251.844556 -40.290242) (xy 251.805819 -40.300519) (xy 251.726967 -40.31488)
			(xy 251.647141 -40.322075) (xy 251.607066 -40.3225) (xy 251.581866 -40.322352) (xy 251.531544 -40.319555)
			(xy 251.506482 -40.316912) (xy 251.497134 -40.316192) (xy 251.478995 -40.320884) (xy 251.471176 -40.326056)
			(xy 251.446792 -40.343582) (xy 251.439356 -40.349308) (xy 251.429033 -40.364966) (xy 251.426726 -40.374062)
			(xy 251.417072 -40.41608) (xy 251.39069 -40.498164) (xy 251.356491 -40.577311) (xy 251.314794 -40.652777)
			(xy 251.26599 -40.723855) (xy 251.210539 -40.789877) (xy 251.14896 -40.850224) (xy 251.081831 -40.90433)
			(xy 251.009782 -40.951688) (xy 250.933488 -40.991851) (xy 250.853667 -41.024445) (xy 250.771067 -41.049163)
			(xy 250.686462 -41.065772) (xy 250.600648 -41.074118) (xy 250.557538 -41.074594) (xy 250.515188 -41.074108)
			(xy 250.430872 -41.06606) (xy 250.347703 -41.050034) (xy 250.266433 -41.026174) (xy 250.1878 -40.994697)
			(xy 250.112515 -40.955887) (xy 250.04126 -40.910097) (xy 249.97468 -40.857741) (xy 249.913379 -40.799293)
			(xy 249.857912 -40.735283) (xy 249.80878 -40.66629) (xy 249.766429 -40.592938) (xy 249.731243 -40.515893)
			(xy 249.70354 -40.435853) (xy 249.683571 -40.353541) (xy 249.671516 -40.269704) (xy 249.667486 -40.1851)
			(xy 249.671516 -40.100496) (xy 249.683571 -40.016659) (xy 249.70354 -39.934347) (xy 249.731243 -39.854307)
			(xy 249.766429 -39.777262) (xy 249.80878 -39.70391) (xy 249.857912 -39.634917) (xy 249.913379 -39.570907)
			(xy 249.97468 -39.512459) (xy 250.04126 -39.460103) (xy 250.112515 -39.414313) (xy 250.1878 -39.375503)
			(xy 250.266433 -39.344026) (xy 250.347703 -39.320166) (xy 250.430872 -39.30414) (xy 250.515188 -39.296092)
			(xy 250.557538 -39.295578) (xy 250.582738 -39.295726) (xy 250.63306 -39.298523) (xy 250.658122 -39.301166)
			(xy 250.667466 -39.301829) (xy 250.685588 -39.297147) (xy 250.693428 -39.292022) (xy 250.717812 -39.274496)
			(xy 250.725245 -39.268768) (xy 250.73556 -39.253109) (xy 250.737878 -39.244016) (xy 250.742958 -39.221918)
			(xy 250.745752 -39.210488) (xy 250.740926 -39.187628) (xy 250.684284 -39.115492) (xy 250.676706 -39.106781)
			(xy 250.65594 -39.096742) (xy 250.644406 -39.096188) (xy 248.23547 -39.096188) (xy 248.206514 -39.122096)
			(xy 248.204482 -39.141908) (xy 248.200865 -39.171835) (xy 248.185412 -39.2301) (xy 248.160989 -39.28521)
			(xy 248.128204 -39.335794) (xy 248.087873 -39.380594) (xy 248.064782 -39.399972) (xy 248.056908 -39.406322)
			(xy 248.050485 -39.412458) (xy 248.042035 -39.428071) (xy 248.040398 -39.436802) (xy 248.03989 -39.444422)
			(xy 248.03989 -39.524178) (xy 248.040398 -39.531798) (xy 248.042268 -39.541311) (xy 248.052067 -39.558022)
			(xy 248.059448 -39.56431) (xy 248.081937 -39.582498) (xy 248.121686 -39.624511) (xy 248.154637 -39.672044)
			(xy 248.180035 -39.724006) (xy 248.197297 -39.779207) (xy 248.206028 -39.836381) (xy 248.206514 -39.8653)
			(xy 248.206028 -39.892551) (xy 248.198272 -39.946499) (xy 248.182917 -39.998794) (xy 248.160275 -40.048371)
			(xy 248.130809 -40.094221) (xy 248.095118 -40.135412) (xy 248.053927 -40.171103) (xy 248.008077 -40.200569)
			(xy 247.9585 -40.223211) (xy 247.906205 -40.238566) (xy 247.852257 -40.246322) (xy 247.797755 -40.246322)
			(xy 247.743807 -40.238566) (xy 247.691512 -40.223211) (xy 247.641935 -40.200569) (xy 247.596085 -40.171103)
			(xy 247.554894 -40.135412) (xy 247.519203 -40.094221) (xy 247.489737 -40.048371) (xy 247.467095 -39.998794)
			(xy 247.45174 -39.946499) (xy 247.443984 -39.892551) (xy 247.443498 -39.8653) (xy 247.444032 -39.836383)
			(xy 247.452759 -39.779212) (xy 247.470013 -39.724012) (xy 247.495399 -39.672048) (xy 247.528335 -39.62451)
			(xy 247.568068 -39.582486) (xy 247.590564 -39.56431) (xy 247.597954 -39.558029) (xy 247.607766 -39.541317)
			(xy 247.609614 -39.531798) (xy 247.610122 -39.524178) (xy 247.610122 -39.444422) (xy 247.609614 -39.436802)
			(xy 247.607744 -39.427288) (xy 247.597947 -39.410576) (xy 247.590564 -39.40429) (xy 247.588278 -39.402512)
			(xy 247.58523 -39.399972) (xy 247.562147 -39.380584) (xy 247.521809 -39.335792) (xy 247.489021 -39.28521)
			(xy 247.464599 -39.230101) (xy 247.449152 -39.171835) (xy 247.44553 -39.141908) (xy 247.443498 -39.122096)
			(xy 247.414542 -39.096188) (xy 247.306846 -39.096188) (xy 247.296883 -39.096672) (xy 247.278454 -39.104255)
			(xy 247.271032 -39.11092) (xy 247.082564 -39.299388) (xy 244.779292 -41.602406) (xy 244.777006 -41.604946)
			(xy 244.767608 -41.61409) (xy 244.760242 -41.639236) (xy 244.78488 -41.748964) (xy 244.802406 -41.768522)
			(xy 244.814598 -41.77284) (xy 244.854194 -41.787317) (xy 244.930706 -41.822739) (xy 245.003523 -41.865242)
			(xy 245.071991 -41.914446) (xy 245.135494 -41.969908) (xy 245.193464 -42.031131) (xy 245.24538 -42.097566)
			(xy 245.290776 -42.168615) (xy 245.329244 -42.243642) (xy 245.360439 -42.321972) (xy 245.384082 -42.402904)
			(xy 245.399959 -42.485709) (xy 245.407928 -42.569645) (xy 245.40845 -42.611802) (xy 245.408039 -42.650091)
			(xy 245.40143 -42.726385) (xy 245.388279 -42.801826) (xy 245.368684 -42.875856) (xy 245.356126 -42.91203)
			(xy 245.353483 -42.920468) (xy 245.353484 -42.938136) (xy 245.356126 -42.946574) (xy 245.368669 -42.982752)
			(xy 245.388243 -43.056784) (xy 245.401388 -43.132224) (xy 245.408006 -43.208514) (xy 245.40845 -43.246802)
			(xy 245.407946 -43.28915) (xy 245.399895 -43.373464) (xy 245.383866 -43.45663) (xy 245.360005 -43.537897)
			(xy 245.328526 -43.616527) (xy 245.289715 -43.691808) (xy 245.243925 -43.76306) (xy 245.191569 -43.829636)
			(xy 245.133121 -43.890934) (xy 245.069111 -43.946399) (xy 245.000119 -43.995528) (xy 244.926769 -44.037877)
			(xy 244.849726 -44.073061) (xy 244.769687 -44.100763) (xy 244.687378 -44.120731) (xy 244.603543 -44.132784)
			(xy 244.518942 -44.136815) (xy 244.434341 -44.132784) (xy 244.350506 -44.120731) (xy 244.268197 -44.100763)
			(xy 244.188158 -44.073061) (xy 244.111115 -44.037877) (xy 244.037765 -43.995528) (xy 243.968773 -43.946399)
			(xy 243.904763 -43.890934) (xy 243.846315 -43.829636) (xy 243.793959 -43.76306) (xy 243.748169 -43.691808)
			(xy 243.709358 -43.616527) (xy 243.677879 -43.537897) (xy 243.654018 -43.45663) (xy 243.637989 -43.373464)
			(xy 243.629938 -43.28915) (xy 243.629434 -43.246802) (xy 243.629845 -43.208512) (xy 243.636453 -43.132219)
			(xy 243.649603 -43.056777) (xy 243.669198 -42.982747) (xy 243.681758 -42.946574) (xy 243.684401 -42.938136)
			(xy 243.684402 -42.920468) (xy 243.681758 -42.91203) (xy 243.667788 -42.870374) (xy 243.663978 -42.85742)
			(xy 243.644674 -42.839132) (xy 243.547138 -42.814748) (xy 243.538574 -42.812957) (xy 243.521171 -42.81463)
			(xy 243.505346 -42.822062) (xy 243.498878 -42.827956) (xy 242.39855 -43.928284) (xy 242.391711 -43.935684)
			(xy 242.383999 -43.954283) (xy 242.383564 -43.964352) (xy 242.383564 -45.726153) (xy 244.028673 -45.726153)
			(xy 244.028673 -45.671647) (xy 244.036431 -45.617697) (xy 244.051787 -45.5654) (xy 244.07443 -45.515821)
			(xy 244.103899 -45.469969) (xy 244.139593 -45.428777) (xy 244.180786 -45.393085) (xy 244.22664 -45.363619)
			(xy 244.276221 -45.340979) (xy 244.328519 -45.325626) (xy 244.382469 -45.317872) (xy 244.409722 -45.31741)
			(xy 244.41912 -45.31741) (xy 244.432582 -45.317918) (xy 244.45595 -45.305218) (xy 244.51691 -45.208444)
			(xy 244.51818 -45.182028) (xy 244.512084 -45.169836) (xy 244.499055 -45.142926) (xy 244.480598 -45.086061)
			(xy 244.471261 -45.027009) (xy 244.470682 -44.997116) (xy 244.471168 -44.969865) (xy 244.478924 -44.915917)
			(xy 244.494279 -44.863622) (xy 244.516921 -44.814045) (xy 244.546387 -44.768195) (xy 244.582078 -44.727004)
			(xy 244.623269 -44.691313) (xy 244.669119 -44.661847) (xy 244.718696 -44.639205) (xy 244.770991 -44.62385)
			(xy 244.824939 -44.616094) (xy 244.879441 -44.616094) (xy 244.933389 -44.62385) (xy 244.985684 -44.639205)
			(xy 245.035261 -44.661847) (xy 245.081111 -44.691313) (xy 245.122302 -44.727004) (xy 245.157993 -44.768195)
			(xy 245.187459 -44.814045) (xy 245.210101 -44.863622) (xy 245.225456 -44.915917) (xy 245.233212 -44.969865)
			(xy 245.233698 -44.997116) (xy 245.233189 -45.025048) (xy 245.225048 -45.080314) (xy 245.208941 -45.133805)
			(xy 245.185214 -45.184379) (xy 245.170198 -45.207936) (xy 245.164102 -45.21708) (xy 245.160546 -45.23867)
			(xy 245.186708 -45.33392) (xy 245.200678 -45.350684) (xy 245.210838 -45.35551) (xy 245.234703 -45.367543)
			(xy 245.279101 -45.397298) (xy 245.31891 -45.43296) (xy 245.353352 -45.47383) (xy 245.38175 -45.519108)
			(xy 245.40355 -45.567907) (xy 245.418323 -45.619271) (xy 245.425782 -45.672195) (xy 245.42623 -45.698918)
			(xy 245.425739 -45.726169) (xy 245.417981 -45.780115) (xy 245.402624 -45.832408) (xy 245.379983 -45.881984)
			(xy 245.350517 -45.927833) (xy 245.314826 -45.969023) (xy 245.273637 -46.004714) (xy 245.227788 -46.034181)
			(xy 245.178212 -46.056823) (xy 245.125919 -46.07218) (xy 245.071973 -46.079939) (xy 245.044722 -46.080426)
			(xy 245.017351 -46.079965) (xy 244.963171 -46.072149) (xy 244.910667 -46.056659) (xy 244.860921 -46.033816)
			(xy 244.814955 -46.004089) (xy 244.794024 -45.986446) (xy 244.786912 -45.98035) (xy 244.769894 -45.974)
			(xy 244.68455 -45.974) (xy 244.667532 -45.98035) (xy 244.66042 -45.986446) (xy 244.639484 -46.004081)
			(xy 244.593513 -46.033795) (xy 244.543767 -46.056633) (xy 244.491267 -46.072125) (xy 244.437091 -46.079953)
			(xy 244.409722 -46.080426) (xy 244.382469 -46.079928) (xy 244.328519 -46.072174) (xy 244.276221 -46.056821)
			(xy 244.22664 -46.034181) (xy 244.180786 -46.004715) (xy 244.139593 -45.969023) (xy 244.103899 -45.927831)
			(xy 244.07443 -45.881979) (xy 244.051787 -45.8324) (xy 244.036431 -45.780103) (xy 244.028673 -45.726153)
			(xy 242.383564 -45.726153) (xy 242.383564 -47.116054) (xy 248.905961 -47.116054) (xy 248.905961 -47.061546)
			(xy 248.913719 -47.007594) (xy 248.929076 -46.955294) (xy 248.951721 -46.905713) (xy 248.981191 -46.859859)
			(xy 249.016887 -46.818666) (xy 249.058083 -46.782973) (xy 249.103939 -46.753506) (xy 249.153522 -46.730866)
			(xy 249.205823 -46.715513) (xy 249.259776 -46.707759) (xy 249.28703 -46.707298) (xy 249.319753 -46.707953)
			(xy 249.384248 -46.719055) (xy 249.4153 -46.729396) (xy 249.423986 -46.732171) (xy 249.442209 -46.732028)
			(xy 249.45086 -46.729142) (xy 249.479308 -46.717966) (xy 249.487869 -46.714156) (xy 249.501684 -46.701521)
			(xy 249.506232 -46.693328) (xy 249.524985 -46.656696) (xy 249.568231 -46.586674) (xy 249.61776 -46.520945)
			(xy 249.673148 -46.460073) (xy 249.733922 -46.404576) (xy 249.799562 -46.35493) (xy 249.869507 -46.311559)
			(xy 249.943158 -46.274833) (xy 250.019887 -46.245067) (xy 250.099037 -46.222516) (xy 250.179932 -46.207371)
			(xy 250.26188 -46.199763) (xy 250.30303 -46.199298) (xy 250.344133 -46.199738) (xy 250.425989 -46.207326)
			(xy 250.506795 -46.222434) (xy 250.585862 -46.244933) (xy 250.662517 -46.274631) (xy 250.736104 -46.311276)
			(xy 250.805996 -46.354553) (xy 250.871597 -46.404095) (xy 250.932347 -46.459479) (xy 250.987728 -46.520231)
			(xy 251.037267 -46.585834) (xy 251.080542 -46.655728) (xy 251.117183 -46.729316) (xy 251.146879 -46.805972)
			(xy 251.169375 -46.88504) (xy 251.184479 -46.965847) (xy 251.192064 -47.047703) (xy 251.192538 -47.088806)
			(xy 251.192049 -47.13012) (xy 251.184383 -47.212393) (xy 251.16912 -47.293599) (xy 251.146389 -47.37304)
			(xy 251.116387 -47.450029) (xy 251.079373 -47.523904) (xy 251.057918 -47.559214) (xy 251.050806 -47.570644)
			(xy 251.04979 -47.596552) (xy 251.10059 -47.698152) (xy 251.12218 -47.712884) (xy 251.135388 -47.714154)
			(xy 251.163573 -47.717102) (xy 251.218695 -47.730247) (xy 251.271265 -47.751405) (xy 251.320124 -47.780109)
			(xy 251.364198 -47.815727) (xy 251.402516 -47.857476) (xy 251.434233 -47.904436) (xy 251.458652 -47.955573)
			(xy 251.475234 -48.00976) (xy 251.483615 -48.065804) (xy 251.48413 -48.094138) (xy 251.483644 -48.121389)
			(xy 251.475888 -48.175337) (xy 251.460533 -48.227632) (xy 251.437891 -48.277209) (xy 251.408425 -48.323059)
			(xy 251.372734 -48.36425) (xy 251.331543 -48.399941) (xy 251.285693 -48.429407) (xy 251.236116 -48.452049)
			(xy 251.183821 -48.467404) (xy 251.129873 -48.47516) (xy 251.075371 -48.47516) (xy 251.021423 -48.467404)
			(xy 250.969128 -48.452049) (xy 250.919551 -48.429407) (xy 250.873701 -48.399941) (xy 250.83251 -48.36425)
			(xy 250.796819 -48.323059) (xy 250.767353 -48.277209) (xy 250.744711 -48.227632) (xy 250.729356 -48.175337)
			(xy 250.7216 -48.121389) (xy 250.721114 -48.094138) (xy 250.721234 -48.080693) (xy 250.72314 -48.053871)
			(xy 250.724924 -48.040544) (xy 250.726702 -48.027336) (xy 250.717304 -48.002952) (xy 250.629928 -47.930562)
			(xy 250.60402 -47.92599) (xy 250.59132 -47.930308) (xy 250.544796 -47.945523) (xy 250.449269 -47.966891)
			(xy 250.351974 -47.977642) (xy 250.30303 -47.978314) (xy 250.261878 -47.97783) (xy 250.179925 -47.970238)
			(xy 250.099025 -47.955107) (xy 250.019868 -47.932566) (xy 249.943132 -47.902808) (xy 249.869474 -47.866088)
			(xy 249.799524 -47.82272) (xy 249.733879 -47.773075) (xy 249.673102 -47.717576) (xy 249.617713 -47.656701)
			(xy 249.568184 -47.590968) (xy 249.524941 -47.52094) (xy 249.506232 -47.484284) (xy 249.501673 -47.476099)
			(xy 249.487865 -47.46346) (xy 249.479308 -47.459646) (xy 249.45086 -47.44847) (xy 249.442209 -47.445577)
			(xy 249.423985 -47.445432) (xy 249.4153 -47.448216) (xy 249.384244 -47.458544) (xy 249.319752 -47.469658)
			(xy 249.28703 -47.470314) (xy 249.259776 -47.469841) (xy 249.205823 -47.462087) (xy 249.153522 -47.446734)
			(xy 249.103939 -47.424094) (xy 249.058083 -47.394627) (xy 249.016887 -47.358934) (xy 248.981191 -47.317741)
			(xy 248.951721 -47.271887) (xy 248.929076 -47.222306) (xy 248.913719 -47.170006) (xy 248.905961 -47.116054)
			(xy 242.383564 -47.116054) (xy 242.383564 -47.23765) (xy 242.387374 -47.250858) (xy 242.39093 -47.256954)
			(xy 242.394436 -47.263059) (xy 242.398309 -47.276589) (xy 242.39855 -47.283624) (xy 242.39855 -50.779172)
			(xy 242.399018 -50.789046) (xy 242.40647 -50.807335) (xy 242.413028 -50.814732) (xy 242.413282 -50.814986)
			(xy 243.656358 -52.058062) (xy 243.662942 -52.06418) (xy 243.679224 -52.071763) (xy 243.697123 -52.073267)
			(xy 243.705888 -52.07127) (xy 243.804694 -52.043584) (xy 243.82349 -52.024026) (xy 243.827046 -52.010564)
			(xy 243.834257 -51.983309) (xy 243.855613 -51.931132) (xy 243.884421 -51.882671) (xy 243.920054 -51.838983)
			(xy 243.961734 -51.801019) (xy 244.008551 -51.76961) (xy 244.059485 -51.74544) (xy 244.113423 -51.729037)
			(xy 244.169189 -51.720758) (xy 244.197378 -51.720242) (xy 244.223758 -51.720686) (xy 244.276017 -51.727946)
			(xy 244.326778 -51.742332) (xy 244.375076 -51.763569) (xy 244.41999 -51.791253) (xy 244.460664 -51.824857)
			(xy 244.496326 -51.863741) (xy 244.526294 -51.907164) (xy 244.5385 -51.930554) (xy 244.54485 -51.943762)
			(xy 244.569234 -51.958748) (xy 244.689122 -51.958748) (xy 244.713506 -51.943762) (xy 244.719856 -51.930554)
			(xy 244.732101 -51.907187) (xy 244.762062 -51.863764) (xy 244.797716 -51.824881) (xy 244.838386 -51.791278)
			(xy 244.883295 -51.763596) (xy 244.931588 -51.742362) (xy 244.982346 -51.727981) (xy 245.0346 -51.720727)
			(xy 245.060978 -51.720242) (xy 245.088228 -51.720704) (xy 245.142175 -51.728457) (xy 245.194468 -51.743809)
			(xy 245.244045 -51.766448) (xy 245.289894 -51.795911) (xy 245.331084 -51.8316) (xy 245.366776 -51.872788)
			(xy 245.396242 -51.918636) (xy 245.418883 -51.968211) (xy 245.434238 -52.020504) (xy 245.441995 -52.07445)
			(xy 245.441995 -52.12895) (xy 245.434238 -52.182896) (xy 245.418883 -52.235189) (xy 245.396242 -52.284764)
			(xy 245.366776 -52.330612) (xy 245.331084 -52.3718) (xy 245.289894 -52.407489) (xy 245.244045 -52.436952)
			(xy 245.194468 -52.459591) (xy 245.142175 -52.474943) (xy 245.088228 -52.482696) (xy 245.060978 -52.483258)
			(xy 245.034599 -52.482811) (xy 244.982345 -52.475546) (xy 244.931588 -52.461156) (xy 244.883295 -52.439915)
			(xy 244.838386 -52.412229) (xy 244.797716 -52.378624) (xy 244.762059 -52.33974) (xy 244.732095 -52.296318)
			(xy 244.719856 -52.272946) (xy 244.713506 -52.259738) (xy 244.689122 -52.244752) (xy 244.569234 -52.244752)
			(xy 244.54485 -52.259738) (xy 244.5385 -52.272946) (xy 244.525717 -52.297289) (xy 244.494218 -52.342351)
			(xy 244.456579 -52.382429) (xy 244.413579 -52.416692) (xy 244.366109 -52.444431) (xy 244.31515 -52.465072)
			(xy 244.288564 -52.472082) (xy 244.275102 -52.475638) (xy 244.255544 -52.494434) (xy 244.227858 -52.59324)
			(xy 244.225818 -52.601998) (xy 244.227333 -52.619904) (xy 244.234943 -52.636184) (xy 244.241066 -52.64277)
			(xy 244.460268 -52.861972) (xy 244.460776 -52.86248) (xy 244.46816 -52.869056) (xy 244.486458 -52.876494)
			(xy 244.496336 -52.876958)
		)
		(stroke
			(width 0)
			(type solid)
		)
		(fill yes)
		(layer "In2.Cu")
		(net "P12V_E1S_0")
	)
	(gr_poly
		(pts
			(xy 134.095998 -81.31302) (xy 134.105877 -81.312564) (xy 134.124183 -81.305128) (xy 134.131558 -81.298542)
			(xy 134.131812 -81.298288) (xy 134.152894 -81.277206) (xy 134.153402 -81.276698) (xy 134.159982 -81.269317)
			(xy 134.167423 -81.251017) (xy 134.16788 -81.241138) (xy 134.16788 -70.018656) (xy 134.167448 -70.00859)
			(xy 134.15972 -69.989999) (xy 134.152894 -69.982588) (xy 134.023354 -69.853048) (xy 134.016242 -69.845682)
			(xy 133.997446 -69.838062) (xy 114.682778 -69.838062) (xy 114.672711 -69.838491) (xy 114.654118 -69.846218)
			(xy 114.64671 -69.853048) (xy 113.884202 -70.615556) (xy 113.883948 -70.615556) (xy 113.848134 -70.65137)
			(xy 113.840768 -70.658482) (xy 113.833148 -70.677278) (xy 113.833148 -71.348648) (xy 115.0666 -71.348648)
			(xy 115.0666 -71.294152) (xy 115.074355 -71.24021) (xy 115.089708 -71.18792) (xy 115.112346 -71.138348)
			(xy 115.141808 -71.092501) (xy 115.177494 -71.051314) (xy 115.218679 -71.015625) (xy 115.264523 -70.986159)
			(xy 115.314094 -70.963518) (xy 115.366382 -70.948161) (xy 115.420324 -70.940402) (xy 115.447572 -70.939914)
			(xy 115.476004 -70.940456) (xy 115.53224 -70.948887) (xy 115.586599 -70.965582) (xy 115.637873 -70.990169)
			(xy 115.661694 -71.0057) (xy 115.670838 -71.011796) (xy 115.691412 -71.015606) (xy 115.785646 -70.993254)
			(xy 115.802156 -70.980554) (xy 115.80749 -70.970902) (xy 115.822018 -70.945803) (xy 115.857558 -70.899975)
			(xy 115.899623 -70.860052) (xy 115.947244 -70.826955) (xy 115.999325 -70.801445) (xy 116.054667 -70.784109)
			(xy 116.111995 -70.775347) (xy 116.140992 -70.774814) (xy 116.168246 -70.775263) (xy 116.222198 -70.783019)
			(xy 116.274498 -70.798375) (xy 116.324079 -70.821019) (xy 116.369933 -70.850488) (xy 116.411127 -70.886183)
			(xy 116.446821 -70.927378) (xy 116.476288 -70.973233) (xy 116.498929 -71.022815) (xy 116.514284 -71.075115)
			(xy 116.522038 -71.129068) (xy 116.5225 -71.156322) (xy 116.522047 -71.183693) (xy 116.514226 -71.237872)
			(xy 116.498734 -71.290376) (xy 116.480376 -71.330352) (xy 130.866589 -71.330352) (xy 130.866589 -71.275848)
			(xy 130.874347 -71.221898) (xy 130.889704 -71.169601) (xy 130.912347 -71.120023) (xy 130.941816 -71.074172)
			(xy 130.977511 -71.032982) (xy 131.018705 -70.997291) (xy 131.06456 -70.967827) (xy 131.114141 -70.945189)
			(xy 131.166439 -70.929838) (xy 131.22039 -70.922086) (xy 131.247642 -70.921626) (xy 131.275352 -70.922112)
			(xy 131.330187 -70.930142) (xy 131.383282 -70.946025) (xy 131.433518 -70.969427) (xy 131.479837 -70.999856)
			(xy 131.50088 -71.017892) (xy 131.507992 -71.023988) (xy 131.525264 -71.030592) (xy 131.61137 -71.030592)
			(xy 131.628642 -71.023988) (xy 131.635754 -71.017892) (xy 131.656797 -70.999858) (xy 131.703117 -70.969432)
			(xy 131.753353 -70.946034) (xy 131.806448 -70.930156) (xy 131.861283 -70.922132) (xy 131.916701 -70.922132)
			(xy 131.971536 -70.930156) (xy 132.024631 -70.946034) (xy 132.074867 -70.969432) (xy 132.121187 -70.999858)
			(xy 132.14223 -71.017892) (xy 132.149342 -71.023988) (xy 132.166614 -71.030592) (xy 132.25272 -71.030592)
			(xy 132.269992 -71.023988) (xy 132.277104 -71.017892) (xy 132.298136 -70.999844) (xy 132.344457 -70.969416)
			(xy 132.394696 -70.946017) (xy 132.447794 -70.93014) (xy 132.502632 -70.92212) (xy 132.530342 -70.921626)
			(xy 132.557594 -70.922047) (xy 132.611542 -70.929809) (xy 132.663836 -70.945169) (xy 132.713412 -70.967814)
			(xy 132.759262 -70.997285) (xy 132.800451 -71.032979) (xy 132.836141 -71.074172) (xy 132.865606 -71.120024)
			(xy 132.888246 -71.169603) (xy 132.9036 -71.221899) (xy 132.911356 -71.275848) (xy 132.911356 -71.330352)
			(xy 132.9036 -71.384301) (xy 132.888246 -71.436597) (xy 132.865606 -71.486176) (xy 132.836141 -71.532028)
			(xy 132.800451 -71.573221) (xy 132.759262 -71.608915) (xy 132.713412 -71.638386) (xy 132.663836 -71.661031)
			(xy 132.611542 -71.676391) (xy 132.557594 -71.684153) (xy 132.530342 -71.684642) (xy 132.502633 -71.684148)
			(xy 132.447799 -71.676118) (xy 132.394704 -71.660236) (xy 132.344468 -71.636835) (xy 132.298148 -71.60641)
			(xy 132.277104 -71.588376) (xy 132.269992 -71.58228) (xy 132.25272 -71.575676) (xy 132.166614 -71.575676)
			(xy 132.149342 -71.58228) (xy 132.14223 -71.588376) (xy 132.121187 -71.60641) (xy 132.074867 -71.636836)
			(xy 132.024631 -71.660234) (xy 131.971536 -71.676112) (xy 131.916701 -71.684136) (xy 131.861283 -71.684136)
			(xy 131.806448 -71.676112) (xy 131.753353 -71.660234) (xy 131.703117 -71.636836) (xy 131.656797 -71.60641)
			(xy 131.635754 -71.588376) (xy 131.628642 -71.58228) (xy 131.61137 -71.575676) (xy 131.525264 -71.575676)
			(xy 131.507992 -71.58228) (xy 131.50088 -71.588376) (xy 131.479849 -71.606427) (xy 131.433529 -71.636855)
			(xy 131.383289 -71.660254) (xy 131.330191 -71.67613) (xy 131.275353 -71.684148) (xy 131.247642 -71.684642)
			(xy 131.22039 -71.684114) (xy 131.166439 -71.676362) (xy 131.114141 -71.661011) (xy 131.06456 -71.638373)
			(xy 131.018705 -71.608909) (xy 130.977511 -71.573218) (xy 130.941816 -71.532028) (xy 130.912347 -71.486177)
			(xy 130.889704 -71.436599) (xy 130.874347 -71.384302) (xy 130.866589 -71.330352) (xy 116.480376 -71.330352)
			(xy 116.475889 -71.340122) (xy 116.446162 -71.386089) (xy 116.42852 -71.40702) (xy 116.422424 -71.414132)
			(xy 116.416074 -71.43115) (xy 116.416074 -71.516494) (xy 116.422424 -71.533512) (xy 116.42852 -71.540624)
			(xy 116.44614 -71.561571) (xy 116.475854 -71.60754) (xy 116.498693 -71.657284) (xy 116.514189 -71.709781)
			(xy 116.522023 -71.763954) (xy 116.5225 -71.791322) (xy 116.522094 -71.817196) (xy 116.515108 -71.86847)
			(xy 116.501254 -71.918328) (xy 116.480786 -71.965856) (xy 116.454081 -72.01018) (xy 116.421628 -72.050487)
			(xy 116.384023 -72.086036) (xy 116.363242 -72.101456) (xy 116.355622 -72.107044) (xy 116.345208 -72.122792)
			(xy 116.327174 -72.208644) (xy 116.330222 -72.22744) (xy 116.335048 -72.235568) (xy 116.347727 -72.257734)
			(xy 116.367675 -72.304741) (xy 116.381173 -72.35399) (xy 116.387981 -72.404599) (xy 116.388388 -72.430132)
			(xy 116.387902 -72.457383) (xy 116.380146 -72.511331) (xy 116.364791 -72.563626) (xy 116.363697 -72.566022)
			(xy 119.059704 -72.566022) (xy 119.063775 -72.5104) (xy 119.075901 -72.455963) (xy 119.095824 -72.403872)
			(xy 119.12312 -72.355237) (xy 119.157206 -72.311094) (xy 119.197355 -72.272385) (xy 119.242713 -72.239934)
			(xy 119.292313 -72.214433) (xy 119.345097 -72.196426) (xy 119.39994 -72.186296) (xy 119.455674 -72.184259)
			(xy 119.511111 -72.190359) (xy 119.565068 -72.204465) (xy 119.616397 -72.226277) (xy 119.664003 -72.255331)
			(xy 119.706871 -72.291006) (xy 119.744088 -72.332543) (xy 119.774861 -72.379056) (xy 119.798533 -72.429553)
			(xy 119.814601 -72.48296) (xy 119.822721 -72.538136) (xy 119.82323 -72.566022) (xy 119.822721 -72.593908)
			(xy 119.819349 -72.616822) (xy 122.509024 -72.616822) (xy 122.513095 -72.5612) (xy 122.525221 -72.506763)
			(xy 122.545144 -72.454672) (xy 122.57244 -72.406037) (xy 122.606526 -72.361894) (xy 122.646675 -72.323185)
			(xy 122.692033 -72.290734) (xy 122.741633 -72.265233) (xy 122.794417 -72.247226) (xy 122.84926 -72.237096)
			(xy 122.904994 -72.235059) (xy 122.960431 -72.241159) (xy 123.014388 -72.255265) (xy 123.065717 -72.277077)
			(xy 123.113323 -72.306131) (xy 123.156191 -72.341806) (xy 123.193408 -72.383343) (xy 123.224181 -72.429856)
			(xy 123.247853 -72.480353) (xy 123.263921 -72.53376) (xy 123.272041 -72.588936) (xy 123.27255 -72.616822)
			(xy 123.272041 -72.644708) (xy 123.263921 -72.699884) (xy 123.247853 -72.753291) (xy 123.224181 -72.803788)
			(xy 123.193408 -72.850301) (xy 123.156191 -72.891838) (xy 123.113323 -72.927513) (xy 123.065717 -72.956567)
			(xy 123.014388 -72.978379) (xy 122.960431 -72.992485) (xy 122.904994 -72.998585) (xy 122.84926 -72.996548)
			(xy 122.794417 -72.986418) (xy 122.741633 -72.968411) (xy 122.692033 -72.94291) (xy 122.646675 -72.910459)
			(xy 122.606526 -72.87175) (xy 122.57244 -72.827607) (xy 122.545144 -72.778972) (xy 122.525221 -72.726881)
			(xy 122.513095 -72.672444) (xy 122.509024 -72.616822) (xy 119.819349 -72.616822) (xy 119.814601 -72.649084)
			(xy 119.798533 -72.702491) (xy 119.774861 -72.752988) (xy 119.744088 -72.799501) (xy 119.706871 -72.841038)
			(xy 119.664003 -72.876713) (xy 119.616397 -72.905767) (xy 119.565068 -72.927579) (xy 119.511111 -72.941685)
			(xy 119.455674 -72.947785) (xy 119.39994 -72.945748) (xy 119.345097 -72.935618) (xy 119.292313 -72.917611)
			(xy 119.242713 -72.89211) (xy 119.197355 -72.859659) (xy 119.157206 -72.82095) (xy 119.12312 -72.776807)
			(xy 119.095824 -72.728172) (xy 119.075901 -72.676081) (xy 119.063775 -72.621644) (xy 119.059704 -72.566022)
			(xy 116.363697 -72.566022) (xy 116.342149 -72.613203) (xy 116.312683 -72.659053) (xy 116.276992 -72.700244)
			(xy 116.235801 -72.735935) (xy 116.189951 -72.765401) (xy 116.140374 -72.788043) (xy 116.088079 -72.803398)
			(xy 116.034131 -72.811154) (xy 115.979629 -72.811154) (xy 115.925681 -72.803398) (xy 115.873386 -72.788043)
			(xy 115.823809 -72.765401) (xy 115.777959 -72.735935) (xy 115.736768 -72.700244) (xy 115.701077 -72.659053)
			(xy 115.671611 -72.613203) (xy 115.648969 -72.563626) (xy 115.633614 -72.511331) (xy 115.625858 -72.457383)
			(xy 115.625372 -72.430132) (xy 115.625788 -72.404258) (xy 115.632769 -72.352983) (xy 115.646618 -72.303124)
			(xy 115.667084 -72.255595) (xy 115.693788 -72.21127) (xy 115.726242 -72.170964) (xy 115.763848 -72.135417)
			(xy 115.78463 -72.119998) (xy 115.79225 -72.11441) (xy 115.802664 -72.098662) (xy 115.820698 -72.01281)
			(xy 115.81765 -71.994014) (xy 115.812824 -71.985886) (xy 115.800164 -71.96371) (xy 115.780212 -71.916706)
			(xy 115.766708 -71.86746) (xy 115.759894 -71.816854) (xy 115.759484 -71.791322) (xy 115.7605 -71.763128)
			(xy 115.761516 -71.749666) (xy 115.749578 -71.725028) (xy 115.654074 -71.660258) (xy 115.626896 -71.65848)
			(xy 115.614704 -71.664322) (xy 115.588549 -71.676514) (xy 115.533469 -71.693715) (xy 115.476424 -71.702406)
			(xy 115.447572 -71.70293) (xy 115.420324 -71.702398) (xy 115.366382 -71.694639) (xy 115.314094 -71.679282)
			(xy 115.264523 -71.656641) (xy 115.218679 -71.627175) (xy 115.177494 -71.591486) (xy 115.141808 -71.550299)
			(xy 115.112346 -71.504452) (xy 115.089708 -71.45488) (xy 115.074355 -71.40259) (xy 115.0666 -71.348648)
			(xy 113.833148 -71.348648) (xy 113.833148 -73.442156) (xy 130.485545 -73.442156) (xy 130.485545 -73.387644)
			(xy 130.493303 -73.333688) (xy 130.508662 -73.281386) (xy 130.531308 -73.231801) (xy 130.560781 -73.185945)
			(xy 130.59648 -73.14475) (xy 130.637679 -73.109056) (xy 130.683538 -73.079588) (xy 130.733125 -73.056947)
			(xy 130.785429 -73.041594) (xy 130.839386 -73.033842) (xy 130.866642 -73.033382) (xy 130.894351 -73.033879)
			(xy 130.949186 -73.041908) (xy 131.00228 -73.057789) (xy 131.052516 -73.081189) (xy 131.098836 -73.111614)
			(xy 131.11988 -73.129648) (xy 131.126992 -73.135744) (xy 131.144264 -73.142348) (xy 131.23037 -73.142348)
			(xy 131.247642 -73.135744) (xy 131.254754 -73.129648) (xy 131.275797 -73.111614) (xy 131.322117 -73.081188)
			(xy 131.372353 -73.05779) (xy 131.425448 -73.041912) (xy 131.480283 -73.033888) (xy 131.535701 -73.033888)
			(xy 131.590536 -73.041912) (xy 131.643631 -73.05779) (xy 131.693867 -73.081188) (xy 131.740187 -73.111614)
			(xy 131.76123 -73.129648) (xy 131.768342 -73.135744) (xy 131.785614 -73.142348) (xy 131.87172 -73.142348)
			(xy 131.888992 -73.135744) (xy 131.896104 -73.129648) (xy 131.917147 -73.111614) (xy 131.963467 -73.081188)
			(xy 132.013703 -73.05779) (xy 132.066798 -73.041912) (xy 132.121633 -73.033888) (xy 132.177051 -73.033888)
			(xy 132.231886 -73.041912) (xy 132.284981 -73.05779) (xy 132.335217 -73.081188) (xy 132.381537 -73.111614)
			(xy 132.40258 -73.129648) (xy 132.409692 -73.135744) (xy 132.426964 -73.142348) (xy 132.51307 -73.142348)
			(xy 132.530342 -73.135744) (xy 132.537454 -73.129648) (xy 132.5585 -73.111616) (xy 132.604817 -73.081187)
			(xy 132.655053 -73.057786) (xy 132.708148 -73.041905) (xy 132.762983 -73.03388) (xy 132.790692 -73.033382)
			(xy 132.817945 -73.033865) (xy 132.871895 -73.041621) (xy 132.924192 -73.056976) (xy 132.973772 -73.079617)
			(xy 133.019625 -73.109084) (xy 133.060818 -73.144777) (xy 133.096511 -73.185969) (xy 133.125979 -73.231821)
			(xy 133.148622 -73.2814) (xy 133.163978 -73.333697) (xy 133.171735 -73.387647) (xy 133.171735 -73.442153)
			(xy 133.163978 -73.496103) (xy 133.148622 -73.5484) (xy 133.125979 -73.597979) (xy 133.096511 -73.643831)
			(xy 133.060818 -73.685023) (xy 133.019625 -73.720716) (xy 132.973772 -73.750183) (xy 132.924192 -73.772824)
			(xy 132.871895 -73.788179) (xy 132.817945 -73.795935) (xy 132.790692 -73.796398) (xy 132.762983 -73.795886)
			(xy 132.708149 -73.787862) (xy 132.655055 -73.771984) (xy 132.604818 -73.748588) (xy 132.558498 -73.718165)
			(xy 132.537454 -73.700132) (xy 132.530342 -73.694036) (xy 132.51307 -73.687432) (xy 132.426964 -73.687432)
			(xy 132.409692 -73.694036) (xy 132.40258 -73.700132) (xy 132.381537 -73.718166) (xy 132.335217 -73.748592)
			(xy 132.284981 -73.77199) (xy 132.231886 -73.787868) (xy 132.177051 -73.795892) (xy 132.121633 -73.795892)
			(xy 132.066798 -73.787868) (xy 132.013703 -73.77199) (xy 131.963467 -73.748592) (xy 131.917147 -73.718166)
			(xy 131.896104 -73.700132) (xy 131.888992 -73.694036) (xy 131.87172 -73.687432) (xy 131.785614 -73.687432)
			(xy 131.768342 -73.694036) (xy 131.76123 -73.700132) (xy 131.740187 -73.718166) (xy 131.693867 -73.748592)
			(xy 131.643631 -73.77199) (xy 131.590536 -73.787868) (xy 131.535701 -73.795892) (xy 131.480283 -73.795892)
			(xy 131.425448 -73.787868) (xy 131.372353 -73.77199) (xy 131.322117 -73.748592) (xy 131.275797 -73.718166)
			(xy 131.254754 -73.700132) (xy 131.247642 -73.694036) (xy 131.23037 -73.687432) (xy 131.144264 -73.687432)
			(xy 131.126992 -73.694036) (xy 131.11988 -73.700132) (xy 131.098857 -73.718192) (xy 131.052533 -73.748617)
			(xy 131.002292 -73.772013) (xy 130.949192 -73.787888) (xy 130.894353 -73.795905) (xy 130.866642 -73.796398)
			(xy 130.839386 -73.795958) (xy 130.785429 -73.788206) (xy 130.733125 -73.772853) (xy 130.683538 -73.750212)
			(xy 130.637679 -73.720744) (xy 130.59648 -73.68505) (xy 130.560781 -73.643855) (xy 130.531308 -73.597999)
			(xy 130.508662 -73.548414) (xy 130.493303 -73.496112) (xy 130.485545 -73.442156) (xy 113.833148 -73.442156)
			(xy 113.833148 -74.038968) (xy 120.219214 -74.038968) (xy 120.223285 -73.983346) (xy 120.235411 -73.928909)
			(xy 120.255334 -73.876818) (xy 120.28263 -73.828183) (xy 120.316716 -73.78404) (xy 120.356865 -73.745331)
			(xy 120.402223 -73.71288) (xy 120.451823 -73.687379) (xy 120.504607 -73.669372) (xy 120.55945 -73.659242)
			(xy 120.615184 -73.657205) (xy 120.670621 -73.663305) (xy 120.724578 -73.677411) (xy 120.775907 -73.699223)
			(xy 120.823513 -73.728277) (xy 120.866381 -73.763952) (xy 120.903598 -73.805489) (xy 120.934371 -73.852002)
			(xy 120.958043 -73.902499) (xy 120.974111 -73.955906) (xy 120.982231 -74.011082) (xy 120.982314 -74.015652)
			(xy 122.273777 -74.015652) (xy 122.273777 -73.961148) (xy 122.281534 -73.907198) (xy 122.296891 -73.854901)
			(xy 122.319533 -73.805323) (xy 122.349002 -73.759471) (xy 122.384696 -73.71828) (xy 122.425889 -73.682589)
			(xy 122.471742 -73.653123) (xy 122.521322 -73.630483) (xy 122.57362 -73.61513) (xy 122.62757 -73.607376)
			(xy 122.654822 -73.606914) (xy 122.684157 -73.607438) (xy 122.742138 -73.616412) (xy 122.79806 -73.634158)
			(xy 122.850605 -73.660259) (xy 122.898533 -73.694099) (xy 122.919998 -73.714102) (xy 122.930403 -73.723572)
			(xy 122.955184 -73.736877) (xy 122.982652 -73.742927) (xy 123.010729 -73.741263) (xy 123.037291 -73.732012)
			(xy 123.060327 -73.715873) (xy 123.078093 -73.694068) (xy 123.084082 -73.681336) (xy 123.095504 -73.656036)
			(xy 123.124646 -73.60879) (xy 123.160328 -73.566267) (xy 123.201797 -73.529366) (xy 123.248177 -73.498865)
			(xy 123.298488 -73.475409) (xy 123.351668 -73.459494) (xy 123.406593 -73.451454) (xy 123.434348 -73.450958)
			(xy 123.461595 -73.451515) (xy 123.515532 -73.459277) (xy 123.567816 -73.474635) (xy 123.617383 -73.497277)
			(xy 123.663223 -73.526741) (xy 123.704404 -73.56243) (xy 123.740087 -73.603615) (xy 123.769546 -73.649459)
			(xy 123.792182 -73.699029) (xy 123.807533 -73.751315) (xy 123.815288 -73.805253) (xy 123.815288 -73.859747)
			(xy 123.807533 -73.913685) (xy 123.792182 -73.965971) (xy 123.769546 -74.015541) (xy 123.740087 -74.061385)
			(xy 123.704404 -74.10257) (xy 123.663223 -74.138259) (xy 123.617383 -74.167723) (xy 123.567816 -74.190365)
			(xy 123.515532 -74.205723) (xy 123.461595 -74.213485) (xy 123.434348 -74.213974) (xy 123.405014 -74.21341)
			(xy 123.347035 -74.204447) (xy 123.291113 -74.18671) (xy 123.238567 -74.160618) (xy 123.190638 -74.126786)
			(xy 123.169172 -74.106786) (xy 123.158793 -74.097285) (xy 123.134005 -74.083984) (xy 123.106531 -74.077939)
			(xy 123.078449 -74.079608) (xy 123.051884 -74.088865) (xy 123.028846 -74.105008) (xy 123.011077 -74.126817)
			(xy 123.005088 -74.139552) (xy 122.993604 -74.164823) (xy 122.964471 -74.212067) (xy 122.928797 -74.254589)
			(xy 122.887337 -74.291493) (xy 122.840967 -74.321997) (xy 122.790664 -74.345458) (xy 122.737492 -74.361381)
			(xy 122.682574 -74.369429) (xy 122.654822 -74.36993) (xy 122.62757 -74.369424) (xy 122.573619 -74.36167)
			(xy 122.521322 -74.346317) (xy 122.471742 -74.323677) (xy 122.425889 -74.294211) (xy 122.384696 -74.25852)
			(xy 122.349002 -74.217329) (xy 122.319533 -74.171477) (xy 122.296891 -74.121899) (xy 122.281534 -74.069602)
			(xy 122.273777 -74.015652) (xy 120.982314 -74.015652) (xy 120.98274 -74.038968) (xy 120.982231 -74.066854)
			(xy 120.974111 -74.12203) (xy 120.958043 -74.175437) (xy 120.934371 -74.225934) (xy 120.903598 -74.272447)
			(xy 120.866381 -74.313984) (xy 120.823513 -74.349659) (xy 120.775907 -74.378713) (xy 120.724578 -74.400525)
			(xy 120.670621 -74.414631) (xy 120.615184 -74.420731) (xy 120.55945 -74.418694) (xy 120.504607 -74.408564)
			(xy 120.451823 -74.390557) (xy 120.402223 -74.365056) (xy 120.356865 -74.332605) (xy 120.316716 -74.293896)
			(xy 120.28263 -74.249753) (xy 120.255334 -74.201118) (xy 120.235411 -74.149027) (xy 120.223285 -74.09459)
			(xy 120.219214 -74.038968) (xy 113.833148 -74.038968) (xy 113.833148 -78.016862) (xy 121.734324 -78.016862)
			(xy 121.738395 -77.96124) (xy 121.750521 -77.906803) (xy 121.770444 -77.854712) (xy 121.79774 -77.806077)
			(xy 121.831826 -77.761934) (xy 121.871975 -77.723225) (xy 121.917333 -77.690774) (xy 121.966933 -77.665273)
			(xy 122.019717 -77.647266) (xy 122.07456 -77.637136) (xy 122.130294 -77.635099) (xy 122.174162 -77.639926)
			(xy 122.569984 -77.639926) (xy 122.574055 -77.584304) (xy 122.586181 -77.529867) (xy 122.606104 -77.477776)
			(xy 122.6334 -77.429141) (xy 122.667486 -77.384998) (xy 122.707635 -77.346289) (xy 122.752993 -77.313838)
			(xy 122.802593 -77.288337) (xy 122.855377 -77.27033) (xy 122.91022 -77.2602) (xy 122.965954 -77.258163)
			(xy 123.021391 -77.264263) (xy 123.075348 -77.278369) (xy 123.126677 -77.300181) (xy 123.174283 -77.329235)
			(xy 123.217151 -77.36491) (xy 123.254368 -77.406447) (xy 123.285141 -77.45296) (xy 123.308813 -77.503457)
			(xy 123.318018 -77.534053) (xy 130.485585 -77.534053) (xy 130.485585 -77.479547) (xy 130.493343 -77.425597)
			(xy 130.5087 -77.3733) (xy 130.531344 -77.323721) (xy 130.560813 -77.277869) (xy 130.596509 -77.236679)
			(xy 130.637703 -77.200988) (xy 130.683558 -77.171523) (xy 130.733139 -77.148885) (xy 130.785438 -77.133534)
			(xy 130.839389 -77.125782) (xy 130.866642 -77.125322) (xy 130.894352 -77.125809) (xy 130.949187 -77.133838)
			(xy 131.002282 -77.149722) (xy 131.052518 -77.173124) (xy 131.098837 -77.203553) (xy 131.11988 -77.221588)
			(xy 131.126992 -77.227684) (xy 131.144264 -77.234288) (xy 131.23037 -77.234288) (xy 131.247642 -77.227684)
			(xy 131.254754 -77.221588) (xy 131.275797 -77.203554) (xy 131.322117 -77.173128) (xy 131.372353 -77.14973)
			(xy 131.425448 -77.133852) (xy 131.480283 -77.125828) (xy 131.535701 -77.125828) (xy 131.590536 -77.133852)
			(xy 131.643631 -77.14973) (xy 131.693867 -77.173128) (xy 131.740187 -77.203554) (xy 131.76123 -77.221588)
			(xy 131.768342 -77.227684) (xy 131.785614 -77.234288) (xy 131.87172 -77.234288) (xy 131.888992 -77.227684)
			(xy 131.896104 -77.221588) (xy 131.917136 -77.203539) (xy 131.963457 -77.173111) (xy 132.013696 -77.149713)
			(xy 132.066794 -77.133836) (xy 132.121631 -77.125816) (xy 132.149342 -77.125322) (xy 132.176593 -77.125751)
			(xy 132.230541 -77.133513) (xy 132.282835 -77.148873) (xy 132.332411 -77.171518) (xy 132.378259 -77.200988)
			(xy 132.419448 -77.236682) (xy 132.455137 -77.277874) (xy 132.484602 -77.323726) (xy 132.507242 -77.373305)
			(xy 132.522596 -77.4256) (xy 132.530352 -77.479549) (xy 132.530352 -77.534051) (xy 132.522596 -77.588)
			(xy 132.507242 -77.640295) (xy 132.484602 -77.689874) (xy 132.455137 -77.735726) (xy 132.419448 -77.776918)
			(xy 132.378259 -77.812612) (xy 132.33241 -77.842082) (xy 132.282835 -77.864727) (xy 132.230541 -77.880087)
			(xy 132.176593 -77.887849) (xy 132.149342 -77.888338) (xy 132.121633 -77.887845) (xy 132.066798 -77.879815)
			(xy 132.013704 -77.863932) (xy 131.963468 -77.840532) (xy 131.917148 -77.810106) (xy 131.896104 -77.792072)
			(xy 131.888992 -77.785976) (xy 131.87172 -77.779372) (xy 131.785614 -77.779372) (xy 131.768342 -77.785976)
			(xy 131.76123 -77.792072) (xy 131.740187 -77.810106) (xy 131.693867 -77.840532) (xy 131.643631 -77.86393)
			(xy 131.590536 -77.879808) (xy 131.535701 -77.887832) (xy 131.480283 -77.887832) (xy 131.425448 -77.879808)
			(xy 131.372353 -77.86393) (xy 131.322117 -77.840532) (xy 131.275797 -77.810106) (xy 131.254754 -77.792072)
			(xy 131.247642 -77.785976) (xy 131.23037 -77.779372) (xy 131.144264 -77.779372) (xy 131.126992 -77.785976)
			(xy 131.11988 -77.792072) (xy 131.098849 -77.810122) (xy 131.052528 -77.840551) (xy 131.002289 -77.86395)
			(xy 130.949191 -77.879826) (xy 130.894353 -77.887844) (xy 130.866642 -77.888338) (xy 130.839389 -77.887818)
			(xy 130.785438 -77.880066) (xy 130.733139 -77.864715) (xy 130.683558 -77.842077) (xy 130.637703 -77.812612)
			(xy 130.596509 -77.776921) (xy 130.560813 -77.735731) (xy 130.531344 -77.689879) (xy 130.5087 -77.6403)
			(xy 130.493343 -77.588003) (xy 130.485585 -77.534053) (xy 123.318018 -77.534053) (xy 123.324881 -77.556864)
			(xy 123.333001 -77.61204) (xy 123.33351 -77.639926) (xy 123.333001 -77.667812) (xy 123.324881 -77.722988)
			(xy 123.308813 -77.776395) (xy 123.285141 -77.826892) (xy 123.254368 -77.873405) (xy 123.217151 -77.914942)
			(xy 123.174283 -77.950617) (xy 123.126677 -77.979671) (xy 123.075348 -78.001483) (xy 123.021391 -78.015589)
			(xy 122.965954 -78.021689) (xy 122.91022 -78.019652) (xy 122.855377 -78.009522) (xy 122.802593 -77.991515)
			(xy 122.752993 -77.966014) (xy 122.707635 -77.933563) (xy 122.667486 -77.894854) (xy 122.6334 -77.850711)
			(xy 122.606104 -77.802076) (xy 122.586181 -77.749985) (xy 122.574055 -77.695548) (xy 122.569984 -77.639926)
			(xy 122.174162 -77.639926) (xy 122.185731 -77.641199) (xy 122.239688 -77.655305) (xy 122.291017 -77.677117)
			(xy 122.338623 -77.706171) (xy 122.381491 -77.741846) (xy 122.418708 -77.783383) (xy 122.449481 -77.829896)
			(xy 122.473153 -77.880393) (xy 122.489221 -77.9338) (xy 122.497341 -77.988976) (xy 122.49785 -78.016862)
			(xy 122.497341 -78.044748) (xy 122.489221 -78.099924) (xy 122.473153 -78.153331) (xy 122.449481 -78.203828)
			(xy 122.418708 -78.250341) (xy 122.381491 -78.291878) (xy 122.338623 -78.327553) (xy 122.291017 -78.356607)
			(xy 122.239688 -78.378419) (xy 122.185731 -78.392525) (xy 122.130294 -78.398625) (xy 122.07456 -78.396588)
			(xy 122.019717 -78.386458) (xy 121.966933 -78.368451) (xy 121.917333 -78.34295) (xy 121.871975 -78.310499)
			(xy 121.831826 -78.27179) (xy 121.79774 -78.227647) (xy 121.770444 -78.179012) (xy 121.750521 -78.126921)
			(xy 121.738395 -78.072484) (xy 121.734324 -78.016862) (xy 113.833148 -78.016862) (xy 113.833148 -79.580055)
			(xy 130.485555 -79.580055) (xy 130.485555 -79.525545) (xy 130.493314 -79.471591) (xy 130.508672 -79.419289)
			(xy 130.531317 -79.369707) (xy 130.560789 -79.323851) (xy 130.596487 -79.282658) (xy 130.637685 -79.246964)
			(xy 130.683543 -79.217497) (xy 130.733129 -79.194857) (xy 130.785432 -79.179505) (xy 130.839387 -79.171752)
			(xy 130.866642 -79.171292) (xy 130.894351 -79.171787) (xy 130.949186 -79.179815) (xy 131.00228 -79.195697)
			(xy 131.052517 -79.219098) (xy 131.098836 -79.249524) (xy 131.11988 -79.267558) (xy 131.126992 -79.273654)
			(xy 131.144264 -79.280258) (xy 131.23037 -79.280258) (xy 131.247642 -79.273654) (xy 131.254754 -79.267558)
			(xy 131.275797 -79.249524) (xy 131.322117 -79.219098) (xy 131.372353 -79.1957) (xy 131.425448 -79.179822)
			(xy 131.480283 -79.171798) (xy 131.535701 -79.171798) (xy 131.590536 -79.179822) (xy 131.643631 -79.1957)
			(xy 131.693867 -79.219098) (xy 131.740187 -79.249524) (xy 131.76123 -79.267558) (xy 131.768342 -79.273654)
			(xy 131.785614 -79.280258) (xy 131.87172 -79.280258) (xy 131.888992 -79.273654) (xy 131.896104 -79.267558)
			(xy 131.917132 -79.249504) (xy 131.963454 -79.219078) (xy 132.013695 -79.195681) (xy 132.066793 -79.179805)
			(xy 132.121631 -79.171786) (xy 132.149342 -79.171292) (xy 132.176591 -79.171781) (xy 132.230534 -79.179542)
			(xy 132.282824 -79.194901) (xy 132.332396 -79.217544) (xy 132.378241 -79.247012) (xy 132.419426 -79.282703)
			(xy 132.455113 -79.323892) (xy 132.484576 -79.369741) (xy 132.507214 -79.419315) (xy 132.522567 -79.471607)
			(xy 132.530322 -79.525551) (xy 132.530322 -79.580049) (xy 132.522567 -79.633993) (xy 132.507214 -79.686285)
			(xy 132.484576 -79.735859) (xy 132.455113 -79.781708) (xy 132.419426 -79.822897) (xy 132.378241 -79.858588)
			(xy 132.332396 -79.888056) (xy 132.282824 -79.910699) (xy 132.230534 -79.926058) (xy 132.176591 -79.933819)
			(xy 132.149342 -79.934308) (xy 132.121632 -79.933823) (xy 132.066797 -79.925792) (xy 132.013703 -79.909908)
			(xy 131.963467 -79.886505) (xy 131.917147 -79.856077) (xy 131.896104 -79.838042) (xy 131.888992 -79.831946)
			(xy 131.87172 -79.825342) (xy 131.785614 -79.825342) (xy 131.768342 -79.831946) (xy 131.76123 -79.838042)
			(xy 131.740187 -79.856076) (xy 131.693867 -79.886502) (xy 131.643631 -79.9099) (xy 131.590536 -79.925778)
			(xy 131.535701 -79.933802) (xy 131.480283 -79.933802) (xy 131.425448 -79.925778) (xy 131.372353 -79.9099)
			(xy 131.322117 -79.886502) (xy 131.275797 -79.856076) (xy 131.254754 -79.838042) (xy 131.247642 -79.831946)
			(xy 131.23037 -79.825342) (xy 131.144264 -79.825342) (xy 131.126992 -79.831946) (xy 131.11988 -79.838042)
			(xy 131.098859 -79.856103) (xy 131.052534 -79.886528) (xy 131.002292 -79.909924) (xy 130.949192 -79.925798)
			(xy 130.894353 -79.933815) (xy 130.866642 -79.934308) (xy 130.839387 -79.933848) (xy 130.785432 -79.926095)
			(xy 130.733129 -79.910743) (xy 130.683543 -79.888103) (xy 130.637685 -79.858636) (xy 130.596487 -79.822942)
			(xy 130.560789 -79.781749) (xy 130.531317 -79.735893) (xy 130.508672 -79.686311) (xy 130.493314 -79.634009)
			(xy 130.485555 -79.580055) (xy 113.833148 -79.580055) (xy 113.833148 -80.137508) (xy 121.321574 -80.137508)
			(xy 121.325645 -80.081886) (xy 121.337771 -80.027449) (xy 121.357694 -79.975358) (xy 121.38499 -79.926723)
			(xy 121.419076 -79.88258) (xy 121.459225 -79.843871) (xy 121.504583 -79.81142) (xy 121.554183 -79.785919)
			(xy 121.606967 -79.767912) (xy 121.66181 -79.757782) (xy 121.717544 -79.755745) (xy 121.772981 -79.761845)
			(xy 121.826938 -79.775951) (xy 121.878267 -79.797763) (xy 121.925873 -79.826817) (xy 121.968741 -79.862492)
			(xy 122.005958 -79.904029) (xy 122.036731 -79.950542) (xy 122.060403 -80.001039) (xy 122.076471 -80.054446)
			(xy 122.084591 -80.109622) (xy 122.0851 -80.137508) (xy 122.084591 -80.165394) (xy 122.076471 -80.22057)
			(xy 122.060403 -80.273977) (xy 122.036731 -80.324474) (xy 122.005958 -80.370987) (xy 121.968741 -80.412524)
			(xy 121.925873 -80.448199) (xy 121.878267 -80.477253) (xy 121.826938 -80.499065) (xy 121.772981 -80.513171)
			(xy 121.717544 -80.519271) (xy 121.66181 -80.517234) (xy 121.606967 -80.507104) (xy 121.554183 -80.489097)
			(xy 121.504583 -80.463596) (xy 121.459225 -80.431145) (xy 121.419076 -80.392436) (xy 121.38499 -80.348293)
			(xy 121.357694 -80.299658) (xy 121.337771 -80.247567) (xy 121.325645 -80.19313) (xy 121.321574 -80.137508)
			(xy 113.833148 -80.137508) (xy 113.833148 -81.241138) (xy 113.83361 -81.251015) (xy 113.841053 -81.269313)
			(xy 113.847626 -81.276698) (xy 113.84788 -81.276952) (xy 113.868962 -81.298034) (xy 113.86947 -81.298542)
			(xy 113.876851 -81.305123) (xy 113.895151 -81.312569) (xy 113.90503 -81.31302)
		)
		(stroke
			(width 0)
			(type solid)
		)
		(fill yes)
		(layer "In2.Cu")
		(net "GND")
	)
	(gr_poly
		(pts
			(xy 156.193998 -83.59902) (xy 156.204069 -83.598598) (xy 156.222676 -83.590886) (xy 156.230066 -83.584034)
			(xy 156.250894 -83.563206) (xy 156.257742 -83.555808) (xy 156.26548 -83.53721) (xy 156.26588 -83.527138)
			(xy 156.26588 -72.304656) (xy 156.265448 -72.29459) (xy 156.25772 -72.275999) (xy 156.250894 -72.268588)
			(xy 156.121354 -72.139048) (xy 156.114242 -72.131682) (xy 156.095446 -72.124062) (xy 136.780778 -72.124062)
			(xy 136.770711 -72.124491) (xy 136.752118 -72.132218) (xy 136.74471 -72.139048) (xy 135.982202 -72.901556)
			(xy 135.981948 -72.901556) (xy 135.946134 -72.93737) (xy 135.938768 -72.944482) (xy 135.931148 -72.963278)
			(xy 135.931148 -73.621953) (xy 137.238177 -73.621953) (xy 137.238177 -73.567447) (xy 137.245935 -73.513497)
			(xy 137.261291 -73.461199) (xy 137.283935 -73.41162) (xy 137.313404 -73.365768) (xy 137.349099 -73.324577)
			(xy 137.390293 -73.288885) (xy 137.436148 -73.25942) (xy 137.485729 -73.23678) (xy 137.538028 -73.221428)
			(xy 137.591979 -73.213675) (xy 137.619232 -73.213214) (xy 137.650162 -73.213794) (xy 137.711216 -73.223731)
			(xy 137.769868 -73.243389) (xy 137.824579 -73.272252) (xy 137.84961 -73.29043) (xy 137.858246 -73.297288)
			(xy 137.88009 -73.302114) (xy 137.977118 -73.281032) (xy 137.994898 -73.267824) (xy 138.000232 -73.257918)
			(xy 138.014686 -73.232456) (xy 138.050123 -73.185852) (xy 138.092266 -73.14521) (xy 138.140124 -73.111485)
			(xy 138.192573 -73.08547) (xy 138.248382 -73.067774) (xy 138.306239 -73.058814) (xy 138.335512 -73.058274)
			(xy 138.362763 -73.058767) (xy 138.416709 -73.066524) (xy 138.469003 -73.08188) (xy 138.518579 -73.104521)
			(xy 138.564428 -73.133987) (xy 138.605618 -73.169678) (xy 138.641309 -73.210867) (xy 138.670776 -73.256716)
			(xy 138.693418 -73.306292) (xy 138.708774 -73.358585) (xy 138.716533 -73.412531) (xy 138.71702 -73.439782)
			(xy 138.716563 -73.467153) (xy 138.708746 -73.521333) (xy 138.693256 -73.573837) (xy 138.673733 -73.616352)
			(xy 152.964589 -73.616352) (xy 152.964589 -73.561848) (xy 152.972347 -73.507898) (xy 152.987704 -73.455601)
			(xy 153.010347 -73.406023) (xy 153.039816 -73.360172) (xy 153.075511 -73.318982) (xy 153.116705 -73.283291)
			(xy 153.16256 -73.253827) (xy 153.212141 -73.231189) (xy 153.264439 -73.215838) (xy 153.31839 -73.208086)
			(xy 153.345642 -73.207626) (xy 153.373352 -73.208112) (xy 153.428187 -73.216142) (xy 153.481282 -73.232025)
			(xy 153.531518 -73.255427) (xy 153.577837 -73.285856) (xy 153.59888 -73.303892) (xy 153.605992 -73.309988)
			(xy 153.623264 -73.316592) (xy 153.70937 -73.316592) (xy 153.726642 -73.309988) (xy 153.733754 -73.303892)
			(xy 153.754797 -73.285858) (xy 153.801117 -73.255432) (xy 153.851353 -73.232034) (xy 153.904448 -73.216156)
			(xy 153.959283 -73.208132) (xy 154.014701 -73.208132) (xy 154.069536 -73.216156) (xy 154.122631 -73.232034)
			(xy 154.172867 -73.255432) (xy 154.219187 -73.285858) (xy 154.24023 -73.303892) (xy 154.247342 -73.309988)
			(xy 154.264614 -73.316592) (xy 154.35072 -73.316592) (xy 154.367992 -73.309988) (xy 154.375104 -73.303892)
			(xy 154.396136 -73.285844) (xy 154.442457 -73.255416) (xy 154.492696 -73.232017) (xy 154.545794 -73.21614)
			(xy 154.600632 -73.20812) (xy 154.628342 -73.207626) (xy 154.655594 -73.208047) (xy 154.709542 -73.215809)
			(xy 154.761836 -73.231169) (xy 154.811412 -73.253814) (xy 154.857262 -73.283285) (xy 154.898451 -73.318979)
			(xy 154.934141 -73.360172) (xy 154.963606 -73.406024) (xy 154.986246 -73.455603) (xy 155.0016 -73.507899)
			(xy 155.009356 -73.561848) (xy 155.009356 -73.616352) (xy 155.0016 -73.670301) (xy 154.986246 -73.722597)
			(xy 154.963606 -73.772176) (xy 154.934141 -73.818028) (xy 154.898451 -73.859221) (xy 154.857262 -73.894915)
			(xy 154.811412 -73.924386) (xy 154.761836 -73.947031) (xy 154.709542 -73.962391) (xy 154.655594 -73.970153)
			(xy 154.628342 -73.970642) (xy 154.600633 -73.970148) (xy 154.545799 -73.962118) (xy 154.492704 -73.946236)
			(xy 154.442468 -73.922835) (xy 154.396148 -73.89241) (xy 154.375104 -73.874376) (xy 154.367992 -73.86828)
			(xy 154.35072 -73.861676) (xy 154.264614 -73.861676) (xy 154.247342 -73.86828) (xy 154.24023 -73.874376)
			(xy 154.219187 -73.89241) (xy 154.172867 -73.922836) (xy 154.122631 -73.946234) (xy 154.069536 -73.962112)
			(xy 154.014701 -73.970136) (xy 153.959283 -73.970136) (xy 153.904448 -73.962112) (xy 153.851353 -73.946234)
			(xy 153.801117 -73.922836) (xy 153.754797 -73.89241) (xy 153.733754 -73.874376) (xy 153.726642 -73.86828)
			(xy 153.70937 -73.861676) (xy 153.623264 -73.861676) (xy 153.605992 -73.86828) (xy 153.59888 -73.874376)
			(xy 153.577849 -73.892427) (xy 153.531529 -73.922855) (xy 153.481289 -73.946254) (xy 153.428191 -73.96213)
			(xy 153.373353 -73.970148) (xy 153.345642 -73.970642) (xy 153.31839 -73.970114) (xy 153.264439 -73.962362)
			(xy 153.212141 -73.947011) (xy 153.16256 -73.924373) (xy 153.116705 -73.894909) (xy 153.075511 -73.859218)
			(xy 153.039816 -73.818028) (xy 153.010347 -73.772177) (xy 152.987704 -73.722599) (xy 152.972347 -73.670302)
			(xy 152.964589 -73.616352) (xy 138.673733 -73.616352) (xy 138.670412 -73.623584) (xy 138.640683 -73.669549)
			(xy 138.62304 -73.69048) (xy 138.616944 -73.697592) (xy 138.610594 -73.71461) (xy 138.610594 -73.799954)
			(xy 138.616944 -73.816972) (xy 138.62304 -73.824084) (xy 138.640692 -73.845006) (xy 138.6704 -73.890982)
			(xy 138.693233 -73.940732) (xy 138.708722 -73.993235) (xy 138.716548 -74.047412) (xy 138.71702 -74.074782)
			(xy 138.716585 -74.101067) (xy 138.709381 -74.153142) (xy 138.695094 -74.203734) (xy 138.673994 -74.251885)
			(xy 138.646482 -74.296681) (xy 138.613077 -74.337274) (xy 138.574415 -74.372896) (xy 138.531227 -74.40287)
			(xy 138.507978 -74.415142) (xy 138.498834 -74.419714) (xy 138.48588 -74.4347) (xy 138.45667 -74.521822)
			(xy 138.458194 -74.54138) (xy 138.462512 -74.550524) (xy 138.474828 -74.576829) (xy 138.492268 -74.632227)
			(xy 138.501085 -74.689633) (xy 138.501628 -74.718672) (xy 138.501142 -74.745923) (xy 138.493386 -74.799871)
			(xy 138.478073 -74.852022) (xy 141.157704 -74.852022) (xy 141.161775 -74.7964) (xy 141.173901 -74.741963)
			(xy 141.193824 -74.689872) (xy 141.22112 -74.641237) (xy 141.255206 -74.597094) (xy 141.295355 -74.558385)
			(xy 141.340713 -74.525934) (xy 141.390313 -74.500433) (xy 141.443097 -74.482426) (xy 141.49794 -74.472296)
			(xy 141.553674 -74.470259) (xy 141.609111 -74.476359) (xy 141.663068 -74.490465) (xy 141.714397 -74.512277)
			(xy 141.762003 -74.541331) (xy 141.804871 -74.577006) (xy 141.842088 -74.618543) (xy 141.872861 -74.665056)
			(xy 141.896533 -74.715553) (xy 141.912601 -74.76896) (xy 141.920721 -74.824136) (xy 141.92123 -74.852022)
			(xy 141.920721 -74.879908) (xy 141.917349 -74.902822) (xy 144.607024 -74.902822) (xy 144.611095 -74.8472)
			(xy 144.623221 -74.792763) (xy 144.643144 -74.740672) (xy 144.67044 -74.692037) (xy 144.704526 -74.647894)
			(xy 144.744675 -74.609185) (xy 144.790033 -74.576734) (xy 144.839633 -74.551233) (xy 144.892417 -74.533226)
			(xy 144.94726 -74.523096) (xy 145.002994 -74.521059) (xy 145.058431 -74.527159) (xy 145.112388 -74.541265)
			(xy 145.163717 -74.563077) (xy 145.211323 -74.592131) (xy 145.254191 -74.627806) (xy 145.291408 -74.669343)
			(xy 145.322181 -74.715856) (xy 145.345853 -74.766353) (xy 145.361921 -74.81976) (xy 145.370041 -74.874936)
			(xy 145.37055 -74.902822) (xy 145.370041 -74.930708) (xy 145.361921 -74.985884) (xy 145.345853 -75.039291)
			(xy 145.322181 -75.089788) (xy 145.291408 -75.136301) (xy 145.254191 -75.177838) (xy 145.211323 -75.213513)
			(xy 145.163717 -75.242567) (xy 145.112388 -75.264379) (xy 145.058431 -75.278485) (xy 145.002994 -75.284585)
			(xy 144.94726 -75.282548) (xy 144.892417 -75.272418) (xy 144.839633 -75.254411) (xy 144.790033 -75.22891)
			(xy 144.744675 -75.196459) (xy 144.704526 -75.15775) (xy 144.67044 -75.113607) (xy 144.643144 -75.064972)
			(xy 144.623221 -75.012881) (xy 144.611095 -74.958444) (xy 144.607024 -74.902822) (xy 141.917349 -74.902822)
			(xy 141.912601 -74.935084) (xy 141.896533 -74.988491) (xy 141.872861 -75.038988) (xy 141.842088 -75.085501)
			(xy 141.804871 -75.127038) (xy 141.762003 -75.162713) (xy 141.714397 -75.191767) (xy 141.663068 -75.213579)
			(xy 141.609111 -75.227685) (xy 141.553674 -75.233785) (xy 141.49794 -75.231748) (xy 141.443097 -75.221618)
			(xy 141.390313 -75.203611) (xy 141.340713 -75.17811) (xy 141.295355 -75.145659) (xy 141.255206 -75.10695)
			(xy 141.22112 -75.062807) (xy 141.193824 -75.014172) (xy 141.173901 -74.962081) (xy 141.161775 -74.907644)
			(xy 141.157704 -74.852022) (xy 138.478073 -74.852022) (xy 138.478031 -74.852166) (xy 138.455389 -74.901743)
			(xy 138.425923 -74.947593) (xy 138.390232 -74.988784) (xy 138.349041 -75.024475) (xy 138.303191 -75.053941)
			(xy 138.253614 -75.076583) (xy 138.201319 -75.091938) (xy 138.147371 -75.099694) (xy 138.092869 -75.099694)
			(xy 138.038921 -75.091938) (xy 137.986626 -75.076583) (xy 137.937049 -75.053941) (xy 137.891199 -75.024475)
			(xy 137.850008 -74.988784) (xy 137.814317 -74.947593) (xy 137.784851 -74.901743) (xy 137.762209 -74.852166)
			(xy 137.746854 -74.799871) (xy 137.739098 -74.745923) (xy 137.738612 -74.718672) (xy 137.739074 -74.692387)
			(xy 137.746271 -74.640313) (xy 137.760553 -74.589721) (xy 137.781648 -74.54157) (xy 137.809157 -74.496773)
			(xy 137.842558 -74.456179) (xy 137.881219 -74.420557) (xy 137.924406 -74.390584) (xy 137.947654 -74.378312)
			(xy 137.956798 -74.37374) (xy 137.969752 -74.358754) (xy 137.998962 -74.271632) (xy 137.997438 -74.252074)
			(xy 137.99312 -74.24293) (xy 137.980784 -74.216634) (xy 137.963352 -74.161231) (xy 137.954543 -74.103823)
			(xy 137.954004 -74.074782) (xy 137.954086 -74.063132) (xy 137.955484 -74.039875) (xy 137.956798 -74.0283)
			(xy 137.958576 -74.013822) (xy 137.946638 -73.987914) (xy 137.847324 -73.921366) (xy 137.818876 -73.920096)
			(xy 137.806176 -73.927208) (xy 137.784693 -73.93885) (xy 137.73939 -73.957162) (xy 137.692124 -73.969554)
			(xy 137.643664 -73.975822) (xy 137.619232 -73.97623) (xy 137.591979 -73.975725) (xy 137.538028 -73.967972)
			(xy 137.485729 -73.95262) (xy 137.436148 -73.92998) (xy 137.390293 -73.900515) (xy 137.349099 -73.864823)
			(xy 137.313404 -73.823632) (xy 137.283935 -73.77778) (xy 137.261291 -73.728201) (xy 137.245935 -73.675903)
			(xy 137.238177 -73.621953) (xy 135.931148 -73.621953) (xy 135.931148 -76.324968) (xy 142.317214 -76.324968)
			(xy 142.321285 -76.269346) (xy 142.333411 -76.214909) (xy 142.353334 -76.162818) (xy 142.38063 -76.114183)
			(xy 142.414716 -76.07004) (xy 142.454865 -76.031331) (xy 142.500223 -75.99888) (xy 142.549823 -75.973379)
			(xy 142.602607 -75.955372) (xy 142.65745 -75.945242) (xy 142.713184 -75.943205) (xy 142.768621 -75.949305)
			(xy 142.822578 -75.963411) (xy 142.873907 -75.985223) (xy 142.921513 -76.014277) (xy 142.964381 -76.049952)
			(xy 143.001598 -76.091489) (xy 143.032371 -76.138002) (xy 143.056043 -76.188499) (xy 143.072111 -76.241906)
			(xy 143.080231 -76.297082) (xy 143.080314 -76.301652) (xy 144.371777 -76.301652) (xy 144.371777 -76.247148)
			(xy 144.379534 -76.193198) (xy 144.394891 -76.140901) (xy 144.417533 -76.091323) (xy 144.447002 -76.045471)
			(xy 144.482696 -76.00428) (xy 144.523889 -75.968589) (xy 144.569742 -75.939123) (xy 144.619322 -75.916483)
			(xy 144.67162 -75.90113) (xy 144.72557 -75.893376) (xy 144.752822 -75.892914) (xy 144.782807 -75.893527)
			(xy 144.842034 -75.902939) (xy 144.899066 -75.921482) (xy 144.92605 -75.93457) (xy 144.935194 -75.939142)
			(xy 144.954752 -75.940666) (xy 145.042636 -75.912472) (xy 145.057622 -75.899772) (xy 145.062448 -75.890628)
			(xy 145.074767 -75.867592) (xy 145.104805 -75.824853) (xy 145.140395 -75.786612) (xy 145.18087 -75.753587)
			(xy 145.225474 -75.726394) (xy 145.273372 -75.705542) (xy 145.323667 -75.691422) (xy 145.375418 -75.684298)
			(xy 145.401538 -75.683872) (xy 145.428786 -75.684401) (xy 145.482727 -75.692161) (xy 145.535014 -75.707519)
			(xy 145.580194 -75.728156) (xy 152.583545 -75.728156) (xy 152.583545 -75.673644) (xy 152.591303 -75.619688)
			(xy 152.606662 -75.567386) (xy 152.629308 -75.517801) (xy 152.658781 -75.471945) (xy 152.69448 -75.43075)
			(xy 152.735679 -75.395056) (xy 152.781538 -75.365588) (xy 152.831125 -75.342947) (xy 152.883429 -75.327594)
			(xy 152.937386 -75.319842) (xy 152.964642 -75.319382) (xy 152.992351 -75.319879) (xy 153.047186 -75.327908)
			(xy 153.10028 -75.343789) (xy 153.150516 -75.367189) (xy 153.196836 -75.397614) (xy 153.21788 -75.415648)
			(xy 153.224992 -75.421744) (xy 153.242264 -75.428348) (xy 153.32837 -75.428348) (xy 153.345642 -75.421744)
			(xy 153.352754 -75.415648) (xy 153.373797 -75.397614) (xy 153.420117 -75.367188) (xy 153.470353 -75.34379)
			(xy 153.523448 -75.327912) (xy 153.578283 -75.319888) (xy 153.633701 -75.319888) (xy 153.688536 -75.327912)
			(xy 153.741631 -75.34379) (xy 153.791867 -75.367188) (xy 153.838187 -75.397614) (xy 153.85923 -75.415648)
			(xy 153.866342 -75.421744) (xy 153.883614 -75.428348) (xy 153.96972 -75.428348) (xy 153.986992 -75.421744)
			(xy 153.994104 -75.415648) (xy 154.015147 -75.397614) (xy 154.061467 -75.367188) (xy 154.111703 -75.34379)
			(xy 154.164798 -75.327912) (xy 154.219633 -75.319888) (xy 154.275051 -75.319888) (xy 154.329886 -75.327912)
			(xy 154.382981 -75.34379) (xy 154.433217 -75.367188) (xy 154.479537 -75.397614) (xy 154.50058 -75.415648)
			(xy 154.507692 -75.421744) (xy 154.524964 -75.428348) (xy 154.61107 -75.428348) (xy 154.628342 -75.421744)
			(xy 154.635454 -75.415648) (xy 154.6565 -75.397616) (xy 154.702817 -75.367187) (xy 154.753053 -75.343786)
			(xy 154.806148 -75.327905) (xy 154.860983 -75.31988) (xy 154.888692 -75.319382) (xy 154.915945 -75.319865)
			(xy 154.969895 -75.327621) (xy 155.022192 -75.342976) (xy 155.071772 -75.365617) (xy 155.117625 -75.395084)
			(xy 155.158818 -75.430777) (xy 155.194511 -75.471969) (xy 155.223979 -75.517821) (xy 155.246622 -75.5674)
			(xy 155.261978 -75.619697) (xy 155.269735 -75.673647) (xy 155.269735 -75.728153) (xy 155.261978 -75.782103)
			(xy 155.246622 -75.8344) (xy 155.223979 -75.883979) (xy 155.194511 -75.929831) (xy 155.158818 -75.971023)
			(xy 155.117625 -76.006716) (xy 155.071772 -76.036183) (xy 155.022192 -76.058824) (xy 154.969895 -76.074179)
			(xy 154.915945 -76.081935) (xy 154.888692 -76.082398) (xy 154.860983 -76.081886) (xy 154.806149 -76.073862)
			(xy 154.753055 -76.057984) (xy 154.702818 -76.034588) (xy 154.656498 -76.004165) (xy 154.635454 -75.986132)
			(xy 154.628342 -75.980036) (xy 154.61107 -75.973432) (xy 154.524964 -75.973432) (xy 154.507692 -75.980036)
			(xy 154.50058 -75.986132) (xy 154.479537 -76.004166) (xy 154.433217 -76.034592) (xy 154.382981 -76.05799)
			(xy 154.329886 -76.073868) (xy 154.275051 -76.081892) (xy 154.219633 -76.081892) (xy 154.164798 -76.073868)
			(xy 154.111703 -76.05799) (xy 154.061467 -76.034592) (xy 154.015147 -76.004166) (xy 153.994104 -75.986132)
			(xy 153.986992 -75.980036) (xy 153.96972 -75.973432) (xy 153.883614 -75.973432) (xy 153.866342 -75.980036)
			(xy 153.85923 -75.986132) (xy 153.838187 -76.004166) (xy 153.791867 -76.034592) (xy 153.741631 -76.05799)
			(xy 153.688536 -76.073868) (xy 153.633701 -76.081892) (xy 153.578283 -76.081892) (xy 153.523448 -76.073868)
			(xy 153.470353 -76.05799) (xy 153.420117 -76.034592) (xy 153.373797 -76.004166) (xy 153.352754 -75.986132)
			(xy 153.345642 -75.980036) (xy 153.32837 -75.973432) (xy 153.242264 -75.973432) (xy 153.224992 -75.980036)
			(xy 153.21788 -75.986132) (xy 153.196857 -76.004192) (xy 153.150533 -76.034617) (xy 153.100292 -76.058013)
			(xy 153.047192 -76.073888) (xy 152.992353 -76.081905) (xy 152.964642 -76.082398) (xy 152.937386 -76.081958)
			(xy 152.883429 -76.074206) (xy 152.831125 -76.058853) (xy 152.781538 -76.036212) (xy 152.735679 -76.006744)
			(xy 152.69448 -75.97105) (xy 152.658781 -75.929855) (xy 152.629308 -75.883999) (xy 152.606662 -75.834414)
			(xy 152.591303 -75.782112) (xy 152.583545 -75.728156) (xy 145.580194 -75.728156) (xy 145.584584 -75.730161)
			(xy 145.630427 -75.759627) (xy 145.671611 -75.795316) (xy 145.707296 -75.836503) (xy 145.736757 -75.882349)
			(xy 145.759394 -75.931922) (xy 145.774747 -75.98421) (xy 145.782502 -76.038152) (xy 145.782502 -76.092648)
			(xy 145.774747 -76.14659) (xy 145.759394 -76.198878) (xy 145.736757 -76.248451) (xy 145.707296 -76.294297)
			(xy 145.671611 -76.335484) (xy 145.630427 -76.371173) (xy 145.584584 -76.400639) (xy 145.535014 -76.423281)
			(xy 145.482727 -76.438639) (xy 145.428786 -76.446399) (xy 145.401538 -76.446888) (xy 145.371553 -76.446289)
			(xy 145.312325 -76.436871) (xy 145.255294 -76.418323) (xy 145.22831 -76.405232) (xy 145.219166 -76.40066)
			(xy 145.199608 -76.399136) (xy 145.111724 -76.42733) (xy 145.096738 -76.44003) (xy 145.091912 -76.449174)
			(xy 145.079623 -76.472227) (xy 145.049581 -76.514967) (xy 145.013987 -76.553207) (xy 144.973507 -76.586232)
			(xy 144.928899 -76.613423) (xy 144.880997 -76.634271) (xy 144.830698 -76.648387) (xy 144.778943 -76.655506)
			(xy 144.752822 -76.65593) (xy 144.72557 -76.655424) (xy 144.671619 -76.64767) (xy 144.619322 -76.632317)
			(xy 144.569742 -76.609677) (xy 144.523889 -76.580211) (xy 144.482696 -76.54452) (xy 144.447002 -76.503329)
			(xy 144.417533 -76.457477) (xy 144.394891 -76.407899) (xy 144.379534 -76.355602) (xy 144.371777 -76.301652)
			(xy 143.080314 -76.301652) (xy 143.08074 -76.324968) (xy 143.080231 -76.352854) (xy 143.072111 -76.40803)
			(xy 143.056043 -76.461437) (xy 143.032371 -76.511934) (xy 143.001598 -76.558447) (xy 142.964381 -76.599984)
			(xy 142.921513 -76.635659) (xy 142.873907 -76.664713) (xy 142.822578 -76.686525) (xy 142.768621 -76.700631)
			(xy 142.713184 -76.706731) (xy 142.65745 -76.704694) (xy 142.602607 -76.694564) (xy 142.549823 -76.676557)
			(xy 142.500223 -76.651056) (xy 142.454865 -76.618605) (xy 142.414716 -76.579896) (xy 142.38063 -76.535753)
			(xy 142.353334 -76.487118) (xy 142.333411 -76.435027) (xy 142.321285 -76.38059) (xy 142.317214 -76.324968)
			(xy 135.931148 -76.324968) (xy 135.931148 -80.302862) (xy 143.832324 -80.302862) (xy 143.836395 -80.24724)
			(xy 143.848521 -80.192803) (xy 143.868444 -80.140712) (xy 143.89574 -80.092077) (xy 143.929826 -80.047934)
			(xy 143.969975 -80.009225) (xy 144.015333 -79.976774) (xy 144.064933 -79.951273) (xy 144.117717 -79.933266)
			(xy 144.17256 -79.923136) (xy 144.228294 -79.921099) (xy 144.272162 -79.925926) (xy 144.667984 -79.925926)
			(xy 144.672055 -79.870304) (xy 144.684181 -79.815867) (xy 144.704104 -79.763776) (xy 144.7314 -79.715141)
			(xy 144.765486 -79.670998) (xy 144.805635 -79.632289) (xy 144.850993 -79.599838) (xy 144.900593 -79.574337)
			(xy 144.953377 -79.55633) (xy 145.00822 -79.5462) (xy 145.063954 -79.544163) (xy 145.119391 -79.550263)
			(xy 145.173348 -79.564369) (xy 145.224677 -79.586181) (xy 145.272283 -79.615235) (xy 145.315151 -79.65091)
			(xy 145.352368 -79.692447) (xy 145.383141 -79.73896) (xy 145.406813 -79.789457) (xy 145.416018 -79.820053)
			(xy 152.583585 -79.820053) (xy 152.583585 -79.765547) (xy 152.591343 -79.711597) (xy 152.6067 -79.6593)
			(xy 152.629344 -79.609721) (xy 152.658813 -79.563869) (xy 152.694509 -79.522679) (xy 152.735703 -79.486988)
			(xy 152.781558 -79.457523) (xy 152.831139 -79.434885) (xy 152.883438 -79.419534) (xy 152.937389 -79.411782)
			(xy 152.964642 -79.411322) (xy 152.992352 -79.411809) (xy 153.047187 -79.419838) (xy 153.100282 -79.435722)
			(xy 153.150518 -79.459124) (xy 153.196837 -79.489553) (xy 153.21788 -79.507588) (xy 153.224992 -79.513684)
			(xy 153.242264 -79.520288) (xy 153.32837 -79.520288) (xy 153.345642 -79.513684) (xy 153.352754 -79.507588)
			(xy 153.373797 -79.489554) (xy 153.420117 -79.459128) (xy 153.470353 -79.43573) (xy 153.523448 -79.419852)
			(xy 153.578283 -79.411828) (xy 153.633701 -79.411828) (xy 153.688536 -79.419852) (xy 153.741631 -79.43573)
			(xy 153.791867 -79.459128) (xy 153.838187 -79.489554) (xy 153.85923 -79.507588) (xy 153.866342 -79.513684)
			(xy 153.883614 -79.520288) (xy 153.96972 -79.520288) (xy 153.986992 -79.513684) (xy 153.994104 -79.507588)
			(xy 154.015147 -79.489554) (xy 154.061467 -79.459128) (xy 154.111703 -79.43573) (xy 154.164798 -79.419852)
			(xy 154.219633 -79.411828) (xy 154.275051 -79.411828) (xy 154.329886 -79.419852) (xy 154.382981 -79.43573)
			(xy 154.433217 -79.459128) (xy 154.479537 -79.489554) (xy 154.50058 -79.507588) (xy 154.507692 -79.513684)
			(xy 154.524964 -79.520288) (xy 154.61107 -79.520288) (xy 154.628342 -79.513684) (xy 154.635454 -79.507588)
			(xy 154.656505 -79.489562) (xy 154.702821 -79.459131) (xy 154.753055 -79.435728) (xy 154.806149 -79.419846)
			(xy 154.860983 -79.41182) (xy 154.888692 -79.411322) (xy 154.915947 -79.411724) (xy 154.969903 -79.419481)
			(xy 155.022206 -79.434838) (xy 155.071792 -79.457481) (xy 155.117649 -79.486952) (xy 155.158846 -79.522648)
			(xy 155.194544 -79.563844) (xy 155.224015 -79.609701) (xy 155.24666 -79.659286) (xy 155.262017 -79.711589)
			(xy 155.269775 -79.765545) (xy 155.269775 -79.820055) (xy 155.262017 -79.874011) (xy 155.24666 -79.926314)
			(xy 155.224015 -79.975899) (xy 155.194544 -80.021756) (xy 155.158846 -80.062952) (xy 155.117649 -80.098648)
			(xy 155.071792 -80.128119) (xy 155.022206 -80.150762) (xy 154.969903 -80.166119) (xy 154.915947 -80.173876)
			(xy 154.888692 -80.174338) (xy 154.860984 -80.173816) (xy 154.806151 -80.165793) (xy 154.753057 -80.149917)
			(xy 154.70282 -80.126523) (xy 154.656499 -80.096103) (xy 154.635454 -80.078072) (xy 154.628342 -80.071976)
			(xy 154.61107 -80.065372) (xy 154.524964 -80.065372) (xy 154.507692 -80.071976) (xy 154.50058 -80.078072)
			(xy 154.479537 -80.096106) (xy 154.433217 -80.126532) (xy 154.382981 -80.14993) (xy 154.329886 -80.165808)
			(xy 154.275051 -80.173832) (xy 154.219633 -80.173832) (xy 154.164798 -80.165808) (xy 154.111703 -80.14993)
			(xy 154.061467 -80.126532) (xy 154.015147 -80.096106) (xy 153.994104 -80.078072) (xy 153.986992 -80.071976)
			(xy 153.96972 -80.065372) (xy 153.883614 -80.065372) (xy 153.866342 -80.071976) (xy 153.85923 -80.078072)
			(xy 153.838187 -80.096106) (xy 153.791867 -80.126532) (xy 153.741631 -80.14993) (xy 153.688536 -80.165808)
			(xy 153.633701 -80.173832) (xy 153.578283 -80.173832) (xy 153.523448 -80.165808) (xy 153.470353 -80.14993)
			(xy 153.420117 -80.126532) (xy 153.373797 -80.096106) (xy 153.352754 -80.078072) (xy 153.345642 -80.071976)
			(xy 153.32837 -80.065372) (xy 153.242264 -80.065372) (xy 153.224992 -80.071976) (xy 153.21788 -80.078072)
			(xy 153.196849 -80.096122) (xy 153.150528 -80.126551) (xy 153.100289 -80.14995) (xy 153.047191 -80.165826)
			(xy 152.992353 -80.173844) (xy 152.964642 -80.174338) (xy 152.937389 -80.173818) (xy 152.883438 -80.166066)
			(xy 152.831139 -80.150715) (xy 152.781558 -80.128077) (xy 152.735703 -80.098612) (xy 152.694509 -80.062921)
			(xy 152.658813 -80.021731) (xy 152.629344 -79.975879) (xy 152.6067 -79.9263) (xy 152.591343 -79.874003)
			(xy 152.583585 -79.820053) (xy 145.416018 -79.820053) (xy 145.422881 -79.842864) (xy 145.431001 -79.89804)
			(xy 145.43151 -79.925926) (xy 145.431001 -79.953812) (xy 145.422881 -80.008988) (xy 145.406813 -80.062395)
			(xy 145.383141 -80.112892) (xy 145.352368 -80.159405) (xy 145.315151 -80.200942) (xy 145.272283 -80.236617)
			(xy 145.224677 -80.265671) (xy 145.173348 -80.287483) (xy 145.119391 -80.301589) (xy 145.063954 -80.307689)
			(xy 145.00822 -80.305652) (xy 144.953377 -80.295522) (xy 144.900593 -80.277515) (xy 144.850993 -80.252014)
			(xy 144.805635 -80.219563) (xy 144.765486 -80.180854) (xy 144.7314 -80.136711) (xy 144.704104 -80.088076)
			(xy 144.684181 -80.035985) (xy 144.672055 -79.981548) (xy 144.667984 -79.925926) (xy 144.272162 -79.925926)
			(xy 144.283731 -79.927199) (xy 144.337688 -79.941305) (xy 144.389017 -79.963117) (xy 144.436623 -79.992171)
			(xy 144.479491 -80.027846) (xy 144.516708 -80.069383) (xy 144.547481 -80.115896) (xy 144.571153 -80.166393)
			(xy 144.587221 -80.2198) (xy 144.595341 -80.274976) (xy 144.59585 -80.302862) (xy 144.595341 -80.330748)
			(xy 144.587221 -80.385924) (xy 144.571153 -80.439331) (xy 144.547481 -80.489828) (xy 144.516708 -80.536341)
			(xy 144.479491 -80.577878) (xy 144.436623 -80.613553) (xy 144.389017 -80.642607) (xy 144.337688 -80.664419)
			(xy 144.283731 -80.678525) (xy 144.228294 -80.684625) (xy 144.17256 -80.682588) (xy 144.117717 -80.672458)
			(xy 144.064933 -80.654451) (xy 144.015333 -80.62895) (xy 143.969975 -80.596499) (xy 143.929826 -80.55779)
			(xy 143.89574 -80.513647) (xy 143.868444 -80.465012) (xy 143.848521 -80.412921) (xy 143.836395 -80.358484)
			(xy 143.832324 -80.302862) (xy 135.931148 -80.302862) (xy 135.931148 -81.866055) (xy 152.583555 -81.866055)
			(xy 152.583555 -81.811545) (xy 152.591314 -81.757591) (xy 152.606672 -81.705289) (xy 152.629317 -81.655707)
			(xy 152.658789 -81.609851) (xy 152.694487 -81.568658) (xy 152.735685 -81.532964) (xy 152.781543 -81.503497)
			(xy 152.831129 -81.480857) (xy 152.883432 -81.465505) (xy 152.937387 -81.457752) (xy 152.964642 -81.457292)
			(xy 152.992351 -81.457787) (xy 153.047186 -81.465815) (xy 153.10028 -81.481697) (xy 153.150517 -81.505098)
			(xy 153.196836 -81.535524) (xy 153.21788 -81.553558) (xy 153.224992 -81.559654) (xy 153.242264 -81.566258)
			(xy 153.32837 -81.566258) (xy 153.345642 -81.559654) (xy 153.352754 -81.553558) (xy 153.373797 -81.535524)
			(xy 153.420117 -81.505098) (xy 153.470353 -81.4817) (xy 153.523448 -81.465822) (xy 153.578283 -81.457798)
			(xy 153.633701 -81.457798) (xy 153.688536 -81.465822) (xy 153.741631 -81.4817) (xy 153.791867 -81.505098)
			(xy 153.838187 -81.535524) (xy 153.85923 -81.553558) (xy 153.866342 -81.559654) (xy 153.883614 -81.566258)
			(xy 153.96972 -81.566258) (xy 153.986992 -81.559654) (xy 153.994104 -81.553558) (xy 154.015147 -81.535524)
			(xy 154.061467 -81.505098) (xy 154.111703 -81.4817) (xy 154.164798 -81.465822) (xy 154.219633 -81.457798)
			(xy 154.275051 -81.457798) (xy 154.329886 -81.465822) (xy 154.382981 -81.4817) (xy 154.433217 -81.505098)
			(xy 154.479537 -81.535524) (xy 154.50058 -81.553558) (xy 154.507692 -81.559654) (xy 154.524964 -81.566258)
			(xy 154.61107 -81.566258) (xy 154.628342 -81.559654) (xy 154.635454 -81.553558) (xy 154.656501 -81.535528)
			(xy 154.702818 -81.505098) (xy 154.753054 -81.481697) (xy 154.806148 -81.465815) (xy 154.860983 -81.45779)
			(xy 154.888692 -81.457292) (xy 154.915945 -81.457755) (xy 154.969897 -81.465511) (xy 155.022196 -81.480866)
			(xy 155.071777 -81.503508) (xy 155.117631 -81.532976) (xy 155.158825 -81.56867) (xy 155.194519 -81.609863)
			(xy 155.223988 -81.655716) (xy 155.246631 -81.705297) (xy 155.261987 -81.757595) (xy 155.269745 -81.811547)
			(xy 155.269745 -81.866053) (xy 155.261987 -81.920005) (xy 155.246631 -81.972303) (xy 155.223988 -82.021884)
			(xy 155.194519 -82.067737) (xy 155.158825 -82.10893) (xy 155.117631 -82.144624) (xy 155.071777 -82.174092)
			(xy 155.022196 -82.196734) (xy 154.969897 -82.212089) (xy 154.915945 -82.219845) (xy 154.888692 -82.220308)
			(xy 154.860983 -82.219793) (xy 154.80615 -82.21177) (xy 154.753055 -82.195892) (xy 154.702819 -82.172496)
			(xy 154.656498 -82.142074) (xy 154.635454 -82.124042) (xy 154.628342 -82.117946) (xy 154.61107 -82.111342)
			(xy 154.524964 -82.111342) (xy 154.507692 -82.117946) (xy 154.50058 -82.124042) (xy 154.479537 -82.142076)
			(xy 154.433217 -82.172502) (xy 154.382981 -82.1959) (xy 154.329886 -82.211778) (xy 154.275051 -82.219802)
			(xy 154.219633 -82.219802) (xy 154.164798 -82.211778) (xy 154.111703 -82.1959) (xy 154.061467 -82.172502)
			(xy 154.015147 -82.142076) (xy 153.994104 -82.124042) (xy 153.986992 -82.117946) (xy 153.96972 -82.111342)
			(xy 153.883614 -82.111342) (xy 153.866342 -82.117946) (xy 153.85923 -82.124042) (xy 153.838187 -82.142076)
			(xy 153.791867 -82.172502) (xy 153.741631 -82.1959) (xy 153.688536 -82.211778) (xy 153.633701 -82.219802)
			(xy 153.578283 -82.219802) (xy 153.523448 -82.211778) (xy 153.470353 -82.1959) (xy 153.420117 -82.172502)
			(xy 153.373797 -82.142076) (xy 153.352754 -82.124042) (xy 153.345642 -82.117946) (xy 153.32837 -82.111342)
			(xy 153.242264 -82.111342) (xy 153.224992 -82.117946) (xy 153.21788 -82.124042) (xy 153.196859 -82.142103)
			(xy 153.150534 -82.172528) (xy 153.100292 -82.195924) (xy 153.047192 -82.211798) (xy 152.992353 -82.219815)
			(xy 152.964642 -82.220308) (xy 152.937387 -82.219848) (xy 152.883432 -82.212095) (xy 152.831129 -82.196743)
			(xy 152.781543 -82.174103) (xy 152.735685 -82.144636) (xy 152.694487 -82.108942) (xy 152.658789 -82.067749)
			(xy 152.629317 -82.021893) (xy 152.606672 -81.972311) (xy 152.591314 -81.920009) (xy 152.583555 -81.866055)
			(xy 135.931148 -81.866055) (xy 135.931148 -82.423508) (xy 143.419574 -82.423508) (xy 143.423645 -82.367886)
			(xy 143.435771 -82.313449) (xy 143.455694 -82.261358) (xy 143.48299 -82.212723) (xy 143.517076 -82.16858)
			(xy 143.557225 -82.129871) (xy 143.602583 -82.09742) (xy 143.652183 -82.071919) (xy 143.704967 -82.053912)
			(xy 143.75981 -82.043782) (xy 143.815544 -82.041745) (xy 143.870981 -82.047845) (xy 143.924938 -82.061951)
			(xy 143.976267 -82.083763) (xy 144.023873 -82.112817) (xy 144.066741 -82.148492) (xy 144.103958 -82.190029)
			(xy 144.134731 -82.236542) (xy 144.158403 -82.287039) (xy 144.174471 -82.340446) (xy 144.182591 -82.395622)
			(xy 144.1831 -82.423508) (xy 144.182591 -82.451394) (xy 144.174471 -82.50657) (xy 144.158403 -82.559977)
			(xy 144.134731 -82.610474) (xy 144.103958 -82.656987) (xy 144.066741 -82.698524) (xy 144.023873 -82.734199)
			(xy 143.976267 -82.763253) (xy 143.924938 -82.785065) (xy 143.870981 -82.799171) (xy 143.815544 -82.805271)
			(xy 143.75981 -82.803234) (xy 143.704967 -82.793104) (xy 143.652183 -82.775097) (xy 143.602583 -82.749596)
			(xy 143.557225 -82.717145) (xy 143.517076 -82.678436) (xy 143.48299 -82.634293) (xy 143.455694 -82.585658)
			(xy 143.435771 -82.533567) (xy 143.423645 -82.47913) (xy 143.419574 -82.423508) (xy 135.931148 -82.423508)
			(xy 135.931148 -83.527138) (xy 135.931579 -83.537204) (xy 135.939309 -83.555794) (xy 135.946134 -83.563206)
			(xy 135.966962 -83.584034) (xy 135.974361 -83.590878) (xy 135.99296 -83.5986) (xy 136.00303 -83.59902)
		)
		(stroke
			(width 0)
			(type solid)
		)
		(fill yes)
		(layer "In2.Cu")
		(net "GND")
	)
	(gr_poly
		(pts
			(xy 125.165358 -41.28516) (xy 125.175423 -41.284725) (xy 125.194008 -41.276991) (xy 125.201426 -41.270174)
			(xy 125.351794 -41.119806) (xy 125.35916 -41.096184) (xy 125.356874 -41.083738) (xy 125.35296 -41.061017)
			(xy 125.348762 -41.015099) (xy 125.348492 -40.992044) (xy 125.348492 -40.991536) (xy 125.348998 -40.958748)
			(xy 125.357428 -40.893718) (xy 125.374166 -40.830315) (xy 125.386084 -40.799766) (xy 125.391926 -40.785542)
			(xy 125.38583 -40.75557) (xy 125.140466 -40.510206) (xy 125.133611 -40.502811) (xy 125.125864 -40.484212)
			(xy 125.12548 -40.474138) (xy 125.12548 -39.954962) (xy 125.125909 -39.944894) (xy 125.133631 -39.926298)
			(xy 125.140466 -39.918894) (xy 126.126494 -38.932866) (xy 126.133889 -38.926011) (xy 126.152488 -38.918264)
			(xy 126.162562 -38.91788) (xy 127.509778 -38.91788) (xy 127.519841 -38.917442) (xy 127.538423 -38.909706)
			(xy 127.545846 -38.902894) (xy 127.823214 -38.625526) (xy 127.829657 -38.618462) (xy 127.837247 -38.600928)
			(xy 127.837954 -38.581834) (xy 127.835152 -38.572694) (xy 127.799592 -38.472364) (xy 127.776732 -38.454076)
			(xy 127.762 -38.452552) (xy 127.734292 -38.449068) (xy 127.68024 -38.435039) (xy 127.62881 -38.413282)
			(xy 127.581101 -38.38426) (xy 127.538131 -38.348594) (xy 127.500819 -38.307046) (xy 127.469961 -38.260503)
			(xy 127.446217 -38.20996) (xy 127.430093 -38.156495) (xy 127.421935 -38.101251) (xy 127.421386 -38.07333)
			(xy 127.421847 -38.046076) (xy 127.429601 -37.992121) (xy 127.444954 -37.939819) (xy 127.467595 -37.890235)
			(xy 127.497062 -37.844378) (xy 127.532755 -37.803181) (xy 127.573949 -37.767484) (xy 127.619803 -37.738012)
			(xy 127.669386 -37.715367) (xy 127.721686 -37.700008) (xy 127.77564 -37.69225) (xy 127.802894 -37.691822)
			(xy 127.830824 -37.692302) (xy 127.88609 -37.700436) (xy 127.939578 -37.716544) (xy 127.990143 -37.740282)
			(xy 128.036706 -37.771142) (xy 128.078268 -37.808465) (xy 128.113942 -37.851451) (xy 128.142963 -37.899181)
			(xy 128.164711 -37.950635) (xy 128.178721 -38.00471) (xy 128.182116 -38.032436) (xy 128.18364 -38.047168)
			(xy 128.201928 -38.070028) (xy 128.302258 -38.105588) (xy 128.311404 -38.108424) (xy 128.330528 -38.10779)
			(xy 128.34808 -38.10017) (xy 128.35509 -38.09365) (xy 128.478534 -37.970206) (xy 128.485389 -37.962811)
			(xy 128.493136 -37.944212) (xy 128.49352 -37.934138) (xy 128.49352 -35.41522) (xy 128.493147 -35.406104)
			(xy 128.486772 -35.389023) (xy 128.474823 -35.375254) (xy 128.458811 -35.366538) (xy 128.449832 -35.364928)
			(xy 128.181354 -35.364928) (xy 128.181354 -34.781998) (xy 128.457706 -34.781998) (xy 128.467898 -34.778333)
			(xy 128.484129 -34.764019) (xy 128.493049 -34.744303) (xy 128.49352 -34.733484) (xy 128.49352 -34.21507)
			(xy 128.493139 -34.20596) (xy 128.486755 -34.188894) (xy 128.474805 -34.175139) (xy 128.458799 -34.166434)
			(xy 128.449832 -34.164778) (xy 128.181354 -34.164778) (xy 128.181354 -33.581848) (xy 128.457706 -33.581848)
			(xy 128.467893 -33.57818) (xy 128.48411 -33.563864) (xy 128.493011 -33.544149) (xy 128.49352 -33.533334)
			(xy 128.49352 -24.816562) (xy 128.493091 -24.806494) (xy 128.485369 -24.787898) (xy 128.478534 -24.780494)
			(xy 125.734826 -22.036786) (xy 125.727428 -22.029942) (xy 125.708828 -22.022221) (xy 125.698758 -22.0218)
			(xy 121.687082 -22.0218) (xy 121.668286 -22.02942) (xy 121.661174 -22.036786) (xy 120.774206 -22.923754)
			(xy 120.767367 -22.931155) (xy 120.759652 -22.949753) (xy 120.75922 -22.959822) (xy 120.75922 -24.021796)
			(xy 121.385582 -24.021796) (xy 121.389653 -23.966174) (xy 121.401779 -23.911737) (xy 121.421702 -23.859646)
			(xy 121.448998 -23.811011) (xy 121.483084 -23.766868) (xy 121.523233 -23.728159) (xy 121.568591 -23.695708)
			(xy 121.618191 -23.670207) (xy 121.670975 -23.6522) (xy 121.725818 -23.64207) (xy 121.781552 -23.640033)
			(xy 121.836989 -23.646133) (xy 121.890946 -23.660239) (xy 121.942275 -23.682051) (xy 121.989881 -23.711105)
			(xy 122.032749 -23.74678) (xy 122.069966 -23.788317) (xy 122.100739 -23.83483) (xy 122.124411 -23.885327)
			(xy 122.140479 -23.938734) (xy 122.148599 -23.99391) (xy 122.149108 -24.021796) (xy 122.148599 -24.049682)
			(xy 122.140479 -24.104858) (xy 122.124411 -24.158265) (xy 122.100739 -24.208762) (xy 122.069966 -24.255275)
			(xy 122.032749 -24.296812) (xy 121.989881 -24.332487) (xy 121.942275 -24.361541) (xy 121.890946 -24.383353)
			(xy 121.836989 -24.397459) (xy 121.781552 -24.403559) (xy 121.725818 -24.401522) (xy 121.670975 -24.391392)
			(xy 121.618191 -24.373385) (xy 121.568591 -24.347884) (xy 121.523233 -24.315433) (xy 121.483084 -24.276724)
			(xy 121.448998 -24.232581) (xy 121.421702 -24.183946) (xy 121.401779 -24.131855) (xy 121.389653 -24.077418)
			(xy 121.385582 -24.021796) (xy 120.75922 -24.021796) (xy 120.75922 -24.822658) (xy 120.759654 -24.832723)
			(xy 120.767386 -24.85131) (xy 120.774206 -24.858726) (xy 122.315986 -26.400506) (xy 122.32339 -26.407338)
			(xy 122.341988 -26.41504) (xy 122.352054 -26.415492) (xy 125.864874 -26.415492) (xy 125.869954 -26.415746)
			(xy 125.872494 -26.416) (xy 125.885956 -26.416) (xy 125.893068 -26.423112) (xy 125.89383 -26.423366)
			(xy 126.148084 -26.67762) (xy 126.148338 -26.677874) (xy 126.15037 -26.679906) (xy 126.15164 -26.68143)
			(xy 126.162054 -26.692098) (xy 126.162308 -26.693368) (xy 126.162308 -27.173936) (xy 127.332992 -27.173936)
			(xy 127.337063 -27.118314) (xy 127.349189 -27.063877) (xy 127.369112 -27.011786) (xy 127.396408 -26.963151)
			(xy 127.430494 -26.919008) (xy 127.470643 -26.880299) (xy 127.516001 -26.847848) (xy 127.565601 -26.822347)
			(xy 127.618385 -26.80434) (xy 127.673228 -26.79421) (xy 127.728962 -26.792173) (xy 127.784399 -26.798273)
			(xy 127.838356 -26.812379) (xy 127.889685 -26.834191) (xy 127.937291 -26.863245) (xy 127.980159 -26.89892)
			(xy 128.017376 -26.940457) (xy 128.048149 -26.98697) (xy 128.071821 -27.037467) (xy 128.087889 -27.090874)
			(xy 128.096009 -27.14605) (xy 128.096518 -27.173936) (xy 128.096009 -27.201822) (xy 128.087889 -27.256998)
			(xy 128.071821 -27.310405) (xy 128.048149 -27.360902) (xy 128.017376 -27.407415) (xy 127.980159 -27.448952)
			(xy 127.937291 -27.484627) (xy 127.889685 -27.513681) (xy 127.838356 -27.535493) (xy 127.784399 -27.549599)
			(xy 127.728962 -27.555699) (xy 127.673228 -27.553662) (xy 127.618385 -27.543532) (xy 127.565601 -27.525525)
			(xy 127.516001 -27.500024) (xy 127.470643 -27.467573) (xy 127.430494 -27.428864) (xy 127.396408 -27.384721)
			(xy 127.369112 -27.336086) (xy 127.349189 -27.283995) (xy 127.337063 -27.229558) (xy 127.332992 -27.173936)
			(xy 126.162308 -27.173936) (xy 126.162308 -28.264104) (xy 127.316228 -28.264104) (xy 127.320301 -28.208445)
			(xy 127.332436 -28.153972) (xy 127.352372 -28.101846) (xy 127.379686 -28.053178) (xy 127.413794 -28.009006)
			(xy 127.453971 -27.970271) (xy 127.499359 -27.937799) (xy 127.548991 -27.912281) (xy 127.601811 -27.894262)
			(xy 127.65669 -27.884125) (xy 127.712461 -27.882087) (xy 127.767935 -27.88819) (xy 127.821928 -27.902306)
			(xy 127.873291 -27.924133) (xy 127.920929 -27.953206) (xy 127.963825 -27.988905) (xy 128.001067 -28.030469)
			(xy 128.031861 -28.077013) (xy 128.055549 -28.127544) (xy 128.071627 -28.180986) (xy 128.079753 -28.2362)
			(xy 128.080262 -28.264104) (xy 128.079753 -28.292008) (xy 128.071627 -28.347222) (xy 128.055549 -28.400664)
			(xy 128.031861 -28.451195) (xy 128.001067 -28.497739) (xy 127.963825 -28.539303) (xy 127.920929 -28.575002)
			(xy 127.873291 -28.604075) (xy 127.821928 -28.625902) (xy 127.767935 -28.640018) (xy 127.712461 -28.646121)
			(xy 127.65669 -28.644083) (xy 127.601811 -28.633946) (xy 127.548991 -28.615927) (xy 127.499359 -28.590409)
			(xy 127.453971 -28.557937) (xy 127.413794 -28.519202) (xy 127.379686 -28.47503) (xy 127.352372 -28.426362)
			(xy 127.332436 -28.374236) (xy 127.320301 -28.319763) (xy 127.316228 -28.264104) (xy 126.162308 -28.264104)
			(xy 126.162308 -29.530294) (xy 126.789434 -29.530294) (xy 126.78992 -29.503025) (xy 126.797682 -29.449041)
			(xy 126.813047 -29.396711) (xy 126.835704 -29.347101) (xy 126.86519 -29.30122) (xy 126.900905 -29.260003)
			(xy 126.942122 -29.224288) (xy 126.988003 -29.194802) (xy 127.037613 -29.172145) (xy 127.089943 -29.15678)
			(xy 127.143927 -29.149018) (xy 127.198465 -29.149018) (xy 127.252449 -29.15678) (xy 127.304779 -29.172145)
			(xy 127.354389 -29.194802) (xy 127.40027 -29.224288) (xy 127.441487 -29.260003) (xy 127.477202 -29.30122)
			(xy 127.506688 -29.347101) (xy 127.529345 -29.396711) (xy 127.54471 -29.449041) (xy 127.552472 -29.503025)
			(xy 127.552958 -29.530294) (xy 127.552394 -29.560224) (xy 127.543057 -29.619353) (xy 127.524611 -29.6763)
			(xy 127.497507 -29.729674) (xy 127.46241 -29.778166) (xy 127.441706 -29.799788) (xy 127.431954 -29.810213)
			(xy 127.418157 -29.835191) (xy 127.411825 -29.863015) (xy 127.413453 -29.891504) (xy 127.422915 -29.918425)
			(xy 127.439468 -29.941669) (xy 127.450342 -29.950918) (xy 127.472386 -29.969102) (xy 127.511261 -30.010985)
			(xy 127.543456 -30.058197) (xy 127.568251 -30.109682) (xy 127.585092 -30.164289) (xy 127.593603 -30.220796)
			(xy 127.594106 -30.249368) (xy 127.59362 -30.276637) (xy 127.585858 -30.330621) (xy 127.570493 -30.382951)
			(xy 127.547836 -30.432561) (xy 127.51835 -30.478442) (xy 127.482635 -30.519659) (xy 127.441418 -30.555374)
			(xy 127.395537 -30.58486) (xy 127.345927 -30.607517) (xy 127.293597 -30.622882) (xy 127.239613 -30.630644)
			(xy 127.185075 -30.630644) (xy 127.131091 -30.622882) (xy 127.078761 -30.607517) (xy 127.029151 -30.58486)
			(xy 126.98327 -30.555374) (xy 126.942053 -30.519659) (xy 126.906338 -30.478442) (xy 126.876852 -30.432561)
			(xy 126.854195 -30.382951) (xy 126.83883 -30.330621) (xy 126.831068 -30.276637) (xy 126.830582 -30.249368)
			(xy 126.831202 -30.21944) (xy 126.840528 -30.160315) (xy 126.858962 -30.103369) (xy 126.886052 -30.049994)
			(xy 126.921137 -30.001499) (xy 126.941834 -29.979874) (xy 126.95162 -29.969479) (xy 126.965408 -29.944491)
			(xy 126.971732 -29.91666) (xy 126.970097 -29.888167) (xy 126.96063 -29.861243) (xy 126.944073 -29.837996)
			(xy 126.933198 -29.828744) (xy 126.911192 -29.810516) (xy 126.872313 -29.768643) (xy 126.840112 -29.72144)
			(xy 126.81531 -29.669964) (xy 126.798461 -29.615365) (xy 126.789942 -29.558864) (xy 126.789434 -29.530294)
			(xy 126.162308 -29.530294) (xy 126.162308 -30.450536) (xy 126.162054 -30.455616) (xy 126.1618 -30.458156)
			(xy 126.1618 -30.471618) (xy 126.151386 -30.482032) (xy 126.150116 -30.483556) (xy 126.147322 -30.486604)
			(xy 125.960378 -30.673548) (xy 125.9586 -30.675326) (xy 125.95606 -30.677358) (xy 125.953266 -30.680406)
			(xy 125.93447 -30.688026) (xy 125.929898 -30.688026) (xy 125.92812 -30.68828) (xy 125.925834 -30.68828)
			(xy 125.925326 -30.68828) (xy 125.525276 -30.68828) (xy 125.514619 -30.688743) (xy 125.495156 -30.69743)
			(xy 125.487684 -30.705044) (xy 125.429772 -30.768798) (xy 125.423168 -30.78861) (xy 125.424184 -30.799278)
			(xy 125.425708 -30.832806) (xy 125.425203 -30.860636) (xy 125.417116 -30.915705) (xy 125.401115 -30.969016)
			(xy 125.377539 -31.019436) (xy 125.346888 -31.065896) (xy 125.309813 -31.107411) (xy 125.288802 -31.125668)
			(xy 125.287024 -31.127192) (xy 125.28296 -31.131256) (xy 125.280069 -31.134182) (xy 125.275213 -31.140819)
			(xy 125.273308 -31.144464) (xy 125.262132 -31.166816) (xy 125.260862 -31.171896) (xy 125.259084 -31.185104)
			(xy 125.259084 -31.242508) (xy 125.25923 -31.248377) (xy 125.261919 -31.259802) (xy 125.264418 -31.265114)
			(xy 125.273308 -31.283148) (xy 125.275258 -31.286766) (xy 125.280103 -31.293403) (xy 125.28296 -31.296356)
			(xy 125.287024 -31.30042) (xy 125.288802 -31.301944) (xy 125.309827 -31.320183) (xy 125.346888 -31.36171)
			(xy 125.377528 -31.408177) (xy 125.401098 -31.458599) (xy 125.417099 -31.511909) (xy 125.425192 -31.566976)
			(xy 125.425708 -31.594806) (xy 125.425222 -31.622057) (xy 125.417466 -31.676005) (xy 125.402111 -31.7283)
			(xy 125.379469 -31.777877) (xy 125.350003 -31.823727) (xy 125.314312 -31.864918) (xy 125.273121 -31.900609)
			(xy 125.227271 -31.930075) (xy 125.177694 -31.952717) (xy 125.125399 -31.968072) (xy 125.071451 -31.975828)
			(xy 125.016949 -31.975828) (xy 124.963001 -31.968072) (xy 124.910706 -31.952717) (xy 124.861129 -31.930075)
			(xy 124.815279 -31.900609) (xy 124.774088 -31.864918) (xy 124.738397 -31.823727) (xy 124.708931 -31.777877)
			(xy 124.686289 -31.7283) (xy 124.670934 -31.676005) (xy 124.663178 -31.622057) (xy 124.662692 -31.594806)
			(xy 124.663196 -31.566976) (xy 124.671281 -31.511905) (xy 124.687281 -31.458594) (xy 124.710856 -31.408172)
			(xy 124.741506 -31.361711) (xy 124.778581 -31.320195) (xy 124.799598 -31.301944) (xy 124.801376 -31.30042)
			(xy 124.80544 -31.296356) (xy 124.808322 -31.293352) (xy 124.81317 -31.286586) (xy 124.815092 -31.282894)
			(xy 124.824236 -31.264606) (xy 124.826608 -31.259326) (xy 124.829166 -31.24804) (xy 124.829316 -31.242254)
			(xy 124.829316 -31.185358) (xy 124.829185 -31.17957) (xy 124.826612 -31.168286) (xy 124.824236 -31.163006)
			(xy 124.815092 -31.144718) (xy 124.813184 -31.141017) (xy 124.808331 -31.134252) (xy 124.80544 -31.131256)
			(xy 124.801376 -31.127192) (xy 124.799598 -31.125668) (xy 124.778572 -31.107429) (xy 124.74151 -31.065902)
			(xy 124.710869 -31.019436) (xy 124.687297 -30.969014) (xy 124.671294 -30.915704) (xy 124.663199 -30.860636)
			(xy 124.662692 -30.832806) (xy 124.664216 -30.799278) (xy 124.665232 -30.78861) (xy 124.658628 -30.768798)
			(xy 124.600716 -30.705044) (xy 124.594076 -30.698363) (xy 124.577271 -30.689891) (xy 124.56795 -30.688534)
			(xy 124.56541 -30.68828) (xy 123.401582 -30.68828) (xy 123.382786 -30.6959) (xy 123.375674 -30.703266)
			(xy 123.088146 -30.990794) (xy 123.081294 -30.99819) (xy 123.07355 -31.016788) (xy 123.07316 -31.026862)
			(xy 123.07316 -33.413756) (xy 123.540413 -33.413756) (xy 123.540414 -33.358836) (xy 123.548288 -33.304484)
			(xy 123.563874 -33.251822) (xy 123.586848 -33.201938) (xy 123.616737 -33.155864) (xy 123.652923 -33.114551)
			(xy 123.694658 -33.078853) (xy 123.74108 -33.049507) (xy 123.791229 -33.02712) (xy 123.84407 -33.012153)
			(xy 123.871228 -33.008062) (xy 123.88634 -33.005548) (xy 123.914145 -32.992717) (xy 123.936885 -32.972208)
			(xy 123.952511 -32.945872) (xy 123.956572 -32.9311) (xy 123.957558 -32.926793) (xy 123.958191 -32.917979)
			(xy 123.957842 -32.913574) (xy 123.95708 -32.902144) (xy 123.95708 -32.90189) (xy 123.95708 -32.600646)
			(xy 123.95742 -32.587332) (xy 123.964185 -32.561582) (xy 123.977397 -32.538468) (xy 123.996151 -32.51957)
			(xy 124.019164 -32.506182) (xy 124.044861 -32.49922) (xy 124.058172 -32.498792) (xy 124.20092 -32.498792)
			(xy 124.20092 -32.525208) (xy 124.205155 -32.536912) (xy 124.222749 -32.554482) (xy 124.234448 -32.558736)
			(xy 124.749306 -32.558736) (xy 124.770388 -32.548322) (xy 124.777754 -32.53867) (xy 124.787616 -32.526629)
			(xy 124.813057 -32.508726) (xy 124.842717 -32.499347) (xy 124.858272 -32.498792) (xy 125.118368 -32.498792)
			(xy 125.133918 -32.499353) (xy 125.163563 -32.50876) (xy 125.189004 -32.52665) (xy 125.198886 -32.53867)
			(xy 125.206252 -32.548322) (xy 125.227334 -32.558736) (xy 125.746002 -32.558736) (xy 125.77572 -32.529018)
			(xy 125.77572 -32.52851) (xy 125.777244 -32.526986) (xy 125.777244 -32.500316) (xy 125.803914 -32.500316)
			(xy 125.805438 -32.498792) (xy 125.918468 -32.498792) (xy 125.931783 -32.499172) (xy 125.957485 -32.506144)
			(xy 125.980501 -32.519542) (xy 125.999256 -32.538448) (xy 126.012468 -32.561571) (xy 126.019234 -32.587328)
			(xy 126.01956 -32.600646) (xy 126.01956 -32.90189) (xy 126.01956 -32.902144) (xy 126.018798 -32.913574)
			(xy 126.018439 -32.917979) (xy 126.019074 -32.926794) (xy 126.020068 -32.9311) (xy 126.024167 -32.945852)
			(xy 126.039822 -32.972148) (xy 126.062548 -32.992643) (xy 126.090316 -33.005509) (xy 126.105412 -33.008062)
			(xy 126.132555 -33.012218) (xy 126.185382 -33.027186) (xy 126.235519 -33.049573) (xy 126.281928 -33.078915)
			(xy 126.323651 -33.114608) (xy 126.359827 -33.155914) (xy 126.389707 -33.201979) (xy 126.412675 -33.251852)
			(xy 126.428256 -33.304502) (xy 126.436128 -33.358842) (xy 126.436129 -33.413749) (xy 126.428258 -33.46809)
			(xy 126.412678 -33.52074) (xy 126.389711 -33.570614) (xy 126.359832 -33.616679) (xy 126.323657 -33.657986)
			(xy 126.281935 -33.69368) (xy 126.235526 -33.723023) (xy 126.18539 -33.745411) (xy 126.132563 -33.76038)
			(xy 126.105412 -33.764474) (xy 126.090299 -33.766989) (xy 126.062492 -33.779816) (xy 126.039749 -33.800324)
			(xy 126.024126 -33.826663) (xy 126.020068 -33.841436) (xy 126.019098 -33.845746) (xy 126.018455 -33.854557)
			(xy 126.018798 -33.858962) (xy 126.01956 -33.870392) (xy 126.01956 -33.870646) (xy 126.01956 -34.17189)
			(xy 126.019213 -34.185202) (xy 126.012442 -34.210948) (xy 125.999229 -34.234058) (xy 125.980478 -34.252954)
			(xy 125.95747 -34.266343) (xy 125.931777 -34.273312) (xy 125.918468 -34.273744) (xy 125.77572 -34.273744)
			(xy 125.77572 -34.252154) (xy 125.772382 -34.241387) (xy 125.758061 -34.224013) (xy 125.737701 -34.214399)
			(xy 125.726444 -34.2138) (xy 125.227334 -34.2138) (xy 125.206252 -34.224214) (xy 125.198886 -34.233866)
			(xy 125.189011 -34.245895) (xy 125.163576 -34.263799) (xy 125.133921 -34.273184) (xy 125.118368 -34.273744)
			(xy 124.858272 -34.273744) (xy 124.842726 -34.273144) (xy 124.813084 -34.263752) (xy 124.787641 -34.245878)
			(xy 124.777754 -34.233866) (xy 124.770388 -34.224214) (xy 124.749306 -34.2138) (xy 124.230638 -34.2138)
			(xy 124.20092 -34.243518) (xy 124.20092 -34.244026) (xy 124.199396 -34.24555) (xy 124.199396 -34.27222)
			(xy 124.172726 -34.27222) (xy 124.171202 -34.273744) (xy 124.058172 -34.273744) (xy 124.044862 -34.273294)
			(xy 124.019167 -34.266334) (xy 123.996154 -34.25295) (xy 123.977399 -34.234057) (xy 123.964183 -34.210948)
			(xy 123.95741 -34.185203) (xy 123.95708 -34.17189) (xy 123.95708 -33.870646) (xy 123.95708 -33.870392)
			(xy 123.957842 -33.858962) (xy 123.958217 -33.854558) (xy 123.957572 -33.845742) (xy 123.956572 -33.841436)
			(xy 123.952481 -33.826683) (xy 123.936818 -33.800392) (xy 123.914089 -33.779899) (xy 123.886323 -33.767031)
			(xy 123.871228 -33.764474) (xy 123.844062 -33.760445) (xy 123.791221 -33.745478) (xy 123.741072 -33.723089)
			(xy 123.694651 -33.693742) (xy 123.652917 -33.658043) (xy 123.616732 -33.616729) (xy 123.586844 -33.570654)
			(xy 123.563871 -33.52077) (xy 123.548286 -33.468108) (xy 123.540413 -33.413756) (xy 123.07316 -33.413756)
			(xy 123.07316 -34.4424) (xy 127.379982 -34.4424) (xy 127.384053 -34.386778) (xy 127.396179 -34.332341)
			(xy 127.416102 -34.28025) (xy 127.443398 -34.231615) (xy 127.477484 -34.187472) (xy 127.517633 -34.148763)
			(xy 127.562991 -34.116312) (xy 127.612591 -34.090811) (xy 127.665375 -34.072804) (xy 127.720218 -34.062674)
			(xy 127.775952 -34.060637) (xy 127.831389 -34.066737) (xy 127.885346 -34.080843) (xy 127.936675 -34.102655)
			(xy 127.984281 -34.131709) (xy 128.027149 -34.167384) (xy 128.064366 -34.208921) (xy 128.095139 -34.255434)
			(xy 128.118811 -34.305931) (xy 128.134879 -34.359338) (xy 128.142999 -34.414514) (xy 128.143508 -34.4424)
			(xy 128.142999 -34.470286) (xy 128.134879 -34.525462) (xy 128.118811 -34.578869) (xy 128.095139 -34.629366)
			(xy 128.064366 -34.675879) (xy 128.027149 -34.717416) (xy 127.984281 -34.753091) (xy 127.936675 -34.782145)
			(xy 127.885346 -34.803957) (xy 127.831389 -34.818063) (xy 127.775952 -34.824163) (xy 127.720218 -34.822126)
			(xy 127.665375 -34.811996) (xy 127.612591 -34.793989) (xy 127.562991 -34.768488) (xy 127.517633 -34.736037)
			(xy 127.477484 -34.697328) (xy 127.443398 -34.653185) (xy 127.416102 -34.60455) (xy 127.396179 -34.552459)
			(xy 127.384053 -34.498022) (xy 127.379982 -34.4424) (xy 123.07316 -34.4424) (xy 123.07316 -34.644838)
			(xy 123.072729 -34.654904) (xy 123.065 -34.673495) (xy 123.058174 -34.680906) (xy 122.839226 -34.899854)
			(xy 122.831826 -34.906694) (xy 122.813227 -34.914409) (xy 122.803158 -34.91484) (xy 122.164602 -34.91484)
			(xy 122.154533 -34.914416) (xy 122.135934 -34.906695) (xy 122.128534 -34.899854) (xy 121.914666 -34.685986)
			(xy 121.90727 -34.679135) (xy 121.888671 -34.6714) (xy 121.878598 -34.671) (xy 110.460282 -34.671)
			(xy 110.450213 -34.670573) (xy 110.431614 -34.662854) (xy 110.424214 -34.656014) (xy 110.059724 -34.291524)
			(xy 110.059724 -28.142438) (xy 109.567472 -27.650186) (xy 108.599986 -27.650186) (xy 108.592591 -27.643332)
			(xy 108.573992 -27.63559) (xy 108.563918 -27.6352) (xy 107.554522 -27.6352) (xy 107.535726 -27.64282)
			(xy 107.528614 -27.650186) (xy 107.304586 -27.874214) (xy 107.297732 -27.881609) (xy 107.28999 -27.900208)
			(xy 107.2896 -27.910282) (xy 107.2896 -30.825948) (xy 108.093764 -30.825948) (xy 108.093764 -30.169612)
			(xy 108.094178 -30.159539) (xy 108.101886 -30.140927) (xy 108.116132 -30.126682) (xy 108.134745 -30.118977)
			(xy 108.144818 -30.118558) (xy 108.652818 -30.118558) (xy 108.662878 -30.119022) (xy 108.681465 -30.126728)
			(xy 108.695689 -30.14096) (xy 108.703384 -30.159551) (xy 108.703872 -30.169612) (xy 108.703872 -30.825948)
			(xy 108.703403 -30.836007) (xy 108.695693 -30.854588) (xy 108.681463 -30.86881) (xy 108.662877 -30.876509)
			(xy 108.652818 -30.877002) (xy 108.144818 -30.877002) (xy 108.134767 -30.87645) (xy 108.116193 -30.868767)
			(xy 108.10197 -30.854563) (xy 108.094263 -30.835998) (xy 108.093764 -30.825948) (xy 107.2896 -30.825948)
			(xy 107.2896 -30.900624) (xy 107.290063 -30.910566) (xy 107.297611 -30.928962) (xy 107.311598 -30.943094)
			(xy 107.320588 -30.94736) (xy 107.395518 -30.978856) (xy 107.404847 -30.982283) (xy 107.424702 -30.982528)
			(xy 107.434126 -30.979364) (xy 107.4547 -30.970982) (xy 107.461558 -30.964886) (xy 107.482729 -30.946386)
			(xy 107.529485 -30.915165) (xy 107.580315 -30.891139) (xy 107.634119 -30.87483) (xy 107.689733 -30.86659)
			(xy 107.717844 -30.86608) (xy 107.73029 -30.866334) (xy 107.731052 -30.866334) (xy 107.733592 -30.866334)
			(xy 107.761817 -30.867332) (xy 107.817523 -30.876621) (xy 107.871251 -30.894021) (xy 107.921828 -30.919151)
			(xy 107.968147 -30.951462) (xy 108.009197 -30.990248) (xy 108.044081 -31.034662) (xy 108.072037 -31.083733)
			(xy 108.092453 -31.136389) (xy 108.104884 -31.19148) (xy 108.109058 -31.247801) (xy 108.104884 -31.304122)
			(xy 108.092453 -31.359212) (xy 108.072036 -31.411868) (xy 108.04408 -31.460939) (xy 108.009196 -31.505353)
			(xy 107.968146 -31.544139) (xy 107.921827 -31.57645) (xy 107.87125 -31.60158) (xy 107.817522 -31.618979)
			(xy 107.761815 -31.628268) (xy 107.733592 -31.62935) (xy 107.731052 -31.62935) (xy 107.73029 -31.62935)
			(xy 107.717844 -31.629604) (xy 107.71759 -31.629604) (xy 107.688577 -31.62907) (xy 107.631219 -31.620301)
			(xy 107.575848 -31.602952) (xy 107.523742 -31.577422) (xy 107.476099 -31.544299) (xy 107.4547 -31.524702)
			(xy 107.443524 -31.514034) (xy 107.41406 -31.5087) (xy 107.320588 -31.548324) (xy 107.311628 -31.55264)
			(xy 107.29765 -31.566761) (xy 107.290067 -31.585127) (xy 107.2896 -31.59506) (xy 107.2896 -32.326072)
			(xy 108.093764 -32.326072) (xy 108.093764 -31.669736) (xy 108.094197 -31.659665) (xy 108.101897 -31.641052)
			(xy 108.116137 -31.626807) (xy 108.134747 -31.619101) (xy 108.144818 -31.618682) (xy 108.652818 -31.618682)
			(xy 108.662895 -31.619054) (xy 108.681512 -31.626775) (xy 108.695756 -31.641034) (xy 108.703457 -31.659659)
			(xy 108.703872 -31.669736) (xy 108.703872 -32.326072) (xy 108.70341 -32.336139) (xy 108.695714 -32.354745)
			(xy 108.681483 -32.368988) (xy 108.662885 -32.376701) (xy 108.652818 -32.377126) (xy 108.144818 -32.377126)
			(xy 108.134744 -32.376717) (xy 108.11613 -32.369009) (xy 108.101885 -32.354762) (xy 108.094181 -32.336146)
			(xy 108.093764 -32.326072) (xy 107.2896 -32.326072) (xy 107.2896 -33.32607) (xy 108.093764 -33.32607)
			(xy 108.093764 -32.669734) (xy 108.094196 -32.659663) (xy 108.101896 -32.64105) (xy 108.116137 -32.626805)
			(xy 108.134747 -32.619099) (xy 108.144818 -32.61868) (xy 108.652818 -32.61868) (xy 108.662895 -32.619054)
			(xy 108.681511 -32.626774) (xy 108.695755 -32.641033) (xy 108.703457 -32.659657) (xy 108.703872 -32.669734)
			(xy 108.703872 -33.32607) (xy 108.703408 -33.336137) (xy 108.695713 -33.354743) (xy 108.681483 -33.368986)
			(xy 108.662885 -33.376699) (xy 108.652818 -33.377124) (xy 108.144818 -33.377124) (xy 108.134744 -33.376717)
			(xy 108.116129 -33.369009) (xy 108.101884 -33.354761) (xy 108.094181 -33.336144) (xy 108.093764 -33.32607)
			(xy 107.2896 -33.32607) (xy 107.2896 -34.2392) (xy 107.290093 -34.249531) (xy 107.298227 -34.268527)
			(xy 107.305348 -34.27603) (xy 107.358942 -34.32683) (xy 107.366263 -34.333212) (xy 107.38429 -34.340393)
			(xy 107.393994 -34.3408) (xy 107.399074 -34.3408) (xy 107.400344 -34.3408) (xy 107.41406 -34.340292)
			(xy 107.414314 -34.340292) (xy 107.441555 -34.340792) (xy 107.49548 -34.348574) (xy 107.547749 -34.363947)
			(xy 107.597299 -34.386601) (xy 107.643123 -34.416073) (xy 107.684287 -34.451764) (xy 107.719956 -34.492949)
			(xy 107.749402 -34.538789) (xy 107.772028 -34.588352) (xy 107.787372 -34.64063) (xy 107.795123 -34.694558)
			(xy 107.795123 -34.749042) (xy 107.787372 -34.80297) (xy 107.772028 -34.855248) (xy 107.749402 -34.904811)
			(xy 107.719956 -34.950651) (xy 107.684287 -34.991836) (xy 107.643123 -35.027527) (xy 107.597299 -35.056999)
			(xy 107.547749 -35.079653) (xy 107.49548 -35.095026) (xy 107.441555 -35.102808) (xy 107.414314 -35.103308)
			(xy 107.41406 -35.103308) (xy 107.396788 -35.1028) (xy 107.396534 -35.1028) (xy 107.386263 -35.102756)
			(xy 107.367004 -35.109842) (xy 107.359196 -35.116516) (xy 107.305602 -35.167316) (xy 107.298335 -35.174815)
			(xy 107.290069 -35.193968) (xy 107.2896 -35.2044) (xy 107.2896 -36.053268) (xy 121.444258 -36.053268)
			(xy 121.444695 -36.025997) (xy 121.452461 -35.972011) (xy 121.467832 -35.919679) (xy 121.490493 -35.870067)
			(xy 121.519984 -35.824186) (xy 121.555705 -35.782968) (xy 121.596927 -35.747253) (xy 121.642813 -35.717768)
			(xy 121.692428 -35.695114) (xy 121.744761 -35.67975) (xy 121.798749 -35.671991) (xy 121.82602 -35.671506)
			(xy 121.85904 -35.67303) (xy 121.863104 -35.672776) (xy 121.880884 -35.67176) (xy 121.890017 -35.671031)
			(xy 121.906932 -35.66404) (xy 121.920315 -35.651554) (xy 121.928461 -35.635163) (xy 121.930333 -35.616956)
			(xy 121.928382 -35.608006) (xy 121.926802 -35.601583) (xy 121.925151 -35.588458) (xy 121.92508 -35.581844)
			(xy 121.92508 -35.58159) (xy 121.92508 -35.280346) (xy 121.92542 -35.267032) (xy 121.932185 -35.241282)
			(xy 121.945397 -35.218168) (xy 121.964151 -35.19927) (xy 121.987164 -35.185882) (xy 122.012861 -35.17892)
			(xy 122.026172 -35.178492) (xy 122.16892 -35.178492) (xy 122.16892 -35.204908) (xy 122.173155 -35.216612)
			(xy 122.190749 -35.234182) (xy 122.202448 -35.238436) (xy 122.717306 -35.238436) (xy 122.738388 -35.228022)
			(xy 122.745754 -35.21837) (xy 122.755616 -35.206329) (xy 122.781057 -35.188426) (xy 122.810717 -35.179047)
			(xy 122.826272 -35.178492) (xy 123.086368 -35.178492) (xy 123.101918 -35.179053) (xy 123.131563 -35.18846)
			(xy 123.157004 -35.20635) (xy 123.166886 -35.21837) (xy 123.174252 -35.228022) (xy 123.195334 -35.238436)
			(xy 123.694444 -35.238436) (xy 123.704518 -35.23805) (xy 123.723117 -35.230304) (xy 123.730512 -35.22345)
			(xy 123.74372 -35.210242) (xy 123.74372 -35.178492) (xy 123.886468 -35.178492) (xy 123.899783 -35.178872)
			(xy 123.925485 -35.185844) (xy 123.948501 -35.199242) (xy 123.967256 -35.218148) (xy 123.980468 -35.241271)
			(xy 123.987234 -35.267028) (xy 123.98756 -35.280346) (xy 123.98756 -35.58159) (xy 123.98756 -35.581844)
			(xy 123.987487 -35.588458) (xy 123.985829 -35.601581) (xy 123.984258 -35.608006) (xy 123.982256 -35.617013)
			(xy 123.984121 -35.635357) (xy 123.992374 -35.651844) (xy 124.00594 -35.664331) (xy 124.023054 -35.67119)
			(xy 124.032264 -35.67176) (xy 124.056394 -35.67303) (xy 124.06503 -35.67303) (xy 124.098812 -35.671506)
			(xy 124.09932 -35.671506) (xy 124.126586 -35.672058) (xy 124.180563 -35.679821) (xy 124.232886 -35.695187)
			(xy 124.282489 -35.717842) (xy 124.328364 -35.747326) (xy 124.369576 -35.783038) (xy 124.405286 -35.824252)
			(xy 124.408165 -35.828732) (xy 126.652526 -35.828732) (xy 126.656597 -35.77311) (xy 126.668723 -35.718673)
			(xy 126.688646 -35.666582) (xy 126.715942 -35.617947) (xy 126.750028 -35.573804) (xy 126.790177 -35.535095)
			(xy 126.835535 -35.502644) (xy 126.885135 -35.477143) (xy 126.937919 -35.459136) (xy 126.992762 -35.449006)
			(xy 127.048496 -35.446969) (xy 127.103933 -35.453069) (xy 127.15789 -35.467175) (xy 127.209219 -35.488987)
			(xy 127.256825 -35.518041) (xy 127.299693 -35.553716) (xy 127.33691 -35.595253) (xy 127.367683 -35.641766)
			(xy 127.391355 -35.692263) (xy 127.407423 -35.74567) (xy 127.415543 -35.800846) (xy 127.416052 -35.828732)
			(xy 127.415543 -35.856618) (xy 127.407423 -35.911794) (xy 127.391355 -35.965201) (xy 127.367683 -36.015698)
			(xy 127.33691 -36.062211) (xy 127.299693 -36.103748) (xy 127.256825 -36.139423) (xy 127.209219 -36.168477)
			(xy 127.15789 -36.190289) (xy 127.103933 -36.204395) (xy 127.048496 -36.210495) (xy 126.992762 -36.208458)
			(xy 126.937919 -36.198328) (xy 126.885135 -36.180321) (xy 126.835535 -36.15482) (xy 126.790177 -36.122369)
			(xy 126.750028 -36.08366) (xy 126.715942 -36.039517) (xy 126.688646 -35.990882) (xy 126.668723 -35.938791)
			(xy 126.656597 -35.884354) (xy 126.652526 -35.828732) (xy 124.408165 -35.828732) (xy 124.434767 -35.870128)
			(xy 124.45742 -35.919733) (xy 124.472783 -35.972056) (xy 124.480544 -36.026034) (xy 124.480544 -36.080566)
			(xy 124.472783 -36.134544) (xy 124.45742 -36.186867) (xy 124.434767 -36.236472) (xy 124.405286 -36.282348)
			(xy 124.369576 -36.323562) (xy 124.328364 -36.359274) (xy 124.282489 -36.388758) (xy 124.232886 -36.411413)
			(xy 124.180563 -36.426779) (xy 124.126586 -36.434542) (xy 124.09932 -36.43503) (xy 124.098812 -36.43503)
			(xy 124.06503 -36.433506) (xy 124.056394 -36.433506) (xy 124.032264 -36.434776) (xy 124.023071 -36.435397)
			(xy 124.005998 -36.442285) (xy 123.99246 -36.454762) (xy 123.984205 -36.471217) (xy 123.982296 -36.489528)
			(xy 123.984258 -36.49853) (xy 123.985824 -36.504956) (xy 123.987484 -36.518078) (xy 123.98756 -36.524692)
			(xy 123.98756 -36.524946) (xy 123.98756 -36.82619) (xy 123.987213 -36.839502) (xy 123.980442 -36.865248)
			(xy 123.967229 -36.888358) (xy 123.948478 -36.907254) (xy 123.92547 -36.920643) (xy 123.899777 -36.927612)
			(xy 123.886468 -36.928044) (xy 123.74372 -36.928044) (xy 123.74372 -36.901628) (xy 123.73945 -36.889941)
			(xy 123.721881 -36.872363) (xy 123.710192 -36.8681) (xy 123.195334 -36.8681) (xy 123.174252 -36.878514)
			(xy 123.166886 -36.888166) (xy 123.157011 -36.900195) (xy 123.131576 -36.918099) (xy 123.101921 -36.927484)
			(xy 123.086368 -36.928044) (xy 122.826272 -36.928044) (xy 122.810726 -36.927444) (xy 122.781084 -36.918052)
			(xy 122.755641 -36.900178) (xy 122.745754 -36.888166) (xy 122.738388 -36.878514) (xy 122.717306 -36.8681)
			(xy 122.218196 -36.8681) (xy 122.208123 -36.868497) (xy 122.189524 -36.876235) (xy 122.182128 -36.883086)
			(xy 122.16892 -36.896294) (xy 122.16892 -36.928044) (xy 122.026172 -36.928044) (xy 122.012862 -36.927594)
			(xy 121.987167 -36.920634) (xy 121.964154 -36.90725) (xy 121.945399 -36.888357) (xy 121.932183 -36.865248)
			(xy 121.92541 -36.839503) (xy 121.92508 -36.82619) (xy 121.92508 -36.524946) (xy 121.92508 -36.524692)
			(xy 121.925158 -36.518078) (xy 121.926813 -36.504955) (xy 121.928382 -36.49853) (xy 121.930314 -36.489562)
			(xy 121.928507 -36.471326) (xy 121.920381 -36.454901) (xy 121.906981 -36.442401) (xy 121.890031 -36.435434)
			(xy 121.880884 -36.434776) (xy 121.863104 -36.43376) (xy 121.85904 -36.433506) (xy 121.82602 -36.43503)
			(xy 121.798748 -36.43458) (xy 121.744759 -36.42682) (xy 121.692424 -36.411454) (xy 121.642809 -36.388797)
			(xy 121.596924 -36.359308) (xy 121.555702 -36.323589) (xy 121.519985 -36.282367) (xy 121.490498 -36.236481)
			(xy 121.467842 -36.186865) (xy 121.452478 -36.134529) (xy 121.444719 -36.08054) (xy 121.444258 -36.053268)
			(xy 107.2896 -36.053268) (xy 107.2896 -39.963598) (xy 107.290023 -39.973668) (xy 107.297737 -39.992273)
			(xy 107.304586 -39.999666) (xy 107.587796 -40.282876) (xy 110.388144 -40.282876) (xy 110.392215 -40.227254)
			(xy 110.404341 -40.172817) (xy 110.424264 -40.120726) (xy 110.45156 -40.072091) (xy 110.485646 -40.027948)
			(xy 110.525795 -39.989239) (xy 110.571153 -39.956788) (xy 110.620753 -39.931287) (xy 110.673537 -39.91328)
			(xy 110.72838 -39.90315) (xy 110.784114 -39.901113) (xy 110.839551 -39.907213) (xy 110.893508 -39.921319)
			(xy 110.944837 -39.943131) (xy 110.992443 -39.972185) (xy 111.035311 -40.00786) (xy 111.072528 -40.049397)
			(xy 111.103301 -40.09591) (xy 111.126973 -40.146407) (xy 111.143041 -40.199814) (xy 111.151161 -40.25499)
			(xy 111.15167 -40.282876) (xy 111.151369 -40.299386) (xy 113.419634 -40.299386) (xy 113.423705 -40.243764)
			(xy 113.435831 -40.189327) (xy 113.455754 -40.137236) (xy 113.48305 -40.088601) (xy 113.517136 -40.044458)
			(xy 113.557285 -40.005749) (xy 113.602643 -39.973298) (xy 113.652243 -39.947797) (xy 113.705027 -39.92979)
			(xy 113.75987 -39.91966) (xy 113.815604 -39.917623) (xy 113.871041 -39.923723) (xy 113.924998 -39.937829)
			(xy 113.976327 -39.959641) (xy 114.023933 -39.988695) (xy 114.066801 -40.02437) (xy 114.104018 -40.065907)
			(xy 114.134791 -40.11242) (xy 114.158463 -40.162917) (xy 114.174531 -40.216324) (xy 114.182651 -40.2715)
			(xy 114.18316 -40.299386) (xy 114.182651 -40.327272) (xy 114.174531 -40.382448) (xy 114.158463 -40.435855)
			(xy 114.134791 -40.486352) (xy 114.104018 -40.532865) (xy 114.066801 -40.574402) (xy 114.023933 -40.610077)
			(xy 113.976327 -40.639131) (xy 113.924998 -40.660943) (xy 113.871041 -40.675049) (xy 113.815604 -40.681149)
			(xy 113.75987 -40.679112) (xy 113.705027 -40.668982) (xy 113.652243 -40.650975) (xy 113.602643 -40.625474)
			(xy 113.557285 -40.593023) (xy 113.517136 -40.554314) (xy 113.48305 -40.510171) (xy 113.455754 -40.461536)
			(xy 113.435831 -40.409445) (xy 113.423705 -40.355008) (xy 113.419634 -40.299386) (xy 111.151369 -40.299386)
			(xy 111.151161 -40.310762) (xy 111.143041 -40.365938) (xy 111.126973 -40.419345) (xy 111.103301 -40.469842)
			(xy 111.072528 -40.516355) (xy 111.035311 -40.557892) (xy 110.992443 -40.593567) (xy 110.944837 -40.622621)
			(xy 110.893508 -40.644433) (xy 110.839551 -40.658539) (xy 110.784114 -40.664639) (xy 110.72838 -40.662602)
			(xy 110.673537 -40.652472) (xy 110.620753 -40.634465) (xy 110.571153 -40.608964) (xy 110.525795 -40.576513)
			(xy 110.485646 -40.537804) (xy 110.45156 -40.493661) (xy 110.424264 -40.445026) (xy 110.404341 -40.392935)
			(xy 110.392215 -40.338498) (xy 110.388144 -40.282876) (xy 107.587796 -40.282876) (xy 108.575094 -41.270174)
			(xy 108.582491 -41.277024) (xy 108.601089 -41.284765) (xy 108.611162 -41.28516)
		)
		(stroke
			(width 0)
			(type solid)
		)
		(fill yes)
		(layer "In2.Cu")
		(net "P3V3_AUX_CPU0_USB2_AVDD33")
	)
	(gr_poly
		(pts
			(xy 71.167244 -10.51814) (xy 71.167658 -10.506093) (xy 71.175093 -10.483175) (xy 71.189249 -10.463679)
			(xy 71.208738 -10.449512) (xy 71.231651 -10.442064) (xy 71.243698 -10.441686) (xy 72.280272 -10.441686)
			(xy 72.292315 -10.442101) (xy 72.315224 -10.44954) (xy 72.334711 -10.463698) (xy 72.348865 -10.483186)
			(xy 72.3563 -10.506097) (xy 72.356726 -10.51814) (xy 72.356726 -10.756646) (xy 76.181712 -10.756646)
			(xy 76.19178 -10.756219) (xy 76.210376 -10.748496) (xy 76.21778 -10.74166) (xy 76.479146 -10.480294)
			(xy 76.485997 -10.472898) (xy 76.493738 -10.454299) (xy 76.494132 -10.444226) (xy 76.494132 -7.669784)
			(xy 76.493542 -7.658026) (xy 76.483083 -7.636966) (xy 76.474066 -7.629398) (xy 76.399898 -7.573264)
			(xy 76.376784 -7.568692) (xy 76.3651 -7.571994) (xy 76.339835 -7.578624) (xy 76.288092 -7.585767)
			(xy 76.261976 -7.586218) (xy 76.234725 -7.585731) (xy 76.180779 -7.577971) (xy 76.128485 -7.562613)
			(xy 76.07891 -7.53997) (xy 76.033061 -7.510503) (xy 75.991873 -7.47481) (xy 75.956183 -7.433619)
			(xy 75.926718 -7.387769) (xy 75.904078 -7.338192) (xy 75.888724 -7.285898) (xy 75.880968 -7.231951)
			(xy 75.880968 -7.177449) (xy 75.888724 -7.123502) (xy 75.904078 -7.071208) (xy 75.926718 -7.021631)
			(xy 75.956183 -6.975781) (xy 75.991873 -6.93459) (xy 76.033061 -6.898897) (xy 76.07891 -6.86943)
			(xy 76.128485 -6.846787) (xy 76.180779 -6.831429) (xy 76.234725 -6.823669) (xy 76.261976 -6.823202)
			(xy 76.289514 -6.823706) (xy 76.344012 -6.831668) (xy 76.396799 -6.847386) (xy 76.421996 -6.858508)
			(xy 76.432156 -6.86308) (xy 76.443332 -6.86308) (xy 76.453334 -6.862586) (xy 76.471811 -6.85492)
			(xy 76.485949 -6.840768) (xy 76.493596 -6.822282) (xy 76.494132 -6.81228) (xy 76.494132 -6.79831)
			(xy 76.492608 -6.79196) (xy 76.486916 -6.768559) (xy 76.480797 -6.72079) (xy 76.480416 -6.69671)
			(xy 76.480816 -6.672632) (xy 76.486931 -6.624863) (xy 76.492608 -6.60146) (xy 76.494132 -6.59511)
			(xy 76.494132 -6.169152) (xy 76.493698 -6.159407) (xy 76.486409 -6.141331) (xy 76.472876 -6.127307)
			(xy 76.46416 -6.122924) (xy 76.365862 -6.078728) (xy 76.336398 -6.083046) (xy 76.325222 -6.093206)
			(xy 76.304182 -6.111189) (xy 76.257891 -6.141528) (xy 76.207704 -6.164865) (xy 76.154674 -6.180712)
			(xy 76.099911 -6.188737) (xy 76.072238 -6.189218) (xy 76.071984 -6.189218) (xy 76.044733 -6.188731)
			(xy 75.990785 -6.180973) (xy 75.938491 -6.165616) (xy 75.888915 -6.142973) (xy 75.843065 -6.113505)
			(xy 75.801876 -6.077813) (xy 75.766185 -6.036622) (xy 75.736719 -5.990771) (xy 75.714079 -5.941194)
			(xy 75.698724 -5.888899) (xy 75.690968 -5.834951) (xy 75.690968 -5.780449) (xy 75.698724 -5.726501)
			(xy 75.714079 -5.674206) (xy 75.736719 -5.624629) (xy 75.766185 -5.578778) (xy 75.801876 -5.537587)
			(xy 75.843065 -5.501895) (xy 75.888915 -5.472427) (xy 75.938491 -5.449784) (xy 75.990785 -5.434427)
			(xy 76.044733 -5.426669) (xy 76.071984 -5.426202) (xy 76.072238 -5.426202) (xy 76.099913 -5.426693)
			(xy 76.154681 -5.434691) (xy 76.207716 -5.450527) (xy 76.257903 -5.473869) (xy 76.304185 -5.504226)
			(xy 76.325222 -5.522214) (xy 76.336398 -5.532374) (xy 76.365862 -5.536692) (xy 76.46416 -5.492496)
			(xy 76.472853 -5.488089) (xy 76.486344 -5.474047) (xy 76.493663 -5.456002) (xy 76.494132 -5.446268)
			(xy 76.494132 -2.847848) (xy 76.4937 -2.837781) (xy 76.485976 -2.819188) (xy 76.479146 -2.81178)
			(xy 76.149708 -2.482342) (xy 76.142312 -2.47549) (xy 76.123714 -2.467746) (xy 76.11364 -2.467356)
			(xy 70.914006 -2.467356) (xy 70.903937 -2.46778) (xy 70.885336 -2.475499) (xy 70.877938 -2.482342)
			(xy 69.596 -3.76428) (xy 73.531982 -3.76428) (xy 73.536053 -3.708658) (xy 73.548179 -3.654221) (xy 73.568102 -3.60213)
			(xy 73.595398 -3.553495) (xy 73.629484 -3.509352) (xy 73.669633 -3.470643) (xy 73.714991 -3.438192)
			(xy 73.764591 -3.412691) (xy 73.817375 -3.394684) (xy 73.872218 -3.384554) (xy 73.927952 -3.382517)
			(xy 73.983389 -3.388617) (xy 74.037346 -3.402723) (xy 74.088675 -3.424535) (xy 74.136281 -3.453589)
			(xy 74.179149 -3.489264) (xy 74.216366 -3.530801) (xy 74.247139 -3.577314) (xy 74.270811 -3.627811)
			(xy 74.286879 -3.681218) (xy 74.294999 -3.736394) (xy 74.295508 -3.76428) (xy 74.294999 -3.792166)
			(xy 74.286879 -3.847342) (xy 74.270811 -3.900749) (xy 74.247139 -3.951246) (xy 74.216366 -3.997759)
			(xy 74.179149 -4.039296) (xy 74.136281 -4.074971) (xy 74.088675 -4.104025) (xy 74.037346 -4.125837)
			(xy 73.983389 -4.139943) (xy 73.927952 -4.146043) (xy 73.872218 -4.144006) (xy 73.817375 -4.133876)
			(xy 73.764591 -4.115869) (xy 73.714991 -4.090368) (xy 73.669633 -4.057917) (xy 73.629484 -4.019208)
			(xy 73.595398 -3.975065) (xy 73.568102 -3.92643) (xy 73.548179 -3.874339) (xy 73.536053 -3.819902)
			(xy 73.531982 -3.76428) (xy 69.596 -3.76428) (xy 68.24218 -5.1181) (xy 68.23478 -5.124943) (xy 68.216182 -5.13267)
			(xy 68.206112 -5.133086) (xy 63.024004 -5.133086) (xy 62.99454 -5.161788) (xy 62.99414 -5.17271)
			(xy 72.514966 -5.17271) (xy 72.519037 -5.117088) (xy 72.531163 -5.062651) (xy 72.551086 -5.01056)
			(xy 72.578382 -4.961925) (xy 72.612468 -4.917782) (xy 72.652617 -4.879073) (xy 72.697975 -4.846622)
			(xy 72.747575 -4.821121) (xy 72.800359 -4.803114) (xy 72.855202 -4.792984) (xy 72.910936 -4.790947)
			(xy 72.966373 -4.797047) (xy 73.02033 -4.811153) (xy 73.071659 -4.832965) (xy 73.119265 -4.862019)
			(xy 73.162133 -4.897694) (xy 73.19935 -4.939231) (xy 73.230123 -4.985744) (xy 73.253795 -5.036241)
			(xy 73.269863 -5.089648) (xy 73.277983 -5.144824) (xy 73.278492 -5.17271) (xy 73.277983 -5.200596)
			(xy 73.269863 -5.255772) (xy 73.253795 -5.309179) (xy 73.230123 -5.359676) (xy 73.19935 -5.406189)
			(xy 73.174136 -5.43433) (xy 73.572116 -5.43433) (xy 73.572602 -5.407079) (xy 73.580358 -5.353131)
			(xy 73.595713 -5.300836) (xy 73.618355 -5.251259) (xy 73.647821 -5.205409) (xy 73.683512 -5.164218)
			(xy 73.724703 -5.128527) (xy 73.770553 -5.099061) (xy 73.82013 -5.076419) (xy 73.872425 -5.061064)
			(xy 73.926373 -5.053308) (xy 73.980875 -5.053308) (xy 74.034823 -5.061064) (xy 74.087118 -5.076419)
			(xy 74.136695 -5.099061) (xy 74.182545 -5.128527) (xy 74.223736 -5.164218) (xy 74.259427 -5.205409)
			(xy 74.288893 -5.251259) (xy 74.311535 -5.300836) (xy 74.32689 -5.353131) (xy 74.334646 -5.407079)
			(xy 74.335132 -5.43433) (xy 74.334667 -5.461794) (xy 74.326802 -5.516156) (xy 74.311225 -5.568829)
			(xy 74.288258 -5.618724) (xy 74.258375 -5.664812) (xy 74.240644 -5.68579) (xy 74.231439 -5.697128)
			(xy 74.219203 -5.723628) (xy 74.214954 -5.752506) (xy 74.219037 -5.781408) (xy 74.23112 -5.807979)
			(xy 74.250219 -5.830052) (xy 74.274776 -5.84583) (xy 74.28865 -5.850382) (xy 74.314733 -5.858492)
			(xy 74.364486 -5.881029) (xy 74.410513 -5.910435) (xy 74.451872 -5.946109) (xy 74.487717 -5.98732)
			(xy 74.517314 -6.033225) (xy 74.540057 -6.082883) (xy 74.55548 -6.13528) (xy 74.563267 -6.18934)
			(xy 74.563732 -6.21665) (xy 74.563246 -6.243901) (xy 74.55549 -6.297849) (xy 74.540135 -6.350144)
			(xy 74.517493 -6.399721) (xy 74.488027 -6.445571) (xy 74.452336 -6.486762) (xy 74.411145 -6.522453)
			(xy 74.365295 -6.551919) (xy 74.315718 -6.574561) (xy 74.263423 -6.589916) (xy 74.209475 -6.597672)
			(xy 74.154973 -6.597672) (xy 74.101025 -6.589916) (xy 74.04873 -6.574561) (xy 73.999153 -6.551919)
			(xy 73.953303 -6.522453) (xy 73.912112 -6.486762) (xy 73.876421 -6.445571) (xy 73.846955 -6.399721)
			(xy 73.824313 -6.350144) (xy 73.808958 -6.297849) (xy 73.801202 -6.243901) (xy 73.800716 -6.21665)
			(xy 73.801158 -6.189185) (xy 73.809026 -6.134822) (xy 73.824608 -6.082148) (xy 73.84758 -6.032253)
			(xy 73.877469 -5.986167) (xy 73.895204 -5.96519) (xy 73.904458 -5.953886) (xy 73.916701 -5.927376)
			(xy 73.920951 -5.898486) (xy 73.916862 -5.869573) (xy 73.904768 -5.842995) (xy 73.885654 -5.820918)
			(xy 73.86108 -5.805145) (xy 73.847198 -5.800598) (xy 73.821099 -5.792538) (xy 73.771346 -5.769994)
			(xy 73.72532 -5.74058) (xy 73.683962 -5.704899) (xy 73.648119 -5.663681) (xy 73.618524 -5.617771)
			(xy 73.595784 -5.568107) (xy 73.580364 -5.515706) (xy 73.572579 -5.461641) (xy 73.572116 -5.43433)
			(xy 73.174136 -5.43433) (xy 73.162133 -5.447726) (xy 73.119265 -5.483401) (xy 73.071659 -5.512455)
			(xy 73.02033 -5.534267) (xy 72.966373 -5.548373) (xy 72.910936 -5.554473) (xy 72.855202 -5.552436)
			(xy 72.800359 -5.542306) (xy 72.747575 -5.524299) (xy 72.697975 -5.498798) (xy 72.652617 -5.466347)
			(xy 72.612468 -5.427638) (xy 72.578382 -5.383495) (xy 72.551086 -5.33486) (xy 72.531163 -5.282769)
			(xy 72.519037 -5.228332) (xy 72.514966 -5.17271) (xy 62.99414 -5.17271) (xy 62.993778 -5.182616)
			(xy 62.992568 -5.210676) (xy 62.982928 -5.266004) (xy 62.965278 -5.319321) (xy 62.939999 -5.369473)
			(xy 62.907639 -5.415375) (xy 62.868896 -5.456035) (xy 62.824609 -5.490573) (xy 62.775736 -5.518243)
			(xy 62.723333 -5.538446) (xy 62.668534 -5.550745) (xy 62.612524 -5.554875) (xy 62.556514 -5.550745)
			(xy 62.501715 -5.538446) (xy 62.449312 -5.518243) (xy 62.400439 -5.490573) (xy 62.356152 -5.456035)
			(xy 62.317409 -5.415375) (xy 62.285049 -5.369473) (xy 62.25977 -5.319321) (xy 62.24212 -5.266004)
			(xy 62.23248 -5.210676) (xy 62.23127 -5.182616) (xy 62.230508 -5.161788) (xy 62.201044 -5.133086)
			(xy 61.703204 -5.133086) (xy 61.67374 -5.161026) (xy 61.672724 -5.181346) (xy 61.67087 -5.208939)
			(xy 61.660198 -5.263201) (xy 61.641802 -5.315353) (xy 61.616069 -5.364302) (xy 61.583537 -5.409023)
			(xy 61.544888 -5.448577) (xy 61.500933 -5.482136) (xy 61.452593 -5.508996) (xy 61.400881 -5.528594)
			(xy 61.34688 -5.54052) (xy 61.291724 -5.544523) (xy 61.236568 -5.54052) (xy 61.182567 -5.528594)
			(xy 61.130855 -5.508996) (xy 61.082515 -5.482136) (xy 61.03856 -5.448577) (xy 60.999911 -5.409023)
			(xy 60.967379 -5.364302) (xy 60.941646 -5.315353) (xy 60.92325 -5.263201) (xy 60.912578 -5.208939)
			(xy 60.910724 -5.181346) (xy 60.909708 -5.161026) (xy 60.880244 -5.133086) (xy 60.281566 -5.133086)
			(xy 60.272611 -5.133435) (xy 60.255791 -5.139585) (xy 60.242096 -5.151128) (xy 60.23737 -5.15874)
			(xy 60.187078 -5.24764) (xy 60.187332 -5.274818) (xy 60.194444 -5.286756) (xy 60.207283 -5.309042)
			(xy 60.227515 -5.35633) (xy 60.24121 -5.405906) (xy 60.248121 -5.456873) (xy 60.248546 -5.48259)
			(xy 60.248061 -5.509843) (xy 60.240306 -5.563794) (xy 60.224952 -5.616092) (xy 60.202312 -5.665673)
			(xy 60.172846 -5.711527) (xy 60.137155 -5.752721) (xy 60.095965 -5.788418) (xy 60.050115 -5.817889)
			(xy 60.000537 -5.840535) (xy 59.991226 -5.84327) (xy 61.463426 -5.84327) (xy 61.467497 -5.787648)
			(xy 61.479623 -5.733211) (xy 61.499546 -5.68112) (xy 61.526842 -5.632485) (xy 61.560928 -5.588342)
			(xy 61.601077 -5.549633) (xy 61.646435 -5.517182) (xy 61.696035 -5.491681) (xy 61.748819 -5.473674)
			(xy 61.803662 -5.463544) (xy 61.859396 -5.461507) (xy 61.914833 -5.467607) (xy 61.96879 -5.481713)
			(xy 62.020119 -5.503525) (xy 62.067725 -5.532579) (xy 62.110593 -5.568254) (xy 62.14781 -5.609791)
			(xy 62.178583 -5.656304) (xy 62.202255 -5.706801) (xy 62.218323 -5.760208) (xy 62.226443 -5.815384)
			(xy 62.226952 -5.84327) (xy 62.226443 -5.871156) (xy 62.218323 -5.926332) (xy 62.202255 -5.979739)
			(xy 62.178583 -6.030236) (xy 62.14781 -6.076749) (xy 62.110593 -6.118286) (xy 62.067725 -6.153961)
			(xy 62.020119 -6.183015) (xy 61.96879 -6.204827) (xy 61.914833 -6.218933) (xy 61.859396 -6.225033)
			(xy 61.803662 -6.222996) (xy 61.748819 -6.212866) (xy 61.696035 -6.194859) (xy 61.646435 -6.169358)
			(xy 61.601077 -6.136907) (xy 61.560928 -6.098198) (xy 61.526842 -6.054055) (xy 61.499546 -6.00542)
			(xy 61.479623 -5.953329) (xy 61.467497 -5.898892) (xy 61.463426 -5.84327) (xy 59.991226 -5.84327)
			(xy 59.948241 -5.855896) (xy 59.894291 -5.863657) (xy 59.867038 -5.864098) (xy 59.83839 -5.863585)
			(xy 59.781738 -5.855016) (xy 59.727007 -5.838065) (xy 59.675429 -5.813113) (xy 59.628167 -5.780723)
			(xy 59.586284 -5.741625) (xy 59.550725 -5.696699) (xy 59.536076 -5.672074) (xy 59.52998 -5.661914)
			(xy 59.510422 -5.648706) (xy 59.418728 -5.636514) (xy 59.407039 -5.635519) (xy 59.384805 -5.642923)
			(xy 59.376056 -5.650738) (xy 59.348878 -5.677916) (xy 59.342026 -5.685312) (xy 59.334285 -5.703911)
			(xy 59.333892 -5.713984) (xy 59.333892 -6.66369) (xy 60.084968 -6.66369) (xy 60.089039 -6.608068)
			(xy 60.101165 -6.553631) (xy 60.121088 -6.50154) (xy 60.148384 -6.452905) (xy 60.18247 -6.408762)
			(xy 60.222619 -6.370053) (xy 60.267977 -6.337602) (xy 60.317577 -6.312101) (xy 60.370361 -6.294094)
			(xy 60.425204 -6.283964) (xy 60.480938 -6.281927) (xy 60.536375 -6.288027) (xy 60.590332 -6.302133)
			(xy 60.641661 -6.323945) (xy 60.689267 -6.352999) (xy 60.732135 -6.388674) (xy 60.769352 -6.430211)
			(xy 60.800125 -6.476724) (xy 60.823797 -6.527221) (xy 60.839865 -6.580628) (xy 60.847985 -6.635804)
			(xy 60.848494 -6.66369) (xy 60.847985 -6.691576) (xy 60.839865 -6.746752) (xy 60.823797 -6.800159)
			(xy 60.813947 -6.82117) (xy 62.192406 -6.82117) (xy 62.196477 -6.765548) (xy 62.208603 -6.711111)
			(xy 62.228526 -6.65902) (xy 62.255822 -6.610385) (xy 62.289908 -6.566242) (xy 62.330057 -6.527533)
			(xy 62.375415 -6.495082) (xy 62.425015 -6.469581) (xy 62.477799 -6.451574) (xy 62.532642 -6.441444)
			(xy 62.588376 -6.439407) (xy 62.643813 -6.445507) (xy 62.69777 -6.459613) (xy 62.749099 -6.481425)
			(xy 62.796705 -6.510479) (xy 62.839573 -6.546154) (xy 62.87679 -6.587691) (xy 62.907563 -6.634204)
			(xy 62.931235 -6.684701) (xy 62.947303 -6.738108) (xy 62.955423 -6.793284) (xy 62.955932 -6.82117)
			(xy 62.955423 -6.849056) (xy 62.947303 -6.904232) (xy 62.931235 -6.957639) (xy 62.907563 -7.008136)
			(xy 62.87679 -7.054649) (xy 62.839573 -7.096186) (xy 62.796705 -7.131861) (xy 62.749099 -7.160915)
			(xy 62.69777 -7.182727) (xy 62.643813 -7.196833) (xy 62.588376 -7.202933) (xy 62.532642 -7.200896)
			(xy 62.477799 -7.190766) (xy 62.425015 -7.172759) (xy 62.375415 -7.147258) (xy 62.330057 -7.114807)
			(xy 62.289908 -7.076098) (xy 62.255822 -7.031955) (xy 62.228526 -6.98332) (xy 62.208603 -6.931229)
			(xy 62.196477 -6.876792) (xy 62.192406 -6.82117) (xy 60.813947 -6.82117) (xy 60.800125 -6.850656)
			(xy 60.769352 -6.897169) (xy 60.732135 -6.938706) (xy 60.689267 -6.974381) (xy 60.641661 -7.003435)
			(xy 60.590332 -7.025247) (xy 60.536375 -7.039353) (xy 60.480938 -7.045453) (xy 60.425204 -7.043416)
			(xy 60.370361 -7.033286) (xy 60.317577 -7.015279) (xy 60.267977 -6.989778) (xy 60.222619 -6.957327)
			(xy 60.18247 -6.918618) (xy 60.148384 -6.874475) (xy 60.121088 -6.82584) (xy 60.101165 -6.773749)
			(xy 60.089039 -6.719312) (xy 60.084968 -6.66369) (xy 59.333892 -6.66369) (xy 59.333892 -7.20471)
			(xy 62.989966 -7.20471) (xy 62.994037 -7.149088) (xy 63.006163 -7.094651) (xy 63.026086 -7.04256)
			(xy 63.053382 -6.993925) (xy 63.087468 -6.949782) (xy 63.127617 -6.911073) (xy 63.172975 -6.878622)
			(xy 63.222575 -6.853121) (xy 63.275359 -6.835114) (xy 63.330202 -6.824984) (xy 63.385936 -6.822947)
			(xy 63.441373 -6.829047) (xy 63.49533 -6.843153) (xy 63.546659 -6.864965) (xy 63.594265 -6.894019)
			(xy 63.637133 -6.929694) (xy 63.67435 -6.971231) (xy 63.705123 -7.017744) (xy 63.728795 -7.068241)
			(xy 63.744863 -7.121648) (xy 63.752983 -7.176824) (xy 63.753492 -7.20471) (xy 63.878966 -7.20471)
			(xy 63.883037 -7.149088) (xy 63.895163 -7.094651) (xy 63.915086 -7.04256) (xy 63.942382 -6.993925)
			(xy 63.976468 -6.949782) (xy 64.016617 -6.911073) (xy 64.061975 -6.878622) (xy 64.111575 -6.853121)
			(xy 64.164359 -6.835114) (xy 64.219202 -6.824984) (xy 64.274936 -6.822947) (xy 64.330373 -6.829047)
			(xy 64.38433 -6.843153) (xy 64.435659 -6.864965) (xy 64.483265 -6.894019) (xy 64.526133 -6.929694)
			(xy 64.56335 -6.971231) (xy 64.594123 -7.017744) (xy 64.617795 -7.068241) (xy 64.633863 -7.121648)
			(xy 64.641983 -7.176824) (xy 64.642492 -7.20471) (xy 64.767966 -7.20471) (xy 64.772037 -7.149088)
			(xy 64.784163 -7.094651) (xy 64.804086 -7.04256) (xy 64.831382 -6.993925) (xy 64.865468 -6.949782)
			(xy 64.905617 -6.911073) (xy 64.950975 -6.878622) (xy 65.000575 -6.853121) (xy 65.053359 -6.835114)
			(xy 65.108202 -6.824984) (xy 65.163936 -6.822947) (xy 65.219373 -6.829047) (xy 65.27333 -6.843153)
			(xy 65.324659 -6.864965) (xy 65.372265 -6.894019) (xy 65.415133 -6.929694) (xy 65.45235 -6.971231)
			(xy 65.483123 -7.017744) (xy 65.506795 -7.068241) (xy 65.522863 -7.121648) (xy 65.530983 -7.176824)
			(xy 65.531492 -7.20471) (xy 65.656966 -7.20471) (xy 65.661037 -7.149088) (xy 65.673163 -7.094651)
			(xy 65.693086 -7.04256) (xy 65.720382 -6.993925) (xy 65.754468 -6.949782) (xy 65.794617 -6.911073)
			(xy 65.839975 -6.878622) (xy 65.889575 -6.853121) (xy 65.942359 -6.835114) (xy 65.997202 -6.824984)
			(xy 66.052936 -6.822947) (xy 66.108373 -6.829047) (xy 66.16233 -6.843153) (xy 66.213659 -6.864965)
			(xy 66.261265 -6.894019) (xy 66.304133 -6.929694) (xy 66.306424 -6.932251) (xy 68.858368 -6.932251)
			(xy 68.858368 -6.877749) (xy 68.866124 -6.823801) (xy 68.881479 -6.771506) (xy 68.904119 -6.721929)
			(xy 68.933585 -6.676078) (xy 68.969276 -6.634887) (xy 69.010465 -6.599195) (xy 69.056315 -6.569727)
			(xy 69.105891 -6.547084) (xy 69.158185 -6.531727) (xy 69.212133 -6.523969) (xy 69.239384 -6.523482)
			(xy 69.268171 -6.524017) (xy 69.32509 -6.532665) (xy 69.380064 -6.549768) (xy 69.431844 -6.574938)
			(xy 69.479255 -6.607602) (xy 69.521218 -6.647018) (xy 69.556783 -6.692293) (xy 69.585141 -6.742398)
			(xy 69.605648 -6.796195) (xy 69.612256 -6.824218) (xy 69.614542 -6.83514) (xy 69.627496 -6.852412)
			(xy 69.714618 -6.900164) (xy 69.736208 -6.901688) (xy 69.746876 -6.897878) (xy 69.778891 -6.886763)
			(xy 69.845583 -6.874756) (xy 69.879464 -6.874002) (xy 69.906719 -6.874442) (xy 69.960676 -6.882195)
			(xy 70.012979 -6.897549) (xy 70.062565 -6.92019) (xy 70.108424 -6.949658) (xy 70.149622 -6.985352)
			(xy 70.185321 -7.026547) (xy 70.214793 -7.072403) (xy 70.237439 -7.121987) (xy 70.252797 -7.174289)
			(xy 70.254749 -7.187866) (xy 70.479701 -7.187866) (xy 70.487455 -7.133923) (xy 70.502806 -7.081633)
			(xy 70.525442 -7.032059) (xy 70.554903 -6.986211) (xy 70.590588 -6.945023) (xy 70.631772 -6.909332)
			(xy 70.677616 -6.879865) (xy 70.727187 -6.857223) (xy 70.779476 -6.841865) (xy 70.833417 -6.834105)
			(xy 70.860666 -6.833616) (xy 70.867524 -6.833616) (xy 70.879716 -6.83387) (xy 70.90156 -6.823202)
			(xy 70.965822 -6.737604) (xy 70.969886 -6.713474) (xy 70.966076 -6.70179) (xy 70.957965 -6.673916)
			(xy 70.94929 -6.616516) (xy 70.948804 -6.58749) (xy 70.949314 -6.560233) (xy 70.95707 -6.506275)
			(xy 70.972422 -6.453968) (xy 70.995058 -6.404377) (xy 71.024518 -6.35851) (xy 71.060203 -6.3173)
			(xy 71.101387 -6.281585) (xy 71.147233 -6.252092) (xy 71.196807 -6.229419) (xy 71.249103 -6.214029)
			(xy 71.303056 -6.206234) (xy 71.330312 -6.205728) (xy 72.13473 -6.205728) (xy 72.144977 -6.205257)
			(xy 72.163852 -6.197279) (xy 72.171306 -6.190234) (xy 72.229218 -6.13029) (xy 72.236584 -6.110986)
			(xy 72.23633 -6.100572) (xy 72.236076 -6.08711) (xy 72.236562 -6.059859) (xy 72.244318 -6.005911)
			(xy 72.259673 -5.953616) (xy 72.282315 -5.904039) (xy 72.311781 -5.858189) (xy 72.347472 -5.816998)
			(xy 72.388663 -5.781307) (xy 72.434513 -5.751841) (xy 72.48409 -5.729199) (xy 72.536385 -5.713844)
			(xy 72.590333 -5.706088) (xy 72.644835 -5.706088) (xy 72.698783 -5.713844) (xy 72.751078 -5.729199)
			(xy 72.800655 -5.751841) (xy 72.846505 -5.781307) (xy 72.887696 -5.816998) (xy 72.923387 -5.858189)
			(xy 72.952853 -5.904039) (xy 72.975495 -5.953616) (xy 72.99085 -6.005911) (xy 72.998606 -6.059859)
			(xy 72.999092 -6.08711) (xy 72.998606 -6.114749) (xy 72.990653 -6.169453) (xy 72.974886 -6.222435)
			(xy 72.951635 -6.272586) (xy 72.921387 -6.318854) (xy 72.884776 -6.360271) (xy 72.84257 -6.395969)
			(xy 72.795652 -6.4252) (xy 72.745006 -6.447351) (xy 72.691692 -6.461958) (xy 72.66432 -6.465824)
			(xy 72.654668 -6.46684) (xy 72.637904 -6.475984) (xy 72.581008 -6.543294) (xy 72.574658 -6.561328)
			(xy 72.575166 -6.57098) (xy 72.57542 -6.58749) (xy 72.574939 -6.616517) (xy 72.566268 -6.673918)
			(xy 72.559628 -6.69671) (xy 74.679046 -6.69671) (xy 74.683117 -6.641088) (xy 74.695243 -6.586651)
			(xy 74.715166 -6.53456) (xy 74.742462 -6.485925) (xy 74.776548 -6.441782) (xy 74.816697 -6.403073)
			(xy 74.862055 -6.370622) (xy 74.911655 -6.345121) (xy 74.964439 -6.327114) (xy 75.019282 -6.316984)
			(xy 75.075016 -6.314947) (xy 75.130453 -6.321047) (xy 75.18441 -6.335153) (xy 75.235739 -6.356965)
			(xy 75.283345 -6.386019) (xy 75.326213 -6.421694) (xy 75.36343 -6.463231) (xy 75.394203 -6.509744)
			(xy 75.417875 -6.560241) (xy 75.433943 -6.613648) (xy 75.442063 -6.668824) (xy 75.442572 -6.69671)
			(xy 75.442063 -6.724596) (xy 75.433943 -6.779772) (xy 75.417875 -6.833179) (xy 75.394203 -6.883676)
			(xy 75.36343 -6.930189) (xy 75.326213 -6.971726) (xy 75.283345 -7.007401) (xy 75.235739 -7.036455)
			(xy 75.18441 -7.058267) (xy 75.130453 -7.072373) (xy 75.075016 -7.078473) (xy 75.019282 -7.076436)
			(xy 74.964439 -7.066306) (xy 74.911655 -7.048299) (xy 74.862055 -7.022798) (xy 74.816697 -6.990347)
			(xy 74.776548 -6.951638) (xy 74.742462 -6.907495) (xy 74.715166 -6.85886) (xy 74.695243 -6.806769)
			(xy 74.683117 -6.752332) (xy 74.679046 -6.69671) (xy 72.559628 -6.69671) (xy 72.558148 -6.70179)
			(xy 72.554338 -6.713474) (xy 72.558402 -6.737096) (xy 72.622156 -6.823202) (xy 72.643746 -6.83387)
			(xy 72.656192 -6.833616) (xy 72.660764 -6.833616) (xy 72.68802 -6.834016) (xy 72.741977 -6.841769)
			(xy 72.794281 -6.857122) (xy 72.843869 -6.879762) (xy 72.889729 -6.909229) (xy 72.930929 -6.944923)
			(xy 72.96663 -6.986116) (xy 72.996105 -7.031972) (xy 73.018754 -7.081555) (xy 73.034116 -7.133857)
			(xy 73.041879 -7.187812) (xy 73.04188 -7.20471) (xy 73.479912 -7.20471) (xy 73.483983 -7.149088)
			(xy 73.496109 -7.094651) (xy 73.516032 -7.04256) (xy 73.543328 -6.993925) (xy 73.577414 -6.949782)
			(xy 73.617563 -6.911073) (xy 73.662921 -6.878622) (xy 73.712521 -6.853121) (xy 73.765305 -6.835114)
			(xy 73.820148 -6.824984) (xy 73.875882 -6.822947) (xy 73.931319 -6.829047) (xy 73.985276 -6.843153)
			(xy 74.036605 -6.864965) (xy 74.084211 -6.894019) (xy 74.127079 -6.929694) (xy 74.164296 -6.971231)
			(xy 74.195069 -7.017744) (xy 74.218741 -7.068241) (xy 74.234809 -7.121648) (xy 74.242929 -7.176824)
			(xy 74.243438 -7.20471) (xy 74.242929 -7.232596) (xy 74.234809 -7.287772) (xy 74.218741 -7.341179)
			(xy 74.195069 -7.391676) (xy 74.164296 -7.438189) (xy 74.127079 -7.479726) (xy 74.084211 -7.515401)
			(xy 74.036605 -7.544455) (xy 73.985276 -7.566267) (xy 73.931319 -7.580373) (xy 73.875882 -7.586473)
			(xy 73.820148 -7.584436) (xy 73.765305 -7.574306) (xy 73.712521 -7.556299) (xy 73.662921 -7.530798)
			(xy 73.617563 -7.498347) (xy 73.577414 -7.459638) (xy 73.543328 -7.415495) (xy 73.516032 -7.36686)
			(xy 73.496109 -7.314769) (xy 73.483983 -7.260332) (xy 73.479912 -7.20471) (xy 73.04188 -7.20471)
			(xy 73.041883 -7.242324) (xy 73.03413 -7.296281) (xy 73.018777 -7.348585) (xy 72.996136 -7.398172)
			(xy 72.966669 -7.444032) (xy 72.930975 -7.485232) (xy 72.88978 -7.520933) (xy 72.843925 -7.550407)
			(xy 72.794341 -7.573056) (xy 72.742039 -7.588417) (xy 72.688084 -7.596179) (xy 72.633572 -7.596183)
			(xy 72.579615 -7.588429) (xy 72.527311 -7.573075) (xy 72.477724 -7.550434) (xy 72.431864 -7.520966)
			(xy 72.390665 -7.485272) (xy 72.354965 -7.444077) (xy 72.325491 -7.398221) (xy 72.302843 -7.348638)
			(xy 72.287482 -7.296336) (xy 72.279721 -7.24238) (xy 72.279256 -7.215124) (xy 72.279812 -7.186152)
			(xy 72.288615 -7.12888) (xy 72.296782 -7.101078) (xy 72.300338 -7.08914) (xy 72.296528 -7.065518)
			(xy 72.23252 -6.979666) (xy 72.21093 -6.968998) (xy 72.198484 -6.968998) (xy 72.193912 -6.969252)
			(xy 71.330312 -6.969252) (xy 71.323454 -6.968998) (xy 71.311262 -6.968744) (xy 71.289164 -6.979666)
			(xy 71.225156 -7.065264) (xy 71.221092 -7.089394) (xy 71.224648 -7.101078) (xy 71.23281 -7.128882)
			(xy 71.241614 -7.186153) (xy 71.242174 -7.215124) (xy 71.241696 -7.242373) (xy 71.233937 -7.296315)
			(xy 71.218581 -7.348604) (xy 71.195939 -7.398175) (xy 71.166474 -7.44402) (xy 71.130784 -7.485204)
			(xy 71.089597 -7.520891) (xy 71.04375 -7.550353) (xy 70.994177 -7.572991) (xy 70.941887 -7.588343)
			(xy 70.887944 -7.596098) (xy 70.833447 -7.596098) (xy 70.779504 -7.588341) (xy 70.727215 -7.572988)
			(xy 70.677642 -7.550349) (xy 70.631796 -7.520885) (xy 70.590609 -7.485198) (xy 70.554921 -7.444012)
			(xy 70.525456 -7.398167) (xy 70.502816 -7.348595) (xy 70.487461 -7.296306) (xy 70.479703 -7.242363)
			(xy 70.479701 -7.187866) (xy 70.254749 -7.187866) (xy 70.260555 -7.228245) (xy 70.260555 -7.282755)
			(xy 70.252797 -7.336711) (xy 70.237439 -7.389013) (xy 70.214793 -7.438597) (xy 70.185321 -7.484453)
			(xy 70.149622 -7.525648) (xy 70.108424 -7.561342) (xy 70.062565 -7.59081) (xy 70.012979 -7.613451)
			(xy 69.960676 -7.628805) (xy 69.906719 -7.636558) (xy 69.879464 -7.637018) (xy 69.850679 -7.63644)
			(xy 69.793761 -7.627798) (xy 69.738788 -7.610702) (xy 69.687008 -7.585539) (xy 69.639598 -7.55288)
			(xy 69.597633 -7.513468) (xy 69.562067 -7.468198) (xy 69.533709 -7.418097) (xy 69.5132 -7.364303)
			(xy 69.506592 -7.336282) (xy 69.504306 -7.32536) (xy 69.491352 -7.308088) (xy 69.40423 -7.260336)
			(xy 69.38264 -7.258812) (xy 69.371972 -7.262622) (xy 69.339953 -7.273725) (xy 69.273265 -7.285739)
			(xy 69.239384 -7.286498) (xy 69.212133 -7.286031) (xy 69.158185 -7.278273) (xy 69.105891 -7.262916)
			(xy 69.056315 -7.240273) (xy 69.010465 -7.210805) (xy 68.969276 -7.175113) (xy 68.933585 -7.133922)
			(xy 68.904119 -7.088071) (xy 68.881479 -7.038494) (xy 68.866124 -6.986199) (xy 68.858368 -6.932251)
			(xy 66.306424 -6.932251) (xy 66.34135 -6.971231) (xy 66.372123 -7.017744) (xy 66.395795 -7.068241)
			(xy 66.411863 -7.121648) (xy 66.419983 -7.176824) (xy 66.420492 -7.20471) (xy 66.419983 -7.232596)
			(xy 66.411863 -7.287772) (xy 66.395795 -7.341179) (xy 66.372123 -7.391676) (xy 66.34135 -7.438189)
			(xy 66.304133 -7.479726) (xy 66.261265 -7.515401) (xy 66.213659 -7.544455) (xy 66.16233 -7.566267)
			(xy 66.108373 -7.580373) (xy 66.052936 -7.586473) (xy 65.997202 -7.584436) (xy 65.942359 -7.574306)
			(xy 65.889575 -7.556299) (xy 65.839975 -7.530798) (xy 65.794617 -7.498347) (xy 65.754468 -7.459638)
			(xy 65.720382 -7.415495) (xy 65.693086 -7.36686) (xy 65.673163 -7.314769) (xy 65.661037 -7.260332)
			(xy 65.656966 -7.20471) (xy 65.531492 -7.20471) (xy 65.530983 -7.232596) (xy 65.522863 -7.287772)
			(xy 65.506795 -7.341179) (xy 65.483123 -7.391676) (xy 65.45235 -7.438189) (xy 65.415133 -7.479726)
			(xy 65.372265 -7.515401) (xy 65.324659 -7.544455) (xy 65.27333 -7.566267) (xy 65.219373 -7.580373)
			(xy 65.163936 -7.586473) (xy 65.108202 -7.584436) (xy 65.053359 -7.574306) (xy 65.000575 -7.556299)
			(xy 64.950975 -7.530798) (xy 64.905617 -7.498347) (xy 64.865468 -7.459638) (xy 64.831382 -7.415495)
			(xy 64.804086 -7.36686) (xy 64.784163 -7.314769) (xy 64.772037 -7.260332) (xy 64.767966 -7.20471)
			(xy 64.642492 -7.20471) (xy 64.641983 -7.232596) (xy 64.633863 -7.287772) (xy 64.617795 -7.341179)
			(xy 64.594123 -7.391676) (xy 64.56335 -7.438189) (xy 64.526133 -7.479726) (xy 64.483265 -7.515401)
			(xy 64.435659 -7.544455) (xy 64.38433 -7.566267) (xy 64.330373 -7.580373) (xy 64.274936 -7.586473)
			(xy 64.219202 -7.584436) (xy 64.164359 -7.574306) (xy 64.111575 -7.556299) (xy 64.061975 -7.530798)
			(xy 64.016617 -7.498347) (xy 63.976468 -7.459638) (xy 63.942382 -7.415495) (xy 63.915086 -7.36686)
			(xy 63.895163 -7.314769) (xy 63.883037 -7.260332) (xy 63.878966 -7.20471) (xy 63.753492 -7.20471)
			(xy 63.752983 -7.232596) (xy 63.744863 -7.287772) (xy 63.728795 -7.341179) (xy 63.705123 -7.391676)
			(xy 63.67435 -7.438189) (xy 63.637133 -7.479726) (xy 63.594265 -7.515401) (xy 63.546659 -7.544455)
			(xy 63.49533 -7.566267) (xy 63.441373 -7.580373) (xy 63.385936 -7.586473) (xy 63.330202 -7.584436)
			(xy 63.275359 -7.574306) (xy 63.222575 -7.556299) (xy 63.172975 -7.530798) (xy 63.127617 -7.498347)
			(xy 63.087468 -7.459638) (xy 63.053382 -7.415495) (xy 63.026086 -7.36686) (xy 63.006163 -7.314769)
			(xy 62.994037 -7.260332) (xy 62.989966 -7.20471) (xy 59.333892 -7.20471) (xy 59.333892 -8.824633)
			(xy 66.435226 -8.824633) (xy 66.435226 -8.764867) (xy 66.443364 -8.705657) (xy 66.459489 -8.648107)
			(xy 66.4833 -8.593288) (xy 66.514354 -8.542222) (xy 66.552072 -8.495861) (xy 66.595751 -8.455067)
			(xy 66.644579 -8.420601) (xy 66.697645 -8.393104) (xy 66.75396 -8.373089) (xy 66.812477 -8.36093)
			(xy 66.872104 -8.356851) (xy 66.931731 -8.36093) (xy 66.990248 -8.373089) (xy 67.046563 -8.393104)
			(xy 67.099629 -8.420601) (xy 67.148457 -8.455067) (xy 67.192136 -8.495861) (xy 67.229854 -8.542222)
			(xy 67.260908 -8.593288) (xy 67.284719 -8.648107) (xy 67.300844 -8.705657) (xy 67.308982 -8.764867)
			(xy 67.309492 -8.79475) (xy 67.308982 -8.824633) (xy 67.300844 -8.883843) (xy 67.284719 -8.941393)
			(xy 67.260908 -8.996212) (xy 67.229854 -9.047278) (xy 67.209852 -9.071864) (xy 71.167244 -9.071864)
			(xy 71.167244 -7.672324) (xy 71.167686 -7.660283) (xy 71.175122 -7.637377) (xy 71.189273 -7.617891)
			(xy 71.208754 -7.603733) (xy 71.231657 -7.59629) (xy 71.243698 -7.59587) (xy 72.280272 -7.59587)
			(xy 72.292316 -7.596289) (xy 72.315225 -7.603727) (xy 72.334714 -7.617884) (xy 72.348871 -7.637371)
			(xy 72.35631 -7.66028) (xy 72.356726 -7.672324) (xy 72.356726 -9.071864) (xy 72.356304 -9.083908)
			(xy 72.348868 -9.106818) (xy 72.334712 -9.126307) (xy 72.315225 -9.140464) (xy 72.292316 -9.147903)
			(xy 72.280272 -9.148318) (xy 71.243698 -9.148318) (xy 71.231652 -9.147936) (xy 71.208739 -9.140488)
			(xy 71.18925 -9.126323) (xy 71.175095 -9.106827) (xy 71.167658 -9.083911) (xy 71.167244 -9.071864)
			(xy 67.209852 -9.071864) (xy 67.192136 -9.093639) (xy 67.148457 -9.134433) (xy 67.099629 -9.168899)
			(xy 67.046563 -9.196396) (xy 66.990248 -9.216411) (xy 66.931731 -9.22857) (xy 66.872104 -9.232649)
			(xy 66.812477 -9.22857) (xy 66.75396 -9.216411) (xy 66.697645 -9.196396) (xy 66.644579 -9.168899)
			(xy 66.595751 -9.134433) (xy 66.552072 -9.093639) (xy 66.514354 -9.047278) (xy 66.4833 -8.996212)
			(xy 66.459489 -8.941393) (xy 66.443364 -8.883843) (xy 66.435226 -8.824633) (xy 59.333892 -8.824633)
			(xy 59.333892 -10.20191) (xy 68.603366 -10.20191) (xy 68.607437 -10.146288) (xy 68.619563 -10.091851)
			(xy 68.639486 -10.03976) (xy 68.666782 -9.991125) (xy 68.700868 -9.946982) (xy 68.741017 -9.908273)
			(xy 68.786375 -9.875822) (xy 68.835975 -9.850321) (xy 68.888759 -9.832314) (xy 68.943602 -9.822184)
			(xy 68.999336 -9.820147) (xy 69.054773 -9.826247) (xy 69.10873 -9.840353) (xy 69.160059 -9.862165)
			(xy 69.207665 -9.891219) (xy 69.250533 -9.926894) (xy 69.28775 -9.968431) (xy 69.318523 -10.014944)
			(xy 69.342195 -10.065441) (xy 69.358263 -10.118848) (xy 69.365067 -10.16508) (xy 72.443846 -10.16508)
			(xy 72.447917 -10.109458) (xy 72.460043 -10.055021) (xy 72.479966 -10.00293) (xy 72.507262 -9.954295)
			(xy 72.541348 -9.910152) (xy 72.581497 -9.871443) (xy 72.626855 -9.838992) (xy 72.676455 -9.813491)
			(xy 72.729239 -9.795484) (xy 72.784082 -9.785354) (xy 72.839816 -9.783317) (xy 72.895253 -9.789417)
			(xy 72.94921 -9.803523) (xy 73.000539 -9.825335) (xy 73.048145 -9.854389) (xy 73.091013 -9.890064)
			(xy 73.12823 -9.931601) (xy 73.159003 -9.978114) (xy 73.182675 -10.028611) (xy 73.198743 -10.082018)
			(xy 73.206863 -10.137194) (xy 73.207372 -10.16508) (xy 73.206863 -10.192966) (xy 73.198743 -10.248142)
			(xy 73.182675 -10.301549) (xy 73.159003 -10.352046) (xy 73.12823 -10.398559) (xy 73.091013 -10.440096)
			(xy 73.048145 -10.475771) (xy 73.000539 -10.504825) (xy 72.94921 -10.526637) (xy 72.895253 -10.540743)
			(xy 72.839816 -10.546843) (xy 72.784082 -10.544806) (xy 72.729239 -10.534676) (xy 72.676455 -10.516669)
			(xy 72.626855 -10.491168) (xy 72.581497 -10.458717) (xy 72.541348 -10.420008) (xy 72.507262 -10.375865)
			(xy 72.479966 -10.32723) (xy 72.460043 -10.275139) (xy 72.447917 -10.220702) (xy 72.443846 -10.16508)
			(xy 69.365067 -10.16508) (xy 69.366383 -10.174024) (xy 69.366892 -10.20191) (xy 69.366383 -10.229796)
			(xy 69.358263 -10.284972) (xy 69.342195 -10.338379) (xy 69.318523 -10.388876) (xy 69.28775 -10.435389)
			(xy 69.250533 -10.476926) (xy 69.207665 -10.512601) (xy 69.160059 -10.541655) (xy 69.10873 -10.563467)
			(xy 69.054773 -10.577573) (xy 68.999336 -10.583673) (xy 68.943602 -10.581636) (xy 68.888759 -10.571506)
			(xy 68.835975 -10.553499) (xy 68.786375 -10.527998) (xy 68.741017 -10.495547) (xy 68.700868 -10.456838)
			(xy 68.666782 -10.412695) (xy 68.639486 -10.36406) (xy 68.619563 -10.311969) (xy 68.607437 -10.257532)
			(xy 68.603366 -10.20191) (xy 59.333892 -10.20191) (xy 59.333892 -10.533126) (xy 59.334319 -10.543194)
			(xy 59.34204 -10.561793) (xy 59.348878 -10.569194) (xy 59.521344 -10.74166) (xy 59.528743 -10.748504)
			(xy 59.547342 -10.756228) (xy 59.557412 -10.756646) (xy 71.167244 -10.756646)
		)
		(stroke
			(width 0)
			(type solid)
		)
		(fill yes)
		(layer "In2.Cu")
		(net "P3V3_OCP_V3_2")
	)
	(gr_poly
		(pts
			(xy 101.525832 -256.861564) (xy 101.537903 -256.860897) (xy 101.559387 -256.84989) (xy 101.56698 -256.840482)
			(xy 101.621082 -256.765552) (xy 101.624892 -256.741422) (xy 101.621082 -256.729738) (xy 101.613966 -256.706571)
			(xy 101.606314 -256.658718) (xy 101.605842 -256.634488) (xy 101.606364 -256.609233) (xy 101.614677 -256.559411)
			(xy 101.631078 -256.511637) (xy 101.655119 -256.467214) (xy 101.686143 -256.427354) (xy 101.723305 -256.393144)
			(xy 101.765591 -256.365518) (xy 101.811847 -256.345228) (xy 101.860812 -256.332828) (xy 101.91115 -256.328657)
			(xy 101.961488 -256.332828) (xy 102.010453 -256.345228) (xy 102.056709 -256.365518) (xy 102.098995 -256.393144)
			(xy 102.136157 -256.427354) (xy 102.167181 -256.467214) (xy 102.191222 -256.511637) (xy 102.207623 -256.559411)
			(xy 102.215936 -256.609233) (xy 102.216458 -256.634488) (xy 102.215994 -256.658719) (xy 102.208339 -256.706572)
			(xy 102.201218 -256.729738) (xy 102.197408 -256.741422) (xy 102.201218 -256.765552) (xy 102.25532 -256.840482)
			(xy 102.262932 -256.849865) (xy 102.284406 -256.860865) (xy 102.296468 -256.861564) (xy 102.465632 -256.861564)
			(xy 102.477703 -256.860897) (xy 102.499187 -256.84989) (xy 102.50678 -256.840482) (xy 102.560882 -256.765298)
			(xy 102.564692 -256.741168) (xy 102.560882 -256.729484) (xy 102.553566 -256.706026) (xy 102.545661 -256.657531)
			(xy 102.545134 -256.632964) (xy 102.545656 -256.607709) (xy 102.553969 -256.557887) (xy 102.57037 -256.510113)
			(xy 102.594411 -256.46569) (xy 102.625435 -256.42583) (xy 102.662597 -256.39162) (xy 102.704883 -256.363994)
			(xy 102.751139 -256.343704) (xy 102.800104 -256.331304) (xy 102.850442 -256.327133) (xy 102.90078 -256.331304)
			(xy 102.949745 -256.343704) (xy 102.996001 -256.363994) (xy 103.038287 -256.39162) (xy 103.075449 -256.42583)
			(xy 103.106473 -256.46569) (xy 103.130514 -256.510113) (xy 103.146915 -256.557887) (xy 103.155228 -256.607709)
			(xy 103.15575 -256.632964) (xy 103.155236 -256.657532) (xy 103.147321 -256.706026) (xy 103.140002 -256.729484)
			(xy 103.136192 -256.741168) (xy 103.140002 -256.765298) (xy 103.194104 -256.840482) (xy 103.201715 -256.849868)
			(xy 103.223189 -256.860875) (xy 103.235252 -256.861564) (xy 105.88371 -256.861564) (xy 105.893554 -256.861041)
			(xy 105.911736 -256.853476) (xy 105.919016 -256.846832) (xy 106.016552 -256.749296) (xy 106.023262 -256.742057)
			(xy 106.030853 -256.723852) (xy 106.031284 -256.71399) (xy 106.031284 -255.739646) (xy 106.030851 -255.729581)
			(xy 106.023121 -255.710992) (xy 106.016298 -255.703578) (xy 103.974392 -253.661672) (xy 103.94188 -253.656592)
			(xy 103.927148 -253.664212) (xy 103.90549 -253.674797) (xy 103.859666 -253.689753) (xy 103.812058 -253.697306)
			(xy 103.787956 -253.69774) (xy 103.782622 -253.69774) (xy 103.756564 -253.696752) (xy 103.705343 -253.686994)
			(xy 103.656522 -253.668682) (xy 103.611519 -253.642345) (xy 103.571642 -253.60875) (xy 103.538048 -253.568871)
			(xy 103.511713 -253.523867) (xy 103.493402 -253.475046) (xy 103.483647 -253.423824) (xy 103.482648 -253.397766)
			(xy 103.482648 -253.393956) (xy 103.482648 -253.392432) (xy 103.483104 -253.368332) (xy 103.49067 -253.32073)
			(xy 103.505604 -253.274902) (xy 103.516176 -253.25324) (xy 103.523796 -253.238508) (xy 103.518716 -253.205996)
			(xy 102.856538 -252.543818) (xy 102.849367 -252.537191) (xy 102.831452 -252.529471) (xy 102.811949 -252.529042)
			(xy 102.80269 -252.532134) (xy 102.704392 -252.56871) (xy 102.686612 -252.592078) (xy 102.685596 -252.607064)
			(xy 102.683214 -252.632364) (xy 102.671118 -252.681716) (xy 102.651016 -252.728384) (xy 102.623463 -252.771079)
			(xy 102.589221 -252.808622) (xy 102.549234 -252.839976) (xy 102.504607 -252.864275) (xy 102.456573 -252.880848)
			(xy 102.406457 -252.889238) (xy 102.38105 -252.889766) (xy 102.357063 -252.889292) (xy 102.309679 -252.881779)
			(xy 102.264055 -252.866947) (xy 102.221312 -252.84516) (xy 102.182504 -252.816955) (xy 102.148585 -252.783026)
			(xy 102.120392 -252.744209) (xy 102.098618 -252.70146) (xy 102.083799 -252.655831) (xy 102.076301 -252.608446)
			(xy 102.075742 -252.584458) (xy 102.07625 -252.559053) (xy 102.084664 -252.508945) (xy 102.101254 -252.460919)
			(xy 102.125561 -252.416301) (xy 102.156917 -252.376319) (xy 102.194456 -252.342078) (xy 102.237143 -252.314519)
			(xy 102.283802 -252.294404) (xy 102.333146 -252.282287) (xy 102.358444 -252.279912) (xy 102.37343 -252.278896)
			(xy 102.396798 -252.261116) (xy 102.433374 -252.162818) (xy 102.43637 -252.153543) (xy 102.435912 -252.134074)
			(xy 102.428268 -252.116161) (xy 102.42169 -252.10897) (xy 102.285546 -251.972826) (xy 102.277826 -251.965767)
			(xy 102.258414 -251.958027) (xy 102.247954 -251.95784) (xy 102.165404 -251.96038) (xy 102.146608 -251.969016)
			(xy 102.139496 -251.977144) (xy 102.121958 -251.996089) (xy 102.081684 -252.028382) (xy 102.036552 -252.05344)
			(xy 101.987849 -252.070551) (xy 101.936961 -252.079225) (xy 101.91115 -252.07976) (xy 101.887163 -252.079286)
			(xy 101.83978 -252.071773) (xy 101.794156 -252.056941) (xy 101.751413 -252.035154) (xy 101.712606 -252.006949)
			(xy 101.678688 -251.97302) (xy 101.650495 -251.934203) (xy 101.628722 -251.891454) (xy 101.613904 -251.845825)
			(xy 101.606407 -251.798439) (xy 101.605842 -251.774452) (xy 101.605981 -251.761689) (xy 101.608144 -251.736255)
			(xy 101.61016 -251.723652) (xy 101.609906 -251.723652) (xy 101.614757 -251.698184) (xy 101.63188 -251.649254)
			(xy 101.657012 -251.603914) (xy 101.689432 -251.563463) (xy 101.708458 -251.545852) (xy 101.716586 -251.53874)
			(xy 101.725222 -251.520198) (xy 101.727762 -251.437648) (xy 101.727576 -251.427186) (xy 101.719849 -251.407765)
			(xy 101.712776 -251.400056) (xy 101.571552 -251.258832) (xy 101.544374 -251.251974) (xy 101.530658 -251.256292)
			(xy 101.508777 -251.262575) (xy 101.463758 -251.269336) (xy 101.440996 -251.269754) (xy 101.417004 -251.269283)
			(xy 101.36961 -251.261777) (xy 101.323973 -251.24695) (xy 101.281218 -251.225167) (xy 101.242396 -251.196964)
			(xy 101.208463 -251.163036) (xy 101.180255 -251.124218) (xy 101.158466 -251.081466) (xy 101.143633 -251.035831)
			(xy 101.13612 -250.988438) (xy 101.135688 -250.964446) (xy 101.136105 -250.941684) (xy 101.142858 -250.896663)
			(xy 101.14915 -250.874784) (xy 101.153468 -250.861068) (xy 101.14661 -250.83389) (xy 101.05009 -250.73737)
			(xy 101.042694 -250.730518) (xy 101.024095 -250.722776) (xy 101.014022 -250.722384) (xy 100.435918 -250.722384)
			(xy 100.426082 -250.721845) (xy 100.407925 -250.714254) (xy 100.400612 -250.707652) (xy 100.146612 -250.453652)
			(xy 100.120704 -250.44654) (xy 100.107496 -250.450096) (xy 100.08871 -250.454633) (xy 100.050366 -250.459476)
			(xy 100.031042 -250.459748) (xy 100.007046 -250.459305) (xy 99.959643 -250.451804) (xy 99.913997 -250.436979)
			(xy 99.871232 -250.415197) (xy 99.832401 -250.386993) (xy 99.798461 -250.353061) (xy 99.770246 -250.314238)
			(xy 99.748452 -250.271479) (xy 99.733615 -250.225837) (xy 99.726101 -250.178436) (xy 99.725734 -250.15444)
			(xy 99.726014 -250.135116) (xy 99.730851 -250.096772) (xy 99.735386 -250.077986) (xy 99.738942 -250.064778)
			(xy 99.73183 -250.03887) (xy 98.87331 -249.18035) (xy 98.865914 -249.173497) (xy 98.847316 -249.165751)
			(xy 98.837242 -249.165364) (xy 98.079052 -249.165364) (xy 98.067767 -249.165976) (xy 98.047349 -249.175601)
			(xy 98.039682 -249.183906) (xy 97.983802 -249.251978) (xy 97.978214 -249.273822) (xy 97.9805 -249.285252)
			(xy 97.983224 -249.299896) (xy 97.986151 -249.32954) (xy 97.986342 -249.344434) (xy 97.98582 -249.369689)
			(xy 97.977507 -249.419511) (xy 97.961106 -249.467285) (xy 97.937065 -249.511708) (xy 97.906041 -249.551568)
			(xy 97.868879 -249.585778) (xy 97.826593 -249.613404) (xy 97.780337 -249.633694) (xy 97.731372 -249.646094)
			(xy 97.681034 -249.650265) (xy 97.630696 -249.646094) (xy 97.581731 -249.633694) (xy 97.535475 -249.613404)
			(xy 97.493189 -249.585778) (xy 97.456027 -249.551568) (xy 97.425003 -249.511708) (xy 97.400962 -249.467285)
			(xy 97.384561 -249.419511) (xy 97.376248 -249.369689) (xy 97.375726 -249.344434) (xy 97.375918 -249.32954)
			(xy 97.378847 -249.299896) (xy 97.381568 -249.285252) (xy 97.383854 -249.273822) (xy 97.378266 -249.251978)
			(xy 97.322386 -249.183906) (xy 97.314764 -249.175541) (xy 97.29432 -249.165906) (xy 97.283016 -249.165364)
			(xy 96.63176 -249.165364) (xy 96.621919 -249.165894) (xy 96.603747 -249.173469) (xy 96.596454 -249.180096)
			(xy 96.394016 -249.382534) (xy 96.387303 -249.389772) (xy 96.379713 -249.407977) (xy 96.379284 -249.41784)
			(xy 96.379284 -249.850402) (xy 96.39427 -249.874786) (xy 96.407478 -249.881136) (xy 96.428894 -249.892361)
			(xy 96.468191 -249.92053) (xy 96.50256 -249.954537) (xy 96.531145 -249.993532) (xy 96.553232 -250.036543)
			(xy 96.568269 -250.082496) (xy 96.575881 -250.130243) (xy 96.575879 -250.15444) (xy 97.84513 -250.15444)
			(xy 97.84909 -250.105386) (xy 97.860867 -250.057602) (xy 97.880158 -250.012326) (xy 97.906461 -249.97073)
			(xy 97.939096 -249.933893) (xy 97.977217 -249.902768) (xy 98.019838 -249.878161) (xy 98.065854 -249.860709)
			(xy 98.114073 -249.850865) (xy 98.163248 -249.848884) (xy 98.212103 -249.854816) (xy 98.259374 -249.868508)
			(xy 98.303836 -249.889606) (xy 98.344339 -249.917562) (xy 98.379832 -249.951654) (xy 98.409397 -249.990998)
			(xy 98.432268 -250.034575) (xy 98.447852 -250.081256) (xy 98.455747 -250.129833) (xy 98.456242 -250.15444)
			(xy 98.455747 -250.179047) (xy 98.447852 -250.227624) (xy 98.432268 -250.274305) (xy 98.409397 -250.317882)
			(xy 98.379832 -250.357226) (xy 98.344339 -250.391318) (xy 98.303836 -250.419274) (xy 98.259374 -250.440372)
			(xy 98.212103 -250.454064) (xy 98.163248 -250.459996) (xy 98.114073 -250.458015) (xy 98.065854 -250.448171)
			(xy 98.019838 -250.430719) (xy 97.977217 -250.406112) (xy 97.939096 -250.374987) (xy 97.906461 -250.33815)
			(xy 97.880158 -250.296554) (xy 97.860867 -250.251278) (xy 97.84909 -250.203494) (xy 97.84513 -250.15444)
			(xy 96.575879 -250.15444) (xy 96.575878 -250.178593) (xy 96.568261 -250.226339) (xy 96.553218 -250.27229)
			(xy 96.531126 -250.315298) (xy 96.502537 -250.35429) (xy 96.468163 -250.388293) (xy 96.428863 -250.416457)
			(xy 96.407478 -250.427744) (xy 96.39427 -250.434094) (xy 96.379284 -250.458478) (xy 96.379284 -250.964446)
			(xy 97.37523 -250.964446) (xy 97.37919 -250.915392) (xy 97.390967 -250.867608) (xy 97.410258 -250.822332)
			(xy 97.436561 -250.780736) (xy 97.469196 -250.743899) (xy 97.507317 -250.712774) (xy 97.549938 -250.688167)
			(xy 97.595954 -250.670715) (xy 97.644173 -250.660871) (xy 97.693348 -250.65889) (xy 97.742203 -250.664822)
			(xy 97.789474 -250.678514) (xy 97.833936 -250.699612) (xy 97.874439 -250.727568) (xy 97.909932 -250.76166)
			(xy 97.939497 -250.801004) (xy 97.962368 -250.844581) (xy 97.977952 -250.891262) (xy 97.985847 -250.939839)
			(xy 97.986342 -250.964446) (xy 99.255338 -250.964446) (xy 99.259298 -250.915392) (xy 99.271075 -250.867608)
			(xy 99.290366 -250.822332) (xy 99.316669 -250.780736) (xy 99.349304 -250.743899) (xy 99.387425 -250.712774)
			(xy 99.430046 -250.688167) (xy 99.476062 -250.670715) (xy 99.524281 -250.660871) (xy 99.573456 -250.65889)
			(xy 99.622311 -250.664822) (xy 99.669582 -250.678514) (xy 99.714044 -250.699612) (xy 99.754547 -250.727568)
			(xy 99.79004 -250.76166) (xy 99.819605 -250.801004) (xy 99.842476 -250.844581) (xy 99.85806 -250.891262)
			(xy 99.865955 -250.939839) (xy 99.86645 -250.964446) (xy 99.865955 -250.989053) (xy 99.85806 -251.03763)
			(xy 99.842476 -251.084311) (xy 99.819605 -251.127888) (xy 99.79004 -251.167232) (xy 99.754547 -251.201324)
			(xy 99.714044 -251.22928) (xy 99.669582 -251.250378) (xy 99.622311 -251.26407) (xy 99.573456 -251.270002)
			(xy 99.524281 -251.268021) (xy 99.476062 -251.258177) (xy 99.430046 -251.240725) (xy 99.387425 -251.216118)
			(xy 99.349304 -251.184993) (xy 99.316669 -251.148156) (xy 99.290366 -251.10656) (xy 99.271075 -251.061284)
			(xy 99.259298 -251.0135) (xy 99.255338 -250.964446) (xy 97.986342 -250.964446) (xy 97.985847 -250.989053)
			(xy 97.977952 -251.03763) (xy 97.962368 -251.084311) (xy 97.939497 -251.127888) (xy 97.909932 -251.167232)
			(xy 97.874439 -251.201324) (xy 97.833936 -251.22928) (xy 97.789474 -251.250378) (xy 97.742203 -251.26407)
			(xy 97.693348 -251.270002) (xy 97.644173 -251.268021) (xy 97.595954 -251.258177) (xy 97.549938 -251.240725)
			(xy 97.507317 -251.216118) (xy 97.469196 -251.184993) (xy 97.436561 -251.148156) (xy 97.410258 -251.10656)
			(xy 97.390967 -251.061284) (xy 97.37919 -251.0135) (xy 97.37523 -250.964446) (xy 96.379284 -250.964446)
			(xy 96.379284 -251.470414) (xy 96.39427 -251.494798) (xy 96.407478 -251.501148) (xy 96.428901 -251.512373)
			(xy 96.468211 -251.540545) (xy 96.502594 -251.574556) (xy 96.531192 -251.613558) (xy 96.553289 -251.656576)
			(xy 96.568336 -251.702539) (xy 96.575956 -251.750297) (xy 96.575958 -251.774452) (xy 97.84513 -251.774452)
			(xy 97.84909 -251.725398) (xy 97.860867 -251.677614) (xy 97.880158 -251.632338) (xy 97.906461 -251.590742)
			(xy 97.939096 -251.553905) (xy 97.977217 -251.52278) (xy 98.019838 -251.498173) (xy 98.065854 -251.480721)
			(xy 98.114073 -251.470877) (xy 98.163248 -251.468896) (xy 98.212103 -251.474828) (xy 98.259374 -251.48852)
			(xy 98.303836 -251.509618) (xy 98.344339 -251.537574) (xy 98.379832 -251.571666) (xy 98.409397 -251.61101)
			(xy 98.432268 -251.654587) (xy 98.447852 -251.701268) (xy 98.455747 -251.749845) (xy 98.456242 -251.774452)
			(xy 99.725238 -251.774452) (xy 99.729198 -251.725398) (xy 99.740975 -251.677614) (xy 99.760266 -251.632338)
			(xy 99.786569 -251.590742) (xy 99.819204 -251.553905) (xy 99.857325 -251.52278) (xy 99.899946 -251.498173)
			(xy 99.945962 -251.480721) (xy 99.994181 -251.470877) (xy 100.043356 -251.468896) (xy 100.092211 -251.474828)
			(xy 100.139482 -251.48852) (xy 100.183944 -251.509618) (xy 100.224447 -251.537574) (xy 100.25994 -251.571666)
			(xy 100.289505 -251.61101) (xy 100.312376 -251.654587) (xy 100.32796 -251.701268) (xy 100.335855 -251.749845)
			(xy 100.33635 -251.774452) (xy 100.335855 -251.799059) (xy 100.32796 -251.847636) (xy 100.312376 -251.894317)
			(xy 100.289505 -251.937894) (xy 100.25994 -251.977238) (xy 100.224447 -252.01133) (xy 100.183944 -252.039286)
			(xy 100.139482 -252.060384) (xy 100.092211 -252.074076) (xy 100.043356 -252.080008) (xy 99.994181 -252.078027)
			(xy 99.945962 -252.068183) (xy 99.899946 -252.050731) (xy 99.857325 -252.026124) (xy 99.819204 -251.994999)
			(xy 99.786569 -251.958162) (xy 99.760266 -251.916566) (xy 99.740975 -251.87129) (xy 99.729198 -251.823506)
			(xy 99.725238 -251.774452) (xy 98.456242 -251.774452) (xy 98.455747 -251.799059) (xy 98.447852 -251.847636)
			(xy 98.432268 -251.894317) (xy 98.409397 -251.937894) (xy 98.379832 -251.977238) (xy 98.344339 -252.01133)
			(xy 98.303836 -252.039286) (xy 98.259374 -252.060384) (xy 98.212103 -252.074076) (xy 98.163248 -252.080008)
			(xy 98.114073 -252.078027) (xy 98.065854 -252.068183) (xy 98.019838 -252.050731) (xy 97.977217 -252.026124)
			(xy 97.939096 -251.994999) (xy 97.906461 -251.958162) (xy 97.880158 -251.916566) (xy 97.860867 -251.87129)
			(xy 97.84909 -251.823506) (xy 97.84513 -251.774452) (xy 96.575958 -251.774452) (xy 96.57596 -251.79866)
			(xy 96.568346 -251.846419) (xy 96.553306 -251.892384) (xy 96.531214 -251.935406) (xy 96.502622 -251.974412)
			(xy 96.468244 -252.008427) (xy 96.428938 -252.036604) (xy 96.407478 -252.047756) (xy 96.39427 -252.054106)
			(xy 96.379284 -252.07849) (xy 96.379284 -252.584458) (xy 97.37523 -252.584458) (xy 97.37919 -252.535404)
			(xy 97.390967 -252.48762) (xy 97.410258 -252.442344) (xy 97.436561 -252.400748) (xy 97.469196 -252.363911)
			(xy 97.507317 -252.332786) (xy 97.549938 -252.308179) (xy 97.595954 -252.290727) (xy 97.644173 -252.280883)
			(xy 97.693348 -252.278902) (xy 97.742203 -252.284834) (xy 97.789474 -252.298526) (xy 97.833936 -252.319624)
			(xy 97.874439 -252.34758) (xy 97.909932 -252.381672) (xy 97.939497 -252.421016) (xy 97.962368 -252.464593)
			(xy 97.977952 -252.511274) (xy 97.985847 -252.559851) (xy 97.986342 -252.584458) (xy 99.255338 -252.584458)
			(xy 99.259298 -252.535404) (xy 99.271075 -252.48762) (xy 99.290366 -252.442344) (xy 99.316669 -252.400748)
			(xy 99.349304 -252.363911) (xy 99.387425 -252.332786) (xy 99.430046 -252.308179) (xy 99.476062 -252.290727)
			(xy 99.524281 -252.280883) (xy 99.573456 -252.278902) (xy 99.622311 -252.284834) (xy 99.669582 -252.298526)
			(xy 99.714044 -252.319624) (xy 99.754547 -252.34758) (xy 99.79004 -252.381672) (xy 99.819605 -252.421016)
			(xy 99.842476 -252.464593) (xy 99.85806 -252.511274) (xy 99.865955 -252.559851) (xy 99.86645 -252.584458)
			(xy 101.135192 -252.584458) (xy 101.139152 -252.535404) (xy 101.150929 -252.48762) (xy 101.17022 -252.442344)
			(xy 101.196523 -252.400748) (xy 101.229158 -252.363911) (xy 101.267279 -252.332786) (xy 101.3099 -252.308179)
			(xy 101.355916 -252.290727) (xy 101.404135 -252.280883) (xy 101.45331 -252.278902) (xy 101.502165 -252.284834)
			(xy 101.549436 -252.298526) (xy 101.593898 -252.319624) (xy 101.634401 -252.34758) (xy 101.669894 -252.381672)
			(xy 101.699459 -252.421016) (xy 101.72233 -252.464593) (xy 101.737914 -252.511274) (xy 101.745809 -252.559851)
			(xy 101.746304 -252.584458) (xy 101.745809 -252.609065) (xy 101.737914 -252.657642) (xy 101.72233 -252.704323)
			(xy 101.699459 -252.7479) (xy 101.669894 -252.787244) (xy 101.634401 -252.821336) (xy 101.593898 -252.849292)
			(xy 101.549436 -252.87039) (xy 101.502165 -252.884082) (xy 101.45331 -252.890014) (xy 101.404135 -252.888033)
			(xy 101.355916 -252.878189) (xy 101.3099 -252.860737) (xy 101.267279 -252.83613) (xy 101.229158 -252.805005)
			(xy 101.196523 -252.768168) (xy 101.17022 -252.726572) (xy 101.150929 -252.681296) (xy 101.139152 -252.633512)
			(xy 101.135192 -252.584458) (xy 99.86645 -252.584458) (xy 99.865955 -252.609065) (xy 99.85806 -252.657642)
			(xy 99.842476 -252.704323) (xy 99.819605 -252.7479) (xy 99.79004 -252.787244) (xy 99.754547 -252.821336)
			(xy 99.714044 -252.849292) (xy 99.669582 -252.87039) (xy 99.622311 -252.884082) (xy 99.573456 -252.890014)
			(xy 99.524281 -252.888033) (xy 99.476062 -252.878189) (xy 99.430046 -252.860737) (xy 99.387425 -252.83613)
			(xy 99.349304 -252.805005) (xy 99.316669 -252.768168) (xy 99.290366 -252.726572) (xy 99.271075 -252.681296)
			(xy 99.259298 -252.633512) (xy 99.255338 -252.584458) (xy 97.986342 -252.584458) (xy 97.985847 -252.609065)
			(xy 97.977952 -252.657642) (xy 97.962368 -252.704323) (xy 97.939497 -252.7479) (xy 97.909932 -252.787244)
			(xy 97.874439 -252.821336) (xy 97.833936 -252.849292) (xy 97.789474 -252.87039) (xy 97.742203 -252.884082)
			(xy 97.693348 -252.890014) (xy 97.644173 -252.888033) (xy 97.595954 -252.878189) (xy 97.549938 -252.860737)
			(xy 97.507317 -252.83613) (xy 97.469196 -252.805005) (xy 97.436561 -252.768168) (xy 97.410258 -252.726572)
			(xy 97.390967 -252.681296) (xy 97.37919 -252.633512) (xy 97.37523 -252.584458) (xy 96.379284 -252.584458)
			(xy 96.379284 -253.090426) (xy 96.39427 -253.11481) (xy 96.407478 -253.12116) (xy 96.4289 -253.132385)
			(xy 96.468208 -253.160556) (xy 96.50259 -253.194567) (xy 96.531185 -253.233568) (xy 96.553282 -253.276586)
			(xy 96.568327 -253.322547) (xy 96.575946 -253.370303) (xy 96.575947 -253.394464) (xy 97.84513 -253.394464)
			(xy 97.84909 -253.34541) (xy 97.860867 -253.297626) (xy 97.880158 -253.25235) (xy 97.906461 -253.210754)
			(xy 97.939096 -253.173917) (xy 97.977217 -253.142792) (xy 98.019838 -253.118185) (xy 98.065854 -253.100733)
			(xy 98.114073 -253.090889) (xy 98.163248 -253.088908) (xy 98.212103 -253.09484) (xy 98.259374 -253.108532)
			(xy 98.303836 -253.12963) (xy 98.344339 -253.157586) (xy 98.379832 -253.191678) (xy 98.409397 -253.231022)
			(xy 98.432268 -253.274599) (xy 98.447852 -253.32128) (xy 98.455747 -253.369857) (xy 98.456242 -253.394464)
			(xy 99.725238 -253.394464) (xy 99.729198 -253.34541) (xy 99.740975 -253.297626) (xy 99.760266 -253.25235)
			(xy 99.786569 -253.210754) (xy 99.819204 -253.173917) (xy 99.857325 -253.142792) (xy 99.899946 -253.118185)
			(xy 99.945962 -253.100733) (xy 99.994181 -253.090889) (xy 100.043356 -253.088908) (xy 100.092211 -253.09484)
			(xy 100.139482 -253.108532) (xy 100.183944 -253.12963) (xy 100.224447 -253.157586) (xy 100.25994 -253.191678)
			(xy 100.289505 -253.231022) (xy 100.312376 -253.274599) (xy 100.32796 -253.32128) (xy 100.335855 -253.369857)
			(xy 100.33635 -253.394464) (xy 100.665292 -253.394464) (xy 100.669252 -253.34541) (xy 100.681029 -253.297626)
			(xy 100.70032 -253.25235) (xy 100.726623 -253.210754) (xy 100.759258 -253.173917) (xy 100.797379 -253.142792)
			(xy 100.84 -253.118185) (xy 100.886016 -253.100733) (xy 100.934235 -253.090889) (xy 100.98341 -253.088908)
			(xy 101.032265 -253.09484) (xy 101.079536 -253.108532) (xy 101.123998 -253.12963) (xy 101.164501 -253.157586)
			(xy 101.199994 -253.191678) (xy 101.229559 -253.231022) (xy 101.25243 -253.274599) (xy 101.268014 -253.32128)
			(xy 101.275909 -253.369857) (xy 101.276404 -253.394464) (xy 101.605346 -253.394464) (xy 101.609306 -253.34541)
			(xy 101.621083 -253.297626) (xy 101.640374 -253.25235) (xy 101.666677 -253.210754) (xy 101.699312 -253.173917)
			(xy 101.737433 -253.142792) (xy 101.780054 -253.118185) (xy 101.82607 -253.100733) (xy 101.874289 -253.090889)
			(xy 101.923464 -253.088908) (xy 101.972319 -253.09484) (xy 102.01959 -253.108532) (xy 102.064052 -253.12963)
			(xy 102.104555 -253.157586) (xy 102.140048 -253.191678) (xy 102.169613 -253.231022) (xy 102.192484 -253.274599)
			(xy 102.208068 -253.32128) (xy 102.215963 -253.369857) (xy 102.216458 -253.394464) (xy 102.215963 -253.419071)
			(xy 102.208068 -253.467648) (xy 102.192484 -253.514329) (xy 102.169613 -253.557906) (xy 102.140048 -253.59725)
			(xy 102.104555 -253.631342) (xy 102.064052 -253.659298) (xy 102.01959 -253.680396) (xy 101.972319 -253.694088)
			(xy 101.923464 -253.70002) (xy 101.874289 -253.698039) (xy 101.82607 -253.688195) (xy 101.780054 -253.670743)
			(xy 101.737433 -253.646136) (xy 101.699312 -253.615011) (xy 101.666677 -253.578174) (xy 101.640374 -253.536578)
			(xy 101.621083 -253.491302) (xy 101.609306 -253.443518) (xy 101.605346 -253.394464) (xy 101.276404 -253.394464)
			(xy 101.275909 -253.419071) (xy 101.268014 -253.467648) (xy 101.25243 -253.514329) (xy 101.229559 -253.557906)
			(xy 101.199994 -253.59725) (xy 101.164501 -253.631342) (xy 101.123998 -253.659298) (xy 101.079536 -253.680396)
			(xy 101.032265 -253.694088) (xy 100.98341 -253.70002) (xy 100.934235 -253.698039) (xy 100.886016 -253.688195)
			(xy 100.84 -253.670743) (xy 100.797379 -253.646136) (xy 100.759258 -253.615011) (xy 100.726623 -253.578174)
			(xy 100.70032 -253.536578) (xy 100.681029 -253.491302) (xy 100.669252 -253.443518) (xy 100.665292 -253.394464)
			(xy 100.33635 -253.394464) (xy 100.335855 -253.419071) (xy 100.32796 -253.467648) (xy 100.312376 -253.514329)
			(xy 100.289505 -253.557906) (xy 100.25994 -253.59725) (xy 100.224447 -253.631342) (xy 100.183944 -253.659298)
			(xy 100.139482 -253.680396) (xy 100.092211 -253.694088) (xy 100.043356 -253.70002) (xy 99.994181 -253.698039)
			(xy 99.945962 -253.688195) (xy 99.899946 -253.670743) (xy 99.857325 -253.646136) (xy 99.819204 -253.615011)
			(xy 99.786569 -253.578174) (xy 99.760266 -253.536578) (xy 99.740975 -253.491302) (xy 99.729198 -253.443518)
			(xy 99.725238 -253.394464) (xy 98.456242 -253.394464) (xy 98.455747 -253.419071) (xy 98.447852 -253.467648)
			(xy 98.432268 -253.514329) (xy 98.409397 -253.557906) (xy 98.379832 -253.59725) (xy 98.344339 -253.631342)
			(xy 98.303836 -253.659298) (xy 98.259374 -253.680396) (xy 98.212103 -253.694088) (xy 98.163248 -253.70002)
			(xy 98.114073 -253.698039) (xy 98.065854 -253.688195) (xy 98.019838 -253.670743) (xy 97.977217 -253.646136)
			(xy 97.939096 -253.615011) (xy 97.906461 -253.578174) (xy 97.880158 -253.536578) (xy 97.860867 -253.491302)
			(xy 97.84909 -253.443518) (xy 97.84513 -253.394464) (xy 96.575947 -253.394464) (xy 96.575949 -253.418664)
			(xy 96.568335 -253.466422) (xy 96.553294 -253.512385) (xy 96.531202 -253.555405) (xy 96.502611 -253.594409)
			(xy 96.468233 -253.628423) (xy 96.428927 -253.656598) (xy 96.407478 -253.667768) (xy 96.39427 -253.674118)
			(xy 96.379284 -253.698502) (xy 96.379284 -254.20447) (xy 97.37523 -254.20447) (xy 97.37919 -254.155416)
			(xy 97.390967 -254.107632) (xy 97.410258 -254.062356) (xy 97.436561 -254.02076) (xy 97.469196 -253.983923)
			(xy 97.507317 -253.952798) (xy 97.549938 -253.928191) (xy 97.595954 -253.910739) (xy 97.644173 -253.900895)
			(xy 97.693348 -253.898914) (xy 97.742203 -253.904846) (xy 97.789474 -253.918538) (xy 97.833936 -253.939636)
			(xy 97.874439 -253.967592) (xy 97.909932 -254.001684) (xy 97.939497 -254.041028) (xy 97.962368 -254.084605)
			(xy 97.977952 -254.131286) (xy 97.985847 -254.179863) (xy 97.986342 -254.20447) (xy 99.255338 -254.20447)
			(xy 99.259298 -254.155416) (xy 99.271075 -254.107632) (xy 99.290366 -254.062356) (xy 99.316669 -254.02076)
			(xy 99.349304 -253.983923) (xy 99.387425 -253.952798) (xy 99.430046 -253.928191) (xy 99.476062 -253.910739)
			(xy 99.524281 -253.900895) (xy 99.573456 -253.898914) (xy 99.622311 -253.904846) (xy 99.669582 -253.918538)
			(xy 99.714044 -253.939636) (xy 99.754547 -253.967592) (xy 99.79004 -254.001684) (xy 99.819605 -254.041028)
			(xy 99.842476 -254.084605) (xy 99.85806 -254.131286) (xy 99.865955 -254.179863) (xy 99.86645 -254.20447)
			(xy 101.135192 -254.20447) (xy 101.139152 -254.155416) (xy 101.150929 -254.107632) (xy 101.17022 -254.062356)
			(xy 101.196523 -254.02076) (xy 101.229158 -253.983923) (xy 101.267279 -253.952798) (xy 101.3099 -253.928191)
			(xy 101.355916 -253.910739) (xy 101.404135 -253.900895) (xy 101.45331 -253.898914) (xy 101.502165 -253.904846)
			(xy 101.549436 -253.918538) (xy 101.593898 -253.939636) (xy 101.634401 -253.967592) (xy 101.669894 -254.001684)
			(xy 101.699459 -254.041028) (xy 101.72233 -254.084605) (xy 101.737914 -254.131286) (xy 101.745809 -254.179863)
			(xy 101.746304 -254.20447) (xy 102.075246 -254.20447) (xy 102.079206 -254.155416) (xy 102.090983 -254.107632)
			(xy 102.110274 -254.062356) (xy 102.136577 -254.02076) (xy 102.169212 -253.983923) (xy 102.207333 -253.952798)
			(xy 102.249954 -253.928191) (xy 102.29597 -253.910739) (xy 102.344189 -253.900895) (xy 102.393364 -253.898914)
			(xy 102.442219 -253.904846) (xy 102.48949 -253.918538) (xy 102.533952 -253.939636) (xy 102.574455 -253.967592)
			(xy 102.609948 -254.001684) (xy 102.639513 -254.041028) (xy 102.662384 -254.084605) (xy 102.677968 -254.131286)
			(xy 102.685863 -254.179863) (xy 102.686358 -254.20447) (xy 102.685863 -254.229077) (xy 102.677968 -254.277654)
			(xy 102.662384 -254.324335) (xy 102.639513 -254.367912) (xy 102.609948 -254.407256) (xy 102.574455 -254.441348)
			(xy 102.533952 -254.469304) (xy 102.48949 -254.490402) (xy 102.442219 -254.504094) (xy 102.393364 -254.510026)
			(xy 102.344189 -254.508045) (xy 102.29597 -254.498201) (xy 102.249954 -254.480749) (xy 102.207333 -254.456142)
			(xy 102.169212 -254.425017) (xy 102.136577 -254.38818) (xy 102.110274 -254.346584) (xy 102.090983 -254.301308)
			(xy 102.079206 -254.253524) (xy 102.075246 -254.20447) (xy 101.746304 -254.20447) (xy 101.745809 -254.229077)
			(xy 101.737914 -254.277654) (xy 101.72233 -254.324335) (xy 101.699459 -254.367912) (xy 101.669894 -254.407256)
			(xy 101.634401 -254.441348) (xy 101.593898 -254.469304) (xy 101.549436 -254.490402) (xy 101.502165 -254.504094)
			(xy 101.45331 -254.510026) (xy 101.404135 -254.508045) (xy 101.355916 -254.498201) (xy 101.3099 -254.480749)
			(xy 101.267279 -254.456142) (xy 101.229158 -254.425017) (xy 101.196523 -254.38818) (xy 101.17022 -254.346584)
			(xy 101.150929 -254.301308) (xy 101.139152 -254.253524) (xy 101.135192 -254.20447) (xy 99.86645 -254.20447)
			(xy 99.865955 -254.229077) (xy 99.85806 -254.277654) (xy 99.842476 -254.324335) (xy 99.819605 -254.367912)
			(xy 99.79004 -254.407256) (xy 99.754547 -254.441348) (xy 99.714044 -254.469304) (xy 99.669582 -254.490402)
			(xy 99.622311 -254.504094) (xy 99.573456 -254.510026) (xy 99.524281 -254.508045) (xy 99.476062 -254.498201)
			(xy 99.430046 -254.480749) (xy 99.387425 -254.456142) (xy 99.349304 -254.425017) (xy 99.316669 -254.38818)
			(xy 99.290366 -254.346584) (xy 99.271075 -254.301308) (xy 99.259298 -254.253524) (xy 99.255338 -254.20447)
			(xy 97.986342 -254.20447) (xy 97.985847 -254.229077) (xy 97.977952 -254.277654) (xy 97.962368 -254.324335)
			(xy 97.939497 -254.367912) (xy 97.909932 -254.407256) (xy 97.874439 -254.441348) (xy 97.833936 -254.469304)
			(xy 97.789474 -254.490402) (xy 97.742203 -254.504094) (xy 97.693348 -254.510026) (xy 97.644173 -254.508045)
			(xy 97.595954 -254.498201) (xy 97.549938 -254.480749) (xy 97.507317 -254.456142) (xy 97.469196 -254.425017)
			(xy 97.436561 -254.38818) (xy 97.410258 -254.346584) (xy 97.390967 -254.301308) (xy 97.37919 -254.253524)
			(xy 97.37523 -254.20447) (xy 96.379284 -254.20447) (xy 96.379284 -254.710438) (xy 96.39427 -254.734822)
			(xy 96.407478 -254.741172) (xy 96.428899 -254.752397) (xy 96.468206 -254.780568) (xy 96.502585 -254.814578)
			(xy 96.531179 -254.853578) (xy 96.553274 -254.896595) (xy 96.568318 -254.942554) (xy 96.575936 -254.99031)
			(xy 96.575937 -255.014476) (xy 97.84513 -255.014476) (xy 97.84909 -254.965422) (xy 97.860867 -254.917638)
			(xy 97.880158 -254.872362) (xy 97.906461 -254.830766) (xy 97.939096 -254.793929) (xy 97.977217 -254.762804)
			(xy 98.019838 -254.738197) (xy 98.065854 -254.720745) (xy 98.114073 -254.710901) (xy 98.163248 -254.70892)
			(xy 98.212103 -254.714852) (xy 98.259374 -254.728544) (xy 98.303836 -254.749642) (xy 98.344339 -254.777598)
			(xy 98.379832 -254.81169) (xy 98.409397 -254.851034) (xy 98.432268 -254.894611) (xy 98.447852 -254.941292)
			(xy 98.455747 -254.989869) (xy 98.456242 -255.014476) (xy 99.725238 -255.014476) (xy 99.729198 -254.965422)
			(xy 99.740975 -254.917638) (xy 99.760266 -254.872362) (xy 99.786569 -254.830766) (xy 99.819204 -254.793929)
			(xy 99.857325 -254.762804) (xy 99.899946 -254.738197) (xy 99.945962 -254.720745) (xy 99.994181 -254.710901)
			(xy 100.043356 -254.70892) (xy 100.092211 -254.714852) (xy 100.139482 -254.728544) (xy 100.183944 -254.749642)
			(xy 100.224447 -254.777598) (xy 100.25994 -254.81169) (xy 100.289505 -254.851034) (xy 100.312376 -254.894611)
			(xy 100.32796 -254.941292) (xy 100.335855 -254.989869) (xy 100.33635 -255.014476) (xy 100.665292 -255.014476)
			(xy 100.669252 -254.965422) (xy 100.681029 -254.917638) (xy 100.70032 -254.872362) (xy 100.726623 -254.830766)
			(xy 100.759258 -254.793929) (xy 100.797379 -254.762804) (xy 100.84 -254.738197) (xy 100.886016 -254.720745)
			(xy 100.934235 -254.710901) (xy 100.98341 -254.70892) (xy 101.032265 -254.714852) (xy 101.079536 -254.728544)
			(xy 101.123998 -254.749642) (xy 101.164501 -254.777598) (xy 101.199994 -254.81169) (xy 101.229559 -254.851034)
			(xy 101.25243 -254.894611) (xy 101.268014 -254.941292) (xy 101.275909 -254.989869) (xy 101.276404 -255.014476)
			(xy 101.605346 -255.014476) (xy 101.609306 -254.965422) (xy 101.621083 -254.917638) (xy 101.640374 -254.872362)
			(xy 101.666677 -254.830766) (xy 101.699312 -254.793929) (xy 101.737433 -254.762804) (xy 101.780054 -254.738197)
			(xy 101.82607 -254.720745) (xy 101.874289 -254.710901) (xy 101.923464 -254.70892) (xy 101.972319 -254.714852)
			(xy 102.01959 -254.728544) (xy 102.064052 -254.749642) (xy 102.104555 -254.777598) (xy 102.140048 -254.81169)
			(xy 102.169613 -254.851034) (xy 102.192484 -254.894611) (xy 102.208068 -254.941292) (xy 102.215963 -254.989869)
			(xy 102.216458 -255.014476) (xy 102.215963 -255.039083) (xy 102.208068 -255.08766) (xy 102.192484 -255.134341)
			(xy 102.169613 -255.177918) (xy 102.140048 -255.217262) (xy 102.104555 -255.251354) (xy 102.064052 -255.27931)
			(xy 102.01959 -255.300408) (xy 101.972319 -255.3141) (xy 101.923464 -255.320032) (xy 101.874289 -255.318051)
			(xy 101.82607 -255.308207) (xy 101.780054 -255.290755) (xy 101.737433 -255.266148) (xy 101.699312 -255.235023)
			(xy 101.666677 -255.198186) (xy 101.640374 -255.15659) (xy 101.621083 -255.111314) (xy 101.609306 -255.06353)
			(xy 101.605346 -255.014476) (xy 101.276404 -255.014476) (xy 101.275909 -255.039083) (xy 101.268014 -255.08766)
			(xy 101.25243 -255.134341) (xy 101.229559 -255.177918) (xy 101.199994 -255.217262) (xy 101.164501 -255.251354)
			(xy 101.123998 -255.27931) (xy 101.079536 -255.300408) (xy 101.032265 -255.3141) (xy 100.98341 -255.320032)
			(xy 100.934235 -255.318051) (xy 100.886016 -255.308207) (xy 100.84 -255.290755) (xy 100.797379 -255.266148)
			(xy 100.759258 -255.235023) (xy 100.726623 -255.198186) (xy 100.70032 -255.15659) (xy 100.681029 -255.111314)
			(xy 100.669252 -255.06353) (xy 100.665292 -255.014476) (xy 100.33635 -255.014476) (xy 100.335855 -255.039083)
			(xy 100.32796 -255.08766) (xy 100.312376 -255.134341) (xy 100.289505 -255.177918) (xy 100.25994 -255.217262)
			(xy 100.224447 -255.251354) (xy 100.183944 -255.27931) (xy 100.139482 -255.300408) (xy 100.092211 -255.3141)
			(xy 100.043356 -255.320032) (xy 99.994181 -255.318051) (xy 99.945962 -255.308207) (xy 99.899946 -255.290755)
			(xy 99.857325 -255.266148) (xy 99.819204 -255.235023) (xy 99.786569 -255.198186) (xy 99.760266 -255.15659)
			(xy 99.740975 -255.111314) (xy 99.729198 -255.06353) (xy 99.725238 -255.014476) (xy 98.456242 -255.014476)
			(xy 98.455747 -255.039083) (xy 98.447852 -255.08766) (xy 98.432268 -255.134341) (xy 98.409397 -255.177918)
			(xy 98.379832 -255.217262) (xy 98.344339 -255.251354) (xy 98.303836 -255.27931) (xy 98.259374 -255.300408)
			(xy 98.212103 -255.3141) (xy 98.163248 -255.320032) (xy 98.114073 -255.318051) (xy 98.065854 -255.308207)
			(xy 98.019838 -255.290755) (xy 97.977217 -255.266148) (xy 97.939096 -255.235023) (xy 97.906461 -255.198186)
			(xy 97.880158 -255.15659) (xy 97.860867 -255.111314) (xy 97.84909 -255.06353) (xy 97.84513 -255.014476)
			(xy 96.575937 -255.014476) (xy 96.575938 -255.038669) (xy 96.568323 -255.086425) (xy 96.553282 -255.132385)
			(xy 96.53119 -255.175404) (xy 96.502599 -255.214406) (xy 96.468222 -255.248418) (xy 96.428917 -255.276592)
			(xy 96.407478 -255.28778) (xy 96.39427 -255.29413) (xy 96.379284 -255.318514) (xy 96.379284 -255.951482)
			(xy 96.379722 -255.961546) (xy 96.387455 -255.98013) (xy 96.39427 -255.98755) (xy 96.491298 -256.084578)
			(xy 96.498695 -256.091427) (xy 96.517294 -256.099166) (xy 96.527366 -256.099564) (xy 97.31502 -256.099564)
			(xy 97.323585 -256.099188) (xy 97.339738 -256.093472) (xy 97.353126 -256.082777) (xy 97.357946 -256.075688)
			(xy 97.409762 -255.993646) (xy 97.411032 -255.967738) (xy 97.405444 -255.9558) (xy 97.396069 -255.935191)
			(xy 97.382827 -255.891896) (xy 97.376126 -255.847119) (xy 97.375726 -255.824482) (xy 97.376248 -255.799227)
			(xy 97.384561 -255.749405) (xy 97.400962 -255.701631) (xy 97.425003 -255.657208) (xy 97.456027 -255.617348)
			(xy 97.493189 -255.583138) (xy 97.535475 -255.555512) (xy 97.581731 -255.535222) (xy 97.630696 -255.522822)
			(xy 97.681034 -255.518651) (xy 97.731372 -255.522822) (xy 97.780337 -255.535222) (xy 97.826593 -255.555512)
			(xy 97.868879 -255.583138) (xy 97.906041 -255.617348) (xy 97.937065 -255.657208) (xy 97.961106 -255.701631)
			(xy 97.977507 -255.749405) (xy 97.98582 -255.799227) (xy 97.986342 -255.824482) (xy 97.985931 -255.847119)
			(xy 97.979239 -255.891896) (xy 97.966001 -255.935192) (xy 97.956624 -255.9558) (xy 97.951036 -255.967738)
			(xy 97.952306 -255.993646) (xy 98.004122 -256.075688) (xy 98.008932 -256.082796) (xy 98.022299 -256.093541)
			(xy 98.038473 -256.099245) (xy 98.047048 -256.099564) (xy 99.195128 -256.099564) (xy 99.203693 -256.099187)
			(xy 99.219844 -256.093469) (xy 99.23323 -256.082774) (xy 99.238054 -256.075688) (xy 99.28987 -255.993646)
			(xy 99.29114 -255.967738) (xy 99.285552 -255.9558) (xy 99.276177 -255.935191) (xy 99.262934 -255.891896)
			(xy 99.256233 -255.847119) (xy 99.255834 -255.824482) (xy 99.256356 -255.799227) (xy 99.264669 -255.749405)
			(xy 99.28107 -255.701631) (xy 99.305111 -255.657208) (xy 99.336135 -255.617348) (xy 99.373297 -255.583138)
			(xy 99.415583 -255.555512) (xy 99.461839 -255.535222) (xy 99.510804 -255.522822) (xy 99.561142 -255.518651)
			(xy 99.61148 -255.522822) (xy 99.660445 -255.535222) (xy 99.706701 -255.555512) (xy 99.748987 -255.583138)
			(xy 99.786149 -255.617348) (xy 99.817173 -255.657208) (xy 99.841214 -255.701631) (xy 99.857615 -255.749405)
			(xy 99.865928 -255.799227) (xy 99.86645 -255.824482) (xy 99.866039 -255.847119) (xy 99.859347 -255.891897)
			(xy 99.84611 -255.935192) (xy 99.836732 -255.9558) (xy 99.831144 -255.967738) (xy 99.832414 -255.993646)
			(xy 99.88423 -256.075688) (xy 99.88904 -256.082795) (xy 99.902408 -256.093538) (xy 99.918582 -256.099239)
			(xy 99.927156 -256.099564) (xy 100.134928 -256.099564) (xy 100.143493 -256.099187) (xy 100.159644 -256.093469)
			(xy 100.17303 -256.082774) (xy 100.177854 -256.075688) (xy 100.22967 -255.993646) (xy 100.23094 -255.967738)
			(xy 100.225352 -255.9558) (xy 100.215977 -255.935191) (xy 100.202734 -255.891896) (xy 100.196033 -255.847119)
			(xy 100.195634 -255.824482) (xy 100.196156 -255.799227) (xy 100.204469 -255.749405) (xy 100.22087 -255.701631)
			(xy 100.244911 -255.657208) (xy 100.275935 -255.617348) (xy 100.313097 -255.583138) (xy 100.355383 -255.555512)
			(xy 100.401639 -255.535222) (xy 100.450604 -255.522822) (xy 100.500942 -255.518651) (xy 100.55128 -255.522822)
			(xy 100.600245 -255.535222) (xy 100.646501 -255.555512) (xy 100.688787 -255.583138) (xy 100.725949 -255.617348)
			(xy 100.756973 -255.657208) (xy 100.781014 -255.701631) (xy 100.797415 -255.749405) (xy 100.805728 -255.799227)
			(xy 100.80625 -255.824482) (xy 101.135192 -255.824482) (xy 101.139152 -255.775428) (xy 101.150929 -255.727644)
			(xy 101.17022 -255.682368) (xy 101.196523 -255.640772) (xy 101.229158 -255.603935) (xy 101.267279 -255.57281)
			(xy 101.3099 -255.548203) (xy 101.355916 -255.530751) (xy 101.404135 -255.520907) (xy 101.45331 -255.518926)
			(xy 101.502165 -255.524858) (xy 101.549436 -255.53855) (xy 101.593898 -255.559648) (xy 101.634401 -255.587604)
			(xy 101.669894 -255.621696) (xy 101.699459 -255.66104) (xy 101.72233 -255.704617) (xy 101.737914 -255.751298)
			(xy 101.745809 -255.799875) (xy 101.746304 -255.824482) (xy 102.075246 -255.824482) (xy 102.079206 -255.775428)
			(xy 102.090983 -255.727644) (xy 102.110274 -255.682368) (xy 102.136577 -255.640772) (xy 102.169212 -255.603935)
			(xy 102.207333 -255.57281) (xy 102.249954 -255.548203) (xy 102.29597 -255.530751) (xy 102.344189 -255.520907)
			(xy 102.393364 -255.518926) (xy 102.442219 -255.524858) (xy 102.48949 -255.53855) (xy 102.533952 -255.559648)
			(xy 102.574455 -255.587604) (xy 102.609948 -255.621696) (xy 102.639513 -255.66104) (xy 102.662384 -255.704617)
			(xy 102.677968 -255.751298) (xy 102.685863 -255.799875) (xy 102.686317 -255.82245) (xy 103.011998 -255.82245)
			(xy 103.015958 -255.773396) (xy 103.027735 -255.725612) (xy 103.047026 -255.680336) (xy 103.073329 -255.63874)
			(xy 103.105964 -255.601903) (xy 103.144085 -255.570778) (xy 103.186706 -255.546171) (xy 103.232722 -255.528719)
			(xy 103.280941 -255.518875) (xy 103.330116 -255.516894) (xy 103.378971 -255.522826) (xy 103.426242 -255.536518)
			(xy 103.470704 -255.557616) (xy 103.511207 -255.585572) (xy 103.5467 -255.619664) (xy 103.576265 -255.659008)
			(xy 103.599136 -255.702585) (xy 103.61472 -255.749266) (xy 103.622615 -255.797843) (xy 103.62311 -255.82245)
			(xy 103.952052 -255.82245) (xy 103.956012 -255.773396) (xy 103.967789 -255.725612) (xy 103.98708 -255.680336)
			(xy 104.013383 -255.63874) (xy 104.046018 -255.601903) (xy 104.084139 -255.570778) (xy 104.12676 -255.546171)
			(xy 104.172776 -255.528719) (xy 104.220995 -255.518875) (xy 104.27017 -255.516894) (xy 104.319025 -255.522826)
			(xy 104.366296 -255.536518) (xy 104.410758 -255.557616) (xy 104.451261 -255.585572) (xy 104.486754 -255.619664)
			(xy 104.516319 -255.659008) (xy 104.53919 -255.702585) (xy 104.554774 -255.749266) (xy 104.562669 -255.797843)
			(xy 104.563164 -255.82245) (xy 104.562669 -255.847057) (xy 104.554774 -255.895634) (xy 104.53919 -255.942315)
			(xy 104.516319 -255.985892) (xy 104.486754 -256.025236) (xy 104.451261 -256.059328) (xy 104.410758 -256.087284)
			(xy 104.366296 -256.108382) (xy 104.319025 -256.122074) (xy 104.27017 -256.128006) (xy 104.220995 -256.126025)
			(xy 104.172776 -256.116181) (xy 104.12676 -256.098729) (xy 104.084139 -256.074122) (xy 104.046018 -256.042997)
			(xy 104.013383 -256.00616) (xy 103.98708 -255.964564) (xy 103.967789 -255.919288) (xy 103.956012 -255.871504)
			(xy 103.952052 -255.82245) (xy 103.62311 -255.82245) (xy 103.622615 -255.847057) (xy 103.61472 -255.895634)
			(xy 103.599136 -255.942315) (xy 103.576265 -255.985892) (xy 103.5467 -256.025236) (xy 103.511207 -256.059328)
			(xy 103.470704 -256.087284) (xy 103.426242 -256.108382) (xy 103.378971 -256.122074) (xy 103.330116 -256.128006)
			(xy 103.280941 -256.126025) (xy 103.232722 -256.116181) (xy 103.186706 -256.098729) (xy 103.144085 -256.074122)
			(xy 103.105964 -256.042997) (xy 103.073329 -256.00616) (xy 103.047026 -255.964564) (xy 103.027735 -255.919288)
			(xy 103.015958 -255.871504) (xy 103.011998 -255.82245) (xy 102.686317 -255.82245) (xy 102.686358 -255.824482)
			(xy 102.685863 -255.849089) (xy 102.677968 -255.897666) (xy 102.662384 -255.944347) (xy 102.639513 -255.987924)
			(xy 102.609948 -256.027268) (xy 102.574455 -256.06136) (xy 102.533952 -256.089316) (xy 102.48949 -256.110414)
			(xy 102.442219 -256.124106) (xy 102.393364 -256.130038) (xy 102.344189 -256.128057) (xy 102.29597 -256.118213)
			(xy 102.249954 -256.100761) (xy 102.207333 -256.076154) (xy 102.169212 -256.045029) (xy 102.136577 -256.008192)
			(xy 102.110274 -255.966596) (xy 102.090983 -255.92132) (xy 102.079206 -255.873536) (xy 102.075246 -255.824482)
			(xy 101.746304 -255.824482) (xy 101.745809 -255.849089) (xy 101.737914 -255.897666) (xy 101.72233 -255.944347)
			(xy 101.699459 -255.987924) (xy 101.669894 -256.027268) (xy 101.634401 -256.06136) (xy 101.593898 -256.089316)
			(xy 101.549436 -256.110414) (xy 101.502165 -256.124106) (xy 101.45331 -256.130038) (xy 101.404135 -256.128057)
			(xy 101.355916 -256.118213) (xy 101.3099 -256.100761) (xy 101.267279 -256.076154) (xy 101.229158 -256.045029)
			(xy 101.196523 -256.008192) (xy 101.17022 -255.966596) (xy 101.150929 -255.92132) (xy 101.139152 -255.873536)
			(xy 101.135192 -255.824482) (xy 100.80625 -255.824482) (xy 100.80611 -255.837245) (xy 100.803944 -255.862678)
			(xy 100.801932 -255.875282) (xy 100.797002 -255.90114) (xy 100.779469 -255.950769) (xy 100.753697 -255.996663)
			(xy 100.720449 -256.037467) (xy 100.680705 -256.071977) (xy 100.63564 -256.099173) (xy 100.586585 -256.118251)
			(xy 100.560886 -256.123948) (xy 100.54717 -256.126742) (xy 100.526596 -256.145538) (xy 100.497132 -256.242312)
			(xy 100.49484 -256.251226) (xy 100.496037 -256.269579) (xy 100.503594 -256.286346) (xy 100.509832 -256.293112)
			(xy 100.624386 -256.407666) (xy 100.631609 -256.414317) (xy 100.64964 -256.422039) (xy 100.659438 -256.422652)
			(xy 100.738178 -256.424176) (xy 100.756212 -256.417318) (xy 100.763578 -256.41046) (xy 100.78062 -256.395273)
			(xy 100.818365 -256.369606) (xy 100.859509 -256.349838) (xy 100.903135 -256.33641) (xy 100.948273 -256.32962)
			(xy 100.971096 -256.32918) (xy 100.995088 -256.32965) (xy 101.042481 -256.337156) (xy 101.088116 -256.351983)
			(xy 101.13087 -256.373766) (xy 101.16969 -256.401969) (xy 101.203621 -256.435898) (xy 101.231826 -256.474716)
			(xy 101.253611 -256.517469) (xy 101.26844 -256.563104) (xy 101.275948 -256.610496) (xy 101.276404 -256.634488)
			(xy 101.27594 -256.658719) (xy 101.268286 -256.706573) (xy 101.261164 -256.729738) (xy 101.257354 -256.741422)
			(xy 101.261164 -256.765552) (xy 101.315266 -256.840482) (xy 101.322881 -256.849857) (xy 101.344356 -256.860838)
			(xy 101.356414 -256.861564)
		)
		(stroke
			(width 0)
			(type solid)
		)
		(fill yes)
		(layer "In2.Cu")
		(net "PVDD18_S5_P1")
	)
	(gr_poly
		(pts
			(xy 349.4659 -256.86131) (xy 349.477965 -256.860631) (xy 349.499432 -256.849613) (xy 349.507048 -256.840228)
			(xy 349.56115 -256.765298) (xy 349.56496 -256.741168) (xy 349.56115 -256.729484) (xy 349.554031 -256.706318)
			(xy 349.546372 -256.658465) (xy 349.54591 -256.634234) (xy 349.546432 -256.608979) (xy 349.554745 -256.559157)
			(xy 349.571146 -256.511383) (xy 349.595187 -256.46696) (xy 349.626211 -256.4271) (xy 349.663373 -256.39289)
			(xy 349.705659 -256.365264) (xy 349.751915 -256.344974) (xy 349.80088 -256.332574) (xy 349.851218 -256.328403)
			(xy 349.901556 -256.332574) (xy 349.950521 -256.344974) (xy 349.996777 -256.365264) (xy 350.039063 -256.39289)
			(xy 350.076225 -256.4271) (xy 350.107249 -256.46696) (xy 350.13129 -256.511383) (xy 350.147691 -256.559157)
			(xy 350.156004 -256.608979) (xy 350.156526 -256.634234) (xy 350.156058 -256.658464) (xy 350.148395 -256.706315)
			(xy 350.141286 -256.729484) (xy 350.137476 -256.741168) (xy 350.141286 -256.765298) (xy 350.195388 -256.840228)
			(xy 350.202993 -256.849624) (xy 350.224468 -256.86065) (xy 350.236536 -256.86131) (xy 350.4057 -256.86131)
			(xy 350.417765 -256.860631) (xy 350.439232 -256.849613) (xy 350.446848 -256.840228) (xy 350.50095 -256.765044)
			(xy 350.50476 -256.740914) (xy 350.50095 -256.72923) (xy 350.493629 -256.705773) (xy 350.485715 -256.657278)
			(xy 350.485202 -256.63271) (xy 350.485724 -256.607455) (xy 350.494037 -256.557633) (xy 350.510438 -256.509859)
			(xy 350.534479 -256.465436) (xy 350.565503 -256.425576) (xy 350.602665 -256.391366) (xy 350.644951 -256.36374)
			(xy 350.691207 -256.34345) (xy 350.740172 -256.33105) (xy 350.79051 -256.326879) (xy 350.840848 -256.33105)
			(xy 350.889813 -256.34345) (xy 350.936069 -256.36374) (xy 350.978355 -256.391366) (xy 351.015517 -256.425576)
			(xy 351.046541 -256.465436) (xy 351.070582 -256.509859) (xy 351.086983 -256.557633) (xy 351.095296 -256.607455)
			(xy 351.095818 -256.63271) (xy 351.095308 -256.657278) (xy 351.0874 -256.705775) (xy 351.08007 -256.72923)
			(xy 351.07626 -256.740914) (xy 351.08007 -256.765044) (xy 351.134172 -256.840228) (xy 351.141783 -256.84961)
			(xy 351.163259 -256.860601) (xy 351.17532 -256.86131) (xy 353.849178 -256.86131) (xy 353.859015 -256.860773)
			(xy 353.877175 -256.853185) (xy 353.884484 -256.846578) (xy 353.98202 -256.749042) (xy 353.988741 -256.741807)
			(xy 353.996353 -256.723602) (xy 353.996752 -256.713736) (xy 353.996752 -255.739392) (xy 353.996326 -255.729324)
			(xy 353.988604 -255.710726) (xy 353.981766 -255.703324) (xy 351.930462 -253.65202) (xy 351.896426 -253.647448)
			(xy 351.881186 -253.656338) (xy 351.857753 -253.669268) (xy 351.807481 -253.687612) (xy 351.754782 -253.696919)
			(xy 351.728024 -253.697486) (xy 351.721928 -253.697486) (xy 351.695954 -253.696446) (xy 351.644909 -253.686629)
			(xy 351.596264 -253.668313) (xy 351.551421 -253.642025) (xy 351.511676 -253.608525) (xy 351.478176 -253.568781)
			(xy 351.451888 -253.523938) (xy 351.433571 -253.475293) (xy 351.423754 -253.424248) (xy 351.422716 -253.398274)
			(xy 351.422716 -253.393194) (xy 351.423204 -253.366267) (xy 351.432474 -253.31322) (xy 351.450885 -253.262614)
			(xy 351.463864 -253.239016) (xy 351.472754 -253.223776) (xy 351.468182 -253.18974) (xy 350.797622 -252.51918)
			(xy 350.790298 -252.512373) (xy 350.771874 -252.504641) (xy 350.751893 -252.504568) (xy 350.742504 -252.508004)
			(xy 350.643952 -252.547882) (xy 350.62668 -252.573028) (xy 350.626426 -252.588522) (xy 350.625636 -252.612289)
			(xy 350.617598 -252.659155) (xy 350.60239 -252.704209) (xy 350.58038 -252.746359) (xy 350.5521 -252.784587)
			(xy 350.518235 -252.817967) (xy 350.479603 -252.845693) (xy 350.43714 -252.867092) (xy 350.391871 -252.881648)
			(xy 350.344894 -252.889009) (xy 350.321118 -252.889512) (xy 350.297124 -252.889067) (xy 350.249726 -252.881563)
			(xy 350.204086 -252.866736) (xy 350.161327 -252.844951) (xy 350.122502 -252.816746) (xy 350.088568 -252.782815)
			(xy 350.06036 -252.743992) (xy 350.038573 -252.701235) (xy 350.023742 -252.655596) (xy 350.016235 -252.608198)
			(xy 350.01581 -252.584204) (xy 350.016263 -252.560426) (xy 350.023635 -252.513444) (xy 350.038199 -252.468173)
			(xy 350.059606 -252.425707) (xy 350.087336 -252.387073) (xy 350.12072 -252.353204) (xy 350.158951 -252.324919)
			(xy 350.201103 -252.302902) (xy 350.24616 -252.287686) (xy 350.29303 -252.279638) (xy 350.3168 -252.278896)
			(xy 350.332294 -252.278642) (xy 350.35744 -252.26137) (xy 350.397318 -252.162818) (xy 350.400608 -252.153401)
			(xy 350.400505 -252.133473) (xy 350.392862 -252.115069) (xy 350.386142 -252.1077) (xy 350.237044 -251.958602)
			(xy 350.229076 -251.951478) (xy 350.209126 -251.943873) (xy 350.198436 -251.94387) (xy 350.114108 -251.948442)
			(xy 350.095058 -251.958094) (xy 350.0882 -251.966476) (xy 350.070643 -251.987209) (xy 350.029518 -252.0227)
			(xy 349.982758 -252.050349) (xy 349.931843 -252.069283) (xy 349.878379 -252.078904) (xy 349.851218 -252.079506)
			(xy 349.827224 -252.079061) (xy 349.779826 -252.071557) (xy 349.734186 -252.05673) (xy 349.691428 -252.034945)
			(xy 349.652604 -252.00674) (xy 349.618671 -251.972808) (xy 349.590463 -251.933986) (xy 349.568676 -251.891228)
			(xy 349.553847 -251.845589) (xy 349.54634 -251.798192) (xy 349.54591 -251.774198) (xy 349.546526 -251.747041)
			(xy 349.556176 -251.693588) (xy 349.575118 -251.642682) (xy 349.602756 -251.595924) (xy 349.638221 -251.554784)
			(xy 349.65894 -251.537216) (xy 349.667322 -251.530358) (xy 349.676974 -251.511308) (xy 349.681546 -251.42698)
			(xy 349.681677 -251.416267) (xy 349.674063 -251.396259) (xy 349.666814 -251.388372) (xy 349.530162 -251.25172)
			(xy 349.501206 -251.24537) (xy 349.487236 -251.25045) (xy 349.461903 -251.259248) (xy 349.409143 -251.268828)
			(xy 349.382334 -251.2695) (xy 349.377 -251.2695) (xy 349.353422 -251.268744) (xy 349.306914 -251.260864)
			(xy 349.262171 -251.245925) (xy 349.220258 -251.224283) (xy 349.182172 -251.196452) (xy 349.148819 -251.163094)
			(xy 349.120994 -251.125004) (xy 349.099357 -251.083088) (xy 349.084425 -251.038343) (xy 349.076552 -250.991833)
			(xy 349.075756 -250.968256) (xy 349.075756 -250.963938) (xy 349.076361 -250.936874) (xy 349.085942 -250.883599)
			(xy 349.094806 -250.85802) (xy 349.099886 -250.84405) (xy 349.093536 -250.815094) (xy 349.015558 -250.737116)
			(xy 349.008158 -250.730274) (xy 348.98956 -250.722553) (xy 348.97949 -250.72213) (xy 348.401386 -250.72213)
			(xy 348.391543 -250.721605) (xy 348.373365 -250.714035) (xy 348.36608 -250.707398) (xy 348.10573 -250.447048)
			(xy 348.078298 -250.440444) (xy 348.064582 -250.444762) (xy 348.041824 -250.451623) (xy 347.994875 -250.459027)
			(xy 347.97111 -250.459494) (xy 347.947117 -250.459049) (xy 347.899721 -250.451543) (xy 347.854083 -250.436715)
			(xy 347.811326 -250.41493) (xy 347.772504 -250.386724) (xy 347.738573 -250.352793) (xy 347.710368 -250.31397)
			(xy 347.688583 -250.271214) (xy 347.673756 -250.225575) (xy 347.666251 -250.178179) (xy 347.665802 -250.154186)
			(xy 347.66627 -250.130421) (xy 347.673665 -250.083469) (xy 347.680534 -250.060714) (xy 347.684852 -250.046998)
			(xy 347.678248 -250.019566) (xy 346.838778 -249.180096) (xy 346.831378 -249.173254) (xy 346.81278 -249.165528)
			(xy 346.80271 -249.16511) (xy 346.01912 -249.16511) (xy 346.00783 -249.16571) (xy 345.987396 -249.175324)
			(xy 345.97975 -249.183652) (xy 345.92387 -249.251724) (xy 345.918282 -249.273568) (xy 345.920568 -249.284998)
			(xy 345.923289 -249.299642) (xy 345.926211 -249.329286) (xy 345.92641 -249.34418) (xy 345.925888 -249.369435)
			(xy 345.917575 -249.419257) (xy 345.901174 -249.467031) (xy 345.877133 -249.511454) (xy 345.846109 -249.551314)
			(xy 345.808947 -249.585524) (xy 345.766661 -249.61315) (xy 345.720405 -249.63344) (xy 345.67144 -249.64584)
			(xy 345.621102 -249.650011) (xy 345.570764 -249.64584) (xy 345.521799 -249.63344) (xy 345.475543 -249.61315)
			(xy 345.433257 -249.585524) (xy 345.396095 -249.551314) (xy 345.365071 -249.511454) (xy 345.34103 -249.467031)
			(xy 345.324629 -249.419257) (xy 345.316316 -249.369435) (xy 345.315794 -249.34418) (xy 345.315984 -249.329286)
			(xy 345.318908 -249.299641) (xy 345.321636 -249.284998) (xy 345.323922 -249.273568) (xy 345.318334 -249.251724)
			(xy 345.262454 -249.183652) (xy 345.254833 -249.175286) (xy 345.234388 -249.165655) (xy 345.223084 -249.16511)
			(xy 344.597228 -249.16511) (xy 344.587391 -249.165647) (xy 344.569231 -249.173235) (xy 344.561922 -249.179842)
			(xy 344.359484 -249.38228) (xy 344.352766 -249.389516) (xy 344.345161 -249.407721) (xy 344.344752 -249.417586)
			(xy 344.344752 -249.836686) (xy 344.344961 -249.843267) (xy 344.348301 -249.855999) (xy 344.351356 -249.861832)
			(xy 344.36558 -249.886978) (xy 344.373708 -249.895614) (xy 344.378788 -249.89917) (xy 344.399555 -249.913419)
			(xy 344.436547 -249.947592) (xy 344.467424 -249.987377) (xy 344.491346 -250.031692) (xy 344.507666 -250.079336)
			(xy 344.515938 -250.129012) (xy 344.515939 -250.154186) (xy 345.785198 -250.154186) (xy 345.789158 -250.105132)
			(xy 345.800935 -250.057348) (xy 345.820226 -250.012072) (xy 345.846529 -249.970476) (xy 345.879164 -249.933639)
			(xy 345.917285 -249.902514) (xy 345.959906 -249.877907) (xy 346.005922 -249.860455) (xy 346.054141 -249.850611)
			(xy 346.103316 -249.84863) (xy 346.152171 -249.854562) (xy 346.199442 -249.868254) (xy 346.243904 -249.889352)
			(xy 346.284407 -249.917308) (xy 346.3199 -249.9514) (xy 346.349465 -249.990744) (xy 346.372336 -250.034321)
			(xy 346.38792 -250.081002) (xy 346.395815 -250.129579) (xy 346.39631 -250.154186) (xy 346.395815 -250.178793)
			(xy 346.38792 -250.22737) (xy 346.372336 -250.274051) (xy 346.349465 -250.317628) (xy 346.3199 -250.356972)
			(xy 346.284407 -250.391064) (xy 346.243904 -250.41902) (xy 346.199442 -250.440118) (xy 346.152171 -250.45381)
			(xy 346.103316 -250.459742) (xy 346.054141 -250.457761) (xy 346.005922 -250.447917) (xy 345.959906 -250.430465)
			(xy 345.917285 -250.405858) (xy 345.879164 -250.374733) (xy 345.846529 -250.337896) (xy 345.820226 -250.2963)
			(xy 345.800935 -250.251024) (xy 345.789158 -250.20324) (xy 345.785198 -250.154186) (xy 344.515939 -250.154186)
			(xy 344.51594 -250.179373) (xy 344.50767 -250.229049) (xy 344.491353 -250.276693) (xy 344.467432 -250.32101)
			(xy 344.436557 -250.360797) (xy 344.399568 -250.394972) (xy 344.378788 -250.409202) (xy 344.373708 -250.412758)
			(xy 344.36558 -250.421394) (xy 344.351356 -250.44654) (xy 344.348262 -250.452357) (xy 344.344919 -250.465099)
			(xy 344.344752 -250.471686) (xy 344.344752 -250.964192) (xy 345.315298 -250.964192) (xy 345.319258 -250.915138)
			(xy 345.331035 -250.867354) (xy 345.350326 -250.822078) (xy 345.376629 -250.780482) (xy 345.409264 -250.743645)
			(xy 345.447385 -250.71252) (xy 345.490006 -250.687913) (xy 345.536022 -250.670461) (xy 345.584241 -250.660617)
			(xy 345.633416 -250.658636) (xy 345.682271 -250.664568) (xy 345.729542 -250.67826) (xy 345.774004 -250.699358)
			(xy 345.814507 -250.727314) (xy 345.85 -250.761406) (xy 345.879565 -250.80075) (xy 345.902436 -250.844327)
			(xy 345.91802 -250.891008) (xy 345.925915 -250.939585) (xy 345.92641 -250.964192) (xy 347.195406 -250.964192)
			(xy 347.199366 -250.915138) (xy 347.211143 -250.867354) (xy 347.230434 -250.822078) (xy 347.256737 -250.780482)
			(xy 347.289372 -250.743645) (xy 347.327493 -250.71252) (xy 347.370114 -250.687913) (xy 347.41613 -250.670461)
			(xy 347.464349 -250.660617) (xy 347.513524 -250.658636) (xy 347.562379 -250.664568) (xy 347.60965 -250.67826)
			(xy 347.654112 -250.699358) (xy 347.694615 -250.727314) (xy 347.730108 -250.761406) (xy 347.759673 -250.80075)
			(xy 347.782544 -250.844327) (xy 347.798128 -250.891008) (xy 347.806023 -250.939585) (xy 347.806518 -250.964192)
			(xy 347.806023 -250.988799) (xy 347.798128 -251.037376) (xy 347.782544 -251.084057) (xy 347.759673 -251.127634)
			(xy 347.730108 -251.166978) (xy 347.694615 -251.20107) (xy 347.654112 -251.229026) (xy 347.60965 -251.250124)
			(xy 347.562379 -251.263816) (xy 347.513524 -251.269748) (xy 347.464349 -251.267767) (xy 347.41613 -251.257923)
			(xy 347.370114 -251.240471) (xy 347.327493 -251.215864) (xy 347.289372 -251.184739) (xy 347.256737 -251.147902)
			(xy 347.230434 -251.106306) (xy 347.211143 -251.06103) (xy 347.199366 -251.013246) (xy 347.195406 -250.964192)
			(xy 345.92641 -250.964192) (xy 345.925915 -250.988799) (xy 345.91802 -251.037376) (xy 345.902436 -251.084057)
			(xy 345.879565 -251.127634) (xy 345.85 -251.166978) (xy 345.814507 -251.20107) (xy 345.774004 -251.229026)
			(xy 345.729542 -251.250124) (xy 345.682271 -251.263816) (xy 345.633416 -251.269748) (xy 345.584241 -251.267767)
			(xy 345.536022 -251.257923) (xy 345.490006 -251.240471) (xy 345.447385 -251.215864) (xy 345.409264 -251.184739)
			(xy 345.376629 -251.147902) (xy 345.350326 -251.106306) (xy 345.331035 -251.06103) (xy 345.319258 -251.013246)
			(xy 345.315298 -250.964192) (xy 344.344752 -250.964192) (xy 344.344752 -251.456698) (xy 344.344962 -251.463279)
			(xy 344.348305 -251.476009) (xy 344.351356 -251.481844) (xy 344.36558 -251.50699) (xy 344.373708 -251.515626)
			(xy 344.378788 -251.519182) (xy 344.399554 -251.533431) (xy 344.436544 -251.567604) (xy 344.467419 -251.607388)
			(xy 344.49134 -251.651703) (xy 344.507658 -251.699344) (xy 344.515929 -251.749019) (xy 344.515929 -251.774198)
			(xy 345.785198 -251.774198) (xy 345.789158 -251.725144) (xy 345.800935 -251.67736) (xy 345.820226 -251.632084)
			(xy 345.846529 -251.590488) (xy 345.879164 -251.553651) (xy 345.917285 -251.522526) (xy 345.959906 -251.497919)
			(xy 346.005922 -251.480467) (xy 346.054141 -251.470623) (xy 346.103316 -251.468642) (xy 346.152171 -251.474574)
			(xy 346.199442 -251.488266) (xy 346.243904 -251.509364) (xy 346.284407 -251.53732) (xy 346.3199 -251.571412)
			(xy 346.349465 -251.610756) (xy 346.372336 -251.654333) (xy 346.38792 -251.701014) (xy 346.395815 -251.749591)
			(xy 346.39631 -251.774198) (xy 347.665306 -251.774198) (xy 347.669266 -251.725144) (xy 347.681043 -251.67736)
			(xy 347.700334 -251.632084) (xy 347.726637 -251.590488) (xy 347.759272 -251.553651) (xy 347.797393 -251.522526)
			(xy 347.840014 -251.497919) (xy 347.88603 -251.480467) (xy 347.934249 -251.470623) (xy 347.983424 -251.468642)
			(xy 348.032279 -251.474574) (xy 348.07955 -251.488266) (xy 348.124012 -251.509364) (xy 348.164515 -251.53732)
			(xy 348.200008 -251.571412) (xy 348.229573 -251.610756) (xy 348.252444 -251.654333) (xy 348.268028 -251.701014)
			(xy 348.275923 -251.749591) (xy 348.276418 -251.774198) (xy 348.275923 -251.798805) (xy 348.268028 -251.847382)
			(xy 348.252444 -251.894063) (xy 348.229573 -251.93764) (xy 348.200008 -251.976984) (xy 348.164515 -252.011076)
			(xy 348.124012 -252.039032) (xy 348.07955 -252.06013) (xy 348.032279 -252.073822) (xy 347.983424 -252.079754)
			(xy 347.934249 -252.077773) (xy 347.88603 -252.067929) (xy 347.840014 -252.050477) (xy 347.797393 -252.02587)
			(xy 347.759272 -251.994745) (xy 347.726637 -251.957908) (xy 347.700334 -251.916312) (xy 347.681043 -251.871036)
			(xy 347.669266 -251.823252) (xy 347.665306 -251.774198) (xy 346.39631 -251.774198) (xy 346.395815 -251.798805)
			(xy 346.38792 -251.847382) (xy 346.372336 -251.894063) (xy 346.349465 -251.93764) (xy 346.3199 -251.976984)
			(xy 346.284407 -252.011076) (xy 346.243904 -252.039032) (xy 346.199442 -252.06013) (xy 346.152171 -252.073822)
			(xy 346.103316 -252.079754) (xy 346.054141 -252.077773) (xy 346.005922 -252.067929) (xy 345.959906 -252.050477)
			(xy 345.917285 -252.02587) (xy 345.879164 -251.994745) (xy 345.846529 -251.957908) (xy 345.820226 -251.916312)
			(xy 345.800935 -251.871036) (xy 345.789158 -251.823252) (xy 345.785198 -251.774198) (xy 344.515929 -251.774198)
			(xy 344.515929 -251.799378) (xy 344.507658 -251.849053) (xy 344.491341 -251.896695) (xy 344.46742 -251.94101)
			(xy 344.436546 -251.980795) (xy 344.399556 -252.014968) (xy 344.378788 -252.029214) (xy 344.373708 -252.03277)
			(xy 344.36558 -252.041406) (xy 344.351356 -252.066552) (xy 344.348263 -252.07237) (xy 344.344924 -252.085111)
			(xy 344.344752 -252.091698) (xy 344.344752 -252.584204) (xy 345.315298 -252.584204) (xy 345.319258 -252.53515)
			(xy 345.331035 -252.487366) (xy 345.350326 -252.44209) (xy 345.376629 -252.400494) (xy 345.409264 -252.363657)
			(xy 345.447385 -252.332532) (xy 345.490006 -252.307925) (xy 345.536022 -252.290473) (xy 345.584241 -252.280629)
			(xy 345.633416 -252.278648) (xy 345.682271 -252.28458) (xy 345.729542 -252.298272) (xy 345.774004 -252.31937)
			(xy 345.814507 -252.347326) (xy 345.85 -252.381418) (xy 345.879565 -252.420762) (xy 345.902436 -252.464339)
			(xy 345.91802 -252.51102) (xy 345.925915 -252.559597) (xy 345.92641 -252.584204) (xy 347.195406 -252.584204)
			(xy 347.199366 -252.53515) (xy 347.211143 -252.487366) (xy 347.230434 -252.44209) (xy 347.256737 -252.400494)
			(xy 347.289372 -252.363657) (xy 347.327493 -252.332532) (xy 347.370114 -252.307925) (xy 347.41613 -252.290473)
			(xy 347.464349 -252.280629) (xy 347.513524 -252.278648) (xy 347.562379 -252.28458) (xy 347.60965 -252.298272)
			(xy 347.654112 -252.31937) (xy 347.694615 -252.347326) (xy 347.730108 -252.381418) (xy 347.759673 -252.420762)
			(xy 347.782544 -252.464339) (xy 347.798128 -252.51102) (xy 347.806023 -252.559597) (xy 347.806518 -252.584204)
			(xy 349.07526 -252.584204) (xy 349.07922 -252.53515) (xy 349.090997 -252.487366) (xy 349.110288 -252.44209)
			(xy 349.136591 -252.400494) (xy 349.169226 -252.363657) (xy 349.207347 -252.332532) (xy 349.249968 -252.307925)
			(xy 349.295984 -252.290473) (xy 349.344203 -252.280629) (xy 349.393378 -252.278648) (xy 349.442233 -252.28458)
			(xy 349.489504 -252.298272) (xy 349.533966 -252.31937) (xy 349.574469 -252.347326) (xy 349.609962 -252.381418)
			(xy 349.639527 -252.420762) (xy 349.662398 -252.464339) (xy 349.677982 -252.51102) (xy 349.685877 -252.559597)
			(xy 349.686372 -252.584204) (xy 349.685877 -252.608811) (xy 349.677982 -252.657388) (xy 349.662398 -252.704069)
			(xy 349.639527 -252.747646) (xy 349.609962 -252.78699) (xy 349.574469 -252.821082) (xy 349.533966 -252.849038)
			(xy 349.489504 -252.870136) (xy 349.442233 -252.883828) (xy 349.393378 -252.88976) (xy 349.344203 -252.887779)
			(xy 349.295984 -252.877935) (xy 349.249968 -252.860483) (xy 349.207347 -252.835876) (xy 349.169226 -252.804751)
			(xy 349.136591 -252.767914) (xy 349.110288 -252.726318) (xy 349.090997 -252.681042) (xy 349.07922 -252.633258)
			(xy 349.07526 -252.584204) (xy 347.806518 -252.584204) (xy 347.806023 -252.608811) (xy 347.798128 -252.657388)
			(xy 347.782544 -252.704069) (xy 347.759673 -252.747646) (xy 347.730108 -252.78699) (xy 347.694615 -252.821082)
			(xy 347.654112 -252.849038) (xy 347.60965 -252.870136) (xy 347.562379 -252.883828) (xy 347.513524 -252.88976)
			(xy 347.464349 -252.887779) (xy 347.41613 -252.877935) (xy 347.370114 -252.860483) (xy 347.327493 -252.835876)
			(xy 347.289372 -252.804751) (xy 347.256737 -252.767914) (xy 347.230434 -252.726318) (xy 347.211143 -252.681042)
			(xy 347.199366 -252.633258) (xy 347.195406 -252.584204) (xy 345.92641 -252.584204) (xy 345.925915 -252.608811)
			(xy 345.91802 -252.657388) (xy 345.902436 -252.704069) (xy 345.879565 -252.747646) (xy 345.85 -252.78699)
			(xy 345.814507 -252.821082) (xy 345.774004 -252.849038) (xy 345.729542 -252.870136) (xy 345.682271 -252.883828)
			(xy 345.633416 -252.88976) (xy 345.584241 -252.887779) (xy 345.536022 -252.877935) (xy 345.490006 -252.860483)
			(xy 345.447385 -252.835876) (xy 345.409264 -252.804751) (xy 345.376629 -252.767914) (xy 345.350326 -252.726318)
			(xy 345.331035 -252.681042) (xy 345.319258 -252.633258) (xy 345.315298 -252.584204) (xy 344.344752 -252.584204)
			(xy 344.344752 -253.07671) (xy 344.344963 -253.08329) (xy 344.34831 -253.096019) (xy 344.351356 -253.101856)
			(xy 344.36558 -253.127002) (xy 344.373708 -253.135638) (xy 344.378788 -253.139194) (xy 344.399554 -253.153443)
			(xy 344.436541 -253.187615) (xy 344.467414 -253.227399) (xy 344.491333 -253.271713) (xy 344.50765 -253.319353)
			(xy 344.51592 -253.369027) (xy 344.515919 -253.39421) (xy 345.785198 -253.39421) (xy 345.789158 -253.345156)
			(xy 345.800935 -253.297372) (xy 345.820226 -253.252096) (xy 345.846529 -253.2105) (xy 345.879164 -253.173663)
			(xy 345.917285 -253.142538) (xy 345.959906 -253.117931) (xy 346.005922 -253.100479) (xy 346.054141 -253.090635)
			(xy 346.103316 -253.088654) (xy 346.152171 -253.094586) (xy 346.199442 -253.108278) (xy 346.243904 -253.129376)
			(xy 346.284407 -253.157332) (xy 346.3199 -253.191424) (xy 346.349465 -253.230768) (xy 346.372336 -253.274345)
			(xy 346.38792 -253.321026) (xy 346.395815 -253.369603) (xy 346.39631 -253.39421) (xy 347.665306 -253.39421)
			(xy 347.669266 -253.345156) (xy 347.681043 -253.297372) (xy 347.700334 -253.252096) (xy 347.726637 -253.2105)
			(xy 347.759272 -253.173663) (xy 347.797393 -253.142538) (xy 347.840014 -253.117931) (xy 347.88603 -253.100479)
			(xy 347.934249 -253.090635) (xy 347.983424 -253.088654) (xy 348.032279 -253.094586) (xy 348.07955 -253.108278)
			(xy 348.124012 -253.129376) (xy 348.164515 -253.157332) (xy 348.200008 -253.191424) (xy 348.229573 -253.230768)
			(xy 348.252444 -253.274345) (xy 348.268028 -253.321026) (xy 348.275923 -253.369603) (xy 348.276418 -253.39421)
			(xy 348.60536 -253.39421) (xy 348.60932 -253.345156) (xy 348.621097 -253.297372) (xy 348.640388 -253.252096)
			(xy 348.666691 -253.2105) (xy 348.699326 -253.173663) (xy 348.737447 -253.142538) (xy 348.780068 -253.117931)
			(xy 348.826084 -253.100479) (xy 348.874303 -253.090635) (xy 348.923478 -253.088654) (xy 348.972333 -253.094586)
			(xy 349.019604 -253.108278) (xy 349.064066 -253.129376) (xy 349.104569 -253.157332) (xy 349.140062 -253.191424)
			(xy 349.169627 -253.230768) (xy 349.192498 -253.274345) (xy 349.208082 -253.321026) (xy 349.215977 -253.369603)
			(xy 349.216472 -253.39421) (xy 349.545414 -253.39421) (xy 349.549374 -253.345156) (xy 349.561151 -253.297372)
			(xy 349.580442 -253.252096) (xy 349.606745 -253.2105) (xy 349.63938 -253.173663) (xy 349.677501 -253.142538)
			(xy 349.720122 -253.117931) (xy 349.766138 -253.100479) (xy 349.814357 -253.090635) (xy 349.863532 -253.088654)
			(xy 349.912387 -253.094586) (xy 349.959658 -253.108278) (xy 350.00412 -253.129376) (xy 350.044623 -253.157332)
			(xy 350.080116 -253.191424) (xy 350.109681 -253.230768) (xy 350.132552 -253.274345) (xy 350.148136 -253.321026)
			(xy 350.156031 -253.369603) (xy 350.156526 -253.39421) (xy 350.156031 -253.418817) (xy 350.148136 -253.467394)
			(xy 350.132552 -253.514075) (xy 350.109681 -253.557652) (xy 350.080116 -253.596996) (xy 350.044623 -253.631088)
			(xy 350.00412 -253.659044) (xy 349.959658 -253.680142) (xy 349.912387 -253.693834) (xy 349.863532 -253.699766)
			(xy 349.814357 -253.697785) (xy 349.766138 -253.687941) (xy 349.720122 -253.670489) (xy 349.677501 -253.645882)
			(xy 349.63938 -253.614757) (xy 349.606745 -253.57792) (xy 349.580442 -253.536324) (xy 349.561151 -253.491048)
			(xy 349.549374 -253.443264) (xy 349.545414 -253.39421) (xy 349.216472 -253.39421) (xy 349.215977 -253.418817)
			(xy 349.208082 -253.467394) (xy 349.192498 -253.514075) (xy 349.169627 -253.557652) (xy 349.140062 -253.596996)
			(xy 349.104569 -253.631088) (xy 349.064066 -253.659044) (xy 349.019604 -253.680142) (xy 348.972333 -253.693834)
			(xy 348.923478 -253.699766) (xy 348.874303 -253.697785) (xy 348.826084 -253.687941) (xy 348.780068 -253.670489)
			(xy 348.737447 -253.645882) (xy 348.699326 -253.614757) (xy 348.666691 -253.57792) (xy 348.640388 -253.536324)
			(xy 348.621097 -253.491048) (xy 348.60932 -253.443264) (xy 348.60536 -253.39421) (xy 348.276418 -253.39421)
			(xy 348.275923 -253.418817) (xy 348.268028 -253.467394) (xy 348.252444 -253.514075) (xy 348.229573 -253.557652)
			(xy 348.200008 -253.596996) (xy 348.164515 -253.631088) (xy 348.124012 -253.659044) (xy 348.07955 -253.680142)
			(xy 348.032279 -253.693834) (xy 347.983424 -253.699766) (xy 347.934249 -253.697785) (xy 347.88603 -253.687941)
			(xy 347.840014 -253.670489) (xy 347.797393 -253.645882) (xy 347.759272 -253.614757) (xy 347.726637 -253.57792)
			(xy 347.700334 -253.536324) (xy 347.681043 -253.491048) (xy 347.669266 -253.443264) (xy 347.665306 -253.39421)
			(xy 346.39631 -253.39421) (xy 346.395815 -253.418817) (xy 346.38792 -253.467394) (xy 346.372336 -253.514075)
			(xy 346.349465 -253.557652) (xy 346.3199 -253.596996) (xy 346.284407 -253.631088) (xy 346.243904 -253.659044)
			(xy 346.199442 -253.680142) (xy 346.152171 -253.693834) (xy 346.103316 -253.699766) (xy 346.054141 -253.697785)
			(xy 346.005922 -253.687941) (xy 345.959906 -253.670489) (xy 345.917285 -253.645882) (xy 345.879164 -253.614757)
			(xy 345.846529 -253.57792) (xy 345.820226 -253.536324) (xy 345.800935 -253.491048) (xy 345.789158 -253.443264)
			(xy 345.785198 -253.39421) (xy 344.515919 -253.39421) (xy 344.515919 -253.419384) (xy 344.507647 -253.469057)
			(xy 344.491329 -253.516697) (xy 344.467408 -253.56101) (xy 344.436534 -253.600793) (xy 344.399545 -253.634964)
			(xy 344.378788 -253.649226) (xy 344.373708 -253.652782) (xy 344.36558 -253.661418) (xy 344.351356 -253.686564)
			(xy 344.348264 -253.692382) (xy 344.344928 -253.705123) (xy 344.344752 -253.71171) (xy 344.344752 -254.204216)
			(xy 345.315298 -254.204216) (xy 345.319258 -254.155162) (xy 345.331035 -254.107378) (xy 345.350326 -254.062102)
			(xy 345.376629 -254.020506) (xy 345.409264 -253.983669) (xy 345.447385 -253.952544) (xy 345.490006 -253.927937)
			(xy 345.536022 -253.910485) (xy 345.584241 -253.900641) (xy 345.633416 -253.89866) (xy 345.682271 -253.904592)
			(xy 345.729542 -253.918284) (xy 345.774004 -253.939382) (xy 345.814507 -253.967338) (xy 345.85 -254.00143)
			(xy 345.879565 -254.040774) (xy 345.902436 -254.084351) (xy 345.91802 -254.131032) (xy 345.925915 -254.179609)
			(xy 345.92641 -254.204216) (xy 347.195406 -254.204216) (xy 347.199366 -254.155162) (xy 347.211143 -254.107378)
			(xy 347.230434 -254.062102) (xy 347.256737 -254.020506) (xy 347.289372 -253.983669) (xy 347.327493 -253.952544)
			(xy 347.370114 -253.927937) (xy 347.41613 -253.910485) (xy 347.464349 -253.900641) (xy 347.513524 -253.89866)
			(xy 347.562379 -253.904592) (xy 347.60965 -253.918284) (xy 347.654112 -253.939382) (xy 347.694615 -253.967338)
			(xy 347.730108 -254.00143) (xy 347.759673 -254.040774) (xy 347.782544 -254.084351) (xy 347.798128 -254.131032)
			(xy 347.806023 -254.179609) (xy 347.806518 -254.204216) (xy 349.07526 -254.204216) (xy 349.07922 -254.155162)
			(xy 349.090997 -254.107378) (xy 349.110288 -254.062102) (xy 349.136591 -254.020506) (xy 349.169226 -253.983669)
			(xy 349.207347 -253.952544) (xy 349.249968 -253.927937) (xy 349.295984 -253.910485) (xy 349.344203 -253.900641)
			(xy 349.393378 -253.89866) (xy 349.442233 -253.904592) (xy 349.489504 -253.918284) (xy 349.533966 -253.939382)
			(xy 349.574469 -253.967338) (xy 349.609962 -254.00143) (xy 349.639527 -254.040774) (xy 349.662398 -254.084351)
			(xy 349.677982 -254.131032) (xy 349.685877 -254.179609) (xy 349.686372 -254.204216) (xy 350.015314 -254.204216)
			(xy 350.019274 -254.155162) (xy 350.031051 -254.107378) (xy 350.050342 -254.062102) (xy 350.076645 -254.020506)
			(xy 350.10928 -253.983669) (xy 350.147401 -253.952544) (xy 350.190022 -253.927937) (xy 350.236038 -253.910485)
			(xy 350.284257 -253.900641) (xy 350.333432 -253.89866) (xy 350.382287 -253.904592) (xy 350.429558 -253.918284)
			(xy 350.47402 -253.939382) (xy 350.514523 -253.967338) (xy 350.550016 -254.00143) (xy 350.579581 -254.040774)
			(xy 350.602452 -254.084351) (xy 350.618036 -254.131032) (xy 350.625931 -254.179609) (xy 350.626426 -254.204216)
			(xy 350.625931 -254.228823) (xy 350.618036 -254.2774) (xy 350.602452 -254.324081) (xy 350.579581 -254.367658)
			(xy 350.550016 -254.407002) (xy 350.514523 -254.441094) (xy 350.47402 -254.46905) (xy 350.429558 -254.490148)
			(xy 350.382287 -254.50384) (xy 350.333432 -254.509772) (xy 350.284257 -254.507791) (xy 350.236038 -254.497947)
			(xy 350.190022 -254.480495) (xy 350.147401 -254.455888) (xy 350.10928 -254.424763) (xy 350.076645 -254.387926)
			(xy 350.050342 -254.34633) (xy 350.031051 -254.301054) (xy 350.019274 -254.25327) (xy 350.015314 -254.204216)
			(xy 349.686372 -254.204216) (xy 349.685877 -254.228823) (xy 349.677982 -254.2774) (xy 349.662398 -254.324081)
			(xy 349.639527 -254.367658) (xy 349.609962 -254.407002) (xy 349.574469 -254.441094) (xy 349.533966 -254.46905)
			(xy 349.489504 -254.490148) (xy 349.442233 -254.50384) (xy 349.393378 -254.509772) (xy 349.344203 -254.507791)
			(xy 349.295984 -254.497947) (xy 349.249968 -254.480495) (xy 349.207347 -254.455888) (xy 349.169226 -254.424763)
			(xy 349.136591 -254.387926) (xy 349.110288 -254.34633) (xy 349.090997 -254.301054) (xy 349.07922 -254.25327)
			(xy 349.07526 -254.204216) (xy 347.806518 -254.204216) (xy 347.806023 -254.228823) (xy 347.798128 -254.2774)
			(xy 347.782544 -254.324081) (xy 347.759673 -254.367658) (xy 347.730108 -254.407002) (xy 347.694615 -254.441094)
			(xy 347.654112 -254.46905) (xy 347.60965 -254.490148) (xy 347.562379 -254.50384) (xy 347.513524 -254.509772)
			(xy 347.464349 -254.507791) (xy 347.41613 -254.497947) (xy 347.370114 -254.480495) (xy 347.327493 -254.455888)
			(xy 347.289372 -254.424763) (xy 347.256737 -254.387926) (xy 347.230434 -254.34633) (xy 347.211143 -254.301054)
			(xy 347.199366 -254.25327) (xy 347.195406 -254.204216) (xy 345.92641 -254.204216) (xy 345.925915 -254.228823)
			(xy 345.91802 -254.2774) (xy 345.902436 -254.324081) (xy 345.879565 -254.367658) (xy 345.85 -254.407002)
			(xy 345.814507 -254.441094) (xy 345.774004 -254.46905) (xy 345.729542 -254.490148) (xy 345.682271 -254.50384)
			(xy 345.633416 -254.509772) (xy 345.584241 -254.507791) (xy 345.536022 -254.497947) (xy 345.490006 -254.480495)
			(xy 345.447385 -254.455888) (xy 345.409264 -254.424763) (xy 345.376629 -254.387926) (xy 345.350326 -254.34633)
			(xy 345.331035 -254.301054) (xy 345.319258 -254.25327) (xy 345.315298 -254.204216) (xy 344.344752 -254.204216)
			(xy 344.344752 -254.696722) (xy 344.344965 -254.703302) (xy 344.348314 -254.716029) (xy 344.351356 -254.721868)
			(xy 344.36558 -254.747014) (xy 344.373708 -254.75565) (xy 344.378788 -254.759206) (xy 344.399553 -254.773455)
			(xy 344.436538 -254.807627) (xy 344.467409 -254.84741) (xy 344.491327 -254.891723) (xy 344.507641 -254.939362)
			(xy 344.51591 -254.989034) (xy 344.515909 -255.014222) (xy 345.785198 -255.014222) (xy 345.789158 -254.965168)
			(xy 345.800935 -254.917384) (xy 345.820226 -254.872108) (xy 345.846529 -254.830512) (xy 345.879164 -254.793675)
			(xy 345.917285 -254.76255) (xy 345.959906 -254.737943) (xy 346.005922 -254.720491) (xy 346.054141 -254.710647)
			(xy 346.103316 -254.708666) (xy 346.152171 -254.714598) (xy 346.199442 -254.72829) (xy 346.243904 -254.749388)
			(xy 346.284407 -254.777344) (xy 346.3199 -254.811436) (xy 346.349465 -254.85078) (xy 346.372336 -254.894357)
			(xy 346.38792 -254.941038) (xy 346.395815 -254.989615) (xy 346.39631 -255.014222) (xy 347.665306 -255.014222)
			(xy 347.669266 -254.965168) (xy 347.681043 -254.917384) (xy 347.700334 -254.872108) (xy 347.726637 -254.830512)
			(xy 347.759272 -254.793675) (xy 347.797393 -254.76255) (xy 347.840014 -254.737943) (xy 347.88603 -254.720491)
			(xy 347.934249 -254.710647) (xy 347.983424 -254.708666) (xy 348.032279 -254.714598) (xy 348.07955 -254.72829)
			(xy 348.124012 -254.749388) (xy 348.164515 -254.777344) (xy 348.200008 -254.811436) (xy 348.229573 -254.85078)
			(xy 348.252444 -254.894357) (xy 348.268028 -254.941038) (xy 348.275923 -254.989615) (xy 348.276418 -255.014222)
			(xy 348.60536 -255.014222) (xy 348.60932 -254.965168) (xy 348.621097 -254.917384) (xy 348.640388 -254.872108)
			(xy 348.666691 -254.830512) (xy 348.699326 -254.793675) (xy 348.737447 -254.76255) (xy 348.780068 -254.737943)
			(xy 348.826084 -254.720491) (xy 348.874303 -254.710647) (xy 348.923478 -254.708666) (xy 348.972333 -254.714598)
			(xy 349.019604 -254.72829) (xy 349.064066 -254.749388) (xy 349.104569 -254.777344) (xy 349.140062 -254.811436)
			(xy 349.169627 -254.85078) (xy 349.192498 -254.894357) (xy 349.208082 -254.941038) (xy 349.215977 -254.989615)
			(xy 349.216472 -255.014222) (xy 349.545414 -255.014222) (xy 349.549374 -254.965168) (xy 349.561151 -254.917384)
			(xy 349.580442 -254.872108) (xy 349.606745 -254.830512) (xy 349.63938 -254.793675) (xy 349.677501 -254.76255)
			(xy 349.720122 -254.737943) (xy 349.766138 -254.720491) (xy 349.814357 -254.710647) (xy 349.863532 -254.708666)
			(xy 349.912387 -254.714598) (xy 349.959658 -254.72829) (xy 350.00412 -254.749388) (xy 350.044623 -254.777344)
			(xy 350.080116 -254.811436) (xy 350.109681 -254.85078) (xy 350.132552 -254.894357) (xy 350.148136 -254.941038)
			(xy 350.156031 -254.989615) (xy 350.156526 -255.014222) (xy 350.156031 -255.038829) (xy 350.148136 -255.087406)
			(xy 350.132552 -255.134087) (xy 350.109681 -255.177664) (xy 350.080116 -255.217008) (xy 350.044623 -255.2511)
			(xy 350.00412 -255.279056) (xy 349.959658 -255.300154) (xy 349.912387 -255.313846) (xy 349.863532 -255.319778)
			(xy 349.814357 -255.317797) (xy 349.766138 -255.307953) (xy 349.720122 -255.290501) (xy 349.677501 -255.265894)
			(xy 349.63938 -255.234769) (xy 349.606745 -255.197932) (xy 349.580442 -255.156336) (xy 349.561151 -255.11106)
			(xy 349.549374 -255.063276) (xy 349.545414 -255.014222) (xy 349.216472 -255.014222) (xy 349.215977 -255.038829)
			(xy 349.208082 -255.087406) (xy 349.192498 -255.134087) (xy 349.169627 -255.177664) (xy 349.140062 -255.217008)
			(xy 349.104569 -255.2511) (xy 349.064066 -255.279056) (xy 349.019604 -255.300154) (xy 348.972333 -255.313846)
			(xy 348.923478 -255.319778) (xy 348.874303 -255.317797) (xy 348.826084 -255.307953) (xy 348.780068 -255.290501)
			(xy 348.737447 -255.265894) (xy 348.699326 -255.234769) (xy 348.666691 -255.197932) (xy 348.640388 -255.156336)
			(xy 348.621097 -255.11106) (xy 348.60932 -255.063276) (xy 348.60536 -255.014222) (xy 348.276418 -255.014222)
			(xy 348.275923 -255.038829) (xy 348.268028 -255.087406) (xy 348.252444 -255.134087) (xy 348.229573 -255.177664)
			(xy 348.200008 -255.217008) (xy 348.164515 -255.2511) (xy 348.124012 -255.279056) (xy 348.07955 -255.300154)
			(xy 348.032279 -255.313846) (xy 347.983424 -255.319778) (xy 347.934249 -255.317797) (xy 347.88603 -255.307953)
			(xy 347.840014 -255.290501) (xy 347.797393 -255.265894) (xy 347.759272 -255.234769) (xy 347.726637 -255.197932)
			(xy 347.700334 -255.156336) (xy 347.681043 -255.11106) (xy 347.669266 -255.063276) (xy 347.665306 -255.014222)
			(xy 346.39631 -255.014222) (xy 346.395815 -255.038829) (xy 346.38792 -255.087406) (xy 346.372336 -255.134087)
			(xy 346.349465 -255.177664) (xy 346.3199 -255.217008) (xy 346.284407 -255.2511) (xy 346.243904 -255.279056)
			(xy 346.199442 -255.300154) (xy 346.152171 -255.313846) (xy 346.103316 -255.319778) (xy 346.054141 -255.317797)
			(xy 346.005922 -255.307953) (xy 345.959906 -255.290501) (xy 345.917285 -255.265894) (xy 345.879164 -255.234769)
			(xy 345.846529 -255.197932) (xy 345.820226 -255.156336) (xy 345.800935 -255.11106) (xy 345.789158 -255.063276)
			(xy 345.785198 -255.014222) (xy 344.515909 -255.014222) (xy 344.515908 -255.03939) (xy 344.507636 -255.089061)
			(xy 344.491317 -255.136699) (xy 344.467396 -255.181011) (xy 344.436522 -255.220791) (xy 344.399533 -255.25496)
			(xy 344.378788 -255.269238) (xy 344.373708 -255.272794) (xy 344.36558 -255.28143) (xy 344.351356 -255.306576)
			(xy 344.348266 -255.312394) (xy 344.344933 -255.325136) (xy 344.344752 -255.331722) (xy 344.344752 -255.951228)
			(xy 344.345182 -255.961295) (xy 344.352909 -255.979887) (xy 344.359738 -255.987296) (xy 344.456766 -256.084324)
			(xy 344.464164 -256.091168) (xy 344.482764 -256.09889) (xy 344.492834 -256.09931) (xy 345.255088 -256.09931)
			(xy 345.263646 -256.098923) (xy 345.279778 -256.093188) (xy 345.29314 -256.082481) (xy 345.298014 -256.075434)
			(xy 345.34983 -255.993392) (xy 345.3511 -255.967484) (xy 345.345512 -255.955546) (xy 345.336141 -255.934936)
			(xy 345.322908 -255.89164) (xy 345.316216 -255.846864) (xy 345.315794 -255.824228) (xy 345.316316 -255.798973)
			(xy 345.324629 -255.749151) (xy 345.34103 -255.701377) (xy 345.365071 -255.656954) (xy 345.396095 -255.617094)
			(xy 345.433257 -255.582884) (xy 345.475543 -255.555258) (xy 345.521799 -255.534968) (xy 345.570764 -255.522568)
			(xy 345.621102 -255.518397) (xy 345.67144 -255.522568) (xy 345.720405 -255.534968) (xy 345.766661 -255.555258)
			(xy 345.808947 -255.582884) (xy 345.846109 -255.617094) (xy 345.877133 -255.656954) (xy 345.901174 -255.701377)
			(xy 345.917575 -255.749151) (xy 345.925888 -255.798973) (xy 345.92641 -255.824228) (xy 345.925995 -255.846864)
			(xy 345.919297 -255.891639) (xy 345.906052 -255.934931) (xy 345.896692 -255.955546) (xy 345.891104 -255.967484)
			(xy 345.892374 -255.993392) (xy 345.94419 -256.075434) (xy 345.948998 -256.08254) (xy 345.962367 -256.093279)
			(xy 345.978542 -256.098969) (xy 345.987116 -256.09931) (xy 347.135196 -256.09931) (xy 347.143762 -256.098937)
			(xy 347.159916 -256.093222) (xy 347.173301 -256.082523) (xy 347.178122 -256.075434) (xy 347.229938 -255.993392)
			(xy 347.231208 -255.967484) (xy 347.22562 -255.955546) (xy 347.216249 -255.934936) (xy 347.203016 -255.89164)
			(xy 347.196323 -255.846865) (xy 347.195902 -255.824228) (xy 347.196424 -255.798973) (xy 347.204737 -255.749151)
			(xy 347.221138 -255.701377) (xy 347.245179 -255.656954) (xy 347.276203 -255.617094) (xy 347.313365 -255.582884)
			(xy 347.355651 -255.555258) (xy 347.401907 -255.534968) (xy 347.450872 -255.522568) (xy 347.50121 -255.518397)
			(xy 347.551548 -255.522568) (xy 347.600513 -255.534968) (xy 347.646769 -255.555258) (xy 347.689055 -255.582884)
			(xy 347.726217 -255.617094) (xy 347.757241 -255.656954) (xy 347.781282 -255.701377) (xy 347.797683 -255.749151)
			(xy 347.805996 -255.798973) (xy 347.806518 -255.824228) (xy 347.806103 -255.846864) (xy 347.799405 -255.891639)
			(xy 347.78616 -255.934931) (xy 347.7768 -255.955546) (xy 347.771212 -255.967484) (xy 347.772482 -255.993392)
			(xy 347.824298 -256.075434) (xy 347.829107 -256.082539) (xy 347.842475 -256.093276) (xy 347.858651 -256.098963)
			(xy 347.867224 -256.09931) (xy 348.074996 -256.09931) (xy 348.083562 -256.098937) (xy 348.099716 -256.093222)
			(xy 348.113101 -256.082523) (xy 348.117922 -256.075434) (xy 348.169738 -255.993392) (xy 348.171008 -255.967484)
			(xy 348.16542 -255.955546) (xy 348.156049 -255.934936) (xy 348.142816 -255.89164) (xy 348.136123 -255.846865)
			(xy 348.135702 -255.824228) (xy 348.136224 -255.798973) (xy 348.144537 -255.749151) (xy 348.160938 -255.701377)
			(xy 348.184979 -255.656954) (xy 348.216003 -255.617094) (xy 348.253165 -255.582884) (xy 348.295451 -255.555258)
			(xy 348.341707 -255.534968) (xy 348.390672 -255.522568) (xy 348.44101 -255.518397) (xy 348.491348 -255.522568)
			(xy 348.540313 -255.534968) (xy 348.586569 -255.555258) (xy 348.628855 -255.582884) (xy 348.666017 -255.617094)
			(xy 348.697041 -255.656954) (xy 348.721082 -255.701377) (xy 348.737483 -255.749151) (xy 348.745796 -255.798973)
			(xy 348.746318 -255.824228) (xy 349.07526 -255.824228) (xy 349.07922 -255.775174) (xy 349.090997 -255.72739)
			(xy 349.110288 -255.682114) (xy 349.136591 -255.640518) (xy 349.169226 -255.603681) (xy 349.207347 -255.572556)
			(xy 349.249968 -255.547949) (xy 349.295984 -255.530497) (xy 349.344203 -255.520653) (xy 349.393378 -255.518672)
			(xy 349.442233 -255.524604) (xy 349.489504 -255.538296) (xy 349.533966 -255.559394) (xy 349.574469 -255.58735)
			(xy 349.609962 -255.621442) (xy 349.639527 -255.660786) (xy 349.662398 -255.704363) (xy 349.677982 -255.751044)
			(xy 349.685877 -255.799621) (xy 349.686372 -255.824228) (xy 350.015314 -255.824228) (xy 350.019274 -255.775174)
			(xy 350.031051 -255.72739) (xy 350.050342 -255.682114) (xy 350.076645 -255.640518) (xy 350.10928 -255.603681)
			(xy 350.147401 -255.572556) (xy 350.190022 -255.547949) (xy 350.236038 -255.530497) (xy 350.284257 -255.520653)
			(xy 350.333432 -255.518672) (xy 350.382287 -255.524604) (xy 350.429558 -255.538296) (xy 350.47402 -255.559394)
			(xy 350.514523 -255.58735) (xy 350.550016 -255.621442) (xy 350.579581 -255.660786) (xy 350.602452 -255.704363)
			(xy 350.618036 -255.751044) (xy 350.625931 -255.799621) (xy 350.626385 -255.822196) (xy 350.952066 -255.822196)
			(xy 350.956026 -255.773142) (xy 350.967803 -255.725358) (xy 350.987094 -255.680082) (xy 351.013397 -255.638486)
			(xy 351.046032 -255.601649) (xy 351.084153 -255.570524) (xy 351.126774 -255.545917) (xy 351.17279 -255.528465)
			(xy 351.221009 -255.518621) (xy 351.270184 -255.51664) (xy 351.319039 -255.522572) (xy 351.36631 -255.536264)
			(xy 351.410772 -255.557362) (xy 351.451275 -255.585318) (xy 351.486768 -255.61941) (xy 351.516333 -255.658754)
			(xy 351.539204 -255.702331) (xy 351.554788 -255.749012) (xy 351.562683 -255.797589) (xy 351.563178 -255.822196)
			(xy 351.89212 -255.822196) (xy 351.89608 -255.773142) (xy 351.907857 -255.725358) (xy 351.927148 -255.680082)
			(xy 351.953451 -255.638486) (xy 351.986086 -255.601649) (xy 352.024207 -255.570524) (xy 352.066828 -255.545917)
			(xy 352.112844 -255.528465) (xy 352.161063 -255.518621) (xy 352.210238 -255.51664) (xy 352.259093 -255.522572)
			(xy 352.306364 -255.536264) (xy 352.350826 -255.557362) (xy 352.391329 -255.585318) (xy 352.426822 -255.61941)
			(xy 352.456387 -255.658754) (xy 352.479258 -255.702331) (xy 352.494842 -255.749012) (xy 352.502737 -255.797589)
			(xy 352.503232 -255.822196) (xy 352.502737 -255.846803) (xy 352.494842 -255.89538) (xy 352.479258 -255.942061)
			(xy 352.456387 -255.985638) (xy 352.426822 -256.024982) (xy 352.391329 -256.059074) (xy 352.350826 -256.08703)
			(xy 352.306364 -256.108128) (xy 352.259093 -256.12182) (xy 352.210238 -256.127752) (xy 352.161063 -256.125771)
			(xy 352.112844 -256.115927) (xy 352.066828 -256.098475) (xy 352.024207 -256.073868) (xy 351.986086 -256.042743)
			(xy 351.953451 -256.005906) (xy 351.927148 -255.96431) (xy 351.907857 -255.919034) (xy 351.89608 -255.87125)
			(xy 351.89212 -255.822196) (xy 351.563178 -255.822196) (xy 351.562683 -255.846803) (xy 351.554788 -255.89538)
			(xy 351.539204 -255.942061) (xy 351.516333 -255.985638) (xy 351.486768 -256.024982) (xy 351.451275 -256.059074)
			(xy 351.410772 -256.08703) (xy 351.36631 -256.108128) (xy 351.319039 -256.12182) (xy 351.270184 -256.127752)
			(xy 351.221009 -256.125771) (xy 351.17279 -256.115927) (xy 351.126774 -256.098475) (xy 351.084153 -256.073868)
			(xy 351.046032 -256.042743) (xy 351.013397 -256.005906) (xy 350.987094 -255.96431) (xy 350.967803 -255.919034)
			(xy 350.956026 -255.87125) (xy 350.952066 -255.822196) (xy 350.626385 -255.822196) (xy 350.626426 -255.824228)
			(xy 350.625931 -255.848835) (xy 350.618036 -255.897412) (xy 350.602452 -255.944093) (xy 350.579581 -255.98767)
			(xy 350.550016 -256.027014) (xy 350.514523 -256.061106) (xy 350.47402 -256.089062) (xy 350.429558 -256.11016)
			(xy 350.382287 -256.123852) (xy 350.333432 -256.129784) (xy 350.284257 -256.127803) (xy 350.236038 -256.117959)
			(xy 350.190022 -256.100507) (xy 350.147401 -256.0759) (xy 350.10928 -256.044775) (xy 350.076645 -256.007938)
			(xy 350.050342 -255.966342) (xy 350.031051 -255.921066) (xy 350.019274 -255.873282) (xy 350.015314 -255.824228)
			(xy 349.686372 -255.824228) (xy 349.685877 -255.848835) (xy 349.677982 -255.897412) (xy 349.662398 -255.944093)
			(xy 349.639527 -255.98767) (xy 349.609962 -256.027014) (xy 349.574469 -256.061106) (xy 349.533966 -256.089062)
			(xy 349.489504 -256.11016) (xy 349.442233 -256.123852) (xy 349.393378 -256.129784) (xy 349.344203 -256.127803)
			(xy 349.295984 -256.117959) (xy 349.249968 -256.100507) (xy 349.207347 -256.0759) (xy 349.169226 -256.044775)
			(xy 349.136591 -256.007938) (xy 349.110288 -255.966342) (xy 349.090997 -255.921066) (xy 349.07922 -255.873282)
			(xy 349.07526 -255.824228) (xy 348.746318 -255.824228) (xy 348.745807 -255.849443) (xy 348.737534 -255.899191)
			(xy 348.721201 -255.946904) (xy 348.697252 -255.991285) (xy 348.666337 -256.031129) (xy 348.629297 -256.065353)
			(xy 348.587138 -256.093028) (xy 348.541006 -256.1134) (xy 348.516702 -256.120138) (xy 348.50324 -256.12344)
			(xy 348.483936 -256.142744) (xy 348.45752 -256.23901) (xy 348.455586 -256.247733) (xy 348.457147 -256.265517)
			(xy 348.464695 -256.281695) (xy 348.470728 -256.288286) (xy 348.57817 -256.395728) (xy 348.585158 -256.402122)
			(xy 348.602512 -256.40968) (xy 348.611952 -256.41046) (xy 348.68866 -256.413508) (xy 348.706694 -256.407412)
			(xy 348.71406 -256.401062) (xy 348.734891 -256.384189) (xy 348.781242 -256.357267) (xy 348.831581 -256.33885)
			(xy 348.884363 -256.329503) (xy 348.911164 -256.328926) (xy 348.935158 -256.32937) (xy 348.982556 -256.336872)
			(xy 349.028196 -256.351698) (xy 349.070955 -256.373482) (xy 349.109779 -256.401687) (xy 349.143711 -256.43562)
			(xy 349.171917 -256.474443) (xy 349.193701 -256.517202) (xy 349.208528 -256.562842) (xy 349.21603 -256.61024)
			(xy 349.216472 -256.634234) (xy 349.216004 -256.658464) (xy 349.208343 -256.706316) (xy 349.201232 -256.729484)
			(xy 349.197422 -256.741168) (xy 349.201232 -256.765298) (xy 349.255334 -256.840228) (xy 349.262942 -256.849616)
			(xy 349.284418 -256.860623) (xy 349.296482 -256.86131)
		)
		(stroke
			(width 0)
			(type solid)
		)
		(fill yes)
		(layer "In2.Cu")
		(net "PVDD18_S5_P0")
	)
	(gr_poly
		(pts
			(xy 71.87311 -25.996392) (xy 71.877521 -25.996307) (xy 71.88621 -25.994778) (xy 71.890382 -25.993344)
			(xy 71.914258 -25.984708) (xy 71.920862 -25.979374) (xy 71.951616 -25.955101) (xy 72.016681 -25.911446)
			(xy 72.085334 -25.873684) (xy 72.157042 -25.842108) (xy 72.231251 -25.816964) (xy 72.307384 -25.798445)
			(xy 72.346058 -25.792176) (xy 72.379255 -25.78743) (xy 72.446129 -25.782346) (xy 72.479662 -25.782016)
			(xy 72.518874 -25.78246) (xy 72.596992 -25.78939) (xy 72.674197 -25.803166) (xy 72.74989 -25.823681)
			(xy 72.823486 -25.850774) (xy 72.859138 -25.867106) (xy 72.864218 -25.869392) (xy 72.874886 -25.871678)
			(xy 72.880422 -25.87277) (xy 72.891702 -25.87277) (xy 72.897238 -25.871678) (xy 72.907906 -25.869392)
			(xy 72.912986 -25.867106) (xy 72.948629 -25.850752) (xy 73.022223 -25.823645) (xy 73.097918 -25.803128)
			(xy 73.175127 -25.78936) (xy 73.253249 -25.782447) (xy 73.292462 -25.782016) (xy 73.335627 -25.782525)
			(xy 73.42155 -25.790882) (xy 73.506261 -25.807522) (xy 73.588961 -25.832287) (xy 73.668874 -25.864946)
			(xy 73.745249 -25.905191) (xy 73.817366 -25.952644) (xy 73.851262 -25.979374) (xy 73.857866 -25.984708)
			(xy 73.881742 -25.993344) (xy 73.885921 -25.994754) (xy 73.894605 -25.996287) (xy 73.899014 -25.996392)
			(xy 77.646276 -25.996392) (xy 77.656148 -25.995921) (xy 77.674431 -25.988462) (xy 77.681836 -25.981914)
			(xy 77.68209 -25.98166) (xy 78.28661 -25.37714) (xy 78.293472 -25.369635) (xy 78.301138 -25.350818)
			(xy 78.30092 -25.3305) (xy 78.297278 -25.321006) (xy 78.25359 -25.219914) (xy 78.227428 -25.203404)
			(xy 78.21168 -25.203658) (xy 78.185264 -25.204166) (xy 78.143341 -25.203681) (xy 78.059869 -25.195787)
			(xy 77.977509 -25.180073) (xy 77.896994 -25.156678) (xy 77.819038 -25.12581) (xy 77.744333 -25.087743)
			(xy 77.673541 -25.042814) (xy 77.607292 -24.991423) (xy 77.546173 -24.934026) (xy 77.490727 -24.871131)
			(xy 77.441445 -24.803298) (xy 77.398766 -24.731128) (xy 77.363068 -24.655262) (xy 77.334668 -24.576373)
			(xy 77.313818 -24.495162) (xy 77.300703 -24.412349) (xy 77.295439 -24.328669) (xy 77.298074 -24.244865)
			(xy 77.308583 -24.161681) (xy 77.326874 -24.079855) (xy 77.352784 -24.000114) (xy 77.386083 -23.923165)
			(xy 77.426476 -23.849691) (xy 77.473604 -23.780344) (xy 77.527049 -23.71574) (xy 77.586336 -23.656453)
			(xy 77.650939 -23.603007) (xy 77.720286 -23.555879) (xy 77.79376 -23.515486) (xy 77.870708 -23.482186)
			(xy 77.95045 -23.456275) (xy 78.032275 -23.437984) (xy 78.115459 -23.427474) (xy 78.199263 -23.424839)
			(xy 78.282943 -23.430102) (xy 78.365756 -23.443217) (xy 78.446967 -23.464066) (xy 78.525856 -23.492466)
			(xy 78.601722 -23.528163) (xy 78.673893 -23.570842) (xy 78.741726 -23.620123) (xy 78.804621 -23.675569)
			(xy 78.862019 -23.736687) (xy 78.913411 -23.802936) (xy 78.95834 -23.873727) (xy 78.996408 -23.948432)
			(xy 79.027276 -24.026388) (xy 79.050672 -24.106903) (xy 79.066386 -24.189263) (xy 79.074281 -24.272735)
			(xy 79.074772 -24.314658) (xy 79.074264 -24.341074) (xy 79.07401 -24.356822) (xy 79.09052 -24.382984)
			(xy 79.191612 -24.426672) (xy 79.201106 -24.430336) (xy 79.221438 -24.430591) (xy 79.240258 -24.422896)
			(xy 79.247746 -24.416004) (xy 80.113632 -23.550118) (xy 80.121481 -23.541387) (xy 80.128896 -23.51914)
			(xy 80.127856 -23.507446) (xy 80.127856 -23.507192) (xy 80.114394 -23.414228) (xy 80.100932 -23.394924)
			(xy 80.09001 -23.389082) (xy 80.076637 -23.381729) (xy 80.050343 -23.366231) (xy 80.037432 -23.358094)
			(xy 80.020872 -23.347486) (xy 79.988602 -23.324999) (xy 79.972916 -23.313136) (xy 79.963565 -23.306701)
			(xy 79.941401 -23.301947) (xy 79.919353 -23.307218) (xy 79.910178 -23.313898) (xy 79.876298 -23.340539)
			(xy 79.80426 -23.387868) (xy 79.727983 -23.428008) (xy 79.648182 -23.460584) (xy 79.565605 -23.485291)
			(xy 79.481026 -23.501896) (xy 79.395237 -23.510245) (xy 79.35214 -23.510748) (xy 79.309788 -23.510262)
			(xy 79.225466 -23.502214) (xy 79.142292 -23.486186) (xy 79.061017 -23.462325) (xy 78.982379 -23.430846)
			(xy 78.907089 -23.392035) (xy 78.83583 -23.346242) (xy 78.769246 -23.293883) (xy 78.707941 -23.235431)
			(xy 78.65247 -23.171417) (xy 78.603335 -23.102419) (xy 78.560982 -23.029064) (xy 78.525793 -22.952014)
			(xy 78.498088 -22.871968) (xy 78.478118 -22.789651) (xy 78.466063 -22.705809) (xy 78.462032 -22.6212)
			(xy 78.466063 -22.536591) (xy 78.478118 -22.452749) (xy 78.498088 -22.370432) (xy 78.525793 -22.290386)
			(xy 78.560982 -22.213336) (xy 78.603335 -22.139981) (xy 78.65247 -22.070983) (xy 78.707941 -22.006969)
			(xy 78.769246 -21.948517) (xy 78.83583 -21.896158) (xy 78.907089 -21.850365) (xy 78.982379 -21.811554)
			(xy 79.061017 -21.780075) (xy 79.142292 -21.756214) (xy 79.225466 -21.740186) (xy 79.309788 -21.732138)
			(xy 79.35214 -21.731732) (xy 79.393647 -21.732209) (xy 79.476299 -21.739941) (xy 79.55787 -21.755343)
			(xy 79.637651 -21.778281) (xy 79.714947 -21.808555) (xy 79.789084 -21.845902) (xy 79.859418 -21.889997)
			(xy 79.892652 -21.914866) (xy 79.902002 -21.921285) (xy 79.924153 -21.926011) (xy 79.946176 -21.920722)
			(xy 79.95539 -21.914104) (xy 79.989271 -21.887465) (xy 80.06131 -21.840142) (xy 80.137587 -21.800008)
			(xy 80.217389 -21.767438) (xy 80.299966 -21.742737) (xy 80.384545 -21.726138) (xy 80.470332 -21.717796)
			(xy 80.513428 -21.717254) (xy 80.561258 -21.717901) (xy 80.656361 -21.7282) (xy 80.749808 -21.748655)
			(xy 80.795368 -21.763228) (xy 80.805528 -21.76653) (xy 80.826102 -21.764752) (xy 80.900524 -21.725128)
			(xy 80.909323 -21.71985) (xy 80.922171 -21.703873) (xy 80.925416 -21.69414) (xy 80.925416 -21.693886)
			(xy 80.92567 -21.693632) (xy 80.933453 -21.667099) (xy 80.955622 -21.616444) (xy 80.984876 -21.569523)
			(xy 81.020602 -21.527321) (xy 81.062051 -21.490724) (xy 81.084928 -21.475192) (xy 81.090262 -21.471636)
			(xy 81.09839 -21.463) (xy 81.119726 -21.425408) (xy 81.119726 -21.4122) (xy 81.12053 -21.36896) (xy 81.129494 -21.282937)
			(xy 81.146755 -21.198189) (xy 81.17215 -21.115513) (xy 81.188306 -21.075396) (xy 81.192116 -21.065998)
			(xy 81.192116 -20.62607) (xy 81.169256 -20.597876) (xy 81.151476 -20.59432) (xy 81.108897 -20.585144)
			(xy 81.025631 -20.559568) (xy 80.945263 -20.525976) (xy 80.868563 -20.48469) (xy 80.796266 -20.436105)
			(xy 80.729064 -20.380685) (xy 80.6676 -20.318963) (xy 80.612464 -20.251528) (xy 80.564183 -20.179027)
			(xy 80.52322 -20.102154) (xy 80.489966 -20.021646) (xy 80.464741 -19.938272) (xy 80.447786 -19.852833)
			(xy 80.439263 -19.766145) (xy 80.438752 -19.722592) (xy 80.439231 -19.680779) (xy 80.44708 -19.597523)
			(xy 80.462708 -19.515371) (xy 80.485977 -19.435048) (xy 80.516683 -19.357264) (xy 80.554553 -19.282704)
			(xy 80.599253 -19.212028) (xy 80.650389 -19.145859) (xy 80.707509 -19.084782) (xy 80.77011 -19.029334)
			(xy 80.837638 -18.980007) (xy 80.909498 -18.937235) (xy 80.985054 -18.901396) (xy 81.063641 -18.872807)
			(xy 81.103978 -18.861786) (xy 81.113376 -18.859246) (xy 81.12125 -18.853658) (xy 81.125134 -18.85069)
			(xy 81.131783 -18.843526) (xy 81.134458 -18.839434) (xy 81.171288 -18.78076) (xy 81.173696 -18.776682)
			(xy 81.177143 -18.767863) (xy 81.178146 -18.763234) (xy 81.179924 -18.753582) (xy 81.178146 -18.74393)
			(xy 81.170427 -18.701809) (xy 81.162154 -18.61657) (xy 81.161636 -18.57375) (xy 81.16205 -18.535909)
			(xy 81.168526 -18.460504) (xy 81.181393 -18.385923) (xy 81.190592 -18.349214) (xy 81.192116 -18.342864)
			(xy 81.192116 -16.808704) (xy 81.191694 -16.798633) (xy 81.183983 -16.780026) (xy 81.17713 -16.772636)
			(xy 79.532734 -15.12824) (xy 79.525622 -15.120874) (xy 79.506826 -15.113254) (xy 77.522324 -15.113254)
			(xy 77.512261 -15.113693) (xy 77.493682 -15.121432) (xy 77.486256 -15.12824) (xy 77.43952 -15.174722)
			(xy 77.411619 -15.201879) (xy 77.350768 -15.250459) (xy 77.284861 -15.291921) (xy 77.214727 -15.325745)
			(xy 77.141248 -15.351504) (xy 77.065347 -15.368877) (xy 76.987978 -15.377643) (xy 76.949046 -15.378176)
			(xy 72.95261 -15.378176) (xy 72.913677 -15.377639) (xy 72.836302 -15.368894) (xy 72.760394 -15.351536)
			(xy 72.686909 -15.325782) (xy 72.616772 -15.291959) (xy 72.550866 -15.25049) (xy 72.49002 -15.201899)
			(xy 72.462136 -15.174722) (xy 72.4154 -15.12824) (xy 72.408003 -15.121389) (xy 72.389405 -15.113648)
			(xy 72.379332 -15.113254) (xy 71.849996 -15.113254) (xy 71.839927 -15.112829) (xy 71.821328 -15.105108)
			(xy 71.813928 -15.098268) (xy 70.948042 -14.232382) (xy 70.940697 -14.225572) (xy 70.922234 -14.217848)
			(xy 70.912228 -14.217396) (xy 70.4469 -14.217396) (xy 70.407975 -14.21685) (xy 70.330613 -14.208134)
			(xy 70.254714 -14.190811) (xy 70.181232 -14.165099) (xy 70.111091 -14.131322) (xy 70.045172 -14.089904)
			(xy 69.984305 -14.041366) (xy 69.956426 -14.014196) (xy 68.46062 -12.51839) (xy 68.453546 -12.511878)
			(xy 68.435922 -12.504227) (xy 68.41672 -12.503608) (xy 68.407534 -12.506452) (xy 68.307204 -12.542266)
			(xy 68.28917 -12.565126) (xy 68.287646 -12.580112) (xy 68.282701 -12.62327) (xy 68.265469 -12.70842)
			(xy 68.240014 -12.791482) (xy 68.206578 -12.871665) (xy 68.165481 -12.948205) (xy 68.117114 -13.020371)
			(xy 68.061938 -13.087475) (xy 68.00048 -13.148877) (xy 67.933326 -13.203992) (xy 67.861117 -13.252294)
			(xy 67.82308 -13.273278) (xy 67.813809 -13.278728) (xy 67.800642 -13.295706) (xy 67.79768 -13.306044)
			(xy 67.787278 -13.347142) (xy 67.759673 -13.427305) (xy 67.724562 -13.504477) (xy 67.682265 -13.577955)
			(xy 67.633164 -13.647073) (xy 67.577707 -13.711203) (xy 67.516397 -13.769762) (xy 67.44979 -13.822219)
			(xy 67.378493 -13.868097) (xy 67.303152 -13.90698) (xy 67.224451 -13.938514) (xy 67.143106 -13.962413)
			(xy 67.059856 -13.978459) (xy 66.975456 -13.986508) (xy 66.933064 -13.987018) (xy 66.894774 -13.98661)
			(xy 66.818479 -13.980007) (xy 66.743036 -13.96686) (xy 66.669004 -13.947269) (xy 66.632836 -13.934694)
			(xy 66.624398 -13.932052) (xy 66.60673 -13.932052) (xy 66.598292 -13.934694) (xy 66.562114 -13.947239)
			(xy 66.488082 -13.966817) (xy 66.412643 -13.979967) (xy 66.336352 -13.98659) (xy 66.298064 -13.987018)
			(xy 66.254268 -13.9865) (xy 66.167098 -13.977897) (xy 66.081199 -13.960757) (xy 65.997403 -13.935249)
			(xy 65.916523 -13.901618) (xy 65.877694 -13.881354) (xy 65.866228 -13.875936) (xy 65.8409 -13.875936)
			(xy 65.829434 -13.881354) (xy 65.79059 -13.901586) (xy 65.709706 -13.935193) (xy 65.625912 -13.960696)
			(xy 65.54002 -13.977848) (xy 65.452858 -13.986484) (xy 65.409064 -13.987018) (xy 65.365268 -13.9865)
			(xy 65.278098 -13.977897) (xy 65.192199 -13.960757) (xy 65.108403 -13.935249) (xy 65.027523 -13.901618)
			(xy 64.988694 -13.881354) (xy 64.977228 -13.875936) (xy 64.9519 -13.875936) (xy 64.940434 -13.881354)
			(xy 64.90159 -13.901586) (xy 64.820706 -13.935193) (xy 64.736912 -13.960696) (xy 64.65102 -13.977848)
			(xy 64.563858 -13.986484) (xy 64.520064 -13.987018) (xy 64.476268 -13.9865) (xy 64.389098 -13.977897)
			(xy 64.303199 -13.960757) (xy 64.219403 -13.935249) (xy 64.138523 -13.901618) (xy 64.099694 -13.881354)
			(xy 64.088228 -13.875936) (xy 64.0629 -13.875936) (xy 64.051434 -13.881354) (xy 64.01259 -13.901586)
			(xy 63.931706 -13.935193) (xy 63.847912 -13.960696) (xy 63.76202 -13.977848) (xy 63.674858 -13.986484)
			(xy 63.631064 -13.987018) (xy 63.588812 -13.986518) (xy 63.50469 -13.978502) (xy 63.421707 -13.962546)
			(xy 63.34061 -13.938794) (xy 63.262131 -13.907459) (xy 63.186977 -13.868825) (xy 63.115824 -13.823239)
			(xy 63.049315 -13.771112) (xy 62.988047 -13.712913) (xy 62.932574 -13.649167) (xy 62.883395 -13.580449)
			(xy 62.840953 -13.507377) (xy 62.80563 -13.43061) (xy 62.777746 -13.35084) (xy 62.757551 -13.268786)
			(xy 62.750954 -13.22705) (xy 62.748799 -13.216162) (xy 62.736685 -13.197592) (xy 62.727586 -13.191236)
			(xy 62.693699 -13.169508) (xy 62.629586 -13.120822) (xy 62.570133 -13.066543) (xy 62.515827 -13.007114)
			(xy 62.467114 -12.943022) (xy 62.42439 -12.874791) (xy 62.388005 -12.802978) (xy 62.358258 -12.728172)
			(xy 62.335391 -12.650984) (xy 62.327028 -12.611608) (xy 62.324234 -12.597892) (xy 62.305438 -12.577064)
			(xy 62.206124 -12.547092) (xy 62.197252 -12.544798) (xy 62.178981 -12.545997) (xy 62.162315 -12.55358)
			(xy 62.155578 -12.559792) (xy 61.908182 -12.807188) (xy 61.900816 -12.8143) (xy 61.893196 -12.833096)
			(xy 61.893196 -14.700504) (xy 61.893672 -14.711254) (xy 61.902485 -14.730863) (xy 61.910214 -14.73835)
			(xy 61.966856 -14.788896) (xy 61.975221 -14.795671) (xy 61.995742 -14.802106) (xy 62.00648 -14.801342)
			(xy 62.006734 -14.801342) (xy 62.017807 -14.80014) (xy 62.040046 -14.79887) (xy 62.051184 -14.798802)
			(xy 62.078437 -14.799264) (xy 62.132388 -14.807019) (xy 62.184687 -14.822373) (xy 62.234267 -14.845014)
			(xy 62.280121 -14.874481) (xy 62.321315 -14.910174) (xy 62.357009 -14.951366) (xy 62.386478 -14.997219)
			(xy 62.409121 -15.046798) (xy 62.424477 -15.099096) (xy 62.432235 -15.153047) (xy 62.432235 -15.207553)
			(xy 62.424477 -15.261504) (xy 62.409121 -15.313802) (xy 62.386478 -15.363381) (xy 62.357009 -15.409234)
			(xy 62.321315 -15.450426) (xy 62.280121 -15.486119) (xy 62.234267 -15.515586) (xy 62.184687 -15.538227)
			(xy 62.132388 -15.553581) (xy 62.078437 -15.561336) (xy 62.051184 -15.561818) (xy 62.040046 -15.561751)
			(xy 62.017807 -15.560478) (xy 62.006734 -15.559278) (xy 62.00648 -15.559278) (xy 61.995757 -15.558617)
			(xy 61.975291 -15.565066) (xy 61.966856 -15.571724) (xy 61.910214 -15.62227) (xy 61.902585 -15.629832)
			(xy 61.893769 -15.649392) (xy 61.893196 -15.660116) (xy 61.893196 -16.304006) (xy 61.89383 -16.315423)
			(xy 61.903731 -16.335998) (xy 61.912246 -16.34363) (xy 61.98362 -16.40078) (xy 62.005972 -16.40586)
			(xy 62.017402 -16.40332) (xy 62.065527 -16.393134) (xy 62.163288 -16.382186) (xy 62.212474 -16.381476)
			(xy 62.257582 -16.382029) (xy 62.347334 -16.391162) (xy 62.435699 -16.409337) (xy 62.52177 -16.436368)
			(xy 62.604661 -16.471976) (xy 62.68352 -16.515794) (xy 62.757536 -16.567374) (xy 62.792102 -16.59636)
			(xy 62.797436 -16.600424) (xy 62.80262 -16.603542) (xy 62.814043 -16.607513) (xy 62.820042 -16.608298)
			(xy 62.837059 -16.602421) (xy 62.871487 -16.591878) (xy 62.888876 -16.587216) (xy 62.894633 -16.585497)
			(xy 62.905166 -16.579723) (xy 62.909704 -16.575786) (xy 62.940288 -16.548949) (xy 63.005557 -16.500355)
			(xy 63.07499 -16.457922) (xy 63.148008 -16.422005) (xy 63.223999 -16.392904) (xy 63.302329 -16.370862)
			(xy 63.382345 -16.356063) (xy 63.463378 -16.348631) (xy 63.504064 -16.348202) (xy 63.545168 -16.348661)
			(xy 63.627026 -16.356243) (xy 63.707835 -16.371346) (xy 63.786905 -16.39384) (xy 63.863563 -16.423535)
			(xy 63.937153 -16.460177) (xy 64.007049 -16.503452) (xy 64.072654 -16.552992) (xy 64.133407 -16.608375)
			(xy 64.188791 -16.669126) (xy 64.238333 -16.734729) (xy 64.281611 -16.804624) (xy 64.318254 -16.878213)
			(xy 64.347951 -16.95487) (xy 64.370448 -17.03394) (xy 64.385554 -17.114748) (xy 64.393138 -17.196606)
			(xy 64.393572 -17.23771) (xy 64.393102 -17.279429) (xy 64.385295 -17.3625) (xy 64.369743 -17.444475)
			(xy 64.346581 -17.524632) (xy 64.316014 -17.602269) (xy 64.278309 -17.676701) (xy 64.233799 -17.747274)
			(xy 64.182875 -17.813369) (xy 64.125985 -17.874403) (xy 64.063627 -17.929841) (xy 63.996352 -17.979194)
			(xy 63.92475 -18.02203) (xy 63.849451 -18.057971) (xy 63.771116 -18.086702) (xy 63.730886 -18.097754)
			(xy 63.725152 -18.099526) (xy 63.714641 -18.105309) (xy 63.710058 -18.109184) (xy 63.677124 -18.13804)
			(xy 63.606523 -18.189847) (xy 63.531175 -18.234467) (xy 63.451807 -18.271468) (xy 63.369187 -18.300492)
			(xy 63.326772 -18.311368) (xy 63.317919 -18.31393) (xy 63.302708 -18.324313) (xy 63.292119 -18.339381)
			(xy 63.289434 -18.348198) (xy 63.282016 -18.375198) (xy 63.260355 -18.42683) (xy 63.231381 -18.474743)
			(xy 63.195715 -18.517906) (xy 63.194987 -18.518562) (xy 67.655436 -18.518562) (xy 67.655436 -18.433866)
			(xy 67.663487 -18.349552) (xy 67.679516 -18.266386) (xy 67.703377 -18.185119) (xy 67.734856 -18.106489)
			(xy 67.773667 -18.031208) (xy 67.819457 -17.959956) (xy 67.871813 -17.89338) (xy 67.930261 -17.832082)
			(xy 67.994271 -17.776617) (xy 68.063263 -17.727488) (xy 68.136613 -17.685139) (xy 68.213656 -17.649955)
			(xy 68.293695 -17.622253) (xy 68.376004 -17.602285) (xy 68.459839 -17.590232) (xy 68.54444 -17.586202)
			(xy 68.629041 -17.590232) (xy 68.712876 -17.602285) (xy 68.795185 -17.622253) (xy 68.875224 -17.649955)
			(xy 68.952267 -17.685139) (xy 69.025617 -17.727488) (xy 69.094609 -17.776617) (xy 69.158619 -17.832082)
			(xy 69.217067 -17.89338) (xy 69.269423 -17.959956) (xy 69.315213 -18.031208) (xy 69.354024 -18.106489)
			(xy 69.385503 -18.185119) (xy 69.409364 -18.266386) (xy 69.425393 -18.349552) (xy 69.433444 -18.433866)
			(xy 69.433948 -18.476214) (xy 69.43377 -18.4912) (xy 74.232262 -18.4912) (xy 74.232808 -18.448529)
			(xy 74.240982 -18.363579) (xy 74.257255 -18.279803) (xy 74.281476 -18.19797) (xy 74.313425 -18.118833)
			(xy 74.352806 -18.043121) (xy 74.399257 -17.971528) (xy 74.452352 -17.904713) (xy 74.511602 -17.843291)
			(xy 74.576463 -17.787826) (xy 74.646338 -17.738828) (xy 74.720585 -17.696748) (xy 74.79852 -17.661973)
			(xy 74.838814 -17.64792) (xy 74.849466 -17.643697) (xy 74.865885 -17.627756) (xy 74.873802 -17.606285)
			(xy 74.873358 -17.594834) (xy 74.87158 -17.558512) (xy 74.872066 -17.531261) (xy 74.879822 -17.477313)
			(xy 74.895177 -17.425018) (xy 74.917819 -17.375441) (xy 74.947285 -17.329591) (xy 74.982976 -17.2884)
			(xy 75.024167 -17.252709) (xy 75.070017 -17.223243) (xy 75.119594 -17.200601) (xy 75.171889 -17.185246)
			(xy 75.225837 -17.17749) (xy 75.280339 -17.17749) (xy 75.334287 -17.185246) (xy 75.386582 -17.200601)
			(xy 75.436159 -17.223243) (xy 75.482009 -17.252709) (xy 75.5232 -17.2884) (xy 75.558891 -17.329591)
			(xy 75.588357 -17.375441) (xy 75.610999 -17.425018) (xy 75.626354 -17.477313) (xy 75.63411 -17.531261)
			(xy 75.634596 -17.558512) (xy 75.634245 -17.582355) (xy 75.628321 -17.629672) (xy 75.616553 -17.675884)
			(xy 75.60818 -17.698212) (xy 75.604528 -17.709037) (xy 75.606167 -17.731801) (xy 75.617456 -17.751637)
			(xy 75.626468 -17.758664) (xy 75.661973 -17.783798) (xy 75.728437 -17.83993) (xy 75.789106 -17.90228)
			(xy 75.843402 -17.970251) (xy 75.890807 -18.043196) (xy 75.930868 -18.120419) (xy 75.963203 -18.201182)
			(xy 75.987504 -18.284714) (xy 75.996038 -18.32737) (xy 75.99807 -18.3388) (xy 76.011786 -18.357088)
			(xy 76.101702 -18.405602) (xy 76.124816 -18.406618) (xy 76.135484 -18.402046) (xy 76.176588 -18.385277)
			(xy 76.261424 -18.359109) (xy 76.348446 -18.341529) (xy 76.436788 -18.332715) (xy 76.481178 -18.332196)
			(xy 76.519228 -18.332603) (xy 76.59505 -18.339103) (xy 76.67004 -18.352057) (xy 76.743648 -18.371371)
			(xy 76.779628 -18.383758) (xy 76.788671 -18.386584) (xy 76.807592 -18.386078) (xy 76.816458 -18.382742)
			(xy 76.844144 -18.371058) (xy 76.852714 -18.367033) (xy 76.866288 -18.353853) (xy 76.87056 -18.345404)
			(xy 76.888685 -18.307284) (xy 76.931153 -18.234331) (xy 76.980341 -18.165729) (xy 77.035806 -18.102094)
			(xy 77.09705 -18.044001) (xy 77.163522 -17.99197) (xy 77.234624 -17.94647) (xy 77.309716 -17.907911)
			(xy 77.388123 -17.876638) (xy 77.469141 -17.852933) (xy 77.552039 -17.83701) (xy 77.636073 -17.829012)
			(xy 77.67828 -17.828514) (xy 77.718904 -17.829005) (xy 77.799814 -17.836411) (xy 77.879712 -17.851162)
			(xy 77.957932 -17.873137) (xy 78.033822 -17.902151) (xy 78.106752 -17.937964) (xy 78.176112 -17.980277)
			(xy 78.241326 -18.028738) (xy 78.30185 -18.082942) (xy 78.35718 -18.142438) (xy 78.406855 -18.206732)
			(xy 78.450461 -18.275286) (xy 78.487636 -18.347531) (xy 78.503272 -18.385028) (xy 78.507191 -18.393638)
			(xy 78.5201 -18.407444) (xy 78.528418 -18.411952) (xy 78.555596 -18.424906) (xy 78.564331 -18.428603)
			(xy 78.58323 -18.430026) (xy 78.592426 -18.4277) (xy 78.635129 -18.415046) (xy 78.722415 -18.39731)
			(xy 78.811035 -18.388381) (xy 78.85557 -18.387822) (xy 78.897922 -18.388249) (xy 78.982241 -18.396298)
			(xy 79.065414 -18.412325) (xy 79.146687 -18.436187) (xy 79.225324 -18.467666) (xy 79.300612 -18.506477)
			(xy 79.371869 -18.55227) (xy 79.438452 -18.604628) (xy 79.499755 -18.663079) (xy 79.555225 -18.727093)
			(xy 79.604359 -18.796089) (xy 79.646711 -18.869444) (xy 79.681899 -18.946492) (xy 79.709603 -19.026536)
			(xy 79.729573 -19.108852) (xy 79.741628 -19.192693) (xy 79.745658 -19.2773) (xy 79.741628 -19.361907)
			(xy 79.729573 -19.445748) (xy 79.709603 -19.528064) (xy 79.681899 -19.608108) (xy 79.646711 -19.685156)
			(xy 79.604359 -19.758511) (xy 79.555225 -19.827507) (xy 79.499755 -19.891521) (xy 79.438452 -19.949972)
			(xy 79.371869 -20.00233) (xy 79.300612 -20.048123) (xy 79.225324 -20.086934) (xy 79.146687 -20.118413)
			(xy 79.065414 -20.142275) (xy 78.982241 -20.158302) (xy 78.897922 -20.166351) (xy 78.85557 -20.166838)
			(xy 78.814944 -20.166421) (xy 78.734031 -20.15901) (xy 78.654131 -20.144254) (xy 78.575909 -20.122273)
			(xy 78.500016 -20.093253) (xy 78.427086 -20.057434) (xy 78.357725 -20.015115) (xy 78.292512 -19.966648)
			(xy 78.231988 -19.912437) (xy 78.17666 -19.852935) (xy 78.126987 -19.788635) (xy 78.083383 -19.720074)
			(xy 78.046212 -19.647824) (xy 78.030578 -19.610324) (xy 78.026625 -19.601733) (xy 78.01374 -19.587916)
			(xy 78.005432 -19.5834) (xy 77.978254 -19.570446) (xy 77.96951 -19.566775) (xy 77.950619 -19.565336)
			(xy 77.941424 -19.567652) (xy 77.898725 -19.58032) (xy 77.811437 -19.59805) (xy 77.722815 -19.606974)
			(xy 77.67828 -19.60753) (xy 77.64023 -19.607134) (xy 77.564407 -19.60063) (xy 77.489418 -19.587673)
			(xy 77.415809 -19.568357) (xy 77.37983 -19.555968) (xy 77.370793 -19.553118) (xy 77.351866 -19.553639)
			(xy 77.343 -19.556984) (xy 77.315314 -19.568668) (xy 77.306749 -19.572702) (xy 77.293171 -19.585874)
			(xy 77.288898 -19.594322) (xy 77.27115 -19.631643) (xy 77.229678 -19.703133) (xy 77.206094 -19.73707)
			(xy 77.200506 -19.744944) (xy 77.195934 -19.763232) (xy 77.206348 -19.8501) (xy 77.215238 -19.86661)
			(xy 77.22235 -19.87296) (xy 77.242703 -19.891142) (xy 77.278503 -19.932337) (xy 77.308061 -19.978215)
			(xy 77.330776 -20.02784) (xy 77.346182 -20.080197) (xy 77.353964 -20.134216) (xy 77.35443 -20.161504)
			(xy 77.353892 -20.19005) (xy 77.345374 -20.246504) (xy 77.328542 -20.301059) (xy 77.303773 -20.352499)
			(xy 77.288136 -20.376388) (xy 77.282126 -20.386323) (xy 77.27881 -20.409277) (xy 77.285868 -20.431368)
			(xy 77.29347 -20.440142) (xy 77.322601 -20.471192) (xy 77.375459 -20.537945) (xy 77.421699 -20.609442)
			(xy 77.460897 -20.685029) (xy 77.492695 -20.764015) (xy 77.516801 -20.845678) (xy 77.532995 -20.92927)
			(xy 77.541129 -21.014027) (xy 77.541628 -21.0566) (xy 77.54111 -21.09857) (xy 77.53322 -21.182138)
			(xy 77.517492 -21.26459) (xy 77.494064 -21.345194) (xy 77.463146 -21.423232) (xy 77.425013 -21.49801)
			(xy 77.380004 -21.568862) (xy 77.32852 -21.635158) (xy 77.271018 -21.696309) (xy 77.20801 -21.751769)
			(xy 77.140057 -21.801046) (xy 77.067763 -21.843701) (xy 76.991772 -21.879355) (xy 76.91276 -21.907691)
			(xy 76.831429 -21.928455) (xy 76.790042 -21.93544) (xy 76.777342 -21.937218) (xy 76.75753 -21.952204)
			(xy 76.710286 -22.050502) (xy 76.711302 -22.075394) (xy 76.717652 -22.086316) (xy 76.740279 -22.12687)
			(xy 76.777909 -22.211777) (xy 76.806498 -22.30014) (xy 76.825735 -22.390997) (xy 76.835411 -22.483364)
			(xy 76.836016 -22.5298) (xy 76.835585 -22.571119) (xy 76.827906 -22.6534) (xy 76.812632 -22.734614)
			(xy 76.789894 -22.814063) (xy 76.75989 -22.891061) (xy 76.722876 -22.964947) (xy 76.679172 -23.035083)
			(xy 76.629155 -23.100865) (xy 76.573254 -23.161728) (xy 76.511952 -23.217146) (xy 76.479146 -23.24227)
			(xy 76.472222 -23.247833) (xy 76.46247 -23.262667) (xy 76.460096 -23.271226) (xy 76.453238 -23.300182)
			(xy 76.451608 -23.308584) (xy 76.453418 -23.325592) (xy 76.456794 -23.333456) (xy 76.468356 -23.359066)
			(xy 76.484643 -23.412845) (xy 76.492874 -23.468429) (xy 76.49337 -23.496524) (xy 76.492884 -23.523775)
			(xy 76.485128 -23.577723) (xy 76.469773 -23.630018) (xy 76.447131 -23.679595) (xy 76.417665 -23.725445)
			(xy 76.381974 -23.766636) (xy 76.340783 -23.802327) (xy 76.294933 -23.831793) (xy 76.245356 -23.854435)
			(xy 76.193061 -23.86979) (xy 76.139113 -23.877546) (xy 76.084611 -23.877546) (xy 76.030663 -23.86979)
			(xy 75.978368 -23.854435) (xy 75.928791 -23.831793) (xy 75.882941 -23.802327) (xy 75.84175 -23.766636)
			(xy 75.806059 -23.725445) (xy 75.776593 -23.679595) (xy 75.753951 -23.630018) (xy 75.738596 -23.577723)
			(xy 75.73084 -23.523775) (xy 75.730354 -23.496524) (xy 75.730421 -23.486727) (xy 75.731436 -23.467159)
			(xy 75.732386 -23.457408) (xy 75.732877 -23.448872) (xy 75.728853 -23.432263) (xy 75.724512 -23.424896)
			(xy 75.70851 -23.39975) (xy 75.703416 -23.392507) (xy 75.68939 -23.381721) (xy 75.681078 -23.378668)
			(xy 75.63985 -23.365172) (xy 75.559959 -23.331355) (xy 75.483741 -23.289919) (xy 75.411919 -23.241259)
			(xy 75.345176 -23.185838) (xy 75.284147 -23.124181) (xy 75.229411 -23.056875) (xy 75.181488 -22.984559)
			(xy 75.140834 -22.90792) (xy 75.107836 -22.827688) (xy 75.082806 -22.744624) (xy 75.065983 -22.659517)
			(xy 75.057526 -22.573177) (xy 75.057 -22.5298) (xy 75.057494 -22.487829) (xy 75.065384 -22.40426)
			(xy 75.081114 -22.321806) (xy 75.104542 -22.241201) (xy 75.135461 -22.163162) (xy 75.173596 -22.088383)
			(xy 75.218606 -22.017531) (xy 75.270093 -21.951234) (xy 75.327597 -21.890084) (xy 75.390607 -21.834624)
			(xy 75.458562 -21.785347) (xy 75.530858 -21.742693) (xy 75.606851 -21.70704) (xy 75.685865 -21.678706)
			(xy 75.767198 -21.657943) (xy 75.808586 -21.65096) (xy 75.821286 -21.649182) (xy 75.841098 -21.634196)
			(xy 75.888342 -21.535898) (xy 75.887326 -21.511006) (xy 75.880976 -21.500084) (xy 75.858351 -21.459528)
			(xy 75.82072 -21.374622) (xy 75.792131 -21.28626) (xy 75.772893 -21.195402) (xy 75.763217 -21.103036)
			(xy 75.762612 -21.0566) (xy 75.763054 -21.015482) (xy 75.770647 -20.933596) (xy 75.785769 -20.852761)
			(xy 75.80829 -20.773668) (xy 75.838018 -20.696992) (xy 75.874698 -20.623388) (xy 75.918018 -20.553486)
			(xy 75.942444 -20.520406) (xy 75.947966 -20.51244) (xy 75.953053 -20.493752) (xy 75.95235 -20.484084)
			(xy 75.948794 -20.453604) (xy 75.947355 -20.444381) (xy 75.938741 -20.427836) (xy 75.93203 -20.421346)
			(xy 75.912273 -20.40315) (xy 75.877544 -20.362178) (xy 75.8489 -20.316742) (xy 75.826908 -20.26774)
			(xy 75.812 -20.21614) (xy 75.804471 -20.162959) (xy 75.804014 -20.136104) (xy 75.8045 -20.108014)
			(xy 75.812745 -20.052443) (xy 75.829057 -19.998683) (xy 75.853083 -19.9479) (xy 75.868276 -19.924268)
			(xy 75.874278 -19.914104) (xy 75.877174 -19.890704) (xy 75.869411 -19.868439) (xy 75.861418 -19.859752)
			(xy 75.829118 -19.827595) (xy 75.770579 -19.757729) (xy 75.719492 -19.682242) (xy 75.676392 -19.601927)
			(xy 75.64173 -19.517626) (xy 75.61587 -19.430223) (xy 75.60691 -19.385534) (xy 75.604878 -19.374104)
			(xy 75.591162 -19.355816) (xy 75.501246 -19.307302) (xy 75.478132 -19.306286) (xy 75.467464 -19.310858)
			(xy 75.426354 -19.327612) (xy 75.34152 -19.353784) (xy 75.2545 -19.371368) (xy 75.16616 -19.380187)
			(xy 75.12177 -19.380708) (xy 75.080667 -19.380262) (xy 74.998812 -19.372674) (xy 74.918006 -19.357567)
			(xy 74.838939 -19.335068) (xy 74.762285 -19.30537) (xy 74.688698 -19.268725) (xy 74.618806 -19.225448)
			(xy 74.553205 -19.175907) (xy 74.492455 -19.120524) (xy 74.437074 -19.059772) (xy 74.387535 -18.994169)
			(xy 74.34426 -18.924276) (xy 74.307618 -18.850688) (xy 74.277923 -18.774033) (xy 74.255426 -18.694965)
			(xy 74.240321 -18.614158) (xy 74.232737 -18.532303) (xy 74.232262 -18.4912) (xy 69.43377 -18.4912)
			(xy 69.433444 -18.518562) (xy 69.425393 -18.602876) (xy 69.409364 -18.686042) (xy 69.385503 -18.767309)
			(xy 69.354024 -18.845939) (xy 69.315213 -18.92122) (xy 69.269423 -18.992472) (xy 69.217067 -19.059048)
			(xy 69.158619 -19.120346) (xy 69.094609 -19.175811) (xy 69.025617 -19.22494) (xy 68.952267 -19.267289)
			(xy 68.875224 -19.302473) (xy 68.795185 -19.330175) (xy 68.712876 -19.350143) (xy 68.629041 -19.362196)
			(xy 68.54444 -19.366227) (xy 68.459839 -19.362196) (xy 68.376004 -19.350143) (xy 68.293695 -19.330175)
			(xy 68.213656 -19.302473) (xy 68.136613 -19.267289) (xy 68.063263 -19.22494) (xy 67.994271 -19.175811)
			(xy 67.930261 -19.120346) (xy 67.871813 -19.059048) (xy 67.819457 -18.992472) (xy 67.773667 -18.92122)
			(xy 67.734856 -18.845939) (xy 67.703377 -18.767309) (xy 67.679516 -18.686042) (xy 67.663487 -18.602876)
			(xy 67.655436 -18.518562) (xy 63.194987 -18.518562) (xy 63.154124 -18.555393) (xy 63.107501 -18.586399)
			(xy 63.056847 -18.610258) (xy 63.003249 -18.626458) (xy 62.94786 -18.63465) (xy 62.919864 -18.635218)
			(xy 62.892614 -18.63473) (xy 62.83867 -18.626969) (xy 62.786379 -18.611611) (xy 62.736805 -18.588968)
			(xy 62.690959 -18.559501) (xy 62.649772 -18.523809) (xy 62.614084 -18.48262) (xy 62.58462 -18.436772)
			(xy 62.56198 -18.387197) (xy 62.546625 -18.334905) (xy 62.538868 -18.28096) (xy 62.538356 -18.25371)
			(xy 62.53861 -18.239994) (xy 62.539118 -18.228056) (xy 62.529212 -18.206466) (xy 62.448694 -18.140172)
			(xy 62.42558 -18.134838) (xy 62.413896 -18.137378) (xy 62.364367 -18.148153) (xy 62.263664 -18.159733)
			(xy 62.212982 -18.160492) (xy 62.212474 -18.160492) (xy 62.163287 -18.159794) (xy 62.065524 -18.148851)
			(xy 62.017402 -18.138648) (xy 62.005972 -18.136108) (xy 61.98362 -18.141188) (xy 61.912246 -18.198338)
			(xy 61.90374 -18.205972) (xy 61.893864 -18.22655) (xy 61.893196 -18.237962) (xy 61.893196 -19.26971)
			(xy 62.537846 -19.26971) (xy 62.541917 -19.214088) (xy 62.554043 -19.159651) (xy 62.573966 -19.10756)
			(xy 62.601262 -19.058925) (xy 62.635348 -19.014782) (xy 62.675497 -18.976073) (xy 62.720855 -18.943622)
			(xy 62.770455 -18.918121) (xy 62.823239 -18.900114) (xy 62.878082 -18.889984) (xy 62.933816 -18.887947)
			(xy 62.989253 -18.894047) (xy 63.04321 -18.908153) (xy 63.094539 -18.929965) (xy 63.142145 -18.959019)
			(xy 63.185013 -18.994694) (xy 63.22223 -19.036231) (xy 63.253003 -19.082744) (xy 63.276675 -19.133241)
			(xy 63.292743 -19.186648) (xy 63.300863 -19.241824) (xy 63.301372 -19.26971) (xy 63.300863 -19.297596)
			(xy 63.292743 -19.352772) (xy 63.276675 -19.406179) (xy 63.253003 -19.456676) (xy 63.22223 -19.503189)
			(xy 63.185013 -19.544726) (xy 63.142145 -19.580401) (xy 63.094539 -19.609455) (xy 63.04321 -19.631267)
			(xy 62.989253 -19.645373) (xy 62.933816 -19.651473) (xy 62.878082 -19.649436) (xy 62.823239 -19.639306)
			(xy 62.770455 -19.621299) (xy 62.720855 -19.595798) (xy 62.675497 -19.563347) (xy 62.635348 -19.524638)
			(xy 62.601262 -19.480495) (xy 62.573966 -19.43186) (xy 62.554043 -19.379769) (xy 62.541917 -19.325332)
			(xy 62.537846 -19.26971) (xy 61.893196 -19.26971) (xy 61.893196 -19.958304) (xy 74.152504 -19.958304)
			(xy 74.156575 -19.902682) (xy 74.168701 -19.848245) (xy 74.188624 -19.796154) (xy 74.21592 -19.747519)
			(xy 74.250006 -19.703376) (xy 74.290155 -19.664667) (xy 74.335513 -19.632216) (xy 74.385113 -19.606715)
			(xy 74.437897 -19.588708) (xy 74.49274 -19.578578) (xy 74.548474 -19.576541) (xy 74.603911 -19.582641)
			(xy 74.657868 -19.596747) (xy 74.709197 -19.618559) (xy 74.756803 -19.647613) (xy 74.799671 -19.683288)
			(xy 74.836888 -19.724825) (xy 74.867661 -19.771338) (xy 74.891333 -19.821835) (xy 74.907401 -19.875242)
			(xy 74.915521 -19.930418) (xy 74.91603 -19.958304) (xy 74.915521 -19.98619) (xy 74.907401 -20.041366)
			(xy 74.891333 -20.094773) (xy 74.867661 -20.14527) (xy 74.836888 -20.191783) (xy 74.799671 -20.23332)
			(xy 74.756803 -20.268995) (xy 74.709197 -20.298049) (xy 74.657868 -20.319861) (xy 74.603911 -20.333967)
			(xy 74.548474 -20.340067) (xy 74.49274 -20.33803) (xy 74.437897 -20.3279) (xy 74.385113 -20.309893)
			(xy 74.335513 -20.284392) (xy 74.290155 -20.251941) (xy 74.250006 -20.213232) (xy 74.21592 -20.169089)
			(xy 74.188624 -20.120454) (xy 74.168701 -20.068363) (xy 74.156575 -20.013926) (xy 74.152504 -19.958304)
			(xy 61.893196 -19.958304) (xy 61.893196 -21.0881) (xy 69.020483 -21.0881) (xy 69.024513 -21.003501)
			(xy 69.036566 -20.919669) (xy 69.056533 -20.837362) (xy 69.084233 -20.757325) (xy 69.119415 -20.680284)
			(xy 69.161761 -20.606935) (xy 69.210887 -20.537944) (xy 69.266349 -20.473935) (xy 69.327643 -20.415488)
			(xy 69.394216 -20.363131) (xy 69.465464 -20.317339) (xy 69.540742 -20.278527) (xy 69.619368 -20.247046)
			(xy 69.700631 -20.223181) (xy 69.783794 -20.207149) (xy 69.868105 -20.199094) (xy 69.910452 -20.198588)
			(xy 69.952896 -20.19906) (xy 70.037397 -20.207152) (xy 70.120743 -20.223257) (xy 70.202175 -20.247229)
			(xy 70.280954 -20.278849) (xy 70.318884 -20.297902) (xy 70.330048 -20.302883) (xy 70.354456 -20.302883)
			(xy 70.36562 -20.297902) (xy 70.403559 -20.278868) (xy 70.482336 -20.247249) (xy 70.563766 -20.223278)
			(xy 70.64711 -20.207174) (xy 70.731609 -20.199083) (xy 70.774052 -20.198588) (xy 70.816403 -20.199082)
			(xy 70.90072 -20.207129) (xy 70.983892 -20.223155) (xy 71.065163 -20.247014) (xy 71.143798 -20.278491)
			(xy 71.219084 -20.317301) (xy 71.290341 -20.363091) (xy 71.356922 -20.415448) (xy 71.418225 -20.473896)
			(xy 71.473694 -20.537908) (xy 71.522826 -20.606902) (xy 71.565178 -20.680254) (xy 71.600365 -20.757301)
			(xy 71.628069 -20.837343) (xy 71.648039 -20.919656) (xy 71.65261 -20.951444) (xy 74.153774 -20.951444)
			(xy 74.157845 -20.895822) (xy 74.169971 -20.841385) (xy 74.189894 -20.789294) (xy 74.21719 -20.740659)
			(xy 74.251276 -20.696516) (xy 74.291425 -20.657807) (xy 74.336783 -20.625356) (xy 74.386383 -20.599855)
			(xy 74.439167 -20.581848) (xy 74.49401 -20.571718) (xy 74.549744 -20.569681) (xy 74.605181 -20.575781)
			(xy 74.659138 -20.589887) (xy 74.710467 -20.611699) (xy 74.758073 -20.640753) (xy 74.800941 -20.676428)
			(xy 74.838158 -20.717965) (xy 74.868931 -20.764478) (xy 74.892603 -20.814975) (xy 74.908671 -20.868382)
			(xy 74.916791 -20.923558) (xy 74.9173 -20.951444) (xy 74.916791 -20.97933) (xy 74.908671 -21.034506)
			(xy 74.892603 -21.087913) (xy 74.868931 -21.13841) (xy 74.838158 -21.184923) (xy 74.800941 -21.22646)
			(xy 74.758073 -21.262135) (xy 74.710467 -21.291189) (xy 74.659138 -21.313001) (xy 74.605181 -21.327107)
			(xy 74.549744 -21.333207) (xy 74.49401 -21.33117) (xy 74.439167 -21.32104) (xy 74.386383 -21.303033)
			(xy 74.336783 -21.277532) (xy 74.291425 -21.245081) (xy 74.251276 -21.206372) (xy 74.21719 -21.162229)
			(xy 74.189894 -21.113594) (xy 74.169971 -21.061503) (xy 74.157845 -21.007066) (xy 74.153774 -20.951444)
			(xy 71.65261 -20.951444) (xy 71.660094 -21.003495) (xy 71.664124 -21.0881) (xy 71.660094 -21.172705)
			(xy 71.648039 -21.256544) (xy 71.628069 -21.338857) (xy 71.600365 -21.418899) (xy 71.565178 -21.495946)
			(xy 71.522826 -21.569298) (xy 71.473694 -21.638292) (xy 71.418225 -21.702304) (xy 71.356922 -21.760752)
			(xy 71.290341 -21.813109) (xy 71.247803 -21.840444) (xy 74.153774 -21.840444) (xy 74.157845 -21.784822)
			(xy 74.169971 -21.730385) (xy 74.189894 -21.678294) (xy 74.21719 -21.629659) (xy 74.251276 -21.585516)
			(xy 74.291425 -21.546807) (xy 74.336783 -21.514356) (xy 74.386383 -21.488855) (xy 74.439167 -21.470848)
			(xy 74.49401 -21.460718) (xy 74.549744 -21.458681) (xy 74.605181 -21.464781) (xy 74.659138 -21.478887)
			(xy 74.710467 -21.500699) (xy 74.758073 -21.529753) (xy 74.800941 -21.565428) (xy 74.838158 -21.606965)
			(xy 74.868931 -21.653478) (xy 74.892603 -21.703975) (xy 74.908671 -21.757382) (xy 74.916791 -21.812558)
			(xy 74.9173 -21.840444) (xy 74.916791 -21.86833) (xy 74.908671 -21.923506) (xy 74.892603 -21.976913)
			(xy 74.868931 -22.02741) (xy 74.838158 -22.073923) (xy 74.800941 -22.11546) (xy 74.758073 -22.151135)
			(xy 74.710467 -22.180189) (xy 74.659138 -22.202001) (xy 74.605181 -22.216107) (xy 74.549744 -22.222207)
			(xy 74.49401 -22.22017) (xy 74.439167 -22.21004) (xy 74.386383 -22.192033) (xy 74.336783 -22.166532)
			(xy 74.291425 -22.134081) (xy 74.251276 -22.095372) (xy 74.21719 -22.051229) (xy 74.189894 -22.002594)
			(xy 74.169971 -21.950503) (xy 74.157845 -21.896066) (xy 74.153774 -21.840444) (xy 71.247803 -21.840444)
			(xy 71.219084 -21.858899) (xy 71.143798 -21.897709) (xy 71.065163 -21.929186) (xy 70.983892 -21.953045)
			(xy 70.90072 -21.969071) (xy 70.816403 -21.977118) (xy 70.774052 -21.977604) (xy 70.731608 -21.977131)
			(xy 70.647107 -21.969039) (xy 70.563761 -21.952935) (xy 70.482329 -21.928963) (xy 70.40355 -21.897343)
			(xy 70.36562 -21.87829) (xy 70.354456 -21.873309) (xy 70.330048 -21.873309) (xy 70.318884 -21.87829)
			(xy 70.280962 -21.897359) (xy 70.20218 -21.928972) (xy 70.120745 -21.952935) (xy 70.037398 -21.969031)
			(xy 69.952896 -21.977114) (xy 69.910452 -21.977604) (xy 69.868105 -21.977106) (xy 69.783794 -21.969051)
			(xy 69.700631 -21.953019) (xy 69.619368 -21.929154) (xy 69.540742 -21.897673) (xy 69.465464 -21.858861)
			(xy 69.394216 -21.813069) (xy 69.327643 -21.760712) (xy 69.266349 -21.702265) (xy 69.210887 -21.638256)
			(xy 69.161761 -21.569265) (xy 69.119415 -21.495916) (xy 69.084233 -21.418875) (xy 69.056533 -21.338838)
			(xy 69.036566 -21.256531) (xy 69.024513 -21.172699) (xy 69.020483 -21.0881) (xy 61.893196 -21.0881)
			(xy 61.893196 -23.447432) (xy 62.126618 -23.447432) (xy 62.126618 -23.362736) (xy 62.134669 -23.278422)
			(xy 62.150698 -23.195256) (xy 62.174559 -23.113989) (xy 62.206038 -23.035359) (xy 62.244849 -22.960078)
			(xy 62.290639 -22.888826) (xy 62.342995 -22.82225) (xy 62.401443 -22.760952) (xy 62.465453 -22.705487)
			(xy 62.534445 -22.656358) (xy 62.607795 -22.614009) (xy 62.684838 -22.578825) (xy 62.764877 -22.551123)
			(xy 62.847186 -22.531155) (xy 62.931021 -22.519102) (xy 63.015622 -22.515072) (xy 63.100223 -22.519102)
			(xy 63.184058 -22.531155) (xy 63.266367 -22.551123) (xy 63.346406 -22.578825) (xy 63.423449 -22.614009)
			(xy 63.496799 -22.656358) (xy 63.565791 -22.705487) (xy 63.629801 -22.760952) (xy 63.688249 -22.82225)
			(xy 63.740605 -22.888826) (xy 63.786395 -22.960078) (xy 63.825206 -23.035359) (xy 63.856685 -23.113989)
			(xy 63.880546 -23.195256) (xy 63.896575 -23.278422) (xy 63.904626 -23.362736) (xy 63.90513 -23.405084)
			(xy 63.904626 -23.447432) (xy 63.896575 -23.531746) (xy 63.880546 -23.614912) (xy 63.856685 -23.696179)
			(xy 63.825206 -23.774809) (xy 63.786395 -23.85009) (xy 63.740605 -23.921342) (xy 63.688249 -23.987918)
			(xy 63.629801 -24.049216) (xy 63.565791 -24.104681) (xy 63.496799 -24.15381) (xy 63.423449 -24.196159)
			(xy 63.346406 -24.231343) (xy 63.266367 -24.259045) (xy 63.184058 -24.279013) (xy 63.100223 -24.291066)
			(xy 63.015622 -24.295097) (xy 62.931021 -24.291066) (xy 62.847186 -24.279013) (xy 62.764877 -24.259045)
			(xy 62.684838 -24.231343) (xy 62.607795 -24.196159) (xy 62.534445 -24.15381) (xy 62.465453 -24.104681)
			(xy 62.401443 -24.049216) (xy 62.342995 -23.987918) (xy 62.290639 -23.921342) (xy 62.244849 -23.85009)
			(xy 62.206038 -23.774809) (xy 62.174559 -23.696179) (xy 62.150698 -23.614912) (xy 62.134669 -23.531746)
			(xy 62.126618 -23.447432) (xy 61.893196 -23.447432) (xy 61.893196 -25.181306) (xy 61.893654 -25.191184)
			(xy 61.901094 -25.209486) (xy 61.907674 -25.216866) (xy 61.907928 -25.21712) (xy 61.961776 -25.270968)
			(xy 61.968023 -25.276803) (xy 61.983386 -25.284272) (xy 62.000357 -25.286226) (xy 62.008766 -25.284684)
			(xy 62.092332 -25.266142) (xy 62.10054 -25.263943) (xy 62.115007 -25.255051) (xy 62.125807 -25.241948)
			(xy 62.129162 -25.234138) (xy 62.129162 -25.233884) (xy 62.143928 -25.194795) (xy 62.179801 -25.119322)
			(xy 62.222594 -25.047547) (xy 62.27193 -24.980101) (xy 62.327374 -24.91758) (xy 62.388438 -24.860534)
			(xy 62.454583 -24.809467) (xy 62.525226 -24.764829) (xy 62.599744 -24.727013) (xy 62.67748 -24.696353)
			(xy 62.757749 -24.673118) (xy 62.839844 -24.657515) (xy 62.92304 -24.649679) (xy 62.964822 -24.649176)
			(xy 63.008168 -24.649696) (xy 63.094449 -24.65813) (xy 63.1795 -24.674916) (xy 63.262516 -24.699895)
			(xy 63.342708 -24.73283) (xy 63.419317 -24.773408) (xy 63.491616 -24.821245) (xy 63.55892 -24.875887)
			(xy 63.620589 -24.936817) (xy 63.67604 -25.003455) (xy 63.724747 -25.075171) (xy 63.766247 -25.151285)
			(xy 63.783718 -25.190958) (xy 63.784647 -25.193244) (xy 70.553324 -25.193244) (xy 70.557395 -25.137622)
			(xy 70.569521 -25.083185) (xy 70.589444 -25.031094) (xy 70.61674 -24.982459) (xy 70.650826 -24.938316)
			(xy 70.690975 -24.899607) (xy 70.736333 -24.867156) (xy 70.785933 -24.841655) (xy 70.838717 -24.823648)
			(xy 70.89356 -24.813518) (xy 70.949294 -24.811481) (xy 71.004731 -24.817581) (xy 71.058688 -24.831687)
			(xy 71.110017 -24.853499) (xy 71.157623 -24.882553) (xy 71.200491 -24.918228) (xy 71.237708 -24.959765)
			(xy 71.268481 -25.006278) (xy 71.292153 -25.056775) (xy 71.308221 -25.110182) (xy 71.316341 -25.165358)
			(xy 71.31685 -25.193244) (xy 71.316341 -25.22113) (xy 71.308221 -25.276306) (xy 71.292153 -25.329713)
			(xy 71.268481 -25.38021) (xy 71.237708 -25.426723) (xy 71.200491 -25.46826) (xy 71.157623 -25.503935)
			(xy 71.110017 -25.532989) (xy 71.058688 -25.554801) (xy 71.004731 -25.568907) (xy 70.949294 -25.575007)
			(xy 70.89356 -25.57297) (xy 70.838717 -25.56284) (xy 70.785933 -25.544833) (xy 70.736333 -25.519332)
			(xy 70.690975 -25.486881) (xy 70.650826 -25.448172) (xy 70.61674 -25.404029) (xy 70.589444 -25.355394)
			(xy 70.569521 -25.303303) (xy 70.557395 -25.248866) (xy 70.553324 -25.193244) (xy 63.784647 -25.193244)
			(xy 63.78702 -25.199086) (xy 63.805054 -25.21839) (xy 63.808171 -25.221597) (xy 63.815327 -25.226962)
			(xy 63.819278 -25.229058) (xy 63.845948 -25.24252) (xy 63.862966 -25.244552) (xy 63.871856 -25.242774)
			(xy 63.892473 -25.238415) (xy 63.934351 -25.233704) (xy 63.955422 -25.233376) (xy 63.982673 -25.233863)
			(xy 64.036619 -25.241622) (xy 64.088912 -25.256979) (xy 64.138487 -25.279621) (xy 64.184336 -25.309088)
			(xy 64.225525 -25.344779) (xy 64.261216 -25.385969) (xy 64.290682 -25.431818) (xy 64.313323 -25.481394)
			(xy 64.328679 -25.533687) (xy 64.336437 -25.587633) (xy 64.33693 -25.614884) (xy 64.336386 -25.644367)
			(xy 64.327313 -25.702631) (xy 64.309365 -25.758799) (xy 64.282972 -25.811529) (xy 64.266318 -25.835864)
			(xy 64.257936 -25.847802) (xy 64.255904 -25.875742) (xy 64.30391 -25.968706) (xy 64.30645 -25.973278)
			(xy 64.313542 -25.983021) (xy 64.334349 -25.99511) (xy 64.346328 -25.996392)
		)
		(stroke
			(width 0)
			(type solid)
		)
		(fill yes)
		(layer "In2.Cu")
		(net "P12V_OCP_V3_2")
	)
	(gr_poly
		(pts
			(xy 201.766932 -399.318988) (xy 201.776999 -399.318559) (xy 201.795594 -399.310835) (xy 201.803 -399.304002)
			(xy 203.3778 -397.729202) (xy 203.385198 -397.722355) (xy 203.403796 -397.71462) (xy 203.413868 -397.714216)
			(xy 206.779876 -397.714216) (xy 206.78994 -397.714653) (xy 206.808523 -397.722389) (xy 206.815944 -397.729202)
			(xy 208.390744 -399.304002) (xy 208.398145 -399.310841) (xy 208.416743 -399.318559) (xy 208.426812 -399.318988)
			(xy 212.484462 -399.318988) (xy 212.494527 -399.318553) (xy 212.513114 -399.310822) (xy 212.52053 -399.304002)
			(xy 213.827868 -397.996664) (xy 213.835267 -397.989821) (xy 213.853866 -397.982101) (xy 213.863936 -397.981678)
			(xy 217.608912 -397.981678) (xy 217.618982 -397.982103) (xy 217.637585 -397.989818) (xy 217.64498 -397.996664)
			(xy 218.952318 -399.304002) (xy 218.959718 -399.310845) (xy 218.978316 -399.318573) (xy 218.988386 -399.318988)
			(xy 223.134936 -399.318988) (xy 223.145003 -399.318558) (xy 223.163597 -399.310833) (xy 223.171004 -399.304002)
			(xy 224.45599 -398.019016) (xy 224.463387 -398.012166) (xy 224.481985 -398.004425) (xy 224.492058 -398.00403)
			(xy 228.370892 -398.00403) (xy 228.380962 -398.004452) (xy 228.399566 -398.012168) (xy 228.40696 -398.019016)
			(xy 229.691946 -399.304002) (xy 229.699347 -399.310841) (xy 229.717945 -399.318558) (xy 229.728014 -399.318988)
			(xy 234.185968 -399.318988) (xy 234.196032 -399.318552) (xy 234.214618 -399.310819) (xy 234.222036 -399.304002)
			(xy 238.249206 -395.276832) (xy 238.256041 -395.26943) (xy 238.26375 -395.250831) (xy 238.264192 -395.240764)
			(xy 238.264192 -385.429252) (xy 238.256572 -385.41071) (xy 238.254794 -385.408932) (xy 238.254794 -383.056384)
			(xy 238.25522 -383.046315) (xy 238.262937 -383.027714) (xy 238.26978 -383.020316) (xy 238.369348 -382.920748)
			(xy 238.376747 -382.913904) (xy 238.395346 -382.906179) (xy 238.405416 -382.905762) (xy 278.04491 -382.905762)
			(xy 278.054979 -382.905336) (xy 278.073577 -382.897615) (xy 278.080978 -382.890776) (xy 278.196294 -382.77546)
			(xy 278.203135 -382.76806) (xy 278.210856 -382.749461) (xy 278.21128 -382.739392) (xy 278.21128 -382.71704)
			(xy 278.211373 -382.712021) (xy 278.213294 -382.70217) (xy 278.21509 -382.697482) (xy 278.222456 -382.68021)
			(xy 278.224257 -382.675524) (xy 278.226178 -382.665671) (xy 278.226266 -382.660652) (xy 278.226266 -376.200416)
			(xy 278.225827 -376.190353) (xy 278.218087 -376.171774) (xy 278.21128 -376.164348) (xy 277.044658 -374.997726)
			(xy 277.037312 -374.990919) (xy 277.018849 -374.983198) (xy 277.008844 -374.98274) (xy 207.759808 -374.98274)
			(xy 207.749789 -374.983159) (xy 207.731276 -374.990829) (xy 207.717111 -375.005003) (xy 207.709453 -375.02352)
			(xy 207.709008 -375.03354) (xy 207.709008 -375.12117) (xy 207.709391 -375.131293) (xy 207.717134 -375.149995)
			(xy 207.731536 -375.164218) (xy 207.740758 -375.168414) (xy 207.775986 -375.183191) (xy 207.84357 -375.218815)
			(xy 207.907255 -375.261016) (xy 207.966402 -375.309373) (xy 207.993742 -375.336054) (xy 209.212434 -376.554746)
			(xy 209.238325 -376.581238) (xy 209.285404 -376.638433) (xy 209.326717 -376.699924) (xy 209.361873 -376.76513)
			(xy 209.390542 -376.833437) (xy 209.401918 -376.86869) (xy 209.405719 -376.879029) (xy 209.420468 -376.895359)
			(xy 209.44069 -376.904035) (xy 209.451702 -376.90425) (xy 209.477356 -376.903996) (xy 209.51846 -376.904454)
			(xy 209.600319 -376.912036) (xy 209.681129 -376.927138) (xy 209.7602 -376.949632) (xy 209.836858 -376.979327)
			(xy 209.91045 -377.015968) (xy 209.980347 -377.059243) (xy 210.045952 -377.108783) (xy 210.106706 -377.164165)
			(xy 210.162091 -377.224917) (xy 210.211634 -377.29052) (xy 210.254913 -377.360415) (xy 210.291557 -377.434005)
			(xy 210.321255 -377.510662) (xy 210.343753 -377.589733) (xy 210.358859 -377.670542) (xy 210.366444 -377.7524)
			(xy 210.366864 -377.793504) (xy 210.366279 -377.8399) (xy 210.356645 -377.93219) (xy 210.33745 -378.022975)
			(xy 210.308905 -378.111266) (xy 210.290664 -378.15393) (xy 210.286846 -378.16387) (xy 210.286847 -378.185137)
			(xy 210.290664 -378.195078) (xy 210.308902 -378.237743) (xy 210.337442 -378.326036) (xy 210.356638 -378.41682)
			(xy 210.366283 -378.509108) (xy 210.366864 -378.555504) (xy 210.366401 -378.596759) (xy 210.358766 -378.678915)
			(xy 210.343554 -378.760011) (xy 210.320895 -378.839348) (xy 210.290985 -378.916246) (xy 210.254079 -378.990042)
			(xy 210.210497 -379.060103) (xy 210.160611 -379.125824) (xy 210.104852 -379.186643) (xy 210.0437 -379.242034)
			(xy 209.977678 -379.291523) (xy 209.907357 -379.334682) (xy 209.870548 -379.353318) (xy 209.862245 -379.357881)
			(xy 209.849513 -379.371894) (xy 209.842729 -379.38957) (xy 209.842354 -379.399038) (xy 209.842354 -379.48997)
			(xy 209.842696 -379.49944) (xy 209.849494 -379.517116) (xy 209.862248 -379.531115) (xy 209.870548 -379.53569)
			(xy 209.907344 -379.554347) (xy 209.977653 -379.59752) (xy 210.043662 -379.647016) (xy 210.104806 -379.702412)
			(xy 210.160558 -379.76323) (xy 210.21044 -379.82895) (xy 210.254023 -379.899005) (xy 210.290933 -379.972794)
			(xy 210.320852 -380.049684) (xy 210.343524 -380.129014) (xy 210.358754 -380.210102) (xy 210.366411 -380.292251)
			(xy 210.366864 -380.333504) (xy 210.366279 -380.3799) (xy 210.356645 -380.47219) (xy 210.33745 -380.562975)
			(xy 210.308905 -380.651266) (xy 210.290664 -380.69393) (xy 210.286846 -380.70387) (xy 210.286847 -380.725137)
			(xy 210.290664 -380.735078) (xy 210.308902 -380.777743) (xy 210.337442 -380.866036) (xy 210.356638 -380.95682)
			(xy 210.366283 -381.049108) (xy 210.366864 -381.095504) (xy 210.366352 -381.138362) (xy 210.358109 -381.223681)
			(xy 210.342093 -381.3058) (xy 242.544088 -381.3058) (xy 242.548118 -381.221198) (xy 242.560172 -381.137363)
			(xy 242.58014 -381.055053) (xy 242.607842 -380.975014) (xy 242.643027 -380.897971) (xy 242.685376 -380.824621)
			(xy 242.734505 -380.755628) (xy 242.789971 -380.691619) (xy 242.851269 -380.633171) (xy 242.917846 -380.580815)
			(xy 242.989099 -380.535024) (xy 243.064381 -380.496214) (xy 243.143012 -380.464736) (xy 243.224278 -380.440874)
			(xy 243.307445 -380.424846) (xy 243.391759 -380.416796) (xy 243.434108 -380.416308) (xy 243.474162 -380.41672)
			(xy 243.553944 -380.423932) (xy 243.632755 -380.438288) (xy 243.709956 -380.459672) (xy 243.784921 -380.48791)
			(xy 243.857045 -380.522773) (xy 243.925741 -380.56398) (xy 243.990455 -380.611197) (xy 244.020848 -380.637288)
			(xy 244.027964 -380.642979) (xy 244.045018 -380.649358) (xy 244.054122 -380.649734) (xy 244.084094 -380.649734)
			(xy 244.093196 -380.64935) (xy 244.110247 -380.64297) (xy 244.117368 -380.637288) (xy 244.147764 -380.611201)
			(xy 244.212475 -380.563983) (xy 244.281171 -380.522776) (xy 244.353294 -380.487914) (xy 244.42826 -380.459679)
			(xy 244.505461 -380.4383) (xy 244.584272 -380.423951) (xy 244.664055 -380.416748) (xy 244.704108 -380.416308)
			(xy 244.746457 -380.41678) (xy 244.830771 -380.424832) (xy 244.913939 -380.440862) (xy 244.995206 -380.464724)
			(xy 245.073836 -380.496204) (xy 245.149119 -380.535015) (xy 245.220371 -380.580807) (xy 245.286948 -380.633164)
			(xy 245.348247 -380.691613) (xy 245.403712 -380.755624) (xy 245.452841 -380.824617) (xy 245.49519 -380.897967)
			(xy 245.530375 -380.975012) (xy 245.558077 -381.055051) (xy 245.578045 -381.137362) (xy 245.590098 -381.221198)
			(xy 245.594129 -381.3058) (xy 248.479103 -381.3058) (xy 248.483133 -381.221202) (xy 248.495186 -381.13737)
			(xy 248.515153 -381.055064) (xy 248.542853 -380.975028) (xy 248.578036 -380.897988) (xy 248.620382 -380.82464)
			(xy 248.669508 -380.75565) (xy 248.72497 -380.691642) (xy 248.786265 -380.633196) (xy 248.852838 -380.58084)
			(xy 248.924086 -380.53505) (xy 248.999364 -380.496239) (xy 249.07799 -380.46476) (xy 249.159252 -380.440897)
			(xy 249.242415 -380.424866) (xy 249.326725 -380.416813) (xy 249.369072 -380.416308) (xy 249.409125 -380.416742)
			(xy 249.488907 -380.423951) (xy 249.567717 -380.438304) (xy 249.644918 -380.459684) (xy 249.719884 -380.487919)
			(xy 249.792007 -380.52278) (xy 249.860704 -380.563984) (xy 249.925418 -380.611198) (xy 249.955812 -380.637288)
			(xy 249.962939 -380.642963) (xy 249.979984 -380.649352) (xy 249.989086 -380.649734) (xy 250.019058 -380.649734)
			(xy 250.028158 -380.649333) (xy 250.045209 -380.642965) (xy 250.052332 -380.637288) (xy 250.082702 -380.61117)
			(xy 250.147418 -380.563954) (xy 250.216118 -380.522751) (xy 250.288245 -380.487892) (xy 250.363214 -380.459661)
			(xy 250.440419 -380.438287) (xy 250.519233 -380.423943) (xy 250.599018 -380.416745) (xy 250.639072 -380.416308)
			(xy 250.681423 -380.416763) (xy 250.765741 -380.424812) (xy 250.848913 -380.440839) (xy 250.930184 -380.4647)
			(xy 251.008819 -380.496179) (xy 251.084106 -380.53499) (xy 251.155362 -380.580782) (xy 251.221943 -380.63314)
			(xy 251.283246 -380.691589) (xy 251.338714 -380.755602) (xy 251.387847 -380.824597) (xy 251.430199 -380.897951)
			(xy 251.465386 -380.974998) (xy 251.49309 -381.055041) (xy 251.513059 -381.137355) (xy 251.525114 -381.221194)
			(xy 251.529144 -381.3058) (xy 254.413988 -381.3058) (xy 254.418018 -381.221197) (xy 254.430073 -381.13736)
			(xy 254.450042 -381.055048) (xy 254.477745 -380.975008) (xy 254.512931 -380.897963) (xy 254.555281 -380.824612)
			(xy 254.604413 -380.755619) (xy 254.65988 -380.691609) (xy 254.721181 -380.633161) (xy 254.78776 -380.580805)
			(xy 254.859015 -380.535015) (xy 254.934299 -380.496206) (xy 255.012932 -380.464729) (xy 255.094201 -380.440869)
			(xy 255.17737 -380.424842) (xy 255.261686 -380.416794) (xy 255.304036 -380.416308) (xy 255.344089 -380.416764)
			(xy 255.42387 -380.42397) (xy 255.502679 -380.43832) (xy 255.57988 -380.459697) (xy 255.654846 -380.487929)
			(xy 255.726969 -380.522787) (xy 255.795667 -380.563988) (xy 255.860382 -380.6112) (xy 255.890776 -380.637288)
			(xy 255.897884 -380.64299) (xy 255.914944 -380.649363) (xy 255.92405 -380.649734) (xy 255.954022 -380.649734)
			(xy 255.963125 -380.649364) (xy 255.980176 -380.642974) (xy 255.987296 -380.637288) (xy 256.017681 -380.611187)
			(xy 256.082394 -380.56397) (xy 256.151091 -380.522765) (xy 256.223216 -380.487904) (xy 256.298184 -380.459671)
			(xy 256.375386 -380.438295) (xy 256.454199 -380.423948) (xy 256.533982 -380.416747) (xy 256.574036 -380.416308)
			(xy 256.616384 -380.416781) (xy 256.700697 -380.424835) (xy 256.783862 -380.440867) (xy 256.865127 -380.464732)
			(xy 256.943755 -380.496212) (xy 257.019035 -380.535025) (xy 257.090285 -380.580817) (xy 257.15686 -380.633174)
			(xy 257.218156 -380.691623) (xy 257.273619 -380.755633) (xy 257.322747 -380.824625) (xy 257.365094 -380.897975)
			(xy 257.400277 -380.975018) (xy 257.427978 -381.055056) (xy 257.447945 -381.137365) (xy 257.459999 -381.2212)
			(xy 257.464029 -381.3058) (xy 260.349004 -381.3058) (xy 260.353033 -381.2212) (xy 260.365087 -381.137367)
			(xy 260.385055 -381.055059) (xy 260.412756 -380.975022) (xy 260.44794 -380.89798) (xy 260.490287 -380.824632)
			(xy 260.539415 -380.755641) (xy 260.594879 -380.691632) (xy 260.656176 -380.633186) (xy 260.722751 -380.58083)
			(xy 260.794002 -380.53504) (xy 260.869282 -380.496231) (xy 260.947911 -380.464753) (xy 261.029175 -380.440891)
			(xy 261.11234 -380.424862) (xy 261.196652 -380.416812) (xy 261.239 -380.416308) (xy 261.279054 -380.416725)
			(xy 261.358836 -380.423936) (xy 261.437646 -380.438292) (xy 261.514847 -380.459674) (xy 261.589813 -380.487912)
			(xy 261.661936 -380.522775) (xy 261.730633 -380.563981) (xy 261.795346 -380.611197) (xy 261.82574 -380.637288)
			(xy 261.832859 -380.642975) (xy 261.84991 -380.649357) (xy 261.859014 -380.649734) (xy 261.888986 -380.649734)
			(xy 261.898088 -380.649346) (xy 261.915138 -380.642969) (xy 261.92226 -380.637288) (xy 261.952659 -380.611204)
			(xy 262.01737 -380.563986) (xy 262.086065 -380.522779) (xy 262.158188 -380.487916) (xy 262.233153 -380.459681)
			(xy 262.310354 -380.438302) (xy 262.389165 -380.423952) (xy 262.468947 -380.416748) (xy 262.509 -380.416308)
			(xy 262.551349 -380.41678) (xy 262.635664 -380.424831) (xy 262.718832 -380.44086) (xy 262.8001 -380.464722)
			(xy 262.878731 -380.496202) (xy 262.954014 -380.535013) (xy 263.025267 -380.580804) (xy 263.091845 -380.633161)
			(xy 263.153144 -380.69161) (xy 263.20861 -380.755621) (xy 263.25774 -380.824614) (xy 263.300089 -380.897965)
			(xy 263.335274 -380.97501) (xy 263.362976 -381.05505) (xy 263.382945 -381.137361) (xy 263.394998 -381.221197)
			(xy 263.399029 -381.3058) (xy 266.284003 -381.3058) (xy 266.288033 -381.221203) (xy 266.300086 -381.137371)
			(xy 266.320053 -381.055065) (xy 266.347753 -380.97503) (xy 266.382935 -380.89799) (xy 266.42528 -380.824643)
			(xy 266.474406 -380.755653) (xy 266.529867 -380.691645) (xy 266.591161 -380.633198) (xy 266.657734 -380.580843)
			(xy 266.728981 -380.535052) (xy 266.804258 -380.496242) (xy 266.882884 -380.464762) (xy 266.964146 -380.440898)
			(xy 267.047308 -380.424867) (xy 267.131617 -380.416813) (xy 267.173964 -380.416308) (xy 267.214017 -380.416747)
			(xy 267.293799 -380.423955) (xy 267.372609 -380.438307) (xy 267.449809 -380.459687) (xy 267.524775 -380.487921)
			(xy 267.596899 -380.522782) (xy 267.665596 -380.563985) (xy 267.73031 -380.611199) (xy 267.760704 -380.637288)
			(xy 267.767804 -380.643002) (xy 267.78487 -380.649368) (xy 267.793978 -380.649734) (xy 267.82395 -380.649734)
			(xy 267.83305 -380.649329) (xy 267.850101 -380.642964) (xy 267.857224 -380.637288) (xy 267.887598 -380.611174)
			(xy 267.952313 -380.563958) (xy 268.021012 -380.522754) (xy 268.093138 -380.487895) (xy 268.168107 -380.459664)
			(xy 268.245312 -380.438289) (xy 268.324125 -380.423944) (xy 268.40391 -380.416746) (xy 268.443964 -380.416308)
			(xy 268.486315 -380.416762) (xy 268.570634 -380.424811) (xy 268.653806 -380.440838) (xy 268.735078 -380.464698)
			(xy 268.813714 -380.496177) (xy 268.889001 -380.534987) (xy 268.960258 -380.580779) (xy 269.02684 -380.633137)
			(xy 269.088143 -380.691587) (xy 269.143612 -380.755599) (xy 269.192746 -380.824595) (xy 269.235098 -380.897949)
			(xy 269.270285 -380.974996) (xy 269.297989 -381.055039) (xy 269.317959 -381.137354) (xy 269.330014 -381.221194)
			(xy 269.334044 -381.3058) (xy 272.218888 -381.3058) (xy 272.222918 -381.221197) (xy 272.234972 -381.137361)
			(xy 272.254941 -381.05505) (xy 272.282644 -380.97501) (xy 272.31783 -380.897965) (xy 272.36018 -380.824615)
			(xy 272.409311 -380.755622) (xy 272.464777 -380.691612) (xy 272.526078 -380.633164) (xy 272.592656 -380.580808)
			(xy 272.66391 -380.535018) (xy 272.739194 -380.496208) (xy 272.817826 -380.464731) (xy 272.899095 -380.44087)
			(xy 272.982263 -380.424843) (xy 273.066579 -380.416795) (xy 273.108928 -380.416308) (xy 273.148981 -380.416769)
			(xy 273.228761 -380.423974) (xy 273.307571 -380.438323) (xy 273.384772 -380.4597) (xy 273.459737 -380.487931)
			(xy 273.531861 -380.522788) (xy 273.600559 -380.563989) (xy 273.665274 -380.6112) (xy 273.695668 -380.637288)
			(xy 273.702779 -380.642987) (xy 273.719837 -380.649362) (xy 273.728942 -380.649734) (xy 273.758914 -380.649734)
			(xy 273.768017 -380.64936) (xy 273.785068 -380.642973) (xy 273.792188 -380.637288) (xy 273.822576 -380.611191)
			(xy 273.887289 -380.563974) (xy 273.955986 -380.522768) (xy 274.02811 -380.487907) (xy 274.103077 -380.459673)
			(xy 274.180279 -380.438296) (xy 274.259091 -380.423949) (xy 274.338874 -380.416747) (xy 274.378928 -380.416308)
			(xy 274.421276 -380.416781) (xy 274.505589 -380.424834) (xy 274.588755 -380.440866) (xy 274.670021 -380.46473)
			(xy 274.74865 -380.49621) (xy 274.82393 -380.535022) (xy 274.895181 -380.580814) (xy 274.961756 -380.633171)
			(xy 275.023053 -380.69162) (xy 275.078517 -380.75563) (xy 275.127645 -380.824623) (xy 275.169993 -380.897973)
			(xy 275.205176 -380.975016) (xy 275.232878 -381.055055) (xy 275.252845 -381.137364) (xy 275.264899 -381.221199)
			(xy 275.268929 -381.3058) (xy 275.264899 -381.390401) (xy 275.252845 -381.474236) (xy 275.232878 -381.556545)
			(xy 275.205176 -381.636584) (xy 275.169993 -381.713627) (xy 275.127645 -381.786977) (xy 275.078517 -381.85597)
			(xy 275.023053 -381.91998) (xy 274.961756 -381.978429) (xy 274.895181 -382.030786) (xy 274.82393 -382.076578)
			(xy 274.74865 -382.11539) (xy 274.670021 -382.14687) (xy 274.588755 -382.170734) (xy 274.505589 -382.186766)
			(xy 274.421276 -382.194819) (xy 274.378928 -382.195324) (xy 274.338875 -382.194882) (xy 274.259094 -382.187673)
			(xy 274.180284 -382.173321) (xy 274.103083 -382.151941) (xy 274.028118 -382.123707) (xy 273.955994 -382.088848)
			(xy 273.887297 -382.047645) (xy 273.822582 -382.000433) (xy 273.792188 -381.974344) (xy 273.785058 -381.968672)
			(xy 273.768015 -381.96228) (xy 273.758914 -381.961898) (xy 273.728942 -381.961898) (xy 273.719844 -381.962314)
			(xy 273.702793 -381.968673) (xy 273.695668 -381.974344) (xy 273.665302 -382.000468) (xy 273.600585 -382.047682)
			(xy 273.531885 -382.088884) (xy 273.459757 -382.123742) (xy 273.384787 -382.151972) (xy 273.307582 -382.173345)
			(xy 273.228767 -382.187689) (xy 273.148983 -382.194887) (xy 273.108928 -382.195324) (xy 273.066579 -382.194805)
			(xy 272.982263 -382.186757) (xy 272.899095 -382.17073) (xy 272.817826 -382.146869) (xy 272.739194 -382.115392)
			(xy 272.66391 -382.076582) (xy 272.592656 -382.030792) (xy 272.526078 -381.978436) (xy 272.464777 -381.919988)
			(xy 272.409311 -381.855978) (xy 272.36018 -381.786985) (xy 272.31783 -381.713635) (xy 272.282644 -381.63659)
			(xy 272.254941 -381.55655) (xy 272.234972 -381.474239) (xy 272.222918 -381.390403) (xy 272.218888 -381.3058)
			(xy 269.334044 -381.3058) (xy 269.330014 -381.390406) (xy 269.317959 -381.474246) (xy 269.297989 -381.556561)
			(xy 269.270285 -381.636604) (xy 269.235098 -381.713651) (xy 269.192746 -381.787005) (xy 269.143612 -381.856001)
			(xy 269.088143 -381.920013) (xy 269.02684 -381.978463) (xy 268.960258 -382.030821) (xy 268.889001 -382.076613)
			(xy 268.813714 -382.115423) (xy 268.735078 -382.146902) (xy 268.653806 -382.170762) (xy 268.570634 -382.186789)
			(xy 268.486315 -382.194838) (xy 268.443964 -382.195324) (xy 268.403911 -382.19486) (xy 268.324131 -382.187654)
			(xy 268.245322 -382.173305) (xy 268.168121 -382.151929) (xy 268.093156 -382.123698) (xy 268.021032 -382.088841)
			(xy 267.952334 -382.047641) (xy 267.887619 -382.000432) (xy 267.857224 -381.974344) (xy 267.850113 -381.968645)
			(xy 267.833056 -381.962269) (xy 267.82395 -381.961898) (xy 267.793978 -381.961898) (xy 267.784876 -381.962283)
			(xy 267.767826 -381.968664) (xy 267.760704 -381.974344) (xy 267.730324 -382.00045) (xy 267.665609 -382.047666)
			(xy 267.596911 -382.08887) (xy 267.524786 -382.12373) (xy 267.449817 -382.151962) (xy 267.372614 -382.173338)
			(xy 267.293802 -382.187684) (xy 267.214018 -382.194885) (xy 267.173964 -382.195324) (xy 267.131617 -382.194787)
			(xy 267.047308 -382.186733) (xy 266.964146 -382.170702) (xy 266.882884 -382.146838) (xy 266.804258 -382.115358)
			(xy 266.728981 -382.076548) (xy 266.657734 -382.030757) (xy 266.591161 -381.978402) (xy 266.529867 -381.919955)
			(xy 266.474406 -381.855947) (xy 266.42528 -381.786957) (xy 266.382935 -381.71361) (xy 266.347753 -381.63657)
			(xy 266.320053 -381.556535) (xy 266.300086 -381.474229) (xy 266.288033 -381.390397) (xy 266.284003 -381.3058)
			(xy 263.399029 -381.3058) (xy 263.394998 -381.390403) (xy 263.382945 -381.474239) (xy 263.362976 -381.55655)
			(xy 263.335274 -381.63659) (xy 263.300089 -381.713635) (xy 263.25774 -381.786986) (xy 263.20861 -381.855979)
			(xy 263.153144 -381.91999) (xy 263.091845 -381.978439) (xy 263.025267 -382.030796) (xy 262.954014 -382.076587)
			(xy 262.878731 -382.115398) (xy 262.8001 -382.146878) (xy 262.718832 -382.17074) (xy 262.635664 -382.186769)
			(xy 262.551349 -382.19482) (xy 262.509 -382.195324) (xy 262.468947 -382.194899) (xy 262.389165 -382.187688)
			(xy 262.310355 -382.173333) (xy 262.233154 -382.151951) (xy 262.158188 -382.123715) (xy 262.086065 -382.088853)
			(xy 262.017368 -382.047648) (xy 261.952654 -382.000434) (xy 261.92226 -381.974344) (xy 261.915138 -381.96866)
			(xy 261.898089 -381.962275) (xy 261.888986 -381.961898) (xy 261.859014 -381.961898) (xy 261.849914 -381.962301)
			(xy 261.832864 -381.968669) (xy 261.82574 -381.974344) (xy 261.795345 -382.000433) (xy 261.730633 -382.04765)
			(xy 261.661937 -382.088856) (xy 261.589814 -382.123718) (xy 261.514848 -382.151952) (xy 261.437647 -382.173331)
			(xy 261.358836 -382.18768) (xy 261.279053 -382.194884) (xy 261.239 -382.195324) (xy 261.196652 -382.194788)
			(xy 261.11234 -382.186738) (xy 261.029175 -382.170709) (xy 260.947911 -382.146847) (xy 260.869282 -382.115369)
			(xy 260.794002 -382.07656) (xy 260.722751 -382.03077) (xy 260.656176 -381.978414) (xy 260.594879 -381.919968)
			(xy 260.539415 -381.855959) (xy 260.490287 -381.786968) (xy 260.44794 -381.71362) (xy 260.412756 -381.636578)
			(xy 260.385055 -381.556541) (xy 260.365087 -381.474233) (xy 260.353033 -381.3904) (xy 260.349004 -381.3058)
			(xy 257.464029 -381.3058) (xy 257.459999 -381.3904) (xy 257.447945 -381.474235) (xy 257.427978 -381.556544)
			(xy 257.400277 -381.636582) (xy 257.365094 -381.713625) (xy 257.322747 -381.786975) (xy 257.273619 -381.855967)
			(xy 257.218156 -381.919977) (xy 257.15686 -381.978426) (xy 257.090285 -382.030783) (xy 257.019035 -382.076575)
			(xy 256.943755 -382.115388) (xy 256.865127 -382.146868) (xy 256.783862 -382.170733) (xy 256.700697 -382.186765)
			(xy 256.616384 -382.194819) (xy 256.574036 -382.195324) (xy 256.533983 -382.194877) (xy 256.454202 -382.187669)
			(xy 256.375392 -382.173318) (xy 256.298192 -382.151939) (xy 256.223226 -382.123705) (xy 256.151103 -382.088846)
			(xy 256.082405 -382.047644) (xy 256.01769 -382.000433) (xy 255.987296 -381.974344) (xy 255.980193 -381.968633)
			(xy 255.963129 -381.962264) (xy 255.954022 -381.961898) (xy 255.92405 -381.961898) (xy 255.914952 -381.962318)
			(xy 255.897902 -381.968675) (xy 255.890776 -381.974344) (xy 255.860407 -382.000464) (xy 255.795691 -382.047678)
			(xy 255.726991 -382.088881) (xy 255.654863 -382.123739) (xy 255.579894 -382.15197) (xy 255.502689 -382.173344)
			(xy 255.423875 -382.187688) (xy 255.34409 -382.194886) (xy 255.304036 -382.195324) (xy 255.261686 -382.194806)
			(xy 255.17737 -382.186758) (xy 255.094201 -382.170731) (xy 255.012932 -382.146871) (xy 254.934299 -382.115394)
			(xy 254.859015 -382.076585) (xy 254.78776 -382.030795) (xy 254.721181 -381.978439) (xy 254.65988 -381.919991)
			(xy 254.604413 -381.855981) (xy 254.555281 -381.786988) (xy 254.512931 -381.713637) (xy 254.477745 -381.636592)
			(xy 254.450042 -381.556552) (xy 254.430073 -381.47424) (xy 254.418018 -381.390403) (xy 254.413988 -381.3058)
			(xy 251.529144 -381.3058) (xy 251.525114 -381.390406) (xy 251.513059 -381.474245) (xy 251.49309 -381.556559)
			(xy 251.465386 -381.636602) (xy 251.430199 -381.713649) (xy 251.387847 -381.787003) (xy 251.338714 -381.855998)
			(xy 251.283246 -381.920011) (xy 251.221943 -381.97846) (xy 251.155362 -382.030818) (xy 251.084106 -382.07661)
			(xy 251.008819 -382.115421) (xy 250.930184 -382.1469) (xy 250.848913 -382.170761) (xy 250.765741 -382.186788)
			(xy 250.681423 -382.194837) (xy 250.639072 -382.195324) (xy 250.59902 -382.194855) (xy 250.519239 -382.18765)
			(xy 250.44043 -382.173302) (xy 250.36323 -382.151926) (xy 250.288264 -382.123696) (xy 250.21614 -382.08884)
			(xy 250.147442 -382.04764) (xy 250.082727 -382.000431) (xy 250.052332 -381.974344) (xy 250.045219 -381.968649)
			(xy 250.028163 -381.962271) (xy 250.019058 -381.961898) (xy 249.989086 -381.961898) (xy 249.979985 -381.962287)
			(xy 249.962935 -381.968665) (xy 249.955812 -381.974344) (xy 249.925429 -382.000446) (xy 249.860715 -382.047662)
			(xy 249.792017 -382.088867) (xy 249.719892 -382.123727) (xy 249.644924 -382.15196) (xy 249.567721 -382.173336)
			(xy 249.488909 -382.187683) (xy 249.409126 -382.194885) (xy 249.369072 -382.195324) (xy 249.326725 -382.194787)
			(xy 249.242415 -382.186734) (xy 249.159252 -382.170703) (xy 249.07799 -382.14684) (xy 248.999364 -382.115361)
			(xy 248.924086 -382.07655) (xy 248.852838 -382.03076) (xy 248.786265 -381.978404) (xy 248.72497 -381.919958)
			(xy 248.669508 -381.85595) (xy 248.620382 -381.78696) (xy 248.578036 -381.713612) (xy 248.542853 -381.636572)
			(xy 248.515153 -381.556536) (xy 248.495186 -381.47423) (xy 248.483133 -381.390398) (xy 248.479103 -381.3058)
			(xy 245.594129 -381.3058) (xy 245.590098 -381.390402) (xy 245.578045 -381.474238) (xy 245.558077 -381.556549)
			(xy 245.530375 -381.636588) (xy 245.49519 -381.713633) (xy 245.452841 -381.786983) (xy 245.403712 -381.855976)
			(xy 245.348247 -381.919987) (xy 245.286948 -381.978436) (xy 245.220371 -382.030793) (xy 245.149119 -382.076585)
			(xy 245.073836 -382.115396) (xy 244.995206 -382.146876) (xy 244.913939 -382.170738) (xy 244.830771 -382.186768)
			(xy 244.746457 -382.19482) (xy 244.704108 -382.195324) (xy 244.664055 -382.194894) (xy 244.584273 -382.187684)
			(xy 244.505463 -382.17333) (xy 244.428262 -382.151948) (xy 244.353297 -382.123713) (xy 244.281173 -382.088852)
			(xy 244.212476 -382.047647) (xy 244.147762 -382.000434) (xy 244.117368 -381.974344) (xy 244.110244 -381.968664)
			(xy 244.093196 -381.962277) (xy 244.084094 -381.961898) (xy 244.054122 -381.961898) (xy 244.045023 -381.962304)
			(xy 244.027972 -381.968671) (xy 244.020848 -381.974344) (xy 243.99045 -382.000429) (xy 243.925739 -382.047646)
			(xy 243.857043 -382.088853) (xy 243.78492 -382.123715) (xy 243.709955 -382.15195) (xy 243.632754 -382.173329)
			(xy 243.553943 -382.187679) (xy 243.474161 -382.194883) (xy 243.434108 -382.195324) (xy 243.391759 -382.194804)
			(xy 243.307445 -382.186754) (xy 243.224278 -382.170726) (xy 243.143012 -382.146864) (xy 243.064381 -382.115386)
			(xy 242.989099 -382.076576) (xy 242.917846 -382.030785) (xy 242.851269 -381.978429) (xy 242.789971 -381.919981)
			(xy 242.734505 -381.855972) (xy 242.685376 -381.786979) (xy 242.643027 -381.713629) (xy 242.607842 -381.636586)
			(xy 242.58014 -381.556547) (xy 242.560172 -381.474237) (xy 242.548118 -381.390402) (xy 242.544088 -381.3058)
			(xy 210.342093 -381.3058) (xy 210.341701 -381.307812) (xy 210.317278 -381.389976) (xy 210.285069 -381.46941)
			(xy 210.24537 -381.545379) (xy 210.19855 -381.617179) (xy 210.145043 -381.684144) (xy 210.085345 -381.745654)
			(xy 210.020009 -381.801138) (xy 209.985102 -381.826008) (xy 209.974688 -381.83312) (xy 209.963258 -381.854964)
			(xy 209.963258 -381.963676) (xy 209.974688 -381.98552) (xy 209.985102 -381.992632) (xy 210.019995 -382.017522)
			(xy 210.085333 -382.073002) (xy 210.145033 -382.134508) (xy 210.198541 -382.20147) (xy 210.245361 -382.273267)
			(xy 210.28506 -382.349235) (xy 210.31727 -382.428668) (xy 210.34169 -382.51083) (xy 210.358097 -382.594961)
			(xy 210.366336 -382.680279) (xy 210.366864 -382.723136) (xy 210.366277 -382.769532) (xy 210.35664 -382.861821)
			(xy 210.337443 -382.952604) (xy 210.308894 -383.040894) (xy 210.290664 -383.083562) (xy 210.286853 -383.093502)
			(xy 210.286866 -383.114763) (xy 210.290664 -383.12471) (xy 210.308901 -383.167375) (xy 210.337437 -383.255669)
			(xy 210.35663 -383.346452) (xy 210.366272 -383.438741) (xy 210.366864 -383.485136) (xy 210.366399 -383.52639)
			(xy 210.358762 -383.608545) (xy 210.343548 -383.689638) (xy 210.320887 -383.768974) (xy 210.290975 -383.845869)
			(xy 210.254068 -383.919663) (xy 210.210484 -383.989721) (xy 210.160598 -384.05544) (xy 210.104839 -384.116256)
			(xy 210.043686 -384.171645) (xy 209.977665 -384.221132) (xy 209.907344 -384.26429) (xy 209.870548 -384.28295)
			(xy 209.862237 -384.28751) (xy 209.849486 -384.301519) (xy 209.842679 -384.319197) (xy 209.842354 -384.32867)
			(xy 209.842354 -384.419602) (xy 209.842685 -384.429079) (xy 209.849468 -384.446774) (xy 209.862218 -384.460793)
			(xy 209.870548 -384.465322) (xy 209.909133 -384.484916) (xy 209.98268 -384.530532) (xy 210.051454 -384.583069)
			(xy 210.114805 -384.642032) (xy 210.143852 -384.67411) (xy 210.151218 -384.682238) (xy 210.17103 -384.691128)
			(xy 210.185254 -384.691128) (xy 210.222685 -384.691585) (xy 210.297185 -384.69895) (xy 210.370604 -384.713583)
			(xy 210.442234 -384.735344) (xy 210.511386 -384.764024) (xy 210.577393 -384.799345) (xy 210.639619 -384.840967)
			(xy 210.697464 -384.88849) (xy 210.724242 -384.914648) (xy 211.201254 -385.39166) (xy 211.227392 -385.418448)
			(xy 211.274875 -385.476307) (xy 211.316459 -385.538541) (xy 211.351744 -385.604551) (xy 211.380389 -385.673701)
			(xy 211.402119 -385.745326) (xy 211.416725 -385.818736) (xy 211.424066 -385.893224) (xy 211.42452 -385.930648)
			(xy 211.42452 -386.470652) (xy 212.630512 -386.470652) (xy 212.631082 -386.4416) (xy 212.639874 -386.384165)
			(xy 212.657276 -386.328728) (xy 212.682887 -386.276573) (xy 212.716113 -386.228907) (xy 212.756186 -386.186832)
			(xy 212.778848 -386.168646) (xy 212.788246 -386.16128) (xy 212.79866 -386.14096) (xy 212.79993 -386.037582)
			(xy 212.790278 -386.017008) (xy 212.781134 -386.009388) (xy 212.75957 -385.991198) (xy 212.721564 -385.949506)
			(xy 212.690115 -385.902669) (xy 212.66591 -385.85171) (xy 212.649478 -385.797741) (xy 212.641176 -385.74194)
			(xy 212.640672 -385.713732) (xy 212.641185 -385.686481) (xy 212.648937 -385.632533) (xy 212.664288 -385.580237)
			(xy 212.686925 -385.530658) (xy 212.716388 -385.484806) (xy 212.752077 -385.443614) (xy 212.793264 -385.407919)
			(xy 212.839113 -385.37845) (xy 212.888688 -385.355806) (xy 212.940982 -385.340448) (xy 212.994929 -385.332689)
			(xy 213.02218 -385.332224) (xy 213.052195 -385.332809) (xy 213.111482 -385.342219) (xy 213.168566 -385.360794)
			(xy 213.222038 -385.388076) (xy 213.270579 -385.423393) (xy 213.292182 -385.444238) (xy 213.299294 -385.45135)
			(xy 213.317074 -385.45897) (xy 213.407752 -385.460494) (xy 213.425786 -385.453636) (xy 213.433152 -385.446778)
			(xy 213.454444 -385.427736) (xy 213.501644 -385.395567) (xy 213.553112 -385.370791) (xy 213.607696 -385.353961)
			(xy 213.66418 -385.345455) (xy 213.69274 -385.344924) (xy 213.719815 -385.345382) (xy 213.77342 -385.353036)
			(xy 213.825402 -385.368199) (xy 213.874716 -385.390566) (xy 213.920368 -385.419687) (xy 213.96144 -385.454975)
			(xy 213.997104 -385.49572) (xy 214.012272 -385.518152) (xy 214.01913 -385.528312) (xy 214.039704 -385.54025)
			(xy 214.145876 -385.5466) (xy 214.16772 -385.536948) (xy 214.175594 -385.52755) (xy 214.193806 -385.50636)
			(xy 214.23537 -385.469019) (xy 214.281936 -385.438141) (xy 214.332508 -385.414386) (xy 214.386005 -385.398262)
			(xy 214.441281 -385.390115) (xy 214.469218 -385.389628) (xy 214.499234 -385.390188) (xy 214.558522 -385.399603)
			(xy 214.615606 -385.418184) (xy 214.669078 -385.445472) (xy 214.717618 -385.480794) (xy 214.73922 -385.501642)
			(xy 214.746332 -385.508754) (xy 214.764112 -385.516374) (xy 214.85479 -385.517898) (xy 214.872824 -385.51104)
			(xy 214.88019 -385.504182) (xy 214.901508 -385.48517) (xy 214.948701 -385.452996) (xy 215.000162 -385.428214)
			(xy 215.054741 -385.411378) (xy 215.11122 -385.402863) (xy 215.139778 -385.402328) (xy 215.168755 -385.402882)
			(xy 215.226044 -385.411639) (xy 215.281351 -385.428954) (xy 215.333406 -385.45443) (xy 215.381011 -385.487481)
			(xy 215.423074 -385.527349) (xy 215.441276 -385.549902) (xy 215.448896 -385.559808) (xy 215.471756 -385.570222)
			(xy 215.580976 -385.563364) (xy 215.602312 -385.550156) (xy 215.608916 -385.539488) (xy 215.623759 -385.515449)
			(xy 215.65937 -385.471594) (xy 215.701063 -385.433474) (xy 215.747926 -385.401925) (xy 215.798932 -385.377637)
			(xy 215.852963 -385.361143) (xy 215.908837 -385.352803) (xy 215.937084 -385.35229) (xy 215.96688 -385.352819)
			(xy 216.025747 -385.362083) (xy 216.082457 -385.380389) (xy 216.135631 -385.407291) (xy 216.183975 -385.442135)
			(xy 216.226312 -385.484072) (xy 216.244424 -385.507738) (xy 216.25179 -385.517644) (xy 216.273126 -385.528566)
			(xy 216.379552 -385.528312) (xy 216.401142 -385.517644) (xy 216.408254 -385.507738) (xy 216.426378 -385.48399)
			(xy 216.468729 -385.441863) (xy 216.517131 -385.406854) (xy 216.570398 -385.37982) (xy 216.62723 -385.361421)
			(xy 216.686234 -385.352108) (xy 216.716102 -385.351528) (xy 216.746117 -385.352098) (xy 216.805406 -385.361511)
			(xy 216.862489 -385.38009) (xy 216.915961 -385.407375) (xy 216.964502 -385.442695) (xy 216.986104 -385.463542)
			(xy 216.993216 -385.470654) (xy 217.010996 -385.478274) (xy 217.101674 -385.479798) (xy 217.119708 -385.47294)
			(xy 217.127074 -385.466082) (xy 217.148399 -385.447078) (xy 217.19559 -385.414903) (xy 217.247049 -385.39012)
			(xy 217.301627 -385.373281) (xy 217.358104 -385.364764) (xy 217.386662 -385.364228) (xy 217.415602 -385.36477)
			(xy 217.472819 -385.373499) (xy 217.528064 -385.390763) (xy 217.580071 -385.416167) (xy 217.627648 -385.449128)
			(xy 217.649044 -385.468622) (xy 217.65641 -385.475734) (xy 217.675714 -385.4831) (xy 217.769186 -385.479036)
			(xy 217.787728 -385.470146) (xy 217.794586 -385.462526) (xy 217.812785 -385.442813) (xy 217.853733 -385.408151)
			(xy 217.899131 -385.379564) (xy 217.948085 -385.357615) (xy 217.999629 -385.342736) (xy 218.052749 -385.335221)
			(xy 218.079574 -385.334764) (xy 218.106823 -385.335302) (xy 218.160768 -385.343055) (xy 218.21306 -385.358405)
			(xy 218.262635 -385.381041) (xy 218.308484 -385.410502) (xy 218.349674 -385.446188) (xy 218.385366 -385.487373)
			(xy 218.414833 -385.533218) (xy 218.437476 -385.58279) (xy 218.452834 -385.63508) (xy 218.460594 -385.689023)
			(xy 218.461082 -385.716272) (xy 218.460594 -385.743332) (xy 218.452933 -385.796908) (xy 218.437775 -385.848862)
			(xy 218.415424 -385.898151) (xy 218.386329 -385.943786) (xy 218.351075 -385.984849) (xy 218.331034 -386.003038)
			(xy 218.322906 -386.010404) (xy 218.313762 -386.030216) (xy 218.313254 -386.128006) (xy 218.322144 -386.148072)
			(xy 218.330272 -386.155184) (xy 218.349929 -386.173354) (xy 218.384451 -386.214263) (xy 218.412919 -386.259594)
			(xy 218.434775 -386.308458) (xy 218.449589 -386.359896) (xy 218.457073 -386.4129) (xy 218.457526 -386.439664)
			(xy 218.457011 -386.466915) (xy 218.44926 -386.520863) (xy 218.433909 -386.573159) (xy 218.411272 -386.622738)
			(xy 218.38181 -386.66859) (xy 218.346121 -386.709783) (xy 218.304934 -386.745477) (xy 218.259085 -386.774946)
			(xy 218.20951 -386.79759) (xy 218.157216 -386.812948) (xy 218.103269 -386.820707) (xy 218.076018 -386.821172)
			(xy 218.049468 -386.820714) (xy 217.996882 -386.813336) (xy 217.945828 -386.798735) (xy 217.897294 -386.777192)
			(xy 217.852218 -386.749124) (xy 217.811471 -386.715075) (xy 217.793316 -386.695696) (xy 217.786204 -386.688076)
			(xy 217.767916 -386.67944) (xy 217.674698 -386.67563) (xy 217.655902 -386.682742) (xy 217.648282 -386.689854)
			(xy 217.626916 -386.70924) (xy 217.57946 -386.742042) (xy 217.527606 -386.767324) (xy 217.472536 -386.78451)
			(xy 217.415506 -386.793206) (xy 217.386662 -386.79374) (xy 217.356645 -386.793202) (xy 217.297355 -386.783782)
			(xy 217.240271 -386.765197) (xy 217.1868 -386.737904) (xy 217.138261 -386.702576) (xy 217.11666 -386.681726)
			(xy 217.109548 -386.674614) (xy 217.091768 -386.666994) (xy 217.00109 -386.66547) (xy 216.983056 -386.672328)
			(xy 216.97569 -386.679186) (xy 216.95439 -386.698218) (xy 216.907191 -386.730387) (xy 216.855725 -386.755164)
			(xy 216.801143 -386.771995) (xy 216.744661 -386.780507) (xy 216.716102 -386.78104) (xy 216.686306 -386.780509)
			(xy 216.62744 -386.771244) (xy 216.57073 -386.752937) (xy 216.517557 -386.726035) (xy 216.469213 -386.691193)
			(xy 216.426875 -386.649257) (xy 216.408762 -386.625592) (xy 216.401396 -386.615686) (xy 216.38006 -386.604764)
			(xy 216.273634 -386.605018) (xy 216.252044 -386.615686) (xy 216.244932 -386.625592) (xy 216.226824 -386.649353)
			(xy 216.184469 -386.691478) (xy 216.136064 -386.726484) (xy 216.082793 -386.753516) (xy 216.025959 -386.771912)
			(xy 215.966952 -386.781223) (xy 215.937084 -386.781802) (xy 215.908105 -386.781302) (xy 215.850812 -386.772538)
			(xy 215.795503 -386.755214) (xy 215.743448 -386.729728) (xy 215.695844 -386.696665) (xy 215.653785 -386.656787)
			(xy 215.635586 -386.634228) (xy 215.627966 -386.624322) (xy 215.605106 -386.613908) (xy 215.495886 -386.620766)
			(xy 215.47455 -386.633974) (xy 215.467946 -386.644642) (xy 215.45314 -386.668704) (xy 215.417522 -386.712559)
			(xy 215.375822 -386.750676) (xy 215.328953 -386.782222) (xy 215.277941 -386.806506) (xy 215.223905 -386.822995)
			(xy 215.168026 -386.83133) (xy 215.139778 -386.83184) (xy 215.109762 -386.831292) (xy 215.050472 -386.821875)
			(xy 214.993388 -386.803292) (xy 214.939916 -386.776001) (xy 214.891377 -386.740675) (xy 214.869776 -386.719826)
			(xy 214.862664 -386.712714) (xy 214.844884 -386.705094) (xy 214.754206 -386.70357) (xy 214.736172 -386.710428)
			(xy 214.728806 -386.717286) (xy 214.707499 -386.736311) (xy 214.660302 -386.76848) (xy 214.608838 -386.793259)
			(xy 214.554257 -386.810092) (xy 214.497777 -386.818605) (xy 214.469218 -386.81914) (xy 214.440741 -386.818606)
			(xy 214.384418 -386.810148) (xy 214.329981 -386.793403) (xy 214.278642 -386.768743) (xy 214.231544 -386.736718)
			(xy 214.189737 -386.698041) (xy 214.17153 -386.676138) (xy 214.163656 -386.666232) (xy 214.141304 -386.656326)
			(xy 214.033608 -386.662676) (xy 214.012526 -386.675122) (xy 214.005922 -386.68579) (xy 213.990893 -386.708914)
			(xy 213.955204 -386.750959) (xy 213.913833 -386.787427) (xy 213.867642 -386.817557) (xy 213.817593 -386.840721)
			(xy 213.76473 -386.856436) (xy 213.710155 -386.864375) (xy 213.68258 -386.86486) (xy 213.652564 -386.864305)
			(xy 213.593275 -386.854889) (xy 213.536191 -386.836307) (xy 213.48272 -386.809018) (xy 213.43418 -386.773694)
			(xy 213.412578 -386.752846) (xy 213.405466 -386.745734) (xy 213.387686 -386.738114) (xy 213.297008 -386.73659)
			(xy 213.278974 -386.743448) (xy 213.271608 -386.750306) (xy 213.250289 -386.769317) (xy 213.203096 -386.801491)
			(xy 213.151636 -386.826274) (xy 213.097057 -386.84311) (xy 213.040578 -386.851625) (xy 213.01202 -386.85216)
			(xy 212.984765 -386.851726) (xy 212.930811 -386.84397) (xy 212.87851 -386.828615) (xy 212.828926 -386.805971)
			(xy 212.783071 -386.7765) (xy 212.741877 -386.740803) (xy 212.706183 -386.699607) (xy 212.676716 -386.653749)
			(xy 212.654076 -386.604164) (xy 212.638724 -386.551862) (xy 212.630972 -386.497907) (xy 212.630512 -386.470652)
			(xy 211.42452 -386.470652) (xy 211.42452 -386.606034) (xy 211.424074 -386.643459) (xy 211.416734 -386.717947)
			(xy 211.402128 -386.791357) (xy 211.380397 -386.862982) (xy 211.35175 -386.932132) (xy 211.316462 -386.998141)
			(xy 211.274875 -387.060373) (xy 211.227388 -387.118229) (xy 211.201254 -387.145022) (xy 210.714082 -387.632194)
			(xy 210.687615 -387.658078) (xy 210.63047 -387.70515) (xy 210.56903 -387.746461) (xy 210.503876 -387.781621)
			(xy 210.43562 -387.810299) (xy 210.400392 -387.821678) (xy 210.390769 -387.825073) (xy 210.375105 -387.838124)
			(xy 210.365766 -387.856248) (xy 210.364578 -387.866382) (xy 210.361442 -387.904733) (xy 210.349381 -387.980735)
			(xy 210.330806 -388.055413) (xy 210.305857 -388.12821) (xy 210.291974 -388.160514) (xy 221.30132 -388.160514)
			(xy 221.305305 -387.979173) (xy 221.317251 -387.798181) (xy 221.337135 -387.617889) (xy 221.364919 -387.438645)
			(xy 221.40055 -387.260793) (xy 221.443958 -387.084679) (xy 221.49506 -386.910641) (xy 221.553758 -386.739016)
			(xy 221.619937 -386.570135) (xy 221.69347 -386.404323) (xy 221.774215 -386.241902) (xy 221.862017 -386.083183)
			(xy 221.956706 -385.928475) (xy 222.058098 -385.778075) (xy 222.165999 -385.632274) (xy 222.2802 -385.491353)
			(xy 222.400481 -385.355584) (xy 222.526609 -385.22523) (xy 222.658341 -385.100541) (xy 222.795423 -384.981759)
			(xy 222.93759 -384.869113) (xy 223.084567 -384.76282) (xy 223.236072 -384.663086) (xy 223.391811 -384.570102)
			(xy 223.551484 -384.484049) (xy 223.714783 -384.405093) (xy 223.881392 -384.333385) (xy 224.05099 -384.269065)
			(xy 224.22325 -384.212257) (xy 224.397838 -384.163069) (xy 224.574419 -384.121598) (xy 224.752651 -384.087923)
			(xy 224.93219 -384.062109) (xy 225.112689 -384.044207) (xy 225.293801 -384.034249) (xy 225.475175 -384.032257)
			(xy 225.656462 -384.038233) (xy 225.837311 -384.052167) (xy 226.017374 -384.07403) (xy 226.196302 -384.103782)
			(xy 226.373751 -384.141364) (xy 226.549378 -384.186704) (xy 226.722844 -384.239715) (xy 226.893814 -384.300294)
			(xy 227.061959 -384.368324) (xy 227.226952 -384.443674) (xy 227.388477 -384.526199) (xy 227.546221 -384.615739)
			(xy 227.69988 -384.712121) (xy 227.849157 -384.815159) (xy 227.993764 -384.924655) (xy 228.133422 -385.040397)
			(xy 228.267862 -385.162162) (xy 228.396823 -385.289714) (xy 228.520057 -385.422808) (xy 228.637326 -385.561186)
			(xy 228.748404 -385.704582) (xy 228.853076 -385.852718) (xy 228.95114 -386.005309) (xy 229.042407 -386.16206)
			(xy 229.126701 -386.322669) (xy 229.203859 -386.486825) (xy 229.273732 -386.654212) (xy 229.336186 -386.824506)
			(xy 229.391098 -386.997379) (xy 229.438365 -387.172498) (xy 229.477894 -387.349523) (xy 229.509609 -387.528114)
			(xy 229.53345 -387.707926) (xy 229.549369 -387.888611) (xy 229.557336 -388.069821) (xy 229.557834 -388.160514)
			(xy 229.557336 -388.251207) (xy 229.549369 -388.432417) (xy 229.53345 -388.613102) (xy 229.509609 -388.792914)
			(xy 229.477894 -388.971505) (xy 229.438365 -389.14853) (xy 229.391098 -389.323649) (xy 229.336186 -389.496522)
			(xy 229.273732 -389.666816) (xy 229.203859 -389.834203) (xy 229.126701 -389.998359) (xy 229.042407 -390.158968)
			(xy 228.95114 -390.315719) (xy 228.853076 -390.46831) (xy 228.748404 -390.616446) (xy 228.637326 -390.759842)
			(xy 228.520057 -390.89822) (xy 228.396823 -391.031314) (xy 228.267862 -391.158866) (xy 228.133422 -391.280631)
			(xy 227.993764 -391.396373) (xy 227.849157 -391.505869) (xy 227.69988 -391.608907) (xy 227.546221 -391.705289)
			(xy 227.388477 -391.794829) (xy 227.226952 -391.877354) (xy 227.061959 -391.952704) (xy 226.893814 -392.020734)
			(xy 226.722844 -392.081313) (xy 226.549378 -392.134324) (xy 226.373751 -392.179664) (xy 226.196302 -392.217246)
			(xy 226.017374 -392.246998) (xy 225.837311 -392.268861) (xy 225.656462 -392.282795) (xy 225.475175 -392.288771)
			(xy 225.293801 -392.286779) (xy 225.112689 -392.276821) (xy 224.93219 -392.258919) (xy 224.752651 -392.233105)
			(xy 224.574419 -392.19943) (xy 224.397838 -392.157959) (xy 224.22325 -392.108771) (xy 224.05099 -392.051963)
			(xy 223.881392 -391.987643) (xy 223.714783 -391.915935) (xy 223.551484 -391.836979) (xy 223.391811 -391.750926)
			(xy 223.236072 -391.657942) (xy 223.084567 -391.558208) (xy 222.93759 -391.451915) (xy 222.795423 -391.339269)
			(xy 222.658341 -391.220487) (xy 222.526609 -391.095798) (xy 222.400481 -390.965444) (xy 222.2802 -390.829675)
			(xy 222.165999 -390.688754) (xy 222.058098 -390.542953) (xy 221.956706 -390.392553) (xy 221.862017 -390.237845)
			(xy 221.774215 -390.079126) (xy 221.69347 -389.916705) (xy 221.619937 -389.750893) (xy 221.553758 -389.582012)
			(xy 221.49506 -389.410387) (xy 221.443958 -389.236349) (xy 221.40055 -389.060235) (xy 221.364919 -388.882383)
			(xy 221.337135 -388.703139) (xy 221.317251 -388.522847) (xy 221.305305 -388.341855) (xy 221.30132 -388.160514)
			(xy 210.291974 -388.160514) (xy 210.290664 -388.163562) (xy 210.286853 -388.173502) (xy 210.286866 -388.194763)
			(xy 210.290664 -388.20471) (xy 210.308901 -388.247375) (xy 210.337437 -388.335669) (xy 210.35663 -388.426452)
			(xy 210.366272 -388.518741) (xy 210.366864 -388.565136) (xy 210.36636 -388.607484) (xy 210.358309 -388.691798)
			(xy 210.34228 -388.774964) (xy 210.318419 -388.856231) (xy 210.28694 -388.934861) (xy 210.248129 -389.010142)
			(xy 210.202339 -389.081394) (xy 210.149983 -389.14797) (xy 210.091535 -389.209268) (xy 210.027525 -389.264733)
			(xy 209.958533 -389.313862) (xy 209.885183 -389.356211) (xy 209.80814 -389.391395) (xy 209.728101 -389.419097)
			(xy 209.645792 -389.439065) (xy 209.561957 -389.451118) (xy 209.477356 -389.455149) (xy 209.392755 -389.451118)
			(xy 209.30892 -389.439065) (xy 209.226611 -389.419097) (xy 209.146572 -389.391395) (xy 209.069529 -389.356211)
			(xy 208.996179 -389.313862) (xy 208.927187 -389.264733) (xy 208.863177 -389.209268) (xy 208.804729 -389.14797)
			(xy 208.752373 -389.081394) (xy 208.706583 -389.010142) (xy 208.667772 -388.934861) (xy 208.636293 -388.856231)
			(xy 208.612432 -388.774964) (xy 208.596403 -388.691798) (xy 208.588352 -388.607484) (xy 208.587848 -388.565136)
			(xy 208.588431 -388.51874) (xy 208.598061 -388.426448) (xy 208.617252 -388.335662) (xy 208.645795 -388.247369)
			(xy 208.664048 -388.20471) (xy 208.667874 -388.19477) (xy 208.667888 -388.173496) (xy 208.664048 -388.163562)
			(xy 208.646125 -388.121707) (xy 208.617932 -388.035126) (xy 208.598742 -387.946116) (xy 208.593182 -387.900926)
			(xy 208.59115 -387.881368) (xy 208.562448 -387.85546) (xy 208.360264 -387.85546) (xy 208.331562 -387.881368)
			(xy 208.32953 -387.900926) (xy 208.323951 -387.946113) (xy 208.30475 -388.035118) (xy 208.276569 -388.1217)
			(xy 208.258664 -388.163562) (xy 208.254853 -388.173502) (xy 208.254866 -388.194763) (xy 208.258664 -388.20471)
			(xy 208.276901 -388.247375) (xy 208.305437 -388.335669) (xy 208.32463 -388.426452) (xy 208.334272 -388.518741)
			(xy 208.334864 -388.565136) (xy 208.33436 -388.607484) (xy 208.326309 -388.691798) (xy 208.31028 -388.774964)
			(xy 208.286419 -388.856231) (xy 208.25494 -388.934861) (xy 208.216129 -389.010142) (xy 208.170339 -389.081394)
			(xy 208.117983 -389.14797) (xy 208.059535 -389.209268) (xy 207.995525 -389.264733) (xy 207.926533 -389.313862)
			(xy 207.853183 -389.356211) (xy 207.77614 -389.391395) (xy 207.696101 -389.419097) (xy 207.613792 -389.439065)
			(xy 207.529957 -389.451118) (xy 207.445356 -389.455149) (xy 207.360755 -389.451118) (xy 207.27692 -389.439065)
			(xy 207.194611 -389.419097) (xy 207.114572 -389.391395) (xy 207.037529 -389.356211) (xy 206.964179 -389.313862)
			(xy 206.895187 -389.264733) (xy 206.831177 -389.209268) (xy 206.772729 -389.14797) (xy 206.720373 -389.081394)
			(xy 206.674583 -389.010142) (xy 206.635772 -388.934861) (xy 206.604293 -388.856231) (xy 206.580432 -388.774964)
			(xy 206.564403 -388.691798) (xy 206.556352 -388.607484) (xy 206.555848 -388.565136) (xy 206.556431 -388.51874)
			(xy 206.566061 -388.426448) (xy 206.585252 -388.335662) (xy 206.613795 -388.247369) (xy 206.632048 -388.20471)
			(xy 206.635874 -388.19477) (xy 206.635888 -388.173496) (xy 206.632048 -388.163562) (xy 206.614125 -388.121707)
			(xy 206.585932 -388.035126) (xy 206.566742 -387.946116) (xy 206.561182 -387.900926) (xy 206.55915 -387.881368)
			(xy 206.530448 -387.85546) (xy 203.117704 -387.85546) (xy 203.080279 -387.855016) (xy 203.00579 -387.847679)
			(xy 202.932378 -387.833075) (xy 202.860752 -387.811345) (xy 202.791601 -387.782699) (xy 202.725591 -387.747412)
			(xy 202.663358 -387.705823) (xy 202.605502 -387.658335) (xy 202.578716 -387.632194) (xy 200.569322 -385.623054)
			(xy 200.56188 -385.616354) (xy 200.54338 -385.608745) (xy 200.523376 -385.608753) (xy 200.51395 -385.612132)
			(xy 200.499726 -385.617974) (xy 200.482708 -385.643374) (xy 200.482708 -386.6007) (xy 200.482285 -386.61077)
			(xy 200.474572 -386.629376) (xy 200.467722 -386.636768) (xy 200.421494 -386.682996) (xy 200.414648 -386.690395)
			(xy 200.406913 -386.708992) (xy 200.406508 -386.719064) (xy 200.406508 -387.960616) (xy 200.741024 -387.960616)
			(xy 200.745095 -387.904994) (xy 200.757221 -387.850557) (xy 200.777144 -387.798466) (xy 200.80444 -387.749831)
			(xy 200.838526 -387.705688) (xy 200.878675 -387.666979) (xy 200.924033 -387.634528) (xy 200.973633 -387.609027)
			(xy 201.026417 -387.59102) (xy 201.08126 -387.58089) (xy 201.136994 -387.578853) (xy 201.192431 -387.584953)
			(xy 201.246388 -387.599059) (xy 201.297717 -387.620871) (xy 201.345323 -387.649925) (xy 201.388191 -387.6856)
			(xy 201.425408 -387.727137) (xy 201.456181 -387.77365) (xy 201.479853 -387.824147) (xy 201.495921 -387.877554)
			(xy 201.504041 -387.93273) (xy 201.50455 -387.960616) (xy 201.504041 -387.988502) (xy 201.495921 -388.043678)
			(xy 201.479853 -388.097085) (xy 201.456181 -388.147582) (xy 201.425408 -388.194095) (xy 201.388191 -388.235632)
			(xy 201.345323 -388.271307) (xy 201.297717 -388.300361) (xy 201.246388 -388.322173) (xy 201.192431 -388.336279)
			(xy 201.136994 -388.342379) (xy 201.08126 -388.340342) (xy 201.026417 -388.330212) (xy 200.973633 -388.312205)
			(xy 200.924033 -388.286704) (xy 200.878675 -388.254253) (xy 200.838526 -388.215544) (xy 200.80444 -388.171401)
			(xy 200.777144 -388.122766) (xy 200.757221 -388.070675) (xy 200.745095 -388.016238) (xy 200.741024 -387.960616)
			(xy 200.406508 -387.960616) (xy 200.406508 -389.181594) (xy 200.406086 -389.191665) (xy 200.398374 -389.210272)
			(xy 200.391522 -389.217662) (xy 199.619362 -389.989822) (xy 199.611965 -389.996671) (xy 199.593366 -390.004404)
			(xy 199.583294 -390.004808) (xy 199.582278 -390.004808) (xy 199.557386 -390.021064) (xy 199.551036 -390.035034)
			(xy 199.539463 -390.060015) (xy 199.510192 -390.106643) (xy 199.47452 -390.148576) (xy 199.433187 -390.184944)
			(xy 199.387054 -390.214989) (xy 199.33708 -390.238087) (xy 199.284303 -390.253758) (xy 199.229821 -390.261675)
			(xy 199.174767 -390.261675) (xy 199.120285 -390.253758) (xy 199.067508 -390.238087) (xy 199.017534 -390.214989)
			(xy 198.971401 -390.184944) (xy 198.930068 -390.148576) (xy 198.894396 -390.106643) (xy 198.865125 -390.060015)
			(xy 198.853552 -390.035034) (xy 198.847202 -390.021064) (xy 198.82231 -390.004808) (xy 192.95745 -390.004808)
			(xy 192.932558 -390.021064) (xy 192.926208 -390.035034) (xy 192.914635 -390.060015) (xy 192.885364 -390.106643)
			(xy 192.849692 -390.148576) (xy 192.808359 -390.184944) (xy 192.762226 -390.214989) (xy 192.712252 -390.238087)
			(xy 192.659475 -390.253758) (xy 192.604993 -390.261675) (xy 192.549939 -390.261675) (xy 192.495457 -390.253758)
			(xy 192.44268 -390.238087) (xy 192.392706 -390.214989) (xy 192.346573 -390.184944) (xy 192.30524 -390.148576)
			(xy 192.269568 -390.106643) (xy 192.240297 -390.060015) (xy 192.228724 -390.035034) (xy 192.222374 -390.021064)
			(xy 192.197482 -390.004808) (xy 189.13094 -390.004808) (xy 189.120875 -390.005242) (xy 189.102287 -390.012973)
			(xy 189.094872 -390.019794) (xy 184.53481 -394.579856) (xy 184.527971 -394.587257) (xy 184.520255 -394.605855)
			(xy 184.519824 -394.615924) (xy 184.519824 -395.95552) (xy 184.520251 -395.965588) (xy 184.527974 -395.984185)
			(xy 184.53481 -395.991588) (xy 184.616344 -396.073122) (xy 184.623741 -396.07997) (xy 184.64234 -396.087701)
			(xy 184.652412 -396.088108) (xy 185.033412 -396.088108) (xy 185.043481 -396.088534) (xy 185.062082 -396.096252)
			(xy 185.06948 -396.103094) (xy 185.345832 -396.379446) (xy 185.352679 -396.386844) (xy 185.360407 -396.405443)
			(xy 185.360818 -396.415514) (xy 185.360818 -399.052288) (xy 185.361239 -399.062359) (xy 185.368953 -399.080965)
			(xy 185.375804 -399.088356) (xy 185.429398 -399.14195) (xy 185.436794 -399.148802) (xy 185.455392 -399.156545)
			(xy 185.465466 -399.156936) (xy 189.027562 -399.156936) (xy 189.037626 -399.1565) (xy 189.056208 -399.148762)
			(xy 189.06363 -399.14195) (xy 190.454026 -397.751554) (xy 190.461423 -397.744706) (xy 190.480022 -397.736972)
			(xy 190.490094 -397.736568) (xy 193.891408 -397.736568) (xy 193.902695 -397.735961) (xy 193.923117 -397.726338)
			(xy 193.930778 -397.718026) (xy 193.95739 -397.6864) (xy 194.015584 -397.627696) (xy 194.078973 -397.574644)
			(xy 194.147011 -397.527703) (xy 194.219111 -397.487276) (xy 194.294651 -397.453713) (xy 194.372978 -397.427304)
			(xy 194.453418 -397.408275) (xy 194.535277 -397.396792) (xy 194.617848 -397.392954) (xy 194.700419 -397.396792)
			(xy 194.782278 -397.408275) (xy 194.862718 -397.427304) (xy 194.941045 -397.453713) (xy 195.016585 -397.487276)
			(xy 195.088685 -397.527703) (xy 195.156723 -397.574644) (xy 195.220112 -397.627696) (xy 195.278306 -397.6864)
			(xy 195.304918 -397.718026) (xy 195.312536 -397.7264) (xy 195.332981 -397.736046) (xy 195.344288 -397.736568)
			(xy 196.068188 -397.736568) (xy 196.07826 -397.736988) (xy 196.09687 -397.744696) (xy 196.104256 -397.751554)
			(xy 197.656704 -399.304002) (xy 197.664103 -399.310848) (xy 197.682701 -399.31858) (xy 197.692772 -399.318988)
		)
		(stroke
			(width 0)
			(type solid)
		)
		(fill yes)
		(layer "In2.Cu")
		(net "P12V_AUX")
	)
	(gr_poly
		(pts
			(xy 446.916302 -112.658398) (xy 446.92618 -112.657941) (xy 446.944483 -112.650501) (xy 446.951862 -112.64392)
			(xy 446.952116 -112.643666) (xy 448.720718 -110.875064) (xy 448.727532 -110.867721) (xy 448.735264 -110.849257)
			(xy 448.735704 -110.83925) (xy 448.735704 -99.366578) (xy 448.73545 -99.366578) (xy 448.73545 -96.40951)
			(xy 448.736009 -96.380947) (xy 448.744943 -96.324524) (xy 448.762591 -96.270193) (xy 448.78852 -96.219291)
			(xy 448.822091 -96.173071) (xy 448.841876 -96.152462) (xy 448.973702 -96.020636) (xy 449.296536 -95.697802)
			(xy 449.300092 -95.691452) (xy 449.314518 -95.66591) (xy 449.34999 -95.619191) (xy 449.39219 -95.578448)
			(xy 449.440126 -95.544639) (xy 449.492669 -95.518559) (xy 449.548582 -95.500823) (xy 449.606551 -95.491848)
			(xy 449.63588 -95.4913) (xy 449.663134 -95.491762) (xy 449.717086 -95.499517) (xy 449.769386 -95.514871)
			(xy 449.818968 -95.537513) (xy 449.864823 -95.56698) (xy 449.906018 -95.602674) (xy 449.941713 -95.643867)
			(xy 449.971182 -95.689721) (xy 449.993825 -95.739303) (xy 450.009181 -95.791602) (xy 450.016937 -95.845554)
			(xy 450.017388 -95.872808) (xy 450.016851 -95.902137) (xy 450.007875 -95.960105) (xy 449.990137 -96.016017)
			(xy 449.964053 -96.068557) (xy 449.930238 -96.116488) (xy 449.889488 -96.158681) (xy 449.842763 -96.194143)
			(xy 449.817236 -96.208596) (xy 449.810886 -96.212152) (xy 449.475606 -96.547432) (xy 449.470249 -96.553898)
			(xy 449.463637 -96.56932) (xy 449.462652 -96.577658) (xy 449.462652 -96.792034) (xy 449.463197 -96.80305)
			(xy 449.472419 -96.823061) (xy 449.480432 -96.830642) (xy 449.547488 -96.888046) (xy 449.568316 -96.894142)
			(xy 449.579492 -96.892618) (xy 449.593505 -96.890631) (xy 449.621728 -96.888473) (xy 449.63588 -96.8883)
			(xy 449.662982 -96.888774) (xy 449.716641 -96.896443) (xy 449.768674 -96.91163) (xy 449.818033 -96.934029)
			(xy 449.863726 -96.96319) (xy 449.90483 -96.998523) (xy 449.94052 -97.03932) (xy 449.970076 -97.084757)
			(xy 449.992903 -97.13392) (xy 450.008541 -97.185819) (xy 450.016677 -97.239409) (xy 450.017388 -97.266506)
			(xy 450.017388 -97.270062) (xy 450.016882 -97.297442) (xy 450.00898 -97.35163) (xy 450.00164 -97.378012)
			(xy 450.00164 -97.378266) (xy 449.999608 -97.385632) (xy 449.999608 -109.473492) (xy 450.000103 -109.483488)
			(xy 450.007738 -109.501967) (xy 450.021825 -109.516155) (xy 450.03085 -109.520482) (xy 450.045328 -109.526578)
			(xy 450.0753 -109.520482) (xy 450.614542 -108.98124) (xy 450.61505 -108.980732) (xy 450.62163 -108.97335)
			(xy 450.629076 -108.955051) (xy 450.629528 -108.945172) (xy 450.629528 -93.216984) (xy 450.629103 -93.206914)
			(xy 450.621387 -93.188312) (xy 450.614542 -93.180916) (xy 447.662554 -90.228928) (xy 447.655154 -90.222086)
			(xy 447.636556 -90.214364) (xy 447.626486 -90.213942) (xy 417.129468 -90.213942) (xy 417.119401 -90.214372)
			(xy 417.100809 -90.2221) (xy 417.0934 -90.228928) (xy 416.051492 -91.270836) (xy 437.855358 -91.270836)
			(xy 437.859429 -91.215214) (xy 437.871555 -91.160777) (xy 437.891478 -91.108686) (xy 437.918774 -91.060051)
			(xy 437.95286 -91.015908) (xy 437.993009 -90.977199) (xy 438.038367 -90.944748) (xy 438.087967 -90.919247)
			(xy 438.140751 -90.90124) (xy 438.195594 -90.89111) (xy 438.251328 -90.889073) (xy 438.306765 -90.895173)
			(xy 438.360722 -90.909279) (xy 438.412051 -90.931091) (xy 438.459657 -90.960145) (xy 438.502525 -90.99582)
			(xy 438.539742 -91.037357) (xy 438.570515 -91.08387) (xy 438.594187 -91.134367) (xy 438.610255 -91.187774)
			(xy 438.618375 -91.24295) (xy 438.618884 -91.270836) (xy 438.618375 -91.298722) (xy 438.610255 -91.353898)
			(xy 438.594187 -91.407305) (xy 438.570515 -91.457802) (xy 438.539742 -91.504315) (xy 438.502525 -91.545852)
			(xy 438.459657 -91.581527) (xy 438.412051 -91.610581) (xy 438.360722 -91.632393) (xy 438.306765 -91.646499)
			(xy 438.251328 -91.652599) (xy 438.195594 -91.650562) (xy 438.140751 -91.640432) (xy 438.087967 -91.622425)
			(xy 438.038367 -91.596924) (xy 437.993009 -91.564473) (xy 437.95286 -91.525764) (xy 437.918774 -91.481621)
			(xy 437.891478 -91.432986) (xy 437.871555 -91.380895) (xy 437.859429 -91.326458) (xy 437.855358 -91.270836)
			(xy 416.051492 -91.270836) (xy 414.854136 -92.468192) (xy 445.845182 -92.468192) (xy 445.849253 -92.41257)
			(xy 445.861379 -92.358133) (xy 445.881302 -92.306042) (xy 445.908598 -92.257407) (xy 445.942684 -92.213264)
			(xy 445.982833 -92.174555) (xy 446.028191 -92.142104) (xy 446.077791 -92.116603) (xy 446.130575 -92.098596)
			(xy 446.185418 -92.088466) (xy 446.241152 -92.086429) (xy 446.296589 -92.092529) (xy 446.350546 -92.106635)
			(xy 446.401875 -92.128447) (xy 446.449481 -92.157501) (xy 446.492349 -92.193176) (xy 446.529566 -92.234713)
			(xy 446.560339 -92.281226) (xy 446.584011 -92.331723) (xy 446.600079 -92.38513) (xy 446.608199 -92.440306)
			(xy 446.608708 -92.468192) (xy 446.608199 -92.496078) (xy 446.600079 -92.551254) (xy 446.584011 -92.604661)
			(xy 446.560339 -92.655158) (xy 446.529566 -92.701671) (xy 446.492349 -92.743208) (xy 446.449481 -92.778883)
			(xy 446.401875 -92.807937) (xy 446.350546 -92.829749) (xy 446.296589 -92.843855) (xy 446.241152 -92.849955)
			(xy 446.185418 -92.847918) (xy 446.130575 -92.837788) (xy 446.077791 -92.819781) (xy 446.028191 -92.79428)
			(xy 445.982833 -92.761829) (xy 445.942684 -92.72312) (xy 445.908598 -92.678977) (xy 445.881302 -92.630342)
			(xy 445.861379 -92.578251) (xy 445.849253 -92.523814) (xy 445.845182 -92.468192) (xy 414.854136 -92.468192)
			(xy 414.014158 -93.30817) (xy 414.006792 -93.315282) (xy 413.999172 -93.334078) (xy 413.999172 -93.923229)
			(xy 430.865317 -93.923229) (xy 430.865317 -93.859971) (xy 430.873574 -93.797253) (xy 430.889946 -93.73615)
			(xy 430.914153 -93.677706) (xy 430.945782 -93.622922) (xy 430.98429 -93.572735) (xy 431.02902 -93.528004)
			(xy 431.079206 -93.489493) (xy 431.133988 -93.457862) (xy 431.192431 -93.433652) (xy 431.253534 -93.417278)
			(xy 431.316251 -93.409018) (xy 431.34788 -93.4085) (xy 436.29326 -93.4085) (xy 436.324894 -93.408995)
			(xy 436.387622 -93.417239) (xy 436.448736 -93.433604) (xy 436.507189 -93.457809) (xy 436.552889 -93.484192)
			(xy 445.845182 -93.484192) (xy 445.849253 -93.42857) (xy 445.861379 -93.374133) (xy 445.881302 -93.322042)
			(xy 445.908598 -93.273407) (xy 445.942684 -93.229264) (xy 445.982833 -93.190555) (xy 446.028191 -93.158104)
			(xy 446.077791 -93.132603) (xy 446.130575 -93.114596) (xy 446.185418 -93.104466) (xy 446.241152 -93.102429)
			(xy 446.296589 -93.108529) (xy 446.350546 -93.122635) (xy 446.401875 -93.144447) (xy 446.449481 -93.173501)
			(xy 446.492349 -93.209176) (xy 446.529566 -93.250713) (xy 446.560339 -93.297226) (xy 446.584011 -93.347723)
			(xy 446.600079 -93.40113) (xy 446.608199 -93.456306) (xy 446.608708 -93.484192) (xy 446.608199 -93.512078)
			(xy 446.600079 -93.567254) (xy 446.584011 -93.620661) (xy 446.560339 -93.671158) (xy 446.529566 -93.717671)
			(xy 446.492349 -93.759208) (xy 446.449481 -93.794883) (xy 446.401875 -93.823937) (xy 446.350546 -93.845749)
			(xy 446.296589 -93.859855) (xy 446.241152 -93.865955) (xy 446.185418 -93.863918) (xy 446.130575 -93.853788)
			(xy 446.077791 -93.835781) (xy 446.028191 -93.81028) (xy 445.982833 -93.777829) (xy 445.942684 -93.73912)
			(xy 445.908598 -93.694977) (xy 445.881302 -93.646342) (xy 445.861379 -93.594251) (xy 445.849253 -93.539814)
			(xy 445.845182 -93.484192) (xy 436.552889 -93.484192) (xy 436.561981 -93.489441) (xy 436.612173 -93.527958)
			(xy 436.63489 -93.549978) (xy 437.01843 -93.933518) (xy 437.04042 -93.95626) (xy 437.078923 -94.006455)
			(xy 437.110548 -94.061244) (xy 437.134754 -94.119692) (xy 437.151127 -94.180798) (xy 437.159388 -94.243517)
			(xy 437.159908 -94.275148) (xy 437.159436 -94.30678) (xy 437.151173 -94.369501) (xy 437.134794 -94.430608)
			(xy 437.110579 -94.489054) (xy 437.078944 -94.54384) (xy 437.040429 -94.594028) (xy 437.031648 -94.602808)
			(xy 445.878964 -94.602808) (xy 445.883035 -94.547186) (xy 445.895161 -94.492749) (xy 445.915084 -94.440658)
			(xy 445.94238 -94.392023) (xy 445.976466 -94.34788) (xy 446.016615 -94.309171) (xy 446.061973 -94.27672)
			(xy 446.111573 -94.251219) (xy 446.164357 -94.233212) (xy 446.2192 -94.223082) (xy 446.274934 -94.221045)
			(xy 446.330371 -94.227145) (xy 446.384328 -94.241251) (xy 446.435657 -94.263063) (xy 446.483263 -94.292117)
			(xy 446.526131 -94.327792) (xy 446.563348 -94.369329) (xy 446.594121 -94.415842) (xy 446.617793 -94.466339)
			(xy 446.633861 -94.519746) (xy 446.641981 -94.574922) (xy 446.64249 -94.602808) (xy 449.269102 -94.602808)
			(xy 449.273173 -94.547186) (xy 449.285299 -94.492749) (xy 449.305222 -94.440658) (xy 449.332518 -94.392023)
			(xy 449.366604 -94.34788) (xy 449.406753 -94.309171) (xy 449.452111 -94.27672) (xy 449.501711 -94.251219)
			(xy 449.554495 -94.233212) (xy 449.609338 -94.223082) (xy 449.665072 -94.221045) (xy 449.720509 -94.227145)
			(xy 449.774466 -94.241251) (xy 449.825795 -94.263063) (xy 449.873401 -94.292117) (xy 449.916269 -94.327792)
			(xy 449.953486 -94.369329) (xy 449.984259 -94.415842) (xy 450.007931 -94.466339) (xy 450.023999 -94.519746)
			(xy 450.032119 -94.574922) (xy 450.032628 -94.602808) (xy 450.032119 -94.630694) (xy 450.023999 -94.68587)
			(xy 450.007931 -94.739277) (xy 449.984259 -94.789774) (xy 449.953486 -94.836287) (xy 449.916269 -94.877824)
			(xy 449.873401 -94.913499) (xy 449.825795 -94.942553) (xy 449.774466 -94.964365) (xy 449.720509 -94.978471)
			(xy 449.665072 -94.984571) (xy 449.609338 -94.982534) (xy 449.554495 -94.972404) (xy 449.501711 -94.954397)
			(xy 449.452111 -94.928896) (xy 449.406753 -94.896445) (xy 449.366604 -94.857736) (xy 449.332518 -94.813593)
			(xy 449.305222 -94.764958) (xy 449.285299 -94.712867) (xy 449.273173 -94.65843) (xy 449.269102 -94.602808)
			(xy 446.64249 -94.602808) (xy 446.641981 -94.630694) (xy 446.633861 -94.68587) (xy 446.617793 -94.739277)
			(xy 446.594121 -94.789774) (xy 446.563348 -94.836287) (xy 446.526131 -94.877824) (xy 446.483263 -94.913499)
			(xy 446.435657 -94.942553) (xy 446.384328 -94.964365) (xy 446.330371 -94.978471) (xy 446.274934 -94.984571)
			(xy 446.2192 -94.982534) (xy 446.164357 -94.972404) (xy 446.111573 -94.954397) (xy 446.061973 -94.928896)
			(xy 446.016615 -94.896445) (xy 445.976466 -94.857736) (xy 445.94238 -94.813593) (xy 445.915084 -94.764958)
			(xy 445.895161 -94.712867) (xy 445.883035 -94.65843) (xy 445.878964 -94.602808) (xy 437.031648 -94.602808)
			(xy 436.995692 -94.63876) (xy 436.9455 -94.677271) (xy 436.890711 -94.708901) (xy 436.832263 -94.733109)
			(xy 436.771154 -94.749482) (xy 436.708432 -94.757739) (xy 436.6768 -94.758256) (xy 436.645166 -94.757771)
			(xy 436.582438 -94.749523) (xy 436.521325 -94.733155) (xy 436.462872 -94.708947) (xy 436.40808 -94.677314)
			(xy 436.357887 -94.638798) (xy 436.33517 -94.616778) (xy 436.108094 -94.389448) (xy 436.10066 -94.382798)
			(xy 436.082241 -94.375205) (xy 436.07228 -94.374716) (xy 431.34788 -94.374716) (xy 431.316251 -94.374182)
			(xy 431.253534 -94.365922) (xy 431.192431 -94.349548) (xy 431.133988 -94.325338) (xy 431.079206 -94.293707)
			(xy 431.02902 -94.255196) (xy 430.98429 -94.210465) (xy 430.945782 -94.160278) (xy 430.914153 -94.105494)
			(xy 430.889946 -94.04705) (xy 430.873574 -93.985947) (xy 430.865317 -93.923229) (xy 413.999172 -93.923229)
			(xy 413.999172 -95.957898) (xy 438.606182 -95.957898) (xy 438.610253 -95.902276) (xy 438.622379 -95.847839)
			(xy 438.642302 -95.795748) (xy 438.669598 -95.747113) (xy 438.703684 -95.70297) (xy 438.743833 -95.664261)
			(xy 438.789191 -95.63181) (xy 438.838791 -95.606309) (xy 438.891575 -95.588302) (xy 438.946418 -95.578172)
			(xy 439.002152 -95.576135) (xy 439.057589 -95.582235) (xy 439.111546 -95.596341) (xy 439.162875 -95.618153)
			(xy 439.210481 -95.647207) (xy 439.253349 -95.682882) (xy 439.290566 -95.724419) (xy 439.321339 -95.770932)
			(xy 439.345011 -95.821429) (xy 439.360469 -95.872808) (xy 442.723522 -95.872808) (xy 442.727593 -95.817186)
			(xy 442.739719 -95.762749) (xy 442.759642 -95.710658) (xy 442.786938 -95.662023) (xy 442.821024 -95.61788)
			(xy 442.861173 -95.579171) (xy 442.906531 -95.54672) (xy 442.956131 -95.521219) (xy 443.008915 -95.503212)
			(xy 443.063758 -95.493082) (xy 443.119492 -95.491045) (xy 443.174929 -95.497145) (xy 443.228886 -95.511251)
			(xy 443.280215 -95.533063) (xy 443.327821 -95.562117) (xy 443.370689 -95.597792) (xy 443.407906 -95.639329)
			(xy 443.438679 -95.685842) (xy 443.462351 -95.736339) (xy 443.478419 -95.789746) (xy 443.486539 -95.844922)
			(xy 443.487048 -95.872808) (xy 443.486539 -95.900694) (xy 443.478419 -95.95587) (xy 443.462351 -96.009277)
			(xy 443.438679 -96.059774) (xy 443.407906 -96.106287) (xy 443.370689 -96.147824) (xy 443.327821 -96.183499)
			(xy 443.280215 -96.212553) (xy 443.228886 -96.234365) (xy 443.174929 -96.248471) (xy 443.119492 -96.254571)
			(xy 443.063758 -96.252534) (xy 443.008915 -96.242404) (xy 442.956131 -96.224397) (xy 442.906531 -96.198896)
			(xy 442.861173 -96.166445) (xy 442.821024 -96.127736) (xy 442.786938 -96.083593) (xy 442.759642 -96.034958)
			(xy 442.739719 -95.982867) (xy 442.727593 -95.92843) (xy 442.723522 -95.872808) (xy 439.360469 -95.872808)
			(xy 439.361079 -95.874836) (xy 439.369199 -95.930012) (xy 439.369708 -95.957898) (xy 439.369199 -95.985784)
			(xy 439.361079 -96.04096) (xy 439.345011 -96.094367) (xy 439.321339 -96.144864) (xy 439.290566 -96.191377)
			(xy 439.253349 -96.232914) (xy 439.210481 -96.268589) (xy 439.162875 -96.297643) (xy 439.111546 -96.319455)
			(xy 439.057589 -96.333561) (xy 439.002152 -96.339661) (xy 438.946418 -96.337624) (xy 438.891575 -96.327494)
			(xy 438.838791 -96.309487) (xy 438.789191 -96.283986) (xy 438.743833 -96.251535) (xy 438.703684 -96.212826)
			(xy 438.669598 -96.168683) (xy 438.642302 -96.120048) (xy 438.622379 -96.067957) (xy 438.610253 -96.01352)
			(xy 438.606182 -95.957898) (xy 413.999172 -95.957898) (xy 413.999172 -96.812608) (xy 434.902862 -96.812608)
			(xy 434.906933 -96.756986) (xy 434.919059 -96.702549) (xy 434.938982 -96.650458) (xy 434.966278 -96.601823)
			(xy 435.000364 -96.55768) (xy 435.040513 -96.518971) (xy 435.085871 -96.48652) (xy 435.135471 -96.461019)
			(xy 435.188255 -96.443012) (xy 435.243098 -96.432882) (xy 435.298832 -96.430845) (xy 435.354269 -96.436945)
			(xy 435.408226 -96.451051) (xy 435.459555 -96.472863) (xy 435.507161 -96.501917) (xy 435.550029 -96.537592)
			(xy 435.587246 -96.579129) (xy 435.618019 -96.625642) (xy 435.641691 -96.676139) (xy 435.657759 -96.729546)
			(xy 435.665879 -96.784722) (xy 435.666388 -96.812608) (xy 435.791862 -96.812608) (xy 435.795933 -96.756986)
			(xy 435.808059 -96.702549) (xy 435.827982 -96.650458) (xy 435.855278 -96.601823) (xy 435.889364 -96.55768)
			(xy 435.929513 -96.518971) (xy 435.974871 -96.48652) (xy 436.024471 -96.461019) (xy 436.077255 -96.443012)
			(xy 436.132098 -96.432882) (xy 436.187832 -96.430845) (xy 436.243269 -96.436945) (xy 436.297226 -96.451051)
			(xy 436.348555 -96.472863) (xy 436.396161 -96.501917) (xy 436.439029 -96.537592) (xy 436.476246 -96.579129)
			(xy 436.507019 -96.625642) (xy 436.530691 -96.676139) (xy 436.546759 -96.729546) (xy 436.554879 -96.784722)
			(xy 436.555388 -96.812608) (xy 436.554879 -96.840494) (xy 436.546759 -96.89567) (xy 436.530691 -96.949077)
			(xy 436.507019 -96.999574) (xy 436.476246 -97.046087) (xy 436.439029 -97.087624) (xy 436.396161 -97.123299)
			(xy 436.348555 -97.152353) (xy 436.297226 -97.174165) (xy 436.243269 -97.188271) (xy 436.187832 -97.194371)
			(xy 436.132098 -97.192334) (xy 436.077255 -97.182204) (xy 436.024471 -97.164197) (xy 435.974871 -97.138696)
			(xy 435.929513 -97.106245) (xy 435.889364 -97.067536) (xy 435.855278 -97.023393) (xy 435.827982 -96.974758)
			(xy 435.808059 -96.922667) (xy 435.795933 -96.86823) (xy 435.791862 -96.812608) (xy 435.666388 -96.812608)
			(xy 435.665879 -96.840494) (xy 435.657759 -96.89567) (xy 435.641691 -96.949077) (xy 435.618019 -96.999574)
			(xy 435.587246 -97.046087) (xy 435.550029 -97.087624) (xy 435.507161 -97.123299) (xy 435.459555 -97.152353)
			(xy 435.408226 -97.174165) (xy 435.354269 -97.188271) (xy 435.298832 -97.194371) (xy 435.243098 -97.192334)
			(xy 435.188255 -97.182204) (xy 435.135471 -97.164197) (xy 435.085871 -97.138696) (xy 435.040513 -97.106245)
			(xy 435.000364 -97.067536) (xy 434.966278 -97.023393) (xy 434.938982 -96.974758) (xy 434.919059 -96.922667)
			(xy 434.906933 -96.86823) (xy 434.902862 -96.812608) (xy 413.999172 -96.812608) (xy 413.999172 -97.254568)
			(xy 442.690502 -97.254568) (xy 442.694573 -97.198946) (xy 442.706699 -97.144509) (xy 442.726622 -97.092418)
			(xy 442.753918 -97.043783) (xy 442.788004 -96.99964) (xy 442.828153 -96.960931) (xy 442.873511 -96.92848)
			(xy 442.923111 -96.902979) (xy 442.975895 -96.884972) (xy 443.030738 -96.874842) (xy 443.086472 -96.872805)
			(xy 443.141909 -96.878905) (xy 443.195866 -96.893011) (xy 443.247195 -96.914823) (xy 443.294801 -96.943877)
			(xy 443.337669 -96.979552) (xy 443.374886 -97.021089) (xy 443.405659 -97.067602) (xy 443.429331 -97.118099)
			(xy 443.445399 -97.171506) (xy 443.453519 -97.226682) (xy 443.454028 -97.254568) (xy 443.453519 -97.282454)
			(xy 443.445399 -97.33763) (xy 443.429331 -97.391037) (xy 443.405659 -97.441534) (xy 443.374886 -97.488047)
			(xy 443.337669 -97.529584) (xy 443.294801 -97.565259) (xy 443.247195 -97.594313) (xy 443.195866 -97.616125)
			(xy 443.141909 -97.630231) (xy 443.086472 -97.636331) (xy 443.030738 -97.634294) (xy 442.975895 -97.624164)
			(xy 442.923111 -97.606157) (xy 442.873511 -97.580656) (xy 442.828153 -97.548205) (xy 442.788004 -97.509496)
			(xy 442.753918 -97.465353) (xy 442.726622 -97.416718) (xy 442.706699 -97.364627) (xy 442.694573 -97.31019)
			(xy 442.690502 -97.254568) (xy 413.999172 -97.254568) (xy 413.999172 -97.701608) (xy 434.902862 -97.701608)
			(xy 434.906933 -97.645986) (xy 434.919059 -97.591549) (xy 434.938982 -97.539458) (xy 434.966278 -97.490823)
			(xy 435.000364 -97.44668) (xy 435.040513 -97.407971) (xy 435.085871 -97.37552) (xy 435.135471 -97.350019)
			(xy 435.188255 -97.332012) (xy 435.243098 -97.321882) (xy 435.298832 -97.319845) (xy 435.354269 -97.325945)
			(xy 435.408226 -97.340051) (xy 435.459555 -97.361863) (xy 435.507161 -97.390917) (xy 435.550029 -97.426592)
			(xy 435.587246 -97.468129) (xy 435.618019 -97.514642) (xy 435.641691 -97.565139) (xy 435.657759 -97.618546)
			(xy 435.665879 -97.673722) (xy 435.666388 -97.701608) (xy 435.791862 -97.701608) (xy 435.795933 -97.645986)
			(xy 435.808059 -97.591549) (xy 435.827982 -97.539458) (xy 435.855278 -97.490823) (xy 435.889364 -97.44668)
			(xy 435.929513 -97.407971) (xy 435.974871 -97.37552) (xy 436.024471 -97.350019) (xy 436.077255 -97.332012)
			(xy 436.132098 -97.321882) (xy 436.187832 -97.319845) (xy 436.243269 -97.325945) (xy 436.297226 -97.340051)
			(xy 436.348555 -97.361863) (xy 436.396161 -97.390917) (xy 436.439029 -97.426592) (xy 436.476246 -97.468129)
			(xy 436.507019 -97.514642) (xy 436.530691 -97.565139) (xy 436.546759 -97.618546) (xy 436.554879 -97.673722)
			(xy 436.555388 -97.701608) (xy 436.554879 -97.729494) (xy 436.546759 -97.78467) (xy 436.530691 -97.838077)
			(xy 436.507019 -97.888574) (xy 436.476246 -97.935087) (xy 436.439029 -97.976624) (xy 436.396161 -98.012299)
			(xy 436.348555 -98.041353) (xy 436.297226 -98.063165) (xy 436.243269 -98.077271) (xy 436.187832 -98.083371)
			(xy 436.132098 -98.081334) (xy 436.077255 -98.071204) (xy 436.024471 -98.053197) (xy 435.974871 -98.027696)
			(xy 435.929513 -97.995245) (xy 435.889364 -97.956536) (xy 435.855278 -97.912393) (xy 435.827982 -97.863758)
			(xy 435.808059 -97.811667) (xy 435.795933 -97.75723) (xy 435.791862 -97.701608) (xy 435.666388 -97.701608)
			(xy 435.665879 -97.729494) (xy 435.657759 -97.78467) (xy 435.641691 -97.838077) (xy 435.618019 -97.888574)
			(xy 435.587246 -97.935087) (xy 435.550029 -97.976624) (xy 435.507161 -98.012299) (xy 435.459555 -98.041353)
			(xy 435.408226 -98.063165) (xy 435.354269 -98.077271) (xy 435.298832 -98.083371) (xy 435.243098 -98.081334)
			(xy 435.188255 -98.071204) (xy 435.135471 -98.053197) (xy 435.085871 -98.027696) (xy 435.040513 -97.995245)
			(xy 435.000364 -97.956536) (xy 434.966278 -97.912393) (xy 434.938982 -97.863758) (xy 434.919059 -97.811667)
			(xy 434.906933 -97.75723) (xy 434.902862 -97.701608) (xy 413.999172 -97.701608) (xy 413.999172 -98.590608)
			(xy 434.902862 -98.590608) (xy 434.906933 -98.534986) (xy 434.919059 -98.480549) (xy 434.938982 -98.428458)
			(xy 434.966278 -98.379823) (xy 435.000364 -98.33568) (xy 435.040513 -98.296971) (xy 435.085871 -98.26452)
			(xy 435.135471 -98.239019) (xy 435.188255 -98.221012) (xy 435.243098 -98.210882) (xy 435.298832 -98.208845)
			(xy 435.354269 -98.214945) (xy 435.408226 -98.229051) (xy 435.459555 -98.250863) (xy 435.507161 -98.279917)
			(xy 435.550029 -98.315592) (xy 435.587246 -98.357129) (xy 435.618019 -98.403642) (xy 435.641691 -98.454139)
			(xy 435.657759 -98.507546) (xy 435.665879 -98.562722) (xy 435.666388 -98.590608) (xy 435.791862 -98.590608)
			(xy 435.795933 -98.534986) (xy 435.808059 -98.480549) (xy 435.827982 -98.428458) (xy 435.855278 -98.379823)
			(xy 435.889364 -98.33568) (xy 435.929513 -98.296971) (xy 435.974871 -98.26452) (xy 436.024471 -98.239019)
			(xy 436.077255 -98.221012) (xy 436.132098 -98.210882) (xy 436.187832 -98.208845) (xy 436.243269 -98.214945)
			(xy 436.297226 -98.229051) (xy 436.348555 -98.250863) (xy 436.396161 -98.279917) (xy 436.439029 -98.315592)
			(xy 436.476246 -98.357129) (xy 436.507019 -98.403642) (xy 436.530691 -98.454139) (xy 436.546759 -98.507546)
			(xy 436.554879 -98.562722) (xy 436.555388 -98.590608) (xy 436.554879 -98.618494) (xy 436.546759 -98.67367)
			(xy 436.530691 -98.727077) (xy 436.507019 -98.777574) (xy 436.476246 -98.824087) (xy 436.439029 -98.865624)
			(xy 436.396161 -98.901299) (xy 436.348555 -98.930353) (xy 436.297226 -98.952165) (xy 436.243269 -98.966271)
			(xy 436.187832 -98.972371) (xy 436.132098 -98.970334) (xy 436.077255 -98.960204) (xy 436.024471 -98.942197)
			(xy 435.974871 -98.916696) (xy 435.929513 -98.884245) (xy 435.889364 -98.845536) (xy 435.855278 -98.801393)
			(xy 435.827982 -98.752758) (xy 435.808059 -98.700667) (xy 435.795933 -98.64623) (xy 435.791862 -98.590608)
			(xy 435.666388 -98.590608) (xy 435.665879 -98.618494) (xy 435.657759 -98.67367) (xy 435.641691 -98.727077)
			(xy 435.618019 -98.777574) (xy 435.587246 -98.824087) (xy 435.550029 -98.865624) (xy 435.507161 -98.901299)
			(xy 435.459555 -98.930353) (xy 435.408226 -98.952165) (xy 435.354269 -98.966271) (xy 435.298832 -98.972371)
			(xy 435.243098 -98.970334) (xy 435.188255 -98.960204) (xy 435.135471 -98.942197) (xy 435.085871 -98.916696)
			(xy 435.040513 -98.884245) (xy 435.000364 -98.845536) (xy 434.966278 -98.801393) (xy 434.938982 -98.752758)
			(xy 434.919059 -98.700667) (xy 434.906933 -98.64623) (xy 434.902862 -98.590608) (xy 413.999172 -98.590608)
			(xy 413.999172 -99.459796) (xy 413.999667 -99.469793) (xy 414.0073 -99.488275) (xy 414.021383 -99.502471)
			(xy 414.030414 -99.506786) (xy 414.131252 -99.548696) (xy 414.161224 -99.542854) (xy 414.1724 -99.531932)
			(xy 414.193974 -99.511369) (xy 414.242321 -99.476519) (xy 414.295496 -99.449607) (xy 414.352209 -99.431287)
			(xy 414.411079 -99.422005) (xy 414.440878 -99.421442) (xy 414.468128 -99.421904) (xy 414.522075 -99.429657)
			(xy 414.574368 -99.445009) (xy 414.623945 -99.467648) (xy 414.642557 -99.479608) (xy 434.902862 -99.479608)
			(xy 434.906933 -99.423986) (xy 434.919059 -99.369549) (xy 434.938982 -99.317458) (xy 434.966278 -99.268823)
			(xy 435.000364 -99.22468) (xy 435.040513 -99.185971) (xy 435.085871 -99.15352) (xy 435.135471 -99.128019)
			(xy 435.188255 -99.110012) (xy 435.243098 -99.099882) (xy 435.298832 -99.097845) (xy 435.354269 -99.103945)
			(xy 435.408226 -99.118051) (xy 435.459555 -99.139863) (xy 435.507161 -99.168917) (xy 435.550029 -99.204592)
			(xy 435.587246 -99.246129) (xy 435.618019 -99.292642) (xy 435.641691 -99.343139) (xy 435.657759 -99.396546)
			(xy 435.665879 -99.451722) (xy 435.666388 -99.479608) (xy 435.791862 -99.479608) (xy 435.795933 -99.423986)
			(xy 435.808059 -99.369549) (xy 435.827982 -99.317458) (xy 435.855278 -99.268823) (xy 435.889364 -99.22468)
			(xy 435.929513 -99.185971) (xy 435.974871 -99.15352) (xy 436.024471 -99.128019) (xy 436.077255 -99.110012)
			(xy 436.132098 -99.099882) (xy 436.187832 -99.097845) (xy 436.243269 -99.103945) (xy 436.297226 -99.118051)
			(xy 436.348555 -99.139863) (xy 436.396161 -99.168917) (xy 436.439029 -99.204592) (xy 436.476246 -99.246129)
			(xy 436.507019 -99.292642) (xy 436.530691 -99.343139) (xy 436.546759 -99.396546) (xy 436.554879 -99.451722)
			(xy 436.555388 -99.479608) (xy 436.554879 -99.507494) (xy 436.546759 -99.56267) (xy 436.530691 -99.616077)
			(xy 436.507019 -99.666574) (xy 436.476246 -99.713087) (xy 436.439029 -99.754624) (xy 436.396161 -99.790299)
			(xy 436.348555 -99.819353) (xy 436.297226 -99.841165) (xy 436.243269 -99.855271) (xy 436.187832 -99.861371)
			(xy 436.132098 -99.859334) (xy 436.077255 -99.849204) (xy 436.024471 -99.831197) (xy 435.974871 -99.805696)
			(xy 435.929513 -99.773245) (xy 435.889364 -99.734536) (xy 435.855278 -99.690393) (xy 435.827982 -99.641758)
			(xy 435.808059 -99.589667) (xy 435.795933 -99.53523) (xy 435.791862 -99.479608) (xy 435.666388 -99.479608)
			(xy 435.665879 -99.507494) (xy 435.657759 -99.56267) (xy 435.641691 -99.616077) (xy 435.618019 -99.666574)
			(xy 435.587246 -99.713087) (xy 435.550029 -99.754624) (xy 435.507161 -99.790299) (xy 435.459555 -99.819353)
			(xy 435.408226 -99.841165) (xy 435.354269 -99.855271) (xy 435.298832 -99.861371) (xy 435.243098 -99.859334)
			(xy 435.188255 -99.849204) (xy 435.135471 -99.831197) (xy 435.085871 -99.805696) (xy 435.040513 -99.773245)
			(xy 435.000364 -99.734536) (xy 434.966278 -99.690393) (xy 434.938982 -99.641758) (xy 434.919059 -99.589667)
			(xy 434.906933 -99.53523) (xy 434.902862 -99.479608) (xy 414.642557 -99.479608) (xy 414.669794 -99.497111)
			(xy 414.710984 -99.5328) (xy 414.746676 -99.573988) (xy 414.776142 -99.619836) (xy 414.798783 -99.669411)
			(xy 414.814138 -99.721704) (xy 414.821895 -99.77565) (xy 414.821895 -99.83015) (xy 414.814138 -99.884096)
			(xy 414.798783 -99.936389) (xy 414.776142 -99.985964) (xy 414.746676 -100.031812) (xy 414.710984 -100.073)
			(xy 414.669794 -100.108689) (xy 414.623945 -100.138152) (xy 414.574368 -100.160791) (xy 414.522075 -100.176143)
			(xy 414.468128 -100.183896) (xy 414.440878 -100.184458) (xy 414.411077 -100.183889) (xy 414.352199 -100.174629)
			(xy 414.295479 -100.156322) (xy 414.242297 -100.129414) (xy 414.193949 -100.094559) (xy 414.1724 -100.073968)
			(xy 414.161224 -100.063046) (xy 414.131252 -100.057204) (xy 414.030414 -100.099114) (xy 414.021317 -100.103343)
			(xy 414.007162 -100.117538) (xy 413.999542 -100.136079) (xy 413.999172 -100.146104) (xy 413.999172 -102.63945)
			(xy 429.495968 -102.63945) (xy 429.495968 -102.58495) (xy 429.503724 -102.531003) (xy 429.519077 -102.47871)
			(xy 429.541717 -102.429134) (xy 429.57118 -102.383284) (xy 429.606869 -102.342093) (xy 429.648057 -102.306401)
			(xy 429.693904 -102.276933) (xy 429.743478 -102.254289) (xy 429.79577 -102.238931) (xy 429.849716 -102.23117)
			(xy 429.876966 -102.230682) (xy 429.903569 -102.231164) (xy 429.95626 -102.238541) (xy 430.007415 -102.25317)
			(xy 430.056039 -102.274767) (xy 430.10119 -102.302914) (xy 430.14199 -102.337062) (xy 430.177648 -102.376551)
			(xy 430.192942 -102.398322) (xy 430.200458 -102.408259) (xy 430.222413 -102.419979) (xy 430.234852 -102.420674)
			(xy 430.31918 -102.420674) (xy 430.331635 -102.420036) (xy 430.353613 -102.408305) (xy 430.36109 -102.398322)
			(xy 430.376374 -102.376544) (xy 430.412042 -102.337065) (xy 430.452848 -102.302923) (xy 430.498 -102.274779)
			(xy 430.546623 -102.253178) (xy 430.597775 -102.238539) (xy 430.650463 -102.231145) (xy 430.677066 -102.230682)
			(xy 430.704318 -102.231187) (xy 430.758266 -102.238939) (xy 430.810563 -102.25429) (xy 430.860142 -102.276928)
			(xy 430.905995 -102.306392) (xy 430.947188 -102.342081) (xy 430.982882 -102.38327) (xy 431.012351 -102.429119)
			(xy 431.034994 -102.478696) (xy 431.050352 -102.53099) (xy 431.05811 -102.584938) (xy 431.058574 -102.61219)
			(xy 431.058169 -102.636998) (xy 431.057848 -102.639451) (xy 431.370468 -102.639451) (xy 431.370468 -102.584949)
			(xy 431.378224 -102.531001) (xy 431.393579 -102.478706) (xy 431.41622 -102.429128) (xy 431.445685 -102.383277)
			(xy 431.481376 -102.342086) (xy 431.522566 -102.306394) (xy 431.568416 -102.276926) (xy 431.617993 -102.254284)
			(xy 431.670287 -102.238927) (xy 431.724235 -102.231169) (xy 431.751486 -102.230682) (xy 431.780451 -102.231233)
			(xy 431.837715 -102.240002) (xy 431.892995 -102.257325) (xy 431.945022 -102.282805) (xy 431.9926 -102.315856)
			(xy 432.034635 -102.355719) (xy 432.070163 -102.401477) (xy 432.084734 -102.426516) (xy 432.092088 -102.438728)
			(xy 432.112316 -102.458797) (xy 432.137304 -102.472494) (xy 432.165104 -102.47875) (xy 432.19355 -102.47708)
			(xy 432.220426 -102.467612) (xy 432.243639 -102.451085) (xy 432.252882 -102.440232) (xy 432.271098 -102.418176)
			(xy 432.313 -102.379236) (xy 432.360242 -102.346983) (xy 432.411768 -102.322139) (xy 432.466423 -102.30526)
			(xy 432.522985 -102.296724) (xy 432.551586 -102.296214) (xy 432.578841 -102.296632) (xy 432.632797 -102.304388)
			(xy 432.685099 -102.319743) (xy 432.734684 -102.342386) (xy 432.780542 -102.371856) (xy 432.821738 -102.407552)
			(xy 432.857436 -102.448747) (xy 432.886907 -102.494604) (xy 432.909552 -102.544188) (xy 432.924909 -102.59649)
			(xy 432.932667 -102.650445) (xy 432.932667 -102.704955) (xy 432.924909 -102.75891) (xy 432.909552 -102.811212)
			(xy 432.886907 -102.860796) (xy 432.857436 -102.906653) (xy 432.821738 -102.947848) (xy 432.780542 -102.983544)
			(xy 432.734684 -103.013014) (xy 432.685099 -103.035657) (xy 432.632797 -103.051012) (xy 432.578841 -103.058768)
			(xy 432.551586 -103.05923) (xy 432.522618 -103.058746) (xy 432.465349 -103.049971) (xy 432.410065 -103.032639)
			(xy 432.358036 -103.007149) (xy 432.310459 -102.974086) (xy 432.268427 -102.934212) (xy 432.232905 -102.888441)
			(xy 432.218338 -102.863396) (xy 432.211021 -102.851159) (xy 432.190786 -102.831086) (xy 432.16579 -102.817388)
			(xy 432.137982 -102.811133) (xy 432.109529 -102.812809) (xy 432.082648 -102.822285) (xy 432.059433 -102.838822)
			(xy 432.05019 -102.84968) (xy 432.031993 -102.871752) (xy 431.990086 -102.91069) (xy 431.94284 -102.942941)
			(xy 431.891311 -102.967782) (xy 431.836652 -102.984658) (xy 431.780088 -102.99319) (xy 431.751486 -102.993698)
			(xy 431.724235 -102.993231) (xy 431.670287 -102.985473) (xy 431.617993 -102.970116) (xy 431.568416 -102.947474)
			(xy 431.522566 -102.918006) (xy 431.481376 -102.882314) (xy 431.445685 -102.841123) (xy 431.41622 -102.795272)
			(xy 431.393579 -102.745694) (xy 431.378224 -102.693399) (xy 431.370468 -102.639451) (xy 431.057848 -102.639451)
			(xy 431.051732 -102.686194) (xy 431.038953 -102.734135) (xy 431.029872 -102.757224) (xy 431.0253 -102.7684)
			(xy 431.027078 -102.79253) (xy 431.081942 -102.883208) (xy 431.102262 -102.895908) (xy 431.114454 -102.897178)
			(xy 431.142478 -102.90029) (xy 431.197232 -102.913751) (xy 431.249408 -102.935124) (xy 431.29787 -102.963943)
			(xy 431.341562 -102.999582) (xy 431.379534 -103.041264) (xy 431.410956 -103.08808) (xy 431.435146 -103.139011)
			(xy 431.451576 -103.192948) (xy 431.459889 -103.248716) (xy 431.460402 -103.276908) (xy 431.459916 -103.304159)
			(xy 431.45216 -103.358107) (xy 431.436805 -103.410402) (xy 431.414163 -103.459979) (xy 431.384697 -103.505829)
			(xy 431.349006 -103.54702) (xy 431.307815 -103.582711) (xy 431.261965 -103.612177) (xy 431.212388 -103.634819)
			(xy 431.160093 -103.650174) (xy 431.106145 -103.65793) (xy 431.051643 -103.65793) (xy 430.997695 -103.650174)
			(xy 430.9454 -103.634819) (xy 430.895823 -103.612177) (xy 430.849973 -103.582711) (xy 430.808782 -103.54702)
			(xy 430.773091 -103.505829) (xy 430.743625 -103.459979) (xy 430.720983 -103.410402) (xy 430.705628 -103.358107)
			(xy 430.697872 -103.304159) (xy 430.697386 -103.276908) (xy 430.697793 -103.2521) (xy 430.704229 -103.202905)
			(xy 430.717007 -103.154963) (xy 430.726088 -103.131874) (xy 430.73066 -103.120698) (xy 430.728882 -103.096568)
			(xy 430.674018 -103.00589) (xy 430.653698 -102.99319) (xy 430.641506 -102.99192) (xy 430.613609 -102.988818)
			(xy 430.559087 -102.975477) (xy 430.50711 -102.95429) (xy 430.458798 -102.925714) (xy 430.415195 -102.890368)
			(xy 430.377243 -102.849014) (xy 430.36109 -102.826058) (xy 430.353611 -102.816087) (xy 430.331628 -102.804386)
			(xy 430.31918 -102.803706) (xy 430.234852 -102.803706) (xy 430.222401 -102.804371) (xy 430.200423 -102.816084)
			(xy 430.192942 -102.826058) (xy 430.177632 -102.847817) (xy 430.141968 -102.887297) (xy 430.101167 -102.921441)
			(xy 430.05602 -102.949588) (xy 430.007401 -102.971192) (xy 429.956253 -102.985835) (xy 429.903567 -102.993232)
			(xy 429.876966 -102.993698) (xy 429.849716 -102.99323) (xy 429.79577 -102.985469) (xy 429.743478 -102.970111)
			(xy 429.693904 -102.947467) (xy 429.648057 -102.917999) (xy 429.606869 -102.882307) (xy 429.57118 -102.841116)
			(xy 429.541717 -102.795266) (xy 429.519077 -102.74569) (xy 429.503724 -102.693397) (xy 429.495968 -102.63945)
			(xy 413.999172 -102.63945) (xy 413.999172 -104.501188) (xy 418.035232 -104.501188) (xy 418.035683 -104.473817)
			(xy 418.043503 -104.419637) (xy 418.058996 -104.367134) (xy 418.081841 -104.317387) (xy 418.111569 -104.271421)
			(xy 418.129212 -104.25049) (xy 418.135308 -104.243378) (xy 418.141658 -104.22636) (xy 418.141658 -104.141016)
			(xy 418.135308 -104.123998) (xy 418.129212 -104.116886) (xy 418.111602 -104.095931) (xy 418.081885 -104.049965)
			(xy 418.059043 -104.000223) (xy 418.043546 -103.947727) (xy 418.03571 -103.893556) (xy 418.035232 -103.866188)
			(xy 418.035644 -103.838933) (xy 418.043403 -103.784978) (xy 418.058763 -103.732677) (xy 418.08141 -103.683094)
			(xy 418.110883 -103.637239) (xy 418.146582 -103.596045) (xy 418.187781 -103.560352) (xy 418.23364 -103.530885)
			(xy 418.283226 -103.508245) (xy 418.335529 -103.492892) (xy 418.389485 -103.48514) (xy 418.41674 -103.48468)
			(xy 418.442319 -103.485084) (xy 418.493018 -103.491932) (xy 418.542348 -103.505486) (xy 418.589428 -103.525504)
			(xy 418.633414 -103.551628) (xy 418.673519 -103.583389) (xy 418.691568 -103.60152) (xy 418.69868 -103.608886)
			(xy 418.717222 -103.617014) (xy 418.810186 -103.61803) (xy 418.828982 -103.61041) (xy 418.836348 -103.603044)
			(xy 418.857913 -103.582417) (xy 418.906289 -103.547481) (xy 418.959517 -103.520507) (xy 419.016298 -103.502155)
			(xy 419.075244 -103.492872) (xy 419.10508 -103.4923) (xy 419.132333 -103.492774) (xy 419.186284 -103.500528)
			(xy 419.238582 -103.515882) (xy 419.288162 -103.538523) (xy 419.334016 -103.56799) (xy 419.375209 -103.603682)
			(xy 419.410903 -103.644874) (xy 419.440371 -103.690727) (xy 419.463013 -103.740307) (xy 419.478369 -103.792605)
			(xy 419.486125 -103.846555) (xy 419.486588 -103.873808) (xy 419.48613 -103.901179) (xy 419.47831 -103.955358)
			(xy 419.46282 -104.007861) (xy 419.439976 -104.057608) (xy 419.41025 -104.103575) (xy 419.392608 -104.124506)
			(xy 419.386512 -104.131618) (xy 419.380162 -104.148636) (xy 419.380162 -104.23398) (xy 419.386512 -104.250998)
			(xy 419.392608 -104.25811) (xy 419.410266 -104.279026) (xy 419.439975 -104.325004) (xy 419.462807 -104.374755)
			(xy 419.478294 -104.427259) (xy 419.486117 -104.481438) (xy 419.486588 -104.508808) (xy 419.486152 -104.536062)
			(xy 419.478393 -104.590015) (xy 419.463035 -104.642314) (xy 419.440391 -104.691896) (xy 419.41092 -104.73775)
			(xy 419.375223 -104.778943) (xy 419.334028 -104.814637) (xy 419.288171 -104.844104) (xy 419.238588 -104.866745)
			(xy 419.186287 -104.882099) (xy 419.132334 -104.889854) (xy 419.10508 -104.890316) (xy 419.079501 -104.8899)
			(xy 419.028803 -104.883055) (xy 418.979473 -104.869503) (xy 418.932393 -104.849487) (xy 418.888407 -104.823365)
			(xy 418.848301 -104.791606) (xy 418.830252 -104.773476) (xy 418.82314 -104.76611) (xy 418.804598 -104.757982)
			(xy 418.711634 -104.756966) (xy 418.692838 -104.764586) (xy 418.685472 -104.771952) (xy 418.663898 -104.792569)
			(xy 418.615524 -104.827506) (xy 418.562298 -104.854482) (xy 418.50552 -104.872837) (xy 418.446576 -104.882123)
			(xy 418.41674 -104.882696) (xy 418.389488 -104.882207) (xy 418.335537 -104.874456) (xy 418.283239 -104.859104)
			(xy 418.233658 -104.836465) (xy 418.187804 -104.807) (xy 418.146611 -104.771309) (xy 418.110916 -104.730118)
			(xy 418.081448 -104.684267) (xy 418.058806 -104.634687) (xy 418.04345 -104.58239) (xy 418.035695 -104.52844)
			(xy 418.035232 -104.501188) (xy 413.999172 -104.501188) (xy 413.999172 -105.827322) (xy 429.906682 -105.827322)
			(xy 429.910753 -105.7717) (xy 429.922879 -105.717263) (xy 429.942802 -105.665172) (xy 429.970098 -105.616537)
			(xy 430.004184 -105.572394) (xy 430.044333 -105.533685) (xy 430.089691 -105.501234) (xy 430.139291 -105.475733)
			(xy 430.192075 -105.457726) (xy 430.246918 -105.447596) (xy 430.302652 -105.445559) (xy 430.358089 -105.451659)
			(xy 430.412046 -105.465765) (xy 430.463375 -105.487577) (xy 430.510981 -105.516631) (xy 430.553849 -105.552306)
			(xy 430.591066 -105.593843) (xy 430.614291 -105.628948) (xy 433.069492 -105.628948) (xy 433.069988 -105.601579)
			(xy 433.077799 -105.547401) (xy 433.093281 -105.494898) (xy 433.116116 -105.445151) (xy 433.145834 -105.399183)
			(xy 433.163472 -105.37825) (xy 433.169568 -105.371138) (xy 433.175918 -105.35412) (xy 433.175918 -105.268776)
			(xy 433.169568 -105.251758) (xy 433.163472 -105.244646) (xy 433.145837 -105.223711) (xy 433.116125 -105.177739)
			(xy 433.093289 -105.127992) (xy 433.077797 -105.075492) (xy 433.069967 -105.021317) (xy 433.069492 -104.993948)
			(xy 433.069991 -104.965775) (xy 433.078298 -104.910045) (xy 433.094709 -104.856142) (xy 433.118868 -104.805238)
			(xy 433.150249 -104.75844) (xy 433.188171 -104.716765) (xy 433.231808 -104.681118) (xy 433.280212 -104.652276)
			(xy 433.332331 -104.630864) (xy 433.35956 -104.623616) (xy 433.370482 -104.620822) (xy 433.388008 -104.606598)
			(xy 433.432204 -104.516174) (xy 433.432458 -104.493822) (xy 433.427886 -104.483408) (xy 433.417375 -104.458766)
			(xy 433.402561 -104.407283) (xy 433.395071 -104.354238) (xy 433.394612 -104.327452) (xy 433.395098 -104.300201)
			(xy 433.402854 -104.246253) (xy 433.418209 -104.193958) (xy 433.440851 -104.144381) (xy 433.470317 -104.098531)
			(xy 433.506008 -104.05734) (xy 433.547199 -104.021649) (xy 433.593049 -103.992183) (xy 433.642626 -103.969541)
			(xy 433.694921 -103.954186) (xy 433.748869 -103.94643) (xy 433.803371 -103.94643) (xy 433.857319 -103.954186)
			(xy 433.909614 -103.969541) (xy 433.959191 -103.992183) (xy 434.005041 -104.021649) (xy 434.046232 -104.05734)
			(xy 434.081923 -104.098531) (xy 434.111389 -104.144381) (xy 434.134031 -104.193958) (xy 434.149386 -104.246253)
			(xy 434.157142 -104.300201) (xy 434.157628 -104.327452) (xy 434.157175 -104.354753) (xy 434.149421 -104.4088)
			(xy 434.134021 -104.461184) (xy 434.123084 -104.486202) (xy 434.118258 -104.496362) (xy 434.118512 -104.51846)
			(xy 434.160422 -104.609138) (xy 434.17744 -104.623362) (xy 434.188108 -104.62641) (xy 434.214542 -104.634228)
			(xy 434.264983 -104.656465) (xy 434.311697 -104.685732) (xy 434.353711 -104.721419) (xy 434.390149 -104.762783)
			(xy 434.420254 -104.808961) (xy 434.443397 -104.858992) (xy 434.459097 -104.911834) (xy 434.467026 -104.966386)
			(xy 434.467508 -104.993948) (xy 434.467009 -105.021317) (xy 434.459199 -105.075495) (xy 434.443718 -105.127997)
			(xy 434.420883 -105.177745) (xy 434.391166 -105.223713) (xy 434.373528 -105.244646) (xy 434.367432 -105.251758)
			(xy 434.361082 -105.268776) (xy 434.361082 -105.35412) (xy 434.367432 -105.371138) (xy 434.373528 -105.37825)
			(xy 434.391161 -105.399187) (xy 434.420873 -105.445159) (xy 434.44371 -105.494905) (xy 434.459202 -105.547404)
			(xy 434.467033 -105.601579) (xy 434.467508 -105.628948) (xy 434.467067 -105.6562) (xy 434.459304 -105.71015)
			(xy 434.443943 -105.762445) (xy 434.421296 -105.812023) (xy 434.391825 -105.857873) (xy 434.356129 -105.899063)
			(xy 434.314934 -105.934753) (xy 434.269081 -105.964219) (xy 434.2195 -105.986859) (xy 434.167203 -106.002214)
			(xy 434.113252 -106.00997) (xy 434.086 -106.010456) (xy 434.058629 -106.010001) (xy 434.004449 -106.002182)
			(xy 433.951946 -105.986691) (xy 433.902199 -105.963847) (xy 433.856233 -105.934119) (xy 433.835302 -105.916476)
			(xy 433.82819 -105.91038) (xy 433.811172 -105.90403) (xy 433.725828 -105.90403) (xy 433.70881 -105.91038)
			(xy 433.701698 -105.916476) (xy 433.680774 -105.934126) (xy 433.6348 -105.963837) (xy 433.58505 -105.986671)
			(xy 433.532547 -106.00216) (xy 433.47837 -106.009984) (xy 433.451 -106.010456) (xy 433.423751 -106.009922)
			(xy 433.369807 -106.002167) (xy 433.317516 -105.986814) (xy 433.267942 -105.964177) (xy 433.222094 -105.934715)
			(xy 433.180905 -105.899029) (xy 433.145214 -105.857844) (xy 433.115746 -105.812) (xy 433.093102 -105.762429)
			(xy 433.077743 -105.71014) (xy 433.069981 -105.656197) (xy 433.069492 -105.628948) (xy 430.614291 -105.628948)
			(xy 430.621839 -105.640356) (xy 430.645511 -105.690853) (xy 430.661579 -105.74426) (xy 430.669699 -105.799436)
			(xy 430.670208 -105.827322) (xy 430.669699 -105.855208) (xy 430.661579 -105.910384) (xy 430.645511 -105.963791)
			(xy 430.621839 -106.014288) (xy 430.591066 -106.060801) (xy 430.553849 -106.102338) (xy 430.510981 -106.138013)
			(xy 430.463375 -106.167067) (xy 430.412046 -106.188879) (xy 430.358089 -106.202985) (xy 430.302652 -106.209085)
			(xy 430.246918 -106.207048) (xy 430.192075 -106.196918) (xy 430.139291 -106.178911) (xy 430.089691 -106.15341)
			(xy 430.044333 -106.120959) (xy 430.004184 -106.08225) (xy 429.970098 -106.038107) (xy 429.942802 -105.989472)
			(xy 429.922879 -105.937381) (xy 429.910753 -105.882944) (xy 429.906682 -105.827322) (xy 413.999172 -105.827322)
			(xy 413.999172 -107.15117) (xy 428.930814 -107.15117) (xy 428.934885 -107.095548) (xy 428.947011 -107.041111)
			(xy 428.966934 -106.98902) (xy 428.99423 -106.940385) (xy 429.028316 -106.896242) (xy 429.068465 -106.857533)
			(xy 429.113823 -106.825082) (xy 429.163423 -106.799581) (xy 429.216207 -106.781574) (xy 429.27105 -106.771444)
			(xy 429.326784 -106.769407) (xy 429.368344 -106.77398) (xy 433.340254 -106.77398) (xy 433.344325 -106.718358)
			(xy 433.356451 -106.663921) (xy 433.376374 -106.61183) (xy 433.40367 -106.563195) (xy 433.437756 -106.519052)
			(xy 433.477905 -106.480343) (xy 433.523263 -106.447892) (xy 433.572863 -106.422391) (xy 433.625647 -106.404384)
			(xy 433.68049 -106.394254) (xy 433.736224 -106.392217) (xy 433.791661 -106.398317) (xy 433.845618 -106.412423)
			(xy 433.896947 -106.434235) (xy 433.944553 -106.463289) (xy 433.987421 -106.498964) (xy 434.024638 -106.540501)
			(xy 434.055411 -106.587014) (xy 434.079083 -106.637511) (xy 434.095151 -106.690918) (xy 434.103271 -106.746094)
			(xy 434.10378 -106.77398) (xy 434.103271 -106.801866) (xy 434.095151 -106.857042) (xy 434.079083 -106.910449)
			(xy 434.055411 -106.960946) (xy 434.024638 -107.007459) (xy 433.987421 -107.048996) (xy 433.944553 -107.084671)
			(xy 433.896947 -107.113725) (xy 433.845618 -107.135537) (xy 433.791661 -107.149643) (xy 433.736224 -107.155743)
			(xy 433.68049 -107.153706) (xy 433.625647 -107.143576) (xy 433.572863 -107.125569) (xy 433.523263 -107.100068)
			(xy 433.477905 -107.067617) (xy 433.437756 -107.028908) (xy 433.40367 -106.984765) (xy 433.376374 -106.93613)
			(xy 433.356451 -106.884039) (xy 433.344325 -106.829602) (xy 433.340254 -106.77398) (xy 429.368344 -106.77398)
			(xy 429.382221 -106.775507) (xy 429.436178 -106.789613) (xy 429.487507 -106.811425) (xy 429.535113 -106.840479)
			(xy 429.577981 -106.876154) (xy 429.615198 -106.917691) (xy 429.645971 -106.964204) (xy 429.669643 -107.014701)
			(xy 429.685711 -107.068108) (xy 429.693831 -107.123284) (xy 429.69434 -107.15117) (xy 429.693831 -107.179056)
			(xy 429.685711 -107.234232) (xy 429.677688 -107.260898) (xy 430.263552 -107.260898) (xy 430.267623 -107.205276)
			(xy 430.279749 -107.150839) (xy 430.299672 -107.098748) (xy 430.326968 -107.050113) (xy 430.361054 -107.00597)
			(xy 430.401203 -106.967261) (xy 430.446561 -106.93481) (xy 430.496161 -106.909309) (xy 430.548945 -106.891302)
			(xy 430.603788 -106.881172) (xy 430.659522 -106.879135) (xy 430.714959 -106.885235) (xy 430.768916 -106.899341)
			(xy 430.820245 -106.921153) (xy 430.867851 -106.950207) (xy 430.910719 -106.985882) (xy 430.947936 -107.027419)
			(xy 430.978709 -107.073932) (xy 431.002381 -107.124429) (xy 431.018449 -107.177836) (xy 431.026569 -107.233012)
			(xy 431.027078 -107.260898) (xy 431.026569 -107.288784) (xy 431.018449 -107.34396) (xy 431.002381 -107.397367)
			(xy 430.978709 -107.447864) (xy 430.947936 -107.494377) (xy 430.910719 -107.535914) (xy 430.867851 -107.571589)
			(xy 430.820245 -107.600643) (xy 430.768916 -107.622455) (xy 430.714959 -107.636561) (xy 430.659522 -107.642661)
			(xy 430.603788 -107.640624) (xy 430.548945 -107.630494) (xy 430.496161 -107.612487) (xy 430.446561 -107.586986)
			(xy 430.401203 -107.554535) (xy 430.361054 -107.515826) (xy 430.326968 -107.471683) (xy 430.299672 -107.423048)
			(xy 430.279749 -107.370957) (xy 430.267623 -107.31652) (xy 430.263552 -107.260898) (xy 429.677688 -107.260898)
			(xy 429.669643 -107.287639) (xy 429.645971 -107.338136) (xy 429.615198 -107.384649) (xy 429.577981 -107.426186)
			(xy 429.535113 -107.461861) (xy 429.487507 -107.490915) (xy 429.436178 -107.512727) (xy 429.382221 -107.526833)
			(xy 429.326784 -107.532933) (xy 429.27105 -107.530896) (xy 429.216207 -107.520766) (xy 429.163423 -107.502759)
			(xy 429.113823 -107.477258) (xy 429.068465 -107.444807) (xy 429.028316 -107.406098) (xy 428.99423 -107.361955)
			(xy 428.966934 -107.31332) (xy 428.947011 -107.261229) (xy 428.934885 -107.206792) (xy 428.930814 -107.15117)
			(xy 413.999172 -107.15117) (xy 413.999172 -107.645708) (xy 431.703478 -107.645708) (xy 431.707549 -107.590086)
			(xy 431.719675 -107.535649) (xy 431.739598 -107.483558) (xy 431.766894 -107.434923) (xy 431.80098 -107.39078)
			(xy 431.841129 -107.352071) (xy 431.886487 -107.31962) (xy 431.936087 -107.294119) (xy 431.988871 -107.276112)
			(xy 432.043714 -107.265982) (xy 432.099448 -107.263945) (xy 432.154885 -107.270045) (xy 432.208842 -107.284151)
			(xy 432.260171 -107.305963) (xy 432.307777 -107.335017) (xy 432.350645 -107.370692) (xy 432.387862 -107.412229)
			(xy 432.418635 -107.458742) (xy 432.442307 -107.509239) (xy 432.458375 -107.562646) (xy 432.466495 -107.617822)
			(xy 432.467004 -107.645708) (xy 432.466495 -107.673594) (xy 432.458375 -107.72877) (xy 432.442307 -107.782177)
			(xy 432.418635 -107.832674) (xy 432.387862 -107.879187) (xy 432.350645 -107.920724) (xy 432.307777 -107.956399)
			(xy 432.260171 -107.985453) (xy 432.208842 -108.007265) (xy 432.154885 -108.021371) (xy 432.099448 -108.027471)
			(xy 432.043714 -108.025434) (xy 431.988871 -108.015304) (xy 431.936087 -107.997297) (xy 431.886487 -107.971796)
			(xy 431.841129 -107.939345) (xy 431.80098 -107.900636) (xy 431.766894 -107.856493) (xy 431.739598 -107.807858)
			(xy 431.719675 -107.755767) (xy 431.707549 -107.70133) (xy 431.703478 -107.645708) (xy 413.999172 -107.645708)
			(xy 413.999172 -109.66323) (xy 433.334158 -109.66323) (xy 433.338229 -109.607608) (xy 433.350355 -109.553171)
			(xy 433.370278 -109.50108) (xy 433.397574 -109.452445) (xy 433.43166 -109.408302) (xy 433.471809 -109.369593)
			(xy 433.517167 -109.337142) (xy 433.566767 -109.311641) (xy 433.619551 -109.293634) (xy 433.674394 -109.283504)
			(xy 433.730128 -109.281467) (xy 433.785565 -109.287567) (xy 433.839522 -109.301673) (xy 433.890851 -109.323485)
			(xy 433.938457 -109.352539) (xy 433.981325 -109.388214) (xy 434.018542 -109.429751) (xy 434.049315 -109.476264)
			(xy 434.072987 -109.526761) (xy 434.089055 -109.580168) (xy 434.097175 -109.635344) (xy 434.097684 -109.66323)
			(xy 434.097175 -109.691116) (xy 434.089055 -109.746292) (xy 434.072987 -109.799699) (xy 434.049315 -109.850196)
			(xy 434.018542 -109.896709) (xy 433.981325 -109.938246) (xy 433.938457 -109.973921) (xy 433.890851 -110.002975)
			(xy 433.839522 -110.024787) (xy 433.785565 -110.038893) (xy 433.730128 -110.044993) (xy 433.674394 -110.042956)
			(xy 433.619551 -110.032826) (xy 433.566767 -110.014819) (xy 433.517167 -109.989318) (xy 433.471809 -109.956867)
			(xy 433.43166 -109.918158) (xy 433.397574 -109.874015) (xy 433.370278 -109.82538) (xy 433.350355 -109.773289)
			(xy 433.338229 -109.718852) (xy 433.334158 -109.66323) (xy 413.999172 -109.66323) (xy 413.999172 -110.4265)
			(xy 418.726872 -110.4265) (xy 418.730943 -110.370878) (xy 418.743069 -110.316441) (xy 418.762992 -110.26435)
			(xy 418.790288 -110.215715) (xy 418.824374 -110.171572) (xy 418.864523 -110.132863) (xy 418.909881 -110.100412)
			(xy 418.959481 -110.074911) (xy 419.012265 -110.056904) (xy 419.067108 -110.046774) (xy 419.122842 -110.044737)
			(xy 419.178279 -110.050837) (xy 419.232236 -110.064943) (xy 419.283565 -110.086755) (xy 419.331171 -110.115809)
			(xy 419.374039 -110.151484) (xy 419.411256 -110.193021) (xy 419.442029 -110.239534) (xy 419.461448 -110.280958)
			(xy 419.761922 -110.280958) (xy 419.765993 -110.225336) (xy 419.778119 -110.170899) (xy 419.798042 -110.118808)
			(xy 419.825338 -110.070173) (xy 419.859424 -110.02603) (xy 419.899573 -109.987321) (xy 419.944931 -109.95487)
			(xy 419.994531 -109.929369) (xy 420.047315 -109.911362) (xy 420.102158 -109.901232) (xy 420.157892 -109.899195)
			(xy 420.213329 -109.905295) (xy 420.267286 -109.919401) (xy 420.318615 -109.941213) (xy 420.366221 -109.970267)
			(xy 420.409089 -110.005942) (xy 420.446306 -110.047479) (xy 420.477079 -110.093992) (xy 420.500751 -110.144489)
			(xy 420.516819 -110.197896) (xy 420.524939 -110.253072) (xy 420.525448 -110.280958) (xy 420.524939 -110.308844)
			(xy 420.516819 -110.36402) (xy 420.516667 -110.364524) (xy 420.634412 -110.364524) (xy 420.638483 -110.308902)
			(xy 420.650609 -110.254465) (xy 420.670532 -110.202374) (xy 420.697828 -110.153739) (xy 420.731914 -110.109596)
			(xy 420.772063 -110.070887) (xy 420.817421 -110.038436) (xy 420.867021 -110.012935) (xy 420.919805 -109.994928)
			(xy 420.974648 -109.984798) (xy 421.030382 -109.982761) (xy 421.085819 -109.988861) (xy 421.139776 -110.002967)
			(xy 421.191105 -110.024779) (xy 421.238711 -110.053833) (xy 421.281579 -110.089508) (xy 421.318796 -110.131045)
			(xy 421.349569 -110.177558) (xy 421.373241 -110.228055) (xy 421.387858 -110.27664) (xy 428.913542 -110.27664)
			(xy 428.917613 -110.221018) (xy 428.929739 -110.166581) (xy 428.949662 -110.11449) (xy 428.976958 -110.065855)
			(xy 429.011044 -110.021712) (xy 429.051193 -109.983003) (xy 429.096551 -109.950552) (xy 429.146151 -109.925051)
			(xy 429.198935 -109.907044) (xy 429.253778 -109.896914) (xy 429.309512 -109.894877) (xy 429.364949 -109.900977)
			(xy 429.418906 -109.915083) (xy 429.470235 -109.936895) (xy 429.517841 -109.965949) (xy 429.560709 -110.001624)
			(xy 429.597926 -110.043161) (xy 429.628699 -110.089674) (xy 429.652371 -110.140171) (xy 429.668439 -110.193578)
			(xy 429.676559 -110.248754) (xy 429.677068 -110.27664) (xy 429.676559 -110.304526) (xy 429.668439 -110.359702)
			(xy 429.652371 -110.413109) (xy 429.628699 -110.463606) (xy 429.597926 -110.510119) (xy 429.560709 -110.551656)
			(xy 429.517841 -110.587331) (xy 429.470235 -110.616385) (xy 429.418906 -110.638197) (xy 429.364949 -110.652303)
			(xy 429.309512 -110.658403) (xy 429.253778 -110.656366) (xy 429.198935 -110.646236) (xy 429.146151 -110.628229)
			(xy 429.096551 -110.602728) (xy 429.051193 -110.570277) (xy 429.011044 -110.531568) (xy 428.976958 -110.487425)
			(xy 428.949662 -110.43879) (xy 428.929739 -110.386699) (xy 428.917613 -110.332262) (xy 428.913542 -110.27664)
			(xy 421.387858 -110.27664) (xy 421.389309 -110.281462) (xy 421.397429 -110.336638) (xy 421.397938 -110.364524)
			(xy 421.397429 -110.39241) (xy 421.389309 -110.447586) (xy 421.373241 -110.500993) (xy 421.349569 -110.55149)
			(xy 421.318796 -110.598003) (xy 421.281579 -110.63954) (xy 421.238711 -110.675215) (xy 421.191105 -110.704269)
			(xy 421.139776 -110.726081) (xy 421.085819 -110.740187) (xy 421.030382 -110.746287) (xy 420.974648 -110.74425)
			(xy 420.919805 -110.73412) (xy 420.867021 -110.716113) (xy 420.817421 -110.690612) (xy 420.772063 -110.658161)
			(xy 420.731914 -110.619452) (xy 420.697828 -110.575309) (xy 420.670532 -110.526674) (xy 420.650609 -110.474583)
			(xy 420.638483 -110.420146) (xy 420.634412 -110.364524) (xy 420.516667 -110.364524) (xy 420.500751 -110.417427)
			(xy 420.477079 -110.467924) (xy 420.446306 -110.514437) (xy 420.409089 -110.555974) (xy 420.366221 -110.591649)
			(xy 420.318615 -110.620703) (xy 420.267286 -110.642515) (xy 420.213329 -110.656621) (xy 420.157892 -110.662721)
			(xy 420.102158 -110.660684) (xy 420.047315 -110.650554) (xy 419.994531 -110.632547) (xy 419.944931 -110.607046)
			(xy 419.899573 -110.574595) (xy 419.859424 -110.535886) (xy 419.825338 -110.491743) (xy 419.798042 -110.443108)
			(xy 419.778119 -110.391017) (xy 419.765993 -110.33658) (xy 419.761922 -110.280958) (xy 419.461448 -110.280958)
			(xy 419.465701 -110.290031) (xy 419.481769 -110.343438) (xy 419.489889 -110.398614) (xy 419.490398 -110.4265)
			(xy 419.489889 -110.454386) (xy 419.481769 -110.509562) (xy 419.465701 -110.562969) (xy 419.442029 -110.613466)
			(xy 419.411256 -110.659979) (xy 419.374039 -110.701516) (xy 419.331171 -110.737191) (xy 419.283565 -110.766245)
			(xy 419.232236 -110.788057) (xy 419.178279 -110.802163) (xy 419.122842 -110.808263) (xy 419.067108 -110.806226)
			(xy 419.012265 -110.796096) (xy 418.959481 -110.778089) (xy 418.909881 -110.752588) (xy 418.864523 -110.720137)
			(xy 418.824374 -110.681428) (xy 418.790288 -110.637285) (xy 418.762992 -110.58865) (xy 418.743069 -110.536559)
			(xy 418.730943 -110.482122) (xy 418.726872 -110.4265) (xy 413.999172 -110.4265) (xy 413.999172 -110.940088)
			(xy 429.500282 -110.940088) (xy 429.504353 -110.884466) (xy 429.516479 -110.830029) (xy 429.536402 -110.777938)
			(xy 429.563698 -110.729303) (xy 429.597784 -110.68516) (xy 429.637933 -110.646451) (xy 429.683291 -110.614)
			(xy 429.732891 -110.588499) (xy 429.785675 -110.570492) (xy 429.840518 -110.560362) (xy 429.896252 -110.558325)
			(xy 429.951689 -110.564425) (xy 430.005646 -110.578531) (xy 430.056975 -110.600343) (xy 430.104581 -110.629397)
			(xy 430.147449 -110.665072) (xy 430.184666 -110.706609) (xy 430.215439 -110.753122) (xy 430.239111 -110.803619)
			(xy 430.255179 -110.857026) (xy 430.263299 -110.912202) (xy 430.263808 -110.940088) (xy 430.263299 -110.967974)
			(xy 430.255179 -111.02315) (xy 430.239111 -111.076557) (xy 430.215439 -111.127054) (xy 430.184666 -111.173567)
			(xy 430.147449 -111.215104) (xy 430.104581 -111.250779) (xy 430.056975 -111.279833) (xy 430.005646 -111.301645)
			(xy 429.951689 -111.315751) (xy 429.896252 -111.321851) (xy 429.840518 -111.319814) (xy 429.785675 -111.309684)
			(xy 429.732891 -111.291677) (xy 429.683291 -111.266176) (xy 429.637933 -111.233725) (xy 429.597784 -111.195016)
			(xy 429.563698 -111.150873) (xy 429.536402 -111.102238) (xy 429.516479 -111.050147) (xy 429.504353 -110.99571)
			(xy 429.500282 -110.940088) (xy 413.999172 -110.940088) (xy 413.999172 -111.131096) (xy 413.999627 -111.140975)
			(xy 414.007062 -111.159282) (xy 414.01365 -111.166656) (xy 414.013904 -111.16691) (xy 415.490406 -112.643412)
			(xy 415.490914 -112.64392) (xy 415.498292 -112.650512) (xy 415.516591 -112.657981) (xy 415.526474 -112.658398)
		)
		(stroke
			(width 0)
			(type solid)
		)
		(fill yes)
		(layer "In2.Cu")
		(net "GND")
	)
	(gr_poly
		(pts
			(xy 79.761334 -392.588242) (xy 79.7714 -392.587811) (xy 79.78999 -392.580082) (xy 79.797402 -392.573256)
			(xy 79.956406 -392.414252) (xy 79.963772 -392.398758) (xy 79.964534 -392.389868) (xy 79.967901 -392.362387)
			(xy 79.981543 -392.30873) (xy 80.002786 -392.257603) (xy 80.031184 -392.210077) (xy 80.066144 -392.167147)
			(xy 80.0862 -392.14806) (xy 80.093312 -392.14171) (xy 80.10144 -392.124946) (xy 80.109822 -392.038332)
			(xy 80.104742 -392.020552) (xy 80.099154 -392.012678) (xy 80.084997 -391.992833) (xy 80.06251 -391.949585)
			(xy 80.047192 -391.90331) (xy 80.039433 -391.855186) (xy 80.038956 -391.830814) (xy 80.039478 -391.805559)
			(xy 80.047791 -391.755737) (xy 80.064192 -391.707963) (xy 80.088233 -391.66354) (xy 80.119257 -391.62368)
			(xy 80.156419 -391.58947) (xy 80.198705 -391.561844) (xy 80.244961 -391.541554) (xy 80.293926 -391.529154)
			(xy 80.344264 -391.524983) (xy 80.394602 -391.529154) (xy 80.443567 -391.541554) (xy 80.489823 -391.561844)
			(xy 80.532109 -391.58947) (xy 80.569271 -391.62368) (xy 80.600295 -391.66354) (xy 80.624336 -391.707963)
			(xy 80.640737 -391.755737) (xy 80.64905 -391.805559) (xy 80.649572 -391.830814) (xy 80.649074 -391.855184)
			(xy 80.641295 -391.9033) (xy 80.625983 -391.949574) (xy 80.603527 -391.992833) (xy 80.589374 -392.012678)
			(xy 80.583786 -392.020552) (xy 80.578706 -392.038332) (xy 80.587088 -392.124946) (xy 80.595216 -392.14171)
			(xy 80.602328 -392.14806) (xy 80.624305 -392.169064) (xy 80.661956 -392.216789) (xy 80.677258 -392.243056)
			(xy 80.681999 -392.250742) (xy 80.695746 -392.262436) (xy 80.712684 -392.268665) (xy 80.721708 -392.268964)
			(xy 81.166716 -392.268964) (xy 81.175742 -392.268648) (xy 81.192696 -392.262457) (xy 81.206432 -392.250748)
			(xy 81.211166 -392.243056) (xy 81.226488 -392.216801) (xy 81.264129 -392.169072) (xy 81.286096 -392.14806)
			(xy 81.293208 -392.141456) (xy 81.30159 -392.124946) (xy 81.309718 -392.038078) (xy 81.304892 -392.020298)
			(xy 81.29905 -392.012678) (xy 81.284945 -391.992813) (xy 81.262553 -391.949546) (xy 81.247307 -391.903276)
			(xy 81.239593 -391.855173) (xy 81.239106 -391.830814) (xy 81.239628 -391.805559) (xy 81.247941 -391.755737)
			(xy 81.264342 -391.707963) (xy 81.288383 -391.66354) (xy 81.319407 -391.62368) (xy 81.356569 -391.58947)
			(xy 81.398855 -391.561844) (xy 81.445111 -391.541554) (xy 81.494076 -391.529154) (xy 81.544414 -391.524983)
			(xy 81.594752 -391.529154) (xy 81.643717 -391.541554) (xy 81.689973 -391.561844) (xy 81.732259 -391.58947)
			(xy 81.769421 -391.62368) (xy 81.800445 -391.66354) (xy 81.824486 -391.707963) (xy 81.840887 -391.755737)
			(xy 81.8492 -391.805559) (xy 81.849722 -391.830814) (xy 81.849244 -391.855216) (xy 81.841486 -391.903399)
			(xy 81.826169 -391.949737) (xy 81.803683 -391.993052) (xy 81.789524 -392.012932) (xy 81.783936 -392.020552)
			(xy 81.778856 -392.038332) (xy 81.786984 -392.1252) (xy 81.795366 -392.14171) (xy 81.802478 -392.148314)
			(xy 81.824374 -392.169271) (xy 81.861899 -392.216866) (xy 81.877154 -392.243056) (xy 81.881895 -392.250742)
			(xy 81.895641 -392.262438) (xy 81.91258 -392.268667) (xy 81.921604 -392.268964) (xy 82.366866 -392.268964)
			(xy 82.375897 -392.268656) (xy 82.392864 -392.262476) (xy 82.406614 -392.250771) (xy 82.411316 -392.243056)
			(xy 82.42664 -392.216803) (xy 82.464284 -392.169077) (xy 82.486246 -392.14806) (xy 82.493358 -392.14171)
			(xy 82.501486 -392.124946) (xy 82.509868 -392.038332) (xy 82.504788 -392.020552) (xy 82.4992 -392.012678)
			(xy 82.485041 -391.992834) (xy 82.462551 -391.949587) (xy 82.44723 -391.903311) (xy 82.43947 -391.855187)
			(xy 82.439002 -391.830814) (xy 82.439524 -391.805559) (xy 82.447837 -391.755737) (xy 82.464238 -391.707963)
			(xy 82.488279 -391.66354) (xy 82.519303 -391.62368) (xy 82.556465 -391.58947) (xy 82.598751 -391.561844)
			(xy 82.645007 -391.541554) (xy 82.693972 -391.529154) (xy 82.74431 -391.524983) (xy 82.794648 -391.529154)
			(xy 82.843613 -391.541554) (xy 82.889869 -391.561844) (xy 82.932155 -391.58947) (xy 82.969317 -391.62368)
			(xy 83.000341 -391.66354) (xy 83.024382 -391.707963) (xy 83.040783 -391.755737) (xy 83.049096 -391.805559)
			(xy 83.049618 -391.830814) (xy 83.04912 -391.855184) (xy 83.041339 -391.903299) (xy 83.026026 -391.949571)
			(xy 83.003567 -391.992829) (xy 82.98942 -392.012678) (xy 82.983832 -392.020552) (xy 82.978752 -392.038332)
			(xy 82.987134 -392.124946) (xy 82.995262 -392.14171) (xy 83.002374 -392.14806) (xy 83.024349 -392.169065)
			(xy 83.061995 -392.216792) (xy 83.077304 -392.243056) (xy 83.082048 -392.250737) (xy 83.095796 -392.262418)
			(xy 83.112733 -392.268632) (xy 83.121754 -392.268964) (xy 83.566762 -392.268964) (xy 83.575793 -392.268657)
			(xy 83.592761 -392.262477) (xy 83.606512 -392.250773) (xy 83.611212 -392.243056) (xy 83.626536 -392.216803)
			(xy 83.66418 -392.169077) (xy 83.686142 -392.14806) (xy 83.693254 -392.14171) (xy 83.701382 -392.124946)
			(xy 83.709764 -392.038332) (xy 83.704684 -392.020552) (xy 83.699096 -392.012678) (xy 83.684937 -391.992834)
			(xy 83.662447 -391.949586) (xy 83.647127 -391.903311) (xy 83.639367 -391.855187) (xy 83.638898 -391.830814)
			(xy 83.63942 -391.805559) (xy 83.647733 -391.755737) (xy 83.664134 -391.707963) (xy 83.688175 -391.66354)
			(xy 83.719199 -391.62368) (xy 83.756361 -391.58947) (xy 83.798647 -391.561844) (xy 83.844903 -391.541554)
			(xy 83.893868 -391.529154) (xy 83.944206 -391.524983) (xy 83.994544 -391.529154) (xy 84.043509 -391.541554)
			(xy 84.089765 -391.561844) (xy 84.132051 -391.58947) (xy 84.169213 -391.62368) (xy 84.200237 -391.66354)
			(xy 84.224278 -391.707963) (xy 84.240679 -391.755737) (xy 84.248992 -391.805559) (xy 84.249514 -391.830814)
			(xy 84.249015 -391.855184) (xy 84.241235 -391.903299) (xy 84.225921 -391.949571) (xy 84.203462 -391.992828)
			(xy 84.189316 -392.012678) (xy 84.183728 -392.020552) (xy 84.178648 -392.038332) (xy 84.18703 -392.124946)
			(xy 84.195158 -392.14171) (xy 84.20227 -392.14806) (xy 84.224245 -392.169065) (xy 84.261892 -392.216792)
			(xy 84.2772 -392.243056) (xy 84.281943 -392.250737) (xy 84.295692 -392.26242) (xy 84.312629 -392.268635)
			(xy 84.32165 -392.268964) (xy 84.766912 -392.268964) (xy 84.775939 -392.268649) (xy 84.792893 -392.262458)
			(xy 84.80663 -392.25075) (xy 84.811362 -392.243056) (xy 84.826684 -392.216801) (xy 84.864325 -392.169072)
			(xy 84.886292 -392.14806) (xy 84.893404 -392.14171) (xy 84.901532 -392.124946) (xy 84.909914 -392.038332)
			(xy 84.904834 -392.020552) (xy 84.899246 -392.012678) (xy 84.885089 -391.992833) (xy 84.862603 -391.949585)
			(xy 84.847285 -391.903309) (xy 84.839527 -391.855186) (xy 84.839048 -391.830814) (xy 84.83957 -391.805559)
			(xy 84.847883 -391.755737) (xy 84.864284 -391.707963) (xy 84.888325 -391.66354) (xy 84.919349 -391.62368)
			(xy 84.956511 -391.58947) (xy 84.998797 -391.561844) (xy 85.045053 -391.541554) (xy 85.094018 -391.529154)
			(xy 85.144356 -391.524983) (xy 85.194694 -391.529154) (xy 85.243659 -391.541554) (xy 85.289915 -391.561844)
			(xy 85.332201 -391.58947) (xy 85.369363 -391.62368) (xy 85.400387 -391.66354) (xy 85.424428 -391.707963)
			(xy 85.440829 -391.755737) (xy 85.449142 -391.805559) (xy 85.449664 -391.830814) (xy 85.449166 -391.855184)
			(xy 85.441386 -391.9033) (xy 85.426075 -391.949573) (xy 85.403618 -391.992833) (xy 85.389466 -392.012678)
			(xy 85.383878 -392.020552) (xy 85.378798 -392.038332) (xy 85.38718 -392.124946) (xy 85.395308 -392.14171)
			(xy 85.40242 -392.14806) (xy 85.424398 -392.169063) (xy 85.462049 -392.216788) (xy 85.47735 -392.243056)
			(xy 85.482091 -392.250743) (xy 85.495837 -392.262439) (xy 85.512776 -392.26867) (xy 85.5218 -392.268964)
			(xy 85.966808 -392.268964) (xy 85.975835 -392.268649) (xy 85.992791 -392.26246) (xy 86.006529 -392.250752)
			(xy 86.011258 -392.243056) (xy 86.02658 -392.216801) (xy 86.06422 -392.169072) (xy 86.086188 -392.14806)
			(xy 86.0933 -392.14171) (xy 86.101428 -392.124946) (xy 86.10981 -392.038332) (xy 86.10473 -392.020552)
			(xy 86.099142 -392.012678) (xy 86.084985 -391.992833) (xy 86.062499 -391.949585) (xy 86.047182 -391.903309)
			(xy 86.039423 -391.855186) (xy 86.038944 -391.830814) (xy 86.039466 -391.805559) (xy 86.047779 -391.755737)
			(xy 86.06418 -391.707963) (xy 86.088221 -391.66354) (xy 86.119245 -391.62368) (xy 86.156407 -391.58947)
			(xy 86.198693 -391.561844) (xy 86.244949 -391.541554) (xy 86.293914 -391.529154) (xy 86.344252 -391.524983)
			(xy 86.39459 -391.529154) (xy 86.443555 -391.541554) (xy 86.489811 -391.561844) (xy 86.532097 -391.58947)
			(xy 86.569259 -391.62368) (xy 86.600283 -391.66354) (xy 86.624324 -391.707963) (xy 86.640725 -391.755737)
			(xy 86.649038 -391.805559) (xy 86.64956 -391.830814) (xy 86.649062 -391.855184) (xy 86.641282 -391.9033)
			(xy 86.62597 -391.949573) (xy 86.603514 -391.992832) (xy 86.589362 -392.012678) (xy 86.583774 -392.020552)
			(xy 86.578694 -392.038332) (xy 86.587076 -392.124946) (xy 86.595204 -392.14171) (xy 86.602316 -392.14806)
			(xy 86.624294 -392.169063) (xy 86.661945 -392.216788) (xy 86.677246 -392.243056) (xy 86.681992 -392.250732)
			(xy 86.695742 -392.262402) (xy 86.712678 -392.268602) (xy 86.721696 -392.268964) (xy 87.166958 -392.268964)
			(xy 87.17599 -392.268657) (xy 87.192959 -392.262479) (xy 87.206711 -392.250775) (xy 87.211408 -392.243056)
			(xy 87.226732 -392.216803) (xy 87.264375 -392.169076) (xy 87.286338 -392.14806) (xy 87.29345 -392.14171)
			(xy 87.301578 -392.124946) (xy 87.30996 -392.038332) (xy 87.30488 -392.020552) (xy 87.299292 -392.012678)
			(xy 87.285133 -391.992834) (xy 87.262644 -391.949586) (xy 87.247324 -391.903311) (xy 87.239564 -391.855187)
			(xy 87.239094 -391.830814) (xy 87.239616 -391.805559) (xy 87.247929 -391.755737) (xy 87.26433 -391.707963)
			(xy 87.288371 -391.66354) (xy 87.319395 -391.62368) (xy 87.356557 -391.58947) (xy 87.398843 -391.561844)
			(xy 87.445099 -391.541554) (xy 87.494064 -391.529154) (xy 87.544402 -391.524983) (xy 87.59474 -391.529154)
			(xy 87.643705 -391.541554) (xy 87.689961 -391.561844) (xy 87.732247 -391.58947) (xy 87.769409 -391.62368)
			(xy 87.800433 -391.66354) (xy 87.824474 -391.707963) (xy 87.840875 -391.755737) (xy 87.849188 -391.805559)
			(xy 87.84971 -391.830814) (xy 87.849211 -391.855184) (xy 87.841431 -391.903299) (xy 87.826117 -391.949571)
			(xy 87.803658 -391.992828) (xy 87.789512 -392.012678) (xy 87.783924 -392.020552) (xy 87.778844 -392.038332)
			(xy 87.787226 -392.124946) (xy 87.795354 -392.14171) (xy 87.802466 -392.14806) (xy 87.824442 -392.169065)
			(xy 87.862088 -392.216792) (xy 87.877396 -392.243056) (xy 87.882139 -392.250738) (xy 87.895887 -392.262421)
			(xy 87.912825 -392.268638) (xy 87.921846 -392.268964) (xy 88.366854 -392.268964) (xy 88.375886 -392.268658)
			(xy 88.392856 -392.262481) (xy 88.406609 -392.250776) (xy 88.411304 -392.243056) (xy 88.426627 -392.216802)
			(xy 88.464271 -392.169076) (xy 88.486234 -392.14806) (xy 88.493346 -392.14171) (xy 88.501474 -392.124946)
			(xy 88.509856 -392.038332) (xy 88.504776 -392.020552) (xy 88.499188 -392.012678) (xy 88.485029 -391.992834)
			(xy 88.46254 -391.949586) (xy 88.44722 -391.903311) (xy 88.43946 -391.855187) (xy 88.43899 -391.830814)
			(xy 88.439512 -391.805559) (xy 88.447825 -391.755737) (xy 88.464226 -391.707963) (xy 88.488267 -391.66354)
			(xy 88.519291 -391.62368) (xy 88.556453 -391.58947) (xy 88.598739 -391.561844) (xy 88.644995 -391.541554)
			(xy 88.69396 -391.529154) (xy 88.744298 -391.524983) (xy 88.794636 -391.529154) (xy 88.843601 -391.541554)
			(xy 88.889857 -391.561844) (xy 88.932143 -391.58947) (xy 88.969305 -391.62368) (xy 89.000329 -391.66354)
			(xy 89.02437 -391.707963) (xy 89.040771 -391.755737) (xy 89.049084 -391.805559) (xy 89.049606 -391.830814)
			(xy 89.049107 -391.855184) (xy 89.041327 -391.903299) (xy 89.026013 -391.949571) (xy 89.003553 -391.992828)
			(xy 88.989408 -392.012678) (xy 88.98382 -392.020552) (xy 88.97874 -392.038332) (xy 88.987122 -392.124946)
			(xy 88.99525 -392.14171) (xy 89.002362 -392.14806) (xy 89.024338 -392.169065) (xy 89.061985 -392.216791)
			(xy 89.077292 -392.243056) (xy 89.082035 -392.250738) (xy 89.095783 -392.262423) (xy 89.11272 -392.26864)
			(xy 89.121742 -392.268964) (xy 89.567004 -392.268964) (xy 89.576031 -392.26865) (xy 89.592988 -392.262461)
			(xy 89.606727 -392.250754) (xy 89.611454 -392.243056) (xy 89.626727 -392.216877) (xy 89.664242 -392.169278)
			(xy 89.68613 -392.148314) (xy 89.693242 -392.14171) (xy 89.701624 -392.1252) (xy 89.709752 -392.038332)
			(xy 89.704672 -392.020552) (xy 89.699084 -392.012932) (xy 89.684921 -391.993054) (xy 89.662426 -391.949741)
			(xy 89.647104 -391.903402) (xy 89.639343 -391.855217) (xy 89.638886 -391.830814) (xy 89.639408 -391.805559)
			(xy 89.647721 -391.755737) (xy 89.664122 -391.707963) (xy 89.688163 -391.66354) (xy 89.719187 -391.62368)
			(xy 89.756349 -391.58947) (xy 89.798635 -391.561844) (xy 89.844891 -391.541554) (xy 89.893856 -391.529154)
			(xy 89.944194 -391.524983) (xy 89.994532 -391.529154) (xy 90.043497 -391.541554) (xy 90.089753 -391.561844)
			(xy 90.132039 -391.58947) (xy 90.169201 -391.62368) (xy 90.200225 -391.66354) (xy 90.224266 -391.707963)
			(xy 90.240667 -391.755737) (xy 90.24898 -391.805559) (xy 90.249502 -391.830814) (xy 90.249048 -391.855175)
			(xy 90.241345 -391.903285) (xy 90.226089 -391.949557) (xy 90.203669 -391.992814) (xy 90.189558 -392.012678)
			(xy 90.183716 -392.020298) (xy 90.17889 -392.038078) (xy 90.187018 -392.124946) (xy 90.1954 -392.141456)
			(xy 90.202512 -392.14806) (xy 90.22449 -392.169063) (xy 90.262142 -392.216787) (xy 90.277442 -392.243056)
			(xy 90.282188 -392.250732) (xy 90.295938 -392.262404) (xy 90.312874 -392.268605) (xy 90.321892 -392.268964)
			(xy 90.7669 -392.268964) (xy 90.775928 -392.268651) (xy 90.792886 -392.262463) (xy 90.806626 -392.250756)
			(xy 90.81135 -392.243056) (xy 90.826672 -392.216801) (xy 90.864312 -392.169071) (xy 90.88628 -392.14806)
			(xy 90.893392 -392.14171) (xy 90.90152 -392.124946) (xy 90.909902 -392.038332) (xy 90.904822 -392.020552)
			(xy 90.899234 -392.012678) (xy 90.885078 -391.992833) (xy 90.862592 -391.949584) (xy 90.847275 -391.903309)
			(xy 90.839517 -391.855186) (xy 90.839036 -391.830814) (xy 90.839558 -391.805559) (xy 90.847871 -391.755737)
			(xy 90.864272 -391.707963) (xy 90.888313 -391.66354) (xy 90.919337 -391.62368) (xy 90.956499 -391.58947)
			(xy 90.998785 -391.561844) (xy 91.045041 -391.541554) (xy 91.094006 -391.529154) (xy 91.144344 -391.524983)
			(xy 91.194682 -391.529154) (xy 91.243647 -391.541554) (xy 91.289903 -391.561844) (xy 91.332189 -391.58947)
			(xy 91.369351 -391.62368) (xy 91.400375 -391.66354) (xy 91.424416 -391.707963) (xy 91.440817 -391.755737)
			(xy 91.44913 -391.805559) (xy 91.449652 -391.830814) (xy 91.449154 -391.855184) (xy 91.441374 -391.9033)
			(xy 91.426062 -391.949573) (xy 91.403605 -391.992832) (xy 91.389454 -392.012678) (xy 91.383866 -392.020552)
			(xy 91.378786 -392.038332) (xy 91.387168 -392.124946) (xy 91.395296 -392.14171) (xy 91.402408 -392.14806)
			(xy 91.424386 -392.169063) (xy 91.462038 -392.216787) (xy 91.477338 -392.243056) (xy 91.482083 -392.250733)
			(xy 91.495833 -392.262406) (xy 91.512769 -392.268608) (xy 91.521788 -392.268964) (xy 91.96705 -392.268964)
			(xy 91.976082 -392.268659) (xy 91.993053 -392.262482) (xy 92.006808 -392.250778) (xy 92.0115 -392.243056)
			(xy 92.026771 -392.216875) (xy 92.064282 -392.169273) (xy 92.086176 -392.148314) (xy 92.093288 -392.14171)
			(xy 92.10167 -392.1252) (xy 92.109798 -392.038332) (xy 92.104718 -392.020552) (xy 92.09913 -392.012932)
			(xy 92.084969 -391.993053) (xy 92.062479 -391.949739) (xy 92.047159 -391.903401) (xy 92.039399 -391.855216)
			(xy 92.038932 -391.830814) (xy 92.039454 -391.805559) (xy 92.047767 -391.755737) (xy 92.064168 -391.707963)
			(xy 92.088209 -391.66354) (xy 92.119233 -391.62368) (xy 92.156395 -391.58947) (xy 92.198681 -391.561844)
			(xy 92.244937 -391.541554) (xy 92.293902 -391.529154) (xy 92.34424 -391.524983) (xy 92.394578 -391.529154)
			(xy 92.443543 -391.541554) (xy 92.489799 -391.561844) (xy 92.532085 -391.58947) (xy 92.569247 -391.62368)
			(xy 92.600271 -391.66354) (xy 92.624312 -391.707963) (xy 92.640713 -391.755737) (xy 92.649026 -391.805559)
			(xy 92.649548 -391.830814) (xy 92.649094 -391.855175) (xy 92.641389 -391.903284) (xy 92.626131 -391.949554)
			(xy 92.603708 -391.992809) (xy 92.589604 -392.012678) (xy 92.583762 -392.020298) (xy 92.578936 -392.038078)
			(xy 92.587064 -392.124946) (xy 92.595446 -392.141456) (xy 92.602558 -392.14806) (xy 92.624534 -392.169065)
			(xy 92.662182 -392.216791) (xy 92.677488 -392.243056) (xy 92.682231 -392.250739) (xy 92.695979 -392.262424)
			(xy 92.712916 -392.268643) (xy 92.721938 -392.268964) (xy 93.166946 -392.268964) (xy 93.175979 -392.268659)
			(xy 93.192951 -392.262484) (xy 93.206706 -392.25078) (xy 93.211396 -392.243056) (xy 93.226719 -392.216802)
			(xy 93.264362 -392.169075) (xy 93.286326 -392.14806) (xy 93.293438 -392.14171) (xy 93.301566 -392.124946)
			(xy 93.309948 -392.038332) (xy 93.304868 -392.020552) (xy 93.29928 -392.012678) (xy 93.285122 -391.992834)
			(xy 93.262633 -391.949586) (xy 93.247314 -391.90331) (xy 93.239554 -391.855187) (xy 93.239082 -391.830814)
			(xy 93.239604 -391.805559) (xy 93.247917 -391.755737) (xy 93.264318 -391.707963) (xy 93.288359 -391.66354)
			(xy 93.319383 -391.62368) (xy 93.356545 -391.58947) (xy 93.398831 -391.561844) (xy 93.445087 -391.541554)
			(xy 93.494052 -391.529154) (xy 93.54439 -391.524983) (xy 93.594728 -391.529154) (xy 93.643693 -391.541554)
			(xy 93.689949 -391.561844) (xy 93.732235 -391.58947) (xy 93.769397 -391.62368) (xy 93.800421 -391.66354)
			(xy 93.824462 -391.707963) (xy 93.840863 -391.755737) (xy 93.849176 -391.805559) (xy 93.849698 -391.830814)
			(xy 93.849199 -391.855184) (xy 93.841419 -391.903299) (xy 93.826104 -391.94957) (xy 93.803644 -391.992827)
			(xy 93.7895 -392.012678) (xy 93.783912 -392.020552) (xy 93.778832 -392.038332) (xy 93.787214 -392.124946)
			(xy 93.795342 -392.14171) (xy 93.802454 -392.14806) (xy 93.82443 -392.169065) (xy 93.862078 -392.216791)
			(xy 93.877384 -392.243056) (xy 93.882127 -392.250739) (xy 93.895874 -392.262426) (xy 93.912812 -392.268646)
			(xy 93.921834 -392.268964) (xy 94.366842 -392.268964) (xy 94.375875 -392.26866) (xy 94.392848 -392.262485)
			(xy 94.406605 -392.250782) (xy 94.411292 -392.243056) (xy 94.426615 -392.216802) (xy 94.464258 -392.169075)
			(xy 94.486222 -392.14806) (xy 94.493334 -392.14171) (xy 94.501462 -392.124946) (xy 94.509844 -392.038332)
			(xy 94.504764 -392.020552) (xy 94.499176 -392.012678) (xy 94.485018 -391.992834) (xy 94.46253 -391.949586)
			(xy 94.44721 -391.90331) (xy 94.439451 -391.855187) (xy 94.438978 -391.830814) (xy 94.4395 -391.805559)
			(xy 94.447813 -391.755737) (xy 94.464214 -391.707963) (xy 94.488255 -391.66354) (xy 94.519279 -391.62368)
			(xy 94.556441 -391.58947) (xy 94.598727 -391.561844) (xy 94.644983 -391.541554) (xy 94.693948 -391.529154)
			(xy 94.744286 -391.524983) (xy 94.794624 -391.529154) (xy 94.843589 -391.541554) (xy 94.889845 -391.561844)
			(xy 94.932131 -391.58947) (xy 94.969293 -391.62368) (xy 95.000317 -391.66354) (xy 95.024358 -391.707963)
			(xy 95.040759 -391.755737) (xy 95.049072 -391.805559) (xy 95.049594 -391.830814) (xy 95.049095 -391.855184)
			(xy 95.041315 -391.903299) (xy 95.026 -391.94957) (xy 95.00354 -391.992827) (xy 94.989396 -392.012678)
			(xy 94.983808 -392.020552) (xy 94.978728 -392.038332) (xy 94.98711 -392.124946) (xy 94.995238 -392.14171)
			(xy 95.00235 -392.14806) (xy 95.024326 -392.169064) (xy 95.061975 -392.21679) (xy 95.07728 -392.243056)
			(xy 95.082023 -392.250739) (xy 95.09577 -392.262427) (xy 95.112708 -392.268649) (xy 95.12173 -392.268964)
			(xy 95.566738 -392.268964) (xy 95.575771 -392.268661) (xy 95.592746 -392.262487) (xy 95.606504 -392.250784)
			(xy 95.611188 -392.243056) (xy 95.626511 -392.216802) (xy 95.664153 -392.169074) (xy 95.686118 -392.14806)
			(xy 95.69323 -392.14171) (xy 95.701358 -392.124946) (xy 95.70974 -392.038332) (xy 95.70466 -392.020552)
			(xy 95.699072 -392.012678) (xy 95.684914 -391.992834) (xy 95.662426 -391.949586) (xy 95.647107 -391.90331)
			(xy 95.639348 -391.855187) (xy 95.638874 -391.830814) (xy 95.639396 -391.805559) (xy 95.647709 -391.755737)
			(xy 95.66411 -391.707963) (xy 95.688151 -391.66354) (xy 95.719175 -391.62368) (xy 95.756337 -391.58947)
			(xy 95.798623 -391.561844) (xy 95.844879 -391.541554) (xy 95.893844 -391.529154) (xy 95.944182 -391.524983)
			(xy 95.99452 -391.529154) (xy 96.043485 -391.541554) (xy 96.089741 -391.561844) (xy 96.132027 -391.58947)
			(xy 96.169189 -391.62368) (xy 96.200213 -391.66354) (xy 96.224254 -391.707963) (xy 96.240655 -391.755737)
			(xy 96.248968 -391.805559) (xy 96.24949 -391.830814) (xy 96.248991 -391.855184) (xy 96.241211 -391.903298)
			(xy 96.225896 -391.94957) (xy 96.203435 -391.992826) (xy 96.189292 -392.012678) (xy 96.183704 -392.020552)
			(xy 96.178624 -392.038332) (xy 96.187006 -392.124946) (xy 96.195134 -392.14171) (xy 96.202246 -392.14806)
			(xy 96.224223 -392.169064) (xy 96.261871 -392.21679) (xy 96.277176 -392.243056) (xy 96.281918 -392.25074)
			(xy 96.295665 -392.262429) (xy 96.312603 -392.268652) (xy 96.321626 -392.268964) (xy 96.766888 -392.268964)
			(xy 96.775917 -392.268653) (xy 96.792878 -392.262468) (xy 96.806622 -392.250761) (xy 96.811338 -392.243056)
			(xy 96.826659 -392.216801) (xy 96.864298 -392.16907) (xy 96.886268 -392.14806) (xy 96.89338 -392.14171)
			(xy 96.901508 -392.124946) (xy 96.90989 -392.038332) (xy 96.90481 -392.020552) (xy 96.899222 -392.012678)
			(xy 96.885066 -391.992833) (xy 96.862582 -391.949584) (xy 96.847265 -391.903309) (xy 96.839507 -391.855186)
			(xy 96.839024 -391.830814) (xy 96.839546 -391.805559) (xy 96.847859 -391.755737) (xy 96.86426 -391.707963)
			(xy 96.888301 -391.66354) (xy 96.919325 -391.62368) (xy 96.956487 -391.58947) (xy 96.998773 -391.561844)
			(xy 97.045029 -391.541554) (xy 97.093994 -391.529154) (xy 97.144332 -391.524983) (xy 97.19467 -391.529154)
			(xy 97.243635 -391.541554) (xy 97.289891 -391.561844) (xy 97.332177 -391.58947) (xy 97.369339 -391.62368)
			(xy 97.400363 -391.66354) (xy 97.424404 -391.707963) (xy 97.440805 -391.755737) (xy 97.449118 -391.805559)
			(xy 97.44964 -391.830814) (xy 97.449142 -391.855184) (xy 97.441362 -391.903299) (xy 97.426049 -391.949572)
			(xy 97.403591 -391.992831) (xy 97.389442 -392.012678) (xy 97.383854 -392.020552) (xy 97.378774 -392.038332)
			(xy 97.387156 -392.124946) (xy 97.395284 -392.14171) (xy 97.402396 -392.14806) (xy 97.42437 -392.169066)
			(xy 97.462015 -392.216794) (xy 97.477326 -392.243056) (xy 97.48207 -392.250734) (xy 97.49582 -392.26241)
			(xy 97.512756 -392.268617) (xy 97.521776 -392.268964) (xy 97.966784 -392.268964) (xy 97.975813 -392.268653)
			(xy 97.992775 -392.262469) (xy 98.00652 -392.250763) (xy 98.011234 -392.243056) (xy 98.026555 -392.216801)
			(xy 98.064194 -392.169069) (xy 98.086164 -392.14806) (xy 98.093276 -392.14171) (xy 98.101404 -392.124946)
			(xy 98.109786 -392.038332) (xy 98.104706 -392.020552) (xy 98.099118 -392.012678) (xy 98.084958 -391.992834)
			(xy 98.062467 -391.949587) (xy 98.047145 -391.903311) (xy 98.039385 -391.855187) (xy 98.03892 -391.830814)
			(xy 98.039442 -391.805559) (xy 98.047755 -391.755737) (xy 98.064156 -391.707963) (xy 98.088197 -391.66354)
			(xy 98.119221 -391.62368) (xy 98.156383 -391.58947) (xy 98.198669 -391.561844) (xy 98.244925 -391.541554)
			(xy 98.29389 -391.529154) (xy 98.344228 -391.524983) (xy 98.394566 -391.529154) (xy 98.443531 -391.541554)
			(xy 98.489787 -391.561844) (xy 98.532073 -391.58947) (xy 98.569235 -391.62368) (xy 98.600259 -391.66354)
			(xy 98.6243 -391.707963) (xy 98.640701 -391.755737) (xy 98.649014 -391.805559) (xy 98.649536 -391.830814)
			(xy 98.649038 -391.855184) (xy 98.641258 -391.903299) (xy 98.625945 -391.949572) (xy 98.603487 -391.99283)
			(xy 98.589338 -392.012678) (xy 98.58375 -392.020552) (xy 98.57867 -392.038332) (xy 98.587052 -392.124946)
			(xy 98.59518 -392.14171) (xy 98.602292 -392.14806) (xy 98.624266 -392.169066) (xy 98.661911 -392.216794)
			(xy 98.677222 -392.243056) (xy 98.681966 -392.250735) (xy 98.695716 -392.262412) (xy 98.712652 -392.26862)
			(xy 98.721672 -392.268964) (xy 99.920298 -392.268964) (xy 99.930368 -392.268541) (xy 99.948969 -392.260823)
			(xy 99.956366 -392.253978) (xy 100.651564 -391.55878) (xy 100.658411 -391.551382) (xy 100.666144 -391.532784)
			(xy 100.66655 -391.522712) (xy 100.66655 -390.695942) (xy 100.666211 -390.687333) (xy 100.660521 -390.671081)
			(xy 100.649795 -390.65761) (xy 100.642674 -390.652762) (xy 100.5586 -390.59993) (xy 100.532692 -390.59866)
			(xy 100.520754 -390.604248) (xy 100.498231 -390.614654) (xy 100.450845 -390.629354) (xy 100.401796 -390.636817)
			(xy 100.37699 -390.637268) (xy 100.351002 -390.636784) (xy 100.299667 -390.628651) (xy 100.250237 -390.612588)
			(xy 100.203928 -390.588989) (xy 100.161881 -390.558436) (xy 100.125132 -390.521681) (xy 100.094585 -390.479629)
			(xy 100.070993 -390.433317) (xy 100.054937 -390.383884) (xy 100.046812 -390.332548) (xy 100.046282 -390.30656)
			(xy 100.046697 -390.282787) (xy 100.053511 -390.235732) (xy 100.066994 -390.190137) (xy 100.086867 -390.146943)
			(xy 100.112721 -390.107041) (xy 100.12807 -390.088882) (xy 100.133747 -390.081759) (xy 100.140121 -390.064708)
			(xy 100.140516 -390.055608) (xy 100.140516 -390.024112) (xy 100.140139 -390.015009) (xy 100.133754 -389.997959)
			(xy 100.12807 -389.990838) (xy 100.11272 -389.972679) (xy 100.08685 -389.932784) (xy 100.066971 -389.889591)
			(xy 100.053492 -389.843994) (xy 100.046692 -389.796934) (xy 100.046282 -389.77316) (xy 100.046715 -389.748749)
			(xy 100.053888 -389.700458) (xy 100.068087 -389.653748) (xy 100.089002 -389.609634) (xy 100.116179 -389.569077)
			(xy 100.149026 -389.532958) (xy 100.18683 -389.502065) (xy 100.207572 -389.489188) (xy 100.219002 -389.48233)
			(xy 100.23221 -389.459216) (xy 100.23221 -389.344916) (xy 100.219256 -389.321802) (xy 100.207572 -389.31469)
			(xy 100.186863 -389.301814) (xy 100.149127 -389.27093) (xy 100.11634 -389.234835) (xy 100.089214 -389.194314)
			(xy 100.068337 -389.150245) (xy 100.054163 -389.103588) (xy 100.047001 -389.055354) (xy 100.046536 -389.030972)
			(xy 100.047093 -389.003352) (xy 100.056272 -388.94888) (xy 100.07437 -388.896688) (xy 100.100884 -388.848227)
			(xy 100.135078 -388.804842) (xy 100.176003 -388.767739) (xy 100.198936 -388.752334) (xy 100.210366 -388.745222)
			(xy 100.222812 -388.7216) (xy 100.219256 -388.6073) (xy 100.20554 -388.584694) (xy 100.193602 -388.57809)
			(xy 100.171912 -388.565455) (xy 100.132277 -388.534655) (xy 100.09775 -388.498221) (xy 100.069123 -388.456989)
			(xy 100.047054 -388.411906) (xy 100.032048 -388.364006) (xy 100.024451 -388.314389) (xy 100.02393 -388.289292)
			(xy 100.024414 -388.263304) (xy 100.032546 -388.211969) (xy 100.04861 -388.162538) (xy 100.072208 -388.116228)
			(xy 100.102761 -388.074181) (xy 100.139516 -388.037432) (xy 100.181568 -388.006884) (xy 100.22788 -387.983292)
			(xy 100.277314 -387.967235) (xy 100.32865 -387.95911) (xy 100.354638 -387.958584) (xy 100.382634 -387.959178)
			(xy 100.437827 -387.968608) (xy 100.490652 -387.987175) (xy 100.51542 -388.00024) (xy 100.527358 -388.006844)
			(xy 100.554282 -388.00659) (xy 100.641404 -387.955282) (xy 100.648835 -387.950522) (xy 100.660141 -387.936989)
			(xy 100.666154 -387.920411) (xy 100.66655 -387.911594) (xy 100.66655 -386.352542) (xy 100.665941 -386.340689)
			(xy 100.655363 -386.319477) (xy 100.64623 -386.311902) (xy 100.571046 -386.256022) (xy 100.547932 -386.251704)
			(xy 100.535994 -386.25526) (xy 100.509486 -386.262622) (xy 100.455043 -386.270525) (xy 100.427536 -386.271008)
			(xy 100.400281 -386.270547) (xy 100.346327 -386.262794) (xy 100.294024 -386.247441) (xy 100.24444 -386.224801)
			(xy 100.198582 -386.195334) (xy 100.157385 -386.15964) (xy 100.121688 -386.118447) (xy 100.092216 -386.072592)
			(xy 100.069571 -386.023009) (xy 100.054213 -385.970709) (xy 100.046455 -385.916754) (xy 100.046028 -385.8895)
			(xy 100.046557 -385.861035) (xy 100.055026 -385.80474) (xy 100.071776 -385.75033) (xy 100.096434 -385.699018)
			(xy 100.128451 -385.651945) (xy 100.147374 -385.630674) (xy 100.155248 -385.622038) (xy 100.162106 -385.599178)
			(xy 100.144072 -385.496308) (xy 100.130102 -385.477258) (xy 100.119688 -385.47167) (xy 100.095374 -385.4584)
			(xy 100.050731 -385.425615) (xy 100.030788 -385.406392) (xy 99.623372 -384.998976) (xy 99.603558 -384.978383)
			(xy 99.569952 -384.932167) (xy 99.543982 -384.881266) (xy 99.526288 -384.826932) (xy 99.517305 -384.770499)
			(xy 99.516692 -384.741928) (xy 99.516692 -383.791968) (xy 99.517242 -383.763393) (xy 99.526221 -383.706951)
			(xy 99.543922 -383.65261) (xy 99.569908 -383.601708) (xy 99.603539 -383.5555) (xy 99.623372 -383.53492)
			(xy 100.274374 -382.883918) (xy 100.298054 -382.861227) (xy 100.351981 -382.823912) (xy 100.381562 -382.80975)
			(xy 100.393246 -382.804416) (xy 100.408486 -382.784858) (xy 100.425758 -382.69037) (xy 100.427391 -382.678037)
			(xy 100.419938 -382.65433) (xy 100.411534 -382.645158) (xy 100.246434 -382.480058) (xy 100.239035 -382.473216)
			(xy 100.220436 -382.465496) (xy 100.210366 -382.465072) (xy 98.668078 -382.465072) (xy 98.65833 -382.465502)
			(xy 98.640247 -382.472785) (xy 98.626216 -382.486318) (xy 98.62185 -382.495044) (xy 98.577654 -382.593088)
			(xy 98.581972 -382.622552) (xy 98.592132 -382.633982) (xy 98.607648 -382.652213) (xy 98.633812 -382.692301)
			(xy 98.653931 -382.73574) (xy 98.667585 -382.781623) (xy 98.674489 -382.828994) (xy 98.674936 -382.85293)
			(xy 98.674426 -382.878917) (xy 98.666296 -382.930252) (xy 98.650235 -382.979682) (xy 98.626639 -383.025992)
			(xy 98.596089 -383.06804) (xy 98.559338 -383.104791) (xy 98.51729 -383.135341) (xy 98.47098 -383.158937)
			(xy 98.42155 -383.174998) (xy 98.370215 -383.183128) (xy 98.318241 -383.183128) (xy 98.266906 -383.174998)
			(xy 98.217476 -383.158937) (xy 98.171166 -383.135341) (xy 98.129118 -383.104791) (xy 98.092367 -383.06804)
			(xy 98.061817 -383.025992) (xy 98.038221 -382.979682) (xy 98.02216 -382.930252) (xy 98.01403 -382.878917)
			(xy 98.01352 -382.85293) (xy 98.013941 -382.828992) (xy 98.020839 -382.781617) (xy 98.034494 -382.735731)
			(xy 98.054622 -382.692292) (xy 98.080801 -382.652209) (xy 98.096324 -382.633982) (xy 98.106484 -382.622552)
			(xy 98.110802 -382.593088) (xy 98.066606 -382.495044) (xy 98.0622 -382.48635) (xy 98.048159 -382.472855)
			(xy 98.030113 -382.465531) (xy 98.020378 -382.465072) (xy 97.468182 -382.465072) (xy 97.458434 -382.465501)
			(xy 97.44035 -382.472783) (xy 97.426317 -382.486316) (xy 97.421954 -382.495044) (xy 97.377758 -382.593088)
			(xy 97.382076 -382.622552) (xy 97.392236 -382.633982) (xy 97.407752 -382.652213) (xy 97.433916 -382.692302)
			(xy 97.454034 -382.73574) (xy 97.467688 -382.781623) (xy 97.474592 -382.828994) (xy 97.47504 -382.85293)
			(xy 97.47453 -382.878917) (xy 97.4664 -382.930252) (xy 97.450339 -382.979682) (xy 97.426743 -383.025992)
			(xy 97.396193 -383.06804) (xy 97.359442 -383.104791) (xy 97.317394 -383.135341) (xy 97.271084 -383.158937)
			(xy 97.221654 -383.174998) (xy 97.170319 -383.183128) (xy 97.118345 -383.183128) (xy 97.06701 -383.174998)
			(xy 97.01758 -383.158937) (xy 96.97127 -383.135341) (xy 96.929222 -383.104791) (xy 96.892471 -383.06804)
			(xy 96.861921 -383.025992) (xy 96.838325 -382.979682) (xy 96.822264 -382.930252) (xy 96.814134 -382.878917)
			(xy 96.813624 -382.85293) (xy 96.814045 -382.828992) (xy 96.820943 -382.781617) (xy 96.834598 -382.735731)
			(xy 96.854726 -382.692293) (xy 96.880906 -382.65221) (xy 96.896428 -382.633982) (xy 96.906588 -382.622552)
			(xy 96.910906 -382.593088) (xy 96.86671 -382.495044) (xy 96.862304 -382.486349) (xy 96.848263 -382.472853)
			(xy 96.830217 -382.465528) (xy 96.820482 -382.465072) (xy 96.268032 -382.465072) (xy 96.258278 -382.465492)
			(xy 96.240179 -382.472764) (xy 96.226131 -382.486295) (xy 96.221804 -382.495044) (xy 96.177608 -382.593088)
			(xy 96.181926 -382.622552) (xy 96.192086 -382.633982) (xy 96.207604 -382.652212) (xy 96.233772 -382.692299)
			(xy 96.253894 -382.735738) (xy 96.267549 -382.781622) (xy 96.274454 -382.828994) (xy 96.27489 -382.85293)
			(xy 96.27438 -382.878917) (xy 96.26625 -382.930252) (xy 96.250189 -382.979682) (xy 96.226593 -383.025992)
			(xy 96.196043 -383.06804) (xy 96.159292 -383.104791) (xy 96.117244 -383.135341) (xy 96.070934 -383.158937)
			(xy 96.021504 -383.174998) (xy 95.970169 -383.183128) (xy 95.918195 -383.183128) (xy 95.86686 -383.174998)
			(xy 95.81743 -383.158937) (xy 95.77112 -383.135341) (xy 95.729072 -383.104791) (xy 95.692321 -383.06804)
			(xy 95.661771 -383.025992) (xy 95.638175 -382.979682) (xy 95.622114 -382.930252) (xy 95.613984 -382.878917)
			(xy 95.613474 -382.85293) (xy 95.613895 -382.828992) (xy 95.620792 -382.781616) (xy 95.634446 -382.735729)
			(xy 95.654571 -382.692289) (xy 95.680748 -382.652203) (xy 95.696278 -382.633982) (xy 95.706438 -382.622552)
			(xy 95.710756 -382.593088) (xy 95.66656 -382.495044) (xy 95.662152 -382.486355) (xy 95.648108 -382.472872)
			(xy 95.630064 -382.465565) (xy 95.620332 -382.465072) (xy 95.068136 -382.465072) (xy 95.058382 -382.465492)
			(xy 95.040282 -382.472762) (xy 95.026233 -382.486294) (xy 95.021908 -382.495044) (xy 94.977712 -382.593088)
			(xy 94.98203 -382.622552) (xy 94.99219 -382.633982) (xy 95.007708 -382.652212) (xy 95.033875 -382.6923)
			(xy 95.053997 -382.735738) (xy 95.067652 -382.781622) (xy 95.074557 -382.828994) (xy 95.074994 -382.85293)
			(xy 95.074484 -382.878917) (xy 95.066354 -382.930252) (xy 95.050293 -382.979682) (xy 95.026697 -383.025992)
			(xy 94.996147 -383.06804) (xy 94.959396 -383.104791) (xy 94.917348 -383.135341) (xy 94.871038 -383.158937)
			(xy 94.821608 -383.174998) (xy 94.770273 -383.183128) (xy 94.718299 -383.183128) (xy 94.666964 -383.174998)
			(xy 94.617534 -383.158937) (xy 94.571224 -383.135341) (xy 94.529176 -383.104791) (xy 94.492425 -383.06804)
			(xy 94.461875 -383.025992) (xy 94.438279 -382.979682) (xy 94.422218 -382.930252) (xy 94.414088 -382.878917)
			(xy 94.413578 -382.85293) (xy 94.413999 -382.828992) (xy 94.420896 -382.781616) (xy 94.43455 -382.735729)
			(xy 94.454676 -382.692289) (xy 94.480853 -382.652204) (xy 94.496382 -382.633982) (xy 94.506542 -382.622552)
			(xy 94.51086 -382.593088) (xy 94.466664 -382.495044) (xy 94.462256 -382.486355) (xy 94.448213 -382.472871)
			(xy 94.430168 -382.465562) (xy 94.420436 -382.465072) (xy 93.86824 -382.465072) (xy 93.858496 -382.465508)
			(xy 93.840425 -382.4728) (xy 93.826405 -382.486334) (xy 93.822012 -382.495044) (xy 93.777816 -382.593088)
			(xy 93.782134 -382.622552) (xy 93.792294 -382.633982) (xy 93.807811 -382.652212) (xy 93.833979 -382.6923)
			(xy 93.8541 -382.735738) (xy 93.867755 -382.781622) (xy 93.87466 -382.828994) (xy 93.875098 -382.85293)
			(xy 93.874588 -382.878917) (xy 93.866458 -382.930252) (xy 93.850397 -382.979682) (xy 93.826801 -383.025992)
			(xy 93.796251 -383.06804) (xy 93.7595 -383.104791) (xy 93.717452 -383.135341) (xy 93.671142 -383.158937)
			(xy 93.621712 -383.174998) (xy 93.570377 -383.183128) (xy 93.518403 -383.183128) (xy 93.467068 -383.174998)
			(xy 93.417638 -383.158937) (xy 93.371328 -383.135341) (xy 93.32928 -383.104791) (xy 93.292529 -383.06804)
			(xy 93.261979 -383.025992) (xy 93.238383 -382.979682) (xy 93.222322 -382.930252) (xy 93.214192 -382.878917)
			(xy 93.213682 -382.85293) (xy 93.214103 -382.828992) (xy 93.221 -382.781616) (xy 93.234654 -382.735729)
			(xy 93.25478 -382.692289) (xy 93.280957 -382.652204) (xy 93.296486 -382.633982) (xy 93.306646 -382.622552)
			(xy 93.310964 -382.593088) (xy 93.266768 -382.495044) (xy 93.26236 -382.486354) (xy 93.248317 -382.472869)
			(xy 93.230272 -382.465559) (xy 93.22054 -382.465072) (xy 92.66809 -382.465072) (xy 92.658341 -382.4655)
			(xy 92.640254 -382.47278) (xy 92.626219 -382.486313) (xy 92.621862 -382.495044) (xy 92.577666 -382.593088)
			(xy 92.581984 -382.622552) (xy 92.592144 -382.633982) (xy 92.607659 -382.652213) (xy 92.633823 -382.692302)
			(xy 92.653941 -382.735741) (xy 92.667594 -382.781624) (xy 92.674498 -382.828994) (xy 92.674948 -382.85293)
			(xy 92.674438 -382.878917) (xy 92.666308 -382.930252) (xy 92.650247 -382.979682) (xy 92.626651 -383.025992)
			(xy 92.596101 -383.06804) (xy 92.55935 -383.104791) (xy 92.517302 -383.135341) (xy 92.470992 -383.158937)
			(xy 92.421562 -383.174998) (xy 92.370227 -383.183128) (xy 92.318253 -383.183128) (xy 92.266918 -383.174998)
			(xy 92.217488 -383.158937) (xy 92.171178 -383.135341) (xy 92.12913 -383.104791) (xy 92.092379 -383.06804)
			(xy 92.061829 -383.025992) (xy 92.038233 -382.979682) (xy 92.022172 -382.930252) (xy 92.014042 -382.878917)
			(xy 92.013532 -382.85293) (xy 92.013953 -382.828993) (xy 92.020851 -382.781617) (xy 92.034507 -382.735731)
			(xy 92.054635 -382.692293) (xy 92.080815 -382.652211) (xy 92.096336 -382.633982) (xy 92.106496 -382.622552)
			(xy 92.110814 -382.593088) (xy 92.066618 -382.495044) (xy 92.062208 -382.486359) (xy 92.048162 -382.472888)
			(xy 92.030119 -382.465595) (xy 92.02039 -382.465072) (xy 91.468194 -382.465072) (xy 91.458444 -382.465499)
			(xy 91.440357 -382.472779) (xy 91.42632 -382.486311) (xy 91.421966 -382.495044) (xy 91.37777 -382.593088)
			(xy 91.382088 -382.622552) (xy 91.392248 -382.633982) (xy 91.407763 -382.652213) (xy 91.433926 -382.692302)
			(xy 91.454044 -382.735741) (xy 91.467697 -382.781624) (xy 91.474601 -382.828995) (xy 91.475052 -382.85293)
			(xy 91.474542 -382.878917) (xy 91.466412 -382.930252) (xy 91.450351 -382.979682) (xy 91.426755 -383.025992)
			(xy 91.396205 -383.06804) (xy 91.359454 -383.104791) (xy 91.317406 -383.135341) (xy 91.271096 -383.158937)
			(xy 91.221666 -383.174998) (xy 91.170331 -383.183128) (xy 91.118357 -383.183128) (xy 91.067022 -383.174998)
			(xy 91.017592 -383.158937) (xy 90.971282 -383.135341) (xy 90.929234 -383.104791) (xy 90.892483 -383.06804)
			(xy 90.861933 -383.025992) (xy 90.838337 -382.979682) (xy 90.822276 -382.930252) (xy 90.814146 -382.878917)
			(xy 90.813636 -382.85293) (xy 90.814057 -382.828993) (xy 90.820955 -382.781617) (xy 90.834611 -382.735731)
			(xy 90.854739 -382.692293) (xy 90.88092 -382.652211) (xy 90.89644 -382.633982) (xy 90.9066 -382.622552)
			(xy 90.910918 -382.593088) (xy 90.866722 -382.495044) (xy 90.862312 -382.486359) (xy 90.848267 -382.472887)
			(xy 90.830223 -382.465592) (xy 90.820494 -382.465072) (xy 90.268044 -382.465072) (xy 90.2583 -382.465508)
			(xy 90.240227 -382.472798) (xy 90.226206 -382.486332) (xy 90.221816 -382.495044) (xy 90.17762 -382.593088)
			(xy 90.181938 -382.622552) (xy 90.192098 -382.633982) (xy 90.207615 -382.652212) (xy 90.233782 -382.6923)
			(xy 90.253903 -382.735739) (xy 90.267558 -382.781622) (xy 90.274463 -382.828994) (xy 90.274902 -382.85293)
			(xy 90.274392 -382.878917) (xy 90.266262 -382.930252) (xy 90.250201 -382.979682) (xy 90.226605 -383.025992)
			(xy 90.196055 -383.06804) (xy 90.159304 -383.104791) (xy 90.117256 -383.135341) (xy 90.070946 -383.158937)
			(xy 90.021516 -383.174998) (xy 89.970181 -383.183128) (xy 89.918207 -383.183128) (xy 89.866872 -383.174998)
			(xy 89.817442 -383.158937) (xy 89.771132 -383.135341) (xy 89.729084 -383.104791) (xy 89.692333 -383.06804)
			(xy 89.661783 -383.025992) (xy 89.638187 -382.979682) (xy 89.622126 -382.930252) (xy 89.613996 -382.878917)
			(xy 89.613486 -382.85293) (xy 89.613907 -382.828992) (xy 89.620804 -382.781616) (xy 89.634458 -382.735729)
			(xy 89.654584 -382.69229) (xy 89.680762 -382.652205) (xy 89.69629 -382.633982) (xy 89.70645 -382.622552)
			(xy 89.710768 -382.593088) (xy 89.666572 -382.495044) (xy 89.662164 -382.486353) (xy 89.648122 -382.472867)
			(xy 89.630077 -382.465556) (xy 89.620344 -382.465072) (xy 89.068148 -382.465072) (xy 89.058403 -382.465507)
			(xy 89.040329 -382.472796) (xy 89.026307 -382.486331) (xy 89.02192 -382.495044) (xy 88.977724 -382.593088)
			(xy 88.982042 -382.622552) (xy 88.992202 -382.633982) (xy 89.007719 -382.652212) (xy 89.033886 -382.6923)
			(xy 89.054007 -382.735739) (xy 89.067662 -382.781622) (xy 89.074566 -382.828994) (xy 89.075006 -382.85293)
			(xy 89.074496 -382.878917) (xy 89.066366 -382.930252) (xy 89.050305 -382.979682) (xy 89.026709 -383.025992)
			(xy 88.996159 -383.06804) (xy 88.959408 -383.104791) (xy 88.91736 -383.135341) (xy 88.87105 -383.158937)
			(xy 88.82162 -383.174998) (xy 88.770285 -383.183128) (xy 88.718311 -383.183128) (xy 88.666976 -383.174998)
			(xy 88.617546 -383.158937) (xy 88.571236 -383.135341) (xy 88.529188 -383.104791) (xy 88.492437 -383.06804)
			(xy 88.461887 -383.025992) (xy 88.438291 -382.979682) (xy 88.42223 -382.930252) (xy 88.4141 -382.878917)
			(xy 88.41359 -382.85293) (xy 88.414011 -382.828992) (xy 88.420908 -382.781616) (xy 88.434563 -382.735729)
			(xy 88.454689 -382.69229) (xy 88.480867 -382.652205) (xy 88.496394 -382.633982) (xy 88.506554 -382.622552)
			(xy 88.510872 -382.593088) (xy 88.466676 -382.495044) (xy 88.462269 -382.486353) (xy 88.448226 -382.472866)
			(xy 88.430181 -382.465553) (xy 88.420448 -382.465072) (xy 87.868252 -382.465072) (xy 87.858507 -382.465506)
			(xy 87.840432 -382.472795) (xy 87.826408 -382.486329) (xy 87.822024 -382.495044) (xy 87.777828 -382.593088)
			(xy 87.782146 -382.622552) (xy 87.792306 -382.633982) (xy 87.807823 -382.652212) (xy 87.833989 -382.6923)
			(xy 87.85411 -382.735739) (xy 87.867765 -382.781622) (xy 87.874669 -382.828994) (xy 87.87511 -382.85293)
			(xy 87.8746 -382.878917) (xy 87.86647 -382.930252) (xy 87.850409 -382.979682) (xy 87.826813 -383.025992)
			(xy 87.796263 -383.06804) (xy 87.759512 -383.104791) (xy 87.717464 -383.135341) (xy 87.671154 -383.158937)
			(xy 87.621724 -383.174998) (xy 87.570389 -383.183128) (xy 87.518415 -383.183128) (xy 87.46708 -383.174998)
			(xy 87.41765 -383.158937) (xy 87.37134 -383.135341) (xy 87.329292 -383.104791) (xy 87.292541 -383.06804)
			(xy 87.261991 -383.025992) (xy 87.238395 -382.979682) (xy 87.222334 -382.930252) (xy 87.214204 -382.878917)
			(xy 87.213694 -382.85293) (xy 87.214115 -382.828992) (xy 87.221012 -382.781616) (xy 87.234667 -382.735729)
			(xy 87.254793 -382.69229) (xy 87.280971 -382.652206) (xy 87.296498 -382.633982) (xy 87.306658 -382.622552)
			(xy 87.310976 -382.593088) (xy 87.26678 -382.495044) (xy 87.262373 -382.486353) (xy 87.24833 -382.472864)
			(xy 87.230285 -382.46555) (xy 87.220552 -382.465072) (xy 86.668102 -382.465072) (xy 86.658352 -382.465497)
			(xy 86.640262 -382.472776) (xy 86.626223 -382.486308) (xy 86.621874 -382.495044) (xy 86.577678 -382.593088)
			(xy 86.581996 -382.622552) (xy 86.592156 -382.633982) (xy 86.607671 -382.652213) (xy 86.633834 -382.692302)
			(xy 86.653951 -382.735741) (xy 86.667603 -382.781624) (xy 86.674507 -382.828995) (xy 86.67496 -382.85293)
			(xy 86.67445 -382.878917) (xy 86.66632 -382.930252) (xy 86.650259 -382.979682) (xy 86.626663 -383.025992)
			(xy 86.596113 -383.06804) (xy 86.559362 -383.104791) (xy 86.517314 -383.135341) (xy 86.471004 -383.158937)
			(xy 86.421574 -383.174998) (xy 86.370239 -383.183128) (xy 86.318265 -383.183128) (xy 86.26693 -383.174998)
			(xy 86.2175 -383.158937) (xy 86.17119 -383.135341) (xy 86.129142 -383.104791) (xy 86.092391 -383.06804)
			(xy 86.061841 -383.025992) (xy 86.038245 -382.979682) (xy 86.022184 -382.930252) (xy 86.014054 -382.878917)
			(xy 86.013544 -382.85293) (xy 86.013965 -382.828993) (xy 86.020863 -382.781617) (xy 86.034519 -382.735732)
			(xy 86.054648 -382.692294) (xy 86.080829 -382.652212) (xy 86.096348 -382.633982) (xy 86.106508 -382.622552)
			(xy 86.110826 -382.593088) (xy 86.06663 -382.495044) (xy 86.06222 -382.486358) (xy 86.048175 -382.472884)
			(xy 86.030132 -382.465586) (xy 86.020402 -382.465072) (xy 85.468206 -382.465072) (xy 85.458455 -382.465497)
			(xy 85.440364 -382.472774) (xy 85.426324 -382.486306) (xy 85.421978 -382.495044) (xy 85.377782 -382.593088)
			(xy 85.3821 -382.622552) (xy 85.39226 -382.633982) (xy 85.407775 -382.652213) (xy 85.433937 -382.692303)
			(xy 85.454054 -382.735741) (xy 85.467706 -382.781624) (xy 85.47461 -382.828995) (xy 85.475064 -382.85293)
			(xy 85.474554 -382.878917) (xy 85.466424 -382.930252) (xy 85.450363 -382.979682) (xy 85.426767 -383.025992)
			(xy 85.396217 -383.06804) (xy 85.359466 -383.104791) (xy 85.317418 -383.135341) (xy 85.271108 -383.158937)
			(xy 85.221678 -383.174998) (xy 85.170343 -383.183128) (xy 85.118369 -383.183128) (xy 85.067034 -383.174998)
			(xy 85.017604 -383.158937) (xy 84.971294 -383.135341) (xy 84.929246 -383.104791) (xy 84.892495 -383.06804)
			(xy 84.861945 -383.025992) (xy 84.838349 -382.979682) (xy 84.822288 -382.930252) (xy 84.814158 -382.878917)
			(xy 84.813648 -382.85293) (xy 84.81407 -382.828993) (xy 84.820967 -382.781618) (xy 84.834624 -382.735732)
			(xy 84.854753 -382.692294) (xy 84.880934 -382.652213) (xy 84.896452 -382.633982) (xy 84.906612 -382.622552)
			(xy 84.91093 -382.593088) (xy 84.866734 -382.495044) (xy 84.862324 -382.486358) (xy 84.84828 -382.472882)
			(xy 84.830236 -382.465583) (xy 84.820506 -382.465072) (xy 84.268056 -382.465072) (xy 84.25831 -382.465505)
			(xy 84.240234 -382.472793) (xy 84.226209 -382.486327) (xy 84.221828 -382.495044) (xy 84.177632 -382.593088)
			(xy 84.18195 -382.622552) (xy 84.19211 -382.633982) (xy 84.207627 -382.652212) (xy 84.233793 -382.6923)
			(xy 84.253913 -382.735739) (xy 84.267568 -382.781622) (xy 84.274472 -382.828994) (xy 84.274914 -382.85293)
			(xy 84.274404 -382.878917) (xy 84.266274 -382.930252) (xy 84.250213 -382.979682) (xy 84.226617 -383.025992)
			(xy 84.196067 -383.06804) (xy 84.159316 -383.104791) (xy 84.117268 -383.135341) (xy 84.070958 -383.158937)
			(xy 84.021528 -383.174998) (xy 83.970193 -383.183128) (xy 83.918219 -383.183128) (xy 83.866884 -383.174998)
			(xy 83.817454 -383.158937) (xy 83.771144 -383.135341) (xy 83.729096 -383.104791) (xy 83.692345 -383.06804)
			(xy 83.661795 -383.025992) (xy 83.638199 -382.979682) (xy 83.622138 -382.930252) (xy 83.614008 -382.878917)
			(xy 83.613498 -382.85293) (xy 83.613919 -382.828992) (xy 83.620816 -382.781616) (xy 83.634471 -382.73573)
			(xy 83.654598 -382.69229) (xy 83.680776 -382.652206) (xy 83.696302 -382.633982) (xy 83.706462 -382.622552)
			(xy 83.71078 -382.593088) (xy 83.666584 -382.495044) (xy 83.662177 -382.486352) (xy 83.648135 -382.472863)
			(xy 83.63009 -382.465547) (xy 83.620356 -382.465072) (xy 83.06816 -382.465072) (xy 83.058414 -382.465505)
			(xy 83.040337 -382.472792) (xy 83.02631 -382.486326) (xy 83.021932 -382.495044) (xy 82.977736 -382.593088)
			(xy 82.982054 -382.622552) (xy 82.992214 -382.633982) (xy 83.007731 -382.652212) (xy 83.033897 -382.692301)
			(xy 83.054016 -382.735739) (xy 83.067671 -382.781623) (xy 83.074575 -382.828994) (xy 83.075018 -382.85293)
			(xy 83.074508 -382.878917) (xy 83.066378 -382.930252) (xy 83.050317 -382.979682) (xy 83.026721 -383.025992)
			(xy 82.996171 -383.06804) (xy 82.95942 -383.104791) (xy 82.917372 -383.135341) (xy 82.871062 -383.158937)
			(xy 82.821632 -383.174998) (xy 82.770297 -383.183128) (xy 82.718323 -383.183128) (xy 82.666988 -383.174998)
			(xy 82.617558 -383.158937) (xy 82.571248 -383.135341) (xy 82.5292 -383.104791) (xy 82.492449 -383.06804)
			(xy 82.461899 -383.025992) (xy 82.438303 -382.979682) (xy 82.422242 -382.930252) (xy 82.414112 -382.878917)
			(xy 82.413602 -382.85293) (xy 82.414023 -382.828992) (xy 82.420921 -382.781617) (xy 82.434575 -382.73573)
			(xy 82.454702 -382.692291) (xy 82.48088 -382.652207) (xy 82.496406 -382.633982) (xy 82.506566 -382.622552)
			(xy 82.510884 -382.593088) (xy 82.466688 -382.495044) (xy 82.462281 -382.486352) (xy 82.448239 -382.472861)
			(xy 82.430194 -382.465544) (xy 82.42046 -382.465072) (xy 81.868264 -382.465072) (xy 81.858518 -382.465504)
			(xy 81.840439 -382.47279) (xy 81.826412 -382.486324) (xy 81.822036 -382.495044) (xy 81.77784 -382.593088)
			(xy 81.782158 -382.622552) (xy 81.792318 -382.633982) (xy 81.807834 -382.652212) (xy 81.834 -382.692301)
			(xy 81.85412 -382.735739) (xy 81.867774 -382.781623) (xy 81.874678 -382.828994) (xy 81.875122 -382.85293)
			(xy 81.874612 -382.878917) (xy 81.866482 -382.930252) (xy 81.850421 -382.979682) (xy 81.826825 -383.025992)
			(xy 81.796275 -383.06804) (xy 81.759524 -383.104791) (xy 81.717476 -383.135341) (xy 81.671166 -383.158937)
			(xy 81.621736 -383.174998) (xy 81.570401 -383.183128) (xy 81.518427 -383.183128) (xy 81.467092 -383.174998)
			(xy 81.417662 -383.158937) (xy 81.371352 -383.135341) (xy 81.329304 -383.104791) (xy 81.292553 -383.06804)
			(xy 81.262003 -383.025992) (xy 81.238407 -382.979682) (xy 81.222346 -382.930252) (xy 81.214216 -382.878917)
			(xy 81.213706 -382.85293) (xy 81.214127 -382.828992) (xy 81.221025 -382.781617) (xy 81.234679 -382.73573)
			(xy 81.254806 -382.692291) (xy 81.280985 -382.652207) (xy 81.29651 -382.633982) (xy 81.30667 -382.622552)
			(xy 81.310988 -382.593088) (xy 81.266792 -382.495044) (xy 81.262385 -382.486351) (xy 81.248343 -382.47286)
			(xy 81.230298 -382.465541) (xy 81.220564 -382.465072) (xy 80.668114 -382.465072) (xy 80.658362 -382.465495)
			(xy 80.640269 -382.472771) (xy 80.626226 -382.486303) (xy 80.621886 -382.495044) (xy 80.57769 -382.593088)
			(xy 80.582008 -382.622552) (xy 80.592168 -382.633982) (xy 80.607687 -382.652211) (xy 80.633856 -382.692299)
			(xy 80.653979 -382.735737) (xy 80.667635 -382.781621) (xy 80.67454 -382.828994) (xy 80.674972 -382.85293)
			(xy 80.674462 -382.878917) (xy 80.666332 -382.930252) (xy 80.650271 -382.979682) (xy 80.626675 -383.025992)
			(xy 80.596125 -383.06804) (xy 80.559374 -383.104791) (xy 80.517326 -383.135341) (xy 80.471016 -383.158937)
			(xy 80.421586 -383.174998) (xy 80.370251 -383.183128) (xy 80.318277 -383.183128) (xy 80.266942 -383.174998)
			(xy 80.217512 -383.158937) (xy 80.171202 -383.135341) (xy 80.129154 -383.104791) (xy 80.092403 -383.06804)
			(xy 80.061853 -383.025992) (xy 80.038257 -382.979682) (xy 80.022196 -382.930252) (xy 80.014066 -382.878917)
			(xy 80.013556 -382.85293) (xy 80.013978 -382.828993) (xy 80.020876 -382.781618) (xy 80.034532 -382.735732)
			(xy 80.054661 -382.692295) (xy 80.080843 -382.652214) (xy 80.09636 -382.633982) (xy 80.10652 -382.622552)
			(xy 80.110838 -382.593088) (xy 80.066642 -382.495044) (xy 80.062233 -382.486357) (xy 80.048188 -382.472879)
			(xy 80.030145 -382.465578) (xy 80.020414 -382.465072) (xy 77.975968 -382.465072) (xy 77.9659 -382.4655)
			(xy 77.947301 -382.47322) (xy 77.9399 -382.480058) (xy 77.637386 -382.782572) (xy 77.630542 -382.78997)
			(xy 77.62282 -382.80857) (xy 77.6224 -382.81864) (xy 77.6224 -382.934543) (xy 78.666088 -382.934543)
			(xy 78.666088 -382.882569) (xy 78.674218 -382.831234) (xy 78.690279 -382.781804) (xy 78.713875 -382.735494)
			(xy 78.744425 -382.693446) (xy 78.781176 -382.656695) (xy 78.823224 -382.626145) (xy 78.869534 -382.602549)
			(xy 78.918964 -382.586488) (xy 78.970299 -382.578358) (xy 79.022273 -382.578358) (xy 79.073608 -382.586488)
			(xy 79.123038 -382.602549) (xy 79.169348 -382.626145) (xy 79.211396 -382.656695) (xy 79.248147 -382.693446)
			(xy 79.278697 -382.735494) (xy 79.302293 -382.781804) (xy 79.318354 -382.831234) (xy 79.326484 -382.882569)
			(xy 79.326994 -382.908556) (xy 79.326484 -382.934543) (xy 79.318354 -382.985878) (xy 79.302293 -383.035308)
			(xy 79.278697 -383.081618) (xy 79.248147 -383.123666) (xy 79.211396 -383.160417) (xy 79.169348 -383.190967)
			(xy 79.123038 -383.214563) (xy 79.073608 -383.230624) (xy 79.022273 -383.238754) (xy 78.970299 -383.238754)
			(xy 78.918964 -383.230624) (xy 78.869534 -383.214563) (xy 78.823224 -383.190967) (xy 78.781176 -383.160417)
			(xy 78.744425 -383.123666) (xy 78.713875 -383.081618) (xy 78.690279 -383.035308) (xy 78.674218 -382.985878)
			(xy 78.666088 -382.934543) (xy 77.6224 -382.934543) (xy 77.6224 -383.155698) (xy 77.622823 -383.165768)
			(xy 77.630537 -383.184373) (xy 77.637386 -383.191766) (xy 78.034134 -383.58826) (xy 78.041505 -383.595001)
			(xy 78.059967 -383.602587) (xy 78.069948 -383.602992) (xy 96.898968 -383.602992) (xy 96.908958 -383.603524)
			(xy 96.927399 -383.611228) (xy 96.934782 -383.617978) (xy 96.940624 -383.62382) (xy 96.959166 -383.63144)
			(xy 97.177098 -383.63144) (xy 97.187167 -383.631864) (xy 97.205769 -383.639582) (xy 97.213166 -383.646426)
			(xy 97.86239 -384.29565) (xy 97.888806 -384.302762) (xy 97.902014 -384.298952) (xy 97.923617 -384.293357)
			(xy 97.967839 -384.287368) (xy 97.990152 -384.287014) (xy 98.016143 -384.287494) (xy 98.067486 -384.295619)
			(xy 98.116926 -384.311677) (xy 98.163244 -384.335273) (xy 98.2053 -384.365825) (xy 98.242059 -384.40258)
			(xy 98.272614 -384.444634) (xy 98.296213 -384.49095) (xy 98.312275 -384.540388) (xy 98.320404 -384.591731)
			(xy 98.32086 -384.617722) (xy 98.32049 -384.640034) (xy 98.314496 -384.684253) (xy 98.308922 -384.70586)
			(xy 98.305112 -384.719068) (xy 98.312224 -384.745484) (xy 99.042474 -385.475734) (xy 99.049318 -385.483133)
			(xy 99.057044 -385.501731) (xy 99.05746 -385.511802) (xy 99.05746 -386.046472) (xy 99.057898 -386.056535)
			(xy 99.065637 -386.075115) (xy 99.072446 -386.08254) (xy 99.09429 -386.10413) (xy 99.101205 -386.110409)
			(xy 99.118267 -386.117973) (xy 99.127564 -386.118862) (xy 99.152693 -386.12055) (xy 99.202046 -386.130582)
			(xy 99.249307 -386.147984) (xy 99.293381 -386.172352) (xy 99.33325 -386.203122) (xy 99.367992 -386.239584)
			(xy 99.396802 -386.280892) (xy 99.419013 -386.326092) (xy 99.434113 -386.374137) (xy 99.441751 -386.423917)
			(xy 99.441751 -386.474279) (xy 99.434114 -386.524059) (xy 99.419015 -386.572105) (xy 99.396803 -386.617305)
			(xy 99.367994 -386.658614) (xy 99.333253 -386.695075) (xy 99.293384 -386.725846) (xy 99.24931 -386.750214)
			(xy 99.20205 -386.767617) (xy 99.152697 -386.77765) (xy 99.127564 -386.779262) (xy 99.118259 -386.780134)
			(xy 99.10118 -386.787682) (xy 99.09429 -386.793994) (xy 99.072446 -386.815584) (xy 99.065608 -386.822985)
			(xy 99.057897 -386.841584) (xy 99.05746 -386.851652) (xy 99.05746 -389.742934) (xy 99.058053 -389.75469)
			(xy 99.068515 -389.775746) (xy 99.077526 -389.78332) (xy 99.151186 -389.839708) (xy 99.1743 -389.84428)
			(xy 99.18573 -389.840978) (xy 99.207159 -389.835508) (xy 99.250993 -389.829645) (xy 99.273106 -389.829294)
			(xy 99.299093 -389.829804) (xy 99.350426 -389.837935) (xy 99.399856 -389.853997) (xy 99.446164 -389.877593)
			(xy 99.488211 -389.908142) (xy 99.524962 -389.944893) (xy 99.55551 -389.986941) (xy 99.579106 -390.03325)
			(xy 99.595166 -390.08268) (xy 99.603296 -390.134013) (xy 99.603296 -390.185987) (xy 99.595166 -390.23732)
			(xy 99.579106 -390.28675) (xy 99.55551 -390.333059) (xy 99.524962 -390.375107) (xy 99.488211 -390.411858)
			(xy 99.446164 -390.442407) (xy 99.399856 -390.466003) (xy 99.350426 -390.482065) (xy 99.299093 -390.490196)
			(xy 99.273106 -390.49071) (xy 99.249257 -390.490314) (xy 99.202048 -390.483503) (xy 99.156308 -390.469979)
			(xy 99.112986 -390.450022) (xy 99.092766 -390.43737) (xy 99.07778 -390.427464) (xy 99.041966 -390.431274)
			(xy 98.516186 -390.957054) (xy 98.508789 -390.963903) (xy 98.49019 -390.97164) (xy 98.480118 -390.97204)
			(xy 77.614018 -390.97204) (xy 77.603955 -390.972479) (xy 77.585376 -390.980219) (xy 77.57795 -390.987026)
			(xy 77.447902 -391.117074) (xy 77.441067 -391.124477) (xy 77.433359 -391.143075) (xy 77.432916 -391.153142)
			(xy 77.432916 -391.49401) (xy 77.433341 -391.504079) (xy 77.44106 -391.522679) (xy 77.447902 -391.530078)
			(xy 77.719761 -391.801937) (xy 78.692504 -391.801937) (xy 78.692504 -391.749963) (xy 78.700634 -391.698628)
			(xy 78.716695 -391.649198) (xy 78.740291 -391.602888) (xy 78.770841 -391.56084) (xy 78.807592 -391.524089)
			(xy 78.84964 -391.493539) (xy 78.89595 -391.469943) (xy 78.94538 -391.453882) (xy 78.996715 -391.445752)
			(xy 79.048689 -391.445752) (xy 79.100024 -391.453882) (xy 79.149454 -391.469943) (xy 79.195764 -391.493539)
			(xy 79.237812 -391.524089) (xy 79.274563 -391.56084) (xy 79.305113 -391.602888) (xy 79.328709 -391.649198)
			(xy 79.34477 -391.698628) (xy 79.3529 -391.749963) (xy 79.35341 -391.77595) (xy 79.3529 -391.801937)
			(xy 79.34477 -391.853272) (xy 79.328709 -391.902702) (xy 79.305113 -391.949012) (xy 79.274563 -391.99106)
			(xy 79.237812 -392.027811) (xy 79.195764 -392.058361) (xy 79.149454 -392.081957) (xy 79.100024 -392.098018)
			(xy 79.048689 -392.106148) (xy 78.996715 -392.106148) (xy 78.94538 -392.098018) (xy 78.89595 -392.081957)
			(xy 78.84964 -392.058361) (xy 78.807592 -392.027811) (xy 78.770841 -391.99106) (xy 78.740291 -391.949012)
			(xy 78.716695 -391.902702) (xy 78.700634 -391.853272) (xy 78.692504 -391.801937) (xy 77.719761 -391.801937)
			(xy 78.49108 -392.573256) (xy 78.498481 -392.580095) (xy 78.517079 -392.587807) (xy 78.527148 -392.588242)
		)
		(stroke
			(width 0)
			(type solid)
		)
		(fill yes)
		(layer "In2.Cu")
		(net "NCF_CPU1_P1_GND")
	)
	(gr_poly
		(pts
			(xy 208.90103 -39.757604) (xy 208.908276 -39.75598) (xy 208.921453 -39.749147) (xy 208.926938 -39.744142)
			(xy 209.273902 -39.397178) (xy 209.27889 -39.391679) (xy 209.285734 -39.378513) (xy 209.287364 -39.37127)
			(xy 209.28838 -39.361618) (xy 209.28838 -37.27069) (xy 209.288133 -37.263509) (xy 209.284137 -37.249713)
			(xy 209.280506 -37.243512) (xy 209.276696 -37.23767) (xy 209.266282 -37.228272) (xy 209.259424 -37.22497)
			(xy 209.235293 -37.213041) (xy 209.190356 -37.183404) (xy 209.150035 -37.147742) (xy 209.115129 -37.106764)
			(xy 209.086334 -37.061284) (xy 209.064221 -37.012206) (xy 209.049231 -36.960506) (xy 209.041661 -36.907211)
			(xy 209.041661 -36.853382) (xy 209.049232 -36.800087) (xy 209.064224 -36.748388) (xy 209.086337 -36.69931)
			(xy 209.115133 -36.65383) (xy 209.150039 -36.612853) (xy 209.190362 -36.577192) (xy 209.235299 -36.547556)
			(xy 209.259424 -36.535614) (xy 209.265846 -36.532314) (xy 209.276668 -36.522767) (xy 209.28076 -36.516818)
			(xy 209.28457 -36.510976) (xy 209.28838 -36.49726) (xy 209.28838 -32.847534) (xy 209.287893 -32.837572)
			(xy 209.280304 -32.81915) (xy 209.273648 -32.81172) (xy 205.441804 -28.979876) (xy 205.434393 -28.973194)
			(xy 205.415958 -28.965614) (xy 205.40599 -28.965144) (xy 200.74509 -28.965144) (xy 200.708086 -28.964681)
			(xy 200.634495 -28.956829) (xy 200.56216 -28.941184) (xy 200.491902 -28.917923) (xy 200.424522 -28.887311)
			(xy 200.360785 -28.849697) (xy 200.301417 -28.805508) (xy 200.27392 -28.78074) (xy 200.270465 -28.777661)
			(xy 200.262672 -28.772674) (xy 200.258426 -28.770834) (xy 200.241662 -28.763976) (xy 200.237087 -28.762274)
			(xy 200.227493 -28.760484) (xy 200.222612 -28.76042) (xy 199.111362 -28.76042) (xy 199.101294 -28.759991)
			(xy 199.082698 -28.752269) (xy 199.075294 -28.745434) (xy 196.483986 -26.154126) (xy 196.477142 -26.146728)
			(xy 196.469421 -26.128128) (xy 196.469 -26.118058) (xy 196.469 -22.246082) (xy 196.468573 -22.236013)
			(xy 196.460854 -22.217414) (xy 196.454014 -22.210014) (xy 194.777106 -20.533106) (xy 194.769708 -20.526258)
			(xy 194.75111 -20.51852) (xy 194.741038 -20.51812) (xy 190.84798 -20.51812) (xy 190.84057 -20.511437)
			(xy 190.822134 -20.503859) (xy 190.812166 -20.503388) (xy 190.62192 -20.503388) (xy 190.58241 -20.502811)
			(xy 190.503905 -20.493807) (xy 190.426927 -20.475957) (xy 190.38951 -20.463256) (xy 190.353419 -20.449838)
			(xy 190.284196 -20.416114) (xy 190.219131 -20.374934) (xy 190.159025 -20.326804) (xy 190.131446 -20.299934)
			(xy 189.278514 -19.447256) (xy 189.20841 -19.377152) (xy 189.200999 -19.370471) (xy 189.182563 -19.362893)
			(xy 189.172596 -19.36242) (xy 188.69152 -19.36242) (xy 188.682827 -19.362762) (xy 188.666452 -19.3686)
			(xy 188.659516 -19.37385) (xy 188.625458 -19.401017) (xy 188.552944 -19.449314) (xy 188.476054 -19.490287)
			(xy 188.395526 -19.523546) (xy 188.312131 -19.54877) (xy 188.22667 -19.565719) (xy 188.139961 -19.574229)
			(xy 188.096398 -19.574764) (xy 188.052087 -19.574162) (xy 187.963913 -19.565254) (xy 187.920376 -19.556984)
			(xy 187.910956 -19.555461) (xy 187.892172 -19.558738) (xy 187.875894 -19.568667) (xy 187.86983 -19.576034)
			(xy 187.841433 -19.61219) (xy 187.778327 -19.679054) (xy 187.708665 -19.739057) (xy 187.633189 -19.791561)
			(xy 187.593224 -19.814286) (xy 187.560557 -19.831903) (xy 187.492826 -19.862265) (xy 187.422797 -19.886867)
			(xy 187.386976 -19.896582) (xy 187.386722 -19.896582) (xy 187.375292 -19.89963) (xy 187.366656 -19.906742)
			(xy 187.362342 -19.91058) (xy 187.355414 -19.919813) (xy 187.35294 -19.92503) (xy 187.336938 -19.961352)
			(xy 187.320682 -19.997674) (xy 187.318497 -20.002991) (xy 187.316325 -20.014277) (xy 187.316364 -20.020026)
			(xy 187.316618 -20.031202) (xy 187.321952 -20.041616) (xy 187.339943 -20.077213) (xy 187.370231 -20.151006)
			(xy 187.393791 -20.227213) (xy 187.410432 -20.305224) (xy 187.420021 -20.384412) (xy 187.422481 -20.46414)
			(xy 187.417793 -20.543769) (xy 187.405994 -20.622657) (xy 187.387179 -20.700173) (xy 187.374784 -20.738084)
			(xy 187.371539 -20.74921) (xy 187.374361 -20.772188) (xy 187.386991 -20.79159) (xy 187.396628 -20.798028)
			(xy 187.420446 -20.812899) (xy 187.463839 -20.848532) (xy 187.501539 -20.890142) (xy 187.532731 -20.93683)
			(xy 187.556742 -20.987586) (xy 187.573052 -21.041313) (xy 187.581309 -21.096852) (xy 187.581794 -21.124926)
			(xy 187.581306 -21.152176) (xy 187.573546 -21.20612) (xy 187.558189 -21.258411) (xy 187.535546 -21.307984)
			(xy 187.506079 -21.35383) (xy 187.470387 -21.395016) (xy 187.429198 -21.430703) (xy 187.383348 -21.460165)
			(xy 187.333773 -21.482803) (xy 187.281481 -21.498155) (xy 187.227536 -21.505909) (xy 187.200286 -21.506434)
			(xy 187.171971 -21.505917) (xy 187.115965 -21.497542) (xy 187.061812 -21.480979) (xy 187.010702 -21.456592)
			(xy 186.963761 -21.424916) (xy 186.922018 -21.386648) (xy 186.886392 -21.342629) (xy 186.87161 -21.318474)
			(xy 186.86524 -21.308818) (xy 186.845961 -21.296073) (xy 186.823056 -21.292998) (xy 186.81192 -21.296122)
			(xy 186.793632 -21.301964) (xy 186.786092 -21.304617) (xy 186.773021 -21.313798) (xy 186.767978 -21.319998)
			(xy 186.746388 -21.348192) (xy 186.741308 -21.362924) (xy 186.741054 -21.370798) (xy 186.73955 -21.397328)
			(xy 186.730111 -21.449621) (xy 186.713505 -21.500098) (xy 186.690054 -21.547781) (xy 186.660212 -21.591748)
			(xy 186.624556 -21.631147) (xy 186.583776 -21.665216) (xy 186.538663 -21.693294) (xy 186.490089 -21.71484)
			(xy 186.438995 -21.729434) (xy 186.386369 -21.736796) (xy 186.3598 -21.73732) (xy 186.333321 -21.736868)
			(xy 186.28087 -21.729547) (xy 186.229935 -21.715046) (xy 186.181494 -21.693643) (xy 186.136476 -21.665749)
			(xy 186.095746 -21.6319) (xy 186.077606 -21.612606) (xy 186.071794 -21.606634) (xy 186.05728 -21.598468)
			(xy 186.049158 -21.596604) (xy 186.020202 -21.591524) (xy 186.011972 -21.590307) (xy 185.995511 -21.592639)
			(xy 185.987944 -21.596096) (xy 185.961038 -21.609137) (xy 185.904172 -21.627597) (xy 185.845118 -21.636936)
			(xy 185.815224 -21.637498) (xy 185.81497 -21.637498) (xy 185.788861 -21.637074) (xy 185.73713 -21.629958)
			(xy 185.686854 -21.615849) (xy 185.638973 -21.595011) (xy 185.594384 -21.567835) (xy 185.553921 -21.534827)
			(xy 185.51834 -21.496607) (xy 185.488308 -21.453889) (xy 185.464386 -21.407473) (xy 185.455306 -21.38299)
			(xy 185.452157 -21.375093) (xy 185.441518 -21.361846) (xy 185.434478 -21.357082) (xy 185.409586 -21.341334)
			(xy 185.401953 -21.336989) (xy 185.38481 -21.333227) (xy 185.376058 -21.333968) (xy 185.348111 -21.337301)
			(xy 185.291934 -21.340861) (xy 185.26379 -21.34108) (xy 185.26252 -21.34108) (xy 185.221417 -21.340621)
			(xy 185.139561 -21.333037) (xy 185.058754 -21.317933) (xy 184.979685 -21.295437) (xy 184.903029 -21.265742)
			(xy 184.829441 -21.229099) (xy 184.759547 -21.185824) (xy 184.693945 -21.136283) (xy 184.633194 -21.080901)
			(xy 184.577812 -21.020149) (xy 184.528272 -20.954546) (xy 184.484997 -20.884652) (xy 184.448355 -20.811063)
			(xy 184.41866 -20.734407) (xy 184.396165 -20.655339) (xy 184.381062 -20.574531) (xy 184.373479 -20.492675)
			(xy 184.373012 -20.451572) (xy 184.373493 -20.409722) (xy 184.381358 -20.326392) (xy 184.397015 -20.244169)
			(xy 184.420326 -20.163781) (xy 184.451086 -20.085937) (xy 184.489021 -20.011328) (xy 184.533796 -19.940611)
			(xy 184.585017 -19.874412) (xy 184.642228 -19.813318) (xy 184.704926 -19.757868) (xy 184.772555 -19.708552)
			(xy 184.844517 -19.665807) (xy 184.920176 -19.63001) (xy 184.998863 -19.601478) (xy 185.039254 -19.590512)
			(xy 185.050684 -19.587464) (xy 185.05932 -19.580352) (xy 185.063629 -19.57651) (xy 185.070546 -19.567272)
			(xy 185.073036 -19.562064) (xy 185.088784 -19.526504) (xy 185.11012 -19.478498) (xy 185.109612 -19.46529)
			(xy 185.09107 -19.428968) (xy 185.084052 -19.423733) (xy 185.06756 -19.417889) (xy 185.058812 -19.417538)
			(xy 185.040016 -19.421094) (xy 185.039762 -19.421094) (xy 185.00045 -19.436318) (xy 184.919577 -19.460142)
			(xy 184.836815 -19.476213) (xy 184.794906 -19.480784) (xy 184.774635 -19.482618) (xy 184.733979 -19.484653)
			(xy 184.713626 -19.484848) (xy 184.704228 -19.484848) (xy 184.648856 -19.482816) (xy 184.609706 -19.479725)
			(xy 184.532121 -19.46752) (xy 184.455913 -19.448527) (xy 184.381674 -19.422895) (xy 184.309982 -19.390823)
			(xy 184.275476 -19.372072) (xy 184.263538 -19.367246) (xy 184.251346 -19.364198) (xy 184.238392 -19.36242)
			(xy 183.460136 -19.36242) (xy 183.454619 -19.36259) (xy 183.443857 -19.365032) (xy 183.4388 -19.367246)
			(xy 183.420004 -19.375882) (xy 183.415256 -19.378247) (xy 183.406796 -19.384646) (xy 183.40324 -19.388582)
			(xy 183.375124 -19.420173) (xy 183.313839 -19.478459) (xy 183.247299 -19.530665) (xy 183.176105 -19.576321)
			(xy 183.100899 -19.615015) (xy 183.022361 -19.646396) (xy 182.941199 -19.670183) (xy 182.858146 -19.68616)
			(xy 182.773952 -19.694183) (xy 182.731664 -19.694652) (xy 182.688788 -19.694137) (xy 182.603435 -19.685882)
			(xy 182.519273 -19.669451) (xy 182.437082 -19.644998) (xy 182.357626 -19.612749) (xy 182.281641 -19.573003)
			(xy 182.209835 -19.52613) (xy 182.142872 -19.472565) (xy 182.081374 -19.412804) (xy 182.05323 -19.380454)
			(xy 182.052976 -19.3802) (xy 182.049371 -19.376185) (xy 182.040793 -19.369641) (xy 182.035958 -19.367246)
			(xy 182.025798 -19.36242) (xy 182.01132 -19.36242) (xy 182.006636 -19.36258) (xy 181.997438 -19.364377)
			(xy 181.993032 -19.365976) (xy 181.984904 -19.369024) (xy 181.977538 -19.375628) (xy 181.945046 -19.404333)
			(xy 181.875407 -19.455985) (xy 181.801076 -19.500621) (xy 181.722756 -19.537818) (xy 181.64119 -19.567222)
			(xy 181.557152 -19.588556) (xy 181.471437 -19.601616) (xy 181.384858 -19.60628) (xy 181.298237 -19.602503)
			(xy 181.212393 -19.59032) (xy 181.128141 -19.569848) (xy 181.046278 -19.54128) (xy 180.967582 -19.504888)
			(xy 180.892797 -19.461015) (xy 180.822633 -19.410078) (xy 180.789834 -19.381724) (xy 180.78323 -19.375628)
			(xy 180.758084 -19.365976) (xy 180.753691 -19.364329) (xy 180.744486 -19.362531) (xy 180.739796 -19.36242)
			(xy 176.002442 -19.36242) (xy 175.996433 -19.362588) (xy 175.984752 -19.365415) (xy 175.979328 -19.368008)
			(xy 175.975852 -19.369845) (xy 175.96947 -19.374435) (xy 175.966628 -19.377152) (xy 175.643032 -19.700748)
			(xy 175.640328 -19.703601) (xy 175.635741 -19.709982) (xy 175.633888 -19.713448) (xy 175.631306 -19.718875)
			(xy 175.628484 -19.730555) (xy 175.6283 -19.736562) (xy 175.6283 -21.5174) (xy 180.142143 -21.5174)
			(xy 180.146173 -21.432798) (xy 180.158227 -21.348962) (xy 180.178194 -21.266651) (xy 180.205896 -21.186611)
			(xy 180.241079 -21.109566) (xy 180.283427 -21.036214) (xy 180.332555 -20.96722) (xy 180.388019 -20.903208)
			(xy 180.449316 -20.844758) (xy 180.515892 -20.792399) (xy 180.587143 -20.746605) (xy 180.662424 -20.707791)
			(xy 180.741054 -20.676309) (xy 180.82232 -20.652443) (xy 180.905487 -20.636409) (xy 180.989801 -20.628354)
			(xy 181.03215 -20.627848) (xy 181.076289 -20.628376) (xy 181.164131 -20.637125) (xy 181.250676 -20.654532)
			(xy 181.33507 -20.680426) (xy 181.416484 -20.714552) (xy 181.494118 -20.756574) (xy 181.567208 -20.80608)
			(xy 181.635034 -20.862581) (xy 181.69693 -20.925524) (xy 181.752288 -20.994288) (xy 181.776878 -21.030946)
			(xy 181.79923 -21.030692) (xy 181.842297 -21.031181) (xy 181.928027 -21.039504) (xy 182.01255 -21.056077)
			(xy 182.095075 -21.080747) (xy 182.174827 -21.113282) (xy 182.25106 -21.153376) (xy 182.323058 -21.200654)
			(xy 182.390146 -21.254674) (xy 182.421276 -21.284438) (xy 182.429235 -21.291462) (xy 182.449096 -21.298886)
			(xy 182.470265 -21.297673) (xy 182.47995 -21.293328) (xy 182.517508 -21.274739) (xy 182.595429 -21.243882)
			(xy 182.675904 -21.220481) (xy 182.758221 -21.204745) (xy 182.841652 -21.196811) (xy 182.883556 -21.1963)
			(xy 182.884064 -21.1963) (xy 182.924109 -21.19676) (xy 183.003877 -21.203951) (xy 183.082675 -21.21828)
			(xy 183.159868 -21.239629) (xy 183.234831 -21.267826) (xy 183.306958 -21.302644) (xy 183.375665 -21.343801)
			(xy 183.440398 -21.390963) (xy 183.470804 -21.417026) (xy 183.477903 -21.422777) (xy 183.494953 -21.429297)
			(xy 183.504078 -21.429726) (xy 183.53405 -21.429726) (xy 183.543171 -21.429273) (xy 183.560221 -21.422766)
			(xy 183.567324 -21.417026) (xy 183.597713 -21.390939) (xy 183.662436 -21.343754) (xy 183.731139 -21.302581)
			(xy 183.803267 -21.267754) (xy 183.878235 -21.239554) (xy 183.955435 -21.218209) (xy 184.034241 -21.203894)
			(xy 184.114016 -21.196724) (xy 184.154064 -21.1963) (xy 184.195167 -21.196787) (xy 184.277022 -21.204368)
			(xy 184.357828 -21.219471) (xy 184.436897 -21.241965) (xy 184.513552 -21.271659) (xy 184.58714 -21.308299)
			(xy 184.657034 -21.351573) (xy 184.722636 -21.401112) (xy 184.783388 -21.456492) (xy 184.83877 -21.517242)
			(xy 184.888311 -21.582843) (xy 184.931587 -21.652735) (xy 184.96823 -21.726323) (xy 184.997926 -21.802977)
			(xy 185.020423 -21.882044) (xy 185.035528 -21.96285) (xy 185.043112 -22.044705) (xy 185.043572 -22.085808)
			(xy 185.0433 -22.115171) (xy 185.039358 -22.173766) (xy 185.035698 -22.202902) (xy 185.03488 -22.213572)
			(xy 185.040915 -22.234071) (xy 185.054756 -22.250353) (xy 185.064146 -22.25548) (xy 185.081672 -22.264624)
			(xy 185.091044 -22.269169) (xy 185.111774 -22.270994) (xy 185.121804 -22.26818) (xy 185.166593 -22.254138)
			(xy 185.25838 -22.234473) (xy 185.351729 -22.224589) (xy 185.398664 -22.223984) (xy 185.399172 -22.223984)
			(xy 185.440274 -22.224479) (xy 185.522129 -22.232061) (xy 185.602935 -22.247164) (xy 185.682002 -22.269658)
			(xy 185.758657 -22.299352) (xy 185.832244 -22.335992) (xy 185.902137 -22.379266) (xy 185.967739 -22.428804)
			(xy 186.028491 -22.484184) (xy 186.083873 -22.544933) (xy 186.133414 -22.610533) (xy 186.17669 -22.680424)
			(xy 186.213333 -22.75401) (xy 186.24303 -22.830664) (xy 186.265528 -22.90973) (xy 186.280634 -22.990535)
			(xy 186.288219 -23.07239) (xy 186.28868 -23.113492) (xy 186.288296 -23.150242) (xy 186.282191 -23.223489)
			(xy 186.276488 -23.259796) (xy 186.273948 -23.274528) (xy 186.285632 -23.301706) (xy 186.386724 -23.37054)
			(xy 186.416188 -23.371302) (xy 186.428888 -23.363682) (xy 186.463409 -23.34352) (xy 186.535417 -23.308779)
			(xy 186.610254 -23.280645) (xy 186.687314 -23.259345) (xy 186.765977 -23.245051) (xy 186.845605 -23.237878)
			(xy 186.88558 -23.237444) (xy 186.885834 -23.237444) (xy 186.920378 -23.238206) (xy 186.930792 -23.23846)
			(xy 186.950096 -23.231094) (xy 187.017914 -23.165308) (xy 187.025788 -23.146258) (xy 187.025788 -23.127208)
			(xy 187.026267 -23.085282) (xy 187.034158 -23.001803) (xy 187.049869 -22.919436) (xy 187.073262 -22.838914)
			(xy 187.10413 -22.76095) (xy 187.142197 -22.686237) (xy 187.187126 -22.615439) (xy 187.238519 -22.549183)
			(xy 187.295919 -22.488057) (xy 187.358817 -22.432605) (xy 187.426654 -22.383317) (xy 187.498828 -22.340633)
			(xy 187.574699 -22.30493) (xy 187.653594 -22.276526) (xy 187.734811 -22.255673) (xy 187.81763 -22.242555)
			(xy 187.901316 -22.237289) (xy 187.985126 -22.239923) (xy 188.068317 -22.250432) (xy 188.150149 -22.268723)
			(xy 188.229897 -22.294635) (xy 188.306852 -22.327936) (xy 188.380332 -22.368331) (xy 188.449684 -22.415463)
			(xy 188.514293 -22.468912) (xy 188.573586 -22.528204) (xy 188.627035 -22.592812) (xy 188.674166 -22.662164)
			(xy 188.714562 -22.735644) (xy 188.747864 -22.812599) (xy 188.773776 -22.892347) (xy 188.792067 -22.974179)
			(xy 188.802577 -23.05737) (xy 188.805211 -23.14118) (xy 188.799946 -23.224866) (xy 188.786828 -23.307685)
			(xy 188.765975 -23.388903) (xy 188.737571 -23.467797) (xy 188.701869 -23.543668) (xy 188.659185 -23.615843)
			(xy 188.609898 -23.68368) (xy 188.554446 -23.746578) (xy 188.49332 -23.803978) (xy 188.427064 -23.855371)
			(xy 188.356266 -23.900301) (xy 188.281554 -23.938369) (xy 188.20359 -23.969236) (xy 188.123068 -23.99263)
			(xy 188.040701 -24.008342) (xy 187.957222 -24.016233) (xy 187.915296 -24.016716) (xy 187.880752 -24.015954)
			(xy 187.870338 -24.0157) (xy 187.851034 -24.023066) (xy 187.783216 -24.088852) (xy 187.775342 -24.107902)
			(xy 187.775342 -24.126952) (xy 187.774838 -24.169236) (xy 187.766815 -24.253422) (xy 187.750838 -24.336467)
			(xy 187.727051 -24.41762) (xy 187.695668 -24.496149) (xy 187.656972 -24.571344) (xy 187.611314 -24.642527)
			(xy 187.585604 -24.6761) (xy 187.579508 -24.68372) (xy 187.57392 -24.70277) (xy 187.583826 -24.793194)
			(xy 187.592716 -24.810212) (xy 187.60059 -24.816816) (xy 187.621673 -24.835055) (xy 187.658873 -24.876571)
			(xy 187.689634 -24.92306) (xy 187.7133 -24.973532) (xy 187.729366 -25.026911) (xy 187.737491 -25.08206)
			(xy 187.738004 -25.109932) (xy 187.73745 -25.139352) (xy 187.728408 -25.197492) (xy 187.710528 -25.253548)
			(xy 187.697872 -25.280112) (xy 187.693458 -25.290213) (xy 187.692716 -25.312215) (xy 187.701275 -25.332497)
			(xy 187.709048 -25.34031) (xy 187.739037 -25.368336) (xy 187.794291 -25.429044) (xy 187.843714 -25.494587)
			(xy 187.886886 -25.564405) (xy 187.923439 -25.637906) (xy 187.953062 -25.714463) (xy 187.975502 -25.793424)
			(xy 187.99057 -25.874117) (xy 187.998136 -25.955856) (xy 187.998608 -25.9969) (xy 187.998104 -26.039248)
			(xy 187.990053 -26.123562) (xy 187.974024 -26.206728) (xy 187.950163 -26.287995) (xy 187.918684 -26.366625)
			(xy 187.879873 -26.441906) (xy 187.834083 -26.513158) (xy 187.781727 -26.579734) (xy 187.723279 -26.641032)
			(xy 187.659269 -26.696497) (xy 187.590277 -26.745626) (xy 187.516927 -26.787975) (xy 187.439884 -26.823159)
			(xy 187.359845 -26.850861) (xy 187.277536 -26.870829) (xy 187.193701 -26.882882) (xy 187.1091 -26.886913)
			(xy 187.024499 -26.882882) (xy 186.940664 -26.870829) (xy 186.858355 -26.850861) (xy 186.778316 -26.823159)
			(xy 186.701273 -26.787975) (xy 186.627923 -26.745626) (xy 186.558931 -26.696497) (xy 186.494921 -26.641032)
			(xy 186.436473 -26.579734) (xy 186.384117 -26.513158) (xy 186.338327 -26.441906) (xy 186.299516 -26.366625)
			(xy 186.268037 -26.287995) (xy 186.244176 -26.206728) (xy 186.228147 -26.123562) (xy 186.220096 -26.039248)
			(xy 186.219592 -25.9969) (xy 186.219592 -25.996646) (xy 186.220074 -25.954732) (xy 186.227973 -25.871276)
			(xy 186.243686 -25.788933) (xy 186.267073 -25.708433) (xy 186.297928 -25.63049) (xy 186.335977 -25.555794)
			(xy 186.358022 -25.520142) (xy 186.363102 -25.512268) (xy 186.366912 -25.493726) (xy 186.35345 -25.416764)
			(xy 186.351444 -25.407716) (xy 186.341928 -25.391828) (xy 186.334908 -25.385776) (xy 186.334654 -25.385522)
			(xy 186.312171 -25.36733) (xy 186.272438 -25.325309) (xy 186.239501 -25.277774) (xy 186.214112 -25.225813)
			(xy 186.196855 -25.170616) (xy 186.188124 -25.113448) (xy 186.187588 -25.084532) (xy 186.1882 -25.053635)
			(xy 186.198154 -24.992649) (xy 186.217807 -24.934064) (xy 186.246646 -24.879413) (xy 186.264804 -24.854408)
			(xy 186.269986 -24.847053) (xy 186.275316 -24.829878) (xy 186.275218 -24.82088) (xy 186.27344 -24.7904)
			(xy 186.272419 -24.781154) (xy 186.264751 -24.764225) (xy 186.258454 -24.75738) (xy 186.227759 -24.726121)
			(xy 186.172017 -24.658528) (xy 186.123193 -24.585779) (xy 186.081763 -24.508581) (xy 186.048126 -24.427682)
			(xy 186.02261 -24.343866) (xy 186.005463 -24.257947) (xy 185.996849 -24.170759) (xy 185.996326 -24.126952)
			(xy 185.996716 -24.090202) (xy 186.002817 -24.016955) (xy 186.008518 -23.980648) (xy 186.011058 -23.965916)
			(xy 185.999374 -23.938738) (xy 185.898282 -23.869904) (xy 185.868818 -23.869142) (xy 185.856118 -23.876762)
			(xy 185.821592 -23.896916) (xy 185.749586 -23.931659) (xy 185.67475 -23.959795) (xy 185.59769 -23.981097)
			(xy 185.519029 -23.995392) (xy 185.439401 -24.002565) (xy 185.399426 -24.003) (xy 185.399172 -24.003)
			(xy 185.358069 -24.00256) (xy 185.276213 -23.994973) (xy 185.195407 -23.979865) (xy 185.116339 -23.957366)
			(xy 185.039685 -23.927667) (xy 184.966098 -23.891023) (xy 184.896206 -23.847745) (xy 184.830605 -23.798203)
			(xy 184.769854 -23.74282) (xy 184.714474 -23.682068) (xy 184.664934 -23.616465) (xy 184.621659 -23.546571)
			(xy 184.585018 -23.472982) (xy 184.555323 -23.396326) (xy 184.532827 -23.317258) (xy 184.517722 -23.236451)
			(xy 184.510138 -23.154595) (xy 184.509664 -23.113492) (xy 184.50974 -23.097666) (xy 184.510885 -23.066036)
			(xy 184.51195 -23.050246) (xy 184.512712 -23.038054) (xy 184.50306 -23.015702) (xy 184.429908 -22.954996)
			(xy 184.420031 -22.947781) (xy 184.396163 -22.942603) (xy 184.384188 -22.94509) (xy 184.346683 -22.954704)
			(xy 184.270425 -22.968139) (xy 184.193288 -22.974889) (xy 184.154572 -22.975316) (xy 184.154064 -22.975316)
			(xy 184.114018 -22.97486) (xy 184.03425 -22.96767) (xy 183.955451 -22.953343) (xy 183.878258 -22.931994)
			(xy 183.803294 -22.903796) (xy 183.731168 -22.868977) (xy 183.662461 -22.827819) (xy 183.59773 -22.780654)
			(xy 183.567324 -22.75459) (xy 183.560245 -22.748811) (xy 183.54318 -22.742307) (xy 183.53405 -22.74189)
			(xy 183.504078 -22.74189) (xy 183.494958 -22.742353) (xy 183.477907 -22.748853) (xy 183.470804 -22.75459)
			(xy 183.440406 -22.780666) (xy 183.375685 -22.827851) (xy 183.306982 -22.869025) (xy 183.234856 -22.903854)
			(xy 183.15989 -22.932055) (xy 183.082691 -22.953401) (xy 183.003885 -22.967718) (xy 182.924112 -22.974891)
			(xy 182.884064 -22.975316) (xy 182.840997 -22.974829) (xy 182.755267 -22.966506) (xy 182.670744 -22.949931)
			(xy 182.588219 -22.925261) (xy 182.508467 -22.892726) (xy 182.432234 -22.852632) (xy 182.360236 -22.805354)
			(xy 182.293148 -22.751334) (xy 182.262018 -22.72157) (xy 182.254062 -22.714542) (xy 182.234199 -22.707118)
			(xy 182.213029 -22.708333) (xy 182.203344 -22.71268) (xy 182.165787 -22.731272) (xy 182.087866 -22.762128)
			(xy 182.007391 -22.785528) (xy 181.925073 -22.801264) (xy 181.841642 -22.809197) (xy 181.799738 -22.809708)
			(xy 181.79923 -22.809708) (xy 181.755092 -22.809137) (xy 181.66725 -22.800395) (xy 181.580707 -22.782995)
			(xy 181.496312 -22.757107) (xy 181.414898 -22.722987) (xy 181.337263 -22.680969) (xy 181.264173 -22.631467)
			(xy 181.196346 -22.574969) (xy 181.134449 -22.512029) (xy 181.079092 -22.443267) (xy 181.054502 -22.40661)
			(xy 181.03215 -22.406864) (xy 180.989801 -22.406446) (xy 180.905487 -22.398391) (xy 180.82232 -22.382357)
			(xy 180.741054 -22.358491) (xy 180.662424 -22.327009) (xy 180.587143 -22.288195) (xy 180.515892 -22.242401)
			(xy 180.449316 -22.190042) (xy 180.388019 -22.131592) (xy 180.332555 -22.06758) (xy 180.283427 -21.998586)
			(xy 180.241079 -21.925234) (xy 180.205896 -21.848189) (xy 180.178194 -21.768149) (xy 180.158227 -21.685838)
			(xy 180.146173 -21.602002) (xy 180.142143 -21.5174) (xy 175.6283 -21.5174) (xy 175.6283 -24.91486)
			(xy 185.012582 -24.91486) (xy 185.016653 -24.859238) (xy 185.028779 -24.804801) (xy 185.048702 -24.75271)
			(xy 185.075998 -24.704075) (xy 185.110084 -24.659932) (xy 185.150233 -24.621223) (xy 185.195591 -24.588772)
			(xy 185.245191 -24.563271) (xy 185.297975 -24.545264) (xy 185.352818 -24.535134) (xy 185.408552 -24.533097)
			(xy 185.463989 -24.539197) (xy 185.517946 -24.553303) (xy 185.569275 -24.575115) (xy 185.616881 -24.604169)
			(xy 185.659749 -24.639844) (xy 185.696966 -24.681381) (xy 185.727739 -24.727894) (xy 185.751411 -24.778391)
			(xy 185.767479 -24.831798) (xy 185.775599 -24.886974) (xy 185.776108 -24.91486) (xy 185.775599 -24.942746)
			(xy 185.767479 -24.997922) (xy 185.751411 -25.051329) (xy 185.727739 -25.101826) (xy 185.696966 -25.148339)
			(xy 185.659749 -25.189876) (xy 185.616881 -25.225551) (xy 185.569275 -25.254605) (xy 185.517946 -25.276417)
			(xy 185.463989 -25.290523) (xy 185.408552 -25.296623) (xy 185.352818 -25.294586) (xy 185.297975 -25.284456)
			(xy 185.245191 -25.266449) (xy 185.195591 -25.240948) (xy 185.150233 -25.208497) (xy 185.110084 -25.169788)
			(xy 185.075998 -25.125645) (xy 185.048702 -25.07701) (xy 185.028779 -25.024919) (xy 185.016653 -24.970482)
			(xy 185.012582 -24.91486) (xy 175.6283 -24.91486) (xy 175.6283 -25.92324) (xy 180.826662 -25.92324)
			(xy 180.830733 -25.867618) (xy 180.842859 -25.813181) (xy 180.862782 -25.76109) (xy 180.890078 -25.712455)
			(xy 180.924164 -25.668312) (xy 180.964313 -25.629603) (xy 181.009671 -25.597152) (xy 181.059271 -25.571651)
			(xy 181.112055 -25.553644) (xy 181.166898 -25.543514) (xy 181.222632 -25.541477) (xy 181.278069 -25.547577)
			(xy 181.332026 -25.561683) (xy 181.383355 -25.583495) (xy 181.430961 -25.612549) (xy 181.473829 -25.648224)
			(xy 181.511046 -25.689761) (xy 181.541819 -25.736274) (xy 181.565491 -25.786771) (xy 181.581559 -25.840178)
			(xy 181.589679 -25.895354) (xy 181.589812 -25.902666) (xy 184.526426 -25.902666) (xy 184.530497 -25.847044)
			(xy 184.542623 -25.792607) (xy 184.562546 -25.740516) (xy 184.589842 -25.691881) (xy 184.623928 -25.647738)
			(xy 184.664077 -25.609029) (xy 184.709435 -25.576578) (xy 184.759035 -25.551077) (xy 184.811819 -25.53307)
			(xy 184.866662 -25.52294) (xy 184.922396 -25.520903) (xy 184.977833 -25.527003) (xy 185.03179 -25.541109)
			(xy 185.083119 -25.562921) (xy 185.130725 -25.591975) (xy 185.173593 -25.62765) (xy 185.21081 -25.669187)
			(xy 185.241583 -25.7157) (xy 185.265255 -25.766197) (xy 185.281323 -25.819604) (xy 185.289443 -25.87478)
			(xy 185.289952 -25.902666) (xy 185.289443 -25.930552) (xy 185.281323 -25.985728) (xy 185.265255 -26.039135)
			(xy 185.241583 -26.089632) (xy 185.21081 -26.136145) (xy 185.173593 -26.177682) (xy 185.130725 -26.213357)
			(xy 185.083119 -26.242411) (xy 185.03179 -26.264223) (xy 184.977833 -26.278329) (xy 184.922396 -26.284429)
			(xy 184.866662 -26.282392) (xy 184.811819 -26.272262) (xy 184.759035 -26.254255) (xy 184.709435 -26.228754)
			(xy 184.664077 -26.196303) (xy 184.623928 -26.157594) (xy 184.589842 -26.113451) (xy 184.562546 -26.064816)
			(xy 184.542623 -26.012725) (xy 184.530497 -25.958288) (xy 184.526426 -25.902666) (xy 181.589812 -25.902666)
			(xy 181.590188 -25.92324) (xy 181.589679 -25.951126) (xy 181.581559 -26.006302) (xy 181.565491 -26.059709)
			(xy 181.541819 -26.110206) (xy 181.511046 -26.156719) (xy 181.473829 -26.198256) (xy 181.430961 -26.233931)
			(xy 181.383355 -26.262985) (xy 181.332026 -26.284797) (xy 181.278069 -26.298903) (xy 181.222632 -26.305003)
			(xy 181.166898 -26.302966) (xy 181.112055 -26.292836) (xy 181.059271 -26.274829) (xy 181.009671 -26.249328)
			(xy 180.964313 -26.216877) (xy 180.924164 -26.178168) (xy 180.890078 -26.134025) (xy 180.862782 -26.08539)
			(xy 180.842859 -26.033299) (xy 180.830733 -25.978862) (xy 180.826662 -25.92324) (xy 175.6283 -25.92324)
			(xy 175.6283 -27.441398) (xy 175.629316 -27.45105) (xy 175.630943 -27.458295) (xy 175.637782 -27.471465)
			(xy 175.642778 -27.476958) (xy 175.850042 -27.684222) (xy 175.855543 -27.689206) (xy 175.86871 -27.696043)
			(xy 175.87595 -27.697684) (xy 175.885602 -27.6987) (xy 184.597548 -27.6987) (xy 184.607815 -27.69817)
			(xy 184.626677 -27.69004) (xy 184.634124 -27.682952) (xy 184.684924 -27.629866) (xy 184.688324 -27.626117)
			(xy 184.693694 -27.61754) (xy 184.695592 -27.612848) (xy 184.699402 -27.603196) (xy 184.698894 -27.592782)
			(xy 184.698132 -27.554936) (xy 184.698643 -27.512059) (xy 184.70689 -27.426702) (xy 184.723311 -27.342535)
			(xy 184.747754 -27.260338) (xy 184.76341 -27.220418) (xy 184.764426 -27.217878) (xy 184.766412 -27.211468)
			(xy 184.767309 -27.198082) (xy 184.766204 -27.191462) (xy 184.763918 -27.183334) (xy 184.752996 -27.154886)
			(xy 184.749673 -27.147142) (xy 184.738904 -27.134195) (xy 184.731914 -27.129486) (xy 184.709077 -27.117053)
			(xy 184.666692 -27.086935) (xy 184.628787 -27.051344) (xy 184.596061 -27.010939) (xy 184.569122 -26.966466)
			(xy 184.548466 -26.918748) (xy 184.534477 -26.86867) (xy 184.527414 -26.817156) (xy 184.526936 -26.791158)
			(xy 184.527402 -26.763908) (xy 184.535164 -26.709964) (xy 184.550524 -26.657674) (xy 184.57317 -26.608102)
			(xy 184.60264 -26.562257) (xy 184.638334 -26.521073) (xy 184.679526 -26.485388) (xy 184.725377 -26.455929)
			(xy 184.774955 -26.433294) (xy 184.827248 -26.417946) (xy 184.881194 -26.410196) (xy 184.908444 -26.40965)
			(xy 184.937041 -26.410157) (xy 184.993595 -26.41869) (xy 185.04824 -26.435572) (xy 185.099751 -26.460426)
			(xy 185.146973 -26.492694) (xy 185.188847 -26.531652) (xy 185.224434 -26.576426) (xy 185.252935 -26.626013)
			(xy 185.26379 -26.652474) (xy 185.264806 -26.655268) (xy 185.268735 -26.662789) (xy 185.280529 -26.674975)
			(xy 185.28792 -26.679144) (xy 185.315098 -26.693368) (xy 185.320704 -26.696019) (xy 185.332774 -26.698849)
			(xy 185.338974 -26.698956) (xy 185.351674 -26.697178) (xy 185.351928 -26.697178) (xy 185.390351 -26.687087)
			(xy 185.468533 -26.672971) (xy 185.547663 -26.665876) (xy 185.587386 -26.665428) (xy 185.590942 -26.665428)
			(xy 185.631944 -26.666052) (xy 185.713575 -26.673908) (xy 185.794136 -26.689244) (xy 185.872943 -26.711931)
			(xy 185.949327 -26.741776) (xy 186.02264 -26.778526) (xy 186.092259 -26.821868) (xy 186.157592 -26.871434)
			(xy 186.218086 -26.926804) (xy 186.273226 -26.987507) (xy 186.322544 -27.053029) (xy 186.365621 -27.122811)
			(xy 186.402092 -27.196263) (xy 186.431646 -27.27276) (xy 186.454034 -27.351653) (xy 186.469064 -27.432272)
			(xy 186.47661 -27.513932) (xy 186.477148 -27.554936) (xy 186.476692 -27.595692) (xy 186.470528 -27.662816)
			(xy 187.403482 -27.662816) (xy 187.403482 -27.57812) (xy 187.411533 -27.493806) (xy 187.427562 -27.41064)
			(xy 187.451423 -27.329373) (xy 187.482902 -27.250743) (xy 187.521713 -27.175462) (xy 187.567503 -27.10421)
			(xy 187.619859 -27.037634) (xy 187.678307 -26.976336) (xy 187.742317 -26.920871) (xy 187.811309 -26.871742)
			(xy 187.884659 -26.829393) (xy 187.961702 -26.794209) (xy 188.041741 -26.766507) (xy 188.12405 -26.746539)
			(xy 188.207885 -26.734486) (xy 188.292486 -26.730456) (xy 188.377087 -26.734486) (xy 188.460922 -26.746539)
			(xy 188.543231 -26.766507) (xy 188.62327 -26.794209) (xy 188.700313 -26.829393) (xy 188.773663 -26.871742)
			(xy 188.842655 -26.920871) (xy 188.906665 -26.976336) (xy 188.965113 -27.037634) (xy 189.017469 -27.10421)
			(xy 189.063259 -27.175462) (xy 189.10207 -27.250743) (xy 189.133549 -27.329373) (xy 189.15741 -27.41064)
			(xy 189.173439 -27.493806) (xy 189.18149 -27.57812) (xy 189.181994 -27.620468) (xy 189.18149 -27.662816)
			(xy 189.173439 -27.74713) (xy 189.15741 -27.830296) (xy 189.133549 -27.911563) (xy 189.10207 -27.990193)
			(xy 189.063259 -28.065474) (xy 189.017469 -28.136726) (xy 188.965113 -28.203302) (xy 188.906665 -28.2646)
			(xy 188.842655 -28.320065) (xy 188.773663 -28.369194) (xy 188.700313 -28.411543) (xy 188.62327 -28.446727)
			(xy 188.543231 -28.474429) (xy 188.460922 -28.494397) (xy 188.377087 -28.50645) (xy 188.292486 -28.510481)
			(xy 188.207885 -28.50645) (xy 188.12405 -28.494397) (xy 188.041741 -28.474429) (xy 187.961702 -28.446727)
			(xy 187.884659 -28.411543) (xy 187.811309 -28.369194) (xy 187.742317 -28.320065) (xy 187.678307 -28.2646)
			(xy 187.619859 -28.203302) (xy 187.567503 -28.136726) (xy 187.521713 -28.065474) (xy 187.482902 -27.990193)
			(xy 187.451423 -27.911563) (xy 187.427562 -27.830296) (xy 187.411533 -27.74713) (xy 187.403482 -27.662816)
			(xy 186.470528 -27.662816) (xy 186.469238 -27.676863) (xy 186.454386 -27.757011) (xy 186.432262 -27.835463)
			(xy 186.403051 -27.911562) (xy 186.366998 -27.984667) (xy 186.324405 -28.054167) (xy 186.275631 -28.119476)
			(xy 186.221084 -28.180048) (xy 186.161223 -28.235373) (xy 186.129168 -28.260548) (xy 186.128914 -28.260802)
			(xy 186.124745 -28.264181) (xy 186.117816 -28.272374) (xy 186.115198 -28.277058) (xy 186.110118 -28.286456)
			(xy 186.104276 -28.373832) (xy 186.104276 -28.375356) (xy 186.104307 -28.38508) (xy 186.110831 -28.403381)
			(xy 186.116976 -28.410916) (xy 186.117738 -28.411678) (xy 186.118754 -28.412694) (xy 186.151012 -28.444952)
			(xy 186.494418 -28.444952) (xy 186.498489 -28.38933) (xy 186.510615 -28.334893) (xy 186.530538 -28.282802)
			(xy 186.557834 -28.234167) (xy 186.59192 -28.190024) (xy 186.632069 -28.151315) (xy 186.677427 -28.118864)
			(xy 186.727027 -28.093363) (xy 186.779811 -28.075356) (xy 186.834654 -28.065226) (xy 186.890388 -28.063189)
			(xy 186.945825 -28.069289) (xy 186.999782 -28.083395) (xy 187.051111 -28.105207) (xy 187.098717 -28.134261)
			(xy 187.141585 -28.169936) (xy 187.178802 -28.211473) (xy 187.209575 -28.257986) (xy 187.233247 -28.308483)
			(xy 187.249315 -28.36189) (xy 187.257435 -28.417066) (xy 187.257944 -28.444952) (xy 187.257435 -28.472838)
			(xy 187.249315 -28.528014) (xy 187.233247 -28.581421) (xy 187.209575 -28.631918) (xy 187.178802 -28.678431)
			(xy 187.141585 -28.719968) (xy 187.098717 -28.755643) (xy 187.051111 -28.784697) (xy 186.999782 -28.806509)
			(xy 186.945825 -28.820615) (xy 186.890388 -28.826715) (xy 186.834654 -28.824678) (xy 186.779811 -28.814548)
			(xy 186.727027 -28.796541) (xy 186.677427 -28.77104) (xy 186.632069 -28.738589) (xy 186.59192 -28.69988)
			(xy 186.557834 -28.655737) (xy 186.530538 -28.607102) (xy 186.510615 -28.555011) (xy 186.498489 -28.500574)
			(xy 186.494418 -28.444952) (xy 186.151012 -28.444952) (xy 187.243212 -29.537152) (xy 189.111128 -29.537152)
			(xy 189.111621 -29.493347) (xy 189.120216 -29.406158) (xy 189.137337 -29.320237) (xy 189.162819 -29.236413)
			(xy 189.196415 -29.1555) (xy 189.237799 -29.07828) (xy 189.26175 -29.041598) (xy 189.266482 -29.033917)
			(xy 189.270797 -29.016416) (xy 189.26878 -28.998503) (xy 189.265052 -28.99029) (xy 189.24661 -28.95285)
			(xy 189.215994 -28.875201) (xy 189.19278 -28.795029) (xy 189.17717 -28.713035) (xy 189.169302 -28.629941)
			(xy 189.168786 -28.588208) (xy 189.169286 -28.545261) (xy 189.177583 -28.459767) (xy 189.194081 -28.375472)
			(xy 189.218628 -28.293159) (xy 189.250993 -28.213594) (xy 189.290876 -28.13752) (xy 189.337906 -28.065644)
			(xy 189.391644 -27.998636) (xy 189.451591 -27.937118) (xy 189.517187 -27.881665) (xy 189.587823 -27.832793)
			(xy 189.662841 -27.790955) (xy 189.741541 -27.756543) (xy 189.823192 -27.729877) (xy 189.865 -27.720036)
			(xy 189.865254 -27.720036) (xy 189.877044 -27.716656) (xy 189.895758 -27.700865) (xy 189.901068 -27.68981)
			(xy 189.932564 -27.612848) (xy 189.936551 -27.601247) (xy 189.934439 -27.576845) (xy 189.9285 -27.566112)
			(xy 189.906202 -27.530325) (xy 189.867734 -27.455284) (xy 189.836538 -27.37694) (xy 189.812894 -27.295997)
			(xy 189.797013 -27.213179) (xy 189.789039 -27.129231) (xy 189.788546 -27.087068) (xy 189.789036 -27.045966)
			(xy 189.796623 -26.964114) (xy 189.81173 -26.883311) (xy 189.834228 -26.804246) (xy 189.863924 -26.727594)
			(xy 189.900566 -26.654009) (xy 189.943841 -26.584118) (xy 189.99338 -26.518519) (xy 190.048759 -26.457769)
			(xy 190.109508 -26.402389) (xy 190.175107 -26.352849) (xy 190.244997 -26.309573) (xy 190.318581 -26.27293)
			(xy 190.395232 -26.243232) (xy 190.474297 -26.220733) (xy 190.5551 -26.205625) (xy 190.636952 -26.198037)
			(xy 190.678054 -26.19756) (xy 190.720717 -26.198041) (xy 190.805649 -26.206222) (xy 190.889408 -26.222494)
			(xy 190.971225 -26.246708) (xy 191.050349 -26.278641) (xy 191.126054 -26.318001) (xy 191.197644 -26.364425)
			(xy 191.264463 -26.417488) (xy 191.295528 -26.446734) (xy 191.302386 -26.453338) (xy 191.319404 -26.46045)
			(xy 191.397128 -26.46299) (xy 191.406364 -26.462904) (xy 191.423818 -26.456905) (xy 191.431164 -26.451306)
			(xy 191.431418 -26.451306) (xy 191.452115 -26.434429) (xy 191.497363 -26.406064) (xy 191.546127 -26.384292)
			(xy 191.597452 -26.369537) (xy 191.650334 -26.362089) (xy 191.677036 -26.361644) (xy 191.704286 -26.362144)
			(xy 191.758231 -26.369904) (xy 191.810522 -26.385262) (xy 191.860096 -26.407903) (xy 191.905944 -26.437369)
			(xy 191.947133 -26.473059) (xy 191.982824 -26.514246) (xy 192.012291 -26.560093) (xy 192.034934 -26.609667)
			(xy 192.050293 -26.661958) (xy 192.058055 -26.715902) (xy 192.058544 -26.743152) (xy 192.058013 -26.772069)
			(xy 192.049289 -26.82924) (xy 192.032035 -26.88444) (xy 192.006646 -26.936402) (xy 191.973704 -26.983936)
			(xy 191.933963 -27.025952) (xy 191.911478 -27.044142) (xy 191.902658 -27.051737) (xy 191.892482 -27.072647)
			(xy 191.89192 -27.084274) (xy 191.89192 -27.16403) (xy 191.892449 -27.175663) (xy 191.902644 -27.196573)
			(xy 191.911478 -27.204162) (xy 191.933939 -27.22238) (xy 191.973676 -27.264393) (xy 192.006619 -27.311923)
			(xy 192.032011 -27.363879) (xy 192.049272 -27.419072) (xy 192.058006 -27.476237) (xy 192.058544 -27.505152)
			(xy 192.058068 -27.533124) (xy 192.049903 -27.588468) (xy 192.042288 -27.615388) (xy 192.038224 -27.62885)
			(xy 192.044828 -27.655774) (xy 192.118234 -27.729434) (xy 192.12497 -27.735567) (xy 192.141538 -27.743102)
			(xy 192.159695 -27.744361) (xy 192.168526 -27.742134) (xy 192.16878 -27.742134) (xy 192.198438 -27.733514)
			(xy 192.258691 -27.719911) (xy 192.289176 -27.714956) (xy 192.302384 -27.712924) (xy 192.322704 -27.697176)
			(xy 192.367408 -27.593544) (xy 192.364614 -27.567382) (xy 192.357248 -27.556714) (xy 192.332215 -27.519514)
			(xy 192.28892 -27.440989) (xy 192.253744 -27.358507) (xy 192.227045 -27.272904) (xy 192.209094 -27.18505)
			(xy 192.200072 -27.095835) (xy 192.199514 -27.051) (xy 192.199982 -27.010333) (xy 192.207429 -26.929341)
			(xy 192.222233 -26.849365) (xy 192.244271 -26.771074) (xy 192.273359 -26.695119) (xy 192.309255 -26.622135)
			(xy 192.33007 -26.587196) (xy 192.335715 -26.576483) (xy 192.337453 -26.552367) (xy 192.333372 -26.540968)
			(xy 192.29578 -26.453338) (xy 192.276984 -26.43759) (xy 192.265046 -26.43505) (xy 192.223042 -26.425377)
			(xy 192.140986 -26.39897) (xy 192.061869 -26.364749) (xy 191.986432 -26.323036) (xy 191.915385 -26.274222)
			(xy 191.849391 -26.218766) (xy 191.789071 -26.157186) (xy 191.73499 -26.090061) (xy 191.687655 -26.018019)
			(xy 191.64751 -25.941737) (xy 191.614932 -25.861929) (xy 191.590225 -25.779345) (xy 191.573622 -25.694758)
			(xy 191.565279 -25.608962) (xy 191.564768 -25.565862) (xy 191.564768 -25.565354) (xy 191.564915 -25.541495)
			(xy 191.567456 -25.493844) (xy 191.569848 -25.470104) (xy 191.570467 -25.46091) (xy 191.56592 -25.44307)
			(xy 191.560958 -25.435306) (xy 191.543686 -25.410922) (xy 191.537998 -25.40362) (xy 191.522633 -25.393328)
			(xy 191.513714 -25.390856) (xy 191.472279 -25.380688) (xy 191.391394 -25.353535) (xy 191.313481 -25.31876)
			(xy 191.239256 -25.276683) (xy 191.169403 -25.227691) (xy 191.104563 -25.172233) (xy 191.045332 -25.110821)
			(xy 190.992255 -25.044019) (xy 190.94582 -24.97244) (xy 190.906454 -24.896743) (xy 190.874519 -24.817623)
			(xy 190.850308 -24.735809) (xy 190.834043 -24.652052) (xy 190.825875 -24.567123) (xy 190.825374 -24.524462)
			(xy 190.825916 -24.482795) (xy 190.833705 -24.399827) (xy 190.84922 -24.31795) (xy 190.872325 -24.237884)
			(xy 190.902819 -24.16033) (xy 190.940432 -24.085968) (xy 190.984836 -24.01545) (xy 191.035641 -23.949395)
			(xy 191.092402 -23.888382) (xy 191.154621 -23.832945) (xy 191.221752 -23.78357) (xy 191.293208 -23.740692)
			(xy 191.368361 -23.704684) (xy 191.407288 -23.689818) (xy 191.416178 -23.686516) (xy 191.430402 -23.673816)
			(xy 191.470534 -23.59533) (xy 191.472312 -23.576026) (xy 191.469772 -23.566882) (xy 191.459113 -23.527516)
			(xy 191.444204 -23.447327) (xy 191.436712 -23.366109) (xy 191.436244 -23.325328) (xy 191.436244 -23.324566)
			(xy 191.436748 -23.282218) (xy 191.444799 -23.197904) (xy 191.460828 -23.114738) (xy 191.484689 -23.033471)
			(xy 191.516168 -22.954841) (xy 191.554979 -22.87956) (xy 191.600769 -22.808308) (xy 191.653125 -22.741732)
			(xy 191.711573 -22.680434) (xy 191.775583 -22.624969) (xy 191.844575 -22.57584) (xy 191.917925 -22.533491)
			(xy 191.994968 -22.498307) (xy 192.075007 -22.470605) (xy 192.157316 -22.450637) (xy 192.241151 -22.438584)
			(xy 192.325752 -22.434554) (xy 192.410353 -22.438584) (xy 192.494188 -22.450637) (xy 192.576497 -22.470605)
			(xy 192.656536 -22.498307) (xy 192.733579 -22.533491) (xy 192.806929 -22.57584) (xy 192.875921 -22.624969)
			(xy 192.939931 -22.680434) (xy 192.998379 -22.741732) (xy 193.050735 -22.808308) (xy 193.096525 -22.87956)
			(xy 193.135336 -22.954841) (xy 193.166815 -23.033471) (xy 193.190676 -23.114738) (xy 193.206705 -23.197904)
			(xy 193.214756 -23.282218) (xy 193.21526 -23.324566) (xy 193.21526 -23.32482) (xy 193.21472 -23.367263)
			(xy 193.206623 -23.451763) (xy 193.190516 -23.535108) (xy 193.166543 -23.616539) (xy 193.134924 -23.695317)
			(xy 193.095945 -23.770725) (xy 193.049961 -23.842078) (xy 192.99739 -23.908727) (xy 192.93871 -23.970066)
			(xy 192.906904 -23.998174) (xy 192.897506 -24.006302) (xy 192.888362 -24.0284) (xy 192.896998 -24.134572)
			(xy 192.909444 -24.155146) (xy 192.919858 -24.161496) (xy 192.954765 -24.183474) (xy 193.020757 -24.232975)
			(xy 193.081882 -24.288374) (xy 193.137614 -24.349194) (xy 193.187476 -24.414914) (xy 193.231038 -24.484969)
			(xy 193.267927 -24.558756) (xy 193.297825 -24.635641) (xy 193.320475 -24.714965) (xy 193.335683 -24.796045)
			(xy 193.343319 -24.878185) (xy 193.343784 -24.919432) (xy 193.343784 -24.919686) (xy 193.34335 -24.95865)
			(xy 193.336528 -25.036278) (xy 193.322935 -25.11301) (xy 193.302674 -25.188258) (xy 193.289682 -25.224994)
			(xy 193.286907 -25.23354) (xy 193.286913 -25.251497) (xy 193.289682 -25.260046) (xy 193.302652 -25.296756)
			(xy 193.322893 -25.371942) (xy 193.336491 -25.448608) (xy 193.343343 -25.526169) (xy 193.343784 -25.5651)
			(xy 193.343784 -25.565862) (xy 193.343299 -25.606528) (xy 193.335855 -25.68752) (xy 193.321054 -25.767495)
			(xy 193.299019 -25.845787) (xy 193.269934 -25.921742) (xy 193.234042 -25.994727) (xy 193.213228 -26.029666)
			(xy 193.207544 -26.040362) (xy 193.20583 -26.064493) (xy 193.209926 -26.075894) (xy 193.247518 -26.163524)
			(xy 193.266314 -26.179272) (xy 193.278252 -26.181812) (xy 193.32027 -26.191428) (xy 193.402329 -26.217838)
			(xy 193.481449 -26.252062) (xy 193.556887 -26.293778) (xy 193.627936 -26.342596) (xy 193.69393 -26.398057)
			(xy 193.754251 -26.459641) (xy 193.808331 -26.526772) (xy 193.855665 -26.598818) (xy 193.895807 -26.675105)
			(xy 193.928383 -26.754918) (xy 193.953086 -26.837507) (xy 193.969684 -26.922098) (xy 193.978022 -27.007898)
			(xy 193.97853 -27.051) (xy 193.978036 -27.093057) (xy 193.970078 -27.176793) (xy 193.954251 -27.259404)
			(xy 193.930698 -27.340153) (xy 193.899628 -27.418318) (xy 193.861318 -27.493201) (xy 193.816112 -27.564134)
			(xy 193.764412 -27.630483) (xy 193.70668 -27.691656) (xy 193.643432 -27.747107) (xy 193.575232 -27.79634)
			(xy 193.50269 -27.838916) (xy 193.426452 -27.874454) (xy 193.347201 -27.902639) (xy 193.265644 -27.923216)
			(xy 193.22415 -27.930094) (xy 193.210942 -27.932126) (xy 193.190622 -27.947874) (xy 193.145918 -28.051506)
			(xy 193.148712 -28.077668) (xy 193.156078 -28.088336) (xy 193.181092 -28.125548) (xy 193.22439 -28.20407)
			(xy 193.259568 -28.28655) (xy 193.28627 -28.37215) (xy 193.304225 -28.460003) (xy 193.313251 -28.549216)
			(xy 193.313812 -28.59405) (xy 193.313308 -28.636398) (xy 193.305257 -28.720712) (xy 193.289228 -28.803878)
			(xy 193.265367 -28.885145) (xy 193.233888 -28.963775) (xy 193.195077 -29.039056) (xy 193.149287 -29.110308)
			(xy 193.096931 -29.176884) (xy 193.038483 -29.238182) (xy 192.974473 -29.293647) (xy 192.905481 -29.342776)
			(xy 192.832131 -29.385125) (xy 192.755088 -29.420309) (xy 192.675049 -29.448011) (xy 192.59274 -29.467979)
			(xy 192.508905 -29.480032) (xy 192.424304 -29.484063) (xy 192.339703 -29.480032) (xy 192.255868 -29.467979)
			(xy 192.173559 -29.448011) (xy 192.09352 -29.420309) (xy 192.016477 -29.385125) (xy 191.943127 -29.342776)
			(xy 191.874135 -29.293647) (xy 191.810125 -29.238182) (xy 191.751677 -29.176884) (xy 191.699321 -29.110308)
			(xy 191.653531 -29.039056) (xy 191.61472 -28.963775) (xy 191.583241 -28.885145) (xy 191.55938 -28.803878)
			(xy 191.543351 -28.720712) (xy 191.5353 -28.636398) (xy 191.534796 -28.59405) (xy 191.535285 -28.552155)
			(xy 191.543163 -28.468737) (xy 191.558853 -28.386429) (xy 191.582217 -28.305963) (xy 191.613046 -28.228051)
			(xy 191.651068 -28.153385) (xy 191.695946 -28.082627) (xy 191.721232 -28.04922) (xy 191.721232 -28.048966)
			(xy 191.726543 -28.041535) (xy 191.731997 -28.024118) (xy 191.73094 -28.005898) (xy 191.727582 -27.997404)
			(xy 191.685418 -27.902662) (xy 191.662558 -27.88666) (xy 191.648588 -27.885644) (xy 191.620516 -27.883016)
			(xy 191.565525 -27.870578) (xy 191.512965 -27.850176) (xy 191.463985 -27.822254) (xy 191.419651 -27.787422)
			(xy 191.399922 -27.76728) (xy 191.399668 -27.767026) (xy 191.39269 -27.760405) (xy 191.375208 -27.752427)
			(xy 191.365632 -27.751532) (xy 191.29502 -27.747976) (xy 191.285416 -27.747987) (xy 191.267275 -27.754246)
			(xy 191.259714 -27.760168) (xy 191.25946 -27.760168) (xy 191.225889 -27.788446) (xy 191.154129 -27.839004)
			(xy 191.077739 -27.882247) (xy 190.99746 -27.917755) (xy 190.914074 -27.945183) (xy 190.871348 -27.95524)
			(xy 190.871094 -27.95524) (xy 190.8593 -27.958607) (xy 190.84059 -27.974409) (xy 190.83528 -27.985466)
			(xy 190.803784 -28.062428) (xy 190.799819 -28.074035) (xy 190.801919 -28.09843) (xy 190.807848 -28.109164)
			(xy 190.830141 -28.144954) (xy 190.868609 -28.219995) (xy 190.899805 -28.298338) (xy 190.92345 -28.379281)
			(xy 190.939332 -28.462097) (xy 190.947308 -28.546045) (xy 190.947802 -28.588208) (xy 190.947283 -28.632013)
			(xy 190.938693 -28.7192) (xy 190.921576 -28.805121) (xy 190.896099 -28.888944) (xy 190.862508 -28.969858)
			(xy 190.821129 -29.04708) (xy 190.79718 -29.083762) (xy 190.792402 -29.091418) (xy 190.788099 -29.108934)
			(xy 190.790137 -29.126856) (xy 190.793878 -29.13507) (xy 190.8123 -29.17252) (xy 190.84292 -29.250165)
			(xy 190.866139 -29.330335) (xy 190.881754 -29.412327) (xy 190.889626 -29.49542) (xy 190.890144 -29.537152)
			(xy 190.88964 -29.5795) (xy 190.881589 -29.663814) (xy 190.86556 -29.74698) (xy 190.841699 -29.828247)
			(xy 190.81022 -29.906877) (xy 190.771409 -29.982158) (xy 190.725619 -30.05341) (xy 190.673263 -30.119986)
			(xy 190.660091 -30.1338) (xy 197.59597 -30.1338) (xy 197.6 -30.049196) (xy 197.612054 -29.965359)
			(xy 197.632023 -29.883047) (xy 197.659726 -29.803006) (xy 197.694912 -29.725961) (xy 197.737262 -29.652609)
			(xy 197.786393 -29.583615) (xy 197.84186 -29.519604) (xy 197.90316 -29.461155) (xy 197.969739 -29.408798)
			(xy 198.040993 -29.363007) (xy 198.116277 -29.324196) (xy 198.19491 -29.292717) (xy 198.276179 -29.268856)
			(xy 198.359348 -29.252827) (xy 198.443664 -29.244777) (xy 198.486014 -29.24429) (xy 198.524302 -29.244732)
			(xy 198.600592 -29.251352) (xy 198.676032 -29.264497) (xy 198.750064 -29.284071) (xy 198.786242 -29.296614)
			(xy 198.794679 -29.299265) (xy 198.812349 -29.299265) (xy 198.820786 -29.296614) (xy 198.856959 -29.284053)
			(xy 198.930989 -29.264458) (xy 199.006431 -29.251308) (xy 199.082724 -29.2447) (xy 199.121014 -29.24429)
			(xy 199.159302 -29.244732) (xy 199.235592 -29.251352) (xy 199.311032 -29.264497) (xy 199.385064 -29.284071)
			(xy 199.421242 -29.296614) (xy 199.429679 -29.299265) (xy 199.447349 -29.299265) (xy 199.455786 -29.296614)
			(xy 199.491959 -29.284053) (xy 199.565989 -29.264458) (xy 199.641431 -29.251308) (xy 199.717724 -29.2447)
			(xy 199.756014 -29.24429) (xy 199.794302 -29.244732) (xy 199.870592 -29.251352) (xy 199.946032 -29.264497)
			(xy 200.020064 -29.284071) (xy 200.056242 -29.296614) (xy 200.064679 -29.299265) (xy 200.082349 -29.299265)
			(xy 200.090786 -29.296614) (xy 200.126959 -29.284053) (xy 200.200989 -29.264458) (xy 200.276431 -29.251308)
			(xy 200.352724 -29.2447) (xy 200.391014 -29.24429) (xy 200.431701 -29.244705) (xy 200.512736 -29.25213)
			(xy 200.592753 -29.266926) (xy 200.671084 -29.28897) (xy 200.747075 -29.318076) (xy 200.820089 -29.354002)
			(xy 200.889516 -29.396447) (xy 200.954776 -29.445056) (xy 201.015323 -29.499423) (xy 201.07065 -29.559094)
			(xy 201.120296 -29.623569) (xy 201.163845 -29.692309) (xy 201.200933 -29.76474) (xy 201.216514 -29.802328)
			(xy 201.22096 -29.81221) (xy 201.236587 -29.827203) (xy 201.25699 -29.834462) (xy 201.267822 -29.834078)
			(xy 201.286077 -29.832661) (xy 201.322664 -29.831136) (xy 201.340974 -29.83103) (xy 201.383326 -29.831441)
			(xy 201.467646 -29.83949) (xy 201.55082 -29.855518) (xy 201.632093 -29.87938) (xy 201.71073 -29.91086)
			(xy 201.786018 -29.949672) (xy 201.857276 -29.995464) (xy 201.923859 -30.047824) (xy 201.985162 -30.106275)
			(xy 202.040632 -30.170289) (xy 202.089766 -30.239286) (xy 202.132119 -30.312641) (xy 202.167306 -30.38969)
			(xy 202.195011 -30.469735) (xy 202.214981 -30.552051) (xy 202.227036 -30.635892) (xy 202.231066 -30.7205)
			(xy 202.227036 -30.805108) (xy 202.214981 -30.888949) (xy 202.195011 -30.971265) (xy 202.167306 -31.05131)
			(xy 202.132119 -31.128359) (xy 202.089766 -31.201714) (xy 202.040632 -31.270711) (xy 201.985162 -31.334725)
			(xy 201.923859 -31.393176) (xy 201.857276 -31.445536) (xy 201.786018 -31.491328) (xy 201.71073 -31.53014)
			(xy 201.632093 -31.56162) (xy 201.55082 -31.585482) (xy 201.467646 -31.60151) (xy 201.383326 -31.609559)
			(xy 201.340974 -31.610046) (xy 201.302686 -31.609605) (xy 201.226396 -31.602985) (xy 201.150956 -31.589839)
			(xy 201.076924 -31.570265) (xy 201.040746 -31.557722) (xy 201.032309 -31.555071) (xy 201.014639 -31.555071)
			(xy 201.006202 -31.557722) (xy 200.97003 -31.570287) (xy 200.896 -31.589881) (xy 200.820558 -31.60303)
			(xy 200.744264 -31.609636) (xy 200.705974 -31.610046) (xy 200.667686 -31.609605) (xy 200.591396 -31.602985)
			(xy 200.515956 -31.589839) (xy 200.441924 -31.570265) (xy 200.405746 -31.557722) (xy 200.397309 -31.555071)
			(xy 200.379639 -31.555071) (xy 200.371202 -31.557722) (xy 200.33503 -31.570287) (xy 200.261 -31.589881)
			(xy 200.185558 -31.60303) (xy 200.109264 -31.609636) (xy 200.070974 -31.610046) (xy 200.032686 -31.609605)
			(xy 199.956396 -31.602985) (xy 199.880956 -31.589839) (xy 199.806924 -31.570265) (xy 199.770746 -31.557722)
			(xy 199.762309 -31.555071) (xy 199.744639 -31.555071) (xy 199.736202 -31.557722) (xy 199.70003 -31.570287)
			(xy 199.626 -31.589881) (xy 199.550558 -31.60303) (xy 199.474264 -31.609636) (xy 199.435974 -31.610046)
			(xy 199.395289 -31.609531) (xy 199.314259 -31.602114) (xy 199.234244 -31.587326) (xy 199.155915 -31.565292)
			(xy 199.079926 -31.536194) (xy 199.006913 -31.500276) (xy 198.937486 -31.45784) (xy 198.872226 -31.409239)
			(xy 198.811678 -31.35488) (xy 198.756348 -31.295217) (xy 198.7067 -31.23075) (xy 198.663148 -31.162017)
			(xy 198.626057 -31.089593) (xy 198.610474 -31.052008) (xy 198.605944 -31.042172) (xy 198.590355 -31.027175)
			(xy 198.569987 -31.019892) (xy 198.559166 -31.020258) (xy 198.540911 -31.021676) (xy 198.504324 -31.0232)
			(xy 198.486014 -31.023306) (xy 198.443664 -31.022823) (xy 198.359348 -31.014773) (xy 198.276179 -30.998744)
			(xy 198.19491 -30.974883) (xy 198.116277 -30.943404) (xy 198.040993 -30.904593) (xy 197.969739 -30.858802)
			(xy 197.90316 -30.806445) (xy 197.84186 -30.747996) (xy 197.786393 -30.683985) (xy 197.737262 -30.614991)
			(xy 197.694912 -30.541639) (xy 197.659726 -30.464594) (xy 197.632023 -30.384553) (xy 197.612054 -30.302241)
			(xy 197.6 -30.218404) (xy 197.59597 -30.1338) (xy 190.660091 -30.1338) (xy 190.614815 -30.181284)
			(xy 190.550805 -30.236749) (xy 190.481813 -30.285878) (xy 190.408463 -30.328227) (xy 190.33142 -30.363411)
			(xy 190.251381 -30.391113) (xy 190.169072 -30.411081) (xy 190.085237 -30.423134) (xy 190.000636 -30.427165)
			(xy 189.916035 -30.423134) (xy 189.8322 -30.411081) (xy 189.749891 -30.391113) (xy 189.669852 -30.363411)
			(xy 189.592809 -30.328227) (xy 189.519459 -30.285878) (xy 189.450467 -30.236749) (xy 189.386457 -30.181284)
			(xy 189.328009 -30.119986) (xy 189.275653 -30.05341) (xy 189.229863 -29.982158) (xy 189.191052 -29.906877)
			(xy 189.159573 -29.828247) (xy 189.135712 -29.74698) (xy 189.119683 -29.663814) (xy 189.111632 -29.5795)
			(xy 189.111128 -29.537152) (xy 187.243212 -29.537152) (xy 189.176152 -31.470092) (xy 193.210434 -31.470092)
			(xy 193.21092 -31.442841) (xy 193.218676 -31.388893) (xy 193.234031 -31.336598) (xy 193.256673 -31.287021)
			(xy 193.286139 -31.241171) (xy 193.32183 -31.19998) (xy 193.363021 -31.164289) (xy 193.408871 -31.134823)
			(xy 193.458448 -31.112181) (xy 193.510743 -31.096826) (xy 193.564691 -31.08907) (xy 193.619193 -31.08907)
			(xy 193.673141 -31.096826) (xy 193.725436 -31.112181) (xy 193.775013 -31.134823) (xy 193.820863 -31.164289)
			(xy 193.862054 -31.19998) (xy 193.897745 -31.241171) (xy 193.927211 -31.287021) (xy 193.949853 -31.336598)
			(xy 193.965208 -31.388893) (xy 193.972964 -31.442841) (xy 193.97345 -31.470092) (xy 193.97345 -31.470346)
			(xy 193.973009 -31.496175) (xy 193.966011 -31.547359) (xy 193.952177 -31.597131) (xy 193.931758 -31.644585)
			(xy 193.905129 -31.688852) (xy 193.872774 -31.729124) (xy 193.854324 -31.747206) (xy 193.846704 -31.754318)
			(xy 193.838322 -31.773622) (xy 193.839338 -31.869634) (xy 193.84772 -31.888684) (xy 193.855594 -31.895796)
			(xy 193.874818 -31.913965) (xy 193.908603 -31.954664) (xy 193.936445 -31.999639) (xy 193.957809 -32.048027)
			(xy 193.972286 -32.098902) (xy 193.979599 -32.151289) (xy 193.980054 -32.177736) (xy 193.979507 -32.206652)
			(xy 193.970787 -32.263823) (xy 193.953536 -32.319022) (xy 193.928149 -32.370984) (xy 193.89521 -32.418519)
			(xy 193.855472 -32.460536) (xy 193.832988 -32.478726) (xy 193.824177 -32.48633) (xy 193.813996 -32.507233)
			(xy 193.81343 -32.518858) (xy 193.81343 -32.598614) (xy 193.813965 -32.610247) (xy 193.824156 -32.631157)
			(xy 193.832988 -32.638746) (xy 193.855443 -32.656971) (xy 193.895181 -32.698983) (xy 193.928123 -32.746511)
			(xy 193.953517 -32.798466) (xy 193.970779 -32.853657) (xy 193.979515 -32.910822) (xy 193.980054 -32.939736)
			(xy 193.979568 -32.966987) (xy 193.971812 -33.020935) (xy 193.956457 -33.07323) (xy 193.933815 -33.122807)
			(xy 193.904349 -33.168657) (xy 193.868658 -33.209848) (xy 193.827467 -33.245539) (xy 193.781617 -33.275005)
			(xy 193.73204 -33.297647) (xy 193.679745 -33.313002) (xy 193.625797 -33.320758) (xy 193.571295 -33.320758)
			(xy 193.517347 -33.313002) (xy 193.465052 -33.297647) (xy 193.415475 -33.275005) (xy 193.369625 -33.245539)
			(xy 193.328434 -33.209848) (xy 193.292743 -33.168657) (xy 193.263277 -33.122807) (xy 193.240635 -33.07323)
			(xy 193.22528 -33.020935) (xy 193.217524 -32.966987) (xy 193.217038 -32.939736) (xy 193.217568 -32.910819)
			(xy 193.226292 -32.853648) (xy 193.243547 -32.798449) (xy 193.268936 -32.746487) (xy 193.301879 -32.698953)
			(xy 193.341619 -32.656936) (xy 193.364104 -32.638746) (xy 193.372881 -32.63111) (xy 193.383081 -32.610231)
			(xy 193.383662 -32.598614) (xy 193.383662 -32.518858) (xy 193.383146 -32.507223) (xy 193.372942 -32.486313)
			(xy 193.364104 -32.478726) (xy 193.341634 -32.460519) (xy 193.301898 -32.418503) (xy 193.268957 -32.370971)
			(xy 193.243566 -32.319013) (xy 193.226307 -32.263818) (xy 193.217575 -32.206651) (xy 193.217038 -32.177736)
			(xy 193.217038 -32.177482) (xy 193.217502 -32.151653) (xy 193.224495 -32.100471) (xy 193.238325 -32.050699)
			(xy 193.25874 -32.003246) (xy 193.285365 -31.958978) (xy 193.317716 -31.918705) (xy 193.336164 -31.900622)
			(xy 193.343784 -31.89351) (xy 193.352166 -31.874206) (xy 193.35115 -31.778194) (xy 193.342768 -31.759144)
			(xy 193.334894 -31.752032) (xy 193.315633 -31.733901) (xy 193.281851 -31.693193) (xy 193.254015 -31.648211)
			(xy 193.232658 -31.599815) (xy 193.218188 -31.548934) (xy 193.210884 -31.496541) (xy 193.210434 -31.470092)
			(xy 189.176152 -31.470092) (xy 191.902588 -34.196528) (xy 208.182208 -34.196528) (xy 208.186279 -34.140906)
			(xy 208.198405 -34.086469) (xy 208.218328 -34.034378) (xy 208.245624 -33.985743) (xy 208.27971 -33.9416)
			(xy 208.319859 -33.902891) (xy 208.365217 -33.87044) (xy 208.414817 -33.844939) (xy 208.467601 -33.826932)
			(xy 208.522444 -33.816802) (xy 208.578178 -33.814765) (xy 208.633615 -33.820865) (xy 208.687572 -33.834971)
			(xy 208.738901 -33.856783) (xy 208.786507 -33.885837) (xy 208.829375 -33.921512) (xy 208.866592 -33.963049)
			(xy 208.897365 -34.009562) (xy 208.921037 -34.060059) (xy 208.937105 -34.113466) (xy 208.945225 -34.168642)
			(xy 208.945734 -34.196528) (xy 208.945225 -34.224414) (xy 208.937105 -34.27959) (xy 208.921037 -34.332997)
			(xy 208.897365 -34.383494) (xy 208.866592 -34.430007) (xy 208.829375 -34.471544) (xy 208.786507 -34.507219)
			(xy 208.738901 -34.536273) (xy 208.687572 -34.558085) (xy 208.633615 -34.572191) (xy 208.578178 -34.578291)
			(xy 208.522444 -34.576254) (xy 208.467601 -34.566124) (xy 208.414817 -34.548117) (xy 208.365217 -34.522616)
			(xy 208.319859 -34.490165) (xy 208.27971 -34.451456) (xy 208.245624 -34.407313) (xy 208.218328 -34.358678)
			(xy 208.198405 -34.306587) (xy 208.186279 -34.25215) (xy 208.182208 -34.196528) (xy 191.902588 -34.196528)
			(xy 193.228214 -35.522154) (xy 206.00162 -35.522154) (xy 206.002124 -35.479806) (xy 206.010175 -35.395492)
			(xy 206.026204 -35.312326) (xy 206.050065 -35.231059) (xy 206.081544 -35.152429) (xy 206.120355 -35.077148)
			(xy 206.166145 -35.005896) (xy 206.218501 -34.93932) (xy 206.276949 -34.878022) (xy 206.340959 -34.822557)
			(xy 206.409951 -34.773428) (xy 206.483301 -34.731079) (xy 206.560344 -34.695895) (xy 206.640383 -34.668193)
			(xy 206.722692 -34.648225) (xy 206.806527 -34.636172) (xy 206.891128 -34.632142) (xy 206.975729 -34.636172)
			(xy 207.059564 -34.648225) (xy 207.141873 -34.668193) (xy 207.221912 -34.695895) (xy 207.298955 -34.731079)
			(xy 207.372305 -34.773428) (xy 207.441297 -34.822557) (xy 207.505307 -34.878022) (xy 207.563755 -34.93932)
			(xy 207.616111 -35.005896) (xy 207.661901 -35.077148) (xy 207.700712 -35.152429) (xy 207.732191 -35.231059)
			(xy 207.756052 -35.312326) (xy 207.772081 -35.395492) (xy 207.780132 -35.479806) (xy 207.780636 -35.522154)
			(xy 207.780113 -35.566205) (xy 207.771407 -35.653875) (xy 207.754076 -35.740255) (xy 207.728289 -35.824498)
			(xy 207.6943 -35.905779) (xy 207.652441 -35.983302) (xy 207.603122 -36.056305) (xy 207.546828 -36.124076)
			(xy 207.484109 -36.185948) (xy 207.450182 -36.21405) (xy 207.441038 -36.221416) (xy 207.431132 -36.24199)
			(xy 207.431894 -36.34486) (xy 207.442054 -36.365688) (xy 207.451198 -36.3728) (xy 207.482504 -36.398043)
			(xy 207.540946 -36.453293) (xy 207.594164 -36.513592) (xy 207.641723 -36.578447) (xy 207.683234 -36.647331)
			(xy 207.718359 -36.719679) (xy 207.746811 -36.794903) (xy 207.768358 -36.872387) (xy 207.782824 -36.9515)
			(xy 207.790091 -37.031596) (xy 207.790542 -37.071808) (xy 207.790038 -37.114156) (xy 207.781987 -37.19847)
			(xy 207.765958 -37.281636) (xy 207.742097 -37.362903) (xy 207.710618 -37.441533) (xy 207.671807 -37.516814)
			(xy 207.626017 -37.588066) (xy 207.573661 -37.654642) (xy 207.515213 -37.71594) (xy 207.451203 -37.771405)
			(xy 207.382211 -37.820534) (xy 207.308861 -37.862883) (xy 207.231818 -37.898067) (xy 207.151779 -37.925769)
			(xy 207.06947 -37.945737) (xy 206.985635 -37.95779) (xy 206.901034 -37.961821) (xy 206.816433 -37.95779)
			(xy 206.732598 -37.945737) (xy 206.650289 -37.925769) (xy 206.57025 -37.898067) (xy 206.493207 -37.862883)
			(xy 206.419857 -37.820534) (xy 206.350865 -37.771405) (xy 206.286855 -37.71594) (xy 206.228407 -37.654642)
			(xy 206.176051 -37.588066) (xy 206.130261 -37.516814) (xy 206.09145 -37.441533) (xy 206.059971 -37.362903)
			(xy 206.03611 -37.281636) (xy 206.020081 -37.19847) (xy 206.01203 -37.114156) (xy 206.011526 -37.071808)
			(xy 206.012109 -37.027759) (xy 206.020808 -36.940091) (xy 206.038132 -36.853713) (xy 206.063912 -36.769471)
			(xy 206.097894 -36.68819) (xy 206.139746 -36.610668) (xy 206.189057 -36.537663) (xy 206.245344 -36.469891)
			(xy 206.308057 -36.408016) (xy 206.34198 -36.379912) (xy 206.351124 -36.372546) (xy 206.36103 -36.351972)
			(xy 206.360268 -36.249102) (xy 206.350108 -36.228274) (xy 206.340964 -36.221162) (xy 206.309654 -36.195924)
			(xy 206.251209 -36.140675) (xy 206.19799 -36.080377) (xy 206.15043 -36.015521) (xy 206.108919 -35.946637)
			(xy 206.073794 -35.874287) (xy 206.045343 -35.799063) (xy 206.023797 -35.721577) (xy 206.009334 -35.642463)
			(xy 206.00207 -35.562367) (xy 206.00162 -35.522154) (xy 193.228214 -35.522154) (xy 194.139312 -36.433252)
			(xy 195.216524 -36.433252) (xy 195.220595 -36.37763) (xy 195.232721 -36.323193) (xy 195.252644 -36.271102)
			(xy 195.27994 -36.222467) (xy 195.314026 -36.178324) (xy 195.354175 -36.139615) (xy 195.399533 -36.107164)
			(xy 195.449133 -36.081663) (xy 195.501917 -36.063656) (xy 195.55676 -36.053526) (xy 195.612494 -36.051489)
			(xy 195.667931 -36.057589) (xy 195.721888 -36.071695) (xy 195.773217 -36.093507) (xy 195.820823 -36.122561)
			(xy 195.863691 -36.158236) (xy 195.900908 -36.199773) (xy 195.931681 -36.246286) (xy 195.955353 -36.296783)
			(xy 195.971421 -36.35019) (xy 195.979541 -36.405366) (xy 195.98005 -36.433252) (xy 195.979541 -36.461138)
			(xy 195.971421 -36.516314) (xy 195.955353 -36.569721) (xy 195.931681 -36.620218) (xy 195.900908 -36.666731)
			(xy 195.863691 -36.708268) (xy 195.820823 -36.743943) (xy 195.773217 -36.772997) (xy 195.721888 -36.794809)
			(xy 195.667931 -36.808915) (xy 195.612494 -36.815015) (xy 195.55676 -36.812978) (xy 195.501917 -36.802848)
			(xy 195.449133 -36.784841) (xy 195.399533 -36.75934) (xy 195.354175 -36.726889) (xy 195.314026 -36.68818)
			(xy 195.27994 -36.644037) (xy 195.252644 -36.595402) (xy 195.232721 -36.543311) (xy 195.220595 -36.488874)
			(xy 195.216524 -36.433252) (xy 194.139312 -36.433252) (xy 195.880228 -38.174168) (xy 195.885012 -38.178631)
			(xy 195.89633 -38.185186) (xy 195.90258 -38.187122) (xy 195.908676 -38.1889) (xy 195.921884 -38.1889)
			(xy 195.928742 -38.187122) (xy 195.96597 -38.177663) (xy 196.041641 -38.164442) (xy 196.118171 -38.157806)
			(xy 196.15658 -38.157404) (xy 196.197684 -38.157863) (xy 196.27954 -38.165447) (xy 196.360348 -38.180551)
			(xy 196.439417 -38.203047) (xy 196.516073 -38.232742) (xy 196.589662 -38.269384) (xy 196.659557 -38.31266)
			(xy 196.72516 -38.3622) (xy 196.785912 -38.417582) (xy 196.841295 -38.478334) (xy 196.890836 -38.543937)
			(xy 196.934112 -38.613831) (xy 196.970755 -38.687419) (xy 197.000451 -38.764075) (xy 197.022947 -38.843144)
			(xy 197.038052 -38.923952) (xy 197.045636 -39.005808) (xy 197.046088 -39.046912) (xy 197.045671 -39.08532)
			(xy 197.03903 -39.161849) (xy 197.025825 -39.237522) (xy 197.01637 -39.27475) (xy 197.01637 -39.275004)
			(xy 197.01637 -39.30142) (xy 197.018148 -39.307516) (xy 197.024498 -39.318438) (xy 197.450202 -39.744142)
			(xy 197.455701 -39.749129) (xy 197.468868 -39.755973) (xy 197.47611 -39.757604) (xy 197.485762 -39.75862)
			(xy 208.891378 -39.75862)
		)
		(stroke
			(width 0)
			(type solid)
		)
		(fill yes)
		(layer "In2.Cu")
		(net "P12V_SCM_R")
	)
	(gr_poly
		(pts
			(xy 146.861276 -392.588242) (xy 146.871339 -392.587803) (xy 146.889918 -392.580063) (xy 146.897344 -392.573256)
			(xy 147.056348 -392.414252) (xy 147.063714 -392.398758) (xy 147.064476 -392.389868) (xy 147.067843 -392.362386)
			(xy 147.081483 -392.308728) (xy 147.102724 -392.257599) (xy 147.131119 -392.21007) (xy 147.166075 -392.167136)
			(xy 147.186142 -392.14806) (xy 147.193254 -392.14171) (xy 147.201382 -392.124946) (xy 147.209764 -392.038332)
			(xy 147.204684 -392.020552) (xy 147.199096 -392.012678) (xy 147.184937 -391.992834) (xy 147.162447 -391.949586)
			(xy 147.147127 -391.903311) (xy 147.139367 -391.855187) (xy 147.138898 -391.830814) (xy 147.13942 -391.805559)
			(xy 147.147733 -391.755737) (xy 147.164134 -391.707963) (xy 147.188175 -391.66354) (xy 147.219199 -391.62368)
			(xy 147.256361 -391.58947) (xy 147.298647 -391.561844) (xy 147.344903 -391.541554) (xy 147.393868 -391.529154)
			(xy 147.444206 -391.524983) (xy 147.494544 -391.529154) (xy 147.543509 -391.541554) (xy 147.589765 -391.561844)
			(xy 147.632051 -391.58947) (xy 147.669213 -391.62368) (xy 147.700237 -391.66354) (xy 147.724278 -391.707963)
			(xy 147.740679 -391.755737) (xy 147.748992 -391.805559) (xy 147.749514 -391.830814) (xy 147.749015 -391.855184)
			(xy 147.741235 -391.903299) (xy 147.725921 -391.949571) (xy 147.703462 -391.992828) (xy 147.689316 -392.012678)
			(xy 147.683728 -392.020552) (xy 147.678648 -392.038332) (xy 147.68703 -392.124946) (xy 147.695158 -392.14171)
			(xy 147.70227 -392.14806) (xy 147.724245 -392.169065) (xy 147.761892 -392.216792) (xy 147.7772 -392.243056)
			(xy 147.781943 -392.250737) (xy 147.795692 -392.26242) (xy 147.812629 -392.268635) (xy 147.82165 -392.268964)
			(xy 148.266658 -392.268964) (xy 148.27569 -392.268657) (xy 148.292659 -392.262479) (xy 148.306411 -392.250775)
			(xy 148.311108 -392.243056) (xy 148.326432 -392.216803) (xy 148.364075 -392.169076) (xy 148.386038 -392.14806)
			(xy 148.39315 -392.141456) (xy 148.401532 -392.124946) (xy 148.40966 -392.038078) (xy 148.404834 -392.020298)
			(xy 148.398992 -392.012678) (xy 148.384889 -391.992812) (xy 148.362501 -391.949545) (xy 148.347258 -391.903274)
			(xy 148.339546 -391.855172) (xy 148.339048 -391.830814) (xy 148.33957 -391.805559) (xy 148.347883 -391.755737)
			(xy 148.364284 -391.707963) (xy 148.388325 -391.66354) (xy 148.419349 -391.62368) (xy 148.456511 -391.58947)
			(xy 148.498797 -391.561844) (xy 148.545053 -391.541554) (xy 148.594018 -391.529154) (xy 148.644356 -391.524983)
			(xy 148.694694 -391.529154) (xy 148.743659 -391.541554) (xy 148.789915 -391.561844) (xy 148.832201 -391.58947)
			(xy 148.869363 -391.62368) (xy 148.900387 -391.66354) (xy 148.924428 -391.707963) (xy 148.940829 -391.755737)
			(xy 148.949142 -391.805559) (xy 148.949664 -391.830814) (xy 148.949186 -391.855216) (xy 148.941426 -391.903398)
			(xy 148.926107 -391.949734) (xy 148.903617 -391.993047) (xy 148.889466 -392.012932) (xy 148.883878 -392.020552)
			(xy 148.878798 -392.038332) (xy 148.886926 -392.1252) (xy 148.895308 -392.14171) (xy 148.90242 -392.148314)
			(xy 148.924315 -392.169273) (xy 148.961836 -392.216869) (xy 148.977096 -392.243056) (xy 148.981839 -392.250738)
			(xy 148.995587 -392.262421) (xy 149.012525 -392.268638) (xy 149.021546 -392.268964) (xy 149.466808 -392.268964)
			(xy 149.475835 -392.268649) (xy 149.492791 -392.26246) (xy 149.506529 -392.250752) (xy 149.511258 -392.243056)
			(xy 149.52658 -392.216801) (xy 149.56422 -392.169072) (xy 149.586188 -392.14806) (xy 149.5933 -392.14171)
			(xy 149.601428 -392.124946) (xy 149.60981 -392.038332) (xy 149.60473 -392.020552) (xy 149.599142 -392.012678)
			(xy 149.584985 -391.992833) (xy 149.562499 -391.949585) (xy 149.547182 -391.903309) (xy 149.539423 -391.855186)
			(xy 149.538944 -391.830814) (xy 149.539466 -391.805559) (xy 149.547779 -391.755737) (xy 149.56418 -391.707963)
			(xy 149.588221 -391.66354) (xy 149.619245 -391.62368) (xy 149.656407 -391.58947) (xy 149.698693 -391.561844)
			(xy 149.744949 -391.541554) (xy 149.793914 -391.529154) (xy 149.844252 -391.524983) (xy 149.89459 -391.529154)
			(xy 149.943555 -391.541554) (xy 149.989811 -391.561844) (xy 150.032097 -391.58947) (xy 150.069259 -391.62368)
			(xy 150.100283 -391.66354) (xy 150.124324 -391.707963) (xy 150.140725 -391.755737) (xy 150.149038 -391.805559)
			(xy 150.14956 -391.830814) (xy 150.149062 -391.855184) (xy 150.141282 -391.9033) (xy 150.12597 -391.949573)
			(xy 150.103514 -391.992832) (xy 150.089362 -392.012678) (xy 150.083774 -392.020552) (xy 150.078694 -392.038332)
			(xy 150.087076 -392.124946) (xy 150.095204 -392.14171) (xy 150.102316 -392.14806) (xy 150.124294 -392.169063)
			(xy 150.161945 -392.216788) (xy 150.177246 -392.243056) (xy 150.181992 -392.250732) (xy 150.195742 -392.262402)
			(xy 150.212678 -392.268602) (xy 150.221696 -392.268964) (xy 150.666704 -392.268964) (xy 150.675731 -392.26865)
			(xy 150.692688 -392.262461) (xy 150.706427 -392.250754) (xy 150.711154 -392.243056) (xy 150.726476 -392.216801)
			(xy 150.764116 -392.169071) (xy 150.786084 -392.14806) (xy 150.793196 -392.14171) (xy 150.801324 -392.124946)
			(xy 150.809706 -392.038332) (xy 150.804626 -392.020552) (xy 150.799038 -392.012678) (xy 150.784881 -391.992833)
			(xy 150.762396 -391.949585) (xy 150.747079 -391.903309) (xy 150.73932 -391.855186) (xy 150.73884 -391.830814)
			(xy 150.739362 -391.805559) (xy 150.747675 -391.755737) (xy 150.764076 -391.707963) (xy 150.788117 -391.66354)
			(xy 150.819141 -391.62368) (xy 150.856303 -391.58947) (xy 150.898589 -391.561844) (xy 150.944845 -391.541554)
			(xy 150.99381 -391.529154) (xy 151.044148 -391.524983) (xy 151.094486 -391.529154) (xy 151.143451 -391.541554)
			(xy 151.189707 -391.561844) (xy 151.231993 -391.58947) (xy 151.269155 -391.62368) (xy 151.300179 -391.66354)
			(xy 151.32422 -391.707963) (xy 151.340621 -391.755737) (xy 151.348934 -391.805559) (xy 151.349456 -391.830814)
			(xy 151.348958 -391.855184) (xy 151.341178 -391.9033) (xy 151.325866 -391.949573) (xy 151.303409 -391.992832)
			(xy 151.289258 -392.012678) (xy 151.28367 -392.020552) (xy 151.27859 -392.038332) (xy 151.286972 -392.124946)
			(xy 151.2951 -392.14171) (xy 151.302212 -392.14806) (xy 151.32419 -392.169063) (xy 151.361842 -392.216787)
			(xy 151.377142 -392.243056) (xy 151.381888 -392.250732) (xy 151.395638 -392.262404) (xy 151.412574 -392.268605)
			(xy 151.421592 -392.268964) (xy 151.866854 -392.268964) (xy 151.875886 -392.268658) (xy 151.892856 -392.262481)
			(xy 151.906609 -392.250776) (xy 151.911304 -392.243056) (xy 151.926627 -392.216802) (xy 151.964271 -392.169076)
			(xy 151.986234 -392.14806) (xy 151.993346 -392.14171) (xy 152.001474 -392.124946) (xy 152.009856 -392.038332)
			(xy 152.004776 -392.020552) (xy 151.999188 -392.012678) (xy 151.985029 -391.992834) (xy 151.96254 -391.949586)
			(xy 151.94722 -391.903311) (xy 151.93946 -391.855187) (xy 151.93899 -391.830814) (xy 151.939512 -391.805559)
			(xy 151.947825 -391.755737) (xy 151.964226 -391.707963) (xy 151.988267 -391.66354) (xy 152.019291 -391.62368)
			(xy 152.056453 -391.58947) (xy 152.098739 -391.561844) (xy 152.144995 -391.541554) (xy 152.19396 -391.529154)
			(xy 152.244298 -391.524983) (xy 152.294636 -391.529154) (xy 152.343601 -391.541554) (xy 152.389857 -391.561844)
			(xy 152.432143 -391.58947) (xy 152.469305 -391.62368) (xy 152.500329 -391.66354) (xy 152.52437 -391.707963)
			(xy 152.540771 -391.755737) (xy 152.549084 -391.805559) (xy 152.549606 -391.830814) (xy 152.549107 -391.855184)
			(xy 152.541327 -391.903299) (xy 152.526013 -391.949571) (xy 152.503553 -391.992828) (xy 152.489408 -392.012678)
			(xy 152.48382 -392.020552) (xy 152.47874 -392.038332) (xy 152.487122 -392.124946) (xy 152.49525 -392.14171)
			(xy 152.502362 -392.14806) (xy 152.524338 -392.169065) (xy 152.561985 -392.216791) (xy 152.577292 -392.243056)
			(xy 152.582035 -392.250738) (xy 152.595783 -392.262423) (xy 152.61272 -392.26864) (xy 152.621742 -392.268964)
			(xy 153.06675 -392.268964) (xy 153.075782 -392.268659) (xy 153.092753 -392.262482) (xy 153.106508 -392.250778)
			(xy 153.1112 -392.243056) (xy 153.126523 -392.216802) (xy 153.164167 -392.169076) (xy 153.18613 -392.14806)
			(xy 153.193242 -392.14171) (xy 153.20137 -392.124946) (xy 153.209752 -392.038332) (xy 153.204672 -392.020552)
			(xy 153.199084 -392.012678) (xy 153.184925 -391.992834) (xy 153.162437 -391.949586) (xy 153.147117 -391.90331)
			(xy 153.139357 -391.855187) (xy 153.138886 -391.830814) (xy 153.139408 -391.805559) (xy 153.147721 -391.755737)
			(xy 153.164122 -391.707963) (xy 153.188163 -391.66354) (xy 153.219187 -391.62368) (xy 153.256349 -391.58947)
			(xy 153.298635 -391.561844) (xy 153.344891 -391.541554) (xy 153.393856 -391.529154) (xy 153.444194 -391.524983)
			(xy 153.494532 -391.529154) (xy 153.543497 -391.541554) (xy 153.589753 -391.561844) (xy 153.632039 -391.58947)
			(xy 153.669201 -391.62368) (xy 153.700225 -391.66354) (xy 153.724266 -391.707963) (xy 153.740667 -391.755737)
			(xy 153.74898 -391.805559) (xy 153.749502 -391.830814) (xy 153.749003 -391.855184) (xy 153.741223 -391.903299)
			(xy 153.725909 -391.949571) (xy 153.703449 -391.992827) (xy 153.689304 -392.012678) (xy 153.683716 -392.020552)
			(xy 153.678636 -392.038332) (xy 153.687018 -392.124946) (xy 153.695146 -392.14171) (xy 153.702258 -392.14806)
			(xy 153.724234 -392.169065) (xy 153.761882 -392.216791) (xy 153.777188 -392.243056) (xy 153.781931 -392.250739)
			(xy 153.795679 -392.262424) (xy 153.812616 -392.268643) (xy 153.821638 -392.268964) (xy 154.2669 -392.268964)
			(xy 154.275928 -392.268651) (xy 154.292886 -392.262463) (xy 154.306626 -392.250756) (xy 154.31135 -392.243056)
			(xy 154.326672 -392.216801) (xy 154.364312 -392.169071) (xy 154.38628 -392.14806) (xy 154.393392 -392.14171)
			(xy 154.40152 -392.124946) (xy 154.409902 -392.038332) (xy 154.404822 -392.020552) (xy 154.399234 -392.012678)
			(xy 154.385078 -391.992833) (xy 154.362592 -391.949584) (xy 154.347275 -391.903309) (xy 154.339517 -391.855186)
			(xy 154.339036 -391.830814) (xy 154.339558 -391.805559) (xy 154.347871 -391.755737) (xy 154.364272 -391.707963)
			(xy 154.388313 -391.66354) (xy 154.419337 -391.62368) (xy 154.456499 -391.58947) (xy 154.498785 -391.561844)
			(xy 154.545041 -391.541554) (xy 154.594006 -391.529154) (xy 154.644344 -391.524983) (xy 154.694682 -391.529154)
			(xy 154.743647 -391.541554) (xy 154.789903 -391.561844) (xy 154.832189 -391.58947) (xy 154.869351 -391.62368)
			(xy 154.900375 -391.66354) (xy 154.924416 -391.707963) (xy 154.940817 -391.755737) (xy 154.94913 -391.805559)
			(xy 154.949652 -391.830814) (xy 154.949154 -391.855184) (xy 154.941374 -391.9033) (xy 154.926062 -391.949573)
			(xy 154.903605 -391.992832) (xy 154.889454 -392.012678) (xy 154.883866 -392.020552) (xy 154.878786 -392.038332)
			(xy 154.887168 -392.124946) (xy 154.895296 -392.14171) (xy 154.902408 -392.14806) (xy 154.924386 -392.169063)
			(xy 154.962038 -392.216787) (xy 154.977338 -392.243056) (xy 154.982083 -392.250733) (xy 154.995833 -392.262406)
			(xy 155.012769 -392.268608) (xy 155.021788 -392.268964) (xy 155.466796 -392.268964) (xy 155.475824 -392.268651)
			(xy 155.492783 -392.262464) (xy 155.506525 -392.250757) (xy 155.511246 -392.243056) (xy 155.526568 -392.216801)
			(xy 155.564207 -392.16907) (xy 155.586176 -392.14806) (xy 155.593288 -392.14171) (xy 155.601416 -392.124946)
			(xy 155.609798 -392.038332) (xy 155.604718 -392.020552) (xy 155.59913 -392.012678) (xy 155.584974 -391.992833)
			(xy 155.562489 -391.949584) (xy 155.547172 -391.903309) (xy 155.539414 -391.855186) (xy 155.538932 -391.830814)
			(xy 155.539454 -391.805559) (xy 155.547767 -391.755737) (xy 155.564168 -391.707963) (xy 155.588209 -391.66354)
			(xy 155.619233 -391.62368) (xy 155.656395 -391.58947) (xy 155.698681 -391.561844) (xy 155.744937 -391.541554)
			(xy 155.793902 -391.529154) (xy 155.84424 -391.524983) (xy 155.894578 -391.529154) (xy 155.943543 -391.541554)
			(xy 155.989799 -391.561844) (xy 156.032085 -391.58947) (xy 156.069247 -391.62368) (xy 156.100271 -391.66354)
			(xy 156.124312 -391.707963) (xy 156.140713 -391.755737) (xy 156.149026 -391.805559) (xy 156.149548 -391.830814)
			(xy 156.14905 -391.855184) (xy 156.14127 -391.9033) (xy 156.125958 -391.949573) (xy 156.1035 -391.992831)
			(xy 156.08935 -392.012678) (xy 156.083762 -392.020552) (xy 156.078682 -392.038332) (xy 156.087064 -392.124946)
			(xy 156.095192 -392.14171) (xy 156.102304 -392.14806) (xy 156.124282 -392.169063) (xy 156.161935 -392.216787)
			(xy 156.177234 -392.243056) (xy 156.181979 -392.250734) (xy 156.195729 -392.262407) (xy 156.212665 -392.268611)
			(xy 156.221684 -392.268964) (xy 156.666946 -392.268964) (xy 156.675979 -392.268659) (xy 156.692951 -392.262484)
			(xy 156.706706 -392.25078) (xy 156.711396 -392.243056) (xy 156.72667 -392.216878) (xy 156.764188 -392.169282)
			(xy 156.786072 -392.148314) (xy 156.793184 -392.14171) (xy 156.801566 -392.1252) (xy 156.809694 -392.038332)
			(xy 156.804614 -392.020552) (xy 156.799026 -392.012932) (xy 156.784865 -391.993053) (xy 156.762375 -391.949739)
			(xy 156.747056 -391.903401) (xy 156.739296 -391.855216) (xy 156.738828 -391.830814) (xy 156.73935 -391.805559)
			(xy 156.747663 -391.755737) (xy 156.764064 -391.707963) (xy 156.788105 -391.66354) (xy 156.819129 -391.62368)
			(xy 156.856291 -391.58947) (xy 156.898577 -391.561844) (xy 156.944833 -391.541554) (xy 156.993798 -391.529154)
			(xy 157.044136 -391.524983) (xy 157.094474 -391.529154) (xy 157.143439 -391.541554) (xy 157.189695 -391.561844)
			(xy 157.231981 -391.58947) (xy 157.269143 -391.62368) (xy 157.300167 -391.66354) (xy 157.324208 -391.707963)
			(xy 157.340609 -391.755737) (xy 157.348922 -391.805559) (xy 157.349444 -391.830814) (xy 157.34899 -391.855175)
			(xy 157.341285 -391.903284) (xy 157.326027 -391.949554) (xy 157.303604 -391.992809) (xy 157.2895 -392.012678)
			(xy 157.283658 -392.020298) (xy 157.278832 -392.038078) (xy 157.28696 -392.124946) (xy 157.295342 -392.141456)
			(xy 157.302454 -392.14806) (xy 157.32443 -392.169065) (xy 157.362078 -392.216791) (xy 157.377384 -392.243056)
			(xy 157.382127 -392.250739) (xy 157.395874 -392.262426) (xy 157.412812 -392.268646) (xy 157.421834 -392.268964)
			(xy 157.866842 -392.268964) (xy 157.875875 -392.26866) (xy 157.892848 -392.262485) (xy 157.906605 -392.250782)
			(xy 157.911292 -392.243056) (xy 157.926615 -392.216802) (xy 157.964258 -392.169075) (xy 157.986222 -392.14806)
			(xy 157.993334 -392.14171) (xy 158.001462 -392.124946) (xy 158.009844 -392.038332) (xy 158.004764 -392.020552)
			(xy 157.999176 -392.012678) (xy 157.985018 -391.992834) (xy 157.96253 -391.949586) (xy 157.94721 -391.90331)
			(xy 157.939451 -391.855187) (xy 157.938978 -391.830814) (xy 157.9395 -391.805559) (xy 157.947813 -391.755737)
			(xy 157.964214 -391.707963) (xy 157.988255 -391.66354) (xy 158.019279 -391.62368) (xy 158.056441 -391.58947)
			(xy 158.098727 -391.561844) (xy 158.144983 -391.541554) (xy 158.193948 -391.529154) (xy 158.244286 -391.524983)
			(xy 158.294624 -391.529154) (xy 158.343589 -391.541554) (xy 158.389845 -391.561844) (xy 158.432131 -391.58947)
			(xy 158.469293 -391.62368) (xy 158.500317 -391.66354) (xy 158.524358 -391.707963) (xy 158.540759 -391.755737)
			(xy 158.549072 -391.805559) (xy 158.549594 -391.830814) (xy 158.549095 -391.855184) (xy 158.541315 -391.903299)
			(xy 158.526 -391.94957) (xy 158.50354 -391.992827) (xy 158.489396 -392.012678) (xy 158.483808 -392.020552)
			(xy 158.478728 -392.038332) (xy 158.48711 -392.124946) (xy 158.495238 -392.14171) (xy 158.50235 -392.14806)
			(xy 158.524326 -392.169064) (xy 158.561975 -392.21679) (xy 158.57728 -392.243056) (xy 158.582023 -392.250739)
			(xy 158.59577 -392.262427) (xy 158.612708 -392.268649) (xy 158.62173 -392.268964) (xy 159.066992 -392.268964)
			(xy 159.076021 -392.268652) (xy 159.09298 -392.262466) (xy 159.106723 -392.250759) (xy 159.111442 -392.243056)
			(xy 159.126714 -392.216877) (xy 159.164229 -392.169277) (xy 159.186118 -392.148314) (xy 159.19323 -392.14171)
			(xy 159.201612 -392.1252) (xy 159.20974 -392.038332) (xy 159.20466 -392.020552) (xy 159.199072 -392.012932)
			(xy 159.184909 -391.993054) (xy 159.162416 -391.94974) (xy 159.147094 -391.903402) (xy 159.139333 -391.855217)
			(xy 159.138874 -391.830814) (xy 159.139396 -391.805559) (xy 159.147709 -391.755737) (xy 159.16411 -391.707963)
			(xy 159.188151 -391.66354) (xy 159.219175 -391.62368) (xy 159.256337 -391.58947) (xy 159.298623 -391.561844)
			(xy 159.344879 -391.541554) (xy 159.393844 -391.529154) (xy 159.444182 -391.524983) (xy 159.49452 -391.529154)
			(xy 159.543485 -391.541554) (xy 159.589741 -391.561844) (xy 159.632027 -391.58947) (xy 159.669189 -391.62368)
			(xy 159.700213 -391.66354) (xy 159.724254 -391.707963) (xy 159.740655 -391.755737) (xy 159.748968 -391.805559)
			(xy 159.74949 -391.830814) (xy 159.749036 -391.855175) (xy 159.741332 -391.903284) (xy 159.726076 -391.949556)
			(xy 159.703655 -391.992813) (xy 159.689546 -392.012678) (xy 159.683704 -392.020298) (xy 159.678878 -392.038078)
			(xy 159.687006 -392.124946) (xy 159.695388 -392.141456) (xy 159.7025 -392.14806) (xy 159.724479 -392.169063)
			(xy 159.762131 -392.216786) (xy 159.77743 -392.243056) (xy 159.782175 -392.250734) (xy 159.795924 -392.262409)
			(xy 159.812861 -392.268614) (xy 159.82188 -392.268964) (xy 160.266888 -392.268964) (xy 160.275917 -392.268653)
			(xy 160.292878 -392.262468) (xy 160.306622 -392.250761) (xy 160.311338 -392.243056) (xy 160.326659 -392.216801)
			(xy 160.364298 -392.16907) (xy 160.386268 -392.14806) (xy 160.39338 -392.14171) (xy 160.401508 -392.124946)
			(xy 160.40989 -392.038332) (xy 160.40481 -392.020552) (xy 160.399222 -392.012678) (xy 160.385066 -391.992833)
			(xy 160.362582 -391.949584) (xy 160.347265 -391.903309) (xy 160.339507 -391.855186) (xy 160.339024 -391.830814)
			(xy 160.339546 -391.805559) (xy 160.347859 -391.755737) (xy 160.36426 -391.707963) (xy 160.388301 -391.66354)
			(xy 160.419325 -391.62368) (xy 160.456487 -391.58947) (xy 160.498773 -391.561844) (xy 160.545029 -391.541554)
			(xy 160.593994 -391.529154) (xy 160.644332 -391.524983) (xy 160.69467 -391.529154) (xy 160.743635 -391.541554)
			(xy 160.789891 -391.561844) (xy 160.832177 -391.58947) (xy 160.869339 -391.62368) (xy 160.900363 -391.66354)
			(xy 160.924404 -391.707963) (xy 160.940805 -391.755737) (xy 160.949118 -391.805559) (xy 160.94964 -391.830814)
			(xy 160.949142 -391.855184) (xy 160.941362 -391.903299) (xy 160.926049 -391.949572) (xy 160.903591 -391.992831)
			(xy 160.889442 -392.012678) (xy 160.883854 -392.020552) (xy 160.878774 -392.038332) (xy 160.887156 -392.124946)
			(xy 160.895284 -392.14171) (xy 160.902396 -392.14806) (xy 160.92437 -392.169066) (xy 160.962015 -392.216794)
			(xy 160.977326 -392.243056) (xy 160.98207 -392.250734) (xy 160.99582 -392.26241) (xy 161.012756 -392.268617)
			(xy 161.021776 -392.268964) (xy 161.466784 -392.268964) (xy 161.475813 -392.268653) (xy 161.492775 -392.262469)
			(xy 161.50652 -392.250763) (xy 161.511234 -392.243056) (xy 161.526555 -392.216801) (xy 161.564194 -392.169069)
			(xy 161.586164 -392.14806) (xy 161.593276 -392.14171) (xy 161.601404 -392.124946) (xy 161.609786 -392.038332)
			(xy 161.604706 -392.020552) (xy 161.599118 -392.012678) (xy 161.584958 -391.992834) (xy 161.562467 -391.949587)
			(xy 161.547145 -391.903311) (xy 161.539385 -391.855187) (xy 161.53892 -391.830814) (xy 161.539442 -391.805559)
			(xy 161.547755 -391.755737) (xy 161.564156 -391.707963) (xy 161.588197 -391.66354) (xy 161.619221 -391.62368)
			(xy 161.656383 -391.58947) (xy 161.698669 -391.561844) (xy 161.744925 -391.541554) (xy 161.79389 -391.529154)
			(xy 161.844228 -391.524983) (xy 161.894566 -391.529154) (xy 161.943531 -391.541554) (xy 161.989787 -391.561844)
			(xy 162.032073 -391.58947) (xy 162.069235 -391.62368) (xy 162.100259 -391.66354) (xy 162.1243 -391.707963)
			(xy 162.140701 -391.755737) (xy 162.149014 -391.805559) (xy 162.149536 -391.830814) (xy 162.149038 -391.855184)
			(xy 162.141258 -391.903299) (xy 162.125945 -391.949572) (xy 162.103487 -391.99283) (xy 162.089338 -392.012678)
			(xy 162.08375 -392.020552) (xy 162.07867 -392.038332) (xy 162.087052 -392.124946) (xy 162.09518 -392.14171)
			(xy 162.102292 -392.14806) (xy 162.124266 -392.169066) (xy 162.161911 -392.216794) (xy 162.177222 -392.243056)
			(xy 162.181966 -392.250735) (xy 162.195716 -392.262412) (xy 162.212652 -392.26862) (xy 162.221672 -392.268964)
			(xy 162.66668 -392.268964) (xy 162.67571 -392.268654) (xy 162.692673 -392.262471) (xy 162.706419 -392.250765)
			(xy 162.71113 -392.243056) (xy 162.726451 -392.2168) (xy 162.76409 -392.169069) (xy 162.78606 -392.14806)
			(xy 162.793172 -392.14171) (xy 162.8013 -392.124946) (xy 162.809682 -392.038332) (xy 162.804602 -392.020552)
			(xy 162.799014 -392.012678) (xy 162.784854 -391.992834) (xy 162.762363 -391.949587) (xy 162.747042 -391.903311)
			(xy 162.739281 -391.855187) (xy 162.738816 -391.830814) (xy 162.739338 -391.805559) (xy 162.747651 -391.755737)
			(xy 162.764052 -391.707963) (xy 162.788093 -391.66354) (xy 162.819117 -391.62368) (xy 162.856279 -391.58947)
			(xy 162.898565 -391.561844) (xy 162.944821 -391.541554) (xy 162.993786 -391.529154) (xy 163.044124 -391.524983)
			(xy 163.094462 -391.529154) (xy 163.143427 -391.541554) (xy 163.189683 -391.561844) (xy 163.231969 -391.58947)
			(xy 163.269131 -391.62368) (xy 163.300155 -391.66354) (xy 163.324196 -391.707963) (xy 163.340597 -391.755737)
			(xy 163.34891 -391.805559) (xy 163.349432 -391.830814) (xy 163.348934 -391.855184) (xy 163.341154 -391.903299)
			(xy 163.325841 -391.949572) (xy 163.303382 -391.99283) (xy 163.289234 -392.012678) (xy 163.283646 -392.020552)
			(xy 163.278566 -392.038332) (xy 163.286948 -392.124946) (xy 163.295076 -392.14171) (xy 163.302188 -392.14806)
			(xy 163.324163 -392.169066) (xy 163.361808 -392.216794) (xy 163.377118 -392.243056) (xy 163.381862 -392.250735)
			(xy 163.395611 -392.262413) (xy 163.412548 -392.268622) (xy 163.421568 -392.268964) (xy 163.86683 -392.268964)
			(xy 163.875864 -392.268662) (xy 163.89284 -392.26249) (xy 163.906601 -392.250787) (xy 163.91128 -392.243056)
			(xy 163.926603 -392.216802) (xy 163.964245 -392.169074) (xy 163.98621 -392.14806) (xy 163.993322 -392.14171)
			(xy 164.00145 -392.124946) (xy 164.009832 -392.038332) (xy 164.004752 -392.020552) (xy 163.999164 -392.012678)
			(xy 163.985006 -391.992833) (xy 163.962519 -391.949585) (xy 163.9472 -391.90331) (xy 163.939441 -391.855186)
			(xy 163.938966 -391.830814) (xy 163.939488 -391.805559) (xy 163.947801 -391.755737) (xy 163.964202 -391.707963)
			(xy 163.988243 -391.66354) (xy 164.019267 -391.62368) (xy 164.056429 -391.58947) (xy 164.098715 -391.561844)
			(xy 164.144971 -391.541554) (xy 164.193936 -391.529154) (xy 164.244274 -391.524983) (xy 164.294612 -391.529154)
			(xy 164.343577 -391.541554) (xy 164.389833 -391.561844) (xy 164.432119 -391.58947) (xy 164.469281 -391.62368)
			(xy 164.500305 -391.66354) (xy 164.524346 -391.707963) (xy 164.540747 -391.755737) (xy 164.54906 -391.805559)
			(xy 164.549582 -391.830814) (xy 164.549084 -391.855184) (xy 164.541305 -391.9033) (xy 164.525994 -391.949574)
			(xy 164.503539 -391.992834) (xy 164.489384 -392.012678) (xy 164.483796 -392.020552) (xy 164.478716 -392.038332)
			(xy 164.487098 -392.124946) (xy 164.495226 -392.14171) (xy 164.502338 -392.14806) (xy 164.524315 -392.169064)
			(xy 164.561964 -392.216789) (xy 164.577268 -392.243056) (xy 164.58201 -392.250741) (xy 164.595756 -392.262432)
			(xy 164.612695 -392.268658) (xy 164.621718 -392.268964) (xy 165.066726 -392.268964) (xy 165.075761 -392.268663)
			(xy 165.092738 -392.262491) (xy 165.106499 -392.250789) (xy 165.111176 -392.243056) (xy 165.126499 -392.216802)
			(xy 165.16414 -392.169073) (xy 165.186106 -392.14806) (xy 165.193218 -392.14171) (xy 165.201346 -392.124946)
			(xy 165.209728 -392.038332) (xy 165.204648 -392.020552) (xy 165.19906 -392.012678) (xy 165.184902 -391.992833)
			(xy 165.162415 -391.949585) (xy 165.147097 -391.90331) (xy 165.139338 -391.855186) (xy 165.138862 -391.830814)
			(xy 165.139384 -391.805559) (xy 165.147697 -391.755737) (xy 165.164098 -391.707963) (xy 165.188139 -391.66354)
			(xy 165.219163 -391.62368) (xy 165.256325 -391.58947) (xy 165.298611 -391.561844) (xy 165.344867 -391.541554)
			(xy 165.393832 -391.529154) (xy 165.44417 -391.524983) (xy 165.494508 -391.529154) (xy 165.543473 -391.541554)
			(xy 165.589729 -391.561844) (xy 165.632015 -391.58947) (xy 165.669177 -391.62368) (xy 165.700201 -391.66354)
			(xy 165.724242 -391.707963) (xy 165.740643 -391.755737) (xy 165.748956 -391.805559) (xy 165.749478 -391.830814)
			(xy 165.74898 -391.855184) (xy 165.741201 -391.9033) (xy 165.72589 -391.949574) (xy 165.703434 -391.992834)
			(xy 165.68928 -392.012678) (xy 165.683692 -392.020552) (xy 165.678612 -392.038332) (xy 165.686994 -392.124946)
			(xy 165.695122 -392.14171) (xy 165.702234 -392.14806) (xy 165.724211 -392.169064) (xy 165.761861 -392.216789)
			(xy 165.777164 -392.243056) (xy 165.781905 -392.250741) (xy 165.795652 -392.262434) (xy 165.812591 -392.26866)
			(xy 165.821614 -392.268964) (xy 167.02024 -392.268964) (xy 167.030306 -392.268533) (xy 167.048897 -392.260804)
			(xy 167.056308 -392.253978) (xy 167.49268 -391.817606) (xy 167.500554 -391.799318) (xy 167.500554 -391.789412)
			(xy 167.501366 -391.762558) (xy 167.50961 -391.70947) (xy 167.525229 -391.658066) (xy 167.547916 -391.609366)
			(xy 167.577219 -391.564337) (xy 167.594534 -391.543794) (xy 167.60063 -391.536682) (xy 167.60698 -391.519664)
			(xy 167.60698 -391.43432) (xy 167.60063 -391.417302) (xy 167.594534 -391.41019) (xy 167.576891 -391.389259)
			(xy 167.547164 -391.343293) (xy 167.52432 -391.293546) (xy 167.508829 -391.241043) (xy 167.501012 -391.186863)
			(xy 167.500554 -391.159492) (xy 167.501058 -391.13145) (xy 167.509286 -391.075971) (xy 167.525549 -391.022296)
			(xy 167.549497 -390.971581) (xy 167.580613 -390.924919) (xy 167.618226 -390.883316) (xy 167.661526 -390.847669)
			(xy 167.709579 -390.818748) (xy 167.73525 -390.807448) (xy 167.749728 -390.801352) (xy 167.766492 -390.775952)
			(xy 167.766492 -390.695942) (xy 167.766154 -390.687332) (xy 167.760467 -390.671076) (xy 167.749746 -390.657598)
			(xy 167.742616 -390.652762) (xy 167.658542 -390.59993) (xy 167.632634 -390.59866) (xy 167.620696 -390.604248)
			(xy 167.598172 -390.61465) (xy 167.550786 -390.629341) (xy 167.501737 -390.636796) (xy 167.476932 -390.637268)
			(xy 167.450942 -390.636787) (xy 167.399602 -390.62866) (xy 167.350166 -390.6126) (xy 167.303851 -390.589003)
			(xy 167.261799 -390.558451) (xy 167.225044 -390.521695) (xy 167.194493 -390.479642) (xy 167.170897 -390.433327)
			(xy 167.154838 -390.38389) (xy 167.146712 -390.33255) (xy 167.146224 -390.30656) (xy 167.146639 -390.282787)
			(xy 167.153454 -390.235732) (xy 167.166938 -390.190139) (xy 167.186813 -390.146947) (xy 167.21267 -390.107046)
			(xy 167.228012 -390.088882) (xy 167.233694 -390.081761) (xy 167.240076 -390.06471) (xy 167.240458 -390.055608)
			(xy 167.240458 -390.024112) (xy 167.240079 -390.01501) (xy 167.233689 -389.997964) (xy 167.228012 -389.990838)
			(xy 167.212664 -389.972678) (xy 167.186799 -389.932782) (xy 167.166923 -389.889589) (xy 167.153447 -389.843992)
			(xy 167.146648 -389.796934) (xy 167.146224 -389.77316) (xy 167.146657 -389.748749) (xy 167.153829 -389.700456)
			(xy 167.168026 -389.653743) (xy 167.188939 -389.609627) (xy 167.216114 -389.569066) (xy 167.248958 -389.532943)
			(xy 167.286758 -389.502044) (xy 167.307514 -389.489188) (xy 167.318944 -389.48233) (xy 167.332152 -389.459216)
			(xy 167.332152 -389.344916) (xy 167.319198 -389.321802) (xy 167.307514 -389.31469) (xy 167.286803 -389.301815)
			(xy 167.249063 -389.270933) (xy 167.216272 -389.23484) (xy 167.189142 -389.194318) (xy 167.168262 -389.15025)
			(xy 167.154087 -389.10359) (xy 167.146923 -389.055355) (xy 167.146478 -389.030972) (xy 167.147035 -389.003351)
			(xy 167.156213 -388.948877) (xy 167.174308 -388.896683) (xy 167.20082 -388.848219) (xy 167.235011 -388.80483)
			(xy 167.275932 -388.76772) (xy 167.298878 -388.752334) (xy 167.310308 -388.745222) (xy 167.322754 -388.7216)
			(xy 167.319198 -388.6073) (xy 167.305482 -388.584694) (xy 167.293544 -388.57809) (xy 167.271852 -388.565456)
			(xy 167.232212 -388.534659) (xy 167.197681 -388.498226) (xy 167.16905 -388.456995) (xy 167.146978 -388.411911)
			(xy 167.13197 -388.364009) (xy 167.124373 -388.31439) (xy 167.123872 -388.289292) (xy 167.124302 -388.264395)
			(xy 167.131732 -388.215159) (xy 167.146468 -388.167596) (xy 167.168175 -388.122783) (xy 167.196363 -388.081737)
			(xy 167.213026 -388.063232) (xy 167.219884 -388.055866) (xy 167.226996 -388.037832) (xy 167.225726 -387.957314)
			(xy 167.225118 -387.947457) (xy 167.217407 -387.929294) (xy 167.21074 -387.922008) (xy 166.439088 -387.150356)
			(xy 166.419269 -387.129765) (xy 166.38565 -387.083552) (xy 166.359669 -387.032652) (xy 166.341962 -386.978317)
			(xy 166.332966 -386.921881) (xy 166.332408 -386.893308) (xy 166.332408 -386.880862) (xy 166.331942 -386.870617)
			(xy 166.32395 -386.851748) (xy 166.316914 -386.844286) (xy 166.256208 -386.78612) (xy 166.236904 -386.779008)
			(xy 166.22649 -386.779516) (xy 166.211504 -386.77977) (xy 166.185516 -386.779287) (xy 166.134179 -386.771156)
			(xy 166.084746 -386.755094) (xy 166.038435 -386.731496) (xy 165.996386 -386.700943) (xy 165.959635 -386.664188)
			(xy 165.929087 -386.622136) (xy 165.905493 -386.575822) (xy 165.889436 -386.526388) (xy 165.88131 -386.47505)
			(xy 165.880796 -386.449062) (xy 165.88105 -386.437378) (xy 165.881304 -386.427472) (xy 165.874954 -386.409438)
			(xy 165.815772 -386.342382) (xy 165.7985 -386.333492) (xy 165.788848 -386.33273) (xy 165.764654 -386.330085)
			(xy 165.717362 -386.318597) (xy 165.672266 -386.300295) (xy 165.630343 -386.275575) (xy 165.5925 -386.244973)
			(xy 165.559555 -386.209151) (xy 165.532222 -386.168883) (xy 165.511091 -386.125042) (xy 165.496621 -386.078575)
			(xy 165.49243 -386.0546) (xy 165.490906 -386.045202) (xy 165.21811 -385.57327) (xy 165.210744 -385.567428)
			(xy 165.191965 -385.551625) (xy 165.158831 -385.515418) (xy 165.13141 -385.474714) (xy 165.110305 -385.430404)
			(xy 165.095978 -385.383463) (xy 165.088744 -385.33492) (xy 165.088316 -385.31038) (xy 165.088801 -385.284392)
			(xy 165.096935 -385.233058) (xy 165.112999 -385.183627) (xy 165.136598 -385.137319) (xy 165.167151 -385.095272)
			(xy 165.203905 -385.058522) (xy 165.245956 -385.027975) (xy 165.292268 -385.004382) (xy 165.341701 -384.988324)
			(xy 165.393036 -384.980197) (xy 165.419024 -384.979672) (xy 165.445038 -384.980151) (xy 165.496427 -384.988288)
			(xy 165.545907 -385.004374) (xy 165.592257 -385.02801) (xy 165.634332 -385.058614) (xy 165.671096 -385.09543)
			(xy 165.701639 -385.13755) (xy 165.725209 -385.183934) (xy 165.741223 -385.233437) (xy 165.745668 -385.259072)
			(xy 165.747192 -385.26847) (xy 166.019988 -385.740402) (xy 166.027354 -385.746244) (xy 166.046134 -385.762047)
			(xy 166.079272 -385.798252) (xy 166.106696 -385.838956) (xy 166.127805 -385.883266) (xy 166.142136 -385.930207)
			(xy 166.149374 -385.978752) (xy 166.149782 -386.003292) (xy 166.148004 -386.037836) (xy 166.147418 -386.048376)
			(xy 166.153855 -386.068455) (xy 166.16045 -386.076698) (xy 166.181786 -386.101336) (xy 166.189197 -386.108842)
			(xy 166.208347 -386.117631) (xy 166.21887 -386.118354) (xy 166.22649 -386.118608) (xy 166.236904 -386.119116)
			(xy 166.256208 -386.112004) (xy 166.316914 -386.053838) (xy 166.323967 -386.046387) (xy 166.33196 -386.027512)
			(xy 166.332408 -386.017262) (xy 166.332408 -385.027932) (xy 166.332953 -384.999354) (xy 166.341922 -384.942906)
			(xy 166.359612 -384.888556) (xy 166.385588 -384.837643) (xy 166.41921 -384.791422) (xy 166.439088 -384.770884)
			(xy 166.892478 -384.317494) (xy 166.91308 -384.297704) (xy 166.959308 -384.264146) (xy 167.010213 -384.238224)
			(xy 167.064543 -384.220577) (xy 167.120964 -384.211638) (xy 167.149526 -384.211068) (xy 167.402002 -384.211068)
			(xy 167.42931 -384.211537) (xy 167.483318 -384.219668) (xy 167.5355 -384.23579) (xy 167.584681 -384.259541)
			(xy 167.607488 -384.274568) (xy 167.619172 -384.282442) (xy 167.647366 -384.28422) (xy 167.739314 -384.235706)
			(xy 167.747306 -384.231063) (xy 167.759557 -384.217245) (xy 167.766118 -384.199981) (xy 167.766492 -384.190748)
			(xy 167.766492 -383.509012) (xy 167.765956 -383.499024) (xy 167.758245 -383.480589) (xy 167.751506 -383.473198)
			(xy 166.758366 -382.480058) (xy 166.751022 -382.473247) (xy 166.732559 -382.465517) (xy 166.722552 -382.465072)
			(xy 165.76802 -382.465072) (xy 165.758268 -382.465494) (xy 165.740172 -382.472769) (xy 165.726128 -382.486301)
			(xy 165.721792 -382.495044) (xy 165.677596 -382.593088) (xy 165.681914 -382.622552) (xy 165.692074 -382.633982)
			(xy 165.707592 -382.652212) (xy 165.733761 -382.692299) (xy 165.753884 -382.735737) (xy 165.76754 -382.781621)
			(xy 165.774445 -382.828994) (xy 165.774878 -382.85293) (xy 165.774368 -382.878917) (xy 165.766238 -382.930252)
			(xy 165.750177 -382.979682) (xy 165.726581 -383.025992) (xy 165.696031 -383.06804) (xy 165.65928 -383.104791)
			(xy 165.617232 -383.135341) (xy 165.570922 -383.158937) (xy 165.521492 -383.174998) (xy 165.470157 -383.183128)
			(xy 165.418183 -383.183128) (xy 165.366848 -383.174998) (xy 165.317418 -383.158937) (xy 165.271108 -383.135341)
			(xy 165.22906 -383.104791) (xy 165.192309 -383.06804) (xy 165.161759 -383.025992) (xy 165.138163 -382.979682)
			(xy 165.122102 -382.930252) (xy 165.113972 -382.878917) (xy 165.113462 -382.85293) (xy 165.113883 -382.828992)
			(xy 165.12078 -382.781616) (xy 165.134433 -382.735728) (xy 165.154558 -382.692288) (xy 165.180734 -382.652202)
			(xy 165.196266 -382.633982) (xy 165.206426 -382.622552) (xy 165.210744 -382.593088) (xy 165.166548 -382.495044)
			(xy 165.162139 -382.486356) (xy 165.148095 -382.472877) (xy 165.130051 -382.465573) (xy 165.12032 -382.465072)
			(xy 164.568124 -382.465072) (xy 164.558371 -382.465494) (xy 164.540275 -382.472767) (xy 164.526229 -382.486299)
			(xy 164.521896 -382.495044) (xy 164.4777 -382.593088) (xy 164.482018 -382.622552) (xy 164.492178 -382.633982)
			(xy 164.507696 -382.652212) (xy 164.533865 -382.692299) (xy 164.553987 -382.735738) (xy 164.567643 -382.781621)
			(xy 164.574548 -382.828994) (xy 164.574982 -382.85293) (xy 164.574472 -382.878917) (xy 164.566342 -382.930252)
			(xy 164.550281 -382.979682) (xy 164.526685 -383.025992) (xy 164.496135 -383.06804) (xy 164.459384 -383.104791)
			(xy 164.417336 -383.135341) (xy 164.371026 -383.158937) (xy 164.321596 -383.174998) (xy 164.270261 -383.183128)
			(xy 164.218287 -383.183128) (xy 164.166952 -383.174998) (xy 164.117522 -383.158937) (xy 164.071212 -383.135341)
			(xy 164.029164 -383.104791) (xy 163.992413 -383.06804) (xy 163.961863 -383.025992) (xy 163.938267 -382.979682)
			(xy 163.922206 -382.930252) (xy 163.914076 -382.878917) (xy 163.913566 -382.85293) (xy 163.913987 -382.828992)
			(xy 163.920884 -382.781616) (xy 163.934537 -382.735728) (xy 163.954662 -382.692288) (xy 163.980839 -382.652202)
			(xy 163.99637 -382.633982) (xy 164.00653 -382.622552) (xy 164.010848 -382.593088) (xy 163.966652 -382.495044)
			(xy 163.962243 -382.486356) (xy 163.948199 -382.472875) (xy 163.930155 -382.46557) (xy 163.920424 -382.465072)
			(xy 163.367974 -382.465072) (xy 163.358227 -382.465502) (xy 163.340145 -382.472786) (xy 163.326115 -382.48632)
			(xy 163.321746 -382.495044) (xy 163.27755 -382.593088) (xy 163.281868 -382.622552) (xy 163.292028 -382.633982)
			(xy 163.307544 -382.652213) (xy 163.333709 -382.692301) (xy 163.353828 -382.73574) (xy 163.367482 -382.781623)
			(xy 163.374386 -382.828994) (xy 163.374832 -382.85293) (xy 163.374322 -382.878917) (xy 163.366192 -382.930252)
			(xy 163.350131 -382.979682) (xy 163.326535 -383.025992) (xy 163.295985 -383.06804) (xy 163.259234 -383.104791)
			(xy 163.217186 -383.135341) (xy 163.170876 -383.158937) (xy 163.121446 -383.174998) (xy 163.070111 -383.183128)
			(xy 163.018137 -383.183128) (xy 162.966802 -383.174998) (xy 162.917372 -383.158937) (xy 162.871062 -383.135341)
			(xy 162.829014 -383.104791) (xy 162.792263 -383.06804) (xy 162.761713 -383.025992) (xy 162.738117 -382.979682)
			(xy 162.722056 -382.930252) (xy 162.713926 -382.878917) (xy 162.713416 -382.85293) (xy 162.713837 -382.828992)
			(xy 162.720735 -382.781617) (xy 162.73439 -382.73573) (xy 162.754517 -382.692292) (xy 162.780697 -382.652209)
			(xy 162.79622 -382.633982) (xy 162.80638 -382.622552) (xy 162.810698 -382.593088) (xy 162.766502 -382.495044)
			(xy 162.762096 -382.48635) (xy 162.748054 -382.472856) (xy 162.730009 -382.465534) (xy 162.720274 -382.465072)
			(xy 162.168078 -382.465072) (xy 162.15833 -382.465502) (xy 162.140247 -382.472785) (xy 162.126216 -382.486318)
			(xy 162.12185 -382.495044) (xy 162.077654 -382.593088) (xy 162.081972 -382.622552) (xy 162.092132 -382.633982)
			(xy 162.107648 -382.652213) (xy 162.133812 -382.692301) (xy 162.153931 -382.73574) (xy 162.167585 -382.781623)
			(xy 162.174489 -382.828994) (xy 162.174936 -382.85293) (xy 162.174426 -382.878917) (xy 162.166296 -382.930252)
			(xy 162.150235 -382.979682) (xy 162.126639 -383.025992) (xy 162.096089 -383.06804) (xy 162.059338 -383.104791)
			(xy 162.01729 -383.135341) (xy 161.97098 -383.158937) (xy 161.92155 -383.174998) (xy 161.870215 -383.183128)
			(xy 161.818241 -383.183128) (xy 161.766906 -383.174998) (xy 161.717476 -383.158937) (xy 161.671166 -383.135341)
			(xy 161.629118 -383.104791) (xy 161.592367 -383.06804) (xy 161.561817 -383.025992) (xy 161.538221 -382.979682)
			(xy 161.52216 -382.930252) (xy 161.51403 -382.878917) (xy 161.51352 -382.85293) (xy 161.513941 -382.828992)
			(xy 161.520839 -382.781617) (xy 161.534494 -382.735731) (xy 161.554622 -382.692292) (xy 161.580801 -382.652209)
			(xy 161.596324 -382.633982) (xy 161.606484 -382.622552) (xy 161.610802 -382.593088) (xy 161.566606 -382.495044)
			(xy 161.5622 -382.48635) (xy 161.548159 -382.472855) (xy 161.530113 -382.465531) (xy 161.520378 -382.465072)
			(xy 160.968182 -382.465072) (xy 160.958434 -382.465501) (xy 160.94035 -382.472783) (xy 160.926317 -382.486316)
			(xy 160.921954 -382.495044) (xy 160.877758 -382.593088) (xy 160.882076 -382.622552) (xy 160.892236 -382.633982)
			(xy 160.907752 -382.652213) (xy 160.933916 -382.692302) (xy 160.954034 -382.73574) (xy 160.967688 -382.781623)
			(xy 160.974592 -382.828994) (xy 160.97504 -382.85293) (xy 160.97453 -382.878917) (xy 160.9664 -382.930252)
			(xy 160.950339 -382.979682) (xy 160.926743 -383.025992) (xy 160.896193 -383.06804) (xy 160.859442 -383.104791)
			(xy 160.817394 -383.135341) (xy 160.771084 -383.158937) (xy 160.721654 -383.174998) (xy 160.670319 -383.183128)
			(xy 160.618345 -383.183128) (xy 160.56701 -383.174998) (xy 160.51758 -383.158937) (xy 160.47127 -383.135341)
			(xy 160.429222 -383.104791) (xy 160.392471 -383.06804) (xy 160.361921 -383.025992) (xy 160.338325 -382.979682)
			(xy 160.322264 -382.930252) (xy 160.314134 -382.878917) (xy 160.313624 -382.85293) (xy 160.314045 -382.828992)
			(xy 160.320943 -382.781617) (xy 160.334598 -382.735731) (xy 160.354726 -382.692293) (xy 160.380906 -382.65221)
			(xy 160.396428 -382.633982) (xy 160.406588 -382.622552) (xy 160.410906 -382.593088) (xy 160.36671 -382.495044)
			(xy 160.362304 -382.486349) (xy 160.348263 -382.472853) (xy 160.330217 -382.465528) (xy 160.320482 -382.465072)
			(xy 159.768032 -382.465072) (xy 159.758278 -382.465492) (xy 159.740179 -382.472764) (xy 159.726131 -382.486295)
			(xy 159.721804 -382.495044) (xy 159.677608 -382.593088) (xy 159.681926 -382.622552) (xy 159.692086 -382.633982)
			(xy 159.707604 -382.652212) (xy 159.733772 -382.692299) (xy 159.753894 -382.735738) (xy 159.767549 -382.781622)
			(xy 159.774454 -382.828994) (xy 159.77489 -382.85293) (xy 159.77438 -382.878917) (xy 159.76625 -382.930252)
			(xy 159.750189 -382.979682) (xy 159.726593 -383.025992) (xy 159.696043 -383.06804) (xy 159.659292 -383.104791)
			(xy 159.617244 -383.135341) (xy 159.570934 -383.158937) (xy 159.521504 -383.174998) (xy 159.470169 -383.183128)
			(xy 159.418195 -383.183128) (xy 159.36686 -383.174998) (xy 159.31743 -383.158937) (xy 159.27112 -383.135341)
			(xy 159.229072 -383.104791) (xy 159.192321 -383.06804) (xy 159.161771 -383.025992) (xy 159.138175 -382.979682)
			(xy 159.122114 -382.930252) (xy 159.113984 -382.878917) (xy 159.113474 -382.85293) (xy 159.113895 -382.828992)
			(xy 159.120792 -382.781616) (xy 159.134446 -382.735729) (xy 159.154571 -382.692289) (xy 159.180748 -382.652203)
			(xy 159.196278 -382.633982) (xy 159.206438 -382.622552) (xy 159.210756 -382.593088) (xy 159.16656 -382.495044)
			(xy 159.162152 -382.486355) (xy 159.148108 -382.472872) (xy 159.130064 -382.465565) (xy 159.120332 -382.465072)
			(xy 158.568136 -382.465072) (xy 158.558382 -382.465492) (xy 158.540282 -382.472762) (xy 158.526233 -382.486294)
			(xy 158.521908 -382.495044) (xy 158.477712 -382.593088) (xy 158.48203 -382.622552) (xy 158.49219 -382.633982)
			(xy 158.507708 -382.652212) (xy 158.533875 -382.6923) (xy 158.553997 -382.735738) (xy 158.567652 -382.781622)
			(xy 158.574557 -382.828994) (xy 158.574994 -382.85293) (xy 158.574484 -382.878917) (xy 158.566354 -382.930252)
			(xy 158.550293 -382.979682) (xy 158.526697 -383.025992) (xy 158.496147 -383.06804) (xy 158.459396 -383.104791)
			(xy 158.417348 -383.135341) (xy 158.371038 -383.158937) (xy 158.321608 -383.174998) (xy 158.270273 -383.183128)
			(xy 158.218299 -383.183128) (xy 158.166964 -383.174998) (xy 158.117534 -383.158937) (xy 158.071224 -383.135341)
			(xy 158.029176 -383.104791) (xy 157.992425 -383.06804) (xy 157.961875 -383.025992) (xy 157.938279 -382.979682)
			(xy 157.922218 -382.930252) (xy 157.914088 -382.878917) (xy 157.913578 -382.85293) (xy 157.913999 -382.828992)
			(xy 157.920896 -382.781616) (xy 157.93455 -382.735729) (xy 157.954676 -382.692289) (xy 157.980853 -382.652204)
			(xy 157.996382 -382.633982) (xy 158.006542 -382.622552) (xy 158.01086 -382.593088) (xy 157.966664 -382.495044)
			(xy 157.962256 -382.486355) (xy 157.948213 -382.472871) (xy 157.930168 -382.465562) (xy 157.920436 -382.465072)
			(xy 157.367986 -382.465072) (xy 157.358237 -382.4655) (xy 157.340152 -382.472782) (xy 157.326118 -382.486315)
			(xy 157.321758 -382.495044) (xy 157.277562 -382.593088) (xy 157.28188 -382.622552) (xy 157.29204 -382.633982)
			(xy 157.307556 -382.652213) (xy 157.333719 -382.692302) (xy 157.353838 -382.73574) (xy 157.367491 -382.781623)
			(xy 157.374395 -382.828994) (xy 157.374844 -382.85293) (xy 157.374334 -382.878917) (xy 157.366204 -382.930252)
			(xy 157.350143 -382.979682) (xy 157.326547 -383.025992) (xy 157.295997 -383.06804) (xy 157.259246 -383.104791)
			(xy 157.217198 -383.135341) (xy 157.170888 -383.158937) (xy 157.121458 -383.174998) (xy 157.070123 -383.183128)
			(xy 157.018149 -383.183128) (xy 156.966814 -383.174998) (xy 156.917384 -383.158937) (xy 156.871074 -383.135341)
			(xy 156.829026 -383.104791) (xy 156.792275 -383.06804) (xy 156.761725 -383.025992) (xy 156.738129 -382.979682)
			(xy 156.722068 -382.930252) (xy 156.713938 -382.878917) (xy 156.713428 -382.85293) (xy 156.713849 -382.828993)
			(xy 156.720747 -382.781617) (xy 156.734403 -382.735731) (xy 156.754531 -382.692293) (xy 156.780711 -382.65221)
			(xy 156.796232 -382.633982) (xy 156.806392 -382.622552) (xy 156.81071 -382.593088) (xy 156.766514 -382.495044)
			(xy 156.762108 -382.486349) (xy 156.748068 -382.472852) (xy 156.730022 -382.465525) (xy 156.720286 -382.465072)
			(xy 156.16809 -382.465072) (xy 156.158341 -382.4655) (xy 156.140254 -382.47278) (xy 156.126219 -382.486313)
			(xy 156.121862 -382.495044) (xy 156.077666 -382.593088) (xy 156.081984 -382.622552) (xy 156.092144 -382.633982)
			(xy 156.107659 -382.652213) (xy 156.133823 -382.692302) (xy 156.153941 -382.735741) (xy 156.167594 -382.781624)
			(xy 156.174498 -382.828994) (xy 156.174948 -382.85293) (xy 156.174438 -382.878917) (xy 156.166308 -382.930252)
			(xy 156.150247 -382.979682) (xy 156.126651 -383.025992) (xy 156.096101 -383.06804) (xy 156.05935 -383.104791)
			(xy 156.017302 -383.135341) (xy 155.970992 -383.158937) (xy 155.921562 -383.174998) (xy 155.870227 -383.183128)
			(xy 155.818253 -383.183128) (xy 155.766918 -383.174998) (xy 155.717488 -383.158937) (xy 155.671178 -383.135341)
			(xy 155.62913 -383.104791) (xy 155.592379 -383.06804) (xy 155.561829 -383.025992) (xy 155.538233 -382.979682)
			(xy 155.522172 -382.930252) (xy 155.514042 -382.878917) (xy 155.513532 -382.85293) (xy 155.513953 -382.828993)
			(xy 155.520851 -382.781617) (xy 155.534507 -382.735731) (xy 155.554635 -382.692293) (xy 155.580815 -382.652211)
			(xy 155.596336 -382.633982) (xy 155.606496 -382.622552) (xy 155.610814 -382.593088) (xy 155.566618 -382.495044)
			(xy 155.562208 -382.486359) (xy 155.548162 -382.472888) (xy 155.530119 -382.465595) (xy 155.52039 -382.465072)
			(xy 154.968194 -382.465072) (xy 154.958444 -382.465499) (xy 154.940357 -382.472779) (xy 154.92632 -382.486311)
			(xy 154.921966 -382.495044) (xy 154.87777 -382.593088) (xy 154.882088 -382.622552) (xy 154.892248 -382.633982)
			(xy 154.907763 -382.652213) (xy 154.933926 -382.692302) (xy 154.954044 -382.735741) (xy 154.967697 -382.781624)
			(xy 154.974601 -382.828995) (xy 154.975052 -382.85293) (xy 154.974542 -382.878917) (xy 154.966412 -382.930252)
			(xy 154.950351 -382.979682) (xy 154.926755 -383.025992) (xy 154.896205 -383.06804) (xy 154.859454 -383.104791)
			(xy 154.817406 -383.135341) (xy 154.771096 -383.158937) (xy 154.721666 -383.174998) (xy 154.670331 -383.183128)
			(xy 154.618357 -383.183128) (xy 154.567022 -383.174998) (xy 154.517592 -383.158937) (xy 154.471282 -383.135341)
			(xy 154.429234 -383.104791) (xy 154.392483 -383.06804) (xy 154.361933 -383.025992) (xy 154.338337 -382.979682)
			(xy 154.322276 -382.930252) (xy 154.314146 -382.878917) (xy 154.313636 -382.85293) (xy 154.314057 -382.828993)
			(xy 154.320955 -382.781617) (xy 154.334611 -382.735731) (xy 154.354739 -382.692293) (xy 154.38092 -382.652211)
			(xy 154.39644 -382.633982) (xy 154.4066 -382.622552) (xy 154.410918 -382.593088) (xy 154.366722 -382.495044)
			(xy 154.362312 -382.486359) (xy 154.348267 -382.472887) (xy 154.330223 -382.465592) (xy 154.320494 -382.465072)
			(xy 153.768044 -382.465072) (xy 153.7583 -382.465508) (xy 153.740227 -382.472798) (xy 153.726206 -382.486332)
			(xy 153.721816 -382.495044) (xy 153.67762 -382.593088) (xy 153.681938 -382.622552) (xy 153.692098 -382.633982)
			(xy 153.707615 -382.652212) (xy 153.733782 -382.6923) (xy 153.753903 -382.735739) (xy 153.767558 -382.781622)
			(xy 153.774463 -382.828994) (xy 153.774902 -382.85293) (xy 153.774392 -382.878917) (xy 153.766262 -382.930252)
			(xy 153.750201 -382.979682) (xy 153.726605 -383.025992) (xy 153.696055 -383.06804) (xy 153.659304 -383.104791)
			(xy 153.617256 -383.135341) (xy 153.570946 -383.158937) (xy 153.521516 -383.174998) (xy 153.470181 -383.183128)
			(xy 153.418207 -383.183128) (xy 153.366872 -383.174998) (xy 153.317442 -383.158937) (xy 153.271132 -383.135341)
			(xy 153.229084 -383.104791) (xy 153.192333 -383.06804) (xy 153.161783 -383.025992) (xy 153.138187 -382.979682)
			(xy 153.122126 -382.930252) (xy 153.113996 -382.878917) (xy 153.113486 -382.85293) (xy 153.113907 -382.828992)
			(xy 153.120804 -382.781616) (xy 153.134458 -382.735729) (xy 153.154584 -382.69229) (xy 153.180762 -382.652205)
			(xy 153.19629 -382.633982) (xy 153.20645 -382.622552) (xy 153.210768 -382.593088) (xy 153.166572 -382.495044)
			(xy 153.162164 -382.486353) (xy 153.148122 -382.472867) (xy 153.130077 -382.465556) (xy 153.120344 -382.465072)
			(xy 152.568148 -382.465072) (xy 152.558403 -382.465507) (xy 152.540329 -382.472796) (xy 152.526307 -382.486331)
			(xy 152.52192 -382.495044) (xy 152.477724 -382.593088) (xy 152.482042 -382.622552) (xy 152.492202 -382.633982)
			(xy 152.507719 -382.652212) (xy 152.533886 -382.6923) (xy 152.554007 -382.735739) (xy 152.567662 -382.781622)
			(xy 152.574566 -382.828994) (xy 152.575006 -382.85293) (xy 152.574496 -382.878917) (xy 152.566366 -382.930252)
			(xy 152.550305 -382.979682) (xy 152.526709 -383.025992) (xy 152.496159 -383.06804) (xy 152.459408 -383.104791)
			(xy 152.41736 -383.135341) (xy 152.37105 -383.158937) (xy 152.32162 -383.174998) (xy 152.270285 -383.183128)
			(xy 152.218311 -383.183128) (xy 152.166976 -383.174998) (xy 152.117546 -383.158937) (xy 152.071236 -383.135341)
			(xy 152.029188 -383.104791) (xy 151.992437 -383.06804) (xy 151.961887 -383.025992) (xy 151.938291 -382.979682)
			(xy 151.92223 -382.930252) (xy 151.9141 -382.878917) (xy 151.91359 -382.85293) (xy 151.914011 -382.828992)
			(xy 151.920908 -382.781616) (xy 151.934563 -382.735729) (xy 151.954689 -382.69229) (xy 151.980867 -382.652205)
			(xy 151.996394 -382.633982) (xy 152.006554 -382.622552) (xy 152.010872 -382.593088) (xy 151.966676 -382.495044)
			(xy 151.962269 -382.486353) (xy 151.948226 -382.472866) (xy 151.930181 -382.465553) (xy 151.920448 -382.465072)
			(xy 151.367998 -382.465072) (xy 151.358248 -382.465498) (xy 151.340159 -382.472777) (xy 151.326122 -382.48631)
			(xy 151.32177 -382.495044) (xy 151.277574 -382.593088) (xy 151.281892 -382.622552) (xy 151.292052 -382.633982)
			(xy 151.307567 -382.652213) (xy 151.33373 -382.692302) (xy 151.353848 -382.735741) (xy 151.3675 -382.781624)
			(xy 151.374404 -382.828995) (xy 151.374856 -382.85293) (xy 151.374346 -382.878917) (xy 151.366216 -382.930252)
			(xy 151.350155 -382.979682) (xy 151.326559 -383.025992) (xy 151.296009 -383.06804) (xy 151.259258 -383.104791)
			(xy 151.21721 -383.135341) (xy 151.1709 -383.158937) (xy 151.12147 -383.174998) (xy 151.070135 -383.183128)
			(xy 151.018161 -383.183128) (xy 150.966826 -383.174998) (xy 150.917396 -383.158937) (xy 150.871086 -383.135341)
			(xy 150.829038 -383.104791) (xy 150.792287 -383.06804) (xy 150.761737 -383.025992) (xy 150.738141 -382.979682)
			(xy 150.72208 -382.930252) (xy 150.71395 -382.878917) (xy 150.71344 -382.85293) (xy 150.713861 -382.828993)
			(xy 150.720759 -382.781617) (xy 150.734415 -382.735732) (xy 150.754544 -382.692294) (xy 150.780724 -382.652212)
			(xy 150.796244 -382.633982) (xy 150.806404 -382.622552) (xy 150.810722 -382.593088) (xy 150.766526 -382.495044)
			(xy 150.762116 -382.486359) (xy 150.748071 -382.472885) (xy 150.730027 -382.465589) (xy 150.720298 -382.465072)
			(xy 150.168102 -382.465072) (xy 150.158352 -382.465497) (xy 150.140262 -382.472776) (xy 150.126223 -382.486308)
			(xy 150.121874 -382.495044) (xy 150.077678 -382.593088) (xy 150.081996 -382.622552) (xy 150.092156 -382.633982)
			(xy 150.107671 -382.652213) (xy 150.133834 -382.692302) (xy 150.153951 -382.735741) (xy 150.167603 -382.781624)
			(xy 150.174507 -382.828995) (xy 150.17496 -382.85293) (xy 150.17445 -382.878917) (xy 150.16632 -382.930252)
			(xy 150.150259 -382.979682) (xy 150.126663 -383.025992) (xy 150.096113 -383.06804) (xy 150.059362 -383.104791)
			(xy 150.017314 -383.135341) (xy 149.971004 -383.158937) (xy 149.921574 -383.174998) (xy 149.870239 -383.183128)
			(xy 149.818265 -383.183128) (xy 149.76693 -383.174998) (xy 149.7175 -383.158937) (xy 149.67119 -383.135341)
			(xy 149.629142 -383.104791) (xy 149.592391 -383.06804) (xy 149.561841 -383.025992) (xy 149.538245 -382.979682)
			(xy 149.522184 -382.930252) (xy 149.514054 -382.878917) (xy 149.513544 -382.85293) (xy 149.513965 -382.828993)
			(xy 149.520863 -382.781617) (xy 149.534519 -382.735732) (xy 149.554648 -382.692294) (xy 149.580829 -382.652212)
			(xy 149.596348 -382.633982) (xy 149.606508 -382.622552) (xy 149.610826 -382.593088) (xy 149.56663 -382.495044)
			(xy 149.56222 -382.486358) (xy 149.548175 -382.472884) (xy 149.530132 -382.465586) (xy 149.520402 -382.465072)
			(xy 148.968206 -382.465072) (xy 148.958455 -382.465497) (xy 148.940364 -382.472774) (xy 148.926324 -382.486306)
			(xy 148.921978 -382.495044) (xy 148.877782 -382.593088) (xy 148.8821 -382.622552) (xy 148.89226 -382.633982)
			(xy 148.907775 -382.652213) (xy 148.933937 -382.692303) (xy 148.954054 -382.735741) (xy 148.967706 -382.781624)
			(xy 148.97461 -382.828995) (xy 148.975064 -382.85293) (xy 148.974554 -382.878917) (xy 148.966424 -382.930252)
			(xy 148.950363 -382.979682) (xy 148.926767 -383.025992) (xy 148.896217 -383.06804) (xy 148.859466 -383.104791)
			(xy 148.817418 -383.135341) (xy 148.771108 -383.158937) (xy 148.721678 -383.174998) (xy 148.670343 -383.183128)
			(xy 148.618369 -383.183128) (xy 148.567034 -383.174998) (xy 148.517604 -383.158937) (xy 148.471294 -383.135341)
			(xy 148.429246 -383.104791) (xy 148.392495 -383.06804) (xy 148.361945 -383.025992) (xy 148.338349 -382.979682)
			(xy 148.322288 -382.930252) (xy 148.314158 -382.878917) (xy 148.313648 -382.85293) (xy 148.31407 -382.828993)
			(xy 148.320967 -382.781618) (xy 148.334624 -382.735732) (xy 148.354753 -382.692294) (xy 148.380934 -382.652213)
			(xy 148.396452 -382.633982) (xy 148.406612 -382.622552) (xy 148.41093 -382.593088) (xy 148.366734 -382.495044)
			(xy 148.362324 -382.486358) (xy 148.34828 -382.472882) (xy 148.330236 -382.465583) (xy 148.320506 -382.465072)
			(xy 147.768056 -382.465072) (xy 147.75831 -382.465505) (xy 147.740234 -382.472793) (xy 147.726209 -382.486327)
			(xy 147.721828 -382.495044) (xy 147.677632 -382.593088) (xy 147.68195 -382.622552) (xy 147.69211 -382.633982)
			(xy 147.707627 -382.652212) (xy 147.733793 -382.6923) (xy 147.753913 -382.735739) (xy 147.767568 -382.781622)
			(xy 147.774472 -382.828994) (xy 147.774914 -382.85293) (xy 147.774404 -382.878917) (xy 147.766274 -382.930252)
			(xy 147.750213 -382.979682) (xy 147.726617 -383.025992) (xy 147.696067 -383.06804) (xy 147.659316 -383.104791)
			(xy 147.617268 -383.135341) (xy 147.570958 -383.158937) (xy 147.521528 -383.174998) (xy 147.470193 -383.183128)
			(xy 147.418219 -383.183128) (xy 147.366884 -383.174998) (xy 147.317454 -383.158937) (xy 147.271144 -383.135341)
			(xy 147.229096 -383.104791) (xy 147.192345 -383.06804) (xy 147.161795 -383.025992) (xy 147.138199 -382.979682)
			(xy 147.122138 -382.930252) (xy 147.114008 -382.878917) (xy 147.113498 -382.85293) (xy 147.113919 -382.828992)
			(xy 147.120816 -382.781616) (xy 147.134471 -382.73573) (xy 147.154598 -382.69229) (xy 147.180776 -382.652206)
			(xy 147.196302 -382.633982) (xy 147.206462 -382.622552) (xy 147.21078 -382.593088) (xy 147.166584 -382.495044)
			(xy 147.162177 -382.486352) (xy 147.148135 -382.472863) (xy 147.13009 -382.465547) (xy 147.120356 -382.465072)
			(xy 145.07591 -382.465072) (xy 145.065838 -382.465493) (xy 145.047229 -382.473201) (xy 145.039842 -382.480058)
			(xy 144.737328 -382.782572) (xy 144.73049 -382.789973) (xy 144.722777 -382.808572) (xy 144.722342 -382.81864)
			(xy 144.722342 -382.934543) (xy 145.76603 -382.934543) (xy 145.76603 -382.882569) (xy 145.77416 -382.831234)
			(xy 145.790221 -382.781804) (xy 145.813817 -382.735494) (xy 145.844367 -382.693446) (xy 145.881118 -382.656695)
			(xy 145.923166 -382.626145) (xy 145.969476 -382.602549) (xy 146.018906 -382.586488) (xy 146.070241 -382.578358)
			(xy 146.122215 -382.578358) (xy 146.17355 -382.586488) (xy 146.22298 -382.602549) (xy 146.26929 -382.626145)
			(xy 146.311338 -382.656695) (xy 146.348089 -382.693446) (xy 146.378639 -382.735494) (xy 146.402235 -382.781804)
			(xy 146.418296 -382.831234) (xy 146.426426 -382.882569) (xy 146.426936 -382.908556) (xy 146.426426 -382.934543)
			(xy 146.418296 -382.985878) (xy 146.402235 -383.035308) (xy 146.378639 -383.081618) (xy 146.348089 -383.123666)
			(xy 146.311338 -383.160417) (xy 146.26929 -383.190967) (xy 146.22298 -383.214563) (xy 146.17355 -383.230624)
			(xy 146.122215 -383.238754) (xy 146.070241 -383.238754) (xy 146.018906 -383.230624) (xy 145.969476 -383.214563)
			(xy 145.923166 -383.190967) (xy 145.881118 -383.160417) (xy 145.844367 -383.123666) (xy 145.813817 -383.081618)
			(xy 145.790221 -383.035308) (xy 145.77416 -382.985878) (xy 145.76603 -382.934543) (xy 144.722342 -382.934543)
			(xy 144.722342 -383.155698) (xy 144.722766 -383.165767) (xy 144.730485 -383.184368) (xy 144.737328 -383.191766)
			(xy 145.16227 -383.616454) (xy 145.16967 -383.623294) (xy 145.188269 -383.631011) (xy 145.198338 -383.63144)
			(xy 164.034978 -383.63144) (xy 164.045041 -383.631879) (xy 164.063621 -383.639617) (xy 164.071046 -383.646426)
			(xy 164.414454 -383.989834) (xy 164.4213 -383.997232) (xy 164.429029 -384.015831) (xy 164.42944 -384.025902)
			(xy 164.42944 -384.643709) (xy 164.759896 -384.643709) (xy 164.759896 -384.591735) (xy 164.768026 -384.5404)
			(xy 164.784087 -384.49097) (xy 164.807683 -384.44466) (xy 164.838233 -384.402612) (xy 164.874984 -384.365861)
			(xy 164.917032 -384.335311) (xy 164.963342 -384.311715) (xy 165.012772 -384.295654) (xy 165.064107 -384.287524)
			(xy 165.116081 -384.287524) (xy 165.167416 -384.295654) (xy 165.216846 -384.311715) (xy 165.263156 -384.335311)
			(xy 165.305204 -384.365861) (xy 165.341955 -384.402612) (xy 165.372505 -384.44466) (xy 165.396101 -384.49097)
			(xy 165.412162 -384.5404) (xy 165.420292 -384.591735) (xy 165.420802 -384.617722) (xy 165.420292 -384.643709)
			(xy 165.412162 -384.695044) (xy 165.396101 -384.744474) (xy 165.372505 -384.790784) (xy 165.341955 -384.832832)
			(xy 165.305204 -384.869583) (xy 165.263156 -384.900133) (xy 165.216846 -384.923729) (xy 165.167416 -384.93979)
			(xy 165.116081 -384.94792) (xy 165.064107 -384.94792) (xy 165.012772 -384.93979) (xy 164.963342 -384.923729)
			(xy 164.917032 -384.900133) (xy 164.874984 -384.869583) (xy 164.838233 -384.832832) (xy 164.807683 -384.790784)
			(xy 164.784087 -384.744474) (xy 164.768026 -384.695044) (xy 164.759896 -384.643709) (xy 164.42944 -384.643709)
			(xy 164.42944 -385.03225) (xy 164.42994 -385.042676) (xy 164.438192 -385.061826) (xy 164.445442 -385.069334)
			(xy 164.465085 -385.08847) (xy 164.498371 -385.132048) (xy 164.524002 -385.180526) (xy 164.541274 -385.232571)
			(xy 164.546026 -385.25958) (xy 164.547296 -385.268978) (xy 164.819838 -385.740402) (xy 164.827204 -385.746244)
			(xy 164.845982 -385.762048) (xy 164.879114 -385.798256) (xy 164.906535 -385.83896) (xy 164.927641 -385.883269)
			(xy 164.941969 -385.93021) (xy 164.949206 -385.978752) (xy 164.949632 -386.003292) (xy 164.949378 -386.015484)
			(xy 164.949124 -386.025136) (xy 164.95522 -386.04317) (xy 165.013894 -386.11048) (xy 165.030658 -386.119116)
			(xy 165.040564 -386.120132) (xy 165.067334 -386.123456) (xy 165.119367 -386.137675) (xy 165.168403 -386.16015)
			(xy 165.213142 -386.190284) (xy 165.252398 -386.227278) (xy 165.285131 -386.270151) (xy 165.310473 -386.317768)
			(xy 165.327753 -386.368867) (xy 165.336512 -386.422092) (xy 165.336982 -386.449062) (xy 165.336419 -386.476344)
			(xy 165.327454 -386.530165) (xy 165.309779 -386.581786) (xy 165.283871 -386.629807) (xy 165.250434 -386.672924)
			(xy 165.23081 -386.691886) (xy 165.223364 -386.699379) (xy 165.214829 -386.718674) (xy 165.2143 -386.729224)
			(xy 165.2143 -386.8039) (xy 165.214891 -386.814433) (xy 165.223425 -386.833703) (xy 165.23081 -386.841238)
			(xy 165.250466 -386.86017) (xy 165.28391 -386.90329) (xy 165.309819 -386.951317) (xy 165.327489 -387.002946)
			(xy 165.336441 -387.056777) (xy 165.336982 -387.084062) (xy 165.336549 -387.108179) (xy 165.329553 -387.155904)
			(xy 165.315704 -387.202108) (xy 165.295294 -387.245813) (xy 165.282372 -387.26618) (xy 165.27653 -387.27507)
			(xy 165.272974 -387.295136) (xy 165.294056 -387.387338) (xy 165.306248 -387.404102) (xy 165.315138 -387.409436)
			(xy 165.335939 -387.422292) (xy 165.373855 -387.45317) (xy 165.406804 -387.489301) (xy 165.434066 -387.529895)
			(xy 165.455046 -387.574065) (xy 165.469284 -387.620845) (xy 165.476469 -387.669212) (xy 165.476936 -387.693662)
			(xy 165.476498 -387.718033) (xy 165.469342 -387.766245) (xy 165.455194 -387.812888) (xy 165.434359 -387.856952)
			(xy 165.407288 -387.897484) (xy 165.374566 -387.933609) (xy 165.356032 -387.94944) (xy 165.347142 -387.956552)
			(xy 165.337744 -387.97611) (xy 165.33495 -388.075424) (xy 165.343586 -388.09549) (xy 165.351968 -388.10311)
			(xy 165.370386 -388.1206) (xy 165.401721 -388.16057) (xy 165.426013 -388.205173) (xy 165.442591 -388.25318)
			(xy 165.450999 -388.303268) (xy 165.451536 -388.328662) (xy 165.451445 -388.339944) (xy 165.449791 -388.362446)
			(xy 165.448234 -388.37362) (xy 165.446964 -388.38251) (xy 165.45052 -388.400036) (xy 165.493954 -388.470902)
			(xy 165.50767 -388.482078) (xy 165.516306 -388.484872) (xy 165.538548 -388.492812) (xy 165.580464 -388.514567)
			(xy 165.618532 -388.542515) (xy 165.651844 -388.575989) (xy 165.679608 -388.614191) (xy 165.690804 -388.634986)
			(xy 165.691312 -388.636002) (xy 166.083742 -389.314944) (xy 166.096525 -389.338294) (xy 166.114716 -389.388318)
			(xy 166.123999 -389.440731) (xy 166.124636 -389.467344) (xy 166.124186 -389.491348) (xy 166.116666 -389.538765)
			(xy 166.101818 -389.58442) (xy 166.080009 -389.627189) (xy 166.051775 -389.666018) (xy 166.017813 -389.699951)
			(xy 165.978958 -389.72815) (xy 165.93617 -389.749922) (xy 165.890502 -389.764729) (xy 165.843079 -389.772207)
			(xy 165.819074 -389.772652) (xy 165.795543 -389.772215) (xy 165.74904 -389.764988) (xy 165.704197 -389.75071)
			(xy 165.662077 -389.729718) (xy 165.623677 -389.702511) (xy 165.589908 -389.669732) (xy 165.56157 -389.632159)
			(xy 165.550088 -389.611616) (xy 165.549834 -389.611108) (xy 165.549326 -389.610346) (xy 165.151562 -388.922006)
			(xy 165.139663 -388.899338) (xy 165.122788 -388.851007) (xy 165.114226 -388.800536) (xy 165.113716 -388.77494)
			(xy 165.113716 -388.774432) (xy 165.1138 -388.763087) (xy 165.115456 -388.740457) (xy 165.117018 -388.72922)
			(xy 165.118288 -388.72033) (xy 165.114732 -388.703058) (xy 165.071298 -388.631938) (xy 165.057328 -388.621016)
			(xy 165.048946 -388.617968) (xy 165.026545 -388.609947) (xy 164.984353 -388.587958) (xy 164.946081 -388.559693)
			(xy 164.912655 -388.525834) (xy 164.884883 -388.487203) (xy 164.863438 -388.444732) (xy 164.848837 -388.39945)
			(xy 164.841435 -388.352451) (xy 164.84092 -388.328662) (xy 164.84142 -388.303264) (xy 164.84982 -388.253168)
			(xy 164.866399 -388.205154) (xy 164.890698 -388.160548) (xy 164.922047 -388.12058) (xy 164.940488 -388.10311)
			(xy 164.94887 -388.09549) (xy 164.957506 -388.075424) (xy 164.954712 -387.97611) (xy 164.945314 -387.956552)
			(xy 164.936424 -387.94944) (xy 164.917862 -387.933638) (xy 164.885133 -387.897513) (xy 164.858058 -387.856976)
			(xy 164.837223 -387.812906) (xy 164.82308 -387.766256) (xy 164.815934 -387.718035) (xy 164.81552 -387.693662)
			(xy 164.815959 -387.669546) (xy 164.822965 -387.621826) (xy 164.836823 -387.575628) (xy 164.85724 -387.531931)
			(xy 164.87013 -387.511544) (xy 164.875972 -387.502654) (xy 164.879528 -387.482588) (xy 164.858446 -387.390386)
			(xy 164.846254 -387.373622) (xy 164.837364 -387.368288) (xy 164.816561 -387.355433) (xy 164.778643 -387.324555)
			(xy 164.745691 -387.288425) (xy 164.718426 -387.247831) (xy 164.697444 -387.203662) (xy 164.683202 -387.156881)
			(xy 164.676013 -387.108512) (xy 164.675566 -387.084062) (xy 164.676127 -387.056779) (xy 164.685087 -387.002954)
			(xy 164.702758 -386.951329) (xy 164.728661 -386.903303) (xy 164.762093 -386.860179) (xy 164.781738 -386.841238)
			(xy 164.789182 -386.833744) (xy 164.797718 -386.814449) (xy 164.798248 -386.8039) (xy 164.798248 -386.729224)
			(xy 164.79766 -386.71869) (xy 164.789126 -386.699419) (xy 164.781738 -386.691886) (xy 164.762083 -386.672953)
			(xy 164.728641 -386.629832) (xy 164.702733 -386.581805) (xy 164.685062 -386.530176) (xy 164.676108 -386.476347)
			(xy 164.675566 -386.449062) (xy 164.67582 -386.43687) (xy 164.676074 -386.427218) (xy 164.669978 -386.409184)
			(xy 164.611304 -386.341874) (xy 164.59454 -386.333238) (xy 164.584634 -386.332222) (xy 164.551614 -386.327142)
			(xy 164.540184 -386.324602) (xy 164.51834 -386.329936) (xy 164.448236 -386.387086) (xy 164.439832 -386.394701)
			(xy 164.430062 -386.415134) (xy 164.42944 -386.426456) (xy 164.42944 -388.53237) (xy 164.429834 -388.541892)
			(xy 164.436747 -388.559639) (xy 164.442902 -388.566914) (xy 164.45685 -388.582431) (xy 164.480816 -388.616586)
			(xy 164.490654 -388.634986) (xy 164.491416 -388.636256) (xy 164.883592 -389.314944) (xy 164.8964 -389.338276)
			(xy 164.914551 -389.388308) (xy 164.923735 -389.440732) (xy 164.924232 -389.467344) (xy 164.923758 -389.491334)
			(xy 164.916247 -389.538721) (xy 164.901416 -389.584351) (xy 164.87963 -389.627099) (xy 164.851426 -389.665914)
			(xy 164.817499 -389.699839) (xy 164.778682 -389.728041) (xy 164.735933 -389.749823) (xy 164.690302 -389.764651)
			(xy 164.642914 -389.77216) (xy 164.618924 -389.772652) (xy 164.602281 -389.772455) (xy 164.569188 -389.768886)
			(xy 164.552884 -389.76554) (xy 164.541708 -389.763) (xy 164.519356 -389.768334) (xy 164.44849 -389.82523)
			(xy 164.439976 -389.83286) (xy 164.430089 -389.853439) (xy 164.42944 -389.864854) (xy 164.42944 -390.160002)
			(xy 164.71317 -390.160002) (xy 164.71713 -390.110948) (xy 164.728907 -390.063164) (xy 164.748198 -390.017888)
			(xy 164.774501 -389.976292) (xy 164.807136 -389.939455) (xy 164.845257 -389.90833) (xy 164.887878 -389.883723)
			(xy 164.933894 -389.866271) (xy 164.982113 -389.856427) (xy 165.031288 -389.854446) (xy 165.080143 -389.860378)
			(xy 165.127414 -389.87407) (xy 165.171876 -389.895168) (xy 165.212379 -389.923124) (xy 165.247872 -389.957216)
			(xy 165.277437 -389.99656) (xy 165.300308 -390.040137) (xy 165.315892 -390.086818) (xy 165.323787 -390.135395)
			(xy 165.324282 -390.160002) (xy 165.323787 -390.184609) (xy 165.323563 -390.185989) (xy 166.04285 -390.185989)
			(xy 166.04285 -390.134015) (xy 166.05098 -390.08268) (xy 166.067041 -390.03325) (xy 166.090637 -389.98694)
			(xy 166.121187 -389.944892) (xy 166.157938 -389.908141) (xy 166.199986 -389.877591) (xy 166.246296 -389.853995)
			(xy 166.295726 -389.837934) (xy 166.347061 -389.829804) (xy 166.399035 -389.829804) (xy 166.45037 -389.837934)
			(xy 166.4998 -389.853995) (xy 166.54611 -389.877591) (xy 166.588158 -389.908141) (xy 166.624909 -389.944892)
			(xy 166.655459 -389.98694) (xy 166.679055 -390.03325) (xy 166.695116 -390.08268) (xy 166.703246 -390.134015)
			(xy 166.703756 -390.160002) (xy 166.703246 -390.185989) (xy 166.695116 -390.237324) (xy 166.679055 -390.286754)
			(xy 166.655459 -390.333064) (xy 166.624909 -390.375112) (xy 166.588158 -390.411863) (xy 166.54611 -390.442413)
			(xy 166.4998 -390.466009) (xy 166.45037 -390.48207) (xy 166.399035 -390.4902) (xy 166.347061 -390.4902)
			(xy 166.295726 -390.48207) (xy 166.246296 -390.466009) (xy 166.199986 -390.442413) (xy 166.157938 -390.411863)
			(xy 166.121187 -390.375112) (xy 166.090637 -390.333064) (xy 166.067041 -390.286754) (xy 166.05098 -390.237324)
			(xy 166.04285 -390.185989) (xy 165.323563 -390.185989) (xy 165.315892 -390.233186) (xy 165.300308 -390.279867)
			(xy 165.277437 -390.323444) (xy 165.247872 -390.362788) (xy 165.212379 -390.39688) (xy 165.171876 -390.424836)
			(xy 165.127414 -390.445934) (xy 165.080143 -390.459626) (xy 165.031288 -390.465558) (xy 164.982113 -390.463577)
			(xy 164.933894 -390.453733) (xy 164.887878 -390.436281) (xy 164.845257 -390.411674) (xy 164.807136 -390.380549)
			(xy 164.774501 -390.343712) (xy 164.748198 -390.302116) (xy 164.728907 -390.25684) (xy 164.71713 -390.209056)
			(xy 164.71317 -390.160002) (xy 164.42944 -390.160002) (xy 164.42944 -390.884918) (xy 164.429012 -390.894985)
			(xy 164.421286 -390.913579) (xy 164.414454 -390.920986) (xy 164.378386 -390.957054) (xy 164.370989 -390.963903)
			(xy 164.35239 -390.97164) (xy 164.342318 -390.97204) (xy 144.71396 -390.97204) (xy 144.703894 -390.972472)
			(xy 144.685304 -390.980201) (xy 144.677892 -390.987026) (xy 144.547844 -391.117074) (xy 144.541004 -391.124474)
			(xy 144.53329 -391.143073) (xy 144.532858 -391.153142) (xy 144.532858 -391.49401) (xy 144.533285 -391.504078)
			(xy 144.541008 -391.522674) (xy 144.547844 -391.530078) (xy 144.819703 -391.801937) (xy 145.792446 -391.801937)
			(xy 145.792446 -391.749963) (xy 145.800576 -391.698628) (xy 145.816637 -391.649198) (xy 145.840233 -391.602888)
			(xy 145.870783 -391.56084) (xy 145.907534 -391.524089) (xy 145.949582 -391.493539) (xy 145.995892 -391.469943)
			(xy 146.045322 -391.453882) (xy 146.096657 -391.445752) (xy 146.148631 -391.445752) (xy 146.199966 -391.453882)
			(xy 146.249396 -391.469943) (xy 146.295706 -391.493539) (xy 146.337754 -391.524089) (xy 146.374505 -391.56084)
			(xy 146.405055 -391.602888) (xy 146.428651 -391.649198) (xy 146.444712 -391.698628) (xy 146.452842 -391.749963)
			(xy 146.453352 -391.77595) (xy 146.452842 -391.801937) (xy 146.444712 -391.853272) (xy 146.428651 -391.902702)
			(xy 146.405055 -391.949012) (xy 146.374505 -391.99106) (xy 146.337754 -392.027811) (xy 146.295706 -392.058361)
			(xy 146.249396 -392.081957) (xy 146.199966 -392.098018) (xy 146.148631 -392.106148) (xy 146.096657 -392.106148)
			(xy 146.045322 -392.098018) (xy 145.995892 -392.081957) (xy 145.949582 -392.058361) (xy 145.907534 -392.027811)
			(xy 145.870783 -391.99106) (xy 145.840233 -391.949012) (xy 145.816637 -391.902702) (xy 145.800576 -391.853272)
			(xy 145.792446 -391.801937) (xy 144.819703 -391.801937) (xy 144.957546 -391.93978) (xy 144.969484 -391.946638)
			(xy 144.976342 -391.948416) (xy 145.003681 -391.955785) (xy 145.055316 -391.979008) (xy 145.101929 -392.011142)
			(xy 145.122392 -392.030712) (xy 145.664936 -392.573256) (xy 145.672281 -392.580066) (xy 145.690744 -392.587792)
			(xy 145.70075 -392.588242)
		)
		(stroke
			(width 0)
			(type solid)
		)
		(fill yes)
		(layer "In2.Cu")
		(net "NCF_CPU1_P2_GND")
	)
	(gr_poly
		(pts
			(xy 375.525538 -267.93063) (xy 375.535379 -267.930101) (xy 375.553551 -267.922525) (xy 375.560844 -267.915898)
			(xy 375.69902 -267.777722) (xy 375.705738 -267.770486) (xy 375.713343 -267.752281) (xy 375.713752 -267.742416)
			(xy 375.713752 -267.435838) (xy 375.713692 -267.431565) (xy 375.712287 -267.423136) (xy 375.710958 -267.419074)
			(xy 375.703084 -267.396722) (xy 375.698258 -267.390118) (xy 375.687974 -267.376417) (xy 375.668911 -267.347948)
			(xy 375.660158 -267.333222) (xy 375.511314 -267.076936) (xy 375.500843 -267.058457) (xy 375.482409 -267.020188)
			(xy 375.474484 -267.000482) (xy 375.469404 -266.987528) (xy 375.44756 -266.97051) (xy 375.334022 -266.955524)
			(xy 375.308622 -266.966446) (xy 375.30024 -266.977622) (xy 375.285739 -266.996456) (xy 375.251887 -267.029821)
			(xy 375.213275 -267.05754) (xy 375.170836 -267.078944) (xy 375.125594 -267.093517) (xy 375.078641 -267.100906)
			(xy 375.054876 -267.10132) (xy 375.029621 -267.100797) (xy 374.9798 -267.092479) (xy 374.932028 -267.076076)
			(xy 374.887607 -267.052033) (xy 374.847749 -267.021007) (xy 374.813541 -266.983845) (xy 374.785915 -266.941559)
			(xy 374.765627 -266.895302) (xy 374.753228 -266.846338) (xy 374.749057 -266.796) (xy 374.753228 -266.745662)
			(xy 374.765627 -266.696698) (xy 374.785915 -266.650441) (xy 374.813541 -266.608155) (xy 374.847749 -266.570993)
			(xy 374.887607 -266.539967) (xy 374.932028 -266.515924) (xy 374.9798 -266.499521) (xy 375.029621 -266.491203)
			(xy 375.054876 -266.490704) (xy 375.078641 -266.491156) (xy 375.125596 -266.498523) (xy 375.17084 -266.513082)
			(xy 375.21328 -266.534481) (xy 375.251887 -266.562203) (xy 375.285729 -266.595576) (xy 375.30024 -266.614402)
			(xy 375.308622 -266.625578) (xy 375.334022 -266.6365) (xy 375.44756 -266.621514) (xy 375.469404 -266.604496)
			(xy 375.474484 -266.591542) (xy 375.487203 -266.560474) (xy 375.519023 -266.501362) (xy 375.557693 -266.446485)
			(xy 375.602655 -266.396633) (xy 375.653264 -266.352524) (xy 375.680732 -266.333224) (xy 375.686066 -266.329668)
			(xy 375.69394 -266.321032) (xy 375.707656 -266.29614) (xy 375.710507 -266.290453) (xy 375.713596 -266.278116)
			(xy 375.713752 -266.271756) (xy 375.713752 -265.815826) (xy 375.713691 -265.811553) (xy 375.712284 -265.803125)
			(xy 375.710958 -265.799062) (xy 375.703084 -265.77671) (xy 375.698258 -265.770106) (xy 375.687975 -265.756404)
			(xy 375.668912 -265.727936) (xy 375.660158 -265.71321) (xy 375.511314 -265.456924) (xy 375.500844 -265.438444)
			(xy 375.48241 -265.400175) (xy 375.474484 -265.38047) (xy 375.469404 -265.367516) (xy 375.44756 -265.350498)
			(xy 375.334022 -265.335512) (xy 375.308622 -265.346434) (xy 375.30024 -265.35761) (xy 375.285736 -265.376439)
			(xy 375.25188 -265.409795) (xy 375.213267 -265.437506) (xy 375.170829 -265.458904) (xy 375.125589 -265.473472)
			(xy 375.078639 -265.480858) (xy 375.054876 -265.481308) (xy 375.029622 -265.480785) (xy 374.979803 -265.472468)
			(xy 374.932033 -265.456065) (xy 374.887614 -265.432023) (xy 374.847757 -265.400999) (xy 374.81355 -265.363837)
			(xy 374.785926 -265.321553) (xy 374.765638 -265.275298) (xy 374.75324 -265.226336) (xy 374.749069 -265.176)
			(xy 374.75324 -265.125664) (xy 374.765638 -265.076702) (xy 374.785926 -265.030447) (xy 374.81355 -264.988163)
			(xy 374.847757 -264.951001) (xy 374.887614 -264.919977) (xy 374.932033 -264.895935) (xy 374.979803 -264.879532)
			(xy 375.029622 -264.871215) (xy 375.054876 -264.870692) (xy 375.078641 -264.871144) (xy 375.125596 -264.878511)
			(xy 375.170841 -264.893069) (xy 375.213281 -264.914468) (xy 375.251889 -264.942189) (xy 375.285732 -264.975562)
			(xy 375.30024 -264.99439) (xy 375.308622 -265.005566) (xy 375.334022 -265.016488) (xy 375.44756 -265.001502)
			(xy 375.469404 -264.984484) (xy 375.474484 -264.97153) (xy 375.487203 -264.940463) (xy 375.519024 -264.881351)
			(xy 375.557695 -264.826475) (xy 375.602658 -264.776624) (xy 375.653267 -264.732516) (xy 375.680732 -264.713212)
			(xy 375.686066 -264.709656) (xy 375.69394 -264.70102) (xy 375.707656 -264.676128) (xy 375.710505 -264.67044)
			(xy 375.713592 -264.658103) (xy 375.713752 -264.651744) (xy 375.713752 -264.195814) (xy 375.71369 -264.191541)
			(xy 375.712281 -264.183113) (xy 375.710958 -264.17905) (xy 375.703084 -264.156698) (xy 375.698258 -264.150094)
			(xy 375.687975 -264.136392) (xy 375.668912 -264.107923) (xy 375.660158 -264.093198) (xy 375.511314 -263.836912)
			(xy 375.500844 -263.818432) (xy 375.482411 -263.780163) (xy 375.474484 -263.760458) (xy 375.469404 -263.747504)
			(xy 375.44756 -263.730486) (xy 375.334022 -263.7155) (xy 375.308622 -263.726422) (xy 375.30024 -263.737598)
			(xy 375.285736 -263.756428) (xy 375.251881 -263.789785) (xy 375.213268 -263.817497) (xy 375.17083 -263.838896)
			(xy 375.12559 -263.853464) (xy 375.07864 -263.860851) (xy 375.054876 -263.861296) (xy 375.030886 -263.860824)
			(xy 374.983498 -263.853314) (xy 374.937868 -263.838485) (xy 374.89512 -263.8167) (xy 374.856305 -263.788496)
			(xy 374.822381 -263.754567) (xy 374.794181 -263.71575) (xy 374.772401 -263.672998) (xy 374.757577 -263.627367)
			(xy 374.750074 -263.579978) (xy 374.749568 -263.555988) (xy 374.749936 -263.533624) (xy 374.756435 -263.489372)
			(xy 374.762522 -263.46785) (xy 374.766078 -263.456166) (xy 374.762014 -263.432798) (xy 374.707404 -263.358884)
			(xy 374.699792 -263.34966) (xy 374.678454 -263.338932) (xy 374.66651 -263.33831) (xy 373.563134 -263.33831)
			(xy 373.551197 -263.338954) (xy 373.529866 -263.349679) (xy 373.52224 -263.358884) (xy 373.46763 -263.432798)
			(xy 373.463566 -263.456166) (xy 373.467122 -263.46785) (xy 373.473161 -263.489383) (xy 373.479658 -263.533628)
			(xy 373.480076 -263.555988) (xy 373.479554 -263.581243) (xy 373.471241 -263.631065) (xy 373.45484 -263.678839)
			(xy 373.430799 -263.723262) (xy 373.399775 -263.763122) (xy 373.362613 -263.797332) (xy 373.320327 -263.824958)
			(xy 373.274071 -263.845248) (xy 373.225106 -263.857648) (xy 373.174768 -263.861819) (xy 373.12443 -263.857648)
			(xy 373.075465 -263.845248) (xy 373.029209 -263.824958) (xy 372.986923 -263.797332) (xy 372.949761 -263.763122)
			(xy 372.918737 -263.723262) (xy 372.894696 -263.678839) (xy 372.878295 -263.631065) (xy 372.869982 -263.581243)
			(xy 372.86946 -263.555988) (xy 372.869828 -263.533624) (xy 372.876326 -263.489372) (xy 372.882414 -263.46785)
			(xy 372.88597 -263.456166) (xy 372.881906 -263.432798) (xy 372.827296 -263.358884) (xy 372.819684 -263.349661)
			(xy 372.798345 -263.338937) (xy 372.786402 -263.33831) (xy 372.051326 -263.33831) (xy 372.041489 -263.337774)
			(xy 372.023327 -263.330187) (xy 372.01602 -263.323578) (xy 371.749828 -263.057386) (xy 371.734588 -263.05002)
			(xy 371.726206 -263.04875) (xy 371.701332 -263.045063) (xy 371.653171 -263.030615) (xy 371.60803 -263.008468)
			(xy 371.567129 -262.979222) (xy 371.531575 -262.943668) (xy 371.502329 -262.902767) (xy 371.480184 -262.857625)
			(xy 371.465737 -262.809464) (xy 371.462046 -262.78459) (xy 371.460776 -262.776208) (xy 371.45341 -262.760968)
			(xy 371.156738 -262.464296) (xy 371.149336 -262.45746) (xy 371.130738 -262.449748) (xy 371.12067 -262.44931)
			(xy 371.082316 -262.44931) (xy 371.072293 -262.449727) (xy 371.053773 -262.457394) (xy 371.039598 -262.471568)
			(xy 371.031928 -262.490087) (xy 371.031516 -262.50011) (xy 371.031516 -262.510016) (xy 371.038628 -262.52805)
			(xy 371.045486 -262.535162) (xy 371.061263 -262.552297) (xy 371.087961 -262.59046) (xy 371.108548 -262.632239)
			(xy 371.122545 -262.676661) (xy 371.129627 -262.722694) (xy 371.130068 -262.745982) (xy 371.129546 -262.771237)
			(xy 371.121233 -262.821059) (xy 371.104832 -262.868833) (xy 371.080791 -262.913256) (xy 371.049767 -262.953116)
			(xy 371.012605 -262.987326) (xy 370.970319 -263.014952) (xy 370.924063 -263.035242) (xy 370.875098 -263.047642)
			(xy 370.82476 -263.051813) (xy 370.774422 -263.047642) (xy 370.725457 -263.035242) (xy 370.679201 -263.014952)
			(xy 370.636915 -262.987326) (xy 370.599753 -262.953116) (xy 370.568729 -262.913256) (xy 370.544688 -262.868833)
			(xy 370.528287 -262.821059) (xy 370.519974 -262.771237) (xy 370.519452 -262.745982) (xy 370.519957 -262.720247)
			(xy 370.528547 -262.669502) (xy 370.545548 -262.620923) (xy 370.557552 -262.598154) (xy 370.564156 -262.58647)
			(xy 370.563648 -262.559546) (xy 370.51361 -262.474456) (xy 370.508847 -262.467027) (xy 370.495314 -262.455722)
			(xy 370.478739 -262.449706) (xy 370.469922 -262.44931) (xy 370.239544 -262.44931) (xy 370.230739 -262.449736)
			(xy 370.214197 -262.45579) (xy 370.200663 -262.467065) (xy 370.195856 -262.474456) (xy 370.145818 -262.559546)
			(xy 370.14531 -262.58647) (xy 370.151914 -262.598154) (xy 370.163887 -262.620936) (xy 370.180874 -262.669515)
			(xy 370.189499 -262.720251) (xy 370.190014 -262.745982) (xy 370.189492 -262.771237) (xy 370.181179 -262.821059)
			(xy 370.164778 -262.868833) (xy 370.140737 -262.913256) (xy 370.109713 -262.953116) (xy 370.072551 -262.987326)
			(xy 370.030265 -263.014952) (xy 369.984009 -263.035242) (xy 369.935044 -263.047642) (xy 369.884706 -263.051813)
			(xy 369.834368 -263.047642) (xy 369.785403 -263.035242) (xy 369.739147 -263.014952) (xy 369.696861 -262.987326)
			(xy 369.659699 -262.953116) (xy 369.628675 -262.913256) (xy 369.604634 -262.868833) (xy 369.588233 -262.821059)
			(xy 369.57992 -262.771237) (xy 369.579398 -262.745982) (xy 369.579903 -262.720248) (xy 369.588495 -262.669502)
			(xy 369.605498 -262.620925) (xy 369.617498 -262.598154) (xy 369.624102 -262.58647) (xy 369.623594 -262.559546)
			(xy 369.573556 -262.474456) (xy 369.568796 -262.467021) (xy 369.555264 -262.455705) (xy 369.538687 -262.449674)
			(xy 369.529868 -262.44931) (xy 367.606326 -262.44931) (xy 367.596489 -262.448774) (xy 367.578327 -262.441187)
			(xy 367.57102 -262.434578) (xy 366.965738 -261.829296) (xy 366.958336 -261.82246) (xy 366.939738 -261.814748)
			(xy 366.92967 -261.81431) (xy 365.736378 -261.81431) (xy 365.726997 -261.814751) (xy 365.709492 -261.821512)
			(xy 365.695568 -261.834092) (xy 365.690912 -261.84225) (xy 365.644684 -261.934452) (xy 365.647224 -261.9629)
			(xy 365.656114 -261.974584) (xy 365.672137 -261.996993) (xy 365.697584 -262.045849) (xy 365.714906 -262.09814)
			(xy 365.723658 -262.152527) (xy 365.724186 -262.18007) (xy 365.723706 -262.205769) (xy 365.716045 -262.256593)
			(xy 365.700896 -262.305707) (xy 365.678595 -262.352015) (xy 365.649642 -262.394482) (xy 365.614682 -262.432159)
			(xy 365.574498 -262.464205) (xy 365.529986 -262.489904) (xy 365.482141 -262.508681) (xy 365.432032 -262.520119)
			(xy 365.380778 -262.52396) (xy 365.329524 -262.520119) (xy 365.279415 -262.508681) (xy 365.23157 -262.489904)
			(xy 365.187058 -262.464205) (xy 365.146874 -262.432159) (xy 365.111914 -262.394482) (xy 365.082961 -262.352015)
			(xy 365.06066 -262.305707) (xy 365.045511 -262.256593) (xy 365.03785 -262.205769) (xy 365.03737 -262.18007)
			(xy 365.037894 -262.152526) (xy 365.046645 -262.098139) (xy 365.063965 -262.045845) (xy 365.089411 -261.996988)
			(xy 365.105442 -261.974584) (xy 365.114332 -261.9629) (xy 365.116872 -261.934452) (xy 365.070644 -261.84225)
			(xy 365.066095 -261.834007) (xy 365.052155 -261.821373) (xy 365.034587 -261.81464) (xy 365.025178 -261.81431)
			(xy 364.891828 -261.81431) (xy 364.88199 -261.813774) (xy 364.863829 -261.806188) (xy 364.856522 -261.799578)
			(xy 364.56874 -261.511796) (xy 364.560563 -261.504387) (xy 364.53989 -261.496733) (xy 364.528862 -261.497064)
			(xy 364.442502 -261.503922) (xy 364.423198 -261.514844) (xy 364.416594 -261.523988) (xy 364.400304 -261.545627)
			(xy 364.36206 -261.583978) (xy 364.318277 -261.615858) (xy 364.270036 -261.640479) (xy 364.218531 -261.657232)
			(xy 364.165037 -261.665701) (xy 364.137956 -261.666228) (xy 364.110973 -261.665695) (xy 364.057671 -261.657247)
			(xy 364.006347 -261.640566) (xy 363.958263 -261.616062) (xy 363.914605 -261.584339) (xy 363.876446 -261.546177)
			(xy 363.844725 -261.502516) (xy 363.820225 -261.454431) (xy 363.803547 -261.403106) (xy 363.795103 -261.349803)
			(xy 363.794548 -261.32282) (xy 363.795059 -261.296142) (xy 363.803323 -261.24343) (xy 363.819639 -261.192629)
			(xy 363.843615 -261.144963) (xy 363.874673 -261.101578) (xy 363.912068 -261.063518) (xy 363.954898 -261.031699)
			(xy 364.002134 -261.006886) (xy 364.052638 -260.989677) (xy 364.105197 -260.980485) (xy 364.13186 -260.979412)
			(xy 364.137956 -260.979412) (xy 364.160983 -260.979787) (xy 364.20663 -260.985906) (xy 364.251053 -260.998054)
			(xy 364.293461 -261.016015) (xy 364.31347 -261.027418) (xy 364.325154 -261.03453) (xy 364.352332 -261.034784)
			(xy 364.4392 -260.985508) (xy 364.446823 -260.980783) (xy 364.458408 -260.967107) (xy 364.464563 -260.950274)
			(xy 364.464854 -260.941312) (xy 364.464854 -260.21665) (xy 364.464463 -260.207518) (xy 364.458034 -260.190422)
			(xy 364.446013 -260.17667) (xy 364.438184 -260.171946) (xy 364.34903 -260.12394) (xy 364.321598 -260.12521)
			(xy 364.30966 -260.13283) (xy 364.288641 -260.145991) (xy 364.243621 -260.166787) (xy 364.196079 -260.180896)
			(xy 364.147004 -260.188025) (xy 364.122208 -260.188456) (xy 364.115604 -260.188456) (xy 364.089212 -260.187465)
			(xy 364.037189 -260.178379) (xy 363.987169 -260.161436) (xy 363.940333 -260.137035) (xy 363.897784 -260.105752)
			(xy 363.860526 -260.068323) (xy 363.829437 -260.025632) (xy 363.805251 -259.978685) (xy 363.788536 -259.928588)
			(xy 363.779688 -259.876524) (xy 363.7788 -259.850128) (xy 363.7788 -259.846572) (xy 363.7788 -259.845048)
			(xy 363.779287 -259.819564) (xy 363.786857 -259.76916) (xy 363.80178 -259.720424) (xy 363.812328 -259.69722)
			(xy 363.817916 -259.685282) (xy 363.816392 -259.659374) (xy 363.764576 -259.577332) (xy 363.759726 -259.57029)
			(xy 363.746335 -259.559673) (xy 363.730195 -259.55406) (xy 363.72165 -259.55371) (xy 361.922822 -259.55371)
			(xy 361.914274 -259.554033) (xy 361.89813 -259.559656) (xy 361.884739 -259.570281) (xy 361.879896 -259.577332)
			(xy 361.82808 -259.659374) (xy 361.826556 -259.685282) (xy 361.832144 -259.69722) (xy 361.842721 -259.720414)
			(xy 361.857663 -259.769149) (xy 361.865222 -259.819561) (xy 361.865672 -259.845048) (xy 361.865672 -259.850128)
			(xy 361.864767 -259.876852) (xy 361.8557 -259.929547) (xy 361.838577 -259.9802) (xy 361.813811 -260.027587)
			(xy 361.782 -260.070563) (xy 361.743913 -260.108091) (xy 361.70047 -260.139263) (xy 361.652722 -260.163326)
			(xy 361.601821 -260.179698) (xy 361.548998 -260.187984) (xy 361.49553 -260.187984) (xy 361.442707 -260.179698)
			(xy 361.391806 -260.163326) (xy 361.344058 -260.139263) (xy 361.300615 -260.108091) (xy 361.262528 -260.070563)
			(xy 361.230717 -260.027587) (xy 361.205951 -259.9802) (xy 361.188828 -259.929547) (xy 361.179761 -259.876852)
			(xy 361.178856 -259.850128) (xy 361.178856 -259.846572) (xy 361.178856 -259.845048) (xy 361.179343 -259.819564)
			(xy 361.186912 -259.769159) (xy 361.201833 -259.720423) (xy 361.212384 -259.69722) (xy 361.217972 -259.685282)
			(xy 361.216448 -259.659374) (xy 361.164632 -259.577332) (xy 361.159785 -259.570283) (xy 361.146396 -259.559652)
			(xy 361.130254 -259.554022) (xy 361.121706 -259.55371) (xy 360.396028 -259.55371) (xy 360.38619 -259.553174)
			(xy 360.368029 -259.545588) (xy 360.360722 -259.538978) (xy 359.74147 -258.919726) (xy 359.732444 -258.911588)
			(xy 359.709349 -258.904142) (xy 359.697274 -258.905502) (xy 359.60558 -258.920996) (xy 359.586022 -258.935474)
			(xy 359.580434 -258.94665) (xy 359.567893 -258.970935) (xy 359.536297 -259.01553) (xy 359.498037 -259.054559)
			(xy 359.454079 -259.087035) (xy 359.405532 -259.112139) (xy 359.353622 -259.129238) (xy 359.299659 -259.137899)
			(xy 359.272332 -259.13842) (xy 359.245343 -259.137921) (xy 359.192028 -259.129481) (xy 359.14069 -259.112805)
			(xy 359.092593 -259.088303) (xy 359.048921 -259.056578) (xy 359.01075 -259.018412) (xy 358.97902 -258.974745)
			(xy 358.954512 -258.926651) (xy 358.937829 -258.875315) (xy 358.929383 -258.822001) (xy 358.928924 -258.795012)
			(xy 358.929566 -258.763966) (xy 358.940681 -258.70288) (xy 358.951022 -258.6736) (xy 358.955594 -258.661916)
			(xy 358.952546 -258.637278) (xy 358.899206 -258.559808) (xy 358.891681 -258.549911) (xy 358.869713 -258.53833)
			(xy 358.857296 -258.53771) (xy 357.187246 -258.53771) (xy 357.174823 -258.538318) (xy 357.152838 -258.54989)
			(xy 357.145336 -258.559808) (xy 357.091996 -258.637278) (xy 357.088948 -258.661916) (xy 357.09352 -258.6736)
			(xy 357.10385 -258.702883) (xy 357.114973 -258.763967) (xy 357.115618 -258.795012) (xy 357.115088 -258.821997)
			(xy 357.106644 -258.875302) (xy 357.089965 -258.92663) (xy 357.065462 -258.974717) (xy 357.03374 -259.018379)
			(xy 356.995577 -259.056541) (xy 356.951915 -259.088264) (xy 356.903828 -259.112766) (xy 356.8525 -259.129444)
			(xy 356.799195 -259.137888) (xy 356.77221 -259.13842) (xy 356.767892 -259.13842) (xy 356.757926 -259.138896)
			(xy 356.739488 -259.146471) (xy 356.732078 -259.153152) (xy 356.68204 -259.202936) (xy 356.67522 -259.2102)
			(xy 356.667483 -259.228542) (xy 356.667054 -259.238496) (xy 356.667054 -259.401056) (xy 356.667489 -259.41112)
			(xy 356.675224 -259.429705) (xy 356.68204 -259.437124) (xy 356.732078 -259.486908) (xy 356.739487 -259.493595)
			(xy 356.757923 -259.501183) (xy 356.767892 -259.50164) (xy 356.77221 -259.50164) (xy 356.797905 -259.502121)
			(xy 356.84872 -259.509781) (xy 356.897827 -259.52493) (xy 356.944127 -259.547228) (xy 356.986586 -259.576177)
			(xy 357.024257 -259.611132) (xy 357.056297 -259.65131) (xy 357.081992 -259.695815) (xy 357.100766 -259.743653)
			(xy 357.112201 -259.793754) (xy 357.116042 -259.845) (xy 357.116038 -259.845048) (xy 358.928419 -259.845048)
			(xy 358.932449 -259.79255) (xy 358.944446 -259.741282) (xy 358.964129 -259.692447) (xy 358.991035 -259.647188)
			(xy 359.024535 -259.606567) (xy 359.063843 -259.571536) (xy 359.108038 -259.542916) (xy 359.156083 -259.521377)
			(xy 359.206854 -259.507425) (xy 359.259159 -259.501387) (xy 359.311773 -259.503404) (xy 359.363463 -259.513428)
			(xy 359.413016 -259.531226) (xy 359.459272 -259.556379) (xy 359.501146 -259.588298) (xy 359.537658 -259.626236)
			(xy 359.56795 -259.669302) (xy 359.591313 -259.716487) (xy 359.607199 -259.766686) (xy 359.615236 -259.818722)
			(xy 359.61574 -259.845048) (xy 359.615236 -259.871374) (xy 359.607199 -259.92341) (xy 359.591313 -259.973609)
			(xy 359.56795 -260.020794) (xy 359.537658 -260.06386) (xy 359.501146 -260.101798) (xy 359.459272 -260.133717)
			(xy 359.413016 -260.15887) (xy 359.363463 -260.176668) (xy 359.311773 -260.186692) (xy 359.259159 -260.188709)
			(xy 359.206854 -260.182671) (xy 359.156083 -260.168719) (xy 359.108038 -260.14718) (xy 359.063843 -260.11856)
			(xy 359.024535 -260.083529) (xy 358.991035 -260.042908) (xy 358.964129 -259.997649) (xy 358.944446 -259.948814)
			(xy 358.932449 -259.897546) (xy 358.928419 -259.845048) (xy 357.116038 -259.845048) (xy 357.112201 -259.896246)
			(xy 357.100766 -259.946347) (xy 357.081992 -259.994185) (xy 357.056297 -260.03869) (xy 357.024257 -260.078868)
			(xy 356.986586 -260.113823) (xy 356.944127 -260.142772) (xy 356.897827 -260.16507) (xy 356.84872 -260.180219)
			(xy 356.797905 -260.187879) (xy 356.77221 -260.188456) (xy 356.767892 -260.188456) (xy 356.757924 -260.188931)
			(xy 356.739481 -260.196499) (xy 356.732078 -260.203188) (xy 356.68204 -260.252972) (xy 356.675225 -260.260238)
			(xy 356.667501 -260.27858) (xy 356.667054 -260.288532) (xy 356.667054 -260.986524) (xy 356.681786 -261.010654)
			(xy 356.69474 -261.017258) (xy 356.718452 -261.030011) (xy 356.761932 -261.061759) (xy 356.799926 -261.099902)
			(xy 356.831501 -261.143508) (xy 356.855884 -261.191507) (xy 356.872479 -261.242723) (xy 356.880877 -261.295901)
			(xy 356.88143 -261.32282) (xy 357.144069 -261.32282) (xy 357.148099 -261.270322) (xy 357.160096 -261.219054)
			(xy 357.179779 -261.170219) (xy 357.206685 -261.12496) (xy 357.240185 -261.084339) (xy 357.279493 -261.049308)
			(xy 357.323688 -261.020688) (xy 357.371733 -260.999149) (xy 357.422504 -260.985197) (xy 357.474809 -260.979159)
			(xy 357.527423 -260.981176) (xy 357.579113 -260.9912) (xy 357.628666 -261.008998) (xy 357.674922 -261.034151)
			(xy 357.716796 -261.06607) (xy 357.753308 -261.104008) (xy 357.7836 -261.147074) (xy 357.806963 -261.194259)
			(xy 357.822849 -261.244458) (xy 357.830886 -261.296494) (xy 357.83139 -261.32282) (xy 358.094029 -261.32282)
			(xy 358.098059 -261.270322) (xy 358.110056 -261.219054) (xy 358.129739 -261.170219) (xy 358.156645 -261.12496)
			(xy 358.190145 -261.084339) (xy 358.229453 -261.049308) (xy 358.273648 -261.020688) (xy 358.321693 -260.999149)
			(xy 358.372464 -260.985197) (xy 358.424769 -260.979159) (xy 358.477383 -260.981176) (xy 358.529073 -260.9912)
			(xy 358.578626 -261.008998) (xy 358.624882 -261.034151) (xy 358.666756 -261.06607) (xy 358.703268 -261.104008)
			(xy 358.73356 -261.147074) (xy 358.756923 -261.194259) (xy 358.772809 -261.244458) (xy 358.780846 -261.296494)
			(xy 358.78135 -261.32282) (xy 359.043989 -261.32282) (xy 359.048019 -261.270322) (xy 359.060016 -261.219054)
			(xy 359.079699 -261.170219) (xy 359.106605 -261.12496) (xy 359.140105 -261.084339) (xy 359.179413 -261.049308)
			(xy 359.223608 -261.020688) (xy 359.271653 -260.999149) (xy 359.322424 -260.985197) (xy 359.374729 -260.979159)
			(xy 359.427343 -260.981176) (xy 359.479033 -260.9912) (xy 359.528586 -261.008998) (xy 359.574842 -261.034151)
			(xy 359.616716 -261.06607) (xy 359.653228 -261.104008) (xy 359.68352 -261.147074) (xy 359.706883 -261.194259)
			(xy 359.722769 -261.244458) (xy 359.730806 -261.296494) (xy 359.73131 -261.32282) (xy 359.993949 -261.32282)
			(xy 359.997979 -261.270322) (xy 360.009976 -261.219054) (xy 360.029659 -261.170219) (xy 360.056565 -261.12496)
			(xy 360.090065 -261.084339) (xy 360.129373 -261.049308) (xy 360.173568 -261.020688) (xy 360.221613 -260.999149)
			(xy 360.272384 -260.985197) (xy 360.324689 -260.979159) (xy 360.377303 -260.981176) (xy 360.428993 -260.9912)
			(xy 360.478546 -261.008998) (xy 360.524802 -261.034151) (xy 360.566676 -261.06607) (xy 360.603188 -261.104008)
			(xy 360.63348 -261.147074) (xy 360.656843 -261.194259) (xy 360.672729 -261.244458) (xy 360.680766 -261.296494)
			(xy 360.68127 -261.32282) (xy 360.944163 -261.32282) (xy 360.948193 -261.270322) (xy 360.96019 -261.219054)
			(xy 360.979873 -261.170219) (xy 361.006779 -261.12496) (xy 361.040279 -261.084339) (xy 361.079587 -261.049308)
			(xy 361.123782 -261.020688) (xy 361.171827 -260.999149) (xy 361.222598 -260.985197) (xy 361.274903 -260.979159)
			(xy 361.327517 -260.981176) (xy 361.379207 -260.9912) (xy 361.42876 -261.008998) (xy 361.475016 -261.034151)
			(xy 361.51689 -261.06607) (xy 361.553402 -261.104008) (xy 361.583694 -261.147074) (xy 361.607057 -261.194259)
			(xy 361.622943 -261.244458) (xy 361.63098 -261.296494) (xy 361.631484 -261.32282) (xy 361.894123 -261.32282)
			(xy 361.898153 -261.270322) (xy 361.91015 -261.219054) (xy 361.929833 -261.170219) (xy 361.956739 -261.12496)
			(xy 361.990239 -261.084339) (xy 362.029547 -261.049308) (xy 362.073742 -261.020688) (xy 362.121787 -260.999149)
			(xy 362.172558 -260.985197) (xy 362.224863 -260.979159) (xy 362.277477 -260.981176) (xy 362.329167 -260.9912)
			(xy 362.37872 -261.008998) (xy 362.424976 -261.034151) (xy 362.46685 -261.06607) (xy 362.503362 -261.104008)
			(xy 362.533654 -261.147074) (xy 362.557017 -261.194259) (xy 362.572903 -261.244458) (xy 362.58094 -261.296494)
			(xy 362.581444 -261.32282) (xy 362.844083 -261.32282) (xy 362.848113 -261.270322) (xy 362.86011 -261.219054)
			(xy 362.879793 -261.170219) (xy 362.906699 -261.12496) (xy 362.940199 -261.084339) (xy 362.979507 -261.049308)
			(xy 363.023702 -261.020688) (xy 363.071747 -260.999149) (xy 363.122518 -260.985197) (xy 363.174823 -260.979159)
			(xy 363.227437 -260.981176) (xy 363.279127 -260.9912) (xy 363.32868 -261.008998) (xy 363.374936 -261.034151)
			(xy 363.41681 -261.06607) (xy 363.453322 -261.104008) (xy 363.483614 -261.147074) (xy 363.506977 -261.194259)
			(xy 363.522863 -261.244458) (xy 363.5309 -261.296494) (xy 363.531404 -261.32282) (xy 363.5309 -261.349146)
			(xy 363.522863 -261.401182) (xy 363.506977 -261.451381) (xy 363.483614 -261.498566) (xy 363.453322 -261.541632)
			(xy 363.41681 -261.57957) (xy 363.374936 -261.611489) (xy 363.32868 -261.636642) (xy 363.279127 -261.65444)
			(xy 363.227437 -261.664464) (xy 363.174823 -261.666481) (xy 363.122518 -261.660443) (xy 363.071747 -261.646491)
			(xy 363.023702 -261.624952) (xy 362.979507 -261.596332) (xy 362.940199 -261.561301) (xy 362.906699 -261.52068)
			(xy 362.879793 -261.475421) (xy 362.86011 -261.426586) (xy 362.848113 -261.375318) (xy 362.844083 -261.32282)
			(xy 362.581444 -261.32282) (xy 362.58094 -261.349146) (xy 362.572903 -261.401182) (xy 362.557017 -261.451381)
			(xy 362.533654 -261.498566) (xy 362.503362 -261.541632) (xy 362.46685 -261.57957) (xy 362.424976 -261.611489)
			(xy 362.37872 -261.636642) (xy 362.329167 -261.65444) (xy 362.277477 -261.664464) (xy 362.224863 -261.666481)
			(xy 362.172558 -261.660443) (xy 362.121787 -261.646491) (xy 362.073742 -261.624952) (xy 362.029547 -261.596332)
			(xy 361.990239 -261.561301) (xy 361.956739 -261.52068) (xy 361.929833 -261.475421) (xy 361.91015 -261.426586)
			(xy 361.898153 -261.375318) (xy 361.894123 -261.32282) (xy 361.631484 -261.32282) (xy 361.63098 -261.349146)
			(xy 361.622943 -261.401182) (xy 361.607057 -261.451381) (xy 361.583694 -261.498566) (xy 361.553402 -261.541632)
			(xy 361.51689 -261.57957) (xy 361.475016 -261.611489) (xy 361.42876 -261.636642) (xy 361.379207 -261.65444)
			(xy 361.327517 -261.664464) (xy 361.274903 -261.666481) (xy 361.222598 -261.660443) (xy 361.171827 -261.646491)
			(xy 361.123782 -261.624952) (xy 361.079587 -261.596332) (xy 361.040279 -261.561301) (xy 361.006779 -261.52068)
			(xy 360.979873 -261.475421) (xy 360.96019 -261.426586) (xy 360.948193 -261.375318) (xy 360.944163 -261.32282)
			(xy 360.68127 -261.32282) (xy 360.680766 -261.349146) (xy 360.672729 -261.401182) (xy 360.656843 -261.451381)
			(xy 360.63348 -261.498566) (xy 360.603188 -261.541632) (xy 360.566676 -261.57957) (xy 360.524802 -261.611489)
			(xy 360.478546 -261.636642) (xy 360.428993 -261.65444) (xy 360.377303 -261.664464) (xy 360.324689 -261.666481)
			(xy 360.272384 -261.660443) (xy 360.221613 -261.646491) (xy 360.173568 -261.624952) (xy 360.129373 -261.596332)
			(xy 360.090065 -261.561301) (xy 360.056565 -261.52068) (xy 360.029659 -261.475421) (xy 360.009976 -261.426586)
			(xy 359.997979 -261.375318) (xy 359.993949 -261.32282) (xy 359.73131 -261.32282) (xy 359.730806 -261.349146)
			(xy 359.722769 -261.401182) (xy 359.706883 -261.451381) (xy 359.68352 -261.498566) (xy 359.653228 -261.541632)
			(xy 359.616716 -261.57957) (xy 359.574842 -261.611489) (xy 359.528586 -261.636642) (xy 359.479033 -261.65444)
			(xy 359.427343 -261.664464) (xy 359.374729 -261.666481) (xy 359.322424 -261.660443) (xy 359.271653 -261.646491)
			(xy 359.223608 -261.624952) (xy 359.179413 -261.596332) (xy 359.140105 -261.561301) (xy 359.106605 -261.52068)
			(xy 359.079699 -261.475421) (xy 359.060016 -261.426586) (xy 359.048019 -261.375318) (xy 359.043989 -261.32282)
			(xy 358.78135 -261.32282) (xy 358.780846 -261.349146) (xy 358.772809 -261.401182) (xy 358.756923 -261.451381)
			(xy 358.73356 -261.498566) (xy 358.703268 -261.541632) (xy 358.666756 -261.57957) (xy 358.624882 -261.611489)
			(xy 358.578626 -261.636642) (xy 358.529073 -261.65444) (xy 358.477383 -261.664464) (xy 358.424769 -261.666481)
			(xy 358.372464 -261.660443) (xy 358.321693 -261.646491) (xy 358.273648 -261.624952) (xy 358.229453 -261.596332)
			(xy 358.190145 -261.561301) (xy 358.156645 -261.52068) (xy 358.129739 -261.475421) (xy 358.110056 -261.426586)
			(xy 358.098059 -261.375318) (xy 358.094029 -261.32282) (xy 357.83139 -261.32282) (xy 357.830886 -261.349146)
			(xy 357.822849 -261.401182) (xy 357.806963 -261.451381) (xy 357.7836 -261.498566) (xy 357.753308 -261.541632)
			(xy 357.716796 -261.57957) (xy 357.674922 -261.611489) (xy 357.628666 -261.636642) (xy 357.579113 -261.65444)
			(xy 357.527423 -261.664464) (xy 357.474809 -261.666481) (xy 357.422504 -261.660443) (xy 357.371733 -261.646491)
			(xy 357.323688 -261.624952) (xy 357.279493 -261.596332) (xy 357.240185 -261.561301) (xy 357.206685 -261.52068)
			(xy 357.179779 -261.475421) (xy 357.160096 -261.426586) (xy 357.148099 -261.375318) (xy 357.144069 -261.32282)
			(xy 356.88143 -261.32282) (xy 356.880899 -261.349805) (xy 356.872454 -261.403109) (xy 356.855775 -261.454437)
			(xy 356.831272 -261.502524) (xy 356.799549 -261.546186) (xy 356.761387 -261.584348) (xy 356.717725 -261.616071)
			(xy 356.669639 -261.640574) (xy 356.618311 -261.657254) (xy 356.565007 -261.665699) (xy 356.538022 -261.666228)
			(xy 356.53726 -261.666228) (xy 356.516211 -261.665877) (xy 356.474437 -261.66065) (xy 356.453948 -261.655814)
			(xy 356.44074 -261.652512) (xy 356.41534 -261.659624) (xy 356.275386 -261.799578) (xy 356.268149 -261.806294)
			(xy 356.249944 -261.813893) (xy 356.24008 -261.81431) (xy 354.144326 -261.81431) (xy 354.134489 -261.814847)
			(xy 354.11633 -261.822436) (xy 354.10902 -261.829042) (xy 353.782122 -262.15594) (xy 353.774248 -262.174228)
			(xy 353.774248 -262.184134) (xy 353.77342 -262.21091) (xy 353.76448 -262.263727) (xy 353.747447 -262.314514)
			(xy 353.722733 -262.36204) (xy 353.690939 -262.405152) (xy 353.652836 -262.442804) (xy 353.609348 -262.474082)
			(xy 353.56153 -262.498227) (xy 353.510543 -262.514653) (xy 353.457624 -262.522963) (xy 353.43084 -262.523478)
			(xy 353.404061 -262.522968) (xy 353.351151 -262.514658) (xy 353.300172 -262.498235) (xy 353.252362 -262.474095)
			(xy 353.20888 -262.442826) (xy 353.170779 -262.405184) (xy 353.138986 -262.362083) (xy 353.114269 -262.314568)
			(xy 353.09723 -262.263793) (xy 353.092258 -262.237474) (xy 353.08921 -262.219186) (xy 353.061016 -262.19531)
			(xy 352.747326 -262.19531) (xy 352.737489 -262.195847) (xy 352.71933 -262.203436) (xy 352.71202 -262.210042)
			(xy 352.317558 -262.604504) (xy 352.311208 -262.632952) (xy 352.316034 -262.646668) (xy 352.324134 -262.671216)
			(xy 352.332822 -262.722169) (xy 352.333306 -262.748014) (xy 352.332834 -262.772004) (xy 352.325326 -262.819394)
			(xy 352.310498 -262.865026) (xy 352.288713 -262.907777) (xy 352.26051 -262.946593) (xy 352.226581 -262.98052)
			(xy 352.187763 -263.008722) (xy 352.145012 -263.030504) (xy 352.099379 -263.04533) (xy 352.051988 -263.052836)
			(xy 352.027998 -263.053322) (xy 352.002158 -263.052779) (xy 351.951212 -263.044098) (xy 351.926652 -263.03605)
			(xy 351.912936 -263.031224) (xy 351.884488 -263.037574) (xy 351.075752 -263.84631) (xy 359.174291 -263.84631)
			(xy 359.178321 -263.793812) (xy 359.190318 -263.742544) (xy 359.210001 -263.693709) (xy 359.236907 -263.64845)
			(xy 359.270407 -263.607829) (xy 359.309715 -263.572798) (xy 359.35391 -263.544178) (xy 359.401955 -263.522639)
			(xy 359.452726 -263.508687) (xy 359.505031 -263.502649) (xy 359.557645 -263.504666) (xy 359.609335 -263.51469)
			(xy 359.658888 -263.532488) (xy 359.702104 -263.555988) (xy 369.109002 -263.555988) (xy 369.112962 -263.506934)
			(xy 369.124739 -263.45915) (xy 369.14403 -263.413874) (xy 369.170333 -263.372278) (xy 369.202968 -263.335441)
			(xy 369.241089 -263.304316) (xy 369.28371 -263.279709) (xy 369.329726 -263.262257) (xy 369.377945 -263.252413)
			(xy 369.42712 -263.250432) (xy 369.475975 -263.256364) (xy 369.523246 -263.270056) (xy 369.567708 -263.291154)
			(xy 369.608211 -263.31911) (xy 369.643704 -263.353202) (xy 369.673269 -263.392546) (xy 369.69614 -263.436123)
			(xy 369.711724 -263.482804) (xy 369.719619 -263.531381) (xy 369.720114 -263.555988) (xy 370.98911 -263.555988)
			(xy 370.99307 -263.506934) (xy 371.004847 -263.45915) (xy 371.024138 -263.413874) (xy 371.050441 -263.372278)
			(xy 371.083076 -263.335441) (xy 371.121197 -263.304316) (xy 371.163818 -263.279709) (xy 371.209834 -263.262257)
			(xy 371.258053 -263.252413) (xy 371.307228 -263.250432) (xy 371.356083 -263.256364) (xy 371.403354 -263.270056)
			(xy 371.447816 -263.291154) (xy 371.488319 -263.31911) (xy 371.523812 -263.353202) (xy 371.553377 -263.392546)
			(xy 371.576248 -263.436123) (xy 371.591832 -263.482804) (xy 371.599727 -263.531381) (xy 371.600222 -263.555988)
			(xy 371.599727 -263.580595) (xy 371.591832 -263.629172) (xy 371.576248 -263.675853) (xy 371.553377 -263.71943)
			(xy 371.523812 -263.758774) (xy 371.488319 -263.792866) (xy 371.447816 -263.820822) (xy 371.403354 -263.84192)
			(xy 371.356083 -263.855612) (xy 371.307228 -263.861544) (xy 371.258053 -263.859563) (xy 371.209834 -263.849719)
			(xy 371.163818 -263.832267) (xy 371.121197 -263.80766) (xy 371.083076 -263.776535) (xy 371.050441 -263.739698)
			(xy 371.024138 -263.698102) (xy 371.004847 -263.652826) (xy 370.99307 -263.605042) (xy 370.98911 -263.555988)
			(xy 369.720114 -263.555988) (xy 369.719619 -263.580595) (xy 369.711724 -263.629172) (xy 369.69614 -263.675853)
			(xy 369.673269 -263.71943) (xy 369.643704 -263.758774) (xy 369.608211 -263.792866) (xy 369.567708 -263.820822)
			(xy 369.523246 -263.84192) (xy 369.475975 -263.855612) (xy 369.42712 -263.861544) (xy 369.377945 -263.859563)
			(xy 369.329726 -263.849719) (xy 369.28371 -263.832267) (xy 369.241089 -263.80766) (xy 369.202968 -263.776535)
			(xy 369.170333 -263.739698) (xy 369.14403 -263.698102) (xy 369.124739 -263.652826) (xy 369.112962 -263.605042)
			(xy 369.109002 -263.555988) (xy 359.702104 -263.555988) (xy 359.705144 -263.557641) (xy 359.747018 -263.58956)
			(xy 359.78353 -263.627498) (xy 359.813822 -263.670564) (xy 359.837185 -263.717749) (xy 359.853071 -263.767948)
			(xy 359.861108 -263.819984) (xy 359.861612 -263.84631) (xy 359.861108 -263.872636) (xy 359.853071 -263.924672)
			(xy 359.837185 -263.974871) (xy 359.813822 -264.022056) (xy 359.78353 -264.065122) (xy 359.747018 -264.10306)
			(xy 359.705144 -264.134979) (xy 359.658888 -264.160132) (xy 359.609335 -264.17793) (xy 359.557645 -264.187954)
			(xy 359.505031 -264.189971) (xy 359.452726 -264.183933) (xy 359.401955 -264.169981) (xy 359.35391 -264.148442)
			(xy 359.309715 -264.119822) (xy 359.270407 -264.084791) (xy 359.236907 -264.04417) (xy 359.210001 -263.998911)
			(xy 359.190318 -263.950076) (xy 359.178321 -263.898808) (xy 359.174291 -263.84631) (xy 351.075752 -263.84631)
			(xy 350.554036 -264.368026) (xy 351.722194 -264.368026) (xy 351.726154 -264.318972) (xy 351.737931 -264.271188)
			(xy 351.757222 -264.225912) (xy 351.783525 -264.184316) (xy 351.81616 -264.147479) (xy 351.854281 -264.116354)
			(xy 351.896902 -264.091747) (xy 351.942918 -264.074295) (xy 351.991137 -264.064451) (xy 352.040312 -264.06247)
			(xy 352.089167 -264.068402) (xy 352.136438 -264.082094) (xy 352.1809 -264.103192) (xy 352.221403 -264.131148)
			(xy 352.256896 -264.16524) (xy 352.286461 -264.204584) (xy 352.309332 -264.248161) (xy 352.324916 -264.294842)
			(xy 352.332811 -264.343419) (xy 352.333306 -264.368026) (xy 353.602302 -264.368026) (xy 353.606262 -264.318972)
			(xy 353.618039 -264.271188) (xy 353.63733 -264.225912) (xy 353.663633 -264.184316) (xy 353.696268 -264.147479)
			(xy 353.734389 -264.116354) (xy 353.77701 -264.091747) (xy 353.823026 -264.074295) (xy 353.871245 -264.064451)
			(xy 353.92042 -264.06247) (xy 353.969275 -264.068402) (xy 354.016546 -264.082094) (xy 354.061008 -264.103192)
			(xy 354.101511 -264.131148) (xy 354.137004 -264.16524) (xy 354.166569 -264.204584) (xy 354.18944 -264.248161)
			(xy 354.205024 -264.294842) (xy 354.212919 -264.343419) (xy 354.213414 -264.368026) (xy 355.482156 -264.368026)
			(xy 355.486116 -264.318972) (xy 355.497893 -264.271188) (xy 355.517184 -264.225912) (xy 355.543487 -264.184316)
			(xy 355.576122 -264.147479) (xy 355.614243 -264.116354) (xy 355.656864 -264.091747) (xy 355.70288 -264.074295)
			(xy 355.751099 -264.064451) (xy 355.800274 -264.06247) (xy 355.849129 -264.068402) (xy 355.8964 -264.082094)
			(xy 355.940862 -264.103192) (xy 355.981365 -264.131148) (xy 356.016858 -264.16524) (xy 356.046423 -264.204584)
			(xy 356.069294 -264.248161) (xy 356.084878 -264.294842) (xy 356.092773 -264.343419) (xy 356.093268 -264.368026)
			(xy 363.00208 -264.368026) (xy 363.00604 -264.318972) (xy 363.017817 -264.271188) (xy 363.037108 -264.225912)
			(xy 363.063411 -264.184316) (xy 363.096046 -264.147479) (xy 363.134167 -264.116354) (xy 363.176788 -264.091747)
			(xy 363.222804 -264.074295) (xy 363.271023 -264.064451) (xy 363.320198 -264.06247) (xy 363.369053 -264.068402)
			(xy 363.416324 -264.082094) (xy 363.460786 -264.103192) (xy 363.501289 -264.131148) (xy 363.536782 -264.16524)
			(xy 363.566347 -264.204584) (xy 363.589218 -264.248161) (xy 363.604802 -264.294842) (xy 363.612697 -264.343419)
			(xy 363.613192 -264.368026) (xy 364.882188 -264.368026) (xy 364.886148 -264.318972) (xy 364.897925 -264.271188)
			(xy 364.917216 -264.225912) (xy 364.943519 -264.184316) (xy 364.976154 -264.147479) (xy 365.014275 -264.116354)
			(xy 365.056896 -264.091747) (xy 365.102912 -264.074295) (xy 365.151131 -264.064451) (xy 365.200306 -264.06247)
			(xy 365.249161 -264.068402) (xy 365.296432 -264.082094) (xy 365.340894 -264.103192) (xy 365.381397 -264.131148)
			(xy 365.41689 -264.16524) (xy 365.446455 -264.204584) (xy 365.469326 -264.248161) (xy 365.48491 -264.294842)
			(xy 365.492805 -264.343419) (xy 365.4933 -264.368026) (xy 366.762042 -264.368026) (xy 366.766002 -264.318972)
			(xy 366.777779 -264.271188) (xy 366.79707 -264.225912) (xy 366.823373 -264.184316) (xy 366.856008 -264.147479)
			(xy 366.894129 -264.116354) (xy 366.93675 -264.091747) (xy 366.982766 -264.074295) (xy 367.030985 -264.064451)
			(xy 367.08016 -264.06247) (xy 367.129015 -264.068402) (xy 367.176286 -264.082094) (xy 367.220748 -264.103192)
			(xy 367.261251 -264.131148) (xy 367.296744 -264.16524) (xy 367.326309 -264.204584) (xy 367.34918 -264.248161)
			(xy 367.364764 -264.294842) (xy 367.372659 -264.343419) (xy 367.373154 -264.368026) (xy 368.639864 -264.368026)
			(xy 368.643824 -264.318972) (xy 368.655601 -264.271188) (xy 368.674892 -264.225912) (xy 368.701195 -264.184316)
			(xy 368.73383 -264.147479) (xy 368.771951 -264.116354) (xy 368.814572 -264.091747) (xy 368.860588 -264.074295)
			(xy 368.908807 -264.064451) (xy 368.957982 -264.06247) (xy 369.006837 -264.068402) (xy 369.054108 -264.082094)
			(xy 369.09857 -264.103192) (xy 369.139073 -264.131148) (xy 369.174566 -264.16524) (xy 369.204131 -264.204584)
			(xy 369.227002 -264.248161) (xy 369.242586 -264.294842) (xy 369.250481 -264.343419) (xy 369.250935 -264.365994)
			(xy 370.518956 -264.365994) (xy 370.522916 -264.31694) (xy 370.534693 -264.269156) (xy 370.553984 -264.22388)
			(xy 370.580287 -264.182284) (xy 370.612922 -264.145447) (xy 370.651043 -264.114322) (xy 370.693664 -264.089715)
			(xy 370.73968 -264.072263) (xy 370.787899 -264.062419) (xy 370.837074 -264.060438) (xy 370.885929 -264.06637)
			(xy 370.9332 -264.080062) (xy 370.977662 -264.10116) (xy 371.018165 -264.129116) (xy 371.053658 -264.163208)
			(xy 371.083223 -264.202552) (xy 371.106094 -264.246129) (xy 371.121678 -264.29281) (xy 371.129573 -264.341387)
			(xy 371.130068 -264.365994) (xy 372.399064 -264.365994) (xy 372.403024 -264.31694) (xy 372.414801 -264.269156)
			(xy 372.434092 -264.22388) (xy 372.460395 -264.182284) (xy 372.49303 -264.145447) (xy 372.531151 -264.114322)
			(xy 372.573772 -264.089715) (xy 372.619788 -264.072263) (xy 372.668007 -264.062419) (xy 372.717182 -264.060438)
			(xy 372.766037 -264.06637) (xy 372.813308 -264.080062) (xy 372.85777 -264.10116) (xy 372.898273 -264.129116)
			(xy 372.933766 -264.163208) (xy 372.963331 -264.202552) (xy 372.986202 -264.246129) (xy 373.001786 -264.29281)
			(xy 373.009681 -264.341387) (xy 373.010176 -264.365994) (xy 374.278918 -264.365994) (xy 374.282878 -264.31694)
			(xy 374.294655 -264.269156) (xy 374.313946 -264.22388) (xy 374.340249 -264.182284) (xy 374.372884 -264.145447)
			(xy 374.411005 -264.114322) (xy 374.453626 -264.089715) (xy 374.499642 -264.072263) (xy 374.547861 -264.062419)
			(xy 374.597036 -264.060438) (xy 374.645891 -264.06637) (xy 374.693162 -264.080062) (xy 374.737624 -264.10116)
			(xy 374.778127 -264.129116) (xy 374.81362 -264.163208) (xy 374.843185 -264.202552) (xy 374.866056 -264.246129)
			(xy 374.88164 -264.29281) (xy 374.889535 -264.341387) (xy 374.89003 -264.365994) (xy 374.889535 -264.390601)
			(xy 374.88164 -264.439178) (xy 374.866056 -264.485859) (xy 374.843185 -264.529436) (xy 374.81362 -264.56878)
			(xy 374.778127 -264.602872) (xy 374.737624 -264.630828) (xy 374.693162 -264.651926) (xy 374.645891 -264.665618)
			(xy 374.597036 -264.67155) (xy 374.547861 -264.669569) (xy 374.499642 -264.659725) (xy 374.453626 -264.642273)
			(xy 374.411005 -264.617666) (xy 374.372884 -264.586541) (xy 374.340249 -264.549704) (xy 374.313946 -264.508108)
			(xy 374.294655 -264.462832) (xy 374.282878 -264.415048) (xy 374.278918 -264.365994) (xy 373.010176 -264.365994)
			(xy 373.009681 -264.390601) (xy 373.001786 -264.439178) (xy 372.986202 -264.485859) (xy 372.963331 -264.529436)
			(xy 372.933766 -264.56878) (xy 372.898273 -264.602872) (xy 372.85777 -264.630828) (xy 372.813308 -264.651926)
			(xy 372.766037 -264.665618) (xy 372.717182 -264.67155) (xy 372.668007 -264.669569) (xy 372.619788 -264.659725)
			(xy 372.573772 -264.642273) (xy 372.531151 -264.617666) (xy 372.49303 -264.586541) (xy 372.460395 -264.549704)
			(xy 372.434092 -264.508108) (xy 372.414801 -264.462832) (xy 372.403024 -264.415048) (xy 372.399064 -264.365994)
			(xy 371.130068 -264.365994) (xy 371.129573 -264.390601) (xy 371.121678 -264.439178) (xy 371.106094 -264.485859)
			(xy 371.083223 -264.529436) (xy 371.053658 -264.56878) (xy 371.018165 -264.602872) (xy 370.977662 -264.630828)
			(xy 370.9332 -264.651926) (xy 370.885929 -264.665618) (xy 370.837074 -264.67155) (xy 370.787899 -264.669569)
			(xy 370.73968 -264.659725) (xy 370.693664 -264.642273) (xy 370.651043 -264.617666) (xy 370.612922 -264.586541)
			(xy 370.580287 -264.549704) (xy 370.553984 -264.508108) (xy 370.534693 -264.462832) (xy 370.522916 -264.415048)
			(xy 370.518956 -264.365994) (xy 369.250935 -264.365994) (xy 369.250976 -264.368026) (xy 369.250481 -264.392633)
			(xy 369.242586 -264.44121) (xy 369.227002 -264.487891) (xy 369.204131 -264.531468) (xy 369.174566 -264.570812)
			(xy 369.139073 -264.604904) (xy 369.09857 -264.63286) (xy 369.054108 -264.653958) (xy 369.006837 -264.66765)
			(xy 368.957982 -264.673582) (xy 368.908807 -264.671601) (xy 368.860588 -264.661757) (xy 368.814572 -264.644305)
			(xy 368.771951 -264.619698) (xy 368.73383 -264.588573) (xy 368.701195 -264.551736) (xy 368.674892 -264.51014)
			(xy 368.655601 -264.464864) (xy 368.643824 -264.41708) (xy 368.639864 -264.368026) (xy 367.373154 -264.368026)
			(xy 367.372659 -264.392633) (xy 367.364764 -264.44121) (xy 367.34918 -264.487891) (xy 367.326309 -264.531468)
			(xy 367.296744 -264.570812) (xy 367.261251 -264.604904) (xy 367.220748 -264.63286) (xy 367.176286 -264.653958)
			(xy 367.129015 -264.66765) (xy 367.08016 -264.673582) (xy 367.030985 -264.671601) (xy 366.982766 -264.661757)
			(xy 366.93675 -264.644305) (xy 366.894129 -264.619698) (xy 366.856008 -264.588573) (xy 366.823373 -264.551736)
			(xy 366.79707 -264.51014) (xy 366.777779 -264.464864) (xy 366.766002 -264.41708) (xy 366.762042 -264.368026)
			(xy 365.4933 -264.368026) (xy 365.492805 -264.392633) (xy 365.48491 -264.44121) (xy 365.469326 -264.487891)
			(xy 365.446455 -264.531468) (xy 365.41689 -264.570812) (xy 365.381397 -264.604904) (xy 365.340894 -264.63286)
			(xy 365.296432 -264.653958) (xy 365.249161 -264.66765) (xy 365.200306 -264.673582) (xy 365.151131 -264.671601)
			(xy 365.102912 -264.661757) (xy 365.056896 -264.644305) (xy 365.014275 -264.619698) (xy 364.976154 -264.588573)
			(xy 364.943519 -264.551736) (xy 364.917216 -264.51014) (xy 364.897925 -264.464864) (xy 364.886148 -264.41708)
			(xy 364.882188 -264.368026) (xy 363.613192 -264.368026) (xy 363.612697 -264.392633) (xy 363.604802 -264.44121)
			(xy 363.589218 -264.487891) (xy 363.566347 -264.531468) (xy 363.536782 -264.570812) (xy 363.501289 -264.604904)
			(xy 363.460786 -264.63286) (xy 363.416324 -264.653958) (xy 363.369053 -264.66765) (xy 363.320198 -264.673582)
			(xy 363.271023 -264.671601) (xy 363.222804 -264.661757) (xy 363.176788 -264.644305) (xy 363.134167 -264.619698)
			(xy 363.096046 -264.588573) (xy 363.063411 -264.551736) (xy 363.037108 -264.51014) (xy 363.017817 -264.464864)
			(xy 363.00604 -264.41708) (xy 363.00208 -264.368026) (xy 356.093268 -264.368026) (xy 356.092773 -264.392633)
			(xy 356.084878 -264.44121) (xy 356.069294 -264.487891) (xy 356.046423 -264.531468) (xy 356.016858 -264.570812)
			(xy 355.981365 -264.604904) (xy 355.940862 -264.63286) (xy 355.8964 -264.653958) (xy 355.849129 -264.66765)
			(xy 355.800274 -264.673582) (xy 355.751099 -264.671601) (xy 355.70288 -264.661757) (xy 355.656864 -264.644305)
			(xy 355.614243 -264.619698) (xy 355.576122 -264.588573) (xy 355.543487 -264.551736) (xy 355.517184 -264.51014)
			(xy 355.497893 -264.464864) (xy 355.486116 -264.41708) (xy 355.482156 -264.368026) (xy 354.213414 -264.368026)
			(xy 354.212919 -264.392633) (xy 354.205024 -264.44121) (xy 354.18944 -264.487891) (xy 354.166569 -264.531468)
			(xy 354.137004 -264.570812) (xy 354.101511 -264.604904) (xy 354.061008 -264.63286) (xy 354.016546 -264.653958)
			(xy 353.969275 -264.66765) (xy 353.92042 -264.673582) (xy 353.871245 -264.671601) (xy 353.823026 -264.661757)
			(xy 353.77701 -264.644305) (xy 353.734389 -264.619698) (xy 353.696268 -264.588573) (xy 353.663633 -264.551736)
			(xy 353.63733 -264.51014) (xy 353.618039 -264.464864) (xy 353.606262 -264.41708) (xy 353.602302 -264.368026)
			(xy 352.333306 -264.368026) (xy 352.332811 -264.392633) (xy 352.324916 -264.44121) (xy 352.309332 -264.487891)
			(xy 352.286461 -264.531468) (xy 352.256896 -264.570812) (xy 352.221403 -264.604904) (xy 352.1809 -264.63286)
			(xy 352.136438 -264.653958) (xy 352.089167 -264.66765) (xy 352.040312 -264.673582) (xy 351.991137 -264.671601)
			(xy 351.942918 -264.661757) (xy 351.896902 -264.644305) (xy 351.854281 -264.619698) (xy 351.81616 -264.588573)
			(xy 351.783525 -264.551736) (xy 351.757222 -264.51014) (xy 351.737931 -264.464864) (xy 351.726154 -264.41708)
			(xy 351.722194 -264.368026) (xy 350.554036 -264.368026) (xy 350.428814 -264.493248) (xy 350.425258 -264.500614)
			(xy 350.413728 -264.522932) (xy 350.384501 -264.563785) (xy 350.348983 -264.599303) (xy 350.30813 -264.628529)
			(xy 350.285812 -264.64006) (xy 350.278446 -264.643616) (xy 350.059752 -264.86231) (xy 359.174291 -264.86231)
			(xy 359.178321 -264.809812) (xy 359.190318 -264.758544) (xy 359.210001 -264.709709) (xy 359.236907 -264.66445)
			(xy 359.270407 -264.623829) (xy 359.309715 -264.588798) (xy 359.35391 -264.560178) (xy 359.401955 -264.538639)
			(xy 359.452726 -264.524687) (xy 359.505031 -264.518649) (xy 359.557645 -264.520666) (xy 359.609335 -264.53069)
			(xy 359.658888 -264.548488) (xy 359.705144 -264.573641) (xy 359.747018 -264.60556) (xy 359.78353 -264.643498)
			(xy 359.813822 -264.686564) (xy 359.837185 -264.733749) (xy 359.853071 -264.783948) (xy 359.861108 -264.835984)
			(xy 359.861612 -264.86231) (xy 359.861108 -264.888636) (xy 359.853071 -264.940672) (xy 359.837185 -264.990871)
			(xy 359.813822 -265.038056) (xy 359.78353 -265.081122) (xy 359.747018 -265.11906) (xy 359.705144 -265.150979)
			(xy 359.659131 -265.176) (xy 369.109002 -265.176) (xy 369.112962 -265.126946) (xy 369.124739 -265.079162)
			(xy 369.14403 -265.033886) (xy 369.170333 -264.99229) (xy 369.202968 -264.955453) (xy 369.241089 -264.924328)
			(xy 369.28371 -264.899721) (xy 369.329726 -264.882269) (xy 369.377945 -264.872425) (xy 369.42712 -264.870444)
			(xy 369.475975 -264.876376) (xy 369.523246 -264.890068) (xy 369.567708 -264.911166) (xy 369.608211 -264.939122)
			(xy 369.643704 -264.973214) (xy 369.673269 -265.012558) (xy 369.69614 -265.056135) (xy 369.711724 -265.102816)
			(xy 369.719619 -265.151393) (xy 369.720114 -265.176) (xy 370.98911 -265.176) (xy 370.99307 -265.126946)
			(xy 371.004847 -265.079162) (xy 371.024138 -265.033886) (xy 371.050441 -264.99229) (xy 371.083076 -264.955453)
			(xy 371.121197 -264.924328) (xy 371.163818 -264.899721) (xy 371.209834 -264.882269) (xy 371.258053 -264.872425)
			(xy 371.307228 -264.870444) (xy 371.356083 -264.876376) (xy 371.403354 -264.890068) (xy 371.447816 -264.911166)
			(xy 371.488319 -264.939122) (xy 371.523812 -264.973214) (xy 371.553377 -265.012558) (xy 371.576248 -265.056135)
			(xy 371.591832 -265.102816) (xy 371.599727 -265.151393) (xy 371.600222 -265.176) (xy 372.868964 -265.176)
			(xy 372.872924 -265.126946) (xy 372.884701 -265.079162) (xy 372.903992 -265.033886) (xy 372.930295 -264.99229)
			(xy 372.96293 -264.955453) (xy 373.001051 -264.924328) (xy 373.043672 -264.899721) (xy 373.089688 -264.882269)
			(xy 373.137907 -264.872425) (xy 373.187082 -264.870444) (xy 373.235937 -264.876376) (xy 373.283208 -264.890068)
			(xy 373.32767 -264.911166) (xy 373.368173 -264.939122) (xy 373.403666 -264.973214) (xy 373.433231 -265.012558)
			(xy 373.456102 -265.056135) (xy 373.471686 -265.102816) (xy 373.479581 -265.151393) (xy 373.480076 -265.176)
			(xy 373.479581 -265.200607) (xy 373.471686 -265.249184) (xy 373.456102 -265.295865) (xy 373.433231 -265.339442)
			(xy 373.403666 -265.378786) (xy 373.368173 -265.412878) (xy 373.32767 -265.440834) (xy 373.283208 -265.461932)
			(xy 373.235937 -265.475624) (xy 373.187082 -265.481556) (xy 373.137907 -265.479575) (xy 373.089688 -265.469731)
			(xy 373.043672 -265.452279) (xy 373.001051 -265.427672) (xy 372.96293 -265.396547) (xy 372.930295 -265.35971)
			(xy 372.903992 -265.318114) (xy 372.884701 -265.272838) (xy 372.872924 -265.225054) (xy 372.868964 -265.176)
			(xy 371.600222 -265.176) (xy 371.599727 -265.200607) (xy 371.591832 -265.249184) (xy 371.576248 -265.295865)
			(xy 371.553377 -265.339442) (xy 371.523812 -265.378786) (xy 371.488319 -265.412878) (xy 371.447816 -265.440834)
			(xy 371.403354 -265.461932) (xy 371.356083 -265.475624) (xy 371.307228 -265.481556) (xy 371.258053 -265.479575)
			(xy 371.209834 -265.469731) (xy 371.163818 -265.452279) (xy 371.121197 -265.427672) (xy 371.083076 -265.396547)
			(xy 371.050441 -265.35971) (xy 371.024138 -265.318114) (xy 371.004847 -265.272838) (xy 370.99307 -265.225054)
			(xy 370.98911 -265.176) (xy 369.720114 -265.176) (xy 369.719619 -265.200607) (xy 369.711724 -265.249184)
			(xy 369.69614 -265.295865) (xy 369.673269 -265.339442) (xy 369.643704 -265.378786) (xy 369.608211 -265.412878)
			(xy 369.567708 -265.440834) (xy 369.523246 -265.461932) (xy 369.475975 -265.475624) (xy 369.42712 -265.481556)
			(xy 369.377945 -265.479575) (xy 369.329726 -265.469731) (xy 369.28371 -265.452279) (xy 369.241089 -265.427672)
			(xy 369.202968 -265.396547) (xy 369.170333 -265.35971) (xy 369.14403 -265.318114) (xy 369.124739 -265.272838)
			(xy 369.112962 -265.225054) (xy 369.109002 -265.176) (xy 359.659131 -265.176) (xy 359.658888 -265.176132)
			(xy 359.609335 -265.19393) (xy 359.557645 -265.203954) (xy 359.505031 -265.205971) (xy 359.452726 -265.199933)
			(xy 359.401955 -265.185981) (xy 359.35391 -265.164442) (xy 359.309715 -265.135822) (xy 359.270407 -265.100791)
			(xy 359.236907 -265.06017) (xy 359.210001 -265.014911) (xy 359.190318 -264.966076) (xy 359.178321 -264.914808)
			(xy 359.174291 -264.86231) (xy 350.059752 -264.86231) (xy 349.943928 -264.978134) (xy 349.939102 -265.011916)
			(xy 349.947484 -265.026902) (xy 349.959678 -265.049844) (xy 349.977001 -265.098823) (xy 349.985797 -265.150024)
			(xy 349.986346 -265.176) (xy 349.985875 -265.199992) (xy 349.97837 -265.247386) (xy 349.963543 -265.293023)
			(xy 349.94176 -265.335778) (xy 349.913557 -265.3746) (xy 349.879629 -265.408532) (xy 349.840811 -265.43674)
			(xy 349.798058 -265.458528) (xy 349.752423 -265.473361) (xy 349.70503 -265.480872) (xy 349.681038 -265.481308)
			(xy 349.655059 -265.480789) (xy 349.60385 -265.472002) (xy 349.554867 -265.454675) (xy 349.53194 -265.442446)
			(xy 349.516954 -265.434064) (xy 349.483172 -265.43889) (xy 349.007684 -265.914378) (xy 349.000966 -265.921614)
			(xy 348.99336 -265.939819) (xy 348.992952 -265.949684) (xy 348.992952 -265.986006) (xy 349.845388 -265.986006)
			(xy 349.849348 -265.936952) (xy 349.861125 -265.889168) (xy 349.880416 -265.843892) (xy 349.906719 -265.802296)
			(xy 349.939354 -265.765459) (xy 349.977475 -265.734334) (xy 350.020096 -265.709727) (xy 350.066112 -265.692275)
			(xy 350.114331 -265.682431) (xy 350.163506 -265.68045) (xy 350.212361 -265.686382) (xy 350.259632 -265.700074)
			(xy 350.304094 -265.721172) (xy 350.344597 -265.749128) (xy 350.38009 -265.78322) (xy 350.409655 -265.822564)
			(xy 350.432526 -265.866141) (xy 350.44811 -265.912822) (xy 350.456005 -265.961399) (xy 350.4565 -265.986006)
			(xy 350.456005 -266.010613) (xy 350.44811 -266.05919) (xy 350.432526 -266.105871) (xy 350.409655 -266.149448)
			(xy 350.38009 -266.188792) (xy 350.344597 -266.222884) (xy 350.304094 -266.25084) (xy 350.259632 -266.271938)
			(xy 350.212361 -266.28563) (xy 350.163506 -266.291562) (xy 350.114331 -266.289581) (xy 350.066112 -266.279737)
			(xy 350.020096 -266.262285) (xy 349.977475 -266.237678) (xy 349.939354 -266.206553) (xy 349.906719 -266.169716)
			(xy 349.880416 -266.12812) (xy 349.861125 -266.082844) (xy 349.849348 -266.03506) (xy 349.845388 -265.986006)
			(xy 348.992952 -265.986006) (xy 348.992952 -266.129008) (xy 348.993378 -266.139076) (xy 349.0011 -266.157674)
			(xy 349.007938 -266.165076) (xy 349.422974 -266.580112) (xy 349.463106 -266.581128) (xy 349.478346 -266.567666)
			(xy 349.499483 -266.549708) (xy 349.546919 -266.52098) (xy 349.598762 -266.501288) (xy 349.653309 -266.491282)
			(xy 349.681038 -266.490704) (xy 349.705027 -266.491177) (xy 349.752413 -266.498688) (xy 349.798041 -266.513519)
			(xy 349.840788 -266.535305) (xy 349.8796 -266.563509) (xy 349.913523 -266.597438) (xy 349.941721 -266.636255)
			(xy 349.9635 -266.679005) (xy 349.978323 -266.724635) (xy 349.985826 -266.772023) (xy 349.986346 -266.796012)
			(xy 349.985961 -266.817758) (xy 349.97979 -266.860811) (xy 349.967574 -266.902553) (xy 349.958914 -266.922504)
			(xy 349.95358 -266.934442) (xy 349.955358 -266.960096) (xy 350.007428 -267.041122) (xy 350.012282 -267.048082)
			(xy 350.025607 -267.058573) (xy 350.041622 -267.064155) (xy 350.0501 -267.06449) (xy 351.192084 -267.06449)
			(xy 351.200573 -267.064186) (xy 351.216617 -267.058638) (xy 351.229943 -267.04812) (xy 351.234756 -267.041122)
			(xy 351.286826 -266.960096) (xy 351.288604 -266.934442) (xy 351.28327 -266.922504) (xy 351.274608 -266.902553)
			(xy 351.262385 -266.860812) (xy 351.256211 -266.817759) (xy 351.255838 -266.796012) (xy 351.256283 -266.77202)
			(xy 351.263789 -266.724625) (xy 351.278617 -266.678989) (xy 351.300402 -266.636235) (xy 351.328609 -266.597415)
			(xy 351.362541 -266.563486) (xy 351.401364 -266.535285) (xy 351.44412 -266.513504) (xy 351.489758 -266.498681)
			(xy 351.537153 -266.491181) (xy 351.561146 -266.490704) (xy 351.588219 -266.491291) (xy 351.641516 -266.500846)
			(xy 351.692293 -266.519647) (xy 351.73896 -266.547106) (xy 351.780056 -266.582362) (xy 351.79762 -266.602972)
			(xy 351.804478 -266.611354) (xy 351.823528 -266.621006) (xy 351.907856 -266.625324) (xy 351.918485 -266.625312)
			(xy 351.938301 -266.617694) (xy 351.94621 -266.610592) (xy 352.094292 -266.46251) (xy 352.1011 -266.455186)
			(xy 352.108832 -266.436763) (xy 352.108901 -266.416782) (xy 352.105468 -266.407392) (xy 352.06559 -266.30884)
			(xy 352.040698 -266.291568) (xy 352.025204 -266.291314) (xy 352.001513 -266.290416) (xy 351.954824 -266.282199)
			(xy 351.909966 -266.266864) (xy 351.868018 -266.244778) (xy 351.829988 -266.216473) (xy 351.796791 -266.18263)
			(xy 351.769225 -266.144061) (xy 351.747953 -266.101694) (xy 351.733486 -266.056549) (xy 351.726172 -266.00971)
			(xy 351.725738 -265.986006) (xy 351.72626 -265.960751) (xy 351.734573 -265.910929) (xy 351.750974 -265.863155)
			(xy 351.775015 -265.818732) (xy 351.806039 -265.778872) (xy 351.843201 -265.744662) (xy 351.885487 -265.717036)
			(xy 351.931743 -265.696746) (xy 351.980708 -265.684346) (xy 352.031046 -265.680175) (xy 352.081384 -265.684346)
			(xy 352.130349 -265.696746) (xy 352.176605 -265.717036) (xy 352.218891 -265.744662) (xy 352.256053 -265.778872)
			(xy 352.287077 -265.818732) (xy 352.311118 -265.863155) (xy 352.327519 -265.910929) (xy 352.335832 -265.960751)
			(xy 352.336354 -265.986006) (xy 353.60535 -265.986006) (xy 353.60931 -265.936952) (xy 353.621087 -265.889168)
			(xy 353.640378 -265.843892) (xy 353.666681 -265.802296) (xy 353.699316 -265.765459) (xy 353.737437 -265.734334)
			(xy 353.780058 -265.709727) (xy 353.826074 -265.692275) (xy 353.874293 -265.682431) (xy 353.923468 -265.68045)
			(xy 353.972323 -265.686382) (xy 354.019594 -265.700074) (xy 354.064056 -265.721172) (xy 354.104559 -265.749128)
			(xy 354.140052 -265.78322) (xy 354.169617 -265.822564) (xy 354.192488 -265.866141) (xy 354.208072 -265.912822)
			(xy 354.215967 -265.961399) (xy 354.216462 -265.986006) (xy 354.215967 -266.010613) (xy 354.208072 -266.05919)
			(xy 354.192488 -266.105871) (xy 354.169617 -266.149448) (xy 354.140052 -266.188792) (xy 354.104559 -266.222884)
			(xy 354.064056 -266.25084) (xy 354.019594 -266.271938) (xy 353.972323 -266.28563) (xy 353.923468 -266.291562)
			(xy 353.874293 -266.289581) (xy 353.826074 -266.279737) (xy 353.780058 -266.262285) (xy 353.737437 -266.237678)
			(xy 353.699316 -266.206553) (xy 353.666681 -266.169716) (xy 353.640378 -266.12812) (xy 353.621087 -266.082844)
			(xy 353.60931 -266.03506) (xy 353.60535 -265.986006) (xy 352.336354 -265.986006) (xy 352.33596 -266.006849)
			(xy 352.33022 -266.048139) (xy 352.324924 -266.068302) (xy 352.321876 -266.079986) (xy 352.326194 -266.1031)
			(xy 352.381058 -266.175744) (xy 352.388653 -266.184726) (xy 352.409698 -266.195178) (xy 352.421444 -266.19581)
			(xy 353.399598 -266.19581) (xy 353.409433 -266.196351) (xy 353.427586 -266.203946) (xy 353.434904 -266.210542)
			(xy 354.233226 -267.008864) (xy 354.240624 -267.01571) (xy 354.259223 -267.023441) (xy 354.269294 -267.02385)
			(xy 354.936044 -267.02385) (xy 354.948117 -267.023184) (xy 354.96961 -267.012185) (xy 354.977192 -267.002768)
			(xy 355.031294 -266.927584) (xy 355.035104 -266.903454) (xy 355.031294 -266.89177) (xy 355.02416 -266.868797)
			(xy 355.016379 -266.82133) (xy 355.0158 -266.797282) (xy 355.0158 -266.792456) (xy 355.016533 -266.768647)
			(xy 355.024476 -266.721683) (xy 355.039615 -266.676521) (xy 355.061583 -266.634259) (xy 355.089848 -266.59592)
			(xy 355.123724 -266.562436) (xy 355.162389 -266.534619) (xy 355.204904 -266.513144) (xy 355.250239 -266.498531)
			(xy 355.297292 -266.491136) (xy 355.321108 -266.490704) (xy 355.344313 -266.491138) (xy 355.390188 -266.498166)
			(xy 355.434469 -266.512058) (xy 355.476137 -266.532495) (xy 355.51423 -266.559004) (xy 355.547871 -266.590976)
			(xy 355.562408 -266.609068) (xy 355.569266 -266.617704) (xy 355.588316 -266.627864) (xy 355.67366 -266.633198)
			(xy 355.684498 -266.633406) (xy 355.704764 -266.625769) (xy 355.712776 -266.618466) (xy 355.868732 -266.46251)
			(xy 355.875618 -266.45507) (xy 355.883368 -266.436357) (xy 355.883259 -266.416103) (xy 355.879654 -266.40663)
			(xy 355.84384 -266.322302) (xy 355.839523 -266.313344) (xy 355.825402 -266.299372) (xy 355.807036 -266.2918)
			(xy 355.797104 -266.291314) (xy 355.791008 -266.291314) (xy 355.765749 -266.290822) (xy 355.715921 -266.282508)
			(xy 355.66814 -266.266106) (xy 355.623711 -266.242064) (xy 355.583846 -266.211036) (xy 355.549631 -266.173869)
			(xy 355.522 -266.131578) (xy 355.501707 -266.085316) (xy 355.489306 -266.036345) (xy 355.485134 -265.986)
			(xy 355.489306 -265.935655) (xy 355.501707 -265.886684) (xy 355.522 -265.840422) (xy 355.549631 -265.798131)
			(xy 355.583846 -265.760964) (xy 355.623711 -265.729936) (xy 355.66814 -265.705894) (xy 355.715921 -265.689492)
			(xy 355.765749 -265.681178) (xy 355.791008 -265.680698) (xy 355.81471 -265.681146) (xy 355.861544 -265.688472)
			(xy 355.906684 -265.702946) (xy 355.949045 -265.724221) (xy 355.98761 -265.751786) (xy 356.021454 -265.784978)
			(xy 356.049762 -265.823001) (xy 356.071855 -265.864941) (xy 356.087203 -265.909792) (xy 356.095436 -265.956475)
			(xy 356.096316 -265.980164) (xy 356.096316 -265.986006) (xy 357.365312 -265.986006) (xy 357.369272 -265.936952)
			(xy 357.381049 -265.889168) (xy 357.40034 -265.843892) (xy 357.426643 -265.802296) (xy 357.459278 -265.765459)
			(xy 357.497399 -265.734334) (xy 357.54002 -265.709727) (xy 357.586036 -265.692275) (xy 357.634255 -265.682431)
			(xy 357.68343 -265.68045) (xy 357.732285 -265.686382) (xy 357.779556 -265.700074) (xy 357.824018 -265.721172)
			(xy 357.864521 -265.749128) (xy 357.900014 -265.78322) (xy 357.929579 -265.822564) (xy 357.95245 -265.866141)
			(xy 357.968034 -265.912822) (xy 357.975929 -265.961399) (xy 357.976424 -265.986006) (xy 361.118924 -265.986006)
			(xy 361.122884 -265.936952) (xy 361.134661 -265.889168) (xy 361.153952 -265.843892) (xy 361.180255 -265.802296)
			(xy 361.21289 -265.765459) (xy 361.251011 -265.734334) (xy 361.293632 -265.709727) (xy 361.339648 -265.692275)
			(xy 361.387867 -265.682431) (xy 361.437042 -265.68045) (xy 361.485897 -265.686382) (xy 361.533168 -265.700074)
			(xy 361.57763 -265.721172) (xy 361.618133 -265.749128) (xy 361.653626 -265.78322) (xy 361.683191 -265.822564)
			(xy 361.706062 -265.866141) (xy 361.721646 -265.912822) (xy 361.729541 -265.961399) (xy 361.730036 -265.986006)
			(xy 361.729541 -266.010613) (xy 361.721646 -266.05919) (xy 361.706062 -266.105871) (xy 361.683191 -266.149448)
			(xy 361.653626 -266.188792) (xy 361.618133 -266.222884) (xy 361.57763 -266.25084) (xy 361.533168 -266.271938)
			(xy 361.485897 -266.28563) (xy 361.437042 -266.291562) (xy 361.387867 -266.289581) (xy 361.339648 -266.279737)
			(xy 361.293632 -266.262285) (xy 361.251011 -266.237678) (xy 361.21289 -266.206553) (xy 361.180255 -266.169716)
			(xy 361.153952 -266.12812) (xy 361.134661 -266.082844) (xy 361.122884 -266.03506) (xy 361.118924 -265.986006)
			(xy 357.976424 -265.986006) (xy 357.975929 -266.010613) (xy 357.968034 -266.05919) (xy 357.95245 -266.105871)
			(xy 357.929579 -266.149448) (xy 357.900014 -266.188792) (xy 357.864521 -266.222884) (xy 357.824018 -266.25084)
			(xy 357.779556 -266.271938) (xy 357.732285 -266.28563) (xy 357.68343 -266.291562) (xy 357.634255 -266.289581)
			(xy 357.586036 -266.279737) (xy 357.54002 -266.262285) (xy 357.497399 -266.237678) (xy 357.459278 -266.206553)
			(xy 357.426643 -266.169716) (xy 357.40034 -266.12812) (xy 357.381049 -266.082844) (xy 357.369272 -266.03506)
			(xy 357.365312 -265.986006) (xy 356.096316 -265.986006) (xy 356.096316 -265.98626) (xy 356.095762 -266.011948)
			(xy 356.087131 -266.062594) (xy 356.070172 -266.111091) (xy 356.058216 -266.133834) (xy 356.054914 -266.139676)
			(xy 356.051866 -266.151868) (xy 356.051866 -266.158472) (xy 356.052349 -266.168486) (xy 356.060002 -266.186993)
			(xy 356.074155 -266.201163) (xy 356.092653 -266.208839) (xy 356.102666 -266.209272) (xy 356.143052 -266.209272)
			(xy 356.143814 -266.20851) (xy 357.148638 -266.20851) (xy 357.158478 -266.209041) (xy 357.176646 -266.21662)
			(xy 357.183944 -266.223242) (xy 357.997506 -267.036804) (xy 358.004905 -267.043649) (xy 358.023503 -267.051381)
			(xy 358.033574 -267.05179) (xy 358.459278 -267.05179) (xy 358.469342 -267.051352) (xy 358.487925 -267.043617)
			(xy 358.495346 -267.036804) (xy 359.134664 -266.397486) (xy 359.142062 -266.39064) (xy 359.160661 -266.382916)
			(xy 359.170732 -266.3825) (xy 360.515408 -266.3825) (xy 360.525478 -266.382925) (xy 360.54408 -266.390641)
			(xy 360.551476 -266.397486) (xy 361.190794 -267.036804) (xy 361.198192 -267.043651) (xy 361.21679 -267.051387)
			(xy 361.226862 -267.05179) (xy 361.519978 -267.05179) (xy 361.532537 -267.051153) (xy 361.55468 -267.039303)
			(xy 361.562142 -267.029184) (xy 361.615228 -266.95019) (xy 361.617768 -266.92479) (xy 361.612942 -266.913106)
			(xy 361.602137 -266.885174) (xy 361.590377 -266.826459) (xy 361.589574 -266.79652) (xy 361.589574 -266.79144)
			(xy 361.590382 -266.767686) (xy 361.598449 -266.720847) (xy 361.613677 -266.675825) (xy 361.635699 -266.633707)
			(xy 361.663983 -266.595512) (xy 361.697845 -266.562161) (xy 361.736466 -266.534461) (xy 361.778914 -266.513082)
			(xy 361.824163 -266.49854) (xy 361.871118 -266.491187) (xy 361.894882 -266.490704) (xy 361.922019 -266.491293)
			(xy 361.97544 -266.500887) (xy 362.026321 -266.519777) (xy 362.073061 -266.547367) (xy 362.094018 -266.564618)
			(xy 362.101638 -266.570968) (xy 362.119418 -266.577318) (xy 362.196634 -266.574524) (xy 362.206147 -266.573805)
			(xy 362.22365 -266.566249) (xy 362.23067 -266.559792) (xy 362.50118 -266.289282) (xy 362.508416 -266.282564)
			(xy 362.526621 -266.27496) (xy 362.536486 -266.27455) (xy 362.94568 -266.27455) (xy 362.954413 -266.274204)
			(xy 362.970862 -266.268332) (xy 362.984353 -266.25724) (xy 362.989114 -266.249912) (xy 363.03966 -266.166092)
			(xy 363.040676 -266.139422) (xy 363.034326 -266.127738) (xy 363.023373 -266.105734) (xy 363.007857 -266.059098)
			(xy 362.999997 -266.010581) (xy 362.999528 -265.986006) (xy 363.00005 -265.960751) (xy 363.008363 -265.910929)
			(xy 363.024764 -265.863155) (xy 363.048805 -265.818732) (xy 363.079829 -265.778872) (xy 363.116991 -265.744662)
			(xy 363.159277 -265.717036) (xy 363.205533 -265.696746) (xy 363.254498 -265.684346) (xy 363.304836 -265.680175)
			(xy 363.355174 -265.684346) (xy 363.404139 -265.696746) (xy 363.450395 -265.717036) (xy 363.492681 -265.744662)
			(xy 363.529843 -265.778872) (xy 363.560867 -265.818732) (xy 363.584908 -265.863155) (xy 363.601309 -265.910929)
			(xy 363.609622 -265.960751) (xy 363.610144 -265.986006) (xy 364.878886 -265.986006) (xy 364.882846 -265.936952)
			(xy 364.894623 -265.889168) (xy 364.913914 -265.843892) (xy 364.940217 -265.802296) (xy 364.972852 -265.765459)
			(xy 365.010973 -265.734334) (xy 365.053594 -265.709727) (xy 365.09961 -265.692275) (xy 365.147829 -265.682431)
			(xy 365.197004 -265.68045) (xy 365.245859 -265.686382) (xy 365.29313 -265.700074) (xy 365.337592 -265.721172)
			(xy 365.378095 -265.749128) (xy 365.413588 -265.78322) (xy 365.443153 -265.822564) (xy 365.466024 -265.866141)
			(xy 365.481608 -265.912822) (xy 365.489503 -265.961399) (xy 365.489998 -265.986006) (xy 365.489503 -266.010613)
			(xy 365.481608 -266.05919) (xy 365.466024 -266.105871) (xy 365.443153 -266.149448) (xy 365.413588 -266.188792)
			(xy 365.378095 -266.222884) (xy 365.337592 -266.25084) (xy 365.29313 -266.271938) (xy 365.245859 -266.28563)
			(xy 365.197004 -266.291562) (xy 365.147829 -266.289581) (xy 365.09961 -266.279737) (xy 365.053594 -266.262285)
			(xy 365.010973 -266.237678) (xy 364.972852 -266.206553) (xy 364.940217 -266.169716) (xy 364.913914 -266.12812)
			(xy 364.894623 -266.082844) (xy 364.882846 -266.03506) (xy 364.878886 -265.986006) (xy 363.610144 -265.986006)
			(xy 363.609699 -266.010584) (xy 363.601856 -266.059108) (xy 363.586327 -266.105745) (xy 363.575346 -266.127738)
			(xy 363.568996 -266.139422) (xy 363.570012 -266.166092) (xy 363.620558 -266.249912) (xy 363.625368 -266.257199)
			(xy 363.638858 -266.268267) (xy 363.655269 -266.274193) (xy 363.663992 -266.27455) (xy 363.775498 -266.27455)
			(xy 363.785334 -266.27509) (xy 363.803493 -266.282678) (xy 363.810804 -266.289282) (xy 364.543086 -267.021564)
			(xy 364.550487 -267.028401) (xy 364.569086 -267.03611) (xy 364.579154 -267.03655) (xy 365.274352 -267.03655)
			(xy 365.286674 -267.035951) (xy 365.308489 -267.024489) (xy 365.316008 -267.014706) (xy 365.369602 -266.937744)
			(xy 365.37265 -266.913614) (xy 365.368332 -266.901676) (xy 365.359556 -266.876147) (xy 365.350104 -266.823002)
			(xy 365.349536 -266.796012) (xy 365.349981 -266.772019) (xy 365.357487 -266.724625) (xy 365.372315 -266.678989)
			(xy 365.3941 -266.636234) (xy 365.422306 -266.597414) (xy 365.456239 -266.563486) (xy 365.495061 -266.535284)
			(xy 365.537818 -266.513503) (xy 365.583456 -266.498679) (xy 365.630851 -266.491179) (xy 365.654844 -266.490704)
			(xy 365.68206 -266.491271) (xy 365.735637 -266.500867) (xy 365.786661 -266.519818) (xy 365.833512 -266.547522)
			(xy 365.854488 -266.564872) (xy 365.860838 -266.570714) (xy 365.885222 -266.580112) (xy 365.889626 -266.581719)
			(xy 365.898825 -266.583514) (xy 365.90351 -266.583668) (xy 365.92383 -266.583922) (xy 365.934026 -266.583566)
			(xy 365.952885 -266.57583) (xy 365.960406 -266.568936) (xy 366.24006 -266.289282) (xy 366.247295 -266.282561)
			(xy 366.2655 -266.274949) (xy 366.275366 -266.27455) (xy 366.705642 -266.27455) (xy 366.71437 -266.274194)
			(xy 366.730803 -266.268309) (xy 366.744277 -266.257212) (xy 366.749076 -266.249912) (xy 366.799622 -266.166092)
			(xy 366.800638 -266.139422) (xy 366.794288 -266.127738) (xy 366.783336 -266.105733) (xy 366.767822 -266.059097)
			(xy 366.759963 -266.010581) (xy 366.75949 -265.986006) (xy 366.760012 -265.960751) (xy 366.768325 -265.910929)
			(xy 366.784726 -265.863155) (xy 366.808767 -265.818732) (xy 366.839791 -265.778872) (xy 366.876953 -265.744662)
			(xy 366.919239 -265.717036) (xy 366.965495 -265.696746) (xy 367.01446 -265.684346) (xy 367.064798 -265.680175)
			(xy 367.115136 -265.684346) (xy 367.164101 -265.696746) (xy 367.210357 -265.717036) (xy 367.252643 -265.744662)
			(xy 367.289805 -265.778872) (xy 367.320829 -265.818732) (xy 367.34487 -265.863155) (xy 367.361271 -265.910929)
			(xy 367.369584 -265.960751) (xy 367.370106 -265.986006) (xy 368.639102 -265.986006) (xy 368.643062 -265.936952)
			(xy 368.654839 -265.889168) (xy 368.67413 -265.843892) (xy 368.700433 -265.802296) (xy 368.733068 -265.765459)
			(xy 368.771189 -265.734334) (xy 368.81381 -265.709727) (xy 368.859826 -265.692275) (xy 368.908045 -265.682431)
			(xy 368.95722 -265.68045) (xy 369.006075 -265.686382) (xy 369.053346 -265.700074) (xy 369.097808 -265.721172)
			(xy 369.138311 -265.749128) (xy 369.173804 -265.78322) (xy 369.203369 -265.822564) (xy 369.22624 -265.866141)
			(xy 369.241824 -265.912822) (xy 369.249719 -265.961399) (xy 369.250214 -265.986006) (xy 369.249719 -266.010613)
			(xy 369.241824 -266.05919) (xy 369.22624 -266.105871) (xy 369.203369 -266.149448) (xy 369.173804 -266.188792)
			(xy 369.138311 -266.222884) (xy 369.097808 -266.25084) (xy 369.053346 -266.271938) (xy 369.006075 -266.28563)
			(xy 368.95722 -266.291562) (xy 368.908045 -266.289581) (xy 368.859826 -266.279737) (xy 368.81381 -266.262285)
			(xy 368.771189 -266.237678) (xy 368.733068 -266.206553) (xy 368.700433 -266.169716) (xy 368.67413 -266.12812)
			(xy 368.654839 -266.082844) (xy 368.643062 -266.03506) (xy 368.639102 -265.986006) (xy 367.370106 -265.986006)
			(xy 367.369661 -266.010584) (xy 367.361817 -266.059108) (xy 367.346287 -266.105744) (xy 367.335308 -266.127738)
			(xy 367.328958 -266.139422) (xy 367.329974 -266.166092) (xy 367.38052 -266.249912) (xy 367.385333 -266.257193)
			(xy 367.398825 -266.268244) (xy 367.415235 -266.274151) (xy 367.423954 -266.27455) (xy 367.555018 -266.27455)
			(xy 367.564861 -266.275075) (xy 367.58304 -266.282644) (xy 367.590324 -266.289282) (xy 368.322606 -267.021564)
			(xy 368.330003 -267.028413) (xy 368.348601 -267.036151) (xy 368.358674 -267.03655) (xy 369.034314 -267.03655)
			(xy 369.046641 -267.03596) (xy 369.06847 -267.024507) (xy 369.07597 -267.014706) (xy 369.129564 -266.937744)
			(xy 369.132612 -266.913614) (xy 369.128294 -266.901676) (xy 369.119519 -266.876147) (xy 369.110068 -266.823002)
			(xy 369.109498 -266.796012) (xy 369.109943 -266.772018) (xy 369.117449 -266.724622) (xy 369.132276 -266.678983)
			(xy 369.154061 -266.636226) (xy 369.182266 -266.597403) (xy 369.216198 -266.56347) (xy 369.25502 -266.535264)
			(xy 369.297777 -266.513478) (xy 369.343416 -266.49865) (xy 369.390812 -266.491144) (xy 369.414806 -266.490704)
			(xy 369.442533 -266.491308) (xy 369.497078 -266.501313) (xy 369.548924 -266.520993) (xy 369.596368 -266.549702)
			(xy 369.617498 -266.567666) (xy 369.624864 -266.57427) (xy 369.643152 -266.580874) (xy 369.720876 -266.578588)
			(xy 369.730447 -266.577888) (xy 369.748064 -266.570311) (xy 369.755166 -266.563856) (xy 370.09578 -266.223242)
			(xy 370.103019 -266.216529) (xy 370.121223 -266.208931) (xy 370.131086 -266.20851) (xy 370.437918 -266.20851)
			(xy 370.449945 -266.207842) (xy 370.47141 -266.196981) (xy 370.479066 -266.187682) (xy 370.533422 -266.11326)
			(xy 370.537232 -266.089638) (xy 370.533676 -266.077954) (xy 370.526988 -266.055429) (xy 370.519837 -266.008991)
			(xy 370.519452 -265.985498) (xy 370.519452 -265.98245) (xy 370.52025 -265.957387) (xy 370.529018 -265.90802)
			(xy 370.545734 -265.860748) (xy 370.569949 -265.816842) (xy 370.601012 -265.777483) (xy 370.638088 -265.743728)
			(xy 370.680181 -265.716484) (xy 370.72616 -265.696484) (xy 370.774788 -265.684264) (xy 370.82476 -265.680154)
			(xy 370.874732 -265.684264) (xy 370.92336 -265.696484) (xy 370.969339 -265.716484) (xy 371.011432 -265.743728)
			(xy 371.048508 -265.777483) (xy 371.079571 -265.816842) (xy 371.103786 -265.860748) (xy 371.120502 -265.90802)
			(xy 371.12927 -265.957387) (xy 371.130068 -265.98245) (xy 371.130068 -265.985498) (xy 371.130059 -265.986006)
			(xy 372.399064 -265.986006) (xy 372.403024 -265.936952) (xy 372.414801 -265.889168) (xy 372.434092 -265.843892)
			(xy 372.460395 -265.802296) (xy 372.49303 -265.765459) (xy 372.531151 -265.734334) (xy 372.573772 -265.709727)
			(xy 372.619788 -265.692275) (xy 372.668007 -265.682431) (xy 372.717182 -265.68045) (xy 372.766037 -265.686382)
			(xy 372.813308 -265.700074) (xy 372.85777 -265.721172) (xy 372.898273 -265.749128) (xy 372.933766 -265.78322)
			(xy 372.963331 -265.822564) (xy 372.986202 -265.866141) (xy 373.001786 -265.912822) (xy 373.009681 -265.961399)
			(xy 373.010176 -265.986006) (xy 374.278918 -265.986006) (xy 374.282878 -265.936952) (xy 374.294655 -265.889168)
			(xy 374.313946 -265.843892) (xy 374.340249 -265.802296) (xy 374.372884 -265.765459) (xy 374.411005 -265.734334)
			(xy 374.453626 -265.709727) (xy 374.499642 -265.692275) (xy 374.547861 -265.682431) (xy 374.597036 -265.68045)
			(xy 374.645891 -265.686382) (xy 374.693162 -265.700074) (xy 374.737624 -265.721172) (xy 374.778127 -265.749128)
			(xy 374.81362 -265.78322) (xy 374.843185 -265.822564) (xy 374.866056 -265.866141) (xy 374.88164 -265.912822)
			(xy 374.889535 -265.961399) (xy 374.89003 -265.986006) (xy 374.889535 -266.010613) (xy 374.88164 -266.05919)
			(xy 374.866056 -266.105871) (xy 374.843185 -266.149448) (xy 374.81362 -266.188792) (xy 374.778127 -266.222884)
			(xy 374.737624 -266.25084) (xy 374.693162 -266.271938) (xy 374.645891 -266.28563) (xy 374.597036 -266.291562)
			(xy 374.547861 -266.289581) (xy 374.499642 -266.279737) (xy 374.453626 -266.262285) (xy 374.411005 -266.237678)
			(xy 374.372884 -266.206553) (xy 374.340249 -266.169716) (xy 374.313946 -266.12812) (xy 374.294655 -266.082844)
			(xy 374.282878 -266.03506) (xy 374.278918 -265.986006) (xy 373.010176 -265.986006) (xy 373.009681 -266.010613)
			(xy 373.001786 -266.05919) (xy 372.986202 -266.105871) (xy 372.963331 -266.149448) (xy 372.933766 -266.188792)
			(xy 372.898273 -266.222884) (xy 372.85777 -266.25084) (xy 372.813308 -266.271938) (xy 372.766037 -266.28563)
			(xy 372.717182 -266.291562) (xy 372.668007 -266.289581) (xy 372.619788 -266.279737) (xy 372.573772 -266.262285)
			(xy 372.531151 -266.237678) (xy 372.49303 -266.206553) (xy 372.460395 -266.169716) (xy 372.434092 -266.12812)
			(xy 372.414801 -266.082844) (xy 372.403024 -266.03506) (xy 372.399064 -265.986006) (xy 371.130059 -265.986006)
			(xy 371.129635 -266.008988) (xy 371.122498 -266.055422) (xy 371.115844 -266.077954) (xy 371.112288 -266.089638)
			(xy 371.116098 -266.11326) (xy 371.170454 -266.187682) (xy 371.17807 -266.197035) (xy 371.199555 -266.207922)
			(xy 371.211602 -266.20851) (xy 371.278658 -266.20851) (xy 371.288496 -266.209044) (xy 371.306659 -266.216629)
			(xy 371.313964 -266.223242) (xy 372.112286 -267.021564) (xy 372.119687 -267.028401) (xy 372.138286 -267.03611)
			(xy 372.148354 -267.03655) (xy 372.794276 -267.03655) (xy 372.806607 -267.035968) (xy 372.82845 -267.024524)
			(xy 372.835932 -267.014706) (xy 372.889526 -266.937744) (xy 372.892574 -266.913614) (xy 372.888256 -266.901676)
			(xy 372.879479 -266.876147) (xy 372.870026 -266.823002) (xy 372.86946 -266.796012) (xy 372.869982 -266.770757)
			(xy 372.878295 -266.720935) (xy 372.894696 -266.673161) (xy 372.918737 -266.628738) (xy 372.949761 -266.588878)
			(xy 372.986923 -266.554668) (xy 373.029209 -266.527042) (xy 373.075465 -266.506752) (xy 373.12443 -266.494352)
			(xy 373.174768 -266.490181) (xy 373.225106 -266.494352) (xy 373.274071 -266.506752) (xy 373.320327 -266.527042)
			(xy 373.362613 -266.554668) (xy 373.399775 -266.588878) (xy 373.430799 -266.628738) (xy 373.45484 -266.673161)
			(xy 373.471241 -266.720935) (xy 373.479554 -266.770757) (xy 373.480076 -266.796012) (xy 373.479521 -266.823003)
			(xy 373.470061 -266.876147) (xy 373.46128 -266.901676) (xy 373.456962 -266.913614) (xy 373.46001 -266.937744)
			(xy 373.513604 -267.014706) (xy 373.521216 -267.024378) (xy 373.542976 -267.035799) (xy 373.55526 -267.03655)
			(xy 373.75211 -267.03655) (xy 373.76194 -267.036034) (xy 373.780085 -267.028452) (xy 373.793963 -267.014519)
			(xy 373.801473 -266.996344) (xy 373.801894 -266.986512) (xy 373.801894 -266.796012) (xy 373.802376 -266.771422)
			(xy 373.81007 -266.722847) (xy 373.825267 -266.676074) (xy 373.847594 -266.632255) (xy 373.876502 -266.592467)
			(xy 373.911277 -266.557692) (xy 373.951065 -266.528784) (xy 373.994884 -266.506457) (xy 374.041657 -266.49126)
			(xy 374.090232 -266.483566) (xy 374.139412 -266.483566) (xy 374.187987 -266.49126) (xy 374.23476 -266.506457)
			(xy 374.278579 -266.528784) (xy 374.318367 -266.557692) (xy 374.353142 -266.592467) (xy 374.38205 -266.632255)
			(xy 374.404377 -266.676074) (xy 374.419574 -266.722847) (xy 374.427268 -266.771422) (xy 374.42775 -266.796012)
			(xy 374.42775 -267.204698) (xy 374.428275 -267.215624) (xy 374.437368 -267.235493) (xy 374.445276 -267.243052)
			(xy 374.510046 -267.299186) (xy 374.530874 -267.305282) (xy 374.54205 -267.303758) (xy 374.552662 -267.302347)
			(xy 374.574017 -267.300822) (xy 374.584722 -267.30071) (xy 374.60841 -267.301158) (xy 374.655217 -267.308478)
			(xy 374.700333 -267.322938) (xy 374.742674 -267.344192) (xy 374.781225 -267.37173) (xy 374.815061 -267.40489)
			(xy 374.84337 -267.442879) (xy 374.865473 -267.484783) (xy 374.88084 -267.529598) (xy 374.889102 -267.576248)
			(xy 374.89003 -267.599922) (xy 374.89003 -267.603986) (xy 374.89003 -267.606018) (xy 374.889453 -267.633311)
			(xy 374.879806 -267.687038) (xy 374.860768 -267.738196) (xy 374.847358 -267.761974) (xy 374.838214 -267.77696)
			(xy 374.842532 -267.81125) (xy 374.946926 -267.915644) (xy 374.954323 -267.922492) (xy 374.972922 -267.930226)
			(xy 374.982994 -267.93063)
		)
		(stroke
			(width 0)
			(type solid)
		)
		(fill yes)
		(layer "In2.Cu")
		(net "PVDD11_S3_P0")
	)
	(gr_poly
		(pts
			(xy 127.56007 -267.930884) (xy 127.569907 -267.930348) (xy 127.588067 -267.922759) (xy 127.595376 -267.916152)
			(xy 127.733552 -267.777976) (xy 127.740259 -267.770735) (xy 127.747842 -267.752531) (xy 127.748284 -267.74267)
			(xy 127.748284 -267.400278) (xy 127.748218 -267.396471) (xy 127.747071 -267.388945) (xy 127.745998 -267.385292)
			(xy 127.739648 -267.364972) (xy 127.735838 -267.358876) (xy 127.72009 -267.333476) (xy 127.571246 -267.07719)
			(xy 127.560775 -267.058711) (xy 127.542339 -267.020443) (xy 127.534416 -267.000736) (xy 127.529336 -266.987782)
			(xy 127.507492 -266.970764) (xy 127.393954 -266.955778) (xy 127.368554 -266.9667) (xy 127.360172 -266.977876)
			(xy 127.345668 -266.996704) (xy 127.311811 -267.030055) (xy 127.273197 -267.057761) (xy 127.230759 -267.079152)
			(xy 127.185519 -267.093711) (xy 127.13857 -267.101089) (xy 127.114808 -267.101574) (xy 127.089553 -267.101082)
			(xy 127.039731 -267.092769) (xy 126.991957 -267.07637) (xy 126.947533 -267.05233) (xy 126.907673 -267.021306)
			(xy 126.873462 -266.984145) (xy 126.845835 -266.941859) (xy 126.825545 -266.895603) (xy 126.813145 -266.846638)
			(xy 126.808974 -266.7963) (xy 126.813145 -266.745962) (xy 126.825545 -266.696997) (xy 126.845835 -266.650741)
			(xy 126.873462 -266.608455) (xy 126.907673 -266.571294) (xy 126.947533 -266.54027) (xy 126.991957 -266.51623)
			(xy 127.039731 -266.499831) (xy 127.089553 -266.491518) (xy 127.114808 -266.490958) (xy 127.138576 -266.491404)
			(xy 127.185538 -266.498761) (xy 127.230791 -266.513312) (xy 127.273241 -266.534703) (xy 127.31186 -266.562419)
			(xy 127.345714 -266.595788) (xy 127.360172 -266.614656) (xy 127.368554 -266.625832) (xy 127.393954 -266.636754)
			(xy 127.507492 -266.621768) (xy 127.529336 -266.60475) (xy 127.534416 -266.591796) (xy 127.54607 -266.563289)
			(xy 127.574756 -266.508788) (xy 127.609259 -266.457771) (xy 127.649161 -266.410856) (xy 127.693978 -266.368612)
			(xy 127.718312 -266.349734) (xy 127.722884 -266.346178) (xy 127.73025 -266.337542) (xy 127.742696 -266.313158)
			(xy 127.745279 -266.307731) (xy 127.748104 -266.296052) (xy 127.748284 -266.290044) (xy 127.748284 -265.780266)
			(xy 127.748217 -265.776459) (xy 127.747068 -265.768934) (xy 127.745998 -265.76528) (xy 127.739648 -265.74496)
			(xy 127.735838 -265.738864) (xy 127.72009 -265.713464) (xy 127.571246 -265.457178) (xy 127.560775 -265.438699)
			(xy 127.54234 -265.40043) (xy 127.534416 -265.380724) (xy 127.529336 -265.36777) (xy 127.507492 -265.350752)
			(xy 127.393954 -265.335766) (xy 127.368554 -265.346688) (xy 127.360172 -265.357864) (xy 127.345668 -265.376692)
			(xy 127.311812 -265.410045) (xy 127.273198 -265.437752) (xy 127.230759 -265.459143) (xy 127.18552 -265.473703)
			(xy 127.13857 -265.481081) (xy 127.114808 -265.481562) (xy 127.089554 -265.48107) (xy 127.039734 -265.472758)
			(xy 126.991961 -265.456359) (xy 126.94754 -265.43232) (xy 126.907681 -265.401298) (xy 126.873472 -265.364138)
			(xy 126.845846 -265.321854) (xy 126.825556 -265.275599) (xy 126.813157 -265.226636) (xy 126.808986 -265.1763)
			(xy 126.813157 -265.125964) (xy 126.825556 -265.077001) (xy 126.845846 -265.030746) (xy 126.873472 -264.988462)
			(xy 126.907681 -264.951302) (xy 126.94754 -264.92028) (xy 126.991961 -264.896241) (xy 127.039734 -264.879842)
			(xy 127.089554 -264.87153) (xy 127.114808 -264.870946) (xy 127.138575 -264.871393) (xy 127.185535 -264.878752)
			(xy 127.230785 -264.893305) (xy 127.27323 -264.914701) (xy 127.311843 -264.942421) (xy 127.345689 -264.975795)
			(xy 127.360172 -264.994644) (xy 127.368554 -265.00582) (xy 127.393954 -265.016742) (xy 127.507492 -265.001756)
			(xy 127.529336 -264.984738) (xy 127.534416 -264.971784) (xy 127.546071 -264.943277) (xy 127.574757 -264.888777)
			(xy 127.609261 -264.837761) (xy 127.649164 -264.790847) (xy 127.693981 -264.748603) (xy 127.718312 -264.729722)
			(xy 127.722884 -264.726166) (xy 127.73025 -264.71753) (xy 127.742696 -264.693146) (xy 127.745278 -264.687719)
			(xy 127.7481 -264.676039) (xy 127.748284 -264.670032) (xy 127.748284 -264.160254) (xy 127.748216 -264.156448)
			(xy 127.747065 -264.148922) (xy 127.745998 -264.145268) (xy 127.739648 -264.124948) (xy 127.735838 -264.118852)
			(xy 127.72009 -264.093452) (xy 127.571246 -263.837166) (xy 127.560776 -263.818686) (xy 127.542341 -263.780418)
			(xy 127.534416 -263.760712) (xy 127.529336 -263.747758) (xy 127.507492 -263.73074) (xy 127.393954 -263.715754)
			(xy 127.368554 -263.726676) (xy 127.360172 -263.737852) (xy 127.345668 -263.756681) (xy 127.311813 -263.790035)
			(xy 127.273199 -263.817742) (xy 127.230761 -263.839135) (xy 127.18552 -263.853696) (xy 127.138571 -263.861074)
			(xy 127.114808 -263.86155) (xy 127.090815 -263.86108) (xy 127.04342 -263.853575) (xy 126.997782 -263.838749)
			(xy 126.955025 -263.816967) (xy 126.916202 -263.788764) (xy 126.882268 -263.754836) (xy 126.85406 -263.716017)
			(xy 126.83227 -263.673264) (xy 126.817437 -263.627629) (xy 126.809924 -263.580235) (xy 126.8095 -263.556242)
			(xy 126.809872 -263.533879) (xy 126.816377 -263.489629) (xy 126.822454 -263.468104) (xy 126.82601 -263.45642)
			(xy 126.821946 -263.433052) (xy 126.767336 -263.359138) (xy 126.759723 -263.349915) (xy 126.738386 -263.339185)
			(xy 126.726442 -263.338564) (xy 125.623066 -263.338564) (xy 125.611127 -263.339203) (xy 125.589794 -263.349928)
			(xy 125.582172 -263.359138) (xy 125.527562 -263.433052) (xy 125.523498 -263.45642) (xy 125.527054 -263.468104)
			(xy 125.533096 -263.489636) (xy 125.539599 -263.533882) (xy 125.540008 -263.556242) (xy 125.539486 -263.581497)
			(xy 125.531173 -263.631319) (xy 125.514772 -263.679093) (xy 125.490731 -263.723516) (xy 125.459707 -263.763376)
			(xy 125.422545 -263.797586) (xy 125.380259 -263.825212) (xy 125.334003 -263.845502) (xy 125.285038 -263.857902)
			(xy 125.2347 -263.862073) (xy 125.184362 -263.857902) (xy 125.135397 -263.845502) (xy 125.089141 -263.825212)
			(xy 125.046855 -263.797586) (xy 125.009693 -263.763376) (xy 124.978669 -263.723516) (xy 124.954628 -263.679093)
			(xy 124.938227 -263.631319) (xy 124.929914 -263.581497) (xy 124.929392 -263.556242) (xy 124.929764 -263.533879)
			(xy 124.936269 -263.489629) (xy 124.942346 -263.468104) (xy 124.945902 -263.45642) (xy 124.941838 -263.433052)
			(xy 124.887228 -263.359138) (xy 124.879614 -263.349916) (xy 124.858277 -263.339189) (xy 124.846334 -263.338564)
			(xy 124.085858 -263.338564) (xy 124.076017 -263.338035) (xy 124.057842 -263.330462) (xy 124.050552 -263.323832)
			(xy 123.779788 -263.053068) (xy 123.767342 -263.04621) (xy 123.759976 -263.044686) (xy 123.735689 -263.038912)
			(xy 123.689273 -263.02054) (xy 123.646463 -262.994866) (xy 123.608398 -262.962571) (xy 123.576091 -262.924516)
			(xy 123.550403 -262.881714) (xy 123.532017 -262.835305) (xy 123.526296 -262.811006) (xy 123.524772 -262.80364)
			(xy 123.517914 -262.791194) (xy 123.19127 -262.46455) (xy 123.183872 -262.457703) (xy 123.165274 -262.449972)
			(xy 123.155202 -262.449564) (xy 123.142248 -262.449564) (xy 123.132218 -262.449975) (xy 123.113678 -262.457635)
			(xy 123.099482 -262.471807) (xy 123.091791 -262.490334) (xy 123.091448 -262.500364) (xy 123.091448 -262.51027)
			(xy 123.09856 -262.528304) (xy 123.105418 -262.535416) (xy 123.121196 -262.552551) (xy 123.147897 -262.590714)
			(xy 123.168488 -262.632492) (xy 123.18249 -262.676914) (xy 123.189579 -262.722948) (xy 123.19 -262.746236)
			(xy 123.189478 -262.771491) (xy 123.181165 -262.821313) (xy 123.164764 -262.869087) (xy 123.140723 -262.91351)
			(xy 123.109699 -262.95337) (xy 123.072537 -262.98758) (xy 123.030251 -263.015206) (xy 122.983995 -263.035496)
			(xy 122.93503 -263.047896) (xy 122.884692 -263.052067) (xy 122.834354 -263.047896) (xy 122.785389 -263.035496)
			(xy 122.739133 -263.015206) (xy 122.696847 -262.98758) (xy 122.659685 -262.95337) (xy 122.628661 -262.91351)
			(xy 122.60462 -262.869087) (xy 122.588219 -262.821313) (xy 122.579906 -262.771491) (xy 122.579384 -262.746236)
			(xy 122.579893 -262.720503) (xy 122.588491 -262.66976) (xy 122.605499 -262.621186) (xy 122.617484 -262.598408)
			(xy 122.624088 -262.586724) (xy 122.62358 -262.5598) (xy 122.573542 -262.47471) (xy 122.568785 -262.467271)
			(xy 122.555256 -262.455945) (xy 122.538676 -262.449912) (xy 122.529854 -262.449564) (xy 122.299476 -262.449564)
			(xy 122.290667 -262.449984) (xy 122.274112 -262.456028) (xy 122.260562 -262.467296) (xy 122.255788 -262.47471)
			(xy 122.20575 -262.5598) (xy 122.205242 -262.586724) (xy 122.211846 -262.598408) (xy 122.223814 -262.621192)
			(xy 122.24079 -262.669771) (xy 122.249405 -262.720506) (xy 122.249946 -262.746236) (xy 122.249424 -262.771491)
			(xy 122.241111 -262.821313) (xy 122.22471 -262.869087) (xy 122.200669 -262.91351) (xy 122.169645 -262.95337)
			(xy 122.132483 -262.98758) (xy 122.090197 -263.015206) (xy 122.043941 -263.035496) (xy 121.994976 -263.047896)
			(xy 121.944638 -263.052067) (xy 121.8943 -263.047896) (xy 121.845335 -263.035496) (xy 121.799079 -263.015206)
			(xy 121.756793 -262.98758) (xy 121.719631 -262.95337) (xy 121.688607 -262.91351) (xy 121.664566 -262.869087)
			(xy 121.648165 -262.821313) (xy 121.639852 -262.771491) (xy 121.63933 -262.746236) (xy 121.639839 -262.720503)
			(xy 121.648439 -262.669761) (xy 121.66545 -262.621188) (xy 121.67743 -262.598408) (xy 121.684034 -262.586724)
			(xy 121.683526 -262.5598) (xy 121.633488 -262.47471) (xy 121.628729 -262.467276) (xy 121.615197 -262.455966)
			(xy 121.598618 -262.449949) (xy 121.5898 -262.449564) (xy 119.640858 -262.449564) (xy 119.631017 -262.449035)
			(xy 119.612842 -262.441462) (xy 119.605552 -262.434832) (xy 119.00027 -261.82955) (xy 118.992872 -261.822703)
			(xy 118.974274 -261.814972) (xy 118.964202 -261.814564) (xy 117.79631 -261.814564) (xy 117.786924 -261.814999)
			(xy 117.769405 -261.821749) (xy 117.755463 -261.834322) (xy 117.750844 -261.842504) (xy 117.704616 -261.934706)
			(xy 117.707156 -261.963154) (xy 117.716046 -261.974838) (xy 117.73207 -261.997247) (xy 117.757522 -262.046102)
			(xy 117.774849 -262.098393) (xy 117.783607 -262.15278) (xy 117.784118 -262.180324) (xy 117.783638 -262.206023)
			(xy 117.775977 -262.256847) (xy 117.760828 -262.305961) (xy 117.738527 -262.352269) (xy 117.709574 -262.394736)
			(xy 117.674614 -262.432413) (xy 117.63443 -262.464459) (xy 117.589918 -262.490158) (xy 117.542073 -262.508935)
			(xy 117.491964 -262.520373) (xy 117.44071 -262.524214) (xy 117.389456 -262.520373) (xy 117.339347 -262.508935)
			(xy 117.291502 -262.490158) (xy 117.24699 -262.464459) (xy 117.206806 -262.432413) (xy 117.171846 -262.394736)
			(xy 117.142893 -262.352269) (xy 117.120592 -262.305961) (xy 117.105443 -262.256847) (xy 117.097782 -262.206023)
			(xy 117.097302 -262.180324) (xy 117.09783 -262.152782) (xy 117.106588 -262.098398) (xy 117.123915 -262.04611)
			(xy 117.149367 -261.997258) (xy 117.165374 -261.974838) (xy 117.174264 -261.963154) (xy 117.176804 -261.934706)
			(xy 117.130576 -261.842504) (xy 117.126024 -261.834264) (xy 117.112083 -261.821632) (xy 117.094518 -261.814895)
			(xy 117.08511 -261.814564) (xy 116.92636 -261.814564) (xy 116.916519 -261.814035) (xy 116.898344 -261.806463)
			(xy 116.891054 -261.799832) (xy 116.617496 -261.526274) (xy 116.609468 -261.518996) (xy 116.589213 -261.51135)
			(xy 116.57838 -261.511542) (xy 116.493544 -261.516876) (xy 116.474494 -261.526782) (xy 116.467636 -261.535418)
			(xy 116.45127 -261.555468) (xy 116.413532 -261.590884) (xy 116.370904 -261.620231) (xy 116.324352 -261.642844)
			(xy 116.274932 -261.65821) (xy 116.223765 -261.66598) (xy 116.197888 -261.666482) (xy 116.172192 -261.666001)
			(xy 116.121373 -261.65834) (xy 116.072264 -261.64319) (xy 116.025961 -261.620891) (xy 115.983499 -261.591939)
			(xy 115.945826 -261.556982) (xy 115.913784 -261.516801) (xy 115.888088 -261.472294) (xy 115.869313 -261.424453)
			(xy 115.857877 -261.374349) (xy 115.854036 -261.3231) (xy 115.857877 -261.271851) (xy 115.869313 -261.221747)
			(xy 115.888088 -261.173906) (xy 115.913784 -261.129399) (xy 115.945826 -261.089218) (xy 115.983499 -261.054261)
			(xy 116.025961 -261.025309) (xy 116.072264 -261.00301) (xy 116.121373 -260.98786) (xy 116.172192 -260.980199)
			(xy 116.197888 -260.979666) (xy 116.224836 -260.980192) (xy 116.27807 -260.988614) (xy 116.329333 -261.005253)
			(xy 116.35359 -261.017004) (xy 116.365528 -261.0231) (xy 116.39169 -261.022084) (xy 116.475256 -260.970776)
			(xy 116.482441 -260.965911) (xy 116.49329 -260.952383) (xy 116.499014 -260.936014) (xy 116.499386 -260.927342)
			(xy 116.499386 -260.232144) (xy 116.49896 -260.223339) (xy 116.492906 -260.206797) (xy 116.48163 -260.193264)
			(xy 116.47424 -260.188456) (xy 116.388642 -260.138672) (xy 116.361718 -260.138418) (xy 116.350034 -260.145022)
			(xy 116.324212 -260.158772) (xy 116.26905 -260.178249) (xy 116.21139 -260.188116) (xy 116.18214 -260.18871)
			(xy 116.155409 -260.188196) (xy 116.102593 -260.179904) (xy 116.051699 -260.16353) (xy 116.003957 -260.139468)
			(xy 115.960519 -260.1083) (xy 115.922434 -260.070779) (xy 115.890622 -260.027811) (xy 115.865852 -259.980433)
			(xy 115.84872 -259.929789) (xy 115.839641 -259.877103) (xy 115.838732 -259.850382) (xy 115.838732 -259.846826)
			(xy 115.838732 -259.845302) (xy 115.839215 -259.819817) (xy 115.846776 -259.769409) (xy 115.86169 -259.720668)
			(xy 115.87226 -259.697474) (xy 115.877848 -259.685536) (xy 115.876324 -259.659628) (xy 115.824508 -259.577586)
			(xy 115.819664 -259.570534) (xy 115.806276 -259.559898) (xy 115.790131 -259.554268) (xy 115.781582 -259.553964)
			(xy 113.982754 -259.553964) (xy 113.974211 -259.554297) (xy 113.958079 -259.559931) (xy 113.944698 -259.570557)
			(xy 113.939828 -259.577586) (xy 113.888012 -259.659628) (xy 113.886488 -259.685536) (xy 113.892076 -259.697474)
			(xy 113.902648 -259.720669) (xy 113.917582 -259.769405) (xy 113.925132 -259.819816) (xy 113.925604 -259.845302)
			(xy 113.925604 -259.850382) (xy 113.924699 -259.877106) (xy 113.915632 -259.929801) (xy 113.898509 -259.980454)
			(xy 113.873743 -260.027841) (xy 113.841932 -260.070817) (xy 113.803845 -260.108345) (xy 113.760402 -260.139517)
			(xy 113.712654 -260.16358) (xy 113.661753 -260.179952) (xy 113.60893 -260.188238) (xy 113.555462 -260.188238)
			(xy 113.502639 -260.179952) (xy 113.451738 -260.16358) (xy 113.40399 -260.139517) (xy 113.360547 -260.108345)
			(xy 113.32246 -260.070817) (xy 113.290649 -260.027841) (xy 113.265883 -259.980454) (xy 113.24876 -259.929801)
			(xy 113.239693 -259.877106) (xy 113.238788 -259.850382) (xy 113.238788 -259.846826) (xy 113.238788 -259.845302)
			(xy 113.239271 -259.819817) (xy 113.246834 -259.76941) (xy 113.261749 -259.72067) (xy 113.272316 -259.697474)
			(xy 113.277904 -259.685536) (xy 113.27638 -259.659628) (xy 113.224564 -259.577586) (xy 113.219718 -259.570539)
			(xy 113.206328 -259.559914) (xy 113.190185 -259.554298) (xy 113.181638 -259.553964) (xy 112.43056 -259.553964)
			(xy 112.420719 -259.553435) (xy 112.402544 -259.545863) (xy 112.395254 -259.539232) (xy 111.792766 -258.936744)
			(xy 111.783955 -258.928755) (xy 111.761433 -258.921206) (xy 111.749586 -258.922266) (xy 111.658908 -258.935474)
			(xy 111.639604 -258.948936) (xy 111.633762 -258.959604) (xy 111.620733 -258.982455) (xy 111.588808 -259.024259)
			(xy 111.550883 -259.060706) (xy 111.507844 -259.090945) (xy 111.460698 -259.114268) (xy 111.410547 -259.130129)
			(xy 111.358564 -259.138159) (xy 111.332264 -259.138674) (xy 111.305282 -259.138142) (xy 111.251982 -259.129695)
			(xy 111.20066 -259.113013) (xy 111.15258 -259.088509) (xy 111.108925 -259.056785) (xy 111.07077 -259.018622)
			(xy 111.039055 -258.97496) (xy 111.01456 -258.926875) (xy 110.997889 -258.87555) (xy 110.989452 -258.822248)
			(xy 110.988856 -258.795266) (xy 110.989502 -258.764221) (xy 111.000626 -258.703138) (xy 111.010954 -258.673854)
			(xy 111.015526 -258.66217) (xy 111.012478 -258.637532) (xy 110.959138 -258.560062) (xy 110.951611 -258.550167)
			(xy 110.929645 -258.538583) (xy 110.917228 -258.537964) (xy 109.247178 -258.537964) (xy 109.234766 -258.538589)
			(xy 109.212815 -258.550185) (xy 109.205268 -258.560062) (xy 109.151928 -258.637532) (xy 109.14888 -258.66217)
			(xy 109.153452 -258.673854) (xy 109.163777 -258.703138) (xy 109.174889 -258.764222) (xy 109.17555 -258.795266)
			(xy 109.175023 -258.822254) (xy 109.166585 -258.875566) (xy 109.149911 -258.926903) (xy 109.125411 -258.974998)
			(xy 109.09369 -259.018669) (xy 109.055527 -259.05684) (xy 109.011863 -259.088571) (xy 108.963773 -259.113082)
			(xy 108.912441 -259.129767) (xy 108.85913 -259.138217) (xy 108.832142 -259.138674) (xy 108.80852 -259.137912)
			(xy 108.798106 -259.13715) (xy 108.778294 -259.144262) (xy 108.717588 -259.201158) (xy 108.710391 -259.20855)
			(xy 108.702131 -259.227432) (xy 108.701586 -259.237734) (xy 108.701586 -259.402326) (xy 108.702083 -259.412753)
			(xy 108.710334 -259.431905) (xy 108.717588 -259.43941) (xy 108.778294 -259.496306) (xy 108.798106 -259.503418)
			(xy 108.80852 -259.502656) (xy 108.832142 -259.501894) (xy 108.857839 -259.502377) (xy 108.908657 -259.510042)
			(xy 108.957766 -259.525196) (xy 109.004068 -259.547499) (xy 109.046529 -259.576453) (xy 109.084201 -259.611412)
			(xy 109.116242 -259.651595) (xy 109.141937 -259.696104) (xy 109.160712 -259.743945) (xy 109.172147 -259.79405)
			(xy 109.175988 -259.8453) (xy 109.175988 -259.845302) (xy 110.988351 -259.845302) (xy 110.992381 -259.792804)
			(xy 111.004378 -259.741536) (xy 111.024061 -259.692701) (xy 111.050967 -259.647442) (xy 111.084467 -259.606821)
			(xy 111.123775 -259.57179) (xy 111.16797 -259.54317) (xy 111.216015 -259.521631) (xy 111.266786 -259.507679)
			(xy 111.319091 -259.501641) (xy 111.371705 -259.503658) (xy 111.423395 -259.513682) (xy 111.472948 -259.53148)
			(xy 111.519204 -259.556633) (xy 111.561078 -259.588552) (xy 111.59759 -259.62649) (xy 111.627882 -259.669556)
			(xy 111.651245 -259.716741) (xy 111.667131 -259.76694) (xy 111.675168 -259.818976) (xy 111.675672 -259.845302)
			(xy 111.675168 -259.871628) (xy 111.667131 -259.923664) (xy 111.651245 -259.973863) (xy 111.627882 -260.021048)
			(xy 111.59759 -260.064114) (xy 111.561078 -260.102052) (xy 111.519204 -260.133971) (xy 111.472948 -260.159124)
			(xy 111.423395 -260.176922) (xy 111.371705 -260.186946) (xy 111.319091 -260.188963) (xy 111.266786 -260.182925)
			(xy 111.216015 -260.168973) (xy 111.16797 -260.147434) (xy 111.123775 -260.118814) (xy 111.084467 -260.083783)
			(xy 111.050967 -260.043162) (xy 111.024061 -259.997903) (xy 111.004378 -259.949068) (xy 110.992381 -259.8978)
			(xy 110.988351 -259.845302) (xy 109.175988 -259.845302) (xy 109.172147 -259.89655) (xy 109.160712 -259.946655)
			(xy 109.141937 -259.994496) (xy 109.116242 -260.039005) (xy 109.084201 -260.079188) (xy 109.046529 -260.114147)
			(xy 109.004068 -260.143101) (xy 108.957766 -260.165404) (xy 108.908657 -260.180558) (xy 108.857839 -260.188223)
			(xy 108.832142 -260.18871) (xy 108.80852 -260.187948) (xy 108.798106 -260.187186) (xy 108.778294 -260.194298)
			(xy 108.717588 -260.251194) (xy 108.710397 -260.258588) (xy 108.70215 -260.27747) (xy 108.701586 -260.28777)
			(xy 108.701586 -260.975602) (xy 108.71835 -261.001002) (xy 108.732574 -261.007098) (xy 108.755477 -261.017345)
			(xy 108.79829 -261.043506) (xy 108.836839 -261.075621) (xy 108.870303 -261.113004) (xy 108.897969 -261.15486)
			(xy 108.919249 -261.200297) (xy 108.933688 -261.248347) (xy 108.940981 -261.297987) (xy 108.941362 -261.323074)
			(xy 109.204001 -261.323074) (xy 109.208031 -261.270576) (xy 109.220028 -261.219308) (xy 109.239711 -261.170473)
			(xy 109.266617 -261.125214) (xy 109.300117 -261.084593) (xy 109.339425 -261.049562) (xy 109.38362 -261.020942)
			(xy 109.431665 -260.999403) (xy 109.482436 -260.985451) (xy 109.534741 -260.979413) (xy 109.587355 -260.98143)
			(xy 109.639045 -260.991454) (xy 109.688598 -261.009252) (xy 109.734854 -261.034405) (xy 109.776728 -261.066324)
			(xy 109.81324 -261.104262) (xy 109.843532 -261.147328) (xy 109.866895 -261.194513) (xy 109.882781 -261.244712)
			(xy 109.890818 -261.296748) (xy 109.891322 -261.323074) (xy 110.153961 -261.323074) (xy 110.157991 -261.270576)
			(xy 110.169988 -261.219308) (xy 110.189671 -261.170473) (xy 110.216577 -261.125214) (xy 110.250077 -261.084593)
			(xy 110.289385 -261.049562) (xy 110.33358 -261.020942) (xy 110.381625 -260.999403) (xy 110.432396 -260.985451)
			(xy 110.484701 -260.979413) (xy 110.537315 -260.98143) (xy 110.589005 -260.991454) (xy 110.638558 -261.009252)
			(xy 110.684814 -261.034405) (xy 110.726688 -261.066324) (xy 110.7632 -261.104262) (xy 110.793492 -261.147328)
			(xy 110.816855 -261.194513) (xy 110.832741 -261.244712) (xy 110.840778 -261.296748) (xy 110.841282 -261.323074)
			(xy 111.103921 -261.323074) (xy 111.107951 -261.270576) (xy 111.119948 -261.219308) (xy 111.139631 -261.170473)
			(xy 111.166537 -261.125214) (xy 111.200037 -261.084593) (xy 111.239345 -261.049562) (xy 111.28354 -261.020942)
			(xy 111.331585 -260.999403) (xy 111.382356 -260.985451) (xy 111.434661 -260.979413) (xy 111.487275 -260.98143)
			(xy 111.538965 -260.991454) (xy 111.588518 -261.009252) (xy 111.634774 -261.034405) (xy 111.676648 -261.066324)
			(xy 111.71316 -261.104262) (xy 111.743452 -261.147328) (xy 111.766815 -261.194513) (xy 111.782701 -261.244712)
			(xy 111.790738 -261.296748) (xy 111.791242 -261.323074) (xy 112.053881 -261.323074) (xy 112.057911 -261.270576)
			(xy 112.069908 -261.219308) (xy 112.089591 -261.170473) (xy 112.116497 -261.125214) (xy 112.149997 -261.084593)
			(xy 112.189305 -261.049562) (xy 112.2335 -261.020942) (xy 112.281545 -260.999403) (xy 112.332316 -260.985451)
			(xy 112.384621 -260.979413) (xy 112.437235 -260.98143) (xy 112.488925 -260.991454) (xy 112.538478 -261.009252)
			(xy 112.584734 -261.034405) (xy 112.626608 -261.066324) (xy 112.66312 -261.104262) (xy 112.693412 -261.147328)
			(xy 112.716775 -261.194513) (xy 112.732661 -261.244712) (xy 112.740698 -261.296748) (xy 112.741202 -261.323074)
			(xy 113.004095 -261.323074) (xy 113.008125 -261.270576) (xy 113.020122 -261.219308) (xy 113.039805 -261.170473)
			(xy 113.066711 -261.125214) (xy 113.100211 -261.084593) (xy 113.139519 -261.049562) (xy 113.183714 -261.020942)
			(xy 113.231759 -260.999403) (xy 113.28253 -260.985451) (xy 113.334835 -260.979413) (xy 113.387449 -260.98143)
			(xy 113.439139 -260.991454) (xy 113.488692 -261.009252) (xy 113.534948 -261.034405) (xy 113.576822 -261.066324)
			(xy 113.613334 -261.104262) (xy 113.643626 -261.147328) (xy 113.666989 -261.194513) (xy 113.682875 -261.244712)
			(xy 113.690912 -261.296748) (xy 113.691416 -261.323074) (xy 113.954055 -261.323074) (xy 113.958085 -261.270576)
			(xy 113.970082 -261.219308) (xy 113.989765 -261.170473) (xy 114.016671 -261.125214) (xy 114.050171 -261.084593)
			(xy 114.089479 -261.049562) (xy 114.133674 -261.020942) (xy 114.181719 -260.999403) (xy 114.23249 -260.985451)
			(xy 114.284795 -260.979413) (xy 114.337409 -260.98143) (xy 114.389099 -260.991454) (xy 114.438652 -261.009252)
			(xy 114.484908 -261.034405) (xy 114.526782 -261.066324) (xy 114.563294 -261.104262) (xy 114.593586 -261.147328)
			(xy 114.616949 -261.194513) (xy 114.632835 -261.244712) (xy 114.640872 -261.296748) (xy 114.641376 -261.323074)
			(xy 114.904015 -261.323074) (xy 114.908045 -261.270576) (xy 114.920042 -261.219308) (xy 114.939725 -261.170473)
			(xy 114.966631 -261.125214) (xy 115.000131 -261.084593) (xy 115.039439 -261.049562) (xy 115.083634 -261.020942)
			(xy 115.131679 -260.999403) (xy 115.18245 -260.985451) (xy 115.234755 -260.979413) (xy 115.287369 -260.98143)
			(xy 115.339059 -260.991454) (xy 115.388612 -261.009252) (xy 115.434868 -261.034405) (xy 115.476742 -261.066324)
			(xy 115.513254 -261.104262) (xy 115.543546 -261.147328) (xy 115.566909 -261.194513) (xy 115.582795 -261.244712)
			(xy 115.590832 -261.296748) (xy 115.591336 -261.323074) (xy 115.590832 -261.3494) (xy 115.582795 -261.401436)
			(xy 115.566909 -261.451635) (xy 115.543546 -261.49882) (xy 115.513254 -261.541886) (xy 115.476742 -261.579824)
			(xy 115.434868 -261.611743) (xy 115.388612 -261.636896) (xy 115.339059 -261.654694) (xy 115.287369 -261.664718)
			(xy 115.234755 -261.666735) (xy 115.18245 -261.660697) (xy 115.131679 -261.646745) (xy 115.083634 -261.625206)
			(xy 115.039439 -261.596586) (xy 115.000131 -261.561555) (xy 114.966631 -261.520934) (xy 114.939725 -261.475675)
			(xy 114.920042 -261.42684) (xy 114.908045 -261.375572) (xy 114.904015 -261.323074) (xy 114.641376 -261.323074)
			(xy 114.640872 -261.3494) (xy 114.632835 -261.401436) (xy 114.616949 -261.451635) (xy 114.593586 -261.49882)
			(xy 114.563294 -261.541886) (xy 114.526782 -261.579824) (xy 114.484908 -261.611743) (xy 114.438652 -261.636896)
			(xy 114.389099 -261.654694) (xy 114.337409 -261.664718) (xy 114.284795 -261.666735) (xy 114.23249 -261.660697)
			(xy 114.181719 -261.646745) (xy 114.133674 -261.625206) (xy 114.089479 -261.596586) (xy 114.050171 -261.561555)
			(xy 114.016671 -261.520934) (xy 113.989765 -261.475675) (xy 113.970082 -261.42684) (xy 113.958085 -261.375572)
			(xy 113.954055 -261.323074) (xy 113.691416 -261.323074) (xy 113.690912 -261.3494) (xy 113.682875 -261.401436)
			(xy 113.666989 -261.451635) (xy 113.643626 -261.49882) (xy 113.613334 -261.541886) (xy 113.576822 -261.579824)
			(xy 113.534948 -261.611743) (xy 113.488692 -261.636896) (xy 113.439139 -261.654694) (xy 113.387449 -261.664718)
			(xy 113.334835 -261.666735) (xy 113.28253 -261.660697) (xy 113.231759 -261.646745) (xy 113.183714 -261.625206)
			(xy 113.139519 -261.596586) (xy 113.100211 -261.561555) (xy 113.066711 -261.520934) (xy 113.039805 -261.475675)
			(xy 113.020122 -261.42684) (xy 113.008125 -261.375572) (xy 113.004095 -261.323074) (xy 112.741202 -261.323074)
			(xy 112.740698 -261.3494) (xy 112.732661 -261.401436) (xy 112.716775 -261.451635) (xy 112.693412 -261.49882)
			(xy 112.66312 -261.541886) (xy 112.626608 -261.579824) (xy 112.584734 -261.611743) (xy 112.538478 -261.636896)
			(xy 112.488925 -261.654694) (xy 112.437235 -261.664718) (xy 112.384621 -261.666735) (xy 112.332316 -261.660697)
			(xy 112.281545 -261.646745) (xy 112.2335 -261.625206) (xy 112.189305 -261.596586) (xy 112.149997 -261.561555)
			(xy 112.116497 -261.520934) (xy 112.089591 -261.475675) (xy 112.069908 -261.42684) (xy 112.057911 -261.375572)
			(xy 112.053881 -261.323074) (xy 111.791242 -261.323074) (xy 111.790738 -261.3494) (xy 111.782701 -261.401436)
			(xy 111.766815 -261.451635) (xy 111.743452 -261.49882) (xy 111.71316 -261.541886) (xy 111.676648 -261.579824)
			(xy 111.634774 -261.611743) (xy 111.588518 -261.636896) (xy 111.538965 -261.654694) (xy 111.487275 -261.664718)
			(xy 111.434661 -261.666735) (xy 111.382356 -261.660697) (xy 111.331585 -261.646745) (xy 111.28354 -261.625206)
			(xy 111.239345 -261.596586) (xy 111.200037 -261.561555) (xy 111.166537 -261.520934) (xy 111.139631 -261.475675)
			(xy 111.119948 -261.42684) (xy 111.107951 -261.375572) (xy 111.103921 -261.323074) (xy 110.841282 -261.323074)
			(xy 110.840778 -261.3494) (xy 110.832741 -261.401436) (xy 110.816855 -261.451635) (xy 110.793492 -261.49882)
			(xy 110.7632 -261.541886) (xy 110.726688 -261.579824) (xy 110.684814 -261.611743) (xy 110.638558 -261.636896)
			(xy 110.589005 -261.654694) (xy 110.537315 -261.664718) (xy 110.484701 -261.666735) (xy 110.432396 -261.660697)
			(xy 110.381625 -261.646745) (xy 110.33358 -261.625206) (xy 110.289385 -261.596586) (xy 110.250077 -261.561555)
			(xy 110.216577 -261.520934) (xy 110.189671 -261.475675) (xy 110.169988 -261.42684) (xy 110.157991 -261.375572)
			(xy 110.153961 -261.323074) (xy 109.891322 -261.323074) (xy 109.890818 -261.3494) (xy 109.882781 -261.401436)
			(xy 109.866895 -261.451635) (xy 109.843532 -261.49882) (xy 109.81324 -261.541886) (xy 109.776728 -261.579824)
			(xy 109.734854 -261.611743) (xy 109.688598 -261.636896) (xy 109.639045 -261.654694) (xy 109.587355 -261.664718)
			(xy 109.534741 -261.666735) (xy 109.482436 -261.660697) (xy 109.431665 -261.646745) (xy 109.38362 -261.625206)
			(xy 109.339425 -261.596586) (xy 109.300117 -261.561555) (xy 109.266617 -261.520934) (xy 109.239711 -261.475675)
			(xy 109.220028 -261.42684) (xy 109.208031 -261.375572) (xy 109.204001 -261.323074) (xy 108.941362 -261.323074)
			(xy 108.940862 -261.350061) (xy 108.932422 -261.403372) (xy 108.915744 -261.454705) (xy 108.891241 -261.502797)
			(xy 108.859515 -261.546463) (xy 108.821348 -261.584628) (xy 108.77768 -261.616351) (xy 108.729587 -261.640852)
			(xy 108.678252 -261.657526) (xy 108.624941 -261.665964) (xy 108.597954 -261.666482) (xy 108.572222 -261.666046)
			(xy 108.52133 -261.658396) (xy 108.496608 -261.651242) (xy 108.482892 -261.647178) (xy 108.455968 -261.653782)
			(xy 108.309918 -261.799832) (xy 108.302681 -261.806548) (xy 108.284476 -261.81415) (xy 108.274612 -261.814564)
			(xy 106.178858 -261.814564) (xy 106.169018 -261.815094) (xy 106.150846 -261.82267) (xy 106.143552 -261.829296)
			(xy 105.840784 -262.132064) (xy 105.833164 -262.151876) (xy 105.833672 -262.162798) (xy 105.83418 -262.180324)
			(xy 105.833676 -262.207309) (xy 105.82523 -262.260615) (xy 105.808548 -262.311943) (xy 105.784042 -262.360029)
			(xy 105.752316 -262.40369) (xy 105.71415 -262.44185) (xy 105.670485 -262.47357) (xy 105.622395 -262.498068)
			(xy 105.571064 -262.514742) (xy 105.517757 -262.52318) (xy 105.490772 -262.523732) (xy 105.463995 -262.523217)
			(xy 105.41109 -262.514899) (xy 105.360117 -262.498471) (xy 105.312312 -262.474328) (xy 105.268835 -262.443058)
			(xy 105.230738 -262.405418) (xy 105.198946 -262.362321) (xy 105.174229 -262.314811) (xy 105.157186 -262.26404)
			(xy 105.15219 -262.237728) (xy 105.149142 -262.21944) (xy 105.120948 -262.195564) (xy 104.781858 -262.195564)
			(xy 104.772018 -262.196094) (xy 104.753846 -262.20367) (xy 104.746552 -262.210296) (xy 104.370124 -262.586724)
			(xy 104.364028 -262.61695) (xy 104.36987 -262.631174) (xy 104.380676 -262.659106) (xy 104.39244 -262.717821)
			(xy 104.393238 -262.74776) (xy 104.393238 -262.75284) (xy 104.392432 -262.776596) (xy 104.384367 -262.823437)
			(xy 104.369141 -262.868463) (xy 104.34712 -262.910584) (xy 104.318837 -262.948784) (xy 104.284975 -262.982138)
			(xy 104.246353 -263.009841) (xy 104.203903 -263.031223) (xy 104.158653 -263.045768) (xy 104.111695 -263.053124)
			(xy 104.08793 -263.053576) (xy 104.087676 -263.053576) (xy 104.057667 -263.052863) (xy 103.998813 -263.041087)
			(xy 103.970836 -263.030208) (xy 103.956612 -263.024366) (xy 103.926386 -263.030462) (xy 103.110284 -263.846564)
			(xy 111.234223 -263.846564) (xy 111.238253 -263.794066) (xy 111.25025 -263.742798) (xy 111.269933 -263.693963)
			(xy 111.296839 -263.648704) (xy 111.330339 -263.608083) (xy 111.369647 -263.573052) (xy 111.413842 -263.544432)
			(xy 111.461887 -263.522893) (xy 111.512658 -263.508941) (xy 111.564963 -263.502903) (xy 111.617577 -263.50492)
			(xy 111.669267 -263.514944) (xy 111.71882 -263.532742) (xy 111.762036 -263.556242) (xy 121.168934 -263.556242)
			(xy 121.172894 -263.507188) (xy 121.184671 -263.459404) (xy 121.203962 -263.414128) (xy 121.230265 -263.372532)
			(xy 121.2629 -263.335695) (xy 121.301021 -263.30457) (xy 121.343642 -263.279963) (xy 121.389658 -263.262511)
			(xy 121.437877 -263.252667) (xy 121.487052 -263.250686) (xy 121.535907 -263.256618) (xy 121.583178 -263.27031)
			(xy 121.62764 -263.291408) (xy 121.668143 -263.319364) (xy 121.703636 -263.353456) (xy 121.733201 -263.3928)
			(xy 121.756072 -263.436377) (xy 121.771656 -263.483058) (xy 121.779551 -263.531635) (xy 121.780046 -263.556242)
			(xy 123.049042 -263.556242) (xy 123.053002 -263.507188) (xy 123.064779 -263.459404) (xy 123.08407 -263.414128)
			(xy 123.110373 -263.372532) (xy 123.143008 -263.335695) (xy 123.181129 -263.30457) (xy 123.22375 -263.279963)
			(xy 123.269766 -263.262511) (xy 123.317985 -263.252667) (xy 123.36716 -263.250686) (xy 123.416015 -263.256618)
			(xy 123.463286 -263.27031) (xy 123.507748 -263.291408) (xy 123.548251 -263.319364) (xy 123.583744 -263.353456)
			(xy 123.613309 -263.3928) (xy 123.63618 -263.436377) (xy 123.651764 -263.483058) (xy 123.659659 -263.531635)
			(xy 123.660154 -263.556242) (xy 123.659659 -263.580849) (xy 123.651764 -263.629426) (xy 123.63618 -263.676107)
			(xy 123.613309 -263.719684) (xy 123.583744 -263.759028) (xy 123.548251 -263.79312) (xy 123.507748 -263.821076)
			(xy 123.463286 -263.842174) (xy 123.416015 -263.855866) (xy 123.36716 -263.861798) (xy 123.317985 -263.859817)
			(xy 123.269766 -263.849973) (xy 123.22375 -263.832521) (xy 123.181129 -263.807914) (xy 123.143008 -263.776789)
			(xy 123.110373 -263.739952) (xy 123.08407 -263.698356) (xy 123.064779 -263.65308) (xy 123.053002 -263.605296)
			(xy 123.049042 -263.556242) (xy 121.780046 -263.556242) (xy 121.779551 -263.580849) (xy 121.771656 -263.629426)
			(xy 121.756072 -263.676107) (xy 121.733201 -263.719684) (xy 121.703636 -263.759028) (xy 121.668143 -263.79312)
			(xy 121.62764 -263.821076) (xy 121.583178 -263.842174) (xy 121.535907 -263.855866) (xy 121.487052 -263.861798)
			(xy 121.437877 -263.859817) (xy 121.389658 -263.849973) (xy 121.343642 -263.832521) (xy 121.301021 -263.807914)
			(xy 121.2629 -263.776789) (xy 121.230265 -263.739952) (xy 121.203962 -263.698356) (xy 121.184671 -263.65308)
			(xy 121.172894 -263.605296) (xy 121.168934 -263.556242) (xy 111.762036 -263.556242) (xy 111.765076 -263.557895)
			(xy 111.80695 -263.589814) (xy 111.843462 -263.627752) (xy 111.873754 -263.670818) (xy 111.897117 -263.718003)
			(xy 111.913003 -263.768202) (xy 111.92104 -263.820238) (xy 111.921544 -263.846564) (xy 111.92104 -263.87289)
			(xy 111.913003 -263.924926) (xy 111.897117 -263.975125) (xy 111.873754 -264.02231) (xy 111.843462 -264.065376)
			(xy 111.80695 -264.103314) (xy 111.765076 -264.135233) (xy 111.71882 -264.160386) (xy 111.669267 -264.178184)
			(xy 111.617577 -264.188208) (xy 111.564963 -264.190225) (xy 111.512658 -264.184187) (xy 111.461887 -264.170235)
			(xy 111.413842 -264.148696) (xy 111.369647 -264.120076) (xy 111.330339 -264.085045) (xy 111.296839 -264.044424)
			(xy 111.269933 -263.999165) (xy 111.25025 -263.95033) (xy 111.238253 -263.899062) (xy 111.234223 -263.846564)
			(xy 103.110284 -263.846564) (xy 102.588568 -264.36828) (xy 103.782126 -264.36828) (xy 103.786086 -264.319226)
			(xy 103.797863 -264.271442) (xy 103.817154 -264.226166) (xy 103.843457 -264.18457) (xy 103.876092 -264.147733)
			(xy 103.914213 -264.116608) (xy 103.956834 -264.092001) (xy 104.00285 -264.074549) (xy 104.051069 -264.064705)
			(xy 104.100244 -264.062724) (xy 104.149099 -264.068656) (xy 104.19637 -264.082348) (xy 104.240832 -264.103446)
			(xy 104.281335 -264.131402) (xy 104.316828 -264.165494) (xy 104.346393 -264.204838) (xy 104.369264 -264.248415)
			(xy 104.384848 -264.295096) (xy 104.392743 -264.343673) (xy 104.393238 -264.36828) (xy 105.662234 -264.36828)
			(xy 105.666194 -264.319226) (xy 105.677971 -264.271442) (xy 105.697262 -264.226166) (xy 105.723565 -264.18457)
			(xy 105.7562 -264.147733) (xy 105.794321 -264.116608) (xy 105.836942 -264.092001) (xy 105.882958 -264.074549)
			(xy 105.931177 -264.064705) (xy 105.980352 -264.062724) (xy 106.029207 -264.068656) (xy 106.076478 -264.082348)
			(xy 106.12094 -264.103446) (xy 106.161443 -264.131402) (xy 106.196936 -264.165494) (xy 106.226501 -264.204838)
			(xy 106.249372 -264.248415) (xy 106.264956 -264.295096) (xy 106.272851 -264.343673) (xy 106.273346 -264.36828)
			(xy 107.542088 -264.36828) (xy 107.546048 -264.319226) (xy 107.557825 -264.271442) (xy 107.577116 -264.226166)
			(xy 107.603419 -264.18457) (xy 107.636054 -264.147733) (xy 107.674175 -264.116608) (xy 107.716796 -264.092001)
			(xy 107.762812 -264.074549) (xy 107.811031 -264.064705) (xy 107.860206 -264.062724) (xy 107.909061 -264.068656)
			(xy 107.956332 -264.082348) (xy 108.000794 -264.103446) (xy 108.041297 -264.131402) (xy 108.07679 -264.165494)
			(xy 108.106355 -264.204838) (xy 108.129226 -264.248415) (xy 108.14481 -264.295096) (xy 108.152705 -264.343673)
			(xy 108.1532 -264.36828) (xy 115.062012 -264.36828) (xy 115.065972 -264.319226) (xy 115.077749 -264.271442)
			(xy 115.09704 -264.226166) (xy 115.123343 -264.18457) (xy 115.155978 -264.147733) (xy 115.194099 -264.116608)
			(xy 115.23672 -264.092001) (xy 115.282736 -264.074549) (xy 115.330955 -264.064705) (xy 115.38013 -264.062724)
			(xy 115.428985 -264.068656) (xy 115.476256 -264.082348) (xy 115.520718 -264.103446) (xy 115.561221 -264.131402)
			(xy 115.596714 -264.165494) (xy 115.626279 -264.204838) (xy 115.64915 -264.248415) (xy 115.664734 -264.295096)
			(xy 115.672629 -264.343673) (xy 115.673124 -264.36828) (xy 116.94212 -264.36828) (xy 116.94608 -264.319226)
			(xy 116.957857 -264.271442) (xy 116.977148 -264.226166) (xy 117.003451 -264.18457) (xy 117.036086 -264.147733)
			(xy 117.074207 -264.116608) (xy 117.116828 -264.092001) (xy 117.162844 -264.074549) (xy 117.211063 -264.064705)
			(xy 117.260238 -264.062724) (xy 117.309093 -264.068656) (xy 117.356364 -264.082348) (xy 117.400826 -264.103446)
			(xy 117.441329 -264.131402) (xy 117.476822 -264.165494) (xy 117.506387 -264.204838) (xy 117.529258 -264.248415)
			(xy 117.544842 -264.295096) (xy 117.552737 -264.343673) (xy 117.553232 -264.36828) (xy 118.821974 -264.36828)
			(xy 118.825934 -264.319226) (xy 118.837711 -264.271442) (xy 118.857002 -264.226166) (xy 118.883305 -264.18457)
			(xy 118.91594 -264.147733) (xy 118.954061 -264.116608) (xy 118.996682 -264.092001) (xy 119.042698 -264.074549)
			(xy 119.090917 -264.064705) (xy 119.140092 -264.062724) (xy 119.188947 -264.068656) (xy 119.236218 -264.082348)
			(xy 119.28068 -264.103446) (xy 119.321183 -264.131402) (xy 119.356676 -264.165494) (xy 119.386241 -264.204838)
			(xy 119.409112 -264.248415) (xy 119.424696 -264.295096) (xy 119.432591 -264.343673) (xy 119.433086 -264.36828)
			(xy 120.699796 -264.36828) (xy 120.703756 -264.319226) (xy 120.715533 -264.271442) (xy 120.734824 -264.226166)
			(xy 120.761127 -264.18457) (xy 120.793762 -264.147733) (xy 120.831883 -264.116608) (xy 120.874504 -264.092001)
			(xy 120.92052 -264.074549) (xy 120.968739 -264.064705) (xy 121.017914 -264.062724) (xy 121.066769 -264.068656)
			(xy 121.11404 -264.082348) (xy 121.158502 -264.103446) (xy 121.199005 -264.131402) (xy 121.234498 -264.165494)
			(xy 121.264063 -264.204838) (xy 121.286934 -264.248415) (xy 121.302518 -264.295096) (xy 121.310413 -264.343673)
			(xy 121.310867 -264.366248) (xy 122.578888 -264.366248) (xy 122.582848 -264.317194) (xy 122.594625 -264.26941)
			(xy 122.613916 -264.224134) (xy 122.640219 -264.182538) (xy 122.672854 -264.145701) (xy 122.710975 -264.114576)
			(xy 122.753596 -264.089969) (xy 122.799612 -264.072517) (xy 122.847831 -264.062673) (xy 122.897006 -264.060692)
			(xy 122.945861 -264.066624) (xy 122.993132 -264.080316) (xy 123.037594 -264.101414) (xy 123.078097 -264.12937)
			(xy 123.11359 -264.163462) (xy 123.143155 -264.202806) (xy 123.166026 -264.246383) (xy 123.18161 -264.293064)
			(xy 123.189505 -264.341641) (xy 123.19 -264.366248) (xy 124.458996 -264.366248) (xy 124.462956 -264.317194)
			(xy 124.474733 -264.26941) (xy 124.494024 -264.224134) (xy 124.520327 -264.182538) (xy 124.552962 -264.145701)
			(xy 124.591083 -264.114576) (xy 124.633704 -264.089969) (xy 124.67972 -264.072517) (xy 124.727939 -264.062673)
			(xy 124.777114 -264.060692) (xy 124.825969 -264.066624) (xy 124.87324 -264.080316) (xy 124.917702 -264.101414)
			(xy 124.958205 -264.12937) (xy 124.993698 -264.163462) (xy 125.023263 -264.202806) (xy 125.046134 -264.246383)
			(xy 125.061718 -264.293064) (xy 125.069613 -264.341641) (xy 125.070108 -264.366248) (xy 126.33885 -264.366248)
			(xy 126.34281 -264.317194) (xy 126.354587 -264.26941) (xy 126.373878 -264.224134) (xy 126.400181 -264.182538)
			(xy 126.432816 -264.145701) (xy 126.470937 -264.114576) (xy 126.513558 -264.089969) (xy 126.559574 -264.072517)
			(xy 126.607793 -264.062673) (xy 126.656968 -264.060692) (xy 126.705823 -264.066624) (xy 126.753094 -264.080316)
			(xy 126.797556 -264.101414) (xy 126.838059 -264.12937) (xy 126.873552 -264.163462) (xy 126.903117 -264.202806)
			(xy 126.925988 -264.246383) (xy 126.941572 -264.293064) (xy 126.949467 -264.341641) (xy 126.949962 -264.366248)
			(xy 126.949467 -264.390855) (xy 126.941572 -264.439432) (xy 126.925988 -264.486113) (xy 126.903117 -264.52969)
			(xy 126.873552 -264.569034) (xy 126.838059 -264.603126) (xy 126.797556 -264.631082) (xy 126.753094 -264.65218)
			(xy 126.705823 -264.665872) (xy 126.656968 -264.671804) (xy 126.607793 -264.669823) (xy 126.559574 -264.659979)
			(xy 126.513558 -264.642527) (xy 126.470937 -264.61792) (xy 126.432816 -264.586795) (xy 126.400181 -264.549958)
			(xy 126.373878 -264.508362) (xy 126.354587 -264.463086) (xy 126.34281 -264.415302) (xy 126.33885 -264.366248)
			(xy 125.070108 -264.366248) (xy 125.069613 -264.390855) (xy 125.061718 -264.439432) (xy 125.046134 -264.486113)
			(xy 125.023263 -264.52969) (xy 124.993698 -264.569034) (xy 124.958205 -264.603126) (xy 124.917702 -264.631082)
			(xy 124.87324 -264.65218) (xy 124.825969 -264.665872) (xy 124.777114 -264.671804) (xy 124.727939 -264.669823)
			(xy 124.67972 -264.659979) (xy 124.633704 -264.642527) (xy 124.591083 -264.61792) (xy 124.552962 -264.586795)
			(xy 124.520327 -264.549958) (xy 124.494024 -264.508362) (xy 124.474733 -264.463086) (xy 124.462956 -264.415302)
			(xy 124.458996 -264.366248) (xy 123.19 -264.366248) (xy 123.189505 -264.390855) (xy 123.18161 -264.439432)
			(xy 123.166026 -264.486113) (xy 123.143155 -264.52969) (xy 123.11359 -264.569034) (xy 123.078097 -264.603126)
			(xy 123.037594 -264.631082) (xy 122.993132 -264.65218) (xy 122.945861 -264.665872) (xy 122.897006 -264.671804)
			(xy 122.847831 -264.669823) (xy 122.799612 -264.659979) (xy 122.753596 -264.642527) (xy 122.710975 -264.61792)
			(xy 122.672854 -264.586795) (xy 122.640219 -264.549958) (xy 122.613916 -264.508362) (xy 122.594625 -264.463086)
			(xy 122.582848 -264.415302) (xy 122.578888 -264.366248) (xy 121.310867 -264.366248) (xy 121.310908 -264.36828)
			(xy 121.310413 -264.392887) (xy 121.302518 -264.441464) (xy 121.286934 -264.488145) (xy 121.264063 -264.531722)
			(xy 121.234498 -264.571066) (xy 121.199005 -264.605158) (xy 121.158502 -264.633114) (xy 121.11404 -264.654212)
			(xy 121.066769 -264.667904) (xy 121.017914 -264.673836) (xy 120.968739 -264.671855) (xy 120.92052 -264.662011)
			(xy 120.874504 -264.644559) (xy 120.831883 -264.619952) (xy 120.793762 -264.588827) (xy 120.761127 -264.55199)
			(xy 120.734824 -264.510394) (xy 120.715533 -264.465118) (xy 120.703756 -264.417334) (xy 120.699796 -264.36828)
			(xy 119.433086 -264.36828) (xy 119.432591 -264.392887) (xy 119.424696 -264.441464) (xy 119.409112 -264.488145)
			(xy 119.386241 -264.531722) (xy 119.356676 -264.571066) (xy 119.321183 -264.605158) (xy 119.28068 -264.633114)
			(xy 119.236218 -264.654212) (xy 119.188947 -264.667904) (xy 119.140092 -264.673836) (xy 119.090917 -264.671855)
			(xy 119.042698 -264.662011) (xy 118.996682 -264.644559) (xy 118.954061 -264.619952) (xy 118.91594 -264.588827)
			(xy 118.883305 -264.55199) (xy 118.857002 -264.510394) (xy 118.837711 -264.465118) (xy 118.825934 -264.417334)
			(xy 118.821974 -264.36828) (xy 117.553232 -264.36828) (xy 117.552737 -264.392887) (xy 117.544842 -264.441464)
			(xy 117.529258 -264.488145) (xy 117.506387 -264.531722) (xy 117.476822 -264.571066) (xy 117.441329 -264.605158)
			(xy 117.400826 -264.633114) (xy 117.356364 -264.654212) (xy 117.309093 -264.667904) (xy 117.260238 -264.673836)
			(xy 117.211063 -264.671855) (xy 117.162844 -264.662011) (xy 117.116828 -264.644559) (xy 117.074207 -264.619952)
			(xy 117.036086 -264.588827) (xy 117.003451 -264.55199) (xy 116.977148 -264.510394) (xy 116.957857 -264.465118)
			(xy 116.94608 -264.417334) (xy 116.94212 -264.36828) (xy 115.673124 -264.36828) (xy 115.672629 -264.392887)
			(xy 115.664734 -264.441464) (xy 115.64915 -264.488145) (xy 115.626279 -264.531722) (xy 115.596714 -264.571066)
			(xy 115.561221 -264.605158) (xy 115.520718 -264.633114) (xy 115.476256 -264.654212) (xy 115.428985 -264.667904)
			(xy 115.38013 -264.673836) (xy 115.330955 -264.671855) (xy 115.282736 -264.662011) (xy 115.23672 -264.644559)
			(xy 115.194099 -264.619952) (xy 115.155978 -264.588827) (xy 115.123343 -264.55199) (xy 115.09704 -264.510394)
			(xy 115.077749 -264.465118) (xy 115.065972 -264.417334) (xy 115.062012 -264.36828) (xy 108.1532 -264.36828)
			(xy 108.152705 -264.392887) (xy 108.14481 -264.441464) (xy 108.129226 -264.488145) (xy 108.106355 -264.531722)
			(xy 108.07679 -264.571066) (xy 108.041297 -264.605158) (xy 108.000794 -264.633114) (xy 107.956332 -264.654212)
			(xy 107.909061 -264.667904) (xy 107.860206 -264.673836) (xy 107.811031 -264.671855) (xy 107.762812 -264.662011)
			(xy 107.716796 -264.644559) (xy 107.674175 -264.619952) (xy 107.636054 -264.588827) (xy 107.603419 -264.55199)
			(xy 107.577116 -264.510394) (xy 107.557825 -264.465118) (xy 107.546048 -264.417334) (xy 107.542088 -264.36828)
			(xy 106.273346 -264.36828) (xy 106.272851 -264.392887) (xy 106.264956 -264.441464) (xy 106.249372 -264.488145)
			(xy 106.226501 -264.531722) (xy 106.196936 -264.571066) (xy 106.161443 -264.605158) (xy 106.12094 -264.633114)
			(xy 106.076478 -264.654212) (xy 106.029207 -264.667904) (xy 105.980352 -264.673836) (xy 105.931177 -264.671855)
			(xy 105.882958 -264.662011) (xy 105.836942 -264.644559) (xy 105.794321 -264.619952) (xy 105.7562 -264.588827)
			(xy 105.723565 -264.55199) (xy 105.697262 -264.510394) (xy 105.677971 -264.465118) (xy 105.666194 -264.417334)
			(xy 105.662234 -264.36828) (xy 104.393238 -264.36828) (xy 104.392743 -264.392887) (xy 104.384848 -264.441464)
			(xy 104.369264 -264.488145) (xy 104.346393 -264.531722) (xy 104.316828 -264.571066) (xy 104.281335 -264.605158)
			(xy 104.240832 -264.633114) (xy 104.19637 -264.654212) (xy 104.149099 -264.667904) (xy 104.100244 -264.673836)
			(xy 104.051069 -264.671855) (xy 104.00285 -264.662011) (xy 103.956834 -264.644559) (xy 103.914213 -264.619952)
			(xy 103.876092 -264.588827) (xy 103.843457 -264.55199) (xy 103.817154 -264.510394) (xy 103.797863 -264.465118)
			(xy 103.786086 -264.417334) (xy 103.782126 -264.36828) (xy 102.588568 -264.36828) (xy 102.50424 -264.452608)
			(xy 102.50043 -264.464038) (xy 102.492518 -264.486062) (xy 102.470954 -264.527593) (xy 102.443305 -264.565348)
			(xy 102.410221 -264.598443) (xy 102.372475 -264.626103) (xy 102.330951 -264.647681) (xy 102.308914 -264.655554)
			(xy 102.297484 -264.659364) (xy 102.094284 -264.862564) (xy 111.234223 -264.862564) (xy 111.238253 -264.810066)
			(xy 111.25025 -264.758798) (xy 111.269933 -264.709963) (xy 111.296839 -264.664704) (xy 111.330339 -264.624083)
			(xy 111.369647 -264.589052) (xy 111.413842 -264.560432) (xy 111.461887 -264.538893) (xy 111.512658 -264.524941)
			(xy 111.564963 -264.518903) (xy 111.617577 -264.52092) (xy 111.669267 -264.530944) (xy 111.71882 -264.548742)
			(xy 111.765076 -264.573895) (xy 111.80695 -264.605814) (xy 111.843462 -264.643752) (xy 111.873754 -264.686818)
			(xy 111.897117 -264.734003) (xy 111.913003 -264.784202) (xy 111.92104 -264.836238) (xy 111.921544 -264.862564)
			(xy 111.92104 -264.88889) (xy 111.913003 -264.940926) (xy 111.897117 -264.991125) (xy 111.873754 -265.03831)
			(xy 111.843462 -265.081376) (xy 111.80695 -265.119314) (xy 111.765076 -265.151233) (xy 111.719063 -265.176254)
			(xy 121.168934 -265.176254) (xy 121.172894 -265.1272) (xy 121.184671 -265.079416) (xy 121.203962 -265.03414)
			(xy 121.230265 -264.992544) (xy 121.2629 -264.955707) (xy 121.301021 -264.924582) (xy 121.343642 -264.899975)
			(xy 121.389658 -264.882523) (xy 121.437877 -264.872679) (xy 121.487052 -264.870698) (xy 121.535907 -264.87663)
			(xy 121.583178 -264.890322) (xy 121.62764 -264.91142) (xy 121.668143 -264.939376) (xy 121.703636 -264.973468)
			(xy 121.733201 -265.012812) (xy 121.756072 -265.056389) (xy 121.771656 -265.10307) (xy 121.779551 -265.151647)
			(xy 121.780046 -265.176254) (xy 123.049042 -265.176254) (xy 123.053002 -265.1272) (xy 123.064779 -265.079416)
			(xy 123.08407 -265.03414) (xy 123.110373 -264.992544) (xy 123.143008 -264.955707) (xy 123.181129 -264.924582)
			(xy 123.22375 -264.899975) (xy 123.269766 -264.882523) (xy 123.317985 -264.872679) (xy 123.36716 -264.870698)
			(xy 123.416015 -264.87663) (xy 123.463286 -264.890322) (xy 123.507748 -264.91142) (xy 123.548251 -264.939376)
			(xy 123.583744 -264.973468) (xy 123.613309 -265.012812) (xy 123.63618 -265.056389) (xy 123.651764 -265.10307)
			(xy 123.659659 -265.151647) (xy 123.660154 -265.176254) (xy 124.928896 -265.176254) (xy 124.932856 -265.1272)
			(xy 124.944633 -265.079416) (xy 124.963924 -265.03414) (xy 124.990227 -264.992544) (xy 125.022862 -264.955707)
			(xy 125.060983 -264.924582) (xy 125.103604 -264.899975) (xy 125.14962 -264.882523) (xy 125.197839 -264.872679)
			(xy 125.247014 -264.870698) (xy 125.295869 -264.87663) (xy 125.34314 -264.890322) (xy 125.387602 -264.91142)
			(xy 125.428105 -264.939376) (xy 125.463598 -264.973468) (xy 125.493163 -265.012812) (xy 125.516034 -265.056389)
			(xy 125.531618 -265.10307) (xy 125.539513 -265.151647) (xy 125.540008 -265.176254) (xy 125.539513 -265.200861)
			(xy 125.531618 -265.249438) (xy 125.516034 -265.296119) (xy 125.493163 -265.339696) (xy 125.463598 -265.37904)
			(xy 125.428105 -265.413132) (xy 125.387602 -265.441088) (xy 125.34314 -265.462186) (xy 125.295869 -265.475878)
			(xy 125.247014 -265.48181) (xy 125.197839 -265.479829) (xy 125.14962 -265.469985) (xy 125.103604 -265.452533)
			(xy 125.060983 -265.427926) (xy 125.022862 -265.396801) (xy 124.990227 -265.359964) (xy 124.963924 -265.318368)
			(xy 124.944633 -265.273092) (xy 124.932856 -265.225308) (xy 124.928896 -265.176254) (xy 123.660154 -265.176254)
			(xy 123.659659 -265.200861) (xy 123.651764 -265.249438) (xy 123.63618 -265.296119) (xy 123.613309 -265.339696)
			(xy 123.583744 -265.37904) (xy 123.548251 -265.413132) (xy 123.507748 -265.441088) (xy 123.463286 -265.462186)
			(xy 123.416015 -265.475878) (xy 123.36716 -265.48181) (xy 123.317985 -265.479829) (xy 123.269766 -265.469985)
			(xy 123.22375 -265.452533) (xy 123.181129 -265.427926) (xy 123.143008 -265.396801) (xy 123.110373 -265.359964)
			(xy 123.08407 -265.318368) (xy 123.064779 -265.273092) (xy 123.053002 -265.225308) (xy 123.049042 -265.176254)
			(xy 121.780046 -265.176254) (xy 121.779551 -265.200861) (xy 121.771656 -265.249438) (xy 121.756072 -265.296119)
			(xy 121.733201 -265.339696) (xy 121.703636 -265.37904) (xy 121.668143 -265.413132) (xy 121.62764 -265.441088)
			(xy 121.583178 -265.462186) (xy 121.535907 -265.475878) (xy 121.487052 -265.48181) (xy 121.437877 -265.479829)
			(xy 121.389658 -265.469985) (xy 121.343642 -265.452533) (xy 121.301021 -265.427926) (xy 121.2629 -265.396801)
			(xy 121.230265 -265.359964) (xy 121.203962 -265.318368) (xy 121.184671 -265.273092) (xy 121.172894 -265.225308)
			(xy 121.168934 -265.176254) (xy 111.719063 -265.176254) (xy 111.71882 -265.176386) (xy 111.669267 -265.194184)
			(xy 111.617577 -265.204208) (xy 111.564963 -265.206225) (xy 111.512658 -265.200187) (xy 111.461887 -265.186235)
			(xy 111.413842 -265.164696) (xy 111.369647 -265.136076) (xy 111.330339 -265.101045) (xy 111.296839 -265.060424)
			(xy 111.269933 -265.015165) (xy 111.25025 -264.96633) (xy 111.238253 -264.915062) (xy 111.234223 -264.862564)
			(xy 102.094284 -264.862564) (xy 102.0064 -264.950448) (xy 101.998603 -264.95892) (xy 101.990947 -264.98061)
			(xy 101.993542 -265.003465) (xy 101.999288 -265.01344) (xy 102.014004 -265.038021) (xy 102.034973 -265.09133)
			(xy 102.045648 -265.147612) (xy 102.046278 -265.176254) (xy 102.045835 -265.200249) (xy 102.038334 -265.247648)
			(xy 102.023509 -265.29329) (xy 102.001726 -265.33605) (xy 101.97352 -265.374876) (xy 101.939588 -265.40881)
			(xy 101.900764 -265.437017) (xy 101.858005 -265.458803) (xy 101.812364 -265.47363) (xy 101.764965 -265.481134)
			(xy 101.74097 -265.481562) (xy 101.713321 -265.48096) (xy 101.658928 -265.470993) (xy 101.60722 -265.451391)
			(xy 101.583236 -265.43762) (xy 101.577394 -265.434318) (xy 101.563932 -265.430254) (xy 101.555077 -265.428065)
			(xy 101.536899 -265.429405) (xy 101.520336 -265.437014) (xy 101.51364 -265.443208) (xy 101.042216 -265.914632)
			(xy 101.035503 -265.92187) (xy 101.027912 -265.940075) (xy 101.027484 -265.949938) (xy 101.027484 -265.98626)
			(xy 101.90532 -265.98626) (xy 101.90928 -265.937206) (xy 101.921057 -265.889422) (xy 101.940348 -265.844146)
			(xy 101.966651 -265.80255) (xy 101.999286 -265.765713) (xy 102.037407 -265.734588) (xy 102.080028 -265.709981)
			(xy 102.126044 -265.692529) (xy 102.174263 -265.682685) (xy 102.223438 -265.680704) (xy 102.272293 -265.686636)
			(xy 102.319564 -265.700328) (xy 102.364026 -265.721426) (xy 102.404529 -265.749382) (xy 102.440022 -265.783474)
			(xy 102.469587 -265.822818) (xy 102.492458 -265.866395) (xy 102.508042 -265.913076) (xy 102.515937 -265.961653)
			(xy 102.516432 -265.98626) (xy 102.515937 -266.010867) (xy 102.508042 -266.059444) (xy 102.492458 -266.106125)
			(xy 102.469587 -266.149702) (xy 102.440022 -266.189046) (xy 102.404529 -266.223138) (xy 102.364026 -266.251094)
			(xy 102.319564 -266.272192) (xy 102.272293 -266.285884) (xy 102.223438 -266.291816) (xy 102.174263 -266.289835)
			(xy 102.126044 -266.279991) (xy 102.080028 -266.262539) (xy 102.037407 -266.237932) (xy 101.999286 -266.206807)
			(xy 101.966651 -266.16997) (xy 101.940348 -266.128374) (xy 101.921057 -266.083098) (xy 101.90928 -266.035314)
			(xy 101.90532 -265.98626) (xy 101.027484 -265.98626) (xy 101.027484 -266.129262) (xy 101.027918 -266.139328)
			(xy 101.035646 -266.157917) (xy 101.04247 -266.16533) (xy 101.440996 -266.563856) (xy 101.448392 -266.570708)
			(xy 101.466991 -266.578451) (xy 101.477064 -266.578842) (xy 101.497892 -266.578842) (xy 101.502439 -266.578716)
			(xy 101.511381 -266.57705) (xy 101.515672 -266.57554) (xy 101.539294 -266.566904) (xy 101.545898 -266.561316)
			(xy 101.566626 -266.544853) (xy 101.612577 -266.518587) (xy 101.662367 -266.500631) (xy 101.714506 -266.491522)
			(xy 101.74097 -266.490958) (xy 101.764964 -266.491426) (xy 101.812361 -266.498929) (xy 101.858001 -266.513753)
			(xy 101.900761 -266.535534) (xy 101.939586 -266.563737) (xy 101.973522 -266.597665) (xy 102.001732 -266.636485)
			(xy 102.023523 -266.67924) (xy 102.038357 -266.724877) (xy 102.045869 -266.772272) (xy 102.046278 -266.796266)
			(xy 102.045896 -266.818013) (xy 102.03973 -266.861067) (xy 102.027517 -266.902811) (xy 102.018846 -266.922758)
			(xy 102.013512 -266.934696) (xy 102.01529 -266.96035) (xy 102.06736 -267.041376) (xy 102.072219 -267.048326)
			(xy 102.085548 -267.058798) (xy 102.101558 -267.064364) (xy 102.110032 -267.064744) (xy 103.252016 -267.064744)
			(xy 103.260504 -267.064436) (xy 103.276545 -267.058885) (xy 103.289871 -267.04837) (xy 103.294688 -267.041376)
			(xy 103.346758 -266.96035) (xy 103.348536 -266.934696) (xy 103.343202 -266.922758) (xy 103.334542 -266.902807)
			(xy 103.322325 -266.861065) (xy 103.316156 -266.818012) (xy 103.31577 -266.796266) (xy 103.316243 -266.772276)
			(xy 103.323753 -266.724887) (xy 103.338583 -266.679256) (xy 103.360368 -266.636507) (xy 103.388572 -266.597691)
			(xy 103.4225 -266.563764) (xy 103.461317 -266.535562) (xy 103.504067 -266.513779) (xy 103.549699 -266.498951)
			(xy 103.597088 -266.491442) (xy 103.621078 -266.490958) (xy 103.646806 -266.491464) (xy 103.69754 -266.500044)
			(xy 103.746116 -266.517014) (xy 103.791156 -266.541893) (xy 103.831383 -266.573976) (xy 103.848916 -266.592812)
			(xy 103.856028 -266.60094) (xy 103.87457 -266.609576) (xy 103.957374 -266.611862) (xy 103.967764 -266.611622)
			(xy 103.987029 -266.603877) (xy 103.994712 -266.596876) (xy 104.130094 -266.461494) (xy 104.136635 -266.454333)
			(xy 104.144257 -266.436515) (xy 104.144729 -266.417141) (xy 104.141778 -266.4079) (xy 104.105202 -266.309602)
			(xy 104.081834 -266.291822) (xy 104.066848 -266.290552) (xy 104.04165 -266.288054) (xy 103.992527 -266.275781)
			(xy 103.946101 -266.255574) (xy 103.903643 -266.227987) (xy 103.866316 -266.193775) (xy 103.835143 -266.153876)
			(xy 103.810976 -266.109382) (xy 103.794479 -266.061512) (xy 103.786102 -266.011576) (xy 103.78567 -265.98626)
			(xy 103.786192 -265.961005) (xy 103.794505 -265.911183) (xy 103.810906 -265.863409) (xy 103.834947 -265.818986)
			(xy 103.865971 -265.779126) (xy 103.903133 -265.744916) (xy 103.945419 -265.71729) (xy 103.991675 -265.697)
			(xy 104.04064 -265.6846) (xy 104.090978 -265.680429) (xy 104.141316 -265.6846) (xy 104.190281 -265.697)
			(xy 104.236537 -265.71729) (xy 104.278823 -265.744916) (xy 104.315985 -265.779126) (xy 104.347009 -265.818986)
			(xy 104.37105 -265.863409) (xy 104.387451 -265.911183) (xy 104.395764 -265.961005) (xy 104.396286 -265.98626)
			(xy 105.665282 -265.98626) (xy 105.669242 -265.937206) (xy 105.681019 -265.889422) (xy 105.70031 -265.844146)
			(xy 105.726613 -265.80255) (xy 105.759248 -265.765713) (xy 105.797369 -265.734588) (xy 105.83999 -265.709981)
			(xy 105.886006 -265.692529) (xy 105.934225 -265.682685) (xy 105.9834 -265.680704) (xy 106.032255 -265.686636)
			(xy 106.079526 -265.700328) (xy 106.123988 -265.721426) (xy 106.164491 -265.749382) (xy 106.199984 -265.783474)
			(xy 106.229549 -265.822818) (xy 106.25242 -265.866395) (xy 106.268004 -265.913076) (xy 106.275899 -265.961653)
			(xy 106.276394 -265.98626) (xy 106.275899 -266.010867) (xy 106.268004 -266.059444) (xy 106.25242 -266.106125)
			(xy 106.229549 -266.149702) (xy 106.199984 -266.189046) (xy 106.164491 -266.223138) (xy 106.123988 -266.251094)
			(xy 106.079526 -266.272192) (xy 106.032255 -266.285884) (xy 105.9834 -266.291816) (xy 105.934225 -266.289835)
			(xy 105.886006 -266.279991) (xy 105.83999 -266.262539) (xy 105.797369 -266.237932) (xy 105.759248 -266.206807)
			(xy 105.726613 -266.16997) (xy 105.70031 -266.128374) (xy 105.681019 -266.083098) (xy 105.669242 -266.035314)
			(xy 105.665282 -265.98626) (xy 104.396286 -265.98626) (xy 104.395895 -266.007103) (xy 104.39016 -266.048395)
			(xy 104.384856 -266.068556) (xy 104.381808 -266.08024) (xy 104.386126 -266.103354) (xy 104.44099 -266.175998)
			(xy 104.448584 -266.184982) (xy 104.469629 -266.19543) (xy 104.481376 -266.196064) (xy 105.43413 -266.196064)
			(xy 105.443971 -266.196592) (xy 105.462146 -266.204165) (xy 105.469436 -266.210796) (xy 106.267758 -267.009118)
			(xy 106.275156 -267.015964) (xy 106.293755 -267.02369) (xy 106.303826 -267.024104) (xy 106.995976 -267.024104)
			(xy 107.008043 -267.023429) (xy 107.029518 -267.012416) (xy 107.037124 -267.003022) (xy 107.091226 -266.927838)
			(xy 107.095036 -266.903708) (xy 107.091226 -266.892024) (xy 107.084089 -266.869052) (xy 107.076301 -266.821584)
			(xy 107.075732 -266.797536) (xy 107.075732 -266.79271) (xy 107.076469 -266.768905) (xy 107.084417 -266.721947)
			(xy 107.09956 -266.676794) (xy 107.121532 -266.63454) (xy 107.149798 -266.596211) (xy 107.183674 -266.562736)
			(xy 107.222337 -266.534927) (xy 107.264849 -266.513459) (xy 107.310179 -266.498854) (xy 107.357227 -266.491464)
			(xy 107.38104 -266.490958) (xy 107.407516 -266.491527) (xy 107.459672 -266.500667) (xy 107.50947 -266.518668)
			(xy 107.555417 -266.544988) (xy 107.596135 -266.578839) (xy 107.613704 -266.598654) (xy 107.620816 -266.607036)
			(xy 107.639612 -266.61618) (xy 107.723432 -266.619482) (xy 107.733933 -266.619393) (xy 107.753482 -266.611785)
			(xy 107.761278 -266.60475) (xy 107.903518 -266.46251) (xy 107.910141 -266.455234) (xy 107.917793 -266.437127)
			(xy 107.918104 -266.417471) (xy 107.914948 -266.408154) (xy 107.876594 -266.309348) (xy 107.852464 -266.292076)
			(xy 107.837224 -266.291314) (xy 107.811376 -266.289607) (xy 107.760764 -266.278585) (xy 107.712739 -266.259179)
			(xy 107.668678 -266.231944) (xy 107.629847 -266.197664) (xy 107.597359 -266.15732) (xy 107.572147 -266.112072)
			(xy 107.554934 -266.063218) (xy 107.546214 -266.012159) (xy 107.545632 -265.98626) (xy 107.546106 -265.962272)
			(xy 107.553617 -265.914887) (xy 107.568448 -265.869261) (xy 107.590235 -265.826517) (xy 107.618439 -265.787707)
			(xy 107.652368 -265.753787) (xy 107.691185 -265.725593) (xy 107.733935 -265.703818) (xy 107.779565 -265.688998)
			(xy 107.826952 -265.681499) (xy 107.85094 -265.680952) (xy 107.874753 -265.681412) (xy 107.9218 -265.688812)
			(xy 107.967128 -265.703427) (xy 108.009637 -265.724903) (xy 108.048296 -265.752718) (xy 108.082168 -265.786197)
			(xy 108.110431 -265.82453) (xy 108.1324 -265.866786) (xy 108.147542 -265.911941) (xy 108.15549 -265.958898)
			(xy 108.156248 -265.982704) (xy 108.156248 -265.985752) (xy 108.156239 -265.98626) (xy 109.425244 -265.98626)
			(xy 109.429204 -265.937206) (xy 109.440981 -265.889422) (xy 109.460272 -265.844146) (xy 109.486575 -265.80255)
			(xy 109.51921 -265.765713) (xy 109.557331 -265.734588) (xy 109.599952 -265.709981) (xy 109.645968 -265.692529)
			(xy 109.694187 -265.682685) (xy 109.743362 -265.680704) (xy 109.792217 -265.686636) (xy 109.839488 -265.700328)
			(xy 109.88395 -265.721426) (xy 109.924453 -265.749382) (xy 109.959946 -265.783474) (xy 109.989511 -265.822818)
			(xy 110.012382 -265.866395) (xy 110.027966 -265.913076) (xy 110.035861 -265.961653) (xy 110.036356 -265.98626)
			(xy 113.178856 -265.98626) (xy 113.182816 -265.937206) (xy 113.194593 -265.889422) (xy 113.213884 -265.844146)
			(xy 113.240187 -265.80255) (xy 113.272822 -265.765713) (xy 113.310943 -265.734588) (xy 113.353564 -265.709981)
			(xy 113.39958 -265.692529) (xy 113.447799 -265.682685) (xy 113.496974 -265.680704) (xy 113.545829 -265.686636)
			(xy 113.5931 -265.700328) (xy 113.637562 -265.721426) (xy 113.678065 -265.749382) (xy 113.713558 -265.783474)
			(xy 113.743123 -265.822818) (xy 113.765994 -265.866395) (xy 113.781578 -265.913076) (xy 113.789473 -265.961653)
			(xy 113.789968 -265.98626) (xy 113.789473 -266.010867) (xy 113.781578 -266.059444) (xy 113.765994 -266.106125)
			(xy 113.743123 -266.149702) (xy 113.713558 -266.189046) (xy 113.678065 -266.223138) (xy 113.637562 -266.251094)
			(xy 113.5931 -266.272192) (xy 113.545829 -266.285884) (xy 113.496974 -266.291816) (xy 113.447799 -266.289835)
			(xy 113.39958 -266.279991) (xy 113.353564 -266.262539) (xy 113.310943 -266.237932) (xy 113.272822 -266.206807)
			(xy 113.240187 -266.16997) (xy 113.213884 -266.128374) (xy 113.194593 -266.083098) (xy 113.182816 -266.035314)
			(xy 113.178856 -265.98626) (xy 110.036356 -265.98626) (xy 110.035861 -266.010867) (xy 110.027966 -266.059444)
			(xy 110.012382 -266.106125) (xy 109.989511 -266.149702) (xy 109.959946 -266.189046) (xy 109.924453 -266.223138)
			(xy 109.88395 -266.251094) (xy 109.839488 -266.272192) (xy 109.792217 -266.285884) (xy 109.743362 -266.291816)
			(xy 109.694187 -266.289835) (xy 109.645968 -266.279991) (xy 109.599952 -266.262539) (xy 109.557331 -266.237932)
			(xy 109.51921 -266.206807) (xy 109.486575 -266.16997) (xy 109.460272 -266.128374) (xy 109.440981 -266.083098)
			(xy 109.429204 -266.035314) (xy 109.425244 -265.98626) (xy 108.156239 -265.98626) (xy 108.15581 -266.009241)
			(xy 108.148665 -266.055673) (xy 108.142024 -266.078208) (xy 108.138468 -266.089892) (xy 108.142278 -266.113514)
			(xy 108.196634 -266.187936) (xy 108.204253 -266.197285) (xy 108.225737 -266.208168) (xy 108.237782 -266.208764)
			(xy 109.18317 -266.208764) (xy 109.193008 -266.209299) (xy 109.211173 -266.216882) (xy 109.218476 -266.223496)
			(xy 110.032038 -267.037058) (xy 110.039437 -267.043903) (xy 110.058035 -267.05163) (xy 110.068106 -267.052044)
			(xy 110.705138 -267.052044) (xy 110.715204 -267.051612) (xy 110.733793 -267.043882) (xy 110.741206 -267.037058)
			(xy 111.378238 -266.400026) (xy 111.385637 -266.393183) (xy 111.404236 -266.385458) (xy 111.414306 -266.38504)
			(xy 112.707674 -266.38504) (xy 112.717737 -266.385478) (xy 112.736318 -266.393216) (xy 112.743742 -266.400026)
			(xy 113.380774 -267.037058) (xy 113.388174 -267.043897) (xy 113.406773 -267.051612) (xy 113.416842 -267.052044)
			(xy 113.57991 -267.052044) (xy 113.592463 -267.051398) (xy 113.614586 -267.039534) (xy 113.622074 -267.029438)
			(xy 113.67516 -266.950444) (xy 113.6777 -266.925044) (xy 113.672874 -266.91336) (xy 113.662063 -266.885429)
			(xy 113.650291 -266.826714) (xy 113.649506 -266.796774) (xy 113.649506 -266.791694) (xy 113.65031 -266.767935)
			(xy 113.658369 -266.721086) (xy 113.673592 -266.676053) (xy 113.695611 -266.633922) (xy 113.723892 -266.595714)
			(xy 113.757754 -266.56235) (xy 113.796377 -266.534637) (xy 113.838829 -266.513244) (xy 113.884083 -266.49869)
			(xy 113.931046 -266.491325) (xy 113.954814 -266.490958) (xy 113.978951 -266.491416) (xy 114.026625 -266.499012)
			(xy 114.07251 -266.514012) (xy 114.115464 -266.536043) (xy 114.154418 -266.564556) (xy 114.17173 -266.581382)
			(xy 114.171984 -266.581382) (xy 114.17935 -266.588222) (xy 114.197883 -266.595964) (xy 114.217967 -266.595964)
			(xy 114.2365 -266.588222) (xy 114.243866 -266.581382) (xy 114.535712 -266.289536) (xy 114.542948 -266.282818)
			(xy 114.561153 -266.275216) (xy 114.571018 -266.274804) (xy 115.005612 -266.274804) (xy 115.014341 -266.274453)
			(xy 115.030778 -266.268571) (xy 115.044252 -266.257471) (xy 115.049046 -266.250166) (xy 115.099592 -266.166346)
			(xy 115.100608 -266.139676) (xy 115.094258 -266.127992) (xy 115.083307 -266.105987) (xy 115.067796 -266.059351)
			(xy 115.059943 -266.010834) (xy 115.05946 -265.98626) (xy 115.059982 -265.961005) (xy 115.068295 -265.911183)
			(xy 115.084696 -265.863409) (xy 115.108737 -265.818986) (xy 115.139761 -265.779126) (xy 115.176923 -265.744916)
			(xy 115.219209 -265.71729) (xy 115.265465 -265.697) (xy 115.31443 -265.6846) (xy 115.364768 -265.680429)
			(xy 115.415106 -265.6846) (xy 115.464071 -265.697) (xy 115.510327 -265.71729) (xy 115.552613 -265.744916)
			(xy 115.589775 -265.779126) (xy 115.620799 -265.818986) (xy 115.64484 -265.863409) (xy 115.661241 -265.911183)
			(xy 115.669554 -265.961005) (xy 115.670076 -265.98626) (xy 116.938818 -265.98626) (xy 116.942778 -265.937206)
			(xy 116.954555 -265.889422) (xy 116.973846 -265.844146) (xy 117.000149 -265.80255) (xy 117.032784 -265.765713)
			(xy 117.070905 -265.734588) (xy 117.113526 -265.709981) (xy 117.159542 -265.692529) (xy 117.207761 -265.682685)
			(xy 117.256936 -265.680704) (xy 117.305791 -265.686636) (xy 117.353062 -265.700328) (xy 117.397524 -265.721426)
			(xy 117.438027 -265.749382) (xy 117.47352 -265.783474) (xy 117.503085 -265.822818) (xy 117.525956 -265.866395)
			(xy 117.54154 -265.913076) (xy 117.549435 -265.961653) (xy 117.54993 -265.98626) (xy 117.549435 -266.010867)
			(xy 117.54154 -266.059444) (xy 117.525956 -266.106125) (xy 117.503085 -266.149702) (xy 117.47352 -266.189046)
			(xy 117.438027 -266.223138) (xy 117.397524 -266.251094) (xy 117.353062 -266.272192) (xy 117.305791 -266.285884)
			(xy 117.256936 -266.291816) (xy 117.207761 -266.289835) (xy 117.159542 -266.279991) (xy 117.113526 -266.262539)
			(xy 117.070905 -266.237932) (xy 117.032784 -266.206807) (xy 117.000149 -266.16997) (xy 116.973846 -266.128374)
			(xy 116.954555 -266.083098) (xy 116.942778 -266.035314) (xy 116.938818 -265.98626) (xy 115.670076 -265.98626)
			(xy 115.669634 -266.010838) (xy 115.661797 -266.059365) (xy 115.646271 -266.106005) (xy 115.635278 -266.127992)
			(xy 115.628928 -266.139676) (xy 115.629944 -266.166346) (xy 115.68049 -266.250166) (xy 115.685305 -266.257444)
			(xy 115.698799 -266.268491) (xy 115.715206 -266.274401) (xy 115.723924 -266.274804) (xy 115.81003 -266.274804)
			(xy 115.819871 -266.275333) (xy 115.838042 -266.28291) (xy 115.845336 -266.289536) (xy 116.577618 -267.021818)
			(xy 116.585014 -267.02867) (xy 116.603613 -267.036411) (xy 116.613686 -267.036804) (xy 117.334284 -267.036804)
			(xy 117.346616 -267.036222) (xy 117.368465 -267.024784) (xy 117.37594 -267.01496) (xy 117.429534 -266.937998)
			(xy 117.432582 -266.913868) (xy 117.428264 -266.90193) (xy 117.419482 -266.876402) (xy 117.41002 -266.823257)
			(xy 117.409468 -266.796266) (xy 117.409941 -266.772276) (xy 117.417451 -266.724887) (xy 117.432281 -266.679256)
			(xy 117.454066 -266.636506) (xy 117.48227 -266.59769) (xy 117.516198 -266.563763) (xy 117.555015 -266.535561)
			(xy 117.597765 -266.513778) (xy 117.643397 -266.498949) (xy 117.690786 -266.49144) (xy 117.714776 -266.490958)
			(xy 117.737637 -266.491362) (xy 117.782849 -266.498174) (xy 117.826541 -266.511648) (xy 117.867736 -266.531484)
			(xy 117.905514 -266.557239) (xy 117.922548 -266.572492) (xy 117.937788 -266.586462) (xy 117.978428 -266.5857)
			(xy 118.274592 -266.289536) (xy 118.281826 -266.282814) (xy 118.300032 -266.275205) (xy 118.309898 -266.274804)
			(xy 118.765574 -266.274804) (xy 118.774307 -266.274459) (xy 118.790753 -266.268585) (xy 118.804237 -266.257488)
			(xy 118.809008 -266.250166) (xy 118.859554 -266.166346) (xy 118.86057 -266.139676) (xy 118.85422 -266.127992)
			(xy 118.843271 -266.105987) (xy 118.827761 -266.05935) (xy 118.819909 -266.010834) (xy 118.819422 -265.98626)
			(xy 118.819944 -265.961005) (xy 118.828257 -265.911183) (xy 118.844658 -265.863409) (xy 118.868699 -265.818986)
			(xy 118.899723 -265.779126) (xy 118.936885 -265.744916) (xy 118.979171 -265.71729) (xy 119.025427 -265.697)
			(xy 119.074392 -265.6846) (xy 119.12473 -265.680429) (xy 119.175068 -265.6846) (xy 119.224033 -265.697)
			(xy 119.270289 -265.71729) (xy 119.312575 -265.744916) (xy 119.349737 -265.779126) (xy 119.380761 -265.818986)
			(xy 119.404802 -265.863409) (xy 119.421203 -265.911183) (xy 119.429516 -265.961005) (xy 119.430038 -265.98626)
			(xy 120.699034 -265.98626) (xy 120.702994 -265.937206) (xy 120.714771 -265.889422) (xy 120.734062 -265.844146)
			(xy 120.760365 -265.80255) (xy 120.793 -265.765713) (xy 120.831121 -265.734588) (xy 120.873742 -265.709981)
			(xy 120.919758 -265.692529) (xy 120.967977 -265.682685) (xy 121.017152 -265.680704) (xy 121.066007 -265.686636)
			(xy 121.113278 -265.700328) (xy 121.15774 -265.721426) (xy 121.198243 -265.749382) (xy 121.233736 -265.783474)
			(xy 121.263301 -265.822818) (xy 121.286172 -265.866395) (xy 121.301756 -265.913076) (xy 121.309651 -265.961653)
			(xy 121.310146 -265.98626) (xy 121.309651 -266.010867) (xy 121.301756 -266.059444) (xy 121.286172 -266.106125)
			(xy 121.263301 -266.149702) (xy 121.233736 -266.189046) (xy 121.198243 -266.223138) (xy 121.15774 -266.251094)
			(xy 121.113278 -266.272192) (xy 121.066007 -266.285884) (xy 121.017152 -266.291816) (xy 120.967977 -266.289835)
			(xy 120.919758 -266.279991) (xy 120.873742 -266.262539) (xy 120.831121 -266.237932) (xy 120.793 -266.206807)
			(xy 120.760365 -266.16997) (xy 120.734062 -266.128374) (xy 120.714771 -266.083098) (xy 120.702994 -266.035314)
			(xy 120.699034 -265.98626) (xy 119.430038 -265.98626) (xy 119.429596 -266.010839) (xy 119.421761 -266.059366)
			(xy 119.406237 -266.106007) (xy 119.39524 -266.127992) (xy 119.38889 -266.139676) (xy 119.389906 -266.166346)
			(xy 119.440452 -266.250166) (xy 119.445265 -266.257448) (xy 119.458758 -266.268505) (xy 119.475166 -266.274427)
			(xy 119.483886 -266.274804) (xy 119.58955 -266.274804) (xy 119.599389 -266.275337) (xy 119.617555 -266.282919)
			(xy 119.624856 -266.289536) (xy 120.357138 -267.021818) (xy 120.364535 -267.028667) (xy 120.383134 -267.036401)
			(xy 120.393206 -267.036804) (xy 121.094246 -267.036804) (xy 121.106571 -267.036209) (xy 121.128397 -267.024756)
			(xy 121.135902 -267.01496) (xy 121.189496 -266.937998) (xy 121.192544 -266.913868) (xy 121.188226 -266.90193)
			(xy 121.179445 -266.876402) (xy 121.169984 -266.823256) (xy 121.16943 -266.796266) (xy 121.169879 -266.772276)
			(xy 121.17739 -266.724887) (xy 121.192222 -266.679256) (xy 121.21401 -266.636507) (xy 121.242217 -266.597693)
			(xy 121.276148 -266.56377) (xy 121.314969 -266.535572) (xy 121.357722 -266.513794) (xy 121.403357 -266.498973)
			(xy 121.450748 -266.491473) (xy 121.474738 -266.490958) (xy 121.500795 -266.491489) (xy 121.552152 -266.500334)
			(xy 121.601264 -266.517763) (xy 121.646709 -266.543269) (xy 121.66727 -266.559284) (xy 121.674636 -266.565126)
			(xy 121.692162 -266.570968) (xy 121.768108 -266.567158) (xy 121.777408 -266.566275) (xy 121.794471 -266.558712)
			(xy 121.801382 -266.552426) (xy 122.130312 -266.223496) (xy 122.13755 -266.216782) (xy 122.155755 -266.209187)
			(xy 122.165618 -266.208764) (xy 122.49785 -266.208764) (xy 122.509871 -266.208088) (xy 122.531318 -266.197212)
			(xy 122.538998 -266.187936) (xy 122.593354 -266.113514) (xy 122.597164 -266.089892) (xy 122.593608 -266.078208)
			(xy 122.586923 -266.055683) (xy 122.579779 -266.009245) (xy 122.579384 -265.985752) (xy 122.579384 -265.982704)
			(xy 122.580182 -265.957641) (xy 122.58895 -265.908274) (xy 122.605666 -265.861002) (xy 122.629881 -265.817096)
			(xy 122.660944 -265.777737) (xy 122.69802 -265.743982) (xy 122.740113 -265.716738) (xy 122.786092 -265.696738)
			(xy 122.83472 -265.684518) (xy 122.884692 -265.680408) (xy 122.934664 -265.684518) (xy 122.983292 -265.696738)
			(xy 123.029271 -265.716738) (xy 123.071364 -265.743982) (xy 123.10844 -265.777737) (xy 123.139503 -265.817096)
			(xy 123.163718 -265.861002) (xy 123.180434 -265.908274) (xy 123.189202 -265.957641) (xy 123.19 -265.982704)
			(xy 123.19 -265.985752) (xy 123.189991 -265.98626) (xy 124.458996 -265.98626) (xy 124.462956 -265.937206)
			(xy 124.474733 -265.889422) (xy 124.494024 -265.844146) (xy 124.520327 -265.80255) (xy 124.552962 -265.765713)
			(xy 124.591083 -265.734588) (xy 124.633704 -265.709981) (xy 124.67972 -265.692529) (xy 124.727939 -265.682685)
			(xy 124.777114 -265.680704) (xy 124.825969 -265.686636) (xy 124.87324 -265.700328) (xy 124.917702 -265.721426)
			(xy 124.958205 -265.749382) (xy 124.993698 -265.783474) (xy 125.023263 -265.822818) (xy 125.046134 -265.866395)
			(xy 125.061718 -265.913076) (xy 125.069613 -265.961653) (xy 125.070108 -265.98626) (xy 126.33885 -265.98626)
			(xy 126.34281 -265.937206) (xy 126.354587 -265.889422) (xy 126.373878 -265.844146) (xy 126.400181 -265.80255)
			(xy 126.432816 -265.765713) (xy 126.470937 -265.734588) (xy 126.513558 -265.709981) (xy 126.559574 -265.692529)
			(xy 126.607793 -265.682685) (xy 126.656968 -265.680704) (xy 126.705823 -265.686636) (xy 126.753094 -265.700328)
			(xy 126.797556 -265.721426) (xy 126.838059 -265.749382) (xy 126.873552 -265.783474) (xy 126.903117 -265.822818)
			(xy 126.925988 -265.866395) (xy 126.941572 -265.913076) (xy 126.949467 -265.961653) (xy 126.949962 -265.98626)
			(xy 126.949467 -266.010867) (xy 126.941572 -266.059444) (xy 126.925988 -266.106125) (xy 126.903117 -266.149702)
			(xy 126.873552 -266.189046) (xy 126.838059 -266.223138) (xy 126.797556 -266.251094) (xy 126.753094 -266.272192)
			(xy 126.705823 -266.285884) (xy 126.656968 -266.291816) (xy 126.607793 -266.289835) (xy 126.559574 -266.279991)
			(xy 126.513558 -266.262539) (xy 126.470937 -266.237932) (xy 126.432816 -266.206807) (xy 126.400181 -266.16997)
			(xy 126.373878 -266.128374) (xy 126.354587 -266.083098) (xy 126.34281 -266.035314) (xy 126.33885 -265.98626)
			(xy 125.070108 -265.98626) (xy 125.069613 -266.010867) (xy 125.061718 -266.059444) (xy 125.046134 -266.106125)
			(xy 125.023263 -266.149702) (xy 124.993698 -266.189046) (xy 124.958205 -266.223138) (xy 124.917702 -266.251094)
			(xy 124.87324 -266.272192) (xy 124.825969 -266.285884) (xy 124.777114 -266.291816) (xy 124.727939 -266.289835)
			(xy 124.67972 -266.279991) (xy 124.633704 -266.262539) (xy 124.591083 -266.237932) (xy 124.552962 -266.206807)
			(xy 124.520327 -266.16997) (xy 124.494024 -266.128374) (xy 124.474733 -266.083098) (xy 124.462956 -266.035314)
			(xy 124.458996 -265.98626) (xy 123.189991 -265.98626) (xy 123.189563 -266.009241) (xy 123.182418 -266.055673)
			(xy 123.175776 -266.078208) (xy 123.17222 -266.089892) (xy 123.17603 -266.113514) (xy 123.230386 -266.187936)
			(xy 123.238009 -266.197276) (xy 123.259493 -266.208137) (xy 123.271534 -266.208764) (xy 123.31319 -266.208764)
			(xy 123.323027 -266.209303) (xy 123.341186 -266.216891) (xy 123.348496 -266.223496) (xy 124.146818 -267.021818)
			(xy 124.154214 -267.02867) (xy 124.172813 -267.036411) (xy 124.182886 -267.036804) (xy 124.854208 -267.036804)
			(xy 124.866537 -267.036217) (xy 124.888378 -267.024773) (xy 124.895864 -267.01496) (xy 124.949458 -266.937998)
			(xy 124.952506 -266.913868) (xy 124.948188 -266.90193) (xy 124.939406 -266.876402) (xy 124.929943 -266.823257)
			(xy 124.929392 -266.796266) (xy 124.929914 -266.771011) (xy 124.938227 -266.721189) (xy 124.954628 -266.673415)
			(xy 124.978669 -266.628992) (xy 125.009693 -266.589132) (xy 125.046855 -266.554922) (xy 125.089141 -266.527296)
			(xy 125.135397 -266.507006) (xy 125.184362 -266.494606) (xy 125.2347 -266.490435) (xy 125.285038 -266.494606)
			(xy 125.334003 -266.507006) (xy 125.380259 -266.527296) (xy 125.422545 -266.554922) (xy 125.459707 -266.589132)
			(xy 125.490731 -266.628992) (xy 125.514772 -266.673415) (xy 125.531173 -266.721189) (xy 125.539486 -266.771011)
			(xy 125.540008 -266.796266) (xy 125.539457 -266.823257) (xy 125.530006 -266.876405) (xy 125.521212 -266.90193)
			(xy 125.516894 -266.913868) (xy 125.519942 -266.937998) (xy 125.573536 -267.01496) (xy 125.581146 -267.024634)
			(xy 125.602907 -267.036053) (xy 125.615192 -267.036804) (xy 125.794262 -267.036804) (xy 125.806585 -267.036205)
			(xy 125.828405 -267.024748) (xy 125.835918 -267.01496) (xy 125.889512 -266.937998) (xy 125.89256 -266.913868)
			(xy 125.888242 -266.90193) (xy 125.879461 -266.876402) (xy 125.869999 -266.823256) (xy 125.869446 -266.796266)
			(xy 125.869968 -266.771011) (xy 125.878281 -266.721189) (xy 125.894682 -266.673415) (xy 125.918723 -266.628992)
			(xy 125.949747 -266.589132) (xy 125.986909 -266.554922) (xy 126.029195 -266.527296) (xy 126.075451 -266.507006)
			(xy 126.124416 -266.494606) (xy 126.174754 -266.490435) (xy 126.225092 -266.494606) (xy 126.274057 -266.507006)
			(xy 126.320313 -266.527296) (xy 126.362599 -266.554922) (xy 126.399761 -266.589132) (xy 126.430785 -266.628992)
			(xy 126.454826 -266.673415) (xy 126.471227 -266.721189) (xy 126.47954 -266.771011) (xy 126.480062 -266.796266)
			(xy 126.479613 -266.819999) (xy 126.472267 -266.866892) (xy 126.457746 -266.912082) (xy 126.436401 -266.954478)
			(xy 126.408748 -266.993055) (xy 126.375453 -267.026885) (xy 126.33732 -267.055149) (xy 126.316486 -267.066522)
			(xy 126.305818 -267.072364) (xy 126.291848 -267.091922) (xy 126.277624 -267.182854) (xy 126.276468 -267.194827)
			(xy 126.284025 -267.217628) (xy 126.292102 -267.226542) (xy 126.424182 -267.358622) (xy 126.46025 -267.362178)
			(xy 126.47549 -267.352272) (xy 126.494368 -267.340153) (xy 126.534927 -267.320987) (xy 126.577854 -267.307963)
			(xy 126.622225 -267.301362) (xy 126.644654 -267.300964) (xy 126.66865 -267.301407) (xy 126.716053 -267.308908)
			(xy 126.761699 -267.323732) (xy 126.804463 -267.345514) (xy 126.843293 -267.373718) (xy 126.877233 -267.40765)
			(xy 126.905447 -267.446474) (xy 126.92724 -267.489233) (xy 126.942075 -267.534875) (xy 126.949587 -267.582276)
			(xy 126.949962 -267.606272) (xy 126.949583 -267.627974) (xy 126.943439 -267.67094) (xy 126.931271 -267.712602)
			(xy 126.913325 -267.752121) (xy 126.901956 -267.77061) (xy 126.898146 -267.776452) (xy 126.894082 -267.790422)
			(xy 126.891793 -267.799336) (xy 126.892992 -267.817688) (xy 126.900546 -267.834456) (xy 126.906782 -267.841222)
			(xy 126.981458 -267.915898) (xy 126.98886 -267.922736) (xy 127.007458 -267.930449) (xy 127.017526 -267.930884)
		)
		(stroke
			(width 0)
			(type solid)
		)
		(fill yes)
		(layer "In2.Cu")
		(net "PVDD11_S3_P1")
	)
	(gr_poly
		(pts
			(xy 99.2251 -267.203174) (xy 99.234934 -267.202632) (xy 99.253085 -267.195035) (xy 99.260406 -267.188442)
			(xy 99.556824 -266.892024) (xy 99.56419 -266.868148) (xy 99.56165 -266.855448) (xy 99.558926 -266.840804)
			(xy 99.556 -266.81116) (xy 99.555808 -266.796266) (xy 99.556281 -266.772277) (xy 99.563792 -266.72489)
			(xy 99.578622 -266.679262) (xy 99.600408 -266.636515) (xy 99.628612 -266.597702) (xy 99.662541 -266.56378)
			(xy 99.701358 -266.535582) (xy 99.744108 -266.513803) (xy 99.789739 -266.49898) (xy 99.837127 -266.491477)
			(xy 99.861116 -266.490958) (xy 99.87601 -266.491148) (xy 99.905655 -266.494072) (xy 99.920298 -266.4968)
			(xy 99.932998 -266.49934) (xy 99.956874 -266.491974) (xy 100.109782 -266.339066) (xy 100.116496 -266.331734)
			(xy 100.124206 -266.313432) (xy 100.124768 -266.303506) (xy 100.12553 -266.224004) (xy 100.118164 -266.205462)
			(xy 100.111306 -266.19835) (xy 100.095332 -266.181169) (xy 100.06831 -266.142821) (xy 100.047465 -266.100794)
			(xy 100.033288 -266.056076) (xy 100.02611 -266.009716) (xy 100.025708 -265.98626) (xy 100.026182 -265.962271)
			(xy 100.033693 -265.914885) (xy 100.048524 -265.869258) (xy 100.07031 -265.826512) (xy 100.098514 -265.7877)
			(xy 100.132443 -265.753778) (xy 100.17126 -265.725581) (xy 100.21401 -265.703802) (xy 100.25964 -265.68898)
			(xy 100.307027 -265.681477) (xy 100.331016 -265.680952) (xy 100.343779 -265.68109) (xy 100.369213 -265.68325)
			(xy 100.381816 -265.68527) (xy 100.381816 -265.685016) (xy 100.40437 -265.689258) (xy 100.447959 -265.703609)
			(xy 100.488913 -265.724314) (xy 100.526313 -265.750909) (xy 100.543106 -265.76655) (xy 100.550472 -265.773408)
			(xy 100.56876 -265.780774) (xy 100.648262 -265.780012) (xy 100.658184 -265.779437) (xy 100.67648 -265.771725)
			(xy 100.683822 -265.765026) (xy 101.926644 -264.522204) (xy 101.93274 -264.49274) (xy 101.927152 -264.478516)
			(xy 101.917219 -264.451518) (xy 101.906486 -264.395008) (xy 101.905816 -264.366248) (xy 101.906259 -264.342253)
			(xy 101.91376 -264.294853) (xy 101.928584 -264.249211) (xy 101.950367 -264.20645) (xy 101.978573 -264.167623)
			(xy 102.012505 -264.133688) (xy 102.051329 -264.10548) (xy 102.094088 -264.083693) (xy 102.13973 -264.068865)
			(xy 102.187129 -264.061361) (xy 102.211124 -264.06094) (xy 102.239888 -264.061572) (xy 102.296403 -264.072309)
			(xy 102.323392 -264.082276) (xy 102.337616 -264.087864) (xy 102.36708 -264.081768) (xy 102.502208 -263.94664)
			(xy 102.509467 -263.938605) (xy 102.517078 -263.918353) (xy 102.51694 -263.907524) (xy 102.511606 -263.822688)
			(xy 102.501446 -263.803384) (xy 102.49281 -263.79678) (xy 102.474896 -263.782209) (xy 102.443246 -263.748587)
			(xy 102.417017 -263.710584) (xy 102.396806 -263.669067) (xy 102.383074 -263.624981) (xy 102.376133 -263.57933)
			(xy 102.375716 -263.556242) (xy 102.376159 -263.532247) (xy 102.383661 -263.484848) (xy 102.398486 -263.439206)
			(xy 102.420269 -263.396446) (xy 102.448475 -263.357621) (xy 102.482407 -263.323686) (xy 102.521231 -263.295479)
			(xy 102.56399 -263.273693) (xy 102.609631 -263.258865) (xy 102.657029 -263.25136) (xy 102.681024 -263.250934)
			(xy 102.704111 -263.251358) (xy 102.749759 -263.258306) (xy 102.793842 -263.272041) (xy 102.835358 -263.292251)
			(xy 102.873362 -263.318475) (xy 102.90699 -263.350116) (xy 102.921562 -263.368028) (xy 102.928166 -263.376664)
			(xy 102.94747 -263.386824) (xy 103.032306 -263.392158) (xy 103.043148 -263.392376) (xy 103.063426 -263.38475)
			(xy 103.071422 -263.377426) (xy 103.224076 -263.224772) (xy 103.23095 -263.21733) (xy 103.238679 -263.19862)
			(xy 103.238558 -263.178378) (xy 103.234998 -263.168892) (xy 103.199438 -263.084564) (xy 103.195093 -263.075576)
			(xy 103.180886 -263.06158) (xy 103.162421 -263.054044) (xy 103.152448 -263.053576) (xy 103.147876 -263.053576)
			(xy 103.123059 -263.053088) (xy 103.074079 -263.045055) (xy 103.027043 -263.029203) (xy 102.983192 -263.005951)
			(xy 102.94368 -262.975912) (xy 102.909548 -262.939876) (xy 102.881695 -262.898793) (xy 102.860856 -262.853745)
			(xy 102.847578 -262.805919) (xy 102.842213 -262.756575) (xy 102.844901 -262.707013) (xy 102.855571 -262.658539)
			(xy 102.873943 -262.61243) (xy 102.899532 -262.5699) (xy 102.931665 -262.53207) (xy 102.969494 -262.499937)
			(xy 103.012023 -262.474347) (xy 103.058132 -262.455974) (xy 103.106605 -262.445302) (xy 103.156167 -262.442613)
			(xy 103.205511 -262.447977) (xy 103.253337 -262.461253) (xy 103.298386 -262.482091) (xy 103.339469 -262.509943)
			(xy 103.375506 -262.544074) (xy 103.405547 -262.583585) (xy 103.4288 -262.627436) (xy 103.444653 -262.674471)
			(xy 103.452688 -262.723451) (xy 103.453184 -262.748268) (xy 103.453184 -262.75284) (xy 103.453617 -262.76282)
			(xy 103.461149 -262.781299) (xy 103.475171 -262.795497) (xy 103.484172 -262.79983) (xy 103.5685 -262.83539)
			(xy 103.577984 -262.838923) (xy 103.598207 -262.839005) (xy 103.6169 -262.831289) (xy 103.62438 -262.824468)
			(xy 103.798624 -262.650224) (xy 103.802434 -262.640064) (xy 103.812106 -262.616084) (xy 103.838317 -262.571518)
			(xy 103.871661 -262.532004) (xy 103.911184 -262.498671) (xy 103.955756 -262.472472) (xy 103.979726 -262.462772)
			(xy 103.989886 -262.458962) (xy 104.619552 -261.829296) (xy 104.626792 -261.822588) (xy 104.644997 -261.815008)
			(xy 104.654858 -261.814564) (xy 105.62971 -261.814564) (xy 105.639554 -261.814041) (xy 105.657736 -261.806476)
			(xy 105.665016 -261.799832) (xy 105.813352 -261.651496) (xy 105.820592 -261.644788) (xy 105.838797 -261.637208)
			(xy 105.848658 -261.636764) (xy 106.084116 -261.636764) (xy 106.094021 -261.636298) (xy 106.112362 -261.628808)
			(xy 106.126514 -261.614946) (xy 106.130852 -261.60603) (xy 106.172508 -261.50824) (xy 106.167174 -261.478522)
			(xy 106.156506 -261.467346) (xy 106.138824 -261.44806) (xy 106.108912 -261.405132) (xy 106.085857 -261.358165)
			(xy 106.070191 -261.308244) (xy 106.062277 -261.256525) (xy 106.061764 -261.230364) (xy 106.062244 -261.204665)
			(xy 106.069905 -261.153841) (xy 106.085054 -261.104727) (xy 106.107355 -261.058419) (xy 106.136308 -261.015952)
			(xy 106.171268 -260.978275) (xy 106.211452 -260.946229) (xy 106.255964 -260.92053) (xy 106.303809 -260.901753)
			(xy 106.353918 -260.890315) (xy 106.405172 -260.886475) (xy 106.456426 -260.890315) (xy 106.506535 -260.901753)
			(xy 106.55438 -260.92053) (xy 106.598892 -260.946229) (xy 106.639076 -260.978275) (xy 106.674036 -261.015952)
			(xy 106.702989 -261.058419) (xy 106.72529 -261.104727) (xy 106.740439 -261.153841) (xy 106.7481 -261.204665)
			(xy 106.74858 -261.230364) (xy 106.748086 -261.256524) (xy 106.740151 -261.308239) (xy 106.724473 -261.358155)
			(xy 106.701415 -261.40512) (xy 106.671509 -261.44805) (xy 106.653838 -261.467346) (xy 106.64317 -261.478522)
			(xy 106.637836 -261.50824) (xy 106.679492 -261.60603) (xy 106.683823 -261.614958) (xy 106.697959 -261.628857)
			(xy 106.716315 -261.636343) (xy 106.726228 -261.636764) (xy 107.258866 -261.636764) (xy 107.267659 -261.6364)
			(xy 107.28421 -261.630456) (xy 107.297769 -261.619257) (xy 107.302554 -261.611872) (xy 107.352846 -261.526782)
			(xy 107.353354 -261.500112) (xy 107.34675 -261.488174) (xy 107.333487 -261.462698) (xy 107.314696 -261.408427)
			(xy 107.305171 -261.35179) (xy 107.304586 -261.323074) (xy 107.305066 -261.297375) (xy 107.312727 -261.246551)
			(xy 107.327876 -261.197437) (xy 107.350177 -261.151129) (xy 107.37913 -261.108662) (xy 107.41409 -261.070985)
			(xy 107.454274 -261.038939) (xy 107.498786 -261.01324) (xy 107.546631 -260.994463) (xy 107.59674 -260.983025)
			(xy 107.647994 -260.979185) (xy 107.699248 -260.983025) (xy 107.749357 -260.994463) (xy 107.797202 -261.01324)
			(xy 107.841714 -261.038939) (xy 107.881898 -261.070985) (xy 107.916858 -261.108662) (xy 107.945811 -261.151129)
			(xy 107.968112 -261.197437) (xy 107.983261 -261.246551) (xy 107.990922 -261.297375) (xy 107.991402 -261.323074)
			(xy 107.990949 -261.348156) (xy 107.983665 -261.39779) (xy 107.969246 -261.445838) (xy 107.948 -261.491281)
			(xy 107.920377 -261.533156) (xy 107.904026 -261.552182) (xy 107.897676 -261.559294) (xy 107.891072 -261.576566)
			(xy 107.891072 -261.585964) (xy 107.891485 -261.595992) (xy 107.899147 -261.614526) (xy 107.91332 -261.628717)
			(xy 107.931844 -261.636403) (xy 107.941872 -261.636764) (xy 107.943904 -261.636764) (xy 107.953973 -261.636339)
			(xy 107.972573 -261.62862) (xy 107.979972 -261.621778) (xy 108.23956 -261.36219) (xy 108.246445 -261.35474)
			(xy 108.254184 -261.336005) (xy 108.254546 -261.325868) (xy 108.254546 -261.323074) (xy 108.255132 -261.294198)
			(xy 108.264776 -261.237257) (xy 108.283806 -261.18273) (xy 108.311684 -261.132153) (xy 108.329222 -261.109206)
			(xy 108.334302 -261.102856) (xy 108.342938 -261.079234) (xy 108.344346 -261.075055) (xy 108.345876 -261.066371)
			(xy 108.345986 -261.061962) (xy 108.345986 -258.044188) (xy 108.34551 -258.033955) (xy 108.337519 -258.015111)
			(xy 108.322837 -258.000849) (xy 108.313474 -257.99669) (xy 108.212636 -257.957828) (xy 108.182156 -257.96494)
			(xy 108.171488 -257.976624) (xy 108.151817 -257.997354) (xy 108.106857 -258.032623) (xy 108.056679 -258.059965)
			(xy 108.002668 -258.078626) (xy 107.946314 -258.08809) (xy 107.917742 -258.088638) (xy 107.892037 -258.088185)
			(xy 107.841201 -258.080528) (xy 107.792073 -258.06538) (xy 107.745753 -258.043078) (xy 107.703274 -258.014121)
			(xy 107.665585 -257.979156) (xy 107.63353 -257.938964) (xy 107.607823 -257.894442) (xy 107.589039 -257.846587)
			(xy 107.577599 -257.796466) (xy 107.573756 -257.7452) (xy 107.577599 -257.693934) (xy 107.589039 -257.643813)
			(xy 107.607823 -257.595958) (xy 107.63353 -257.551436) (xy 107.665585 -257.511244) (xy 107.703274 -257.476279)
			(xy 107.745753 -257.447322) (xy 107.792073 -257.42502) (xy 107.841201 -257.409872) (xy 107.892037 -257.402215)
			(xy 107.917742 -257.401822) (xy 107.945181 -257.402362) (xy 107.999362 -257.411089) (xy 108.051467 -257.428316)
			(xy 108.100172 -257.453604) (xy 108.14424 -257.486311) (xy 108.18255 -257.525606) (xy 108.214129 -257.570488)
			(xy 108.238174 -257.619819) (xy 108.246672 -257.645916) (xy 108.251498 -257.661918) (xy 108.278422 -257.681984)
			(xy 108.295186 -257.681984) (xy 108.305208 -257.681567) (xy 108.323727 -257.673899) (xy 108.3379 -257.659725)
			(xy 108.345567 -257.641206) (xy 108.345986 -257.631184) (xy 108.345986 -257.54457) (xy 108.345557 -257.534503)
			(xy 108.337833 -257.515907) (xy 108.331 -257.508502) (xy 108.005372 -257.182874) (xy 107.997976 -257.176024)
			(xy 107.979377 -257.168288) (xy 107.969304 -257.167888) (xy 106.818176 -257.167888) (xy 106.805761 -257.168511)
			(xy 106.783798 -257.180096) (xy 106.776266 -257.189986) (xy 106.72318 -257.268218) (xy 106.720386 -257.29311)
			(xy 106.724958 -257.305048) (xy 106.735974 -257.335174) (xy 106.747855 -257.398201) (xy 106.74858 -257.43027)
			(xy 106.7481 -257.455969) (xy 106.740439 -257.506793) (xy 106.72529 -257.555907) (xy 106.702989 -257.602215)
			(xy 106.674036 -257.644682) (xy 106.639076 -257.682359) (xy 106.598892 -257.714405) (xy 106.55438 -257.740104)
			(xy 106.506535 -257.758881) (xy 106.456426 -257.770319) (xy 106.405172 -257.77416) (xy 106.353918 -257.770319)
			(xy 106.303809 -257.758881) (xy 106.255964 -257.740104) (xy 106.211452 -257.714405) (xy 106.171268 -257.682359)
			(xy 106.136308 -257.644682) (xy 106.107355 -257.602215) (xy 106.085054 -257.555907) (xy 106.069905 -257.506793)
			(xy 106.062244 -257.455969) (xy 106.061764 -257.43027) (xy 106.062481 -257.398201) (xy 106.074375 -257.335176)
			(xy 106.085386 -257.305048) (xy 106.089958 -257.29311) (xy 106.087164 -257.268218) (xy 106.034078 -257.189986)
			(xy 106.026549 -257.180098) (xy 106.004581 -257.168533) (xy 105.992168 -257.167888) (xy 105.850182 -257.167888)
			(xy 105.84043 -257.167379) (xy 105.822394 -257.159937) (xy 105.81513 -257.15341) (xy 105.792524 -257.13055)
			(xy 105.785124 -257.12371) (xy 105.766525 -257.115995) (xy 105.756456 -257.115564) (xy 100.971858 -257.115564)
			(xy 100.962017 -257.115035) (xy 100.943842 -257.107462) (xy 100.936552 -257.100832) (xy 100.20427 -256.36855)
			(xy 100.196872 -256.361703) (xy 100.178274 -256.353972) (xy 100.168202 -256.353564) (xy 99.454208 -256.353564)
			(xy 99.445572 -256.353908) (xy 99.42929 -256.359667) (xy 99.415861 -256.370528) (xy 99.411028 -256.377694)
			(xy 99.35972 -256.460498) (xy 99.35845 -256.48666) (xy 99.364292 -256.498598) (xy 99.374371 -256.519818)
			(xy 99.388616 -256.564583) (xy 99.395839 -256.611) (xy 99.396296 -256.634488) (xy 99.395851 -256.658481)
			(xy 99.388345 -256.705878) (xy 99.373518 -256.751516) (xy 99.351733 -256.794273) (xy 99.323527 -256.833095)
			(xy 99.289595 -256.867027) (xy 99.250773 -256.895233) (xy 99.208016 -256.917018) (xy 99.162378 -256.931845)
			(xy 99.114981 -256.939351) (xy 99.090988 -256.939796) (xy 99.06675 -256.93933) (xy 99.018883 -256.93167)
			(xy 98.972827 -256.916545) (xy 98.929739 -256.894334) (xy 98.890701 -256.865595) (xy 98.856693 -256.831049)
			(xy 98.82857 -256.791565) (xy 98.807037 -256.748135) (xy 98.792635 -256.701847) (xy 98.788728 -256.677922)
			(xy 98.78695 -256.665222) (xy 98.785426 -256.634488) (xy 98.78586 -256.610958) (xy 98.793077 -256.564453)
			(xy 98.807339 -256.519605) (xy 98.81743 -256.498344) (xy 98.823272 -256.486406) (xy 98.822256 -256.460244)
			(xy 98.770948 -256.377694) (xy 98.766118 -256.370527) (xy 98.752679 -256.359679) (xy 98.736403 -256.3539)
			(xy 98.727768 -256.353564) (xy 97.574354 -256.353564) (xy 97.565714 -256.353901) (xy 97.54942 -256.35965)
			(xy 97.535979 -256.370507) (xy 97.531174 -256.377694) (xy 97.479866 -256.460498) (xy 97.478596 -256.48666)
			(xy 97.484438 -256.498598) (xy 97.494516 -256.519818) (xy 97.508758 -256.564583) (xy 97.51598 -256.611)
			(xy 97.516442 -256.634488) (xy 97.515972 -256.658481) (xy 97.508468 -256.705876) (xy 97.493642 -256.751514)
			(xy 97.47186 -256.794271) (xy 97.443657 -256.833094) (xy 97.409729 -256.867027) (xy 97.37091 -256.895236)
			(xy 97.328156 -256.917024) (xy 97.282521 -256.931857) (xy 97.235127 -256.939369) (xy 97.211134 -256.939796)
			(xy 97.186899 -256.939326) (xy 97.139038 -256.931659) (xy 97.092989 -256.916529) (xy 97.049909 -256.894315)
			(xy 97.010878 -256.865574) (xy 96.976877 -256.83103) (xy 96.948759 -256.791548) (xy 96.927231 -256.74812)
			(xy 96.912833 -256.701837) (xy 96.908874 -256.677922) (xy 96.907096 -256.665222) (xy 96.905572 -256.634488)
			(xy 96.906006 -256.610957) (xy 96.913222 -256.564453) (xy 96.927481 -256.519604) (xy 96.937576 -256.498344)
			(xy 96.943418 -256.486406) (xy 96.942402 -256.460244) (xy 96.891094 -256.377694) (xy 96.886262 -256.370533)
			(xy 96.87282 -256.359699) (xy 96.856545 -256.353937) (xy 96.847914 -256.353564) (xy 96.272858 -256.353564)
			(xy 96.263018 -256.354094) (xy 96.244846 -256.36167) (xy 96.237552 -256.368296) (xy 95.349314 -257.256534)
			(xy 95.341914 -257.263374) (xy 95.323315 -257.271087) (xy 95.313246 -257.27152) (xy 80.625442 -257.27152)
			(xy 80.615377 -257.271954) (xy 80.59679 -257.279686) (xy 80.589374 -257.286506) (xy 80.187546 -257.688334)
			(xy 80.1807 -257.695732) (xy 80.172971 -257.714331) (xy 80.17256 -257.724402) (xy 80.17256 -257.930396)
			(xy 98.711261 -257.930396) (xy 98.715291 -257.877898) (xy 98.727288 -257.82663) (xy 98.746971 -257.777795)
			(xy 98.773877 -257.732536) (xy 98.807377 -257.691915) (xy 98.846685 -257.656884) (xy 98.89088 -257.628264)
			(xy 98.938925 -257.606725) (xy 98.989696 -257.592773) (xy 99.042001 -257.586735) (xy 99.094615 -257.588752)
			(xy 99.146305 -257.598776) (xy 99.195858 -257.616574) (xy 99.242114 -257.641727) (xy 99.283988 -257.673646)
			(xy 99.3205 -257.711584) (xy 99.350792 -257.75465) (xy 99.374155 -257.801835) (xy 99.390041 -257.852034)
			(xy 99.398078 -257.90407) (xy 99.398582 -257.930396) (xy 100.611181 -257.930396) (xy 100.615211 -257.877898)
			(xy 100.627208 -257.82663) (xy 100.646891 -257.777795) (xy 100.673797 -257.732536) (xy 100.707297 -257.691915)
			(xy 100.746605 -257.656884) (xy 100.7908 -257.628264) (xy 100.838845 -257.606725) (xy 100.889616 -257.592773)
			(xy 100.941921 -257.586735) (xy 100.994535 -257.588752) (xy 101.046225 -257.598776) (xy 101.095778 -257.616574)
			(xy 101.142034 -257.641727) (xy 101.183908 -257.673646) (xy 101.22042 -257.711584) (xy 101.250712 -257.75465)
			(xy 101.274075 -257.801835) (xy 101.289961 -257.852034) (xy 101.297998 -257.90407) (xy 101.298502 -257.930396)
			(xy 102.511101 -257.930396) (xy 102.515131 -257.877898) (xy 102.527128 -257.82663) (xy 102.546811 -257.777795)
			(xy 102.573717 -257.732536) (xy 102.607217 -257.691915) (xy 102.646525 -257.656884) (xy 102.69072 -257.628264)
			(xy 102.738765 -257.606725) (xy 102.789536 -257.592773) (xy 102.841841 -257.586735) (xy 102.894455 -257.588752)
			(xy 102.946145 -257.598776) (xy 102.995698 -257.616574) (xy 103.041954 -257.641727) (xy 103.083828 -257.673646)
			(xy 103.12034 -257.711584) (xy 103.150632 -257.75465) (xy 103.173995 -257.801835) (xy 103.189881 -257.852034)
			(xy 103.197918 -257.90407) (xy 103.198422 -257.930396) (xy 103.197918 -257.956722) (xy 103.189881 -258.008758)
			(xy 103.173995 -258.058957) (xy 103.150632 -258.106142) (xy 103.12034 -258.149208) (xy 103.083828 -258.187146)
			(xy 103.041954 -258.219065) (xy 102.995698 -258.244218) (xy 102.946145 -258.262016) (xy 102.894455 -258.27204)
			(xy 102.841841 -258.274057) (xy 102.789536 -258.268019) (xy 102.738765 -258.254067) (xy 102.69072 -258.232528)
			(xy 102.646525 -258.203908) (xy 102.607217 -258.168877) (xy 102.573717 -258.128256) (xy 102.546811 -258.082997)
			(xy 102.527128 -258.034162) (xy 102.515131 -257.982894) (xy 102.511101 -257.930396) (xy 101.298502 -257.930396)
			(xy 101.297998 -257.956722) (xy 101.289961 -258.008758) (xy 101.274075 -258.058957) (xy 101.250712 -258.106142)
			(xy 101.22042 -258.149208) (xy 101.183908 -258.187146) (xy 101.142034 -258.219065) (xy 101.095778 -258.244218)
			(xy 101.046225 -258.262016) (xy 100.994535 -258.27204) (xy 100.941921 -258.274057) (xy 100.889616 -258.268019)
			(xy 100.838845 -258.254067) (xy 100.7908 -258.232528) (xy 100.746605 -258.203908) (xy 100.707297 -258.168877)
			(xy 100.673797 -258.128256) (xy 100.646891 -258.082997) (xy 100.627208 -258.034162) (xy 100.615211 -257.982894)
			(xy 100.611181 -257.930396) (xy 99.398582 -257.930396) (xy 99.398078 -257.956722) (xy 99.390041 -258.008758)
			(xy 99.374155 -258.058957) (xy 99.350792 -258.106142) (xy 99.3205 -258.149208) (xy 99.283988 -258.187146)
			(xy 99.242114 -258.219065) (xy 99.195858 -258.244218) (xy 99.146305 -258.262016) (xy 99.094615 -258.27204)
			(xy 99.042001 -258.274057) (xy 98.989696 -258.268019) (xy 98.938925 -258.254067) (xy 98.89088 -258.232528)
			(xy 98.846685 -258.203908) (xy 98.807377 -258.168877) (xy 98.773877 -258.128256) (xy 98.746971 -258.082997)
			(xy 98.727288 -258.034162) (xy 98.715291 -257.982894) (xy 98.711261 -257.930396) (xy 80.17256 -257.930396)
			(xy 80.17256 -258.38023) (xy 106.061259 -258.38023) (xy 106.065289 -258.327732) (xy 106.077286 -258.276464)
			(xy 106.096969 -258.227629) (xy 106.123875 -258.18237) (xy 106.157375 -258.141749) (xy 106.196683 -258.106718)
			(xy 106.240878 -258.078098) (xy 106.288923 -258.056559) (xy 106.339694 -258.042607) (xy 106.391999 -258.036569)
			(xy 106.444613 -258.038586) (xy 106.496303 -258.04861) (xy 106.545856 -258.066408) (xy 106.592112 -258.091561)
			(xy 106.633986 -258.12348) (xy 106.670498 -258.161418) (xy 106.70079 -258.204484) (xy 106.724153 -258.251669)
			(xy 106.740039 -258.301868) (xy 106.748076 -258.353904) (xy 106.74858 -258.38023) (xy 106.748076 -258.406556)
			(xy 106.740039 -258.458592) (xy 106.724153 -258.508791) (xy 106.70079 -258.555976) (xy 106.670498 -258.599042)
			(xy 106.633986 -258.63698) (xy 106.592112 -258.668899) (xy 106.545856 -258.694052) (xy 106.496303 -258.71185)
			(xy 106.444613 -258.721874) (xy 106.391999 -258.723891) (xy 106.339694 -258.717853) (xy 106.288923 -258.703901)
			(xy 106.240878 -258.682362) (xy 106.196683 -258.653742) (xy 106.157375 -258.618711) (xy 106.123875 -258.57809)
			(xy 106.096969 -258.532831) (xy 106.077286 -258.483996) (xy 106.065289 -258.432728) (xy 106.061259 -258.38023)
			(xy 80.17256 -258.38023) (xy 80.17256 -258.830318) (xy 98.711261 -258.830318) (xy 98.715291 -258.77782)
			(xy 98.727288 -258.726552) (xy 98.746971 -258.677717) (xy 98.773877 -258.632458) (xy 98.807377 -258.591837)
			(xy 98.846685 -258.556806) (xy 98.89088 -258.528186) (xy 98.938925 -258.506647) (xy 98.989696 -258.492695)
			(xy 99.042001 -258.486657) (xy 99.094615 -258.488674) (xy 99.146305 -258.498698) (xy 99.195858 -258.516496)
			(xy 99.242114 -258.541649) (xy 99.283988 -258.573568) (xy 99.3205 -258.611506) (xy 99.350792 -258.654572)
			(xy 99.374155 -258.701757) (xy 99.390041 -258.751956) (xy 99.398078 -258.803992) (xy 99.398582 -258.830318)
			(xy 100.611181 -258.830318) (xy 100.615211 -258.77782) (xy 100.627208 -258.726552) (xy 100.646891 -258.677717)
			(xy 100.673797 -258.632458) (xy 100.707297 -258.591837) (xy 100.746605 -258.556806) (xy 100.7908 -258.528186)
			(xy 100.838845 -258.506647) (xy 100.889616 -258.492695) (xy 100.941921 -258.486657) (xy 100.994535 -258.488674)
			(xy 101.046225 -258.498698) (xy 101.095778 -258.516496) (xy 101.142034 -258.541649) (xy 101.183908 -258.573568)
			(xy 101.22042 -258.611506) (xy 101.250712 -258.654572) (xy 101.274075 -258.701757) (xy 101.289961 -258.751956)
			(xy 101.297998 -258.803992) (xy 101.298502 -258.830318) (xy 102.511101 -258.830318) (xy 102.515131 -258.77782)
			(xy 102.527128 -258.726552) (xy 102.546811 -258.677717) (xy 102.573717 -258.632458) (xy 102.607217 -258.591837)
			(xy 102.646525 -258.556806) (xy 102.69072 -258.528186) (xy 102.738765 -258.506647) (xy 102.789536 -258.492695)
			(xy 102.841841 -258.486657) (xy 102.894455 -258.488674) (xy 102.946145 -258.498698) (xy 102.995698 -258.516496)
			(xy 103.041954 -258.541649) (xy 103.083828 -258.573568) (xy 103.12034 -258.611506) (xy 103.150632 -258.654572)
			(xy 103.173995 -258.701757) (xy 103.189881 -258.751956) (xy 103.197918 -258.803992) (xy 103.198422 -258.830318)
			(xy 103.197918 -258.856644) (xy 103.189881 -258.90868) (xy 103.173995 -258.958879) (xy 103.150632 -259.006064)
			(xy 103.12034 -259.04913) (xy 103.083828 -259.087068) (xy 103.041954 -259.118987) (xy 102.995698 -259.14414)
			(xy 102.946145 -259.161938) (xy 102.894455 -259.171962) (xy 102.841841 -259.173979) (xy 102.789536 -259.167941)
			(xy 102.738765 -259.153989) (xy 102.69072 -259.13245) (xy 102.646525 -259.10383) (xy 102.607217 -259.068799)
			(xy 102.573717 -259.028178) (xy 102.546811 -258.982919) (xy 102.527128 -258.934084) (xy 102.515131 -258.882816)
			(xy 102.511101 -258.830318) (xy 101.298502 -258.830318) (xy 101.297998 -258.856644) (xy 101.289961 -258.90868)
			(xy 101.274075 -258.958879) (xy 101.250712 -259.006064) (xy 101.22042 -259.04913) (xy 101.183908 -259.087068)
			(xy 101.142034 -259.118987) (xy 101.095778 -259.14414) (xy 101.046225 -259.161938) (xy 100.994535 -259.171962)
			(xy 100.941921 -259.173979) (xy 100.889616 -259.167941) (xy 100.838845 -259.153989) (xy 100.7908 -259.13245)
			(xy 100.746605 -259.10383) (xy 100.707297 -259.068799) (xy 100.673797 -259.028178) (xy 100.646891 -258.982919)
			(xy 100.627208 -258.934084) (xy 100.615211 -258.882816) (xy 100.611181 -258.830318) (xy 99.398582 -258.830318)
			(xy 99.398078 -258.856644) (xy 99.390041 -258.90868) (xy 99.374155 -258.958879) (xy 99.350792 -259.006064)
			(xy 99.3205 -259.04913) (xy 99.283988 -259.087068) (xy 99.242114 -259.118987) (xy 99.195858 -259.14414)
			(xy 99.146305 -259.161938) (xy 99.094615 -259.171962) (xy 99.042001 -259.173979) (xy 98.989696 -259.167941)
			(xy 98.938925 -259.153989) (xy 98.89088 -259.13245) (xy 98.846685 -259.10383) (xy 98.807377 -259.068799)
			(xy 98.773877 -259.028178) (xy 98.746971 -258.982919) (xy 98.727288 -258.934084) (xy 98.715291 -258.882816)
			(xy 98.711261 -258.830318) (xy 80.17256 -258.830318) (xy 80.17256 -259.330444) (xy 106.061259 -259.330444)
			(xy 106.065289 -259.277946) (xy 106.077286 -259.226678) (xy 106.096969 -259.177843) (xy 106.123875 -259.132584)
			(xy 106.157375 -259.091963) (xy 106.196683 -259.056932) (xy 106.240878 -259.028312) (xy 106.288923 -259.006773)
			(xy 106.339694 -258.992821) (xy 106.391999 -258.986783) (xy 106.444613 -258.9888) (xy 106.496303 -258.998824)
			(xy 106.545856 -259.016622) (xy 106.592112 -259.041775) (xy 106.633986 -259.073694) (xy 106.670498 -259.111632)
			(xy 106.70079 -259.154698) (xy 106.724153 -259.201883) (xy 106.740039 -259.252082) (xy 106.748076 -259.304118)
			(xy 106.74858 -259.330444) (xy 106.748076 -259.35677) (xy 106.740039 -259.408806) (xy 106.724153 -259.459005)
			(xy 106.70079 -259.50619) (xy 106.670498 -259.549256) (xy 106.633986 -259.587194) (xy 106.592112 -259.619113)
			(xy 106.545856 -259.644266) (xy 106.496303 -259.662064) (xy 106.444613 -259.672088) (xy 106.391999 -259.674105)
			(xy 106.339694 -259.668067) (xy 106.288923 -259.654115) (xy 106.240878 -259.632576) (xy 106.196683 -259.603956)
			(xy 106.157375 -259.568925) (xy 106.123875 -259.528304) (xy 106.096969 -259.483045) (xy 106.077286 -259.43421)
			(xy 106.065289 -259.382942) (xy 106.061259 -259.330444) (xy 80.17256 -259.330444) (xy 80.17256 -259.73024)
			(xy 98.711261 -259.73024) (xy 98.715291 -259.677742) (xy 98.727288 -259.626474) (xy 98.746971 -259.577639)
			(xy 98.773877 -259.53238) (xy 98.807377 -259.491759) (xy 98.846685 -259.456728) (xy 98.89088 -259.428108)
			(xy 98.938925 -259.406569) (xy 98.989696 -259.392617) (xy 99.042001 -259.386579) (xy 99.094615 -259.388596)
			(xy 99.146305 -259.39862) (xy 99.195858 -259.416418) (xy 99.242114 -259.441571) (xy 99.283988 -259.47349)
			(xy 99.3205 -259.511428) (xy 99.350792 -259.554494) (xy 99.374155 -259.601679) (xy 99.390041 -259.651878)
			(xy 99.398078 -259.703914) (xy 99.398582 -259.73024) (xy 100.611181 -259.73024) (xy 100.615211 -259.677742)
			(xy 100.627208 -259.626474) (xy 100.646891 -259.577639) (xy 100.673797 -259.53238) (xy 100.707297 -259.491759)
			(xy 100.746605 -259.456728) (xy 100.7908 -259.428108) (xy 100.838845 -259.406569) (xy 100.889616 -259.392617)
			(xy 100.941921 -259.386579) (xy 100.994535 -259.388596) (xy 101.046225 -259.39862) (xy 101.095778 -259.416418)
			(xy 101.142034 -259.441571) (xy 101.183908 -259.47349) (xy 101.22042 -259.511428) (xy 101.250712 -259.554494)
			(xy 101.274075 -259.601679) (xy 101.289961 -259.651878) (xy 101.297998 -259.703914) (xy 101.298502 -259.73024)
			(xy 102.511101 -259.73024) (xy 102.515131 -259.677742) (xy 102.527128 -259.626474) (xy 102.546811 -259.577639)
			(xy 102.573717 -259.53238) (xy 102.607217 -259.491759) (xy 102.646525 -259.456728) (xy 102.69072 -259.428108)
			(xy 102.738765 -259.406569) (xy 102.789536 -259.392617) (xy 102.841841 -259.386579) (xy 102.894455 -259.388596)
			(xy 102.946145 -259.39862) (xy 102.995698 -259.416418) (xy 103.041954 -259.441571) (xy 103.083828 -259.47349)
			(xy 103.12034 -259.511428) (xy 103.150632 -259.554494) (xy 103.173995 -259.601679) (xy 103.189881 -259.651878)
			(xy 103.197918 -259.703914) (xy 103.198422 -259.73024) (xy 103.197918 -259.756566) (xy 103.189881 -259.808602)
			(xy 103.173995 -259.858801) (xy 103.150632 -259.905986) (xy 103.12034 -259.949052) (xy 103.083828 -259.98699)
			(xy 103.041954 -260.018909) (xy 102.995698 -260.044062) (xy 102.946145 -260.06186) (xy 102.894455 -260.071884)
			(xy 102.841841 -260.073901) (xy 102.789536 -260.067863) (xy 102.738765 -260.053911) (xy 102.69072 -260.032372)
			(xy 102.646525 -260.003752) (xy 102.607217 -259.968721) (xy 102.573717 -259.9281) (xy 102.546811 -259.882841)
			(xy 102.527128 -259.834006) (xy 102.515131 -259.782738) (xy 102.511101 -259.73024) (xy 101.298502 -259.73024)
			(xy 101.297998 -259.756566) (xy 101.289961 -259.808602) (xy 101.274075 -259.858801) (xy 101.250712 -259.905986)
			(xy 101.22042 -259.949052) (xy 101.183908 -259.98699) (xy 101.142034 -260.018909) (xy 101.095778 -260.044062)
			(xy 101.046225 -260.06186) (xy 100.994535 -260.071884) (xy 100.941921 -260.073901) (xy 100.889616 -260.067863)
			(xy 100.838845 -260.053911) (xy 100.7908 -260.032372) (xy 100.746605 -260.003752) (xy 100.707297 -259.968721)
			(xy 100.673797 -259.9281) (xy 100.646891 -259.882841) (xy 100.627208 -259.834006) (xy 100.615211 -259.782738)
			(xy 100.611181 -259.73024) (xy 99.398582 -259.73024) (xy 99.398078 -259.756566) (xy 99.390041 -259.808602)
			(xy 99.374155 -259.858801) (xy 99.350792 -259.905986) (xy 99.3205 -259.949052) (xy 99.283988 -259.98699)
			(xy 99.242114 -260.018909) (xy 99.195858 -260.044062) (xy 99.146305 -260.06186) (xy 99.094615 -260.071884)
			(xy 99.042001 -260.073901) (xy 98.989696 -260.067863) (xy 98.938925 -260.053911) (xy 98.89088 -260.032372)
			(xy 98.846685 -260.003752) (xy 98.807377 -259.968721) (xy 98.773877 -259.9281) (xy 98.746971 -259.882841)
			(xy 98.727288 -259.834006) (xy 98.715291 -259.782738) (xy 98.711261 -259.73024) (xy 80.17256 -259.73024)
			(xy 80.17256 -260.280404) (xy 106.061259 -260.280404) (xy 106.065289 -260.227906) (xy 106.077286 -260.176638)
			(xy 106.096969 -260.127803) (xy 106.123875 -260.082544) (xy 106.157375 -260.041923) (xy 106.196683 -260.006892)
			(xy 106.240878 -259.978272) (xy 106.288923 -259.956733) (xy 106.339694 -259.942781) (xy 106.391999 -259.936743)
			(xy 106.444613 -259.93876) (xy 106.496303 -259.948784) (xy 106.545856 -259.966582) (xy 106.592112 -259.991735)
			(xy 106.633986 -260.023654) (xy 106.670498 -260.061592) (xy 106.70079 -260.104658) (xy 106.724153 -260.151843)
			(xy 106.740039 -260.202042) (xy 106.748076 -260.254078) (xy 106.74858 -260.280404) (xy 106.748076 -260.30673)
			(xy 106.740039 -260.358766) (xy 106.724153 -260.408965) (xy 106.70079 -260.45615) (xy 106.670498 -260.499216)
			(xy 106.633986 -260.537154) (xy 106.592112 -260.569073) (xy 106.545856 -260.594226) (xy 106.496303 -260.612024)
			(xy 106.444613 -260.622048) (xy 106.391999 -260.624065) (xy 106.339694 -260.618027) (xy 106.288923 -260.604075)
			(xy 106.240878 -260.582536) (xy 106.196683 -260.553916) (xy 106.157375 -260.518885) (xy 106.123875 -260.478264)
			(xy 106.096969 -260.433005) (xy 106.077286 -260.38417) (xy 106.065289 -260.332902) (xy 106.061259 -260.280404)
			(xy 80.17256 -260.280404) (xy 80.17256 -261.019798) (xy 80.172984 -261.029867) (xy 80.180705 -261.048466)
			(xy 80.187546 -261.055866) (xy 80.416654 -261.284974) (xy 80.424054 -261.291815) (xy 80.442653 -261.299533)
			(xy 80.452722 -261.29996) (xy 81.130394 -261.29996) (xy 81.141591 -261.299373) (xy 81.161877 -261.289885)
			(xy 81.16951 -261.281672) (xy 81.22666 -261.213346) (xy 81.232502 -261.191502) (xy 81.23047 -261.180326)
			(xy 81.228206 -261.166915) (xy 81.225788 -261.139824) (xy 81.225644 -261.126224) (xy 81.226166 -261.100969)
			(xy 81.234479 -261.051147) (xy 81.25088 -261.003373) (xy 81.274921 -260.95895) (xy 81.305945 -260.91909)
			(xy 81.343107 -260.88488) (xy 81.385393 -260.857254) (xy 81.431649 -260.836964) (xy 81.480614 -260.824564)
			(xy 81.530952 -260.820393) (xy 81.58129 -260.824564) (xy 81.630255 -260.836964) (xy 81.676511 -260.857254)
			(xy 81.718797 -260.88488) (xy 81.755959 -260.91909) (xy 81.786983 -260.95895) (xy 81.811024 -261.003373)
			(xy 81.827425 -261.051147) (xy 81.835738 -261.100969) (xy 81.83626 -261.126224) (xy 81.836111 -261.139823)
			(xy 81.833694 -261.166915) (xy 81.831434 -261.180326) (xy 81.829402 -261.191502) (xy 81.835244 -261.213346)
			(xy 81.892394 -261.281672) (xy 81.900002 -261.289918) (xy 81.920303 -261.299404) (xy 81.93151 -261.29996)
			(xy 82.070448 -261.29996) (xy 82.081649 -261.299382) (xy 82.10195 -261.289906) (xy 82.109564 -261.281672)
			(xy 82.166714 -261.213346) (xy 82.172556 -261.191502) (xy 82.170524 -261.180326) (xy 82.16826 -261.166915)
			(xy 82.165843 -261.139824) (xy 82.165698 -261.126224) (xy 82.16622 -261.100969) (xy 82.174533 -261.051147)
			(xy 82.190934 -261.003373) (xy 82.214975 -260.95895) (xy 82.245999 -260.91909) (xy 82.283161 -260.88488)
			(xy 82.325447 -260.857254) (xy 82.371703 -260.836964) (xy 82.420668 -260.824564) (xy 82.471006 -260.820393)
			(xy 82.521344 -260.824564) (xy 82.570309 -260.836964) (xy 82.616565 -260.857254) (xy 82.658851 -260.88488)
			(xy 82.696013 -260.91909) (xy 82.727037 -260.95895) (xy 82.751078 -261.003373) (xy 82.767479 -261.051147)
			(xy 82.775792 -261.100969) (xy 82.776314 -261.126224) (xy 82.776165 -261.139823) (xy 82.773748 -261.166915)
			(xy 82.771488 -261.180326) (xy 82.769456 -261.191502) (xy 82.775298 -261.213346) (xy 82.832448 -261.281672)
			(xy 82.840053 -261.289926) (xy 82.860354 -261.29943) (xy 82.871564 -261.29996) (xy 83.010502 -261.29996)
			(xy 83.021698 -261.299371) (xy 83.041982 -261.289882) (xy 83.049618 -261.281672) (xy 83.106768 -261.213346)
			(xy 83.11261 -261.191502) (xy 83.110578 -261.180326) (xy 83.108314 -261.166915) (xy 83.105896 -261.139824)
			(xy 83.105752 -261.126224) (xy 83.106274 -261.100969) (xy 83.114587 -261.051147) (xy 83.130988 -261.003373)
			(xy 83.155029 -260.95895) (xy 83.186053 -260.91909) (xy 83.223215 -260.88488) (xy 83.265501 -260.857254)
			(xy 83.311757 -260.836964) (xy 83.360722 -260.824564) (xy 83.41106 -260.820393) (xy 83.461398 -260.824564)
			(xy 83.510363 -260.836964) (xy 83.556619 -260.857254) (xy 83.598905 -260.88488) (xy 83.636067 -260.91909)
			(xy 83.667091 -260.95895) (xy 83.691132 -261.003373) (xy 83.707533 -261.051147) (xy 83.715846 -261.100969)
			(xy 83.716368 -261.126224) (xy 83.716219 -261.139823) (xy 83.713802 -261.166915) (xy 83.711542 -261.180326)
			(xy 83.70951 -261.191502) (xy 83.715352 -261.213346) (xy 83.772502 -261.281672) (xy 83.78011 -261.289917)
			(xy 83.800412 -261.299399) (xy 83.811618 -261.29996) (xy 83.950556 -261.29996) (xy 83.961756 -261.299381)
			(xy 83.982055 -261.289902) (xy 83.989672 -261.281672) (xy 84.046822 -261.213346) (xy 84.052664 -261.191502)
			(xy 84.050632 -261.180326) (xy 84.048368 -261.166915) (xy 84.045951 -261.139824) (xy 84.045806 -261.126224)
			(xy 84.046328 -261.100969) (xy 84.054641 -261.051147) (xy 84.071042 -261.003373) (xy 84.095083 -260.95895)
			(xy 84.126107 -260.91909) (xy 84.163269 -260.88488) (xy 84.205555 -260.857254) (xy 84.251811 -260.836964)
			(xy 84.300776 -260.824564) (xy 84.351114 -260.820393) (xy 84.401452 -260.824564) (xy 84.450417 -260.836964)
			(xy 84.496673 -260.857254) (xy 84.538959 -260.88488) (xy 84.576121 -260.91909) (xy 84.607145 -260.95895)
			(xy 84.631186 -261.003373) (xy 84.647587 -261.051147) (xy 84.6559 -261.100969) (xy 84.656422 -261.126224)
			(xy 84.656273 -261.139823) (xy 84.653856 -261.166915) (xy 84.651596 -261.180326) (xy 84.649564 -261.191502)
			(xy 84.655406 -261.213346) (xy 84.712556 -261.281672) (xy 84.720162 -261.289925) (xy 84.740463 -261.299425)
			(xy 84.751672 -261.29996) (xy 84.890356 -261.29996) (xy 84.901556 -261.299381) (xy 84.921855 -261.289902)
			(xy 84.929472 -261.281672) (xy 84.986622 -261.213346) (xy 84.992464 -261.191502) (xy 84.990432 -261.180326)
			(xy 84.988168 -261.166915) (xy 84.985751 -261.139824) (xy 84.985606 -261.126224) (xy 84.986128 -261.100969)
			(xy 84.994441 -261.051147) (xy 85.010842 -261.003373) (xy 85.034883 -260.95895) (xy 85.065907 -260.91909)
			(xy 85.103069 -260.88488) (xy 85.145355 -260.857254) (xy 85.191611 -260.836964) (xy 85.240576 -260.824564)
			(xy 85.290914 -260.820393) (xy 85.341252 -260.824564) (xy 85.390217 -260.836964) (xy 85.436473 -260.857254)
			(xy 85.478759 -260.88488) (xy 85.515921 -260.91909) (xy 85.546945 -260.95895) (xy 85.570986 -261.003373)
			(xy 85.587387 -261.051147) (xy 85.5957 -261.100969) (xy 85.596222 -261.126224) (xy 85.596073 -261.139823)
			(xy 85.593656 -261.166915) (xy 85.591396 -261.180326) (xy 85.589364 -261.191502) (xy 85.595206 -261.213346)
			(xy 85.652356 -261.281672) (xy 85.659962 -261.289925) (xy 85.680263 -261.299425) (xy 85.691472 -261.29996)
			(xy 85.83041 -261.29996) (xy 85.841605 -261.29937) (xy 85.861887 -261.289878) (xy 85.869526 -261.281672)
			(xy 85.926676 -261.213346) (xy 85.932518 -261.191502) (xy 85.930486 -261.180326) (xy 85.928222 -261.166915)
			(xy 85.925804 -261.139824) (xy 85.92566 -261.126224) (xy 85.926182 -261.100969) (xy 85.934495 -261.051147)
			(xy 85.950896 -261.003373) (xy 85.974937 -260.95895) (xy 86.005961 -260.91909) (xy 86.043123 -260.88488)
			(xy 86.085409 -260.857254) (xy 86.131665 -260.836964) (xy 86.18063 -260.824564) (xy 86.230968 -260.820393)
			(xy 86.281306 -260.824564) (xy 86.330271 -260.836964) (xy 86.376527 -260.857254) (xy 86.418813 -260.88488)
			(xy 86.455975 -260.91909) (xy 86.486999 -260.95895) (xy 86.51104 -261.003373) (xy 86.527441 -261.051147)
			(xy 86.535754 -261.100969) (xy 86.536276 -261.126224) (xy 86.536127 -261.139823) (xy 86.53371 -261.166915)
			(xy 86.53145 -261.180326) (xy 86.529418 -261.191502) (xy 86.53526 -261.213346) (xy 86.59241 -261.281672)
			(xy 86.600019 -261.289916) (xy 86.620321 -261.299395) (xy 86.631526 -261.29996) (xy 87.710518 -261.29996)
			(xy 87.721712 -261.299368) (xy 87.741991 -261.289874) (xy 87.749634 -261.281672) (xy 87.806784 -261.213346)
			(xy 87.812626 -261.191502) (xy 87.810594 -261.180326) (xy 87.808331 -261.166915) (xy 87.805913 -261.139824)
			(xy 87.805768 -261.126224) (xy 87.80629 -261.100969) (xy 87.814603 -261.051147) (xy 87.831004 -261.003373)
			(xy 87.855045 -260.95895) (xy 87.886069 -260.91909) (xy 87.923231 -260.88488) (xy 87.965517 -260.857254)
			(xy 88.011773 -260.836964) (xy 88.060738 -260.824564) (xy 88.111076 -260.820393) (xy 88.161414 -260.824564)
			(xy 88.210379 -260.836964) (xy 88.256635 -260.857254) (xy 88.298921 -260.88488) (xy 88.336083 -260.91909)
			(xy 88.367107 -260.95895) (xy 88.391148 -261.003373) (xy 88.407549 -261.051147) (xy 88.415862 -261.100969)
			(xy 88.416384 -261.126224) (xy 88.416235 -261.139823) (xy 88.413818 -261.166915) (xy 88.411558 -261.180326)
			(xy 88.409526 -261.191502) (xy 88.415368 -261.213346) (xy 88.472518 -261.281672) (xy 88.480128 -261.289914)
			(xy 88.500429 -261.29939) (xy 88.511634 -261.29996) (xy 88.650572 -261.29996) (xy 88.661771 -261.299377)
			(xy 88.682064 -261.289895) (xy 88.689688 -261.281672) (xy 88.746838 -261.213346) (xy 88.75268 -261.191502)
			(xy 88.750648 -261.180326) (xy 88.748384 -261.166915) (xy 88.745966 -261.139824) (xy 88.745822 -261.126224)
			(xy 88.746344 -261.100969) (xy 88.754657 -261.051147) (xy 88.771058 -261.003373) (xy 88.795099 -260.95895)
			(xy 88.826123 -260.91909) (xy 88.863285 -260.88488) (xy 88.905571 -260.857254) (xy 88.951827 -260.836964)
			(xy 89.000792 -260.824564) (xy 89.05113 -260.820393) (xy 89.101468 -260.824564) (xy 89.150433 -260.836964)
			(xy 89.196689 -260.857254) (xy 89.238975 -260.88488) (xy 89.276137 -260.91909) (xy 89.307161 -260.95895)
			(xy 89.331202 -261.003373) (xy 89.347603 -261.051147) (xy 89.355916 -261.100969) (xy 89.356438 -261.126224)
			(xy 89.356289 -261.139823) (xy 89.353872 -261.166915) (xy 89.351612 -261.180326) (xy 89.34958 -261.191502)
			(xy 89.355422 -261.213346) (xy 89.412572 -261.281672) (xy 89.420179 -261.289922) (xy 89.44048 -261.299416)
			(xy 89.451688 -261.29996) (xy 89.590372 -261.29996) (xy 89.601571 -261.299377) (xy 89.621864 -261.289895)
			(xy 89.629488 -261.281672) (xy 89.686638 -261.213346) (xy 89.69248 -261.191502) (xy 89.690448 -261.180326)
			(xy 89.688184 -261.166915) (xy 89.685766 -261.139824) (xy 89.685622 -261.126224) (xy 89.686144 -261.100969)
			(xy 89.694457 -261.051147) (xy 89.710858 -261.003373) (xy 89.734899 -260.95895) (xy 89.765923 -260.91909)
			(xy 89.803085 -260.88488) (xy 89.845371 -260.857254) (xy 89.891627 -260.836964) (xy 89.940592 -260.824564)
			(xy 89.99093 -260.820393) (xy 90.041268 -260.824564) (xy 90.090233 -260.836964) (xy 90.136489 -260.857254)
			(xy 90.178775 -260.88488) (xy 90.215937 -260.91909) (xy 90.246961 -260.95895) (xy 90.271002 -261.003373)
			(xy 90.287403 -261.051147) (xy 90.295716 -261.100969) (xy 90.296238 -261.126224) (xy 90.296089 -261.139823)
			(xy 90.293672 -261.166915) (xy 90.291412 -261.180326) (xy 90.28938 -261.191502) (xy 90.295222 -261.213346)
			(xy 90.352372 -261.281672) (xy 90.359979 -261.289922) (xy 90.38028 -261.299416) (xy 90.391488 -261.29996)
			(xy 90.530426 -261.29996) (xy 90.541629 -261.299387) (xy 90.561937 -261.289916) (xy 90.569542 -261.281672)
			(xy 90.626692 -261.213346) (xy 90.632534 -261.191502) (xy 90.630502 -261.180326) (xy 90.628238 -261.166915)
			(xy 90.625821 -261.139824) (xy 90.625676 -261.126224) (xy 90.626198 -261.100969) (xy 90.634511 -261.051147)
			(xy 90.650912 -261.003373) (xy 90.674953 -260.95895) (xy 90.705977 -260.91909) (xy 90.743139 -260.88488)
			(xy 90.785425 -260.857254) (xy 90.831681 -260.836964) (xy 90.880646 -260.824564) (xy 90.930984 -260.820393)
			(xy 90.981322 -260.824564) (xy 91.030287 -260.836964) (xy 91.076543 -260.857254) (xy 91.118829 -260.88488)
			(xy 91.155991 -260.91909) (xy 91.187015 -260.95895) (xy 91.211056 -261.003373) (xy 91.227457 -261.051147)
			(xy 91.23577 -261.100969) (xy 91.236292 -261.126224) (xy 91.236143 -261.139823) (xy 91.233727 -261.166915)
			(xy 91.231466 -261.180326) (xy 91.229434 -261.191502) (xy 91.235276 -261.213346) (xy 91.292426 -261.281672)
			(xy 91.300036 -261.289913) (xy 91.320338 -261.299385) (xy 91.331542 -261.29996) (xy 91.47048 -261.29996)
			(xy 91.481678 -261.299376) (xy 91.501969 -261.289892) (xy 91.509596 -261.281672) (xy 91.566746 -261.213346)
			(xy 91.572588 -261.191502) (xy 91.570556 -261.180326) (xy 91.568292 -261.166915) (xy 91.565874 -261.139824)
			(xy 91.56573 -261.126224) (xy 91.566252 -261.100969) (xy 91.574565 -261.051147) (xy 91.590966 -261.003373)
			(xy 91.615007 -260.95895) (xy 91.646031 -260.91909) (xy 91.683193 -260.88488) (xy 91.725479 -260.857254)
			(xy 91.771735 -260.836964) (xy 91.8207 -260.824564) (xy 91.871038 -260.820393) (xy 91.921376 -260.824564)
			(xy 91.970341 -260.836964) (xy 92.016597 -260.857254) (xy 92.058883 -260.88488) (xy 92.096045 -260.91909)
			(xy 92.127069 -260.95895) (xy 92.15111 -261.003373) (xy 92.167511 -261.051147) (xy 92.175824 -261.100969)
			(xy 92.176346 -261.126224) (xy 92.176197 -261.139823) (xy 92.17378 -261.166915) (xy 92.17152 -261.180326)
			(xy 92.169488 -261.191502) (xy 92.17533 -261.213346) (xy 92.23248 -261.281672) (xy 92.240087 -261.28992)
			(xy 92.260389 -261.299411) (xy 92.271596 -261.29996) (xy 92.410534 -261.29996) (xy 92.421737 -261.299385)
			(xy 92.442042 -261.289912) (xy 92.44965 -261.281672) (xy 92.5068 -261.213346) (xy 92.512642 -261.191502)
			(xy 92.51061 -261.180326) (xy 92.508346 -261.166915) (xy 92.505929 -261.139824) (xy 92.505784 -261.126224)
			(xy 92.506306 -261.100969) (xy 92.514619 -261.051147) (xy 92.53102 -261.003373) (xy 92.555061 -260.95895)
			(xy 92.586085 -260.91909) (xy 92.623247 -260.88488) (xy 92.665533 -260.857254) (xy 92.711789 -260.836964)
			(xy 92.760754 -260.824564) (xy 92.811092 -260.820393) (xy 92.86143 -260.824564) (xy 92.910395 -260.836964)
			(xy 92.956651 -260.857254) (xy 92.998937 -260.88488) (xy 93.036099 -260.91909) (xy 93.067123 -260.95895)
			(xy 93.091164 -261.003373) (xy 93.107565 -261.051147) (xy 93.115878 -261.100969) (xy 93.1164 -261.126224)
			(xy 93.116251 -261.139823) (xy 93.113835 -261.166915) (xy 93.111574 -261.180326) (xy 93.109542 -261.191502)
			(xy 93.115384 -261.213346) (xy 93.172534 -261.281672) (xy 93.180144 -261.289912) (xy 93.200446 -261.299381)
			(xy 93.21165 -261.29996) (xy 94.290388 -261.29996) (xy 94.301585 -261.299374) (xy 94.321874 -261.289888)
			(xy 94.329504 -261.281672) (xy 94.386654 -261.213346) (xy 94.392496 -261.191502) (xy 94.390464 -261.180326)
			(xy 94.3882 -261.166915) (xy 94.385782 -261.139824) (xy 94.385638 -261.126224) (xy 94.38616 -261.100969)
			(xy 94.394473 -261.051147) (xy 94.410874 -261.003373) (xy 94.434915 -260.95895) (xy 94.465939 -260.91909)
			(xy 94.503101 -260.88488) (xy 94.545387 -260.857254) (xy 94.591643 -260.836964) (xy 94.640608 -260.824564)
			(xy 94.690946 -260.820393) (xy 94.741284 -260.824564) (xy 94.790249 -260.836964) (xy 94.836505 -260.857254)
			(xy 94.878791 -260.88488) (xy 94.915953 -260.91909) (xy 94.946977 -260.95895) (xy 94.971018 -261.003373)
			(xy 94.987419 -261.051147) (xy 94.995732 -261.100969) (xy 94.996254 -261.126224) (xy 94.996105 -261.139823)
			(xy 94.993688 -261.166915) (xy 94.991428 -261.180326) (xy 94.989396 -261.191502) (xy 94.995238 -261.213346)
			(xy 95.052388 -261.281672) (xy 95.059996 -261.289919) (xy 95.080297 -261.299407) (xy 95.091504 -261.29996)
			(xy 95.230442 -261.29996) (xy 95.241644 -261.299383) (xy 95.261947 -261.289909) (xy 95.269558 -261.281672)
			(xy 95.326708 -261.213346) (xy 95.33255 -261.191502) (xy 95.330518 -261.180326) (xy 95.328254 -261.166915)
			(xy 95.325837 -261.139824) (xy 95.325692 -261.126224) (xy 95.326214 -261.100969) (xy 95.334527 -261.051147)
			(xy 95.350928 -261.003373) (xy 95.374969 -260.95895) (xy 95.405993 -260.91909) (xy 95.443155 -260.88488)
			(xy 95.485441 -260.857254) (xy 95.531697 -260.836964) (xy 95.580662 -260.824564) (xy 95.631 -260.820393)
			(xy 95.681338 -260.824564) (xy 95.730303 -260.836964) (xy 95.776559 -260.857254) (xy 95.818845 -260.88488)
			(xy 95.856007 -260.91909) (xy 95.887031 -260.95895) (xy 95.911072 -261.003373) (xy 95.927473 -261.051147)
			(xy 95.935786 -261.100969) (xy 95.936308 -261.126224) (xy 95.936159 -261.139823) (xy 95.933742 -261.166915)
			(xy 95.931482 -261.180326) (xy 95.92945 -261.191502) (xy 95.935292 -261.213346) (xy 95.992442 -261.281672)
			(xy 96.000053 -261.28991) (xy 96.020355 -261.299377) (xy 96.031558 -261.29996) (xy 96.170496 -261.29996)
			(xy 96.181692 -261.299373) (xy 96.201978 -261.289884) (xy 96.209612 -261.281672) (xy 96.266762 -261.213346)
			(xy 96.272604 -261.191502) (xy 96.270572 -261.180326) (xy 96.268308 -261.166915) (xy 96.26589 -261.139824)
			(xy 96.265746 -261.126224) (xy 96.266268 -261.100969) (xy 96.274581 -261.051147) (xy 96.290982 -261.003373)
			(xy 96.315023 -260.95895) (xy 96.346047 -260.91909) (xy 96.383209 -260.88488) (xy 96.425495 -260.857254)
			(xy 96.471751 -260.836964) (xy 96.520716 -260.824564) (xy 96.571054 -260.820393) (xy 96.621392 -260.824564)
			(xy 96.670357 -260.836964) (xy 96.716613 -260.857254) (xy 96.758899 -260.88488) (xy 96.796061 -260.91909)
			(xy 96.827085 -260.95895) (xy 96.851126 -261.003373) (xy 96.867527 -261.051147) (xy 96.87584 -261.100969)
			(xy 96.876362 -261.126224) (xy 98.145358 -261.126224) (xy 98.149318 -261.07717) (xy 98.161095 -261.029386)
			(xy 98.180386 -260.98411) (xy 98.206689 -260.942514) (xy 98.239324 -260.905677) (xy 98.277445 -260.874552)
			(xy 98.320066 -260.849945) (xy 98.366082 -260.832493) (xy 98.414301 -260.822649) (xy 98.463476 -260.820668)
			(xy 98.512331 -260.8266) (xy 98.559602 -260.840292) (xy 98.604064 -260.86139) (xy 98.644567 -260.889346)
			(xy 98.68006 -260.923438) (xy 98.709625 -260.962782) (xy 98.732496 -261.006359) (xy 98.74808 -261.05304)
			(xy 98.755975 -261.101617) (xy 98.75647 -261.126224) (xy 100.025212 -261.126224) (xy 100.029172 -261.07717)
			(xy 100.040949 -261.029386) (xy 100.06024 -260.98411) (xy 100.086543 -260.942514) (xy 100.119178 -260.905677)
			(xy 100.157299 -260.874552) (xy 100.19992 -260.849945) (xy 100.245936 -260.832493) (xy 100.294155 -260.822649)
			(xy 100.34333 -260.820668) (xy 100.392185 -260.8266) (xy 100.439456 -260.840292) (xy 100.483918 -260.86139)
			(xy 100.524421 -260.889346) (xy 100.559914 -260.923438) (xy 100.589479 -260.962782) (xy 100.61235 -261.006359)
			(xy 100.627934 -261.05304) (xy 100.635829 -261.101617) (xy 100.636324 -261.126224) (xy 100.965266 -261.126224)
			(xy 100.969226 -261.07717) (xy 100.981003 -261.029386) (xy 101.000294 -260.98411) (xy 101.026597 -260.942514)
			(xy 101.059232 -260.905677) (xy 101.097353 -260.874552) (xy 101.139974 -260.849945) (xy 101.18599 -260.832493)
			(xy 101.234209 -260.822649) (xy 101.283384 -260.820668) (xy 101.332239 -260.8266) (xy 101.37951 -260.840292)
			(xy 101.423972 -260.86139) (xy 101.464475 -260.889346) (xy 101.499968 -260.923438) (xy 101.529533 -260.962782)
			(xy 101.552404 -261.006359) (xy 101.567988 -261.05304) (xy 101.575883 -261.101617) (xy 101.576378 -261.126224)
			(xy 101.90532 -261.126224) (xy 101.90928 -261.07717) (xy 101.921057 -261.029386) (xy 101.940348 -260.98411)
			(xy 101.966651 -260.942514) (xy 101.999286 -260.905677) (xy 102.037407 -260.874552) (xy 102.080028 -260.849945)
			(xy 102.126044 -260.832493) (xy 102.174263 -260.822649) (xy 102.223438 -260.820668) (xy 102.272293 -260.8266)
			(xy 102.319564 -260.840292) (xy 102.364026 -260.86139) (xy 102.404529 -260.889346) (xy 102.440022 -260.923438)
			(xy 102.469587 -260.962782) (xy 102.492458 -261.006359) (xy 102.508042 -261.05304) (xy 102.515937 -261.101617)
			(xy 102.516432 -261.126224) (xy 102.516391 -261.128256) (xy 102.842072 -261.128256) (xy 102.846032 -261.079202)
			(xy 102.857809 -261.031418) (xy 102.8771 -260.986142) (xy 102.903403 -260.944546) (xy 102.936038 -260.907709)
			(xy 102.974159 -260.876584) (xy 103.01678 -260.851977) (xy 103.062796 -260.834525) (xy 103.111015 -260.824681)
			(xy 103.16019 -260.8227) (xy 103.209045 -260.828632) (xy 103.256316 -260.842324) (xy 103.300778 -260.863422)
			(xy 103.341281 -260.891378) (xy 103.376774 -260.92547) (xy 103.406339 -260.964814) (xy 103.42921 -261.008391)
			(xy 103.444794 -261.055072) (xy 103.452689 -261.103649) (xy 103.453184 -261.128256) (xy 103.782126 -261.128256)
			(xy 103.786086 -261.079202) (xy 103.797863 -261.031418) (xy 103.817154 -260.986142) (xy 103.843457 -260.944546)
			(xy 103.876092 -260.907709) (xy 103.914213 -260.876584) (xy 103.956834 -260.851977) (xy 104.00285 -260.834525)
			(xy 104.051069 -260.824681) (xy 104.100244 -260.8227) (xy 104.149099 -260.828632) (xy 104.19637 -260.842324)
			(xy 104.240832 -260.863422) (xy 104.281335 -260.891378) (xy 104.316828 -260.92547) (xy 104.346393 -260.964814)
			(xy 104.369264 -261.008391) (xy 104.384848 -261.055072) (xy 104.392743 -261.103649) (xy 104.393238 -261.128256)
			(xy 104.392743 -261.152863) (xy 104.384848 -261.20144) (xy 104.369264 -261.248121) (xy 104.346393 -261.291698)
			(xy 104.316828 -261.331042) (xy 104.281335 -261.365134) (xy 104.240832 -261.39309) (xy 104.19637 -261.414188)
			(xy 104.149099 -261.42788) (xy 104.100244 -261.433812) (xy 104.051069 -261.431831) (xy 104.00285 -261.421987)
			(xy 103.956834 -261.404535) (xy 103.914213 -261.379928) (xy 103.876092 -261.348803) (xy 103.843457 -261.311966)
			(xy 103.817154 -261.27037) (xy 103.797863 -261.225094) (xy 103.786086 -261.17731) (xy 103.782126 -261.128256)
			(xy 103.453184 -261.128256) (xy 103.452689 -261.152863) (xy 103.444794 -261.20144) (xy 103.42921 -261.248121)
			(xy 103.406339 -261.291698) (xy 103.376774 -261.331042) (xy 103.341281 -261.365134) (xy 103.300778 -261.39309)
			(xy 103.256316 -261.414188) (xy 103.209045 -261.42788) (xy 103.16019 -261.433812) (xy 103.111015 -261.431831)
			(xy 103.062796 -261.421987) (xy 103.01678 -261.404535) (xy 102.974159 -261.379928) (xy 102.936038 -261.348803)
			(xy 102.903403 -261.311966) (xy 102.8771 -261.27037) (xy 102.857809 -261.225094) (xy 102.846032 -261.17731)
			(xy 102.842072 -261.128256) (xy 102.516391 -261.128256) (xy 102.515937 -261.150831) (xy 102.508042 -261.199408)
			(xy 102.492458 -261.246089) (xy 102.469587 -261.289666) (xy 102.440022 -261.32901) (xy 102.404529 -261.363102)
			(xy 102.364026 -261.391058) (xy 102.319564 -261.412156) (xy 102.272293 -261.425848) (xy 102.223438 -261.43178)
			(xy 102.174263 -261.429799) (xy 102.126044 -261.419955) (xy 102.080028 -261.402503) (xy 102.037407 -261.377896)
			(xy 101.999286 -261.346771) (xy 101.966651 -261.309934) (xy 101.940348 -261.268338) (xy 101.921057 -261.223062)
			(xy 101.90928 -261.175278) (xy 101.90532 -261.126224) (xy 101.576378 -261.126224) (xy 101.575883 -261.150831)
			(xy 101.567988 -261.199408) (xy 101.552404 -261.246089) (xy 101.529533 -261.289666) (xy 101.499968 -261.32901)
			(xy 101.464475 -261.363102) (xy 101.423972 -261.391058) (xy 101.37951 -261.412156) (xy 101.332239 -261.425848)
			(xy 101.283384 -261.43178) (xy 101.234209 -261.429799) (xy 101.18599 -261.419955) (xy 101.139974 -261.402503)
			(xy 101.097353 -261.377896) (xy 101.059232 -261.346771) (xy 101.026597 -261.309934) (xy 101.000294 -261.268338)
			(xy 100.981003 -261.223062) (xy 100.969226 -261.175278) (xy 100.965266 -261.126224) (xy 100.636324 -261.126224)
			(xy 100.635829 -261.150831) (xy 100.627934 -261.199408) (xy 100.61235 -261.246089) (xy 100.589479 -261.289666)
			(xy 100.559914 -261.32901) (xy 100.524421 -261.363102) (xy 100.483918 -261.391058) (xy 100.439456 -261.412156)
			(xy 100.392185 -261.425848) (xy 100.34333 -261.43178) (xy 100.294155 -261.429799) (xy 100.245936 -261.419955)
			(xy 100.19992 -261.402503) (xy 100.157299 -261.377896) (xy 100.119178 -261.346771) (xy 100.086543 -261.309934)
			(xy 100.06024 -261.268338) (xy 100.040949 -261.223062) (xy 100.029172 -261.175278) (xy 100.025212 -261.126224)
			(xy 98.75647 -261.126224) (xy 98.755975 -261.150831) (xy 98.74808 -261.199408) (xy 98.732496 -261.246089)
			(xy 98.709625 -261.289666) (xy 98.68006 -261.32901) (xy 98.644567 -261.363102) (xy 98.604064 -261.391058)
			(xy 98.559602 -261.412156) (xy 98.512331 -261.425848) (xy 98.463476 -261.43178) (xy 98.414301 -261.429799)
			(xy 98.366082 -261.419955) (xy 98.320066 -261.402503) (xy 98.277445 -261.377896) (xy 98.239324 -261.346771)
			(xy 98.206689 -261.309934) (xy 98.180386 -261.268338) (xy 98.161095 -261.223062) (xy 98.149318 -261.175278)
			(xy 98.145358 -261.126224) (xy 96.876362 -261.126224) (xy 96.875812 -261.152141) (xy 96.867054 -261.20323)
			(xy 96.849793 -261.252106) (xy 96.824526 -261.297365) (xy 96.791978 -261.337706) (xy 96.753085 -261.371971)
			(xy 96.731328 -261.386066) (xy 96.721168 -261.392416) (xy 96.708722 -261.41172) (xy 96.698054 -261.502652)
			(xy 96.697276 -261.514206) (xy 96.70496 -261.536025) (xy 96.712786 -261.544562) (xy 96.745298 -261.577074)
			(xy 96.752133 -261.584477) (xy 96.759841 -261.603075) (xy 96.760284 -261.613142) (xy 96.760284 -261.93623)
			(xy 97.675204 -261.93623) (xy 97.679164 -261.887176) (xy 97.690941 -261.839392) (xy 97.710232 -261.794116)
			(xy 97.736535 -261.75252) (xy 97.76917 -261.715683) (xy 97.807291 -261.684558) (xy 97.849912 -261.659951)
			(xy 97.895928 -261.642499) (xy 97.944147 -261.632655) (xy 97.993322 -261.630674) (xy 98.042177 -261.636606)
			(xy 98.089448 -261.650298) (xy 98.13391 -261.671396) (xy 98.174413 -261.699352) (xy 98.209906 -261.733444)
			(xy 98.239471 -261.772788) (xy 98.262342 -261.816365) (xy 98.277926 -261.863046) (xy 98.285821 -261.911623)
			(xy 98.286316 -261.93623) (xy 99.555312 -261.93623) (xy 99.559272 -261.887176) (xy 99.571049 -261.839392)
			(xy 99.59034 -261.794116) (xy 99.616643 -261.75252) (xy 99.649278 -261.715683) (xy 99.687399 -261.684558)
			(xy 99.73002 -261.659951) (xy 99.776036 -261.642499) (xy 99.824255 -261.632655) (xy 99.87343 -261.630674)
			(xy 99.922285 -261.636606) (xy 99.969556 -261.650298) (xy 100.014018 -261.671396) (xy 100.054521 -261.699352)
			(xy 100.090014 -261.733444) (xy 100.119579 -261.772788) (xy 100.14245 -261.816365) (xy 100.158034 -261.863046)
			(xy 100.165929 -261.911623) (xy 100.166424 -261.93623) (xy 101.435166 -261.93623) (xy 101.439126 -261.887176)
			(xy 101.450903 -261.839392) (xy 101.470194 -261.794116) (xy 101.496497 -261.75252) (xy 101.529132 -261.715683)
			(xy 101.567253 -261.684558) (xy 101.609874 -261.659951) (xy 101.65589 -261.642499) (xy 101.704109 -261.632655)
			(xy 101.753284 -261.630674) (xy 101.802139 -261.636606) (xy 101.84941 -261.650298) (xy 101.893872 -261.671396)
			(xy 101.934375 -261.699352) (xy 101.969868 -261.733444) (xy 101.999433 -261.772788) (xy 102.022304 -261.816365)
			(xy 102.037888 -261.863046) (xy 102.045783 -261.911623) (xy 102.046278 -261.93623) (xy 102.37522 -261.93623)
			(xy 102.37918 -261.887176) (xy 102.390957 -261.839392) (xy 102.410248 -261.794116) (xy 102.436551 -261.75252)
			(xy 102.469186 -261.715683) (xy 102.507307 -261.684558) (xy 102.549928 -261.659951) (xy 102.595944 -261.642499)
			(xy 102.644163 -261.632655) (xy 102.693338 -261.630674) (xy 102.742193 -261.636606) (xy 102.789464 -261.650298)
			(xy 102.833926 -261.671396) (xy 102.874429 -261.699352) (xy 102.909922 -261.733444) (xy 102.939487 -261.772788)
			(xy 102.962358 -261.816365) (xy 102.977942 -261.863046) (xy 102.985837 -261.911623) (xy 102.986332 -261.93623)
			(xy 102.985837 -261.960837) (xy 102.977942 -262.009414) (xy 102.962358 -262.056095) (xy 102.939487 -262.099672)
			(xy 102.909922 -262.139016) (xy 102.874429 -262.173108) (xy 102.833926 -262.201064) (xy 102.789464 -262.222162)
			(xy 102.742193 -262.235854) (xy 102.693338 -262.241786) (xy 102.644163 -262.239805) (xy 102.595944 -262.229961)
			(xy 102.549928 -262.212509) (xy 102.507307 -262.187902) (xy 102.469186 -262.156777) (xy 102.436551 -262.11994)
			(xy 102.410248 -262.078344) (xy 102.390957 -262.033068) (xy 102.37918 -261.985284) (xy 102.37522 -261.93623)
			(xy 102.046278 -261.93623) (xy 102.045783 -261.960837) (xy 102.037888 -262.009414) (xy 102.022304 -262.056095)
			(xy 101.999433 -262.099672) (xy 101.969868 -262.139016) (xy 101.934375 -262.173108) (xy 101.893872 -262.201064)
			(xy 101.84941 -262.222162) (xy 101.802139 -262.235854) (xy 101.753284 -262.241786) (xy 101.704109 -262.239805)
			(xy 101.65589 -262.229961) (xy 101.609874 -262.212509) (xy 101.567253 -262.187902) (xy 101.529132 -262.156777)
			(xy 101.496497 -262.11994) (xy 101.470194 -262.078344) (xy 101.450903 -262.033068) (xy 101.439126 -261.985284)
			(xy 101.435166 -261.93623) (xy 100.166424 -261.93623) (xy 100.165929 -261.960837) (xy 100.158034 -262.009414)
			(xy 100.14245 -262.056095) (xy 100.119579 -262.099672) (xy 100.090014 -262.139016) (xy 100.054521 -262.173108)
			(xy 100.014018 -262.201064) (xy 99.969556 -262.222162) (xy 99.922285 -262.235854) (xy 99.87343 -262.241786)
			(xy 99.824255 -262.239805) (xy 99.776036 -262.229961) (xy 99.73002 -262.212509) (xy 99.687399 -262.187902)
			(xy 99.649278 -262.156777) (xy 99.616643 -262.11994) (xy 99.59034 -262.078344) (xy 99.571049 -262.033068)
			(xy 99.559272 -261.985284) (xy 99.555312 -261.93623) (xy 98.286316 -261.93623) (xy 98.285821 -261.960837)
			(xy 98.277926 -262.009414) (xy 98.262342 -262.056095) (xy 98.239471 -262.099672) (xy 98.209906 -262.139016)
			(xy 98.174413 -262.173108) (xy 98.13391 -262.201064) (xy 98.089448 -262.222162) (xy 98.042177 -262.235854)
			(xy 97.993322 -262.241786) (xy 97.944147 -262.239805) (xy 97.895928 -262.229961) (xy 97.849912 -262.212509)
			(xy 97.807291 -262.187902) (xy 97.76917 -262.156777) (xy 97.736535 -262.11994) (xy 97.710232 -262.078344)
			(xy 97.690941 -262.033068) (xy 97.679164 -261.985284) (xy 97.675204 -261.93623) (xy 96.760284 -261.93623)
			(xy 96.760284 -262.472932) (xy 96.760418 -262.478231) (xy 96.762587 -262.488604) (xy 96.764602 -262.493506)
			(xy 96.776286 -262.520176) (xy 96.783398 -262.527034) (xy 96.800656 -262.544396) (xy 96.829961 -262.583605)
			(xy 96.852628 -262.626991) (xy 96.868073 -262.673441) (xy 96.875902 -262.721761) (xy 96.876362 -262.746236)
			(xy 98.145358 -262.746236) (xy 98.149318 -262.697182) (xy 98.161095 -262.649398) (xy 98.180386 -262.604122)
			(xy 98.206689 -262.562526) (xy 98.239324 -262.525689) (xy 98.277445 -262.494564) (xy 98.320066 -262.469957)
			(xy 98.366082 -262.452505) (xy 98.414301 -262.442661) (xy 98.463476 -262.44068) (xy 98.512331 -262.446612)
			(xy 98.559602 -262.460304) (xy 98.604064 -262.481402) (xy 98.644567 -262.509358) (xy 98.68006 -262.54345)
			(xy 98.709625 -262.582794) (xy 98.732496 -262.626371) (xy 98.74808 -262.673052) (xy 98.755975 -262.721629)
			(xy 98.75647 -262.746236) (xy 100.025212 -262.746236) (xy 100.029172 -262.697182) (xy 100.040949 -262.649398)
			(xy 100.06024 -262.604122) (xy 100.086543 -262.562526) (xy 100.119178 -262.525689) (xy 100.157299 -262.494564)
			(xy 100.19992 -262.469957) (xy 100.245936 -262.452505) (xy 100.294155 -262.442661) (xy 100.34333 -262.44068)
			(xy 100.392185 -262.446612) (xy 100.439456 -262.460304) (xy 100.483918 -262.481402) (xy 100.524421 -262.509358)
			(xy 100.559914 -262.54345) (xy 100.589479 -262.582794) (xy 100.61235 -262.626371) (xy 100.627934 -262.673052)
			(xy 100.635829 -262.721629) (xy 100.636324 -262.746236) (xy 100.965266 -262.746236) (xy 100.969226 -262.697182)
			(xy 100.981003 -262.649398) (xy 101.000294 -262.604122) (xy 101.026597 -262.562526) (xy 101.059232 -262.525689)
			(xy 101.097353 -262.494564) (xy 101.139974 -262.469957) (xy 101.18599 -262.452505) (xy 101.234209 -262.442661)
			(xy 101.283384 -262.44068) (xy 101.332239 -262.446612) (xy 101.37951 -262.460304) (xy 101.423972 -262.481402)
			(xy 101.464475 -262.509358) (xy 101.499968 -262.54345) (xy 101.529533 -262.582794) (xy 101.552404 -262.626371)
			(xy 101.567988 -262.673052) (xy 101.575883 -262.721629) (xy 101.576378 -262.746236) (xy 101.90532 -262.746236)
			(xy 101.90928 -262.697182) (xy 101.921057 -262.649398) (xy 101.940348 -262.604122) (xy 101.966651 -262.562526)
			(xy 101.999286 -262.525689) (xy 102.037407 -262.494564) (xy 102.080028 -262.469957) (xy 102.126044 -262.452505)
			(xy 102.174263 -262.442661) (xy 102.223438 -262.44068) (xy 102.272293 -262.446612) (xy 102.319564 -262.460304)
			(xy 102.364026 -262.481402) (xy 102.404529 -262.509358) (xy 102.440022 -262.54345) (xy 102.469587 -262.582794)
			(xy 102.492458 -262.626371) (xy 102.508042 -262.673052) (xy 102.515937 -262.721629) (xy 102.516432 -262.746236)
			(xy 102.515937 -262.770843) (xy 102.508042 -262.81942) (xy 102.492458 -262.866101) (xy 102.469587 -262.909678)
			(xy 102.440022 -262.949022) (xy 102.404529 -262.983114) (xy 102.364026 -263.01107) (xy 102.319564 -263.032168)
			(xy 102.272293 -263.04586) (xy 102.223438 -263.051792) (xy 102.174263 -263.049811) (xy 102.126044 -263.039967)
			(xy 102.080028 -263.022515) (xy 102.037407 -262.997908) (xy 101.999286 -262.966783) (xy 101.966651 -262.929946)
			(xy 101.940348 -262.88835) (xy 101.921057 -262.843074) (xy 101.90928 -262.79529) (xy 101.90532 -262.746236)
			(xy 101.576378 -262.746236) (xy 101.575883 -262.770843) (xy 101.567988 -262.81942) (xy 101.552404 -262.866101)
			(xy 101.529533 -262.909678) (xy 101.499968 -262.949022) (xy 101.464475 -262.983114) (xy 101.423972 -263.01107)
			(xy 101.37951 -263.032168) (xy 101.332239 -263.04586) (xy 101.283384 -263.051792) (xy 101.234209 -263.049811)
			(xy 101.18599 -263.039967) (xy 101.139974 -263.022515) (xy 101.097353 -262.997908) (xy 101.059232 -262.966783)
			(xy 101.026597 -262.929946) (xy 101.000294 -262.88835) (xy 100.981003 -262.843074) (xy 100.969226 -262.79529)
			(xy 100.965266 -262.746236) (xy 100.636324 -262.746236) (xy 100.635829 -262.770843) (xy 100.627934 -262.81942)
			(xy 100.61235 -262.866101) (xy 100.589479 -262.909678) (xy 100.559914 -262.949022) (xy 100.524421 -262.983114)
			(xy 100.483918 -263.01107) (xy 100.439456 -263.032168) (xy 100.392185 -263.04586) (xy 100.34333 -263.051792)
			(xy 100.294155 -263.049811) (xy 100.245936 -263.039967) (xy 100.19992 -263.022515) (xy 100.157299 -262.997908)
			(xy 100.119178 -262.966783) (xy 100.086543 -262.929946) (xy 100.06024 -262.88835) (xy 100.040949 -262.843074)
			(xy 100.029172 -262.79529) (xy 100.025212 -262.746236) (xy 98.75647 -262.746236) (xy 98.755975 -262.770843)
			(xy 98.74808 -262.81942) (xy 98.732496 -262.866101) (xy 98.709625 -262.909678) (xy 98.68006 -262.949022)
			(xy 98.644567 -262.983114) (xy 98.604064 -263.01107) (xy 98.559602 -263.032168) (xy 98.512331 -263.04586)
			(xy 98.463476 -263.051792) (xy 98.414301 -263.049811) (xy 98.366082 -263.039967) (xy 98.320066 -263.022515)
			(xy 98.277445 -262.997908) (xy 98.239324 -262.966783) (xy 98.206689 -262.929946) (xy 98.180386 -262.88835)
			(xy 98.161095 -262.843074) (xy 98.149318 -262.79529) (xy 98.145358 -262.746236) (xy 96.876362 -262.746236)
			(xy 96.875853 -262.770706) (xy 96.868001 -262.819013) (xy 96.852553 -262.865451) (xy 96.829902 -262.908835)
			(xy 96.800628 -262.948055) (xy 96.783398 -262.965438) (xy 96.776286 -262.972296) (xy 96.764602 -262.998966)
			(xy 96.762573 -263.003864) (xy 96.760399 -263.014239) (xy 96.760284 -263.01954) (xy 96.760284 -263.556242)
			(xy 97.675204 -263.556242) (xy 97.679164 -263.507188) (xy 97.690941 -263.459404) (xy 97.710232 -263.414128)
			(xy 97.736535 -263.372532) (xy 97.76917 -263.335695) (xy 97.807291 -263.30457) (xy 97.849912 -263.279963)
			(xy 97.895928 -263.262511) (xy 97.944147 -263.252667) (xy 97.993322 -263.250686) (xy 98.042177 -263.256618)
			(xy 98.089448 -263.27031) (xy 98.13391 -263.291408) (xy 98.174413 -263.319364) (xy 98.209906 -263.353456)
			(xy 98.239471 -263.3928) (xy 98.262342 -263.436377) (xy 98.277926 -263.483058) (xy 98.285821 -263.531635)
			(xy 98.286316 -263.556242) (xy 99.555312 -263.556242) (xy 99.559272 -263.507188) (xy 99.571049 -263.459404)
			(xy 99.59034 -263.414128) (xy 99.616643 -263.372532) (xy 99.649278 -263.335695) (xy 99.687399 -263.30457)
			(xy 99.73002 -263.279963) (xy 99.776036 -263.262511) (xy 99.824255 -263.252667) (xy 99.87343 -263.250686)
			(xy 99.922285 -263.256618) (xy 99.969556 -263.27031) (xy 100.014018 -263.291408) (xy 100.054521 -263.319364)
			(xy 100.090014 -263.353456) (xy 100.119579 -263.3928) (xy 100.14245 -263.436377) (xy 100.158034 -263.483058)
			(xy 100.165929 -263.531635) (xy 100.166424 -263.556242) (xy 101.435166 -263.556242) (xy 101.439126 -263.507188)
			(xy 101.450903 -263.459404) (xy 101.470194 -263.414128) (xy 101.496497 -263.372532) (xy 101.529132 -263.335695)
			(xy 101.567253 -263.30457) (xy 101.609874 -263.279963) (xy 101.65589 -263.262511) (xy 101.704109 -263.252667)
			(xy 101.753284 -263.250686) (xy 101.802139 -263.256618) (xy 101.84941 -263.27031) (xy 101.893872 -263.291408)
			(xy 101.934375 -263.319364) (xy 101.969868 -263.353456) (xy 101.999433 -263.3928) (xy 102.022304 -263.436377)
			(xy 102.037888 -263.483058) (xy 102.045783 -263.531635) (xy 102.046278 -263.556242) (xy 102.045783 -263.580849)
			(xy 102.037888 -263.629426) (xy 102.022304 -263.676107) (xy 101.999433 -263.719684) (xy 101.969868 -263.759028)
			(xy 101.934375 -263.79312) (xy 101.893872 -263.821076) (xy 101.84941 -263.842174) (xy 101.802139 -263.855866)
			(xy 101.753284 -263.861798) (xy 101.704109 -263.859817) (xy 101.65589 -263.849973) (xy 101.609874 -263.832521)
			(xy 101.567253 -263.807914) (xy 101.529132 -263.776789) (xy 101.496497 -263.739952) (xy 101.470194 -263.698356)
			(xy 101.450903 -263.65308) (xy 101.439126 -263.605296) (xy 101.435166 -263.556242) (xy 100.166424 -263.556242)
			(xy 100.165929 -263.580849) (xy 100.158034 -263.629426) (xy 100.14245 -263.676107) (xy 100.119579 -263.719684)
			(xy 100.090014 -263.759028) (xy 100.054521 -263.79312) (xy 100.014018 -263.821076) (xy 99.969556 -263.842174)
			(xy 99.922285 -263.855866) (xy 99.87343 -263.861798) (xy 99.824255 -263.859817) (xy 99.776036 -263.849973)
			(xy 99.73002 -263.832521) (xy 99.687399 -263.807914) (xy 99.649278 -263.776789) (xy 99.616643 -263.739952)
			(xy 99.59034 -263.698356) (xy 99.571049 -263.65308) (xy 99.559272 -263.605296) (xy 99.555312 -263.556242)
			(xy 98.286316 -263.556242) (xy 98.285821 -263.580849) (xy 98.277926 -263.629426) (xy 98.262342 -263.676107)
			(xy 98.239471 -263.719684) (xy 98.209906 -263.759028) (xy 98.174413 -263.79312) (xy 98.13391 -263.821076)
			(xy 98.089448 -263.842174) (xy 98.042177 -263.855866) (xy 97.993322 -263.861798) (xy 97.944147 -263.859817)
			(xy 97.895928 -263.849973) (xy 97.849912 -263.832521) (xy 97.807291 -263.807914) (xy 97.76917 -263.776789)
			(xy 97.736535 -263.739952) (xy 97.710232 -263.698356) (xy 97.690941 -263.65308) (xy 97.679164 -263.605296)
			(xy 97.675204 -263.556242) (xy 96.760284 -263.556242) (xy 96.760284 -264.092944) (xy 96.760419 -264.098242)
			(xy 96.76259 -264.108615) (xy 96.764602 -264.113518) (xy 96.776286 -264.140188) (xy 96.783398 -264.147046)
			(xy 96.800655 -264.164408) (xy 96.829959 -264.203617) (xy 96.852624 -264.247004) (xy 96.868068 -264.293453)
			(xy 96.875894 -264.341773) (xy 96.876362 -264.366248) (xy 98.145358 -264.366248) (xy 98.149318 -264.317194)
			(xy 98.161095 -264.26941) (xy 98.180386 -264.224134) (xy 98.206689 -264.182538) (xy 98.239324 -264.145701)
			(xy 98.277445 -264.114576) (xy 98.320066 -264.089969) (xy 98.366082 -264.072517) (xy 98.414301 -264.062673)
			(xy 98.463476 -264.060692) (xy 98.512331 -264.066624) (xy 98.559602 -264.080316) (xy 98.604064 -264.101414)
			(xy 98.644567 -264.12937) (xy 98.68006 -264.163462) (xy 98.709625 -264.202806) (xy 98.732496 -264.246383)
			(xy 98.74808 -264.293064) (xy 98.755975 -264.341641) (xy 98.75647 -264.366248) (xy 100.025212 -264.366248)
			(xy 100.029172 -264.317194) (xy 100.040949 -264.26941) (xy 100.06024 -264.224134) (xy 100.086543 -264.182538)
			(xy 100.119178 -264.145701) (xy 100.157299 -264.114576) (xy 100.19992 -264.089969) (xy 100.245936 -264.072517)
			(xy 100.294155 -264.062673) (xy 100.34333 -264.060692) (xy 100.392185 -264.066624) (xy 100.439456 -264.080316)
			(xy 100.483918 -264.101414) (xy 100.524421 -264.12937) (xy 100.559914 -264.163462) (xy 100.589479 -264.202806)
			(xy 100.61235 -264.246383) (xy 100.627934 -264.293064) (xy 100.635829 -264.341641) (xy 100.636324 -264.366248)
			(xy 100.965266 -264.366248) (xy 100.969226 -264.317194) (xy 100.981003 -264.26941) (xy 101.000294 -264.224134)
			(xy 101.026597 -264.182538) (xy 101.059232 -264.145701) (xy 101.097353 -264.114576) (xy 101.139974 -264.089969)
			(xy 101.18599 -264.072517) (xy 101.234209 -264.062673) (xy 101.283384 -264.060692) (xy 101.332239 -264.066624)
			(xy 101.37951 -264.080316) (xy 101.423972 -264.101414) (xy 101.464475 -264.12937) (xy 101.499968 -264.163462)
			(xy 101.529533 -264.202806) (xy 101.552404 -264.246383) (xy 101.567988 -264.293064) (xy 101.575883 -264.341641)
			(xy 101.576378 -264.366248) (xy 101.575883 -264.390855) (xy 101.567988 -264.439432) (xy 101.552404 -264.486113)
			(xy 101.529533 -264.52969) (xy 101.499968 -264.569034) (xy 101.464475 -264.603126) (xy 101.423972 -264.631082)
			(xy 101.37951 -264.65218) (xy 101.332239 -264.665872) (xy 101.283384 -264.671804) (xy 101.234209 -264.669823)
			(xy 101.18599 -264.659979) (xy 101.139974 -264.642527) (xy 101.097353 -264.61792) (xy 101.059232 -264.586795)
			(xy 101.026597 -264.549958) (xy 101.000294 -264.508362) (xy 100.981003 -264.463086) (xy 100.969226 -264.415302)
			(xy 100.965266 -264.366248) (xy 100.636324 -264.366248) (xy 100.635829 -264.390855) (xy 100.627934 -264.439432)
			(xy 100.61235 -264.486113) (xy 100.589479 -264.52969) (xy 100.559914 -264.569034) (xy 100.524421 -264.603126)
			(xy 100.483918 -264.631082) (xy 100.439456 -264.65218) (xy 100.392185 -264.665872) (xy 100.34333 -264.671804)
			(xy 100.294155 -264.669823) (xy 100.245936 -264.659979) (xy 100.19992 -264.642527) (xy 100.157299 -264.61792)
			(xy 100.119178 -264.586795) (xy 100.086543 -264.549958) (xy 100.06024 -264.508362) (xy 100.040949 -264.463086)
			(xy 100.029172 -264.415302) (xy 100.025212 -264.366248) (xy 98.75647 -264.366248) (xy 98.755975 -264.390855)
			(xy 98.74808 -264.439432) (xy 98.732496 -264.486113) (xy 98.709625 -264.52969) (xy 98.68006 -264.569034)
			(xy 98.644567 -264.603126) (xy 98.604064 -264.631082) (xy 98.559602 -264.65218) (xy 98.512331 -264.665872)
			(xy 98.463476 -264.671804) (xy 98.414301 -264.669823) (xy 98.366082 -264.659979) (xy 98.320066 -264.642527)
			(xy 98.277445 -264.61792) (xy 98.239324 -264.586795) (xy 98.206689 -264.549958) (xy 98.180386 -264.508362)
			(xy 98.161095 -264.463086) (xy 98.149318 -264.415302) (xy 98.145358 -264.366248) (xy 96.876362 -264.366248)
			(xy 96.875852 -264.390717) (xy 96.867999 -264.439023) (xy 96.852549 -264.485461) (xy 96.829897 -264.528843)
			(xy 96.800622 -264.568061) (xy 96.783398 -264.58545) (xy 96.776286 -264.592308) (xy 96.764602 -264.618978)
			(xy 96.762574 -264.623876) (xy 96.760402 -264.634251) (xy 96.760284 -264.639552) (xy 96.760284 -265.176254)
			(xy 97.675204 -265.176254) (xy 97.679164 -265.1272) (xy 97.690941 -265.079416) (xy 97.710232 -265.03414)
			(xy 97.736535 -264.992544) (xy 97.76917 -264.955707) (xy 97.807291 -264.924582) (xy 97.849912 -264.899975)
			(xy 97.895928 -264.882523) (xy 97.944147 -264.872679) (xy 97.993322 -264.870698) (xy 98.042177 -264.87663)
			(xy 98.089448 -264.890322) (xy 98.13391 -264.91142) (xy 98.174413 -264.939376) (xy 98.209906 -264.973468)
			(xy 98.239471 -265.012812) (xy 98.262342 -265.056389) (xy 98.277926 -265.10307) (xy 98.285821 -265.151647)
			(xy 98.286316 -265.176254) (xy 99.555312 -265.176254) (xy 99.559272 -265.1272) (xy 99.571049 -265.079416)
			(xy 99.59034 -265.03414) (xy 99.616643 -264.992544) (xy 99.649278 -264.955707) (xy 99.687399 -264.924582)
			(xy 99.73002 -264.899975) (xy 99.776036 -264.882523) (xy 99.824255 -264.872679) (xy 99.87343 -264.870698)
			(xy 99.922285 -264.87663) (xy 99.969556 -264.890322) (xy 100.014018 -264.91142) (xy 100.054521 -264.939376)
			(xy 100.090014 -264.973468) (xy 100.119579 -265.012812) (xy 100.14245 -265.056389) (xy 100.158034 -265.10307)
			(xy 100.165929 -265.151647) (xy 100.166424 -265.176254) (xy 100.165929 -265.200861) (xy 100.158034 -265.249438)
			(xy 100.14245 -265.296119) (xy 100.119579 -265.339696) (xy 100.090014 -265.37904) (xy 100.054521 -265.413132)
			(xy 100.014018 -265.441088) (xy 99.969556 -265.462186) (xy 99.922285 -265.475878) (xy 99.87343 -265.48181)
			(xy 99.824255 -265.479829) (xy 99.776036 -265.469985) (xy 99.73002 -265.452533) (xy 99.687399 -265.427926)
			(xy 99.649278 -265.396801) (xy 99.616643 -265.359964) (xy 99.59034 -265.318368) (xy 99.571049 -265.273092)
			(xy 99.559272 -265.225308) (xy 99.555312 -265.176254) (xy 98.286316 -265.176254) (xy 98.285821 -265.200861)
			(xy 98.277926 -265.249438) (xy 98.262342 -265.296119) (xy 98.239471 -265.339696) (xy 98.209906 -265.37904)
			(xy 98.174413 -265.413132) (xy 98.13391 -265.441088) (xy 98.089448 -265.462186) (xy 98.042177 -265.475878)
			(xy 97.993322 -265.48181) (xy 97.944147 -265.479829) (xy 97.895928 -265.469985) (xy 97.849912 -265.452533)
			(xy 97.807291 -265.427926) (xy 97.76917 -265.396801) (xy 97.736535 -265.359964) (xy 97.710232 -265.318368)
			(xy 97.690941 -265.273092) (xy 97.679164 -265.225308) (xy 97.675204 -265.176254) (xy 96.760284 -265.176254)
			(xy 96.760284 -265.712956) (xy 96.76042 -265.718254) (xy 96.762594 -265.728625) (xy 96.764602 -265.73353)
			(xy 96.776286 -265.7602) (xy 96.783398 -265.767058) (xy 96.800654 -265.78442) (xy 96.829957 -265.82363)
			(xy 96.85262 -265.867017) (xy 96.868062 -265.913466) (xy 96.875887 -265.961786) (xy 96.876362 -265.98626)
			(xy 98.145358 -265.98626) (xy 98.149318 -265.937206) (xy 98.161095 -265.889422) (xy 98.180386 -265.844146)
			(xy 98.206689 -265.80255) (xy 98.239324 -265.765713) (xy 98.277445 -265.734588) (xy 98.320066 -265.709981)
			(xy 98.366082 -265.692529) (xy 98.414301 -265.682685) (xy 98.463476 -265.680704) (xy 98.512331 -265.686636)
			(xy 98.559602 -265.700328) (xy 98.604064 -265.721426) (xy 98.644567 -265.749382) (xy 98.68006 -265.783474)
			(xy 98.709625 -265.822818) (xy 98.732496 -265.866395) (xy 98.74808 -265.913076) (xy 98.755975 -265.961653)
			(xy 98.75647 -265.98626) (xy 98.755975 -266.010867) (xy 98.74808 -266.059444) (xy 98.732496 -266.106125)
			(xy 98.709625 -266.149702) (xy 98.68006 -266.189046) (xy 98.644567 -266.223138) (xy 98.604064 -266.251094)
			(xy 98.559602 -266.272192) (xy 98.512331 -266.285884) (xy 98.463476 -266.291816) (xy 98.414301 -266.289835)
			(xy 98.366082 -266.279991) (xy 98.320066 -266.262539) (xy 98.277445 -266.237932) (xy 98.239324 -266.206807)
			(xy 98.206689 -266.16997) (xy 98.180386 -266.128374) (xy 98.161095 -266.083098) (xy 98.149318 -266.035314)
			(xy 98.145358 -265.98626) (xy 96.876362 -265.98626) (xy 96.875851 -266.010729) (xy 96.867996 -266.059034)
			(xy 96.852545 -266.10547) (xy 96.829892 -266.148851) (xy 96.800616 -266.188068) (xy 96.783398 -266.205462)
			(xy 96.776286 -266.21232) (xy 96.764602 -266.23899) (xy 96.762575 -266.243888) (xy 96.760406 -266.254264)
			(xy 96.760284 -266.259564) (xy 96.760284 -266.796266) (xy 97.675204 -266.796266) (xy 97.679164 -266.747212)
			(xy 97.690941 -266.699428) (xy 97.710232 -266.654152) (xy 97.736535 -266.612556) (xy 97.76917 -266.575719)
			(xy 97.807291 -266.544594) (xy 97.849912 -266.519987) (xy 97.895928 -266.502535) (xy 97.944147 -266.492691)
			(xy 97.993322 -266.49071) (xy 98.042177 -266.496642) (xy 98.089448 -266.510334) (xy 98.13391 -266.531432)
			(xy 98.174413 -266.559388) (xy 98.209906 -266.59348) (xy 98.239471 -266.632824) (xy 98.262342 -266.676401)
			(xy 98.277926 -266.723082) (xy 98.285821 -266.771659) (xy 98.286316 -266.796266) (xy 98.615258 -266.796266)
			(xy 98.619218 -266.747212) (xy 98.630995 -266.699428) (xy 98.650286 -266.654152) (xy 98.676589 -266.612556)
			(xy 98.709224 -266.575719) (xy 98.747345 -266.544594) (xy 98.789966 -266.519987) (xy 98.835982 -266.502535)
			(xy 98.884201 -266.492691) (xy 98.933376 -266.49071) (xy 98.982231 -266.496642) (xy 99.029502 -266.510334)
			(xy 99.073964 -266.531432) (xy 99.114467 -266.559388) (xy 99.14996 -266.59348) (xy 99.179525 -266.632824)
			(xy 99.202396 -266.676401) (xy 99.21798 -266.723082) (xy 99.225875 -266.771659) (xy 99.22637 -266.796266)
			(xy 99.225875 -266.820873) (xy 99.21798 -266.86945) (xy 99.202396 -266.916131) (xy 99.179525 -266.959708)
			(xy 99.14996 -266.999052) (xy 99.114467 -267.033144) (xy 99.073964 -267.0611) (xy 99.029502 -267.082198)
			(xy 98.982231 -267.09589) (xy 98.933376 -267.101822) (xy 98.884201 -267.099841) (xy 98.835982 -267.089997)
			(xy 98.789966 -267.072545) (xy 98.747345 -267.047938) (xy 98.709224 -267.016813) (xy 98.676589 -266.979976)
			(xy 98.650286 -266.93838) (xy 98.630995 -266.893104) (xy 98.619218 -266.84532) (xy 98.615258 -266.796266)
			(xy 98.286316 -266.796266) (xy 98.285821 -266.820873) (xy 98.277926 -266.86945) (xy 98.262342 -266.916131)
			(xy 98.239471 -266.959708) (xy 98.209906 -266.999052) (xy 98.174413 -267.033144) (xy 98.13391 -267.0611)
			(xy 98.089448 -267.082198) (xy 98.042177 -267.09589) (xy 97.993322 -267.101822) (xy 97.944147 -267.099841)
			(xy 97.895928 -267.089997) (xy 97.849912 -267.072545) (xy 97.807291 -267.047938) (xy 97.76917 -267.016813)
			(xy 97.736535 -266.979976) (xy 97.710232 -266.93838) (xy 97.690941 -266.893104) (xy 97.679164 -266.84532)
			(xy 97.675204 -266.796266) (xy 96.760284 -266.796266) (xy 96.760284 -266.978892) (xy 96.760705 -266.988963)
			(xy 96.768416 -267.007571) (xy 96.77527 -267.01496) (xy 96.948498 -267.188188) (xy 96.955896 -267.195036)
			(xy 96.974494 -267.202773) (xy 96.984566 -267.203174)
		)
		(stroke
			(width 0)
			(type solid)
		)
		(fill yes)
		(layer "In2.Cu")
		(net "PVDDIO_P1")
	)
	(gr_poly
		(pts
			(xy 347.190568 -267.20292) (xy 347.200406 -267.202385) (xy 347.21857 -267.194801) (xy 347.225874 -267.188188)
			(xy 347.501972 -266.91209) (xy 347.509084 -266.885928) (xy 347.505782 -266.872974) (xy 347.501119 -266.853948)
			(xy 347.496152 -266.815091) (xy 347.495876 -266.795504) (xy 347.495876 -266.793218) (xy 347.496553 -266.769369)
			(xy 347.504402 -266.722312) (xy 347.519474 -266.677048) (xy 347.541403 -266.634679) (xy 347.569655 -266.596236)
			(xy 347.603542 -266.562655) (xy 347.642239 -266.534752) (xy 347.684805 -266.513208) (xy 347.730204 -266.498547)
			(xy 347.77733 -266.491124) (xy 347.801184 -266.490704) (xy 347.820642 -266.491024) (xy 347.859242 -266.495988)
			(xy 347.878146 -266.50061) (xy 347.8911 -266.503912) (xy 347.917262 -266.4968) (xy 348.062804 -266.351258)
			(xy 348.06975 -266.343697) (xy 348.077471 -266.324692) (xy 348.07779 -266.314428) (xy 348.07652 -266.233148)
			(xy 348.068392 -266.214606) (xy 348.060772 -266.207494) (xy 348.04314 -266.190063) (xy 348.013198 -266.150548)
			(xy 347.990026 -266.106718) (xy 347.974231 -266.059723) (xy 347.966229 -266.010795) (xy 347.965776 -265.986006)
			(xy 347.965776 -265.982958) (xy 347.96603 -265.976608) (xy 347.967194 -265.953118) (xy 347.975844 -265.90689)
			(xy 347.991479 -265.862535) (xy 348.013728 -265.8211) (xy 348.042065 -265.783566) (xy 348.075822 -265.75082)
			(xy 348.114199 -265.723635) (xy 348.15629 -265.702655) (xy 348.2011 -265.688375) (xy 348.247569 -265.681132)
			(xy 348.271084 -265.680698) (xy 348.271338 -265.680698) (xy 348.296103 -265.681176) (xy 348.344983 -265.689172)
			(xy 348.391929 -265.704963) (xy 348.435704 -265.728135) (xy 348.475159 -265.758078) (xy 348.492572 -265.775694)
			(xy 348.499684 -265.783314) (xy 348.518226 -265.791442) (xy 348.599506 -265.792712) (xy 348.609764 -265.792389)
			(xy 348.628751 -265.784643) (xy 348.636336 -265.777726) (xy 349.87484 -264.539222) (xy 349.880428 -264.50798)
			(xy 349.873824 -264.493502) (xy 349.865013 -264.473412) (xy 349.852586 -264.431342) (xy 349.846294 -264.387928)
			(xy 349.845884 -264.365994) (xy 349.845884 -264.361168) (xy 349.846712 -264.337428) (xy 349.854812 -264.290623)
			(xy 349.870064 -264.245637) (xy 349.8921 -264.203557) (xy 349.920389 -264.165399) (xy 349.954247 -264.132083)
			(xy 349.992856 -264.104413) (xy 350.035286 -264.083059) (xy 350.080512 -264.068534) (xy 350.127441 -264.061191)
			(xy 350.151192 -264.060686) (xy 350.151446 -264.060686) (xy 350.17334 -264.061076) (xy 350.216673 -264.067369)
			(xy 350.258659 -264.079803) (xy 350.2787 -264.088626) (xy 350.293178 -264.09523) (xy 350.32442 -264.089642)
			(xy 350.456754 -263.957308) (xy 350.46424 -263.949102) (xy 350.471883 -263.928276) (xy 350.471486 -263.917176)
			(xy 350.46412 -263.830562) (xy 350.453198 -263.811512) (xy 350.444054 -263.804908) (xy 350.424565 -263.79046)
			(xy 350.389991 -263.756431) (xy 350.361231 -263.717363) (xy 350.339008 -263.674241) (xy 350.32388 -263.628149)
			(xy 350.316229 -263.580244) (xy 350.315784 -263.555988) (xy 350.316256 -263.531997) (xy 350.323763 -263.484606)
			(xy 350.338591 -263.438974) (xy 350.360375 -263.396222) (xy 350.388579 -263.357404) (xy 350.422507 -263.323476)
			(xy 350.461325 -263.295273) (xy 350.504077 -263.27349) (xy 350.54971 -263.258662) (xy 350.597101 -263.251155)
			(xy 350.621092 -263.25068) (xy 350.645343 -263.251152) (xy 350.693235 -263.258824) (xy 350.739315 -263.273963)
			(xy 350.782426 -263.296187) (xy 350.821487 -263.32494) (xy 350.855519 -263.359499) (xy 350.870012 -263.37895)
			(xy 350.876616 -263.388094) (xy 350.895666 -263.399016) (xy 350.98228 -263.406382) (xy 350.993371 -263.406717)
			(xy 351.014184 -263.399092) (xy 351.022412 -263.39165) (xy 351.719134 -262.694928) (xy 351.727262 -262.684006)
			(xy 351.730564 -262.678418) (xy 351.732342 -262.671814) (xy 351.732342 -262.67156) (xy 351.738582 -262.649156)
			(xy 351.756913 -262.606416) (xy 351.781517 -262.566952) (xy 351.811824 -262.531678) (xy 351.847133 -262.501411)
			(xy 351.886625 -262.476852) (xy 351.929386 -262.458569) (xy 351.951798 -262.452358) (xy 351.958402 -262.45058)
			(xy 351.96399 -262.447278) (xy 351.974912 -262.43915) (xy 352.58502 -261.829042) (xy 352.592261 -261.822335)
			(xy 352.610465 -261.814751) (xy 352.620326 -261.81431) (xy 353.595178 -261.81431) (xy 353.605015 -261.813773)
			(xy 353.623175 -261.806185) (xy 353.630484 -261.799578) (xy 353.77882 -261.651242) (xy 353.786061 -261.644535)
			(xy 353.804265 -261.636951) (xy 353.814126 -261.63651) (xy 354.024184 -261.63651) (xy 354.034084 -261.636033)
			(xy 354.052409 -261.628533) (xy 354.066552 -261.614673) (xy 354.07092 -261.605776) (xy 354.112576 -261.507986)
			(xy 354.107242 -261.478268) (xy 354.096574 -261.467092) (xy 354.078886 -261.447809) (xy 354.048963 -261.404884)
			(xy 354.025897 -261.357917) (xy 354.010221 -261.307995) (xy 354.002298 -261.256273) (xy 354.001832 -261.23011)
			(xy 354.002312 -261.204411) (xy 354.009973 -261.153587) (xy 354.025122 -261.104473) (xy 354.047423 -261.058165)
			(xy 354.076376 -261.015698) (xy 354.111336 -260.978021) (xy 354.15152 -260.945975) (xy 354.196032 -260.920276)
			(xy 354.243877 -260.901499) (xy 354.293986 -260.890061) (xy 354.34524 -260.886221) (xy 354.396494 -260.890061)
			(xy 354.446603 -260.901499) (xy 354.494448 -260.920276) (xy 354.53896 -260.945975) (xy 354.579144 -260.978021)
			(xy 354.614104 -261.015698) (xy 354.643057 -261.058165) (xy 354.665358 -261.104473) (xy 354.680507 -261.153587)
			(xy 354.688168 -261.204411) (xy 354.688648 -261.23011) (xy 354.688158 -261.256271) (xy 354.680229 -261.30799)
			(xy 354.664557 -261.35791) (xy 354.641502 -261.404879) (xy 354.611597 -261.447813) (xy 354.593906 -261.467092)
			(xy 354.583238 -261.478268) (xy 354.577904 -261.507986) (xy 354.61956 -261.605776) (xy 354.6239 -261.61469)
			(xy 354.638041 -261.628557) (xy 354.656391 -261.636012) (xy 354.666296 -261.63651) (xy 355.198934 -261.63651)
			(xy 355.207723 -261.636136) (xy 355.22426 -261.63018) (xy 355.237809 -261.618982) (xy 355.242622 -261.611618)
			(xy 355.292914 -261.526528) (xy 355.293422 -261.499858) (xy 355.286818 -261.48792) (xy 355.273549 -261.462445)
			(xy 355.254747 -261.408175) (xy 355.245212 -261.351537) (xy 355.244654 -261.32282) (xy 355.245134 -261.297121)
			(xy 355.252795 -261.246297) (xy 355.267944 -261.197183) (xy 355.290245 -261.150875) (xy 355.319198 -261.108408)
			(xy 355.354158 -261.070731) (xy 355.394342 -261.038685) (xy 355.438854 -261.012986) (xy 355.486699 -260.994209)
			(xy 355.536808 -260.982771) (xy 355.588062 -260.978931) (xy 355.639316 -260.982771) (xy 355.689425 -260.994209)
			(xy 355.73727 -261.012986) (xy 355.781782 -261.038685) (xy 355.821966 -261.070731) (xy 355.856926 -261.108408)
			(xy 355.885879 -261.150875) (xy 355.90818 -261.197183) (xy 355.923329 -261.246297) (xy 355.93099 -261.297121)
			(xy 355.93147 -261.32282) (xy 355.931021 -261.347904) (xy 355.923745 -261.397542) (xy 355.909335 -261.445597)
			(xy 355.888097 -261.491048) (xy 355.860481 -261.532932) (xy 355.844094 -261.551928) (xy 355.837744 -261.55904)
			(xy 355.83114 -261.576312) (xy 355.83114 -261.58571) (xy 355.831562 -261.595727) (xy 355.839235 -261.614234)
			(xy 355.853408 -261.628393) (xy 355.871923 -261.636048) (xy 355.88194 -261.63651) (xy 355.90988 -261.63651)
			(xy 355.919717 -261.635973) (xy 355.937876 -261.628384) (xy 355.945186 -261.621778) (xy 356.188518 -261.378446)
			(xy 356.196138 -261.358126) (xy 356.195376 -261.34695) (xy 356.194614 -261.324344) (xy 356.194614 -261.32409)
			(xy 356.195004 -261.297692) (xy 356.202892 -261.245493) (xy 356.218664 -261.195112) (xy 356.241951 -261.147733)
			(xy 356.272205 -261.10447) (xy 356.290118 -261.085076) (xy 356.296722 -261.078472) (xy 356.30739 -261.052564)
			(xy 356.309257 -261.047824) (xy 356.311296 -261.037844) (xy 356.311454 -261.032752) (xy 356.311454 -257.544316)
			(xy 356.311014 -257.534254) (xy 356.303273 -257.515676) (xy 356.296468 -257.508248) (xy 355.97084 -257.18262)
			(xy 355.963439 -257.175781) (xy 355.944841 -257.168065) (xy 355.934772 -257.167634) (xy 354.758244 -257.167634)
			(xy 354.745822 -257.168243) (xy 354.723842 -257.179819) (xy 354.716334 -257.189732) (xy 354.663248 -257.267964)
			(xy 354.660454 -257.292856) (xy 354.665026 -257.304794) (xy 354.676048 -257.334919) (xy 354.68794 -257.397946)
			(xy 354.688648 -257.430016) (xy 354.688168 -257.455715) (xy 354.680507 -257.506539) (xy 354.665358 -257.555653)
			(xy 354.643057 -257.601961) (xy 354.614104 -257.644428) (xy 354.579144 -257.682105) (xy 354.53896 -257.714151)
			(xy 354.494448 -257.73985) (xy 354.481387 -257.744976) (xy 355.513897 -257.744976) (xy 355.517927 -257.692478)
			(xy 355.529924 -257.64121) (xy 355.549607 -257.592375) (xy 355.576513 -257.547116) (xy 355.610013 -257.506495)
			(xy 355.649321 -257.471464) (xy 355.693516 -257.442844) (xy 355.741561 -257.421305) (xy 355.792332 -257.407353)
			(xy 355.844637 -257.401315) (xy 355.897251 -257.403332) (xy 355.948941 -257.413356) (xy 355.998494 -257.431154)
			(xy 356.04475 -257.456307) (xy 356.086624 -257.488226) (xy 356.123136 -257.526164) (xy 356.153428 -257.56923)
			(xy 356.176791 -257.616415) (xy 356.192677 -257.666614) (xy 356.200714 -257.71865) (xy 356.201218 -257.744976)
			(xy 356.200714 -257.771302) (xy 356.192677 -257.823338) (xy 356.176791 -257.873537) (xy 356.153428 -257.920722)
			(xy 356.123136 -257.963788) (xy 356.086624 -258.001726) (xy 356.04475 -258.033645) (xy 355.998494 -258.058798)
			(xy 355.948941 -258.076596) (xy 355.897251 -258.08662) (xy 355.844637 -258.088637) (xy 355.792332 -258.082599)
			(xy 355.741561 -258.068647) (xy 355.693516 -258.047108) (xy 355.649321 -258.018488) (xy 355.610013 -257.983457)
			(xy 355.576513 -257.942836) (xy 355.549607 -257.897577) (xy 355.529924 -257.848742) (xy 355.517927 -257.797474)
			(xy 355.513897 -257.744976) (xy 354.481387 -257.744976) (xy 354.446603 -257.758627) (xy 354.396494 -257.770065)
			(xy 354.34524 -257.773906) (xy 354.293986 -257.770065) (xy 354.243877 -257.758627) (xy 354.196032 -257.73985)
			(xy 354.15152 -257.714151) (xy 354.111336 -257.682105) (xy 354.076376 -257.644428) (xy 354.047423 -257.601961)
			(xy 354.025122 -257.555653) (xy 354.009973 -257.506539) (xy 354.002312 -257.455715) (xy 354.001832 -257.430016)
			(xy 354.002544 -257.397946) (xy 354.014429 -257.334917) (xy 354.025454 -257.304794) (xy 354.030026 -257.292856)
			(xy 354.027232 -257.267964) (xy 353.974146 -257.189732) (xy 353.966626 -257.179825) (xy 353.944658 -257.168221)
			(xy 353.932236 -257.167634) (xy 353.81565 -257.167634) (xy 353.805899 -257.167121) (xy 353.787867 -257.159675)
			(xy 353.780598 -257.153156) (xy 353.757992 -257.130296) (xy 353.750593 -257.123451) (xy 353.731995 -257.11572)
			(xy 353.721924 -257.11531) (xy 348.937326 -257.11531) (xy 348.927489 -257.114774) (xy 348.909327 -257.107187)
			(xy 348.90202 -257.100578) (xy 348.169738 -256.368296) (xy 348.162336 -256.36146) (xy 348.143738 -256.353748)
			(xy 348.13367 -256.35331) (xy 347.394276 -256.35331) (xy 347.385636 -256.353644) (xy 347.369341 -256.359392)
			(xy 347.355901 -256.370252) (xy 347.351096 -256.37744) (xy 347.299788 -256.460244) (xy 347.298518 -256.486406)
			(xy 347.30436 -256.498344) (xy 347.314441 -256.519564) (xy 347.32869 -256.564328) (xy 347.33592 -256.610746)
			(xy 347.336364 -256.634234) (xy 347.335842 -256.659489) (xy 347.327529 -256.709311) (xy 347.311128 -256.757085)
			(xy 347.287087 -256.801508) (xy 347.256063 -256.841368) (xy 347.218901 -256.875578) (xy 347.176615 -256.903204)
			(xy 347.130359 -256.923494) (xy 347.081394 -256.935894) (xy 347.031056 -256.940065) (xy 346.980718 -256.935894)
			(xy 346.931753 -256.923494) (xy 346.885497 -256.903204) (xy 346.843211 -256.875578) (xy 346.806049 -256.841368)
			(xy 346.775025 -256.801508) (xy 346.750984 -256.757085) (xy 346.734583 -256.709311) (xy 346.72627 -256.659489)
			(xy 346.725748 -256.634234) (xy 346.726199 -256.610746) (xy 346.733429 -256.56433) (xy 346.747678 -256.519567)
			(xy 346.757752 -256.498344) (xy 346.763594 -256.486406) (xy 346.762324 -256.460244) (xy 346.711016 -256.37744)
			(xy 346.706188 -256.370271) (xy 346.692749 -256.359422) (xy 346.676471 -256.353647) (xy 346.667836 -256.35331)
			(xy 345.514422 -256.35331) (xy 345.505787 -256.353653) (xy 345.489505 -256.359412) (xy 345.47608 -256.370277)
			(xy 345.471242 -256.37744) (xy 345.419934 -256.460244) (xy 345.418664 -256.486406) (xy 345.424506 -256.498344)
			(xy 345.434589 -256.519563) (xy 345.44884 -256.564327) (xy 345.456072 -256.610745) (xy 345.45651 -256.634234)
			(xy 345.455988 -256.659489) (xy 345.447675 -256.709311) (xy 345.431274 -256.757085) (xy 345.407233 -256.801508)
			(xy 345.376209 -256.841368) (xy 345.339047 -256.875578) (xy 345.296761 -256.903204) (xy 345.250505 -256.923494)
			(xy 345.20154 -256.935894) (xy 345.151202 -256.940065) (xy 345.100864 -256.935894) (xy 345.051899 -256.923494)
			(xy 345.005643 -256.903204) (xy 344.963357 -256.875578) (xy 344.926195 -256.841368) (xy 344.895171 -256.801508)
			(xy 344.87113 -256.757085) (xy 344.854729 -256.709311) (xy 344.846416 -256.659489) (xy 344.845894 -256.634234)
			(xy 344.846345 -256.610746) (xy 344.853574 -256.564329) (xy 344.86782 -256.519565) (xy 344.877898 -256.498344)
			(xy 344.88374 -256.486406) (xy 344.88247 -256.460244) (xy 344.831162 -256.37744) (xy 344.826337 -256.370266)
			(xy 344.812899 -256.359405) (xy 344.79662 -256.353616) (xy 344.787982 -256.35331) (xy 344.238326 -256.35331)
			(xy 344.228489 -256.353847) (xy 344.21033 -256.361436) (xy 344.20302 -256.368042) (xy 343.571068 -256.999994)
			(xy 343.563668 -257.006836) (xy 343.54507 -257.01456) (xy 343.535 -257.01498) (xy 342.757506 -257.01498)
			(xy 342.747606 -257.015498) (xy 342.729308 -257.023074) (xy 342.721946 -257.029712) (xy 342.697872 -257.052802)
			(xy 342.645148 -257.093669) (xy 342.587915 -257.127937) (xy 342.526994 -257.155113) (xy 342.46326 -257.174809)
			(xy 342.397628 -257.18674) (xy 342.33104 -257.190737) (xy 342.264452 -257.18674) (xy 342.19882 -257.174809)
			(xy 342.135086 -257.155113) (xy 342.074165 -257.127937) (xy 342.016932 -257.093669) (xy 341.964208 -257.052802)
			(xy 341.940134 -257.029712) (xy 341.93278 -257.023057) (xy 341.914479 -257.015463) (xy 341.904574 -257.01498)
			(xy 328.189082 -257.01498) (xy 328.179013 -257.015406) (xy 328.160411 -257.023123) (xy 328.153014 -257.029966)
			(xy 328.050906 -257.132074) (xy 328.044071 -257.139476) (xy 328.036362 -257.158075) (xy 328.03592 -257.168142)
			(xy 328.03592 -257.930142) (xy 346.651329 -257.930142) (xy 346.655359 -257.877644) (xy 346.667356 -257.826376)
			(xy 346.687039 -257.777541) (xy 346.713945 -257.732282) (xy 346.747445 -257.691661) (xy 346.786753 -257.65663)
			(xy 346.830948 -257.62801) (xy 346.878993 -257.606471) (xy 346.929764 -257.592519) (xy 346.982069 -257.586481)
			(xy 347.034683 -257.588498) (xy 347.086373 -257.598522) (xy 347.135926 -257.61632) (xy 347.182182 -257.641473)
			(xy 347.224056 -257.673392) (xy 347.260568 -257.71133) (xy 347.29086 -257.754396) (xy 347.314223 -257.801581)
			(xy 347.330109 -257.85178) (xy 347.338146 -257.903816) (xy 347.33865 -257.930142) (xy 348.551249 -257.930142)
			(xy 348.555279 -257.877644) (xy 348.567276 -257.826376) (xy 348.586959 -257.777541) (xy 348.613865 -257.732282)
			(xy 348.647365 -257.691661) (xy 348.686673 -257.65663) (xy 348.730868 -257.62801) (xy 348.778913 -257.606471)
			(xy 348.829684 -257.592519) (xy 348.881989 -257.586481) (xy 348.934603 -257.588498) (xy 348.986293 -257.598522)
			(xy 349.035846 -257.61632) (xy 349.082102 -257.641473) (xy 349.123976 -257.673392) (xy 349.160488 -257.71133)
			(xy 349.19078 -257.754396) (xy 349.214143 -257.801581) (xy 349.230029 -257.85178) (xy 349.238066 -257.903816)
			(xy 349.23857 -257.930142) (xy 350.451169 -257.930142) (xy 350.455199 -257.877644) (xy 350.467196 -257.826376)
			(xy 350.486879 -257.777541) (xy 350.513785 -257.732282) (xy 350.547285 -257.691661) (xy 350.586593 -257.65663)
			(xy 350.630788 -257.62801) (xy 350.678833 -257.606471) (xy 350.729604 -257.592519) (xy 350.781909 -257.586481)
			(xy 350.834523 -257.588498) (xy 350.886213 -257.598522) (xy 350.935766 -257.61632) (xy 350.982022 -257.641473)
			(xy 351.023896 -257.673392) (xy 351.060408 -257.71133) (xy 351.0907 -257.754396) (xy 351.114063 -257.801581)
			(xy 351.129949 -257.85178) (xy 351.137986 -257.903816) (xy 351.13849 -257.930142) (xy 351.137986 -257.956468)
			(xy 351.129949 -258.008504) (xy 351.114063 -258.058703) (xy 351.0907 -258.105888) (xy 351.060408 -258.148954)
			(xy 351.023896 -258.186892) (xy 350.982022 -258.218811) (xy 350.935766 -258.243964) (xy 350.886213 -258.261762)
			(xy 350.834523 -258.271786) (xy 350.781909 -258.273803) (xy 350.729604 -258.267765) (xy 350.678833 -258.253813)
			(xy 350.630788 -258.232274) (xy 350.586593 -258.203654) (xy 350.547285 -258.168623) (xy 350.513785 -258.128002)
			(xy 350.486879 -258.082743) (xy 350.467196 -258.033908) (xy 350.455199 -257.98264) (xy 350.451169 -257.930142)
			(xy 349.23857 -257.930142) (xy 349.238066 -257.956468) (xy 349.230029 -258.008504) (xy 349.214143 -258.058703)
			(xy 349.19078 -258.105888) (xy 349.160488 -258.148954) (xy 349.123976 -258.186892) (xy 349.082102 -258.218811)
			(xy 349.035846 -258.243964) (xy 348.986293 -258.261762) (xy 348.934603 -258.271786) (xy 348.881989 -258.273803)
			(xy 348.829684 -258.267765) (xy 348.778913 -258.253813) (xy 348.730868 -258.232274) (xy 348.686673 -258.203654)
			(xy 348.647365 -258.168623) (xy 348.613865 -258.128002) (xy 348.586959 -258.082743) (xy 348.567276 -258.033908)
			(xy 348.555279 -257.98264) (xy 348.551249 -257.930142) (xy 347.33865 -257.930142) (xy 347.338146 -257.956468)
			(xy 347.330109 -258.008504) (xy 347.314223 -258.058703) (xy 347.29086 -258.105888) (xy 347.260568 -258.148954)
			(xy 347.224056 -258.186892) (xy 347.182182 -258.218811) (xy 347.135926 -258.243964) (xy 347.086373 -258.261762)
			(xy 347.034683 -258.271786) (xy 346.982069 -258.273803) (xy 346.929764 -258.267765) (xy 346.878993 -258.253813)
			(xy 346.830948 -258.232274) (xy 346.786753 -258.203654) (xy 346.747445 -258.168623) (xy 346.713945 -258.128002)
			(xy 346.687039 -258.082743) (xy 346.667356 -258.033908) (xy 346.655359 -257.98264) (xy 346.651329 -257.930142)
			(xy 328.03592 -257.930142) (xy 328.03592 -258.379976) (xy 354.001327 -258.379976) (xy 354.005357 -258.327478)
			(xy 354.017354 -258.27621) (xy 354.037037 -258.227375) (xy 354.063943 -258.182116) (xy 354.097443 -258.141495)
			(xy 354.136751 -258.106464) (xy 354.180946 -258.077844) (xy 354.228991 -258.056305) (xy 354.279762 -258.042353)
			(xy 354.332067 -258.036315) (xy 354.384681 -258.038332) (xy 354.436371 -258.048356) (xy 354.485924 -258.066154)
			(xy 354.53218 -258.091307) (xy 354.574054 -258.123226) (xy 354.610566 -258.161164) (xy 354.640858 -258.20423)
			(xy 354.664221 -258.251415) (xy 354.680107 -258.301614) (xy 354.688144 -258.35365) (xy 354.688648 -258.379976)
			(xy 354.688144 -258.406302) (xy 354.680107 -258.458338) (xy 354.664221 -258.508537) (xy 354.640858 -258.555722)
			(xy 354.610566 -258.598788) (xy 354.574054 -258.636726) (xy 354.53218 -258.668645) (xy 354.485924 -258.693798)
			(xy 354.436371 -258.711596) (xy 354.384681 -258.72162) (xy 354.332067 -258.723637) (xy 354.279762 -258.717599)
			(xy 354.228991 -258.703647) (xy 354.180946 -258.682108) (xy 354.136751 -258.653488) (xy 354.097443 -258.618457)
			(xy 354.063943 -258.577836) (xy 354.037037 -258.532577) (xy 354.017354 -258.483742) (xy 354.005357 -258.432474)
			(xy 354.001327 -258.379976) (xy 328.03592 -258.379976) (xy 328.03592 -258.830064) (xy 346.651329 -258.830064)
			(xy 346.655359 -258.777566) (xy 346.667356 -258.726298) (xy 346.687039 -258.677463) (xy 346.713945 -258.632204)
			(xy 346.747445 -258.591583) (xy 346.786753 -258.556552) (xy 346.830948 -258.527932) (xy 346.878993 -258.506393)
			(xy 346.929764 -258.492441) (xy 346.982069 -258.486403) (xy 347.034683 -258.48842) (xy 347.086373 -258.498444)
			(xy 347.135926 -258.516242) (xy 347.182182 -258.541395) (xy 347.224056 -258.573314) (xy 347.260568 -258.611252)
			(xy 347.29086 -258.654318) (xy 347.314223 -258.701503) (xy 347.330109 -258.751702) (xy 347.338146 -258.803738)
			(xy 347.33865 -258.830064) (xy 348.551249 -258.830064) (xy 348.555279 -258.777566) (xy 348.567276 -258.726298)
			(xy 348.586959 -258.677463) (xy 348.613865 -258.632204) (xy 348.647365 -258.591583) (xy 348.686673 -258.556552)
			(xy 348.730868 -258.527932) (xy 348.778913 -258.506393) (xy 348.829684 -258.492441) (xy 348.881989 -258.486403)
			(xy 348.934603 -258.48842) (xy 348.986293 -258.498444) (xy 349.035846 -258.516242) (xy 349.082102 -258.541395)
			(xy 349.123976 -258.573314) (xy 349.160488 -258.611252) (xy 349.19078 -258.654318) (xy 349.214143 -258.701503)
			(xy 349.230029 -258.751702) (xy 349.238066 -258.803738) (xy 349.23857 -258.830064) (xy 350.451169 -258.830064)
			(xy 350.455199 -258.777566) (xy 350.467196 -258.726298) (xy 350.486879 -258.677463) (xy 350.513785 -258.632204)
			(xy 350.547285 -258.591583) (xy 350.586593 -258.556552) (xy 350.630788 -258.527932) (xy 350.678833 -258.506393)
			(xy 350.729604 -258.492441) (xy 350.781909 -258.486403) (xy 350.834523 -258.48842) (xy 350.886213 -258.498444)
			(xy 350.935766 -258.516242) (xy 350.982022 -258.541395) (xy 351.023896 -258.573314) (xy 351.060408 -258.611252)
			(xy 351.0907 -258.654318) (xy 351.114063 -258.701503) (xy 351.129949 -258.751702) (xy 351.137986 -258.803738)
			(xy 351.13849 -258.830064) (xy 351.137986 -258.85639) (xy 351.129949 -258.908426) (xy 351.114063 -258.958625)
			(xy 351.0907 -259.00581) (xy 351.060408 -259.048876) (xy 351.023896 -259.086814) (xy 350.982022 -259.118733)
			(xy 350.935766 -259.143886) (xy 350.886213 -259.161684) (xy 350.834523 -259.171708) (xy 350.781909 -259.173725)
			(xy 350.729604 -259.167687) (xy 350.678833 -259.153735) (xy 350.630788 -259.132196) (xy 350.586593 -259.103576)
			(xy 350.547285 -259.068545) (xy 350.513785 -259.027924) (xy 350.486879 -258.982665) (xy 350.467196 -258.93383)
			(xy 350.455199 -258.882562) (xy 350.451169 -258.830064) (xy 349.23857 -258.830064) (xy 349.238066 -258.85639)
			(xy 349.230029 -258.908426) (xy 349.214143 -258.958625) (xy 349.19078 -259.00581) (xy 349.160488 -259.048876)
			(xy 349.123976 -259.086814) (xy 349.082102 -259.118733) (xy 349.035846 -259.143886) (xy 348.986293 -259.161684)
			(xy 348.934603 -259.171708) (xy 348.881989 -259.173725) (xy 348.829684 -259.167687) (xy 348.778913 -259.153735)
			(xy 348.730868 -259.132196) (xy 348.686673 -259.103576) (xy 348.647365 -259.068545) (xy 348.613865 -259.027924)
			(xy 348.586959 -258.982665) (xy 348.567276 -258.93383) (xy 348.555279 -258.882562) (xy 348.551249 -258.830064)
			(xy 347.33865 -258.830064) (xy 347.338146 -258.85639) (xy 347.330109 -258.908426) (xy 347.314223 -258.958625)
			(xy 347.29086 -259.00581) (xy 347.260568 -259.048876) (xy 347.224056 -259.086814) (xy 347.182182 -259.118733)
			(xy 347.135926 -259.143886) (xy 347.086373 -259.161684) (xy 347.034683 -259.171708) (xy 346.982069 -259.173725)
			(xy 346.929764 -259.167687) (xy 346.878993 -259.153735) (xy 346.830948 -259.132196) (xy 346.786753 -259.103576)
			(xy 346.747445 -259.068545) (xy 346.713945 -259.027924) (xy 346.687039 -258.982665) (xy 346.667356 -258.93383)
			(xy 346.655359 -258.882562) (xy 346.651329 -258.830064) (xy 328.03592 -258.830064) (xy 328.03592 -259.33019)
			(xy 354.001327 -259.33019) (xy 354.005357 -259.277692) (xy 354.017354 -259.226424) (xy 354.037037 -259.177589)
			(xy 354.063943 -259.13233) (xy 354.097443 -259.091709) (xy 354.136751 -259.056678) (xy 354.180946 -259.028058)
			(xy 354.228991 -259.006519) (xy 354.279762 -258.992567) (xy 354.332067 -258.986529) (xy 354.384681 -258.988546)
			(xy 354.436371 -258.99857) (xy 354.485924 -259.016368) (xy 354.53218 -259.041521) (xy 354.574054 -259.07344)
			(xy 354.610566 -259.111378) (xy 354.640858 -259.154444) (xy 354.664221 -259.201629) (xy 354.680107 -259.251828)
			(xy 354.688144 -259.303864) (xy 354.688648 -259.33019) (xy 354.688144 -259.356516) (xy 354.680107 -259.408552)
			(xy 354.664221 -259.458751) (xy 354.640858 -259.505936) (xy 354.610566 -259.549002) (xy 354.574054 -259.58694)
			(xy 354.53218 -259.618859) (xy 354.485924 -259.644012) (xy 354.436371 -259.66181) (xy 354.384681 -259.671834)
			(xy 354.332067 -259.673851) (xy 354.279762 -259.667813) (xy 354.228991 -259.653861) (xy 354.180946 -259.632322)
			(xy 354.136751 -259.603702) (xy 354.097443 -259.568671) (xy 354.063943 -259.52805) (xy 354.037037 -259.482791)
			(xy 354.017354 -259.433956) (xy 354.005357 -259.382688) (xy 354.001327 -259.33019) (xy 328.03592 -259.33019)
			(xy 328.03592 -259.729986) (xy 346.651329 -259.729986) (xy 346.655359 -259.677488) (xy 346.667356 -259.62622)
			(xy 346.687039 -259.577385) (xy 346.713945 -259.532126) (xy 346.747445 -259.491505) (xy 346.786753 -259.456474)
			(xy 346.830948 -259.427854) (xy 346.878993 -259.406315) (xy 346.929764 -259.392363) (xy 346.982069 -259.386325)
			(xy 347.034683 -259.388342) (xy 347.086373 -259.398366) (xy 347.135926 -259.416164) (xy 347.182182 -259.441317)
			(xy 347.224056 -259.473236) (xy 347.260568 -259.511174) (xy 347.29086 -259.55424) (xy 347.314223 -259.601425)
			(xy 347.330109 -259.651624) (xy 347.338146 -259.70366) (xy 347.33865 -259.729986) (xy 348.551249 -259.729986)
			(xy 348.555279 -259.677488) (xy 348.567276 -259.62622) (xy 348.586959 -259.577385) (xy 348.613865 -259.532126)
			(xy 348.647365 -259.491505) (xy 348.686673 -259.456474) (xy 348.730868 -259.427854) (xy 348.778913 -259.406315)
			(xy 348.829684 -259.392363) (xy 348.881989 -259.386325) (xy 348.934603 -259.388342) (xy 348.986293 -259.398366)
			(xy 349.035846 -259.416164) (xy 349.082102 -259.441317) (xy 349.123976 -259.473236) (xy 349.160488 -259.511174)
			(xy 349.19078 -259.55424) (xy 349.214143 -259.601425) (xy 349.230029 -259.651624) (xy 349.238066 -259.70366)
			(xy 349.23857 -259.729986) (xy 350.451169 -259.729986) (xy 350.455199 -259.677488) (xy 350.467196 -259.62622)
			(xy 350.486879 -259.577385) (xy 350.513785 -259.532126) (xy 350.547285 -259.491505) (xy 350.586593 -259.456474)
			(xy 350.630788 -259.427854) (xy 350.678833 -259.406315) (xy 350.729604 -259.392363) (xy 350.781909 -259.386325)
			(xy 350.834523 -259.388342) (xy 350.886213 -259.398366) (xy 350.935766 -259.416164) (xy 350.982022 -259.441317)
			(xy 351.023896 -259.473236) (xy 351.060408 -259.511174) (xy 351.0907 -259.55424) (xy 351.114063 -259.601425)
			(xy 351.129949 -259.651624) (xy 351.137986 -259.70366) (xy 351.13849 -259.729986) (xy 351.137986 -259.756312)
			(xy 351.129949 -259.808348) (xy 351.114063 -259.858547) (xy 351.0907 -259.905732) (xy 351.060408 -259.948798)
			(xy 351.023896 -259.986736) (xy 350.982022 -260.018655) (xy 350.935766 -260.043808) (xy 350.886213 -260.061606)
			(xy 350.834523 -260.07163) (xy 350.781909 -260.073647) (xy 350.729604 -260.067609) (xy 350.678833 -260.053657)
			(xy 350.630788 -260.032118) (xy 350.586593 -260.003498) (xy 350.547285 -259.968467) (xy 350.513785 -259.927846)
			(xy 350.486879 -259.882587) (xy 350.467196 -259.833752) (xy 350.455199 -259.782484) (xy 350.451169 -259.729986)
			(xy 349.23857 -259.729986) (xy 349.238066 -259.756312) (xy 349.230029 -259.808348) (xy 349.214143 -259.858547)
			(xy 349.19078 -259.905732) (xy 349.160488 -259.948798) (xy 349.123976 -259.986736) (xy 349.082102 -260.018655)
			(xy 349.035846 -260.043808) (xy 348.986293 -260.061606) (xy 348.934603 -260.07163) (xy 348.881989 -260.073647)
			(xy 348.829684 -260.067609) (xy 348.778913 -260.053657) (xy 348.730868 -260.032118) (xy 348.686673 -260.003498)
			(xy 348.647365 -259.968467) (xy 348.613865 -259.927846) (xy 348.586959 -259.882587) (xy 348.567276 -259.833752)
			(xy 348.555279 -259.782484) (xy 348.551249 -259.729986) (xy 347.33865 -259.729986) (xy 347.338146 -259.756312)
			(xy 347.330109 -259.808348) (xy 347.314223 -259.858547) (xy 347.29086 -259.905732) (xy 347.260568 -259.948798)
			(xy 347.224056 -259.986736) (xy 347.182182 -260.018655) (xy 347.135926 -260.043808) (xy 347.086373 -260.061606)
			(xy 347.034683 -260.07163) (xy 346.982069 -260.073647) (xy 346.929764 -260.067609) (xy 346.878993 -260.053657)
			(xy 346.830948 -260.032118) (xy 346.786753 -260.003498) (xy 346.747445 -259.968467) (xy 346.713945 -259.927846)
			(xy 346.687039 -259.882587) (xy 346.667356 -259.833752) (xy 346.655359 -259.782484) (xy 346.651329 -259.729986)
			(xy 328.03592 -259.729986) (xy 328.03592 -260.28015) (xy 354.001327 -260.28015) (xy 354.005357 -260.227652)
			(xy 354.017354 -260.176384) (xy 354.037037 -260.127549) (xy 354.063943 -260.08229) (xy 354.097443 -260.041669)
			(xy 354.136751 -260.006638) (xy 354.180946 -259.978018) (xy 354.228991 -259.956479) (xy 354.279762 -259.942527)
			(xy 354.332067 -259.936489) (xy 354.384681 -259.938506) (xy 354.436371 -259.94853) (xy 354.485924 -259.966328)
			(xy 354.53218 -259.991481) (xy 354.574054 -260.0234) (xy 354.610566 -260.061338) (xy 354.640858 -260.104404)
			(xy 354.664221 -260.151589) (xy 354.680107 -260.201788) (xy 354.688144 -260.253824) (xy 354.688648 -260.28015)
			(xy 354.688144 -260.306476) (xy 354.680107 -260.358512) (xy 354.664221 -260.408711) (xy 354.640858 -260.455896)
			(xy 354.610566 -260.498962) (xy 354.574054 -260.5369) (xy 354.53218 -260.568819) (xy 354.485924 -260.593972)
			(xy 354.436371 -260.61177) (xy 354.384681 -260.621794) (xy 354.332067 -260.623811) (xy 354.279762 -260.617773)
			(xy 354.228991 -260.603821) (xy 354.180946 -260.582282) (xy 354.136751 -260.553662) (xy 354.097443 -260.518631)
			(xy 354.063943 -260.47801) (xy 354.037037 -260.432751) (xy 354.017354 -260.383916) (xy 354.005357 -260.332648)
			(xy 354.001327 -260.28015) (xy 328.03592 -260.28015) (xy 328.03592 -261.250938) (xy 328.036351 -261.261005)
			(xy 328.044077 -261.279597) (xy 328.050906 -261.287006) (xy 328.216514 -261.452614) (xy 328.223909 -261.459468)
			(xy 328.242508 -261.46721) (xy 328.252582 -261.4676) (xy 329.142344 -261.4676) (xy 329.151711 -261.467221)
			(xy 329.169219 -261.460566) (xy 329.183155 -261.448053) (xy 329.18781 -261.439914) (xy 329.235308 -261.346188)
			(xy 329.233022 -261.31774) (xy 329.224386 -261.306056) (xy 329.210539 -261.286339) (xy 329.188585 -261.243453)
			(xy 329.173656 -261.197646) (xy 329.166123 -261.15006) (xy 329.165712 -261.12597) (xy 329.166234 -261.100715)
			(xy 329.174547 -261.050893) (xy 329.190948 -261.003119) (xy 329.214989 -260.958696) (xy 329.246013 -260.918836)
			(xy 329.283175 -260.884626) (xy 329.325461 -260.857) (xy 329.371717 -260.83671) (xy 329.420682 -260.82431)
			(xy 329.47102 -260.820139) (xy 329.521358 -260.82431) (xy 329.570323 -260.83671) (xy 329.616579 -260.857)
			(xy 329.658865 -260.884626) (xy 329.696027 -260.918836) (xy 329.727051 -260.958696) (xy 329.751092 -261.003119)
			(xy 329.767493 -261.050893) (xy 329.775806 -261.100715) (xy 329.776328 -261.12597) (xy 329.775865 -261.150054)
			(xy 329.768296 -261.197623) (xy 329.75337 -261.24342) (xy 329.731456 -261.286314) (xy 329.717654 -261.306056)
			(xy 329.709018 -261.31774) (xy 329.706732 -261.346188) (xy 329.75423 -261.439914) (xy 329.758876 -261.448053)
			(xy 329.772829 -261.46054) (xy 329.790332 -261.46719) (xy 329.799696 -261.4676) (xy 330.082398 -261.4676)
			(xy 330.09177 -261.467229) (xy 330.10929 -261.460584) (xy 330.12324 -261.448073) (xy 330.127864 -261.439914)
			(xy 330.175362 -261.346188) (xy 330.173076 -261.31774) (xy 330.16444 -261.306056) (xy 330.150595 -261.286338)
			(xy 330.128644 -261.243451) (xy 330.113717 -261.197645) (xy 330.106186 -261.150059) (xy 330.105766 -261.12597)
			(xy 330.106288 -261.100715) (xy 330.114601 -261.050893) (xy 330.131002 -261.003119) (xy 330.155043 -260.958696)
			(xy 330.186067 -260.918836) (xy 330.223229 -260.884626) (xy 330.265515 -260.857) (xy 330.311771 -260.83671)
			(xy 330.360736 -260.82431) (xy 330.411074 -260.820139) (xy 330.461412 -260.82431) (xy 330.510377 -260.83671)
			(xy 330.556633 -260.857) (xy 330.598919 -260.884626) (xy 330.636081 -260.918836) (xy 330.667105 -260.958696)
			(xy 330.691146 -261.003119) (xy 330.707547 -261.050893) (xy 330.71586 -261.100715) (xy 330.716382 -261.12597)
			(xy 330.715919 -261.150053) (xy 330.708349 -261.197622) (xy 330.693421 -261.243418) (xy 330.671505 -261.28631)
			(xy 330.657708 -261.306056) (xy 330.649072 -261.31774) (xy 330.646786 -261.346188) (xy 330.694284 -261.439914)
			(xy 330.698928 -261.448058) (xy 330.712878 -261.460558) (xy 330.730383 -261.467223) (xy 330.73975 -261.4676)
			(xy 331.022452 -261.4676) (xy 331.031818 -261.46722) (xy 331.049324 -261.460563) (xy 331.063258 -261.44805)
			(xy 331.067918 -261.439914) (xy 331.115416 -261.346188) (xy 331.11313 -261.31774) (xy 331.104494 -261.306056)
			(xy 331.090647 -261.286339) (xy 331.068692 -261.243453) (xy 331.053762 -261.197646) (xy 331.04623 -261.15006)
			(xy 331.04582 -261.12597) (xy 331.046342 -261.100715) (xy 331.054655 -261.050893) (xy 331.071056 -261.003119)
			(xy 331.095097 -260.958696) (xy 331.126121 -260.918836) (xy 331.163283 -260.884626) (xy 331.205569 -260.857)
			(xy 331.251825 -260.83671) (xy 331.30079 -260.82431) (xy 331.351128 -260.820139) (xy 331.401466 -260.82431)
			(xy 331.450431 -260.83671) (xy 331.496687 -260.857) (xy 331.538973 -260.884626) (xy 331.576135 -260.918836)
			(xy 331.607159 -260.958696) (xy 331.6312 -261.003119) (xy 331.647601 -261.050893) (xy 331.655914 -261.100715)
			(xy 331.656436 -261.12597) (xy 331.655973 -261.150053) (xy 331.648401 -261.197621) (xy 331.633472 -261.243416)
			(xy 331.611553 -261.286306) (xy 331.597762 -261.306056) (xy 331.589126 -261.31774) (xy 331.58684 -261.346188)
			(xy 331.634338 -261.439914) (xy 331.638985 -261.448052) (xy 331.652937 -261.460537) (xy 331.670441 -261.467184)
			(xy 331.679804 -261.4676) (xy 331.962506 -261.4676) (xy 331.971877 -261.467228) (xy 331.989395 -261.460581)
			(xy 332.003343 -261.44807) (xy 332.007972 -261.439914) (xy 332.05547 -261.346188) (xy 332.053184 -261.31774)
			(xy 332.044548 -261.306056) (xy 332.030703 -261.286338) (xy 332.008751 -261.243452) (xy 331.993824 -261.197645)
			(xy 331.986292 -261.150059) (xy 331.985874 -261.12597) (xy 331.986396 -261.100715) (xy 331.994709 -261.050893)
			(xy 332.01111 -261.003119) (xy 332.035151 -260.958696) (xy 332.066175 -260.918836) (xy 332.103337 -260.884626)
			(xy 332.145623 -260.857) (xy 332.191879 -260.83671) (xy 332.240844 -260.82431) (xy 332.291182 -260.820139)
			(xy 332.34152 -260.82431) (xy 332.390485 -260.83671) (xy 332.436741 -260.857) (xy 332.479027 -260.884626)
			(xy 332.516189 -260.918836) (xy 332.547213 -260.958696) (xy 332.571254 -261.003119) (xy 332.587655 -261.050893)
			(xy 332.595968 -261.100715) (xy 332.59649 -261.12597) (xy 332.596027 -261.150053) (xy 332.588457 -261.197622)
			(xy 332.573529 -261.243418) (xy 332.551614 -261.286311) (xy 332.537816 -261.306056) (xy 332.52918 -261.31774)
			(xy 332.526894 -261.346188) (xy 332.574392 -261.439914) (xy 332.579036 -261.448057) (xy 332.592987 -261.460555)
			(xy 332.610492 -261.467217) (xy 332.619858 -261.4676) (xy 332.902306 -261.4676) (xy 332.911677 -261.467228)
			(xy 332.929195 -261.460581) (xy 332.943143 -261.44807) (xy 332.947772 -261.439914) (xy 332.99527 -261.346188)
			(xy 332.992984 -261.31774) (xy 332.984348 -261.306056) (xy 332.970503 -261.286338) (xy 332.948551 -261.243452)
			(xy 332.933624 -261.197645) (xy 332.926092 -261.150059) (xy 332.925674 -261.12597) (xy 332.926196 -261.100715)
			(xy 332.934509 -261.050893) (xy 332.95091 -261.003119) (xy 332.974951 -260.958696) (xy 333.005975 -260.918836)
			(xy 333.043137 -260.884626) (xy 333.085423 -260.857) (xy 333.131679 -260.83671) (xy 333.180644 -260.82431)
			(xy 333.230982 -260.820139) (xy 333.28132 -260.82431) (xy 333.330285 -260.83671) (xy 333.376541 -260.857)
			(xy 333.418827 -260.884626) (xy 333.455989 -260.918836) (xy 333.487013 -260.958696) (xy 333.511054 -261.003119)
			(xy 333.527455 -261.050893) (xy 333.535768 -261.100715) (xy 333.53629 -261.12597) (xy 333.535827 -261.150053)
			(xy 333.528257 -261.197622) (xy 333.513329 -261.243418) (xy 333.491414 -261.286311) (xy 333.477616 -261.306056)
			(xy 333.46898 -261.31774) (xy 333.466694 -261.346188) (xy 333.514192 -261.439914) (xy 333.518836 -261.448057)
			(xy 333.532787 -261.460555) (xy 333.550292 -261.467217) (xy 333.559658 -261.4676) (xy 333.84236 -261.4676)
			(xy 333.851725 -261.467219) (xy 333.869228 -261.46056) (xy 333.883161 -261.448046) (xy 333.887826 -261.439914)
			(xy 333.935324 -261.346188) (xy 333.933038 -261.31774) (xy 333.924402 -261.306056) (xy 333.910555 -261.286339)
			(xy 333.888599 -261.243453) (xy 333.873669 -261.197646) (xy 333.866136 -261.15006) (xy 333.865728 -261.12597)
			(xy 333.86625 -261.100715) (xy 333.874563 -261.050893) (xy 333.890964 -261.003119) (xy 333.915005 -260.958696)
			(xy 333.946029 -260.918836) (xy 333.983191 -260.884626) (xy 334.025477 -260.857) (xy 334.071733 -260.83671)
			(xy 334.120698 -260.82431) (xy 334.171036 -260.820139) (xy 334.221374 -260.82431) (xy 334.270339 -260.83671)
			(xy 334.316595 -260.857) (xy 334.358881 -260.884626) (xy 334.396043 -260.918836) (xy 334.427067 -260.958696)
			(xy 334.451108 -261.003119) (xy 334.467509 -261.050893) (xy 334.475822 -261.100715) (xy 334.476344 -261.12597)
			(xy 334.475881 -261.150053) (xy 334.46831 -261.197621) (xy 334.45338 -261.243416) (xy 334.431462 -261.286307)
			(xy 334.41767 -261.306056) (xy 334.409034 -261.31774) (xy 334.406748 -261.346188) (xy 334.454246 -261.439914)
			(xy 334.458893 -261.448051) (xy 334.472846 -261.460534) (xy 334.490349 -261.467179) (xy 334.499712 -261.4676)
			(xy 335.722468 -261.4676) (xy 335.731833 -261.467217) (xy 335.749333 -261.460557) (xy 335.763263 -261.448043)
			(xy 335.767934 -261.439914) (xy 335.815432 -261.346188) (xy 335.813146 -261.31774) (xy 335.80451 -261.306056)
			(xy 335.790666 -261.286337) (xy 335.768718 -261.243451) (xy 335.753792 -261.197644) (xy 335.746262 -261.150059)
			(xy 335.745836 -261.12597) (xy 335.746358 -261.100715) (xy 335.754671 -261.050893) (xy 335.771072 -261.003119)
			(xy 335.795113 -260.958696) (xy 335.826137 -260.918836) (xy 335.863299 -260.884626) (xy 335.905585 -260.857)
			(xy 335.951841 -260.83671) (xy 336.000806 -260.82431) (xy 336.051144 -260.820139) (xy 336.101482 -260.82431)
			(xy 336.150447 -260.83671) (xy 336.196703 -260.857) (xy 336.238989 -260.884626) (xy 336.276151 -260.918836)
			(xy 336.307175 -260.958696) (xy 336.331216 -261.003119) (xy 336.347617 -261.050893) (xy 336.35593 -261.100715)
			(xy 336.356452 -261.12597) (xy 336.355989 -261.150053) (xy 336.348418 -261.197621) (xy 336.333489 -261.243416)
			(xy 336.311571 -261.286308) (xy 336.297778 -261.306056) (xy 336.289142 -261.31774) (xy 336.286856 -261.346188)
			(xy 336.334354 -261.439914) (xy 336.339001 -261.44805) (xy 336.352955 -261.460531) (xy 336.370458 -261.467173)
			(xy 336.37982 -261.4676) (xy 336.662522 -261.4676) (xy 336.671891 -261.467225) (xy 336.689405 -261.460574)
			(xy 336.703348 -261.448063) (xy 336.707988 -261.439914) (xy 336.755486 -261.346188) (xy 336.7532 -261.31774)
			(xy 336.744564 -261.306056) (xy 336.730718 -261.286338) (xy 336.708766 -261.243452) (xy 336.693837 -261.197645)
			(xy 336.686305 -261.15006) (xy 336.68589 -261.12597) (xy 336.686412 -261.100715) (xy 336.694725 -261.050893)
			(xy 336.711126 -261.003119) (xy 336.735167 -260.958696) (xy 336.766191 -260.918836) (xy 336.803353 -260.884626)
			(xy 336.845639 -260.857) (xy 336.891895 -260.83671) (xy 336.94086 -260.82431) (xy 336.991198 -260.820139)
			(xy 337.041536 -260.82431) (xy 337.090501 -260.83671) (xy 337.136757 -260.857) (xy 337.179043 -260.884626)
			(xy 337.216205 -260.918836) (xy 337.247229 -260.958696) (xy 337.27127 -261.003119) (xy 337.287671 -261.050893)
			(xy 337.295984 -261.100715) (xy 337.296506 -261.12597) (xy 337.296043 -261.150053) (xy 337.288473 -261.197622)
			(xy 337.273546 -261.243419) (xy 337.251632 -261.286312) (xy 337.237832 -261.306056) (xy 337.229196 -261.31774)
			(xy 337.22691 -261.346188) (xy 337.274408 -261.439914) (xy 337.279053 -261.448055) (xy 337.293005 -261.460548)
			(xy 337.310509 -261.467206) (xy 337.319874 -261.4676) (xy 337.602322 -261.4676) (xy 337.611691 -261.467225)
			(xy 337.629205 -261.460574) (xy 337.643148 -261.448063) (xy 337.647788 -261.439914) (xy 337.695286 -261.346188)
			(xy 337.693 -261.31774) (xy 337.684364 -261.306056) (xy 337.670518 -261.286338) (xy 337.648566 -261.243452)
			(xy 337.633637 -261.197645) (xy 337.626105 -261.15006) (xy 337.62569 -261.12597) (xy 337.626212 -261.100715)
			(xy 337.634525 -261.050893) (xy 337.650926 -261.003119) (xy 337.674967 -260.958696) (xy 337.705991 -260.918836)
			(xy 337.743153 -260.884626) (xy 337.785439 -260.857) (xy 337.831695 -260.83671) (xy 337.88066 -260.82431)
			(xy 337.930998 -260.820139) (xy 337.981336 -260.82431) (xy 338.030301 -260.83671) (xy 338.076557 -260.857)
			(xy 338.118843 -260.884626) (xy 338.156005 -260.918836) (xy 338.187029 -260.958696) (xy 338.21107 -261.003119)
			(xy 338.227471 -261.050893) (xy 338.235784 -261.100715) (xy 338.236306 -261.12597) (xy 338.235843 -261.150053)
			(xy 338.228273 -261.197622) (xy 338.213346 -261.243419) (xy 338.191432 -261.286312) (xy 338.177632 -261.306056)
			(xy 338.168996 -261.31774) (xy 338.16671 -261.346188) (xy 338.214208 -261.439914) (xy 338.218853 -261.448055)
			(xy 338.232805 -261.460548) (xy 338.250309 -261.467206) (xy 338.259674 -261.4676) (xy 338.542376 -261.4676)
			(xy 338.55175 -261.467233) (xy 338.569276 -261.460592) (xy 338.583233 -261.448083) (xy 338.587842 -261.439914)
			(xy 338.63534 -261.346188) (xy 338.633054 -261.31774) (xy 338.624418 -261.306056) (xy 338.610574 -261.286338)
			(xy 338.588625 -261.243451) (xy 338.573699 -261.197644) (xy 338.566168 -261.150059) (xy 338.565744 -261.12597)
			(xy 338.566266 -261.100715) (xy 338.574579 -261.050893) (xy 338.59098 -261.003119) (xy 338.615021 -260.958696)
			(xy 338.646045 -260.918836) (xy 338.683207 -260.884626) (xy 338.725493 -260.857) (xy 338.771749 -260.83671)
			(xy 338.820714 -260.82431) (xy 338.871052 -260.820139) (xy 338.92139 -260.82431) (xy 338.970355 -260.83671)
			(xy 339.016611 -260.857) (xy 339.058897 -260.884626) (xy 339.096059 -260.918836) (xy 339.127083 -260.958696)
			(xy 339.151124 -261.003119) (xy 339.167525 -261.050893) (xy 339.175838 -261.100715) (xy 339.17636 -261.12597)
			(xy 339.175897 -261.150053) (xy 339.168326 -261.197622) (xy 339.153397 -261.243417) (xy 339.13148 -261.286308)
			(xy 339.117686 -261.306056) (xy 339.10905 -261.31774) (xy 339.106764 -261.346188) (xy 339.154262 -261.439914)
			(xy 339.15891 -261.448049) (xy 339.172864 -261.460528) (xy 339.190366 -261.467167) (xy 339.199728 -261.4676)
			(xy 339.48243 -261.4676) (xy 339.491798 -261.467224) (xy 339.50931 -261.460571) (xy 339.523251 -261.448059)
			(xy 339.527896 -261.439914) (xy 339.575394 -261.346188) (xy 339.573108 -261.31774) (xy 339.564472 -261.306056)
			(xy 339.550626 -261.286338) (xy 339.528673 -261.243452) (xy 339.513744 -261.197645) (xy 339.506212 -261.15006)
			(xy 339.505798 -261.12597) (xy 339.50632 -261.100715) (xy 339.514633 -261.050893) (xy 339.531034 -261.003119)
			(xy 339.555075 -260.958696) (xy 339.586099 -260.918836) (xy 339.623261 -260.884626) (xy 339.665547 -260.857)
			(xy 339.711803 -260.83671) (xy 339.760768 -260.82431) (xy 339.811106 -260.820139) (xy 339.861444 -260.82431)
			(xy 339.910409 -260.83671) (xy 339.956665 -260.857) (xy 339.998951 -260.884626) (xy 340.036113 -260.918836)
			(xy 340.067137 -260.958696) (xy 340.091178 -261.003119) (xy 340.107579 -261.050893) (xy 340.115892 -261.100715)
			(xy 340.116414 -261.12597) (xy 340.115951 -261.150054) (xy 340.108381 -261.197623) (xy 340.093455 -261.243419)
			(xy 340.071541 -261.286313) (xy 340.05774 -261.306056) (xy 340.049104 -261.31774) (xy 340.046818 -261.346188)
			(xy 340.094316 -261.439914) (xy 340.098962 -261.448054) (xy 340.112913 -261.460545) (xy 340.130417 -261.4672)
			(xy 340.139782 -261.4676) (xy 340.422484 -261.4676) (xy 340.431857 -261.467232) (xy 340.449381 -261.460589)
			(xy 340.463336 -261.448079) (xy 340.46795 -261.439914) (xy 340.515448 -261.346188) (xy 340.513162 -261.31774)
			(xy 340.504526 -261.306056) (xy 340.490682 -261.286338) (xy 340.468732 -261.243451) (xy 340.453806 -261.197644)
			(xy 340.446275 -261.150059) (xy 340.445852 -261.12597) (xy 340.446374 -261.100715) (xy 340.454687 -261.050893)
			(xy 340.471088 -261.003119) (xy 340.495129 -260.958696) (xy 340.526153 -260.918836) (xy 340.563315 -260.884626)
			(xy 340.605601 -260.857) (xy 340.651857 -260.83671) (xy 340.700822 -260.82431) (xy 340.75116 -260.820139)
			(xy 340.801498 -260.82431) (xy 340.850463 -260.83671) (xy 340.896719 -260.857) (xy 340.939005 -260.884626)
			(xy 340.976167 -260.918836) (xy 341.007191 -260.958696) (xy 341.031232 -261.003119) (xy 341.047633 -261.050893)
			(xy 341.055946 -261.100715) (xy 341.056468 -261.12597) (xy 341.056005 -261.150053) (xy 341.048434 -261.197622)
			(xy 341.033506 -261.243417) (xy 341.011589 -261.286309) (xy 340.997794 -261.306056) (xy 340.989158 -261.31774)
			(xy 340.986872 -261.346188) (xy 341.03437 -261.439914) (xy 341.039018 -261.448048) (xy 341.052972 -261.460525)
			(xy 341.070475 -261.467161) (xy 341.079836 -261.4676) (xy 342.302338 -261.4676) (xy 342.311706 -261.467223)
			(xy 342.329215 -261.460568) (xy 342.343153 -261.448056) (xy 342.347804 -261.439914) (xy 342.395302 -261.346188)
			(xy 342.393016 -261.31774) (xy 342.38438 -261.306056) (xy 342.370534 -261.286339) (xy 342.34858 -261.243453)
			(xy 342.333651 -261.197646) (xy 342.326118 -261.15006) (xy 342.325706 -261.12597) (xy 342.326228 -261.100715)
			(xy 342.334541 -261.050893) (xy 342.350942 -261.003119) (xy 342.374983 -260.958696) (xy 342.406007 -260.918836)
			(xy 342.443169 -260.884626) (xy 342.485455 -260.857) (xy 342.531711 -260.83671) (xy 342.580676 -260.82431)
			(xy 342.631014 -260.820139) (xy 342.681352 -260.82431) (xy 342.730317 -260.83671) (xy 342.776573 -260.857)
			(xy 342.818859 -260.884626) (xy 342.856021 -260.918836) (xy 342.887045 -260.958696) (xy 342.911086 -261.003119)
			(xy 342.927487 -261.050893) (xy 342.9358 -261.100715) (xy 342.936322 -261.12597) (xy 342.935859 -261.150054)
			(xy 342.92829 -261.197623) (xy 342.913363 -261.243419) (xy 342.891449 -261.286313) (xy 342.877648 -261.306056)
			(xy 342.869012 -261.31774) (xy 342.866726 -261.346188) (xy 342.914224 -261.439914) (xy 342.91887 -261.448053)
			(xy 342.932822 -261.460542) (xy 342.950326 -261.467194) (xy 342.95969 -261.4676) (xy 343.242392 -261.4676)
			(xy 343.251764 -261.46723) (xy 343.269286 -261.460586) (xy 343.283238 -261.448076) (xy 343.287858 -261.439914)
			(xy 343.335356 -261.346188) (xy 343.33307 -261.31774) (xy 343.324434 -261.306056) (xy 343.310589 -261.286338)
			(xy 343.288639 -261.243451) (xy 343.273712 -261.197644) (xy 343.266181 -261.150059) (xy 343.26576 -261.12597)
			(xy 343.266282 -261.100715) (xy 343.274595 -261.050893) (xy 343.290996 -261.003119) (xy 343.315037 -260.958696)
			(xy 343.346061 -260.918836) (xy 343.383223 -260.884626) (xy 343.425509 -260.857) (xy 343.471765 -260.83671)
			(xy 343.52073 -260.82431) (xy 343.571068 -260.820139) (xy 343.621406 -260.82431) (xy 343.670371 -260.83671)
			(xy 343.716627 -260.857) (xy 343.758913 -260.884626) (xy 343.796075 -260.918836) (xy 343.827099 -260.958696)
			(xy 343.85114 -261.003119) (xy 343.867541 -261.050893) (xy 343.875854 -261.100715) (xy 343.876376 -261.12597)
			(xy 343.876045 -261.146924) (xy 343.870344 -261.188443) (xy 343.859017 -261.228791) (xy 343.850976 -261.248144)
			(xy 343.845388 -261.260844) (xy 343.84869 -261.288276) (xy 343.91981 -261.380986) (xy 343.94521 -261.3914)
			(xy 343.95918 -261.389368) (xy 343.97957 -261.38651) (xy 344.020634 -261.383458) (xy 344.041222 -261.383272)
			(xy 344.061811 -261.383454) (xy 344.102874 -261.386509) (xy 344.123264 -261.389368) (xy 344.13698 -261.3914)
			(xy 344.162634 -261.380986) (xy 344.2335 -261.288276) (xy 344.236802 -261.260844) (xy 344.231214 -261.248144)
			(xy 344.223161 -261.228795) (xy 344.211834 -261.188445) (xy 344.206133 -261.146925) (xy 344.205814 -261.12597)
			(xy 344.206336 -261.100715) (xy 344.214649 -261.050893) (xy 344.23105 -261.003119) (xy 344.255091 -260.958696)
			(xy 344.286115 -260.918836) (xy 344.323277 -260.884626) (xy 344.365563 -260.857) (xy 344.411819 -260.83671)
			(xy 344.460784 -260.82431) (xy 344.511122 -260.820139) (xy 344.56146 -260.82431) (xy 344.610425 -260.83671)
			(xy 344.656681 -260.857) (xy 344.698967 -260.884626) (xy 344.736129 -260.918836) (xy 344.767153 -260.958696)
			(xy 344.791194 -261.003119) (xy 344.807595 -261.050893) (xy 344.815908 -261.100715) (xy 344.81643 -261.12597)
			(xy 346.085426 -261.12597) (xy 346.089386 -261.076916) (xy 346.101163 -261.029132) (xy 346.120454 -260.983856)
			(xy 346.146757 -260.94226) (xy 346.179392 -260.905423) (xy 346.217513 -260.874298) (xy 346.260134 -260.849691)
			(xy 346.30615 -260.832239) (xy 346.354369 -260.822395) (xy 346.403544 -260.820414) (xy 346.452399 -260.826346)
			(xy 346.49967 -260.840038) (xy 346.544132 -260.861136) (xy 346.584635 -260.889092) (xy 346.620128 -260.923184)
			(xy 346.649693 -260.962528) (xy 346.672564 -261.006105) (xy 346.688148 -261.052786) (xy 346.696043 -261.101363)
			(xy 346.696538 -261.12597) (xy 347.96528 -261.12597) (xy 347.96924 -261.076916) (xy 347.981017 -261.029132)
			(xy 348.000308 -260.983856) (xy 348.026611 -260.94226) (xy 348.059246 -260.905423) (xy 348.097367 -260.874298)
			(xy 348.139988 -260.849691) (xy 348.186004 -260.832239) (xy 348.234223 -260.822395) (xy 348.283398 -260.820414)
			(xy 348.332253 -260.826346) (xy 348.379524 -260.840038) (xy 348.423986 -260.861136) (xy 348.464489 -260.889092)
			(xy 348.499982 -260.923184) (xy 348.529547 -260.962528) (xy 348.552418 -261.006105) (xy 348.568002 -261.052786)
			(xy 348.575897 -261.101363) (xy 348.576392 -261.12597) (xy 348.905334 -261.12597) (xy 348.909294 -261.076916)
			(xy 348.921071 -261.029132) (xy 348.940362 -260.983856) (xy 348.966665 -260.94226) (xy 348.9993 -260.905423)
			(xy 349.037421 -260.874298) (xy 349.080042 -260.849691) (xy 349.126058 -260.832239) (xy 349.174277 -260.822395)
			(xy 349.223452 -260.820414) (xy 349.272307 -260.826346) (xy 349.319578 -260.840038) (xy 349.36404 -260.861136)
			(xy 349.404543 -260.889092) (xy 349.440036 -260.923184) (xy 349.469601 -260.962528) (xy 349.492472 -261.006105)
			(xy 349.508056 -261.052786) (xy 349.515951 -261.101363) (xy 349.516446 -261.12597) (xy 349.845388 -261.12597)
			(xy 349.849348 -261.076916) (xy 349.861125 -261.029132) (xy 349.880416 -260.983856) (xy 349.906719 -260.94226)
			(xy 349.939354 -260.905423) (xy 349.977475 -260.874298) (xy 350.020096 -260.849691) (xy 350.066112 -260.832239)
			(xy 350.114331 -260.822395) (xy 350.163506 -260.820414) (xy 350.212361 -260.826346) (xy 350.259632 -260.840038)
			(xy 350.304094 -260.861136) (xy 350.344597 -260.889092) (xy 350.38009 -260.923184) (xy 350.409655 -260.962528)
			(xy 350.432526 -261.006105) (xy 350.44811 -261.052786) (xy 350.456005 -261.101363) (xy 350.4565 -261.12597)
			(xy 350.456459 -261.128002) (xy 350.78214 -261.128002) (xy 350.7861 -261.078948) (xy 350.797877 -261.031164)
			(xy 350.817168 -260.985888) (xy 350.843471 -260.944292) (xy 350.876106 -260.907455) (xy 350.914227 -260.87633)
			(xy 350.956848 -260.851723) (xy 351.002864 -260.834271) (xy 351.051083 -260.824427) (xy 351.100258 -260.822446)
			(xy 351.149113 -260.828378) (xy 351.196384 -260.84207) (xy 351.240846 -260.863168) (xy 351.281349 -260.891124)
			(xy 351.316842 -260.925216) (xy 351.346407 -260.96456) (xy 351.369278 -261.008137) (xy 351.384862 -261.054818)
			(xy 351.392757 -261.103395) (xy 351.393252 -261.128002) (xy 351.722194 -261.128002) (xy 351.726154 -261.078948)
			(xy 351.737931 -261.031164) (xy 351.757222 -260.985888) (xy 351.783525 -260.944292) (xy 351.81616 -260.907455)
			(xy 351.854281 -260.87633) (xy 351.896902 -260.851723) (xy 351.942918 -260.834271) (xy 351.991137 -260.824427)
			(xy 352.040312 -260.822446) (xy 352.089167 -260.828378) (xy 352.136438 -260.84207) (xy 352.1809 -260.863168)
			(xy 352.221403 -260.891124) (xy 352.256896 -260.925216) (xy 352.286461 -260.96456) (xy 352.309332 -261.008137)
			(xy 352.324916 -261.054818) (xy 352.332811 -261.103395) (xy 352.333306 -261.128002) (xy 352.332811 -261.152609)
			(xy 352.324916 -261.201186) (xy 352.309332 -261.247867) (xy 352.286461 -261.291444) (xy 352.256896 -261.330788)
			(xy 352.221403 -261.36488) (xy 352.1809 -261.392836) (xy 352.136438 -261.413934) (xy 352.089167 -261.427626)
			(xy 352.040312 -261.433558) (xy 351.991137 -261.431577) (xy 351.942918 -261.421733) (xy 351.896902 -261.404281)
			(xy 351.854281 -261.379674) (xy 351.81616 -261.348549) (xy 351.783525 -261.311712) (xy 351.757222 -261.270116)
			(xy 351.737931 -261.22484) (xy 351.726154 -261.177056) (xy 351.722194 -261.128002) (xy 351.393252 -261.128002)
			(xy 351.392757 -261.152609) (xy 351.384862 -261.201186) (xy 351.369278 -261.247867) (xy 351.346407 -261.291444)
			(xy 351.316842 -261.330788) (xy 351.281349 -261.36488) (xy 351.240846 -261.392836) (xy 351.196384 -261.413934)
			(xy 351.149113 -261.427626) (xy 351.100258 -261.433558) (xy 351.051083 -261.431577) (xy 351.002864 -261.421733)
			(xy 350.956848 -261.404281) (xy 350.914227 -261.379674) (xy 350.876106 -261.348549) (xy 350.843471 -261.311712)
			(xy 350.817168 -261.270116) (xy 350.797877 -261.22484) (xy 350.7861 -261.177056) (xy 350.78214 -261.128002)
			(xy 350.456459 -261.128002) (xy 350.456005 -261.150577) (xy 350.44811 -261.199154) (xy 350.432526 -261.245835)
			(xy 350.409655 -261.289412) (xy 350.38009 -261.328756) (xy 350.344597 -261.362848) (xy 350.304094 -261.390804)
			(xy 350.259632 -261.411902) (xy 350.212361 -261.425594) (xy 350.163506 -261.431526) (xy 350.114331 -261.429545)
			(xy 350.066112 -261.419701) (xy 350.020096 -261.402249) (xy 349.977475 -261.377642) (xy 349.939354 -261.346517)
			(xy 349.906719 -261.30968) (xy 349.880416 -261.268084) (xy 349.861125 -261.222808) (xy 349.849348 -261.175024)
			(xy 349.845388 -261.12597) (xy 349.516446 -261.12597) (xy 349.515951 -261.150577) (xy 349.508056 -261.199154)
			(xy 349.492472 -261.245835) (xy 349.469601 -261.289412) (xy 349.440036 -261.328756) (xy 349.404543 -261.362848)
			(xy 349.36404 -261.390804) (xy 349.319578 -261.411902) (xy 349.272307 -261.425594) (xy 349.223452 -261.431526)
			(xy 349.174277 -261.429545) (xy 349.126058 -261.419701) (xy 349.080042 -261.402249) (xy 349.037421 -261.377642)
			(xy 348.9993 -261.346517) (xy 348.966665 -261.30968) (xy 348.940362 -261.268084) (xy 348.921071 -261.222808)
			(xy 348.909294 -261.175024) (xy 348.905334 -261.12597) (xy 348.576392 -261.12597) (xy 348.575897 -261.150577)
			(xy 348.568002 -261.199154) (xy 348.552418 -261.245835) (xy 348.529547 -261.289412) (xy 348.499982 -261.328756)
			(xy 348.464489 -261.362848) (xy 348.423986 -261.390804) (xy 348.379524 -261.411902) (xy 348.332253 -261.425594)
			(xy 348.283398 -261.431526) (xy 348.234223 -261.429545) (xy 348.186004 -261.419701) (xy 348.139988 -261.402249)
			(xy 348.097367 -261.377642) (xy 348.059246 -261.346517) (xy 348.026611 -261.30968) (xy 348.000308 -261.268084)
			(xy 347.981017 -261.222808) (xy 347.96924 -261.175024) (xy 347.96528 -261.12597) (xy 346.696538 -261.12597)
			(xy 346.696043 -261.150577) (xy 346.688148 -261.199154) (xy 346.672564 -261.245835) (xy 346.649693 -261.289412)
			(xy 346.620128 -261.328756) (xy 346.584635 -261.362848) (xy 346.544132 -261.390804) (xy 346.49967 -261.411902)
			(xy 346.452399 -261.425594) (xy 346.403544 -261.431526) (xy 346.354369 -261.429545) (xy 346.30615 -261.419701)
			(xy 346.260134 -261.402249) (xy 346.217513 -261.377642) (xy 346.179392 -261.346517) (xy 346.146757 -261.30968)
			(xy 346.120454 -261.268084) (xy 346.101163 -261.222808) (xy 346.089386 -261.175024) (xy 346.085426 -261.12597)
			(xy 344.81643 -261.12597) (xy 344.815986 -261.149263) (xy 344.808901 -261.195306) (xy 344.794906 -261.23974)
			(xy 344.774326 -261.281533) (xy 344.747638 -261.319716) (xy 344.715461 -261.353404) (xy 344.678542 -261.381814)
			(xy 344.637736 -261.404289) (xy 344.616024 -261.412736) (xy 344.603578 -261.417308) (xy 344.58656 -261.436612)
			(xy 344.565224 -261.533132) (xy 344.563694 -261.541499) (xy 344.565677 -261.558382) (xy 344.573122 -261.573664)
			(xy 344.57894 -261.579868) (xy 344.710766 -261.711694) (xy 344.717617 -261.719091) (xy 344.725359 -261.737689)
			(xy 344.725752 -261.747762) (xy 344.725752 -261.935976) (xy 345.615272 -261.935976) (xy 345.619232 -261.886922)
			(xy 345.631009 -261.839138) (xy 345.6503 -261.793862) (xy 345.676603 -261.752266) (xy 345.709238 -261.715429)
			(xy 345.747359 -261.684304) (xy 345.78998 -261.659697) (xy 345.835996 -261.642245) (xy 345.884215 -261.632401)
			(xy 345.93339 -261.63042) (xy 345.982245 -261.636352) (xy 346.029516 -261.650044) (xy 346.073978 -261.671142)
			(xy 346.114481 -261.699098) (xy 346.149974 -261.73319) (xy 346.179539 -261.772534) (xy 346.20241 -261.816111)
			(xy 346.217994 -261.862792) (xy 346.225889 -261.911369) (xy 346.226384 -261.935976) (xy 347.49538 -261.935976)
			(xy 347.49934 -261.886922) (xy 347.511117 -261.839138) (xy 347.530408 -261.793862) (xy 347.556711 -261.752266)
			(xy 347.589346 -261.715429) (xy 347.627467 -261.684304) (xy 347.670088 -261.659697) (xy 347.716104 -261.642245)
			(xy 347.764323 -261.632401) (xy 347.813498 -261.63042) (xy 347.862353 -261.636352) (xy 347.909624 -261.650044)
			(xy 347.954086 -261.671142) (xy 347.994589 -261.699098) (xy 348.030082 -261.73319) (xy 348.059647 -261.772534)
			(xy 348.082518 -261.816111) (xy 348.098102 -261.862792) (xy 348.105997 -261.911369) (xy 348.106492 -261.935976)
			(xy 349.375234 -261.935976) (xy 349.379194 -261.886922) (xy 349.390971 -261.839138) (xy 349.410262 -261.793862)
			(xy 349.436565 -261.752266) (xy 349.4692 -261.715429) (xy 349.507321 -261.684304) (xy 349.549942 -261.659697)
			(xy 349.595958 -261.642245) (xy 349.644177 -261.632401) (xy 349.693352 -261.63042) (xy 349.742207 -261.636352)
			(xy 349.789478 -261.650044) (xy 349.83394 -261.671142) (xy 349.874443 -261.699098) (xy 349.909936 -261.73319)
			(xy 349.939501 -261.772534) (xy 349.962372 -261.816111) (xy 349.977956 -261.862792) (xy 349.985851 -261.911369)
			(xy 349.986346 -261.935976) (xy 350.315288 -261.935976) (xy 350.319248 -261.886922) (xy 350.331025 -261.839138)
			(xy 350.350316 -261.793862) (xy 350.376619 -261.752266) (xy 350.409254 -261.715429) (xy 350.447375 -261.684304)
			(xy 350.489996 -261.659697) (xy 350.536012 -261.642245) (xy 350.584231 -261.632401) (xy 350.633406 -261.63042)
			(xy 350.682261 -261.636352) (xy 350.729532 -261.650044) (xy 350.773994 -261.671142) (xy 350.814497 -261.699098)
			(xy 350.84999 -261.73319) (xy 350.879555 -261.772534) (xy 350.902426 -261.816111) (xy 350.91801 -261.862792)
			(xy 350.925905 -261.911369) (xy 350.9264 -261.935976) (xy 350.925905 -261.960583) (xy 350.91801 -262.00916)
			(xy 350.902426 -262.055841) (xy 350.879555 -262.099418) (xy 350.84999 -262.138762) (xy 350.814497 -262.172854)
			(xy 350.773994 -262.20081) (xy 350.729532 -262.221908) (xy 350.682261 -262.2356) (xy 350.633406 -262.241532)
			(xy 350.584231 -262.239551) (xy 350.536012 -262.229707) (xy 350.489996 -262.212255) (xy 350.447375 -262.187648)
			(xy 350.409254 -262.156523) (xy 350.376619 -262.119686) (xy 350.350316 -262.07809) (xy 350.331025 -262.032814)
			(xy 350.319248 -261.98503) (xy 350.315288 -261.935976) (xy 349.986346 -261.935976) (xy 349.985851 -261.960583)
			(xy 349.977956 -262.00916) (xy 349.962372 -262.055841) (xy 349.939501 -262.099418) (xy 349.909936 -262.138762)
			(xy 349.874443 -262.172854) (xy 349.83394 -262.20081) (xy 349.789478 -262.221908) (xy 349.742207 -262.2356)
			(xy 349.693352 -262.241532) (xy 349.644177 -262.239551) (xy 349.595958 -262.229707) (xy 349.549942 -262.212255)
			(xy 349.507321 -262.187648) (xy 349.4692 -262.156523) (xy 349.436565 -262.119686) (xy 349.410262 -262.07809)
			(xy 349.390971 -262.032814) (xy 349.379194 -261.98503) (xy 349.375234 -261.935976) (xy 348.106492 -261.935976)
			(xy 348.105997 -261.960583) (xy 348.098102 -262.00916) (xy 348.082518 -262.055841) (xy 348.059647 -262.099418)
			(xy 348.030082 -262.138762) (xy 347.994589 -262.172854) (xy 347.954086 -262.20081) (xy 347.909624 -262.221908)
			(xy 347.862353 -262.2356) (xy 347.813498 -262.241532) (xy 347.764323 -262.239551) (xy 347.716104 -262.229707)
			(xy 347.670088 -262.212255) (xy 347.627467 -262.187648) (xy 347.589346 -262.156523) (xy 347.556711 -262.119686)
			(xy 347.530408 -262.07809) (xy 347.511117 -262.032814) (xy 347.49934 -261.98503) (xy 347.49538 -261.935976)
			(xy 346.226384 -261.935976) (xy 346.225889 -261.960583) (xy 346.217994 -262.00916) (xy 346.20241 -262.055841)
			(xy 346.179539 -262.099418) (xy 346.149974 -262.138762) (xy 346.114481 -262.172854) (xy 346.073978 -262.20081)
			(xy 346.029516 -262.221908) (xy 345.982245 -262.2356) (xy 345.93339 -262.241532) (xy 345.884215 -262.239551)
			(xy 345.835996 -262.229707) (xy 345.78998 -262.212255) (xy 345.747359 -262.187648) (xy 345.709238 -262.156523)
			(xy 345.676603 -262.119686) (xy 345.6503 -262.07809) (xy 345.631009 -262.032814) (xy 345.619232 -261.98503)
			(xy 345.615272 -261.935976) (xy 344.725752 -261.935976) (xy 344.725752 -262.499602) (xy 344.725851 -262.504214)
			(xy 344.727508 -262.513289) (xy 344.729054 -262.517636) (xy 344.738198 -262.541766) (xy 344.743786 -262.54837)
			(xy 344.758915 -262.566876) (xy 344.783822 -262.607671) (xy 344.802063 -262.651851) (xy 344.813189 -262.698335)
			(xy 344.81693 -262.745982) (xy 346.085426 -262.745982) (xy 346.089386 -262.696928) (xy 346.101163 -262.649144)
			(xy 346.120454 -262.603868) (xy 346.146757 -262.562272) (xy 346.179392 -262.525435) (xy 346.217513 -262.49431)
			(xy 346.260134 -262.469703) (xy 346.30615 -262.452251) (xy 346.354369 -262.442407) (xy 346.403544 -262.440426)
			(xy 346.452399 -262.446358) (xy 346.49967 -262.46005) (xy 346.544132 -262.481148) (xy 346.584635 -262.509104)
			(xy 346.620128 -262.543196) (xy 346.649693 -262.58254) (xy 346.672564 -262.626117) (xy 346.688148 -262.672798)
			(xy 346.696043 -262.721375) (xy 346.696538 -262.745982) (xy 347.96528 -262.745982) (xy 347.96924 -262.696928)
			(xy 347.981017 -262.649144) (xy 348.000308 -262.603868) (xy 348.026611 -262.562272) (xy 348.059246 -262.525435)
			(xy 348.097367 -262.49431) (xy 348.139988 -262.469703) (xy 348.186004 -262.452251) (xy 348.234223 -262.442407)
			(xy 348.283398 -262.440426) (xy 348.332253 -262.446358) (xy 348.379524 -262.46005) (xy 348.423986 -262.481148)
			(xy 348.464489 -262.509104) (xy 348.499982 -262.543196) (xy 348.529547 -262.58254) (xy 348.552418 -262.626117)
			(xy 348.568002 -262.672798) (xy 348.575897 -262.721375) (xy 348.576392 -262.745982) (xy 348.905334 -262.745982)
			(xy 348.909294 -262.696928) (xy 348.921071 -262.649144) (xy 348.940362 -262.603868) (xy 348.966665 -262.562272)
			(xy 348.9993 -262.525435) (xy 349.037421 -262.49431) (xy 349.080042 -262.469703) (xy 349.126058 -262.452251)
			(xy 349.174277 -262.442407) (xy 349.223452 -262.440426) (xy 349.272307 -262.446358) (xy 349.319578 -262.46005)
			(xy 349.36404 -262.481148) (xy 349.404543 -262.509104) (xy 349.440036 -262.543196) (xy 349.469601 -262.58254)
			(xy 349.492472 -262.626117) (xy 349.508056 -262.672798) (xy 349.515951 -262.721375) (xy 349.516446 -262.745982)
			(xy 349.845388 -262.745982) (xy 349.849348 -262.696928) (xy 349.861125 -262.649144) (xy 349.880416 -262.603868)
			(xy 349.906719 -262.562272) (xy 349.939354 -262.525435) (xy 349.977475 -262.49431) (xy 350.020096 -262.469703)
			(xy 350.066112 -262.452251) (xy 350.114331 -262.442407) (xy 350.163506 -262.440426) (xy 350.212361 -262.446358)
			(xy 350.259632 -262.46005) (xy 350.304094 -262.481148) (xy 350.344597 -262.509104) (xy 350.38009 -262.543196)
			(xy 350.409655 -262.58254) (xy 350.432526 -262.626117) (xy 350.44811 -262.672798) (xy 350.456005 -262.721375)
			(xy 350.4565 -262.745982) (xy 350.456459 -262.748014) (xy 350.78214 -262.748014) (xy 350.7861 -262.69896)
			(xy 350.797877 -262.651176) (xy 350.817168 -262.6059) (xy 350.843471 -262.564304) (xy 350.876106 -262.527467)
			(xy 350.914227 -262.496342) (xy 350.956848 -262.471735) (xy 351.002864 -262.454283) (xy 351.051083 -262.444439)
			(xy 351.100258 -262.442458) (xy 351.149113 -262.44839) (xy 351.196384 -262.462082) (xy 351.240846 -262.48318)
			(xy 351.281349 -262.511136) (xy 351.316842 -262.545228) (xy 351.346407 -262.584572) (xy 351.369278 -262.628149)
			(xy 351.384862 -262.67483) (xy 351.392757 -262.723407) (xy 351.393252 -262.748014) (xy 351.392757 -262.772621)
			(xy 351.384862 -262.821198) (xy 351.369278 -262.867879) (xy 351.346407 -262.911456) (xy 351.316842 -262.9508)
			(xy 351.281349 -262.984892) (xy 351.240846 -263.012848) (xy 351.196384 -263.033946) (xy 351.149113 -263.047638)
			(xy 351.100258 -263.05357) (xy 351.051083 -263.051589) (xy 351.002864 -263.041745) (xy 350.956848 -263.024293)
			(xy 350.914227 -262.999686) (xy 350.876106 -262.968561) (xy 350.843471 -262.931724) (xy 350.817168 -262.890128)
			(xy 350.797877 -262.844852) (xy 350.7861 -262.797068) (xy 350.78214 -262.748014) (xy 350.456459 -262.748014)
			(xy 350.456005 -262.770589) (xy 350.44811 -262.819166) (xy 350.432526 -262.865847) (xy 350.409655 -262.909424)
			(xy 350.38009 -262.948768) (xy 350.344597 -262.98286) (xy 350.304094 -263.010816) (xy 350.259632 -263.031914)
			(xy 350.212361 -263.045606) (xy 350.163506 -263.051538) (xy 350.114331 -263.049557) (xy 350.066112 -263.039713)
			(xy 350.020096 -263.022261) (xy 349.977475 -262.997654) (xy 349.939354 -262.966529) (xy 349.906719 -262.929692)
			(xy 349.880416 -262.888096) (xy 349.861125 -262.84282) (xy 349.849348 -262.795036) (xy 349.845388 -262.745982)
			(xy 349.516446 -262.745982) (xy 349.515951 -262.770589) (xy 349.508056 -262.819166) (xy 349.492472 -262.865847)
			(xy 349.469601 -262.909424) (xy 349.440036 -262.948768) (xy 349.404543 -262.98286) (xy 349.36404 -263.010816)
			(xy 349.319578 -263.031914) (xy 349.272307 -263.045606) (xy 349.223452 -263.051538) (xy 349.174277 -263.049557)
			(xy 349.126058 -263.039713) (xy 349.080042 -263.022261) (xy 349.037421 -262.997654) (xy 348.9993 -262.966529)
			(xy 348.966665 -262.929692) (xy 348.940362 -262.888096) (xy 348.921071 -262.84282) (xy 348.909294 -262.795036)
			(xy 348.905334 -262.745982) (xy 348.576392 -262.745982) (xy 348.575897 -262.770589) (xy 348.568002 -262.819166)
			(xy 348.552418 -262.865847) (xy 348.529547 -262.909424) (xy 348.499982 -262.948768) (xy 348.464489 -262.98286)
			(xy 348.423986 -263.010816) (xy 348.379524 -263.031914) (xy 348.332253 -263.045606) (xy 348.283398 -263.051538)
			(xy 348.234223 -263.049557) (xy 348.186004 -263.039713) (xy 348.139988 -263.022261) (xy 348.097367 -262.997654)
			(xy 348.059246 -262.966529) (xy 348.026611 -262.929692) (xy 348.000308 -262.888096) (xy 347.981017 -262.84282)
			(xy 347.96924 -262.795036) (xy 347.96528 -262.745982) (xy 346.696538 -262.745982) (xy 346.696043 -262.770589)
			(xy 346.688148 -262.819166) (xy 346.672564 -262.865847) (xy 346.649693 -262.909424) (xy 346.620128 -262.948768)
			(xy 346.584635 -262.98286) (xy 346.544132 -263.010816) (xy 346.49967 -263.031914) (xy 346.452399 -263.045606)
			(xy 346.403544 -263.051538) (xy 346.354369 -263.049557) (xy 346.30615 -263.039713) (xy 346.260134 -263.022261)
			(xy 346.217513 -262.997654) (xy 346.179392 -262.966529) (xy 346.146757 -262.929692) (xy 346.120454 -262.888096)
			(xy 346.101163 -262.84282) (xy 346.089386 -262.795036) (xy 346.085426 -262.745982) (xy 344.81693 -262.745982)
			(xy 344.81693 -262.745986) (xy 344.813194 -262.793637) (xy 344.802071 -262.840123) (xy 344.783835 -262.884304)
			(xy 344.758931 -262.925101) (xy 344.743786 -262.943594) (xy 344.738198 -262.950198) (xy 344.729054 -262.974328)
			(xy 344.727512 -262.978676) (xy 344.725854 -262.98775) (xy 344.725752 -262.992362) (xy 344.725752 -263.555988)
			(xy 345.615272 -263.555988) (xy 345.619232 -263.506934) (xy 345.631009 -263.45915) (xy 345.6503 -263.413874)
			(xy 345.676603 -263.372278) (xy 345.709238 -263.335441) (xy 345.747359 -263.304316) (xy 345.78998 -263.279709)
			(xy 345.835996 -263.262257) (xy 345.884215 -263.252413) (xy 345.93339 -263.250432) (xy 345.982245 -263.256364)
			(xy 346.029516 -263.270056) (xy 346.073978 -263.291154) (xy 346.114481 -263.31911) (xy 346.149974 -263.353202)
			(xy 346.179539 -263.392546) (xy 346.20241 -263.436123) (xy 346.217994 -263.482804) (xy 346.225889 -263.531381)
			(xy 346.226384 -263.555988) (xy 347.49538 -263.555988) (xy 347.49934 -263.506934) (xy 347.511117 -263.45915)
			(xy 347.530408 -263.413874) (xy 347.556711 -263.372278) (xy 347.589346 -263.335441) (xy 347.627467 -263.304316)
			(xy 347.670088 -263.279709) (xy 347.716104 -263.262257) (xy 347.764323 -263.252413) (xy 347.813498 -263.250432)
			(xy 347.862353 -263.256364) (xy 347.909624 -263.270056) (xy 347.954086 -263.291154) (xy 347.994589 -263.31911)
			(xy 348.030082 -263.353202) (xy 348.059647 -263.392546) (xy 348.082518 -263.436123) (xy 348.098102 -263.482804)
			(xy 348.105997 -263.531381) (xy 348.106492 -263.555988) (xy 349.375234 -263.555988) (xy 349.379194 -263.506934)
			(xy 349.390971 -263.45915) (xy 349.410262 -263.413874) (xy 349.436565 -263.372278) (xy 349.4692 -263.335441)
			(xy 349.507321 -263.304316) (xy 349.549942 -263.279709) (xy 349.595958 -263.262257) (xy 349.644177 -263.252413)
			(xy 349.693352 -263.250432) (xy 349.742207 -263.256364) (xy 349.789478 -263.270056) (xy 349.83394 -263.291154)
			(xy 349.874443 -263.31911) (xy 349.909936 -263.353202) (xy 349.939501 -263.392546) (xy 349.962372 -263.436123)
			(xy 349.977956 -263.482804) (xy 349.985851 -263.531381) (xy 349.986346 -263.555988) (xy 349.985851 -263.580595)
			(xy 349.977956 -263.629172) (xy 349.962372 -263.675853) (xy 349.939501 -263.71943) (xy 349.909936 -263.758774)
			(xy 349.874443 -263.792866) (xy 349.83394 -263.820822) (xy 349.789478 -263.84192) (xy 349.742207 -263.855612)
			(xy 349.693352 -263.861544) (xy 349.644177 -263.859563) (xy 349.595958 -263.849719) (xy 349.549942 -263.832267)
			(xy 349.507321 -263.80766) (xy 349.4692 -263.776535) (xy 349.436565 -263.739698) (xy 349.410262 -263.698102)
			(xy 349.390971 -263.652826) (xy 349.379194 -263.605042) (xy 349.375234 -263.555988) (xy 348.106492 -263.555988)
			(xy 348.105997 -263.580595) (xy 348.098102 -263.629172) (xy 348.082518 -263.675853) (xy 348.059647 -263.71943)
			(xy 348.030082 -263.758774) (xy 347.994589 -263.792866) (xy 347.954086 -263.820822) (xy 347.909624 -263.84192)
			(xy 347.862353 -263.855612) (xy 347.813498 -263.861544) (xy 347.764323 -263.859563) (xy 347.716104 -263.849719)
			(xy 347.670088 -263.832267) (xy 347.627467 -263.80766) (xy 347.589346 -263.776535) (xy 347.556711 -263.739698)
			(xy 347.530408 -263.698102) (xy 347.511117 -263.652826) (xy 347.49934 -263.605042) (xy 347.49538 -263.555988)
			(xy 346.226384 -263.555988) (xy 346.225889 -263.580595) (xy 346.217994 -263.629172) (xy 346.20241 -263.675853)
			(xy 346.179539 -263.71943) (xy 346.149974 -263.758774) (xy 346.114481 -263.792866) (xy 346.073978 -263.820822)
			(xy 346.029516 -263.84192) (xy 345.982245 -263.855612) (xy 345.93339 -263.861544) (xy 345.884215 -263.859563)
			(xy 345.835996 -263.849719) (xy 345.78998 -263.832267) (xy 345.747359 -263.80766) (xy 345.709238 -263.776535)
			(xy 345.676603 -263.739698) (xy 345.6503 -263.698102) (xy 345.631009 -263.652826) (xy 345.619232 -263.605042)
			(xy 345.615272 -263.555988) (xy 344.725752 -263.555988) (xy 344.725752 -264.119614) (xy 344.725852 -264.124226)
			(xy 344.727511 -264.1333) (xy 344.729054 -264.137648) (xy 344.738198 -264.161778) (xy 344.743786 -264.168382)
			(xy 344.758914 -264.186888) (xy 344.783819 -264.227683) (xy 344.802058 -264.271862) (xy 344.813183 -264.318346)
			(xy 344.816923 -264.365994) (xy 346.085426 -264.365994) (xy 346.089386 -264.31694) (xy 346.101163 -264.269156)
			(xy 346.120454 -264.22388) (xy 346.146757 -264.182284) (xy 346.179392 -264.145447) (xy 346.217513 -264.114322)
			(xy 346.260134 -264.089715) (xy 346.30615 -264.072263) (xy 346.354369 -264.062419) (xy 346.403544 -264.060438)
			(xy 346.452399 -264.06637) (xy 346.49967 -264.080062) (xy 346.544132 -264.10116) (xy 346.584635 -264.129116)
			(xy 346.620128 -264.163208) (xy 346.649693 -264.202552) (xy 346.672564 -264.246129) (xy 346.688148 -264.29281)
			(xy 346.696043 -264.341387) (xy 346.696538 -264.365994) (xy 347.96528 -264.365994) (xy 347.96924 -264.31694)
			(xy 347.981017 -264.269156) (xy 348.000308 -264.22388) (xy 348.026611 -264.182284) (xy 348.059246 -264.145447)
			(xy 348.097367 -264.114322) (xy 348.139988 -264.089715) (xy 348.186004 -264.072263) (xy 348.234223 -264.062419)
			(xy 348.283398 -264.060438) (xy 348.332253 -264.06637) (xy 348.379524 -264.080062) (xy 348.423986 -264.10116)
			(xy 348.464489 -264.129116) (xy 348.499982 -264.163208) (xy 348.529547 -264.202552) (xy 348.552418 -264.246129)
			(xy 348.568002 -264.29281) (xy 348.575897 -264.341387) (xy 348.576392 -264.365994) (xy 348.905334 -264.365994)
			(xy 348.909294 -264.31694) (xy 348.921071 -264.269156) (xy 348.940362 -264.22388) (xy 348.966665 -264.182284)
			(xy 348.9993 -264.145447) (xy 349.037421 -264.114322) (xy 349.080042 -264.089715) (xy 349.126058 -264.072263)
			(xy 349.174277 -264.062419) (xy 349.223452 -264.060438) (xy 349.272307 -264.06637) (xy 349.319578 -264.080062)
			(xy 349.36404 -264.10116) (xy 349.404543 -264.129116) (xy 349.440036 -264.163208) (xy 349.469601 -264.202552)
			(xy 349.492472 -264.246129) (xy 349.508056 -264.29281) (xy 349.515951 -264.341387) (xy 349.516446 -264.365994)
			(xy 349.515951 -264.390601) (xy 349.508056 -264.439178) (xy 349.492472 -264.485859) (xy 349.469601 -264.529436)
			(xy 349.440036 -264.56878) (xy 349.404543 -264.602872) (xy 349.36404 -264.630828) (xy 349.319578 -264.651926)
			(xy 349.272307 -264.665618) (xy 349.223452 -264.67155) (xy 349.174277 -264.669569) (xy 349.126058 -264.659725)
			(xy 349.080042 -264.642273) (xy 349.037421 -264.617666) (xy 348.9993 -264.586541) (xy 348.966665 -264.549704)
			(xy 348.940362 -264.508108) (xy 348.921071 -264.462832) (xy 348.909294 -264.415048) (xy 348.905334 -264.365994)
			(xy 348.576392 -264.365994) (xy 348.575897 -264.390601) (xy 348.568002 -264.439178) (xy 348.552418 -264.485859)
			(xy 348.529547 -264.529436) (xy 348.499982 -264.56878) (xy 348.464489 -264.602872) (xy 348.423986 -264.630828)
			(xy 348.379524 -264.651926) (xy 348.332253 -264.665618) (xy 348.283398 -264.67155) (xy 348.234223 -264.669569)
			(xy 348.186004 -264.659725) (xy 348.139988 -264.642273) (xy 348.097367 -264.617666) (xy 348.059246 -264.586541)
			(xy 348.026611 -264.549704) (xy 348.000308 -264.508108) (xy 347.981017 -264.462832) (xy 347.96924 -264.415048)
			(xy 347.96528 -264.365994) (xy 346.696538 -264.365994) (xy 346.696043 -264.390601) (xy 346.688148 -264.439178)
			(xy 346.672564 -264.485859) (xy 346.649693 -264.529436) (xy 346.620128 -264.56878) (xy 346.584635 -264.602872)
			(xy 346.544132 -264.630828) (xy 346.49967 -264.651926) (xy 346.452399 -264.665618) (xy 346.403544 -264.67155)
			(xy 346.354369 -264.669569) (xy 346.30615 -264.659725) (xy 346.260134 -264.642273) (xy 346.217513 -264.617666)
			(xy 346.179392 -264.586541) (xy 346.146757 -264.549704) (xy 346.120454 -264.508108) (xy 346.101163 -264.462832)
			(xy 346.089386 -264.415048) (xy 346.085426 -264.365994) (xy 344.816923 -264.365994) (xy 344.816923 -264.365995)
			(xy 344.813185 -264.413645) (xy 344.802061 -264.460129) (xy 344.783824 -264.504309) (xy 344.758919 -264.545104)
			(xy 344.743786 -264.563606) (xy 344.738198 -264.57021) (xy 344.729054 -264.59434) (xy 344.727513 -264.598688)
			(xy 344.725857 -264.607762) (xy 344.725752 -264.612374) (xy 344.725752 -265.176) (xy 345.615272 -265.176)
			(xy 345.619232 -265.126946) (xy 345.631009 -265.079162) (xy 345.6503 -265.033886) (xy 345.676603 -264.99229)
			(xy 345.709238 -264.955453) (xy 345.747359 -264.924328) (xy 345.78998 -264.899721) (xy 345.835996 -264.882269)
			(xy 345.884215 -264.872425) (xy 345.93339 -264.870444) (xy 345.982245 -264.876376) (xy 346.029516 -264.890068)
			(xy 346.073978 -264.911166) (xy 346.114481 -264.939122) (xy 346.149974 -264.973214) (xy 346.179539 -265.012558)
			(xy 346.20241 -265.056135) (xy 346.217994 -265.102816) (xy 346.225889 -265.151393) (xy 346.226384 -265.176)
			(xy 347.49538 -265.176) (xy 347.49934 -265.126946) (xy 347.511117 -265.079162) (xy 347.530408 -265.033886)
			(xy 347.556711 -264.99229) (xy 347.589346 -264.955453) (xy 347.627467 -264.924328) (xy 347.670088 -264.899721)
			(xy 347.716104 -264.882269) (xy 347.764323 -264.872425) (xy 347.813498 -264.870444) (xy 347.862353 -264.876376)
			(xy 347.909624 -264.890068) (xy 347.954086 -264.911166) (xy 347.994589 -264.939122) (xy 348.030082 -264.973214)
			(xy 348.059647 -265.012558) (xy 348.082518 -265.056135) (xy 348.098102 -265.102816) (xy 348.105997 -265.151393)
			(xy 348.106492 -265.176) (xy 348.105997 -265.200607) (xy 348.098102 -265.249184) (xy 348.082518 -265.295865)
			(xy 348.059647 -265.339442) (xy 348.030082 -265.378786) (xy 347.994589 -265.412878) (xy 347.954086 -265.440834)
			(xy 347.909624 -265.461932) (xy 347.862353 -265.475624) (xy 347.813498 -265.481556) (xy 347.764323 -265.479575)
			(xy 347.716104 -265.469731) (xy 347.670088 -265.452279) (xy 347.627467 -265.427672) (xy 347.589346 -265.396547)
			(xy 347.556711 -265.35971) (xy 347.530408 -265.318114) (xy 347.511117 -265.272838) (xy 347.49934 -265.225054)
			(xy 347.49538 -265.176) (xy 346.226384 -265.176) (xy 346.225889 -265.200607) (xy 346.217994 -265.249184)
			(xy 346.20241 -265.295865) (xy 346.179539 -265.339442) (xy 346.149974 -265.378786) (xy 346.114481 -265.412878)
			(xy 346.073978 -265.440834) (xy 346.029516 -265.461932) (xy 345.982245 -265.475624) (xy 345.93339 -265.481556)
			(xy 345.884215 -265.479575) (xy 345.835996 -265.469731) (xy 345.78998 -265.452279) (xy 345.747359 -265.427672)
			(xy 345.709238 -265.396547) (xy 345.676603 -265.35971) (xy 345.6503 -265.318114) (xy 345.631009 -265.272838)
			(xy 345.619232 -265.225054) (xy 345.615272 -265.176) (xy 344.725752 -265.176) (xy 344.725752 -265.739626)
			(xy 344.725853 -265.744238) (xy 344.727514 -265.753311) (xy 344.729054 -265.75766) (xy 344.738198 -265.78179)
			(xy 344.743786 -265.788394) (xy 344.758913 -265.8069) (xy 344.783817 -265.847694) (xy 344.802053 -265.891873)
			(xy 344.813177 -265.938356) (xy 344.816915 -265.986005) (xy 344.816915 -265.986006) (xy 346.085426 -265.986006)
			(xy 346.089386 -265.936952) (xy 346.101163 -265.889168) (xy 346.120454 -265.843892) (xy 346.146757 -265.802296)
			(xy 346.179392 -265.765459) (xy 346.217513 -265.734334) (xy 346.260134 -265.709727) (xy 346.30615 -265.692275)
			(xy 346.354369 -265.682431) (xy 346.403544 -265.68045) (xy 346.452399 -265.686382) (xy 346.49967 -265.700074)
			(xy 346.544132 -265.721172) (xy 346.584635 -265.749128) (xy 346.620128 -265.78322) (xy 346.649693 -265.822564)
			(xy 346.672564 -265.866141) (xy 346.688148 -265.912822) (xy 346.696043 -265.961399) (xy 346.696538 -265.986006)
			(xy 346.696043 -266.010613) (xy 346.688148 -266.05919) (xy 346.672564 -266.105871) (xy 346.649693 -266.149448)
			(xy 346.620128 -266.188792) (xy 346.584635 -266.222884) (xy 346.544132 -266.25084) (xy 346.49967 -266.271938)
			(xy 346.452399 -266.28563) (xy 346.403544 -266.291562) (xy 346.354369 -266.289581) (xy 346.30615 -266.279737)
			(xy 346.260134 -266.262285) (xy 346.217513 -266.237678) (xy 346.179392 -266.206553) (xy 346.146757 -266.169716)
			(xy 346.120454 -266.12812) (xy 346.101163 -266.082844) (xy 346.089386 -266.03506) (xy 346.085426 -265.986006)
			(xy 344.816915 -265.986006) (xy 344.813175 -266.033653) (xy 344.802051 -266.080135) (xy 344.783813 -266.124314)
			(xy 344.758907 -266.165107) (xy 344.743786 -266.183618) (xy 344.738198 -266.190222) (xy 344.729054 -266.214352)
			(xy 344.727514 -266.2187) (xy 344.72586 -266.227774) (xy 344.725752 -266.232386) (xy 344.725752 -266.796012)
			(xy 345.615272 -266.796012) (xy 345.619232 -266.746958) (xy 345.631009 -266.699174) (xy 345.6503 -266.653898)
			(xy 345.676603 -266.612302) (xy 345.709238 -266.575465) (xy 345.747359 -266.54434) (xy 345.78998 -266.519733)
			(xy 345.835996 -266.502281) (xy 345.884215 -266.492437) (xy 345.93339 -266.490456) (xy 345.982245 -266.496388)
			(xy 346.029516 -266.51008) (xy 346.073978 -266.531178) (xy 346.114481 -266.559134) (xy 346.149974 -266.593226)
			(xy 346.179539 -266.63257) (xy 346.20241 -266.676147) (xy 346.217994 -266.722828) (xy 346.225889 -266.771405)
			(xy 346.226384 -266.796012) (xy 346.555326 -266.796012) (xy 346.559286 -266.746958) (xy 346.571063 -266.699174)
			(xy 346.590354 -266.653898) (xy 346.616657 -266.612302) (xy 346.649292 -266.575465) (xy 346.687413 -266.54434)
			(xy 346.730034 -266.519733) (xy 346.77605 -266.502281) (xy 346.824269 -266.492437) (xy 346.873444 -266.490456)
			(xy 346.922299 -266.496388) (xy 346.96957 -266.51008) (xy 347.014032 -266.531178) (xy 347.054535 -266.559134)
			(xy 347.090028 -266.593226) (xy 347.119593 -266.63257) (xy 347.142464 -266.676147) (xy 347.158048 -266.722828)
			(xy 347.165943 -266.771405) (xy 347.166438 -266.796012) (xy 347.165943 -266.820619) (xy 347.158048 -266.869196)
			(xy 347.142464 -266.915877) (xy 347.119593 -266.959454) (xy 347.090028 -266.998798) (xy 347.054535 -267.03289)
			(xy 347.014032 -267.060846) (xy 346.96957 -267.081944) (xy 346.922299 -267.095636) (xy 346.873444 -267.101568)
			(xy 346.824269 -267.099587) (xy 346.77605 -267.089743) (xy 346.730034 -267.072291) (xy 346.687413 -267.047684)
			(xy 346.649292 -267.016559) (xy 346.616657 -266.979722) (xy 346.590354 -266.938126) (xy 346.571063 -266.89285)
			(xy 346.559286 -266.845066) (xy 346.555326 -266.796012) (xy 346.226384 -266.796012) (xy 346.225889 -266.820619)
			(xy 346.217994 -266.869196) (xy 346.20241 -266.915877) (xy 346.179539 -266.959454) (xy 346.149974 -266.998798)
			(xy 346.114481 -267.03289) (xy 346.073978 -267.060846) (xy 346.029516 -267.081944) (xy 345.982245 -267.095636)
			(xy 345.93339 -267.101568) (xy 345.884215 -267.099587) (xy 345.835996 -267.089743) (xy 345.78998 -267.072291)
			(xy 345.747359 -267.047684) (xy 345.709238 -267.016559) (xy 345.676603 -266.979722) (xy 345.6503 -266.938126)
			(xy 345.631009 -266.89285) (xy 345.619232 -266.845066) (xy 345.615272 -266.796012) (xy 344.725752 -266.796012)
			(xy 344.725752 -266.978638) (xy 344.726184 -266.988704) (xy 344.733913 -267.007293) (xy 344.740738 -267.014706)
			(xy 344.913966 -267.187934) (xy 344.921365 -267.194777) (xy 344.939964 -267.202498) (xy 344.950034 -267.20292)
		)
		(stroke
			(width 0)
			(type solid)
		)
		(fill yes)
		(layer "In2.Cu")
		(net "PVDDIO_P0")
	)
	(gr_poly
		(pts
			(xy 370.08308 -401.139152) (xy 370.09304 -401.138662) (xy 370.111456 -401.131065) (xy 370.118894 -401.12442)
			(xy 370.531898 -400.711416) (xy 370.538731 -400.704013) (xy 370.546435 -400.685415) (xy 370.546884 -400.675348)
			(xy 370.546884 -398.919446) (xy 370.546433 -398.909292) (xy 370.538568 -398.890566) (xy 370.531644 -398.883124)
			(xy 370.5098 -398.861534) (xy 370.502861 -398.855328) (xy 370.485797 -398.847922) (xy 370.476526 -398.847056)
			(xy 370.452077 -398.84541) (xy 370.404131 -398.835302) (xy 370.358414 -398.817669) (xy 370.316099 -398.792962)
			(xy 370.278271 -398.761816) (xy 370.245903 -398.725029) (xy 370.219823 -398.683546) (xy 370.200701 -398.638432)
			(xy 370.189028 -398.590843) (xy 370.185104 -398.542) (xy 370.189028 -398.493158) (xy 370.200701 -398.445569)
			(xy 370.219823 -398.400454) (xy 370.245902 -398.358971) (xy 370.278271 -398.322184) (xy 370.316098 -398.291038)
			(xy 370.358413 -398.266331) (xy 370.40413 -398.248698) (xy 370.452076 -398.23859) (xy 370.476526 -398.236948)
			(xy 370.485806 -398.236125) (xy 370.502878 -398.228705) (xy 370.5098 -398.22247) (xy 370.531644 -398.20088)
			(xy 370.538594 -398.193456) (xy 370.546453 -398.174719) (xy 370.546884 -398.164558) (xy 370.546884 -397.028924)
			(xy 370.52885 -397.003016) (xy 370.51361 -396.997428) (xy 370.491881 -396.989015) (xy 370.451062 -396.966552)
			(xy 370.414132 -396.938144) (xy 370.381949 -396.904453) (xy 370.355261 -396.866262) (xy 370.334688 -396.824458)
			(xy 370.320708 -396.780012) (xy 370.313647 -396.733958) (xy 370.313204 -396.710662) (xy 370.313704 -396.685264)
			(xy 370.322104 -396.635168) (xy 370.338682 -396.587153) (xy 370.36298 -396.542546) (xy 370.394328 -396.502577)
			(xy 370.412772 -396.48511) (xy 370.421154 -396.47749) (xy 370.42979 -396.457424) (xy 370.426996 -396.35811)
			(xy 370.417598 -396.338552) (xy 370.408708 -396.33144) (xy 370.390146 -396.315638) (xy 370.357419 -396.279511)
			(xy 370.330346 -396.238975) (xy 370.309512 -396.194905) (xy 370.295369 -396.148255) (xy 370.288224 -396.100035)
			(xy 370.287804 -396.075662) (xy 370.288243 -396.051546) (xy 370.295248 -396.003826) (xy 370.309106 -395.957628)
			(xy 370.329522 -395.91393) (xy 370.342414 -395.893544) (xy 370.348256 -395.884654) (xy 370.351812 -395.864588)
			(xy 370.33073 -395.772386) (xy 370.318538 -395.755622) (xy 370.309648 -395.750288) (xy 370.288846 -395.737432)
			(xy 370.250929 -395.706554) (xy 370.217979 -395.670423) (xy 370.190716 -395.629829) (xy 370.169734 -395.58566)
			(xy 370.155494 -395.53888) (xy 370.148305 -395.490512) (xy 370.14785 -395.466062) (xy 370.148411 -395.438779)
			(xy 370.157371 -395.384954) (xy 370.175041 -395.333328) (xy 370.200943 -395.285301) (xy 370.234374 -395.242176)
			(xy 370.254022 -395.223238) (xy 370.261468 -395.215745) (xy 370.270007 -395.19645) (xy 370.270532 -395.1859)
			(xy 370.270532 -395.111224) (xy 370.269947 -395.100688) (xy 370.261423 -395.081408) (xy 370.254022 -395.073886)
			(xy 370.234368 -395.054953) (xy 370.200927 -395.011831) (xy 370.17502 -394.963804) (xy 370.15735 -394.912176)
			(xy 370.148397 -394.858346) (xy 370.14785 -394.831062) (xy 370.148281 -394.80739) (xy 370.155036 -394.760531)
			(xy 370.168387 -394.715109) (xy 370.177822 -394.693394) (xy 370.18214 -394.683996) (xy 370.182902 -394.66393)
			(xy 370.150644 -394.57757) (xy 370.136928 -394.562838) (xy 370.12753 -394.55852) (xy 370.103162 -394.546825)
			(xy 370.058281 -394.516714) (xy 370.018895 -394.479702) (xy 369.986055 -394.436777) (xy 369.960635 -394.389081)
			(xy 369.943312 -394.337885) (xy 369.934548 -394.284554) (xy 369.933982 -394.25753) (xy 369.934463 -394.231539)
			(xy 369.94259 -394.180196) (xy 369.95865 -394.130757) (xy 369.982246 -394.084439) (xy 370.012797 -394.042382)
			(xy 370.049552 -394.005623) (xy 370.091605 -393.975067) (xy 370.13792 -393.951465) (xy 370.187357 -393.9354)
			(xy 370.238699 -393.927266) (xy 370.26469 -393.926822) (xy 370.288458 -393.927232) (xy 370.335506 -393.934034)
			(xy 370.381096 -393.947498) (xy 370.402866 -393.957048) (xy 370.414804 -393.962636) (xy 370.440458 -393.960604)
			(xy 370.523516 -393.907518) (xy 370.530481 -393.902666) (xy 370.540985 -393.889343) (xy 370.546583 -393.873328)
			(xy 370.546884 -393.864846) (xy 370.546884 -393.719558) (xy 370.554504 -393.701016) (xy 370.560092 -393.695428)
			(xy 370.561108 -393.67587) (xy 370.562997 -393.6489) (xy 370.574449 -393.596064) (xy 370.594345 -393.545796)
			(xy 370.622155 -393.499435) (xy 370.657136 -393.458216) (xy 370.698359 -393.423237) (xy 370.744722 -393.395432)
			(xy 370.794992 -393.375541) (xy 370.847829 -393.364094) (xy 370.874798 -393.36218) (xy 370.88445 -393.361672)
			(xy 370.901468 -393.354052) (xy 371.025674 -393.229846) (xy 371.033074 -393.223006) (xy 371.051673 -393.215291)
			(xy 371.061742 -393.21486) (xy 371.345206 -393.21486) (xy 371.356966 -393.214273) (xy 371.378034 -393.203821)
			(xy 371.385592 -393.194794) (xy 371.441726 -393.121388) (xy 371.446298 -393.09802) (xy 371.44325 -393.08659)
			(xy 371.437809 -393.065286) (xy 371.431953 -393.021707) (xy 371.431566 -392.999722) (xy 371.432076 -392.973735)
			(xy 371.440206 -392.9224) (xy 371.456267 -392.87297) (xy 371.479863 -392.82666) (xy 371.510413 -392.784612)
			(xy 371.547164 -392.747861) (xy 371.589212 -392.717311) (xy 371.635522 -392.693715) (xy 371.684952 -392.677654)
			(xy 371.736287 -392.669524) (xy 371.788261 -392.669524) (xy 371.839596 -392.677654) (xy 371.889026 -392.693715)
			(xy 371.935336 -392.717311) (xy 371.977384 -392.747861) (xy 372.014135 -392.784612) (xy 372.044685 -392.82666)
			(xy 372.068281 -392.87297) (xy 372.084342 -392.9224) (xy 372.092472 -392.973735) (xy 372.092982 -392.999722)
			(xy 372.092606 -393.021708) (xy 372.086748 -393.065287) (xy 372.081298 -393.08659) (xy 372.07825 -393.09802)
			(xy 372.082822 -393.121388) (xy 372.138956 -393.194794) (xy 372.146547 -393.203784) (xy 372.167592 -393.214247)
			(xy 372.179342 -393.21486) (xy 372.545356 -393.21486) (xy 372.557111 -393.214262) (xy 372.578161 -393.203798)
			(xy 372.585742 -393.194794) (xy 372.641876 -393.121388) (xy 372.646448 -393.09802) (xy 372.6434 -393.08659)
			(xy 372.637959 -393.065286) (xy 372.632104 -393.021707) (xy 372.631716 -392.999722) (xy 372.632226 -392.973735)
			(xy 372.640356 -392.9224) (xy 372.656417 -392.87297) (xy 372.680013 -392.82666) (xy 372.710563 -392.784612)
			(xy 372.747314 -392.747861) (xy 372.789362 -392.717311) (xy 372.835672 -392.693715) (xy 372.885102 -392.677654)
			(xy 372.936437 -392.669524) (xy 372.988411 -392.669524) (xy 373.039746 -392.677654) (xy 373.089176 -392.693715)
			(xy 373.135486 -392.717311) (xy 373.177534 -392.747861) (xy 373.214285 -392.784612) (xy 373.244835 -392.82666)
			(xy 373.268431 -392.87297) (xy 373.284492 -392.9224) (xy 373.292622 -392.973735) (xy 373.293132 -392.999722)
			(xy 373.292756 -393.021708) (xy 373.286897 -393.065287) (xy 373.281448 -393.08659) (xy 373.2784 -393.09802)
			(xy 373.282972 -393.121388) (xy 373.339106 -393.194794) (xy 373.346701 -393.203775) (xy 373.367746 -393.214218)
			(xy 373.379492 -393.21486) (xy 373.745252 -393.21486) (xy 373.757007 -393.214263) (xy 373.778059 -393.2038)
			(xy 373.785638 -393.194794) (xy 373.841772 -393.121388) (xy 373.846344 -393.09802) (xy 373.843296 -393.08659)
			(xy 373.837855 -393.065286) (xy 373.832001 -393.021707) (xy 373.831612 -392.999722) (xy 373.832122 -392.973735)
			(xy 373.840252 -392.9224) (xy 373.856313 -392.87297) (xy 373.879909 -392.82666) (xy 373.910459 -392.784612)
			(xy 373.94721 -392.747861) (xy 373.989258 -392.717311) (xy 374.035568 -392.693715) (xy 374.084998 -392.677654)
			(xy 374.136333 -392.669524) (xy 374.188307 -392.669524) (xy 374.239642 -392.677654) (xy 374.289072 -392.693715)
			(xy 374.335382 -392.717311) (xy 374.37743 -392.747861) (xy 374.414181 -392.784612) (xy 374.444731 -392.82666)
			(xy 374.468327 -392.87297) (xy 374.484388 -392.9224) (xy 374.492518 -392.973735) (xy 374.493028 -392.999722)
			(xy 374.492652 -393.021708) (xy 374.486792 -393.065287) (xy 374.481344 -393.08659) (xy 374.478296 -393.09802)
			(xy 374.482868 -393.121388) (xy 374.539002 -393.194794) (xy 374.546596 -393.203776) (xy 374.567642 -393.21422)
			(xy 374.579388 -393.21486) (xy 374.945402 -393.21486) (xy 374.957163 -393.214274) (xy 374.978232 -393.203823)
			(xy 374.985788 -393.194794) (xy 375.041922 -393.121388) (xy 375.046494 -393.09802) (xy 375.043446 -393.08659)
			(xy 375.038005 -393.065286) (xy 375.032149 -393.021707) (xy 375.031762 -392.999722) (xy 375.032272 -392.973735)
			(xy 375.040402 -392.9224) (xy 375.056463 -392.87297) (xy 375.080059 -392.82666) (xy 375.110609 -392.784612)
			(xy 375.14736 -392.747861) (xy 375.189408 -392.717311) (xy 375.235718 -392.693715) (xy 375.285148 -392.677654)
			(xy 375.336483 -392.669524) (xy 375.388457 -392.669524) (xy 375.439792 -392.677654) (xy 375.489222 -392.693715)
			(xy 375.535532 -392.717311) (xy 375.57758 -392.747861) (xy 375.614331 -392.784612) (xy 375.644881 -392.82666)
			(xy 375.668477 -392.87297) (xy 375.684538 -392.9224) (xy 375.692668 -392.973735) (xy 375.693178 -392.999722)
			(xy 375.692802 -393.021708) (xy 375.686943 -393.065287) (xy 375.681494 -393.08659) (xy 375.678446 -393.09802)
			(xy 375.683018 -393.121388) (xy 375.739152 -393.194794) (xy 375.746743 -393.203785) (xy 375.767788 -393.214249)
			(xy 375.779538 -393.21486) (xy 376.145298 -393.21486) (xy 376.157059 -393.214275) (xy 376.178129 -393.203824)
			(xy 376.185684 -393.194794) (xy 376.241818 -393.121388) (xy 376.24639 -393.09802) (xy 376.243342 -393.08659)
			(xy 376.237901 -393.065286) (xy 376.232045 -393.021707) (xy 376.231658 -392.999722) (xy 376.232168 -392.973735)
			(xy 376.240298 -392.9224) (xy 376.256359 -392.87297) (xy 376.279955 -392.82666) (xy 376.310505 -392.784612)
			(xy 376.347256 -392.747861) (xy 376.389304 -392.717311) (xy 376.435614 -392.693715) (xy 376.485044 -392.677654)
			(xy 376.536379 -392.669524) (xy 376.588353 -392.669524) (xy 376.639688 -392.677654) (xy 376.689118 -392.693715)
			(xy 376.735428 -392.717311) (xy 376.777476 -392.747861) (xy 376.814227 -392.784612) (xy 376.844777 -392.82666)
			(xy 376.868373 -392.87297) (xy 376.884434 -392.9224) (xy 376.892564 -392.973735) (xy 376.893074 -392.999722)
			(xy 376.892698 -393.021708) (xy 376.886839 -393.065287) (xy 376.88139 -393.08659) (xy 376.878342 -393.09802)
			(xy 376.882914 -393.121388) (xy 376.939048 -393.194794) (xy 376.946639 -393.203785) (xy 376.967684 -393.214252)
			(xy 376.979434 -393.21486) (xy 377.345194 -393.21486) (xy 377.356944 -393.214255) (xy 377.377982 -393.203781)
			(xy 377.38558 -393.194794) (xy 377.441714 -393.121388) (xy 377.446286 -393.09802) (xy 377.443238 -393.08659)
			(xy 377.437797 -393.065286) (xy 377.431941 -393.021707) (xy 377.431554 -392.999722) (xy 377.432064 -392.973735)
			(xy 377.440194 -392.9224) (xy 377.456255 -392.87297) (xy 377.479851 -392.82666) (xy 377.510401 -392.784612)
			(xy 377.547152 -392.747861) (xy 377.5892 -392.717311) (xy 377.63551 -392.693715) (xy 377.68494 -392.677654)
			(xy 377.736275 -392.669524) (xy 377.788249 -392.669524) (xy 377.839584 -392.677654) (xy 377.889014 -392.693715)
			(xy 377.935324 -392.717311) (xy 377.977372 -392.747861) (xy 378.014123 -392.784612) (xy 378.044673 -392.82666)
			(xy 378.068269 -392.87297) (xy 378.08433 -392.9224) (xy 378.09246 -392.973735) (xy 378.09297 -392.999722)
			(xy 378.092594 -393.021708) (xy 378.086735 -393.065287) (xy 378.081286 -393.08659) (xy 378.078238 -393.09802)
			(xy 378.08281 -393.121388) (xy 378.138944 -393.194794) (xy 378.146534 -393.203786) (xy 378.16758 -393.214254)
			(xy 378.17933 -393.21486) (xy 378.545344 -393.21486) (xy 378.5571 -393.214265) (xy 378.578155 -393.203803)
			(xy 378.58573 -393.194794) (xy 378.641864 -393.121388) (xy 378.646436 -393.09802) (xy 378.643388 -393.08659)
			(xy 378.637948 -393.065286) (xy 378.632093 -393.021707) (xy 378.631704 -392.999722) (xy 378.632214 -392.973735)
			(xy 378.640344 -392.9224) (xy 378.656405 -392.87297) (xy 378.680001 -392.82666) (xy 378.710551 -392.784612)
			(xy 378.747302 -392.747861) (xy 378.78935 -392.717311) (xy 378.83566 -392.693715) (xy 378.88509 -392.677654)
			(xy 378.936425 -392.669524) (xy 378.988399 -392.669524) (xy 379.039734 -392.677654) (xy 379.089164 -392.693715)
			(xy 379.135474 -392.717311) (xy 379.177522 -392.747861) (xy 379.214273 -392.784612) (xy 379.244823 -392.82666)
			(xy 379.268419 -392.87297) (xy 379.28448 -392.9224) (xy 379.29261 -392.973735) (xy 379.29312 -392.999722)
			(xy 379.292744 -393.021708) (xy 379.286884 -393.065287) (xy 379.281436 -393.08659) (xy 379.278388 -393.09802)
			(xy 379.28296 -393.121388) (xy 379.339094 -393.194794) (xy 379.346688 -393.203778) (xy 379.367733 -393.214225)
			(xy 379.37948 -393.21486) (xy 379.74524 -393.21486) (xy 379.756996 -393.214266) (xy 379.778052 -393.203805)
			(xy 379.785626 -393.194794) (xy 379.84176 -393.121388) (xy 379.846332 -393.09802) (xy 379.843284 -393.08659)
			(xy 379.837844 -393.065286) (xy 379.831989 -393.021707) (xy 379.8316 -392.999722) (xy 379.83211 -392.973735)
			(xy 379.84024 -392.9224) (xy 379.856301 -392.87297) (xy 379.879897 -392.82666) (xy 379.910447 -392.784612)
			(xy 379.947198 -392.747861) (xy 379.989246 -392.717311) (xy 380.035556 -392.693715) (xy 380.084986 -392.677654)
			(xy 380.136321 -392.669524) (xy 380.188295 -392.669524) (xy 380.23963 -392.677654) (xy 380.28906 -392.693715)
			(xy 380.33537 -392.717311) (xy 380.377418 -392.747861) (xy 380.414169 -392.784612) (xy 380.444719 -392.82666)
			(xy 380.468315 -392.87297) (xy 380.484376 -392.9224) (xy 380.492506 -392.973735) (xy 380.493016 -392.999722)
			(xy 380.49264 -393.021708) (xy 380.48678 -393.065287) (xy 380.481332 -393.08659) (xy 380.478284 -393.09802)
			(xy 380.482856 -393.121388) (xy 380.53899 -393.194794) (xy 380.546583 -393.203778) (xy 380.567629 -393.214227)
			(xy 380.579376 -393.21486) (xy 380.94539 -393.21486) (xy 380.957141 -393.214255) (xy 380.97818 -393.203782)
			(xy 380.985776 -393.194794) (xy 381.04191 -393.121388) (xy 381.046482 -393.09802) (xy 381.043434 -393.08659)
			(xy 381.037993 -393.065286) (xy 381.032137 -393.021707) (xy 381.03175 -392.999722) (xy 381.03226 -392.973735)
			(xy 381.04039 -392.9224) (xy 381.056451 -392.87297) (xy 381.080047 -392.82666) (xy 381.110597 -392.784612)
			(xy 381.147348 -392.747861) (xy 381.189396 -392.717311) (xy 381.235706 -392.693715) (xy 381.285136 -392.677654)
			(xy 381.336471 -392.669524) (xy 381.388445 -392.669524) (xy 381.43978 -392.677654) (xy 381.48921 -392.693715)
			(xy 381.53552 -392.717311) (xy 381.577568 -392.747861) (xy 381.614319 -392.784612) (xy 381.644869 -392.82666)
			(xy 381.668465 -392.87297) (xy 381.684526 -392.9224) (xy 381.692656 -392.973735) (xy 381.693166 -392.999722)
			(xy 381.69279 -393.021708) (xy 381.686931 -393.065287) (xy 381.681482 -393.08659) (xy 381.678434 -393.09802)
			(xy 381.683006 -393.121388) (xy 381.73914 -393.194794) (xy 381.74673 -393.203786) (xy 381.767775 -393.214256)
			(xy 381.779526 -393.21486) (xy 382.145286 -393.21486) (xy 382.157037 -393.214256) (xy 382.178078 -393.203784)
			(xy 382.185672 -393.194794) (xy 382.241806 -393.121388) (xy 382.246378 -393.09802) (xy 382.24333 -393.08659)
			(xy 382.237889 -393.065286) (xy 382.232033 -393.021707) (xy 382.231646 -392.999722) (xy 382.232156 -392.973735)
			(xy 382.240286 -392.9224) (xy 382.256347 -392.87297) (xy 382.279943 -392.82666) (xy 382.310493 -392.784612)
			(xy 382.347244 -392.747861) (xy 382.389292 -392.717311) (xy 382.435602 -392.693715) (xy 382.485032 -392.677654)
			(xy 382.536367 -392.669524) (xy 382.588341 -392.669524) (xy 382.639676 -392.677654) (xy 382.689106 -392.693715)
			(xy 382.735416 -392.717311) (xy 382.777464 -392.747861) (xy 382.814215 -392.784612) (xy 382.844765 -392.82666)
			(xy 382.868361 -392.87297) (xy 382.884422 -392.9224) (xy 382.892552 -392.973735) (xy 382.893062 -392.999722)
			(xy 382.892686 -393.021708) (xy 382.886827 -393.065287) (xy 382.881378 -393.08659) (xy 382.87833 -393.09802)
			(xy 382.882902 -393.121388) (xy 382.939036 -393.194794) (xy 382.946626 -393.203787) (xy 382.967671 -393.214258)
			(xy 382.979422 -393.21486) (xy 383.345182 -393.21486) (xy 383.356934 -393.214257) (xy 383.377975 -393.203786)
			(xy 383.385568 -393.194794) (xy 383.441702 -393.121388) (xy 383.446274 -393.09802) (xy 383.443226 -393.08659)
			(xy 383.437785 -393.065286) (xy 383.43193 -393.021707) (xy 383.431542 -392.999722) (xy 383.432052 -392.973735)
			(xy 383.440182 -392.9224) (xy 383.456243 -392.87297) (xy 383.479839 -392.82666) (xy 383.510389 -392.784612)
			(xy 383.54714 -392.747861) (xy 383.589188 -392.717311) (xy 383.635498 -392.693715) (xy 383.684928 -392.677654)
			(xy 383.736263 -392.669524) (xy 383.788237 -392.669524) (xy 383.839572 -392.677654) (xy 383.889002 -392.693715)
			(xy 383.935312 -392.717311) (xy 383.97736 -392.747861) (xy 384.014111 -392.784612) (xy 384.044661 -392.82666)
			(xy 384.068257 -392.87297) (xy 384.084318 -392.9224) (xy 384.092448 -392.973735) (xy 384.092958 -392.999722)
			(xy 384.092582 -393.021708) (xy 384.086723 -393.065287) (xy 384.081274 -393.08659) (xy 384.078226 -393.09802)
			(xy 384.082798 -393.121388) (xy 384.138932 -393.194794) (xy 384.146522 -393.203788) (xy 384.167567 -393.214261)
			(xy 384.179318 -393.21486) (xy 384.545332 -393.21486) (xy 384.557089 -393.214267) (xy 384.578148 -393.203809)
			(xy 384.585718 -393.194794) (xy 384.641852 -393.121388) (xy 384.646424 -393.09802) (xy 384.643376 -393.08659)
			(xy 384.637936 -393.065286) (xy 384.632081 -393.021707) (xy 384.631692 -392.999722) (xy 384.632202 -392.973735)
			(xy 384.640332 -392.9224) (xy 384.656393 -392.87297) (xy 384.679989 -392.82666) (xy 384.710539 -392.784612)
			(xy 384.74729 -392.747861) (xy 384.789338 -392.717311) (xy 384.835648 -392.693715) (xy 384.885078 -392.677654)
			(xy 384.936413 -392.669524) (xy 384.988387 -392.669524) (xy 385.039722 -392.677654) (xy 385.089152 -392.693715)
			(xy 385.135462 -392.717311) (xy 385.17751 -392.747861) (xy 385.214261 -392.784612) (xy 385.244811 -392.82666)
			(xy 385.268407 -392.87297) (xy 385.284468 -392.9224) (xy 385.292598 -392.973735) (xy 385.293108 -392.999722)
			(xy 385.292732 -393.021708) (xy 385.286872 -393.065287) (xy 385.281424 -393.08659) (xy 385.278376 -393.09802)
			(xy 385.282948 -393.121388) (xy 385.339082 -393.194794) (xy 385.346675 -393.203779) (xy 385.36772 -393.214232)
			(xy 385.379468 -393.21486) (xy 385.755896 -393.21486) (xy 385.765965 -393.215284) (xy 385.784565 -393.223004)
			(xy 385.791964 -393.229846) (xy 385.826 -393.23137) (xy 385.852924 -393.209272) (xy 385.861481 -393.201602)
			(xy 385.871209 -393.180805) (xy 385.870947 -393.157848) (xy 385.866386 -393.147296) (xy 385.855429 -393.124255)
			(xy 385.839943 -393.075642) (xy 385.83209 -393.025231) (xy 385.831588 -392.999722) (xy 385.832069 -392.973732)
			(xy 385.840198 -392.922391) (xy 385.856257 -392.872954) (xy 385.879853 -392.826639) (xy 385.910404 -392.784584)
			(xy 385.947157 -392.747827) (xy 385.989208 -392.717272) (xy 386.035522 -392.693671) (xy 386.084957 -392.677606)
			(xy 386.136297 -392.669472) (xy 386.188277 -392.66947) (xy 386.239617 -392.6776) (xy 386.289054 -392.693661)
			(xy 386.335369 -392.717258) (xy 386.377422 -392.747809) (xy 386.414179 -392.784564) (xy 386.444733 -392.826616)
			(xy 386.468332 -392.87293) (xy 386.484396 -392.922365) (xy 386.492528 -392.973705) (xy 386.492529 -393.025685)
			(xy 386.492525 -393.025709) (xy 387.032248 -393.025709) (xy 387.032248 -392.973735) (xy 387.040378 -392.9224)
			(xy 387.056439 -392.87297) (xy 387.080035 -392.82666) (xy 387.110585 -392.784612) (xy 387.147336 -392.747861)
			(xy 387.189384 -392.717311) (xy 387.235694 -392.693715) (xy 387.285124 -392.677654) (xy 387.336459 -392.669524)
			(xy 387.388433 -392.669524) (xy 387.439768 -392.677654) (xy 387.489198 -392.693715) (xy 387.535508 -392.717311)
			(xy 387.577556 -392.747861) (xy 387.614307 -392.784612) (xy 387.644857 -392.82666) (xy 387.668453 -392.87297)
			(xy 387.684514 -392.9224) (xy 387.692644 -392.973735) (xy 387.693154 -392.999722) (xy 387.692644 -393.025709)
			(xy 387.684514 -393.077044) (xy 387.668453 -393.126474) (xy 387.644857 -393.172784) (xy 387.614307 -393.214832)
			(xy 387.577556 -393.251583) (xy 387.535508 -393.282133) (xy 387.489198 -393.305729) (xy 387.439768 -393.32179)
			(xy 387.388433 -393.32992) (xy 387.336459 -393.32992) (xy 387.285124 -393.32179) (xy 387.235694 -393.305729)
			(xy 387.189384 -393.282133) (xy 387.147336 -393.251583) (xy 387.110585 -393.214832) (xy 387.080035 -393.172784)
			(xy 387.056439 -393.126474) (xy 387.040378 -393.077044) (xy 387.032248 -393.025709) (xy 386.492525 -393.025709)
			(xy 386.484398 -393.077025) (xy 386.468336 -393.126462) (xy 386.444738 -393.172776) (xy 386.414185 -393.214829)
			(xy 386.37743 -393.251585) (xy 386.335377 -393.282138) (xy 386.289062 -393.305736) (xy 386.239626 -393.321798)
			(xy 386.188286 -393.329929) (xy 386.162296 -393.33043) (xy 386.142992 -393.329922) (xy 386.12699 -393.328906)
			(xy 386.10032 -393.345162) (xy 386.054854 -393.446508) (xy 386.051067 -393.456049) (xy 386.050658 -393.476554)
			(xy 386.058346 -393.495568) (xy 386.065268 -393.50315) (xy 386.070856 -393.508738) (xy 386.079 -393.516069)
			(xy 386.099524 -393.523689) (xy 386.11048 -393.52347) (xy 386.198618 -393.516612) (xy 386.217922 -393.505944)
			(xy 386.224526 -393.4968) (xy 386.240224 -393.476234) (xy 386.276937 -393.439783) (xy 386.318879 -393.409494)
			(xy 386.365027 -393.386108) (xy 386.414254 -393.370193) (xy 386.465358 -393.36214) (xy 386.491226 -393.361672)
			(xy 386.51724 -393.362152) (xy 386.568629 -393.370289) (xy 386.618108 -393.386374) (xy 386.664458 -393.410011)
			(xy 386.706533 -393.440615) (xy 386.743296 -393.477431) (xy 386.77384 -393.519551) (xy 386.797409 -393.565934)
			(xy 386.813423 -393.615437) (xy 386.81787 -393.641072) (xy 386.819394 -393.65047) (xy 387.09219 -394.122402)
			(xy 387.099556 -394.128244) (xy 387.118336 -394.144047) (xy 387.151473 -394.180252) (xy 387.178898 -394.220956)
			(xy 387.200007 -394.265266) (xy 387.214338 -394.312208) (xy 387.221576 -394.360752) (xy 387.221984 -394.385292)
			(xy 387.22173 -394.397484) (xy 387.221476 -394.407136) (xy 387.227572 -394.42517) (xy 387.286246 -394.49248)
			(xy 387.30301 -394.501116) (xy 387.312916 -394.502132) (xy 387.339683 -394.505459) (xy 387.391709 -394.519685)
			(xy 387.440738 -394.542164) (xy 387.48547 -394.572299) (xy 387.524719 -394.609293) (xy 387.557446 -394.652165)
			(xy 387.582784 -394.69978) (xy 387.60006 -394.750874) (xy 387.608818 -394.804094) (xy 387.609334 -394.831062)
			(xy 387.608919 -394.854925) (xy 387.602066 -394.902157) (xy 387.588498 -394.947915) (xy 387.578854 -394.969746)
			(xy 387.571996 -394.984478) (xy 387.577584 -395.015466) (xy 387.98881 -395.426692) (xy 387.99535 -395.432806)
			(xy 388.011548 -395.440405) (xy 388.029373 -395.44195) (xy 388.038086 -395.4399) (xy 388.136384 -395.413484)
			(xy 388.155434 -395.394434) (xy 388.15899 -395.380972) (xy 388.165389 -395.35853) (xy 388.183624 -395.315575)
			(xy 388.207705 -395.275602) (xy 388.237155 -395.239403) (xy 388.253986 -395.223238) (xy 388.261436 -395.215747)
			(xy 388.269981 -395.196451) (xy 388.270496 -395.1859) (xy 388.270496 -395.111224) (xy 388.26991 -395.100689)
			(xy 388.261381 -395.081413) (xy 388.253986 -395.073886) (xy 388.234329 -395.054954) (xy 388.200882 -395.011835)
			(xy 388.17497 -394.963808) (xy 388.157296 -394.912179) (xy 388.148341 -394.858348) (xy 388.147814 -394.831062)
			(xy 388.148068 -394.81887) (xy 388.148322 -394.809218) (xy 388.142226 -394.791184) (xy 388.083552 -394.723874)
			(xy 388.066788 -394.715238) (xy 388.056882 -394.714222) (xy 388.029967 -394.710873) (xy 387.977665 -394.69653)
			(xy 387.928405 -394.673844) (xy 387.883508 -394.643422) (xy 387.844178 -394.606079) (xy 387.811471 -394.562819)
			(xy 387.786263 -394.5148) (xy 387.769231 -394.463311) (xy 387.764528 -394.4366) (xy 387.763004 -394.427202)
			(xy 387.489954 -393.954762) (xy 387.482842 -393.94892) (xy 387.46411 -393.93314) (xy 387.431059 -393.896995)
			(xy 387.403702 -393.856369) (xy 387.38264 -393.812151) (xy 387.368333 -393.765309) (xy 387.361094 -393.716869)
			(xy 387.360668 -393.69238) (xy 387.361179 -393.666393) (xy 387.369312 -393.61506) (xy 387.385374 -393.56563)
			(xy 387.408971 -393.519322) (xy 387.439521 -393.477274) (xy 387.476271 -393.440523) (xy 387.518318 -393.409973)
			(xy 387.564627 -393.386376) (xy 387.614056 -393.370313) (xy 387.665389 -393.362179) (xy 387.691376 -393.361672)
			(xy 387.717425 -393.36215) (xy 387.768882 -393.370299) (xy 387.818425 -393.386414) (xy 387.864828 -393.410098)
			(xy 387.906945 -393.440764) (xy 387.943732 -393.477654) (xy 387.974282 -393.519855) (xy 387.997836 -393.566324)
			(xy 388.013815 -393.615911) (xy 388.018274 -393.64158) (xy 388.019544 -393.650978) (xy 388.04348 -393.69238)
			(xy 388.560564 -393.69238) (xy 388.561083 -393.666394) (xy 388.569216 -393.615061) (xy 388.585278 -393.565633)
			(xy 388.608874 -393.519325) (xy 388.639422 -393.477278) (xy 388.676172 -393.440528) (xy 388.718218 -393.409978)
			(xy 388.764525 -393.386381) (xy 388.813953 -393.370318) (xy 388.865286 -393.362184) (xy 388.891272 -393.361672)
			(xy 388.917281 -393.362167) (xy 388.968657 -393.370322) (xy 389.018123 -393.386418) (xy 389.064458 -393.410061)
			(xy 389.106522 -393.440665) (xy 389.143276 -393.477477) (xy 389.173813 -393.519589) (xy 389.197382 -393.565962)
			(xy 389.213401 -393.615453) (xy 389.217916 -393.641072) (xy 389.21944 -393.65047) (xy 389.492236 -394.122402)
			(xy 389.499602 -394.128244) (xy 389.518384 -394.144041) (xy 389.551501 -394.180259) (xy 389.57891 -394.220968)
			(xy 389.600011 -394.265277) (xy 389.61434 -394.312215) (xy 389.621585 -394.360754) (xy 389.62203 -394.385292)
			(xy 389.621776 -394.396976) (xy 389.621522 -394.406882) (xy 389.627872 -394.424916) (xy 389.687054 -394.491972)
			(xy 389.704326 -394.500862) (xy 389.713978 -394.501624) (xy 389.738318 -394.504241) (xy 389.785868 -394.515882)
			(xy 389.831185 -394.5344) (xy 389.873279 -394.559391) (xy 389.911233 -394.590311) (xy 389.944219 -394.626484)
			(xy 389.971516 -394.667122) (xy 389.992529 -394.711337) (xy 390.006799 -394.758165) (xy 390.014016 -394.806585)
			(xy 390.01446 -394.831062) (xy 390.01395 -394.857049) (xy 390.00582 -394.908384) (xy 389.989759 -394.957814)
			(xy 389.966163 -395.004124) (xy 389.935613 -395.046172) (xy 389.898862 -395.082923) (xy 389.856814 -395.113473)
			(xy 389.810504 -395.137069) (xy 389.761074 -395.15313) (xy 389.709739 -395.16126) (xy 389.657765 -395.16126)
			(xy 389.60643 -395.15313) (xy 389.557 -395.137069) (xy 389.51069 -395.113473) (xy 389.468642 -395.082923)
			(xy 389.431891 -395.046172) (xy 389.401341 -395.004124) (xy 389.377745 -394.957814) (xy 389.361684 -394.908384)
			(xy 389.353554 -394.857049) (xy 389.353044 -394.831062) (xy 389.353298 -394.819378) (xy 389.353552 -394.809472)
			(xy 389.347202 -394.791438) (xy 389.28802 -394.724382) (xy 389.270748 -394.715492) (xy 389.261096 -394.71473)
			(xy 389.236913 -394.712058) (xy 389.189648 -394.700518) (xy 389.144582 -394.682185) (xy 389.102684 -394.657453)
			(xy 389.064857 -394.626855) (xy 389.031916 -394.591049) (xy 389.00457 -394.550809) (xy 388.983408 -394.506999)
			(xy 388.968887 -394.460563) (xy 388.964678 -394.4366) (xy 388.963154 -394.427202) (xy 388.690358 -393.95527)
			(xy 388.682992 -393.949428) (xy 388.664243 -393.933593) (xy 388.631124 -393.897383) (xy 388.603711 -393.856682)
			(xy 388.582605 -393.81238) (xy 388.568268 -393.765449) (xy 388.561014 -393.716916) (xy 388.560564 -393.69238)
			(xy 388.04348 -393.69238) (xy 388.292086 -394.122402) (xy 388.299452 -394.128244) (xy 388.318233 -394.144047)
			(xy 388.35137 -394.180252) (xy 388.378794 -394.220956) (xy 388.399904 -394.265265) (xy 388.414235 -394.312207)
			(xy 388.421473 -394.360751) (xy 388.42188 -394.385292) (xy 388.421626 -394.397484) (xy 388.421372 -394.407136)
			(xy 388.427468 -394.42517) (xy 388.486142 -394.49248) (xy 388.502906 -394.501116) (xy 388.512812 -394.502132)
			(xy 388.539579 -394.505459) (xy 388.591606 -394.519684) (xy 388.640635 -394.542163) (xy 388.685368 -394.572298)
			(xy 388.724618 -394.609292) (xy 388.757345 -394.652164) (xy 388.782683 -394.699779) (xy 388.79996 -394.750873)
			(xy 388.808717 -394.804094) (xy 388.80923 -394.831062) (xy 388.808667 -394.858344) (xy 388.799703 -394.912167)
			(xy 388.78203 -394.963789) (xy 388.756125 -395.011812) (xy 388.722691 -395.054933) (xy 388.703058 -395.073886)
			(xy 388.695607 -395.081376) (xy 388.687063 -395.100672) (xy 388.686548 -395.111224) (xy 388.686548 -395.1859)
			(xy 388.68714 -395.196432) (xy 388.69568 -395.215696) (xy 388.703058 -395.223238) (xy 388.722712 -395.242171)
			(xy 388.756151 -395.285293) (xy 388.782056 -395.33332) (xy 388.799724 -395.384949) (xy 388.808674 -395.438778)
			(xy 388.80923 -395.466062) (xy 388.808797 -395.49018) (xy 388.801802 -395.537905) (xy 388.787954 -395.58411)
			(xy 388.767548 -395.627816) (xy 388.75462 -395.64818) (xy 388.748778 -395.65707) (xy 388.745222 -395.677136)
			(xy 388.766304 -395.769338) (xy 388.778496 -395.786102) (xy 388.787386 -395.791436) (xy 388.80819 -395.804289)
			(xy 388.846111 -395.835165) (xy 388.879066 -395.871295) (xy 388.906332 -395.911889) (xy 388.927315 -395.956059)
			(xy 388.941556 -396.002841) (xy 388.948742 -396.051211) (xy 388.949184 -396.075662) (xy 388.948718 -396.101129)
			(xy 388.940916 -396.151463) (xy 388.925491 -396.200006) (xy 388.902807 -396.245611) (xy 388.888478 -396.26667)
			(xy 388.883664 -396.274189) (xy 388.879012 -396.291412) (xy 388.880527 -396.309187) (xy 388.888028 -396.325373)
			(xy 388.894066 -396.331948) (xy 390.197848 -397.63573) (xy 390.204695 -397.643128) (xy 390.212427 -397.661726)
			(xy 390.212834 -397.671798) (xy 390.212834 -399.341086) (xy 390.213274 -399.351149) (xy 390.221014 -399.369727)
			(xy 390.22782 -399.377154) (xy 390.472422 -399.621756) (xy 390.498584 -399.628614) (xy 390.512046 -399.624804)
			(xy 390.540123 -399.617273) (xy 390.597383 -399.607223) (xy 390.626346 -399.604738) (xy 390.63549 -399.603976)
			(xy 390.652 -399.596356) (xy 391.057384 -399.191226) (xy 391.064396 -399.183539) (xy 391.07209 -399.164229)
			(xy 391.071486 -399.143452) (xy 391.067544 -399.133822) (xy 391.020554 -399.03273) (xy 390.993122 -399.016728)
			(xy 390.976866 -399.017998) (xy 390.94918 -399.019268) (xy 390.923193 -399.018783) (xy 390.871859 -399.010649)
			(xy 390.82243 -398.994585) (xy 390.776122 -398.970985) (xy 390.734077 -398.940432) (xy 390.697329 -398.903677)
			(xy 390.666783 -398.861626) (xy 390.643192 -398.815315) (xy 390.627137 -398.765882) (xy 390.619012 -398.714547)
			(xy 390.618472 -398.68856) (xy 390.618887 -398.664787) (xy 390.625701 -398.617731) (xy 390.639184 -398.572137)
			(xy 390.659056 -398.528942) (xy 390.68491 -398.489039) (xy 390.70026 -398.470882) (xy 390.705937 -398.463759)
			(xy 390.712313 -398.446709) (xy 390.712706 -398.437608) (xy 390.712706 -398.406112) (xy 390.712328 -398.397009)
			(xy 390.705943 -398.37996) (xy 390.70026 -398.372838) (xy 390.68491 -398.354679) (xy 390.659042 -398.314784)
			(xy 390.639163 -398.271591) (xy 390.625684 -398.225993) (xy 390.618884 -398.178934) (xy 390.618472 -398.15516)
			(xy 390.618905 -398.130749) (xy 390.626078 -398.082458) (xy 390.640276 -398.035747) (xy 390.661191 -397.991633)
			(xy 390.688368 -397.951075) (xy 390.721215 -397.914956) (xy 390.759017 -397.884061) (xy 390.779762 -397.871188)
			(xy 390.791192 -397.86433) (xy 390.8044 -397.841216) (xy 390.8044 -397.726916) (xy 390.791446 -397.703802)
			(xy 390.779762 -397.69669) (xy 390.759054 -397.683814) (xy 390.721319 -397.652929) (xy 390.688533 -397.616834)
			(xy 390.661407 -397.576312) (xy 390.640531 -397.532244) (xy 390.626358 -397.485587) (xy 390.619196 -397.437353)
			(xy 390.618726 -397.412972) (xy 390.619283 -397.385352) (xy 390.628462 -397.330879) (xy 390.646559 -397.278687)
			(xy 390.673073 -397.230226) (xy 390.707267 -397.18684) (xy 390.748191 -397.149736) (xy 390.771126 -397.134334)
			(xy 390.782556 -397.127222) (xy 390.795002 -397.1036) (xy 390.791446 -396.9893) (xy 390.77773 -396.966694)
			(xy 390.765792 -396.96009) (xy 390.744097 -396.947458) (xy 390.704453 -396.916664) (xy 390.669916 -396.880233)
			(xy 390.641281 -396.839001) (xy 390.619205 -396.793916) (xy 390.604195 -396.746013) (xy 390.596596 -396.696392)
			(xy 390.59612 -396.671292) (xy 390.59663 -396.645305) (xy 390.60476 -396.59397) (xy 390.620821 -396.54454)
			(xy 390.644417 -396.49823) (xy 390.674967 -396.456182) (xy 390.711718 -396.419431) (xy 390.753766 -396.388881)
			(xy 390.800076 -396.365285) (xy 390.849506 -396.349224) (xy 390.900841 -396.341094) (xy 390.952815 -396.341094)
			(xy 391.00415 -396.349224) (xy 391.05358 -396.365285) (xy 391.09989 -396.388881) (xy 391.141938 -396.419431)
			(xy 391.178689 -396.456182) (xy 391.209239 -396.49823) (xy 391.232835 -396.54454) (xy 391.248896 -396.59397)
			(xy 391.257026 -396.645305) (xy 391.257536 -396.671292) (xy 391.256982 -396.698913) (xy 391.247807 -396.753388)
			(xy 391.229713 -396.805583) (xy 391.2032 -396.854047) (xy 391.169005 -396.897434) (xy 391.128079 -396.934539)
			(xy 391.105136 -396.94993) (xy 391.093706 -396.957042) (xy 391.08126 -396.980664) (xy 391.084816 -397.094964)
			(xy 391.098532 -397.11757) (xy 391.11047 -397.124174) (xy 391.132163 -397.136807) (xy 391.171805 -397.167604)
			(xy 391.206339 -397.204037) (xy 391.234973 -397.245268) (xy 391.257049 -397.290352) (xy 391.272061 -397.338253)
			(xy 391.279664 -397.387873) (xy 391.280142 -397.412972) (xy 391.279706 -397.437382) (xy 391.27253 -397.485671)
			(xy 391.258329 -397.532379) (xy 391.237412 -397.57649) (xy 391.210234 -397.617045) (xy 391.177387 -397.653161)
			(xy 391.139586 -397.684054) (xy 391.118852 -397.696944) (xy 391.107422 -397.703802) (xy 391.094214 -397.726916)
			(xy 391.094214 -397.841216) (xy 391.107168 -397.86433) (xy 391.118852 -397.871442) (xy 391.139563 -397.884318)
			(xy 391.177303 -397.915201) (xy 391.210095 -397.951295) (xy 391.237228 -397.991816) (xy 391.258111 -398.035883)
			(xy 391.272293 -398.082542) (xy 391.279465 -398.130777) (xy 391.279888 -398.15516) (xy 391.279472 -398.178932)
			(xy 391.272654 -398.225986) (xy 391.259168 -398.271578) (xy 391.239292 -398.314769) (xy 391.213435 -398.354668)
			(xy 391.1981 -398.372838) (xy 391.19242 -398.37996) (xy 391.186044 -398.397011) (xy 391.185654 -398.406112)
			(xy 391.185654 -398.437608) (xy 391.186034 -398.44671) (xy 391.192421 -398.463758) (xy 391.1981 -398.470882)
			(xy 391.213446 -398.489043) (xy 391.239308 -398.52894) (xy 391.259181 -398.572133) (xy 391.272654 -398.61773)
			(xy 391.279449 -398.664787) (xy 391.279888 -398.68856) (xy 391.278618 -398.716246) (xy 391.277348 -398.732502)
			(xy 391.29335 -398.759934) (xy 391.394442 -398.806924) (xy 391.404076 -398.810819) (xy 391.424829 -398.811371)
			(xy 391.444129 -398.803724) (xy 391.451846 -398.796764) (xy 392.437366 -397.81099) (xy 392.44334 -397.804471)
			(xy 392.450827 -397.788466) (xy 392.452427 -397.770869) (xy 392.450574 -397.762222) (xy 392.425174 -397.664432)
			(xy 392.406378 -397.645128) (xy 392.393424 -397.641572) (xy 392.366645 -397.633414) (xy 392.315638 -397.61035)
			(xy 392.268542 -397.580092) (xy 392.24712 -397.56207) (xy 392.240008 -397.555974) (xy 392.22299 -397.549624)
			(xy 392.137646 -397.549624) (xy 392.120628 -397.555974) (xy 392.113516 -397.56207) (xy 392.092586 -397.579714)
			(xy 392.04662 -397.609444) (xy 391.996874 -397.632292) (xy 391.94437 -397.647785) (xy 391.890189 -397.655607)
			(xy 391.862818 -397.65605) (xy 391.835561 -397.655588) (xy 391.781602 -397.647833) (xy 391.729297 -397.632476)
			(xy 391.679709 -397.609832) (xy 391.633848 -397.580362) (xy 391.592649 -397.544664) (xy 391.556949 -397.503466)
			(xy 391.527476 -397.457607) (xy 391.50483 -397.40802) (xy 391.489471 -397.355715) (xy 391.481713 -397.301757)
			(xy 391.481713 -397.247243) (xy 391.489471 -397.193285) (xy 391.50483 -397.14098) (xy 391.527476 -397.091393)
			(xy 391.556949 -397.045534) (xy 391.592649 -397.004336) (xy 391.633848 -396.968638) (xy 391.679709 -396.939168)
			(xy 391.729297 -396.916524) (xy 391.781602 -396.901167) (xy 391.835561 -396.893412) (xy 391.862818 -396.893034)
			(xy 391.890187 -396.893507) (xy 391.944364 -396.901334) (xy 391.996865 -396.916824) (xy 392.046614 -396.939659)
			(xy 392.092587 -396.969371) (xy 392.113516 -396.987014) (xy 392.120628 -396.99311) (xy 392.137646 -396.99946)
			(xy 392.22299 -396.99946) (xy 392.240008 -396.99311) (xy 392.24712 -396.987014) (xy 392.268053 -396.969373)
			(xy 392.314021 -396.939649) (xy 392.363767 -396.916803) (xy 392.416269 -396.901307) (xy 392.470447 -396.893478)
			(xy 392.525189 -396.893478) (xy 392.579367 -396.901307) (xy 392.631869 -396.916803) (xy 392.681615 -396.939649)
			(xy 392.727583 -396.969373) (xy 392.748516 -396.987014) (xy 392.755628 -396.99311) (xy 392.772646 -396.99946)
			(xy 392.85799 -396.99946) (xy 392.875008 -396.99311) (xy 392.88212 -396.987014) (xy 392.903051 -396.969373)
			(xy 392.949018 -396.939648) (xy 392.998765 -396.916806) (xy 393.051268 -396.901318) (xy 393.105448 -396.893502)
			(xy 393.132818 -396.893034) (xy 393.158175 -396.893467) (xy 393.20844 -396.90021) (xy 393.257374 -396.913535)
			(xy 393.2809 -396.923006) (xy 393.295124 -396.928848) (xy 393.32535 -396.923006) (xy 393.41171 -396.8369)
			(xy 393.418566 -396.829506) (xy 393.426315 -396.810907) (xy 393.426696 -396.800832) (xy 393.426696 -396.11681)
			(xy 393.427222 -396.080679) (xy 393.436143 -396.008969) (xy 393.444476 -395.973808) (xy 393.44727 -395.962632)
			(xy 393.442952 -395.94028) (xy 393.381992 -395.858492) (xy 393.361672 -395.847824) (xy 393.350242 -395.847316)
			(xy 393.323734 -395.845782) (xy 393.271492 -395.836293) (xy 393.221071 -395.819649) (xy 393.173446 -395.796173)
			(xy 393.129538 -395.766318) (xy 393.090194 -395.730662) (xy 393.056176 -395.689894) (xy 393.028142 -395.644801)
			(xy 393.006633 -395.596256) (xy 392.992065 -395.545197) (xy 392.984719 -395.492611) (xy 392.984228 -395.466062)
			(xy 392.984712 -395.438457) (xy 392.992663 -395.383821) (xy 393.008406 -395.330903) (xy 393.031614 -395.280807)
			(xy 393.061801 -395.234579) (xy 393.079732 -395.213586) (xy 393.085828 -395.206728) (xy 393.092432 -395.189202)
			(xy 393.092432 -395.103604) (xy 393.085828 -395.086078) (xy 393.079732 -395.07922) (xy 393.06183 -395.058203)
			(xy 393.031641 -395.011981) (xy 393.008428 -394.96189) (xy 392.992676 -394.908978) (xy 392.984714 -394.854348)
			(xy 392.984228 -394.826744) (xy 392.984688 -394.79949) (xy 392.99244 -394.745536) (xy 393.007793 -394.693235)
			(xy 393.030434 -394.643652) (xy 393.059901 -394.597796) (xy 393.095595 -394.556601) (xy 393.136789 -394.520906)
			(xy 393.182645 -394.491437) (xy 393.232228 -394.468796) (xy 393.284528 -394.453442) (xy 393.338482 -394.445689)
			(xy 393.365736 -394.445236) (xy 393.39101 -394.445649) (xy 393.441115 -394.452331) (xy 393.489897 -394.465574)
			(xy 393.536503 -394.485146) (xy 393.558522 -394.49756) (xy 393.569952 -394.504418) (xy 393.596876 -394.504672)
			(xy 393.696952 -394.449046) (xy 393.710922 -394.425932) (xy 393.71143 -394.41247) (xy 393.712851 -394.381426)
			(xy 393.724521 -394.320392) (xy 393.745933 -394.262057) (xy 393.776521 -394.207966) (xy 393.795504 -394.183362)
			(xy 393.80062 -394.176439) (xy 393.806335 -394.160213) (xy 393.80668 -394.151612) (xy 393.80668 -393.817094)
			(xy 393.806254 -393.80705) (xy 393.798544 -393.7885) (xy 393.784308 -393.774327) (xy 393.775184 -393.770104)
			(xy 393.674092 -393.728448) (xy 393.643866 -393.734544) (xy 393.632944 -393.745466) (xy 393.611327 -393.766401)
			(xy 393.562723 -393.801882) (xy 393.509155 -393.829297) (xy 393.451949 -393.847967) (xy 393.392522 -393.857429)
			(xy 393.362434 -393.857988) (xy 393.335833 -393.857522) (xy 393.283147 -393.850125) (xy 393.231999 -393.835481)
			(xy 393.183381 -393.813877) (xy 393.138234 -393.785729) (xy 393.097434 -393.751585) (xy 393.061771 -393.712105)
			(xy 393.046458 -393.690348) (xy 393.038976 -393.680375) (xy 393.016999 -393.668665) (xy 393.004548 -393.667996)
			(xy 392.92022 -393.667996) (xy 392.907772 -393.668675) (xy 392.885787 -393.680375) (xy 392.87831 -393.690348)
			(xy 392.863016 -393.712119) (xy 392.827359 -393.751608) (xy 392.786559 -393.785755) (xy 392.741408 -393.8139)
			(xy 392.692783 -393.835495) (xy 392.641628 -393.850121) (xy 392.588937 -393.857494) (xy 392.562334 -393.857988)
			(xy 392.535081 -393.857527) (xy 392.481129 -393.849774) (xy 392.42883 -393.834422) (xy 392.379248 -393.811783)
			(xy 392.333393 -393.782317) (xy 392.292199 -393.746625) (xy 392.256503 -393.705434) (xy 392.227034 -393.659582)
			(xy 392.20439 -393.610002) (xy 392.189033 -393.557704) (xy 392.181275 -393.503753) (xy 392.181275 -393.449247)
			(xy 392.189033 -393.395296) (xy 392.20439 -393.342998) (xy 392.227034 -393.293418) (xy 392.256503 -393.247566)
			(xy 392.292199 -393.206375) (xy 392.333393 -393.170683) (xy 392.379248 -393.141217) (xy 392.42883 -393.118578)
			(xy 392.481129 -393.103226) (xy 392.535081 -393.095473) (xy 392.562334 -393.094972) (xy 392.588937 -393.095435)
			(xy 392.641626 -393.102829) (xy 392.692778 -393.117468) (xy 392.741401 -393.139068) (xy 392.786553 -393.167212)
			(xy 392.82736 -393.201354) (xy 392.863029 -393.240831) (xy 392.87831 -393.262612) (xy 392.885786 -393.272596)
			(xy 392.907764 -393.28433) (xy 392.92022 -393.284964) (xy 393.004548 -393.284964) (xy 393.016987 -393.284268)
			(xy 393.03894 -393.272547) (xy 393.046458 -393.262612) (xy 393.061749 -393.240836) (xy 393.097403 -393.201339)
			(xy 393.138201 -393.167183) (xy 393.183352 -393.139029) (xy 393.231978 -393.117427) (xy 393.283135 -393.102794)
			(xy 393.335829 -393.095415) (xy 393.362434 -393.094972) (xy 393.392524 -393.095533) (xy 393.451958 -393.104975)
			(xy 393.509171 -393.123635) (xy 393.562743 -393.15105) (xy 393.611344 -393.186539) (xy 393.632944 -393.207494)
			(xy 393.643866 -393.218416) (xy 393.674092 -393.224512) (xy 393.775184 -393.182856) (xy 393.784314 -393.178647)
			(xy 393.798545 -393.164467) (xy 393.806243 -393.145911) (xy 393.80668 -393.135866) (xy 393.80668 -392.826494)
			(xy 393.806254 -392.81645) (xy 393.798544 -392.7979) (xy 393.784308 -392.783727) (xy 393.775184 -392.779504)
			(xy 393.674092 -392.737848) (xy 393.643866 -392.743944) (xy 393.632944 -392.754866) (xy 393.611327 -392.775801)
			(xy 393.562723 -392.811282) (xy 393.509155 -392.838697) (xy 393.451949 -392.857367) (xy 393.392522 -392.866829)
			(xy 393.362434 -392.867388) (xy 393.335833 -392.866922) (xy 393.283147 -392.859525) (xy 393.231999 -392.844881)
			(xy 393.183381 -392.823277) (xy 393.138234 -392.795129) (xy 393.097434 -392.760985) (xy 393.061771 -392.721505)
			(xy 393.046458 -392.699748) (xy 393.038976 -392.689775) (xy 393.016999 -392.678065) (xy 393.004548 -392.677396)
			(xy 392.92022 -392.677396) (xy 392.907772 -392.678075) (xy 392.885787 -392.689775) (xy 392.87831 -392.699748)
			(xy 392.863016 -392.721519) (xy 392.827359 -392.761008) (xy 392.786559 -392.795155) (xy 392.741408 -392.8233)
			(xy 392.692783 -392.844895) (xy 392.641628 -392.859521) (xy 392.588937 -392.866894) (xy 392.562334 -392.867388)
			(xy 392.535081 -392.866927) (xy 392.481129 -392.859174) (xy 392.42883 -392.843822) (xy 392.379248 -392.821183)
			(xy 392.333393 -392.791717) (xy 392.292199 -392.756025) (xy 392.256503 -392.714834) (xy 392.227034 -392.668982)
			(xy 392.20439 -392.619402) (xy 392.189033 -392.567104) (xy 392.181275 -392.513153) (xy 392.181275 -392.458647)
			(xy 392.189033 -392.404696) (xy 392.20439 -392.352398) (xy 392.227034 -392.302818) (xy 392.256503 -392.256966)
			(xy 392.292199 -392.215775) (xy 392.333393 -392.180083) (xy 392.379248 -392.150617) (xy 392.42883 -392.127978)
			(xy 392.481129 -392.112626) (xy 392.535081 -392.104873) (xy 392.562334 -392.104372) (xy 392.590535 -392.104882)
			(xy 392.646322 -392.113193) (xy 392.700277 -392.129628) (xy 392.751223 -392.15383) (xy 392.798049 -392.18527)
			(xy 392.839735 -392.223264) (xy 392.875372 -392.266982) (xy 392.904183 -392.315471) (xy 392.915394 -392.341354)
			(xy 392.919604 -392.350485) (xy 392.933783 -392.36472) (xy 392.952338 -392.372427) (xy 392.97243 -392.372427)
			(xy 392.990985 -392.36472) (xy 393.005164 -392.350485) (xy 393.009374 -392.341354) (xy 393.015468 -392.326888)
			(xy 393.029711 -392.298913) (xy 393.037822 -392.285474) (xy 393.043156 -392.276838) (xy 393.046458 -392.257788)
			(xy 393.027916 -392.169904) (xy 393.017248 -392.153902) (xy 393.00912 -392.148314) (xy 392.987645 -392.132984)
			(xy 392.948727 -392.097355) (xy 392.915091 -392.056704) (xy 392.887377 -392.011805) (xy 392.866114 -391.963516)
			(xy 392.851709 -391.912757) (xy 392.844436 -391.860498) (xy 392.84402 -391.834116) (xy 392.844506 -391.806865)
			(xy 392.852262 -391.752917) (xy 392.867617 -391.700622) (xy 392.890259 -391.651045) (xy 392.919725 -391.605195)
			(xy 392.955416 -391.564004) (xy 392.996607 -391.528313) (xy 393.042457 -391.498847) (xy 393.092034 -391.476205)
			(xy 393.144329 -391.46085) (xy 393.198277 -391.453094) (xy 393.252779 -391.453094) (xy 393.306727 -391.46085)
			(xy 393.359022 -391.476205) (xy 393.408599 -391.498847) (xy 393.454449 -391.528313) (xy 393.49564 -391.564004)
			(xy 393.531331 -391.605195) (xy 393.560797 -391.651045) (xy 393.583439 -391.700622) (xy 393.598794 -391.752917)
			(xy 393.60655 -391.806865) (xy 393.607036 -391.834116) (xy 393.606588 -391.860502) (xy 393.599308 -391.912771)
			(xy 393.584892 -391.963537) (xy 393.563612 -392.011829) (xy 393.55014 -392.034522) (xy 393.544806 -392.043158)
			(xy 393.541504 -392.062208) (xy 393.560046 -392.150092) (xy 393.570714 -392.166094) (xy 393.578842 -392.171682)
			(xy 393.593258 -392.181875) (xy 393.62035 -392.20452) (xy 393.632944 -392.216894) (xy 393.643866 -392.227816)
			(xy 393.674092 -392.233912) (xy 393.775184 -392.192256) (xy 393.784314 -392.188047) (xy 393.798545 -392.173867)
			(xy 393.806243 -392.155311) (xy 393.80668 -392.145266) (xy 393.80668 -391.709402) (xy 393.806257 -391.699332)
			(xy 393.798541 -391.680729) (xy 393.791694 -391.673334) (xy 392.822684 -390.704324) (xy 392.815286 -390.697478)
			(xy 392.796687 -390.689745) (xy 392.786616 -390.689338) (xy 388.71652 -390.689338) (xy 388.7058 -390.689764)
			(xy 388.686209 -390.698462) (xy 388.678674 -390.706102) (xy 388.620762 -390.770364) (xy 388.614158 -390.790684)
			(xy 388.615428 -390.801352) (xy 388.61746 -390.838944) (xy 388.61746 -390.850374) (xy 388.617758 -390.859059)
			(xy 388.623476 -390.875457) (xy 388.634361 -390.888987) (xy 388.64159 -390.893808) (xy 388.727188 -390.945878)
			(xy 388.75335 -390.946894) (xy 388.765288 -390.940798) (xy 388.788794 -390.92927) (xy 388.838544 -390.912966)
			(xy 388.890242 -390.904713) (xy 388.916418 -390.904222) (xy 388.942405 -390.904706) (xy 388.99374 -390.91284)
			(xy 389.04317 -390.928904) (xy 389.089479 -390.952504) (xy 389.131525 -390.983057) (xy 389.168275 -391.019811)
			(xy 389.198822 -391.061862) (xy 389.222414 -391.108174) (xy 389.238471 -391.157607) (xy 389.246597 -391.208942)
			(xy 389.247126 -391.23493) (xy 389.246502 -391.264872) (xy 389.235765 -391.323785) (xy 389.22579 -391.352024)
			(xy 389.221218 -391.363962) (xy 389.224266 -391.388346) (xy 389.278876 -391.467594) (xy 389.2864 -391.477493)
			(xy 389.308368 -391.489082) (xy 389.320786 -391.489692) (xy 389.382508 -391.489692) (xy 389.41107 -391.490253)
			(xy 389.467491 -391.499189) (xy 389.521819 -391.516841) (xy 389.572717 -391.542774) (xy 389.618933 -391.576349)
			(xy 389.639556 -391.596118) (xy 390.62152 -392.578082) (xy 390.628919 -392.584927) (xy 390.647517 -392.592657)
			(xy 390.657588 -392.593068) (xy 390.87425 -392.593068) (xy 390.896573 -392.593346) (xy 390.940894 -392.598696)
			(xy 390.962642 -392.603736) (xy 390.975342 -392.607038) (xy 391.000234 -392.600434) (xy 391.081514 -392.524234)
			(xy 391.089642 -392.49985) (xy 391.087356 -392.486896) (xy 391.084401 -392.469841) (xy 391.08122 -392.43537)
			(xy 391.081006 -392.418062) (xy 391.081492 -392.390811) (xy 391.089248 -392.336863) (xy 391.104603 -392.284568)
			(xy 391.127245 -392.234991) (xy 391.156711 -392.189141) (xy 391.192402 -392.14795) (xy 391.233593 -392.112259)
			(xy 391.279443 -392.082793) (xy 391.32902 -392.060151) (xy 391.381315 -392.044796) (xy 391.435263 -392.03704)
			(xy 391.489765 -392.03704) (xy 391.543713 -392.044796) (xy 391.596008 -392.060151) (xy 391.645585 -392.082793)
			(xy 391.691435 -392.112259) (xy 391.732626 -392.14795) (xy 391.768317 -392.189141) (xy 391.797783 -392.234991)
			(xy 391.820425 -392.284568) (xy 391.83578 -392.336863) (xy 391.843536 -392.390811) (xy 391.844022 -392.418062)
			(xy 391.843546 -392.445431) (xy 391.835715 -392.499605) (xy 391.820222 -392.552104) (xy 391.797385 -392.60185)
			(xy 391.767673 -392.647822) (xy 391.750042 -392.66876) (xy 391.743946 -392.675872) (xy 391.737596 -392.69289)
			(xy 391.737596 -392.778234) (xy 391.743946 -392.795252) (xy 391.750042 -392.802364) (xy 391.767687 -392.823296)
			(xy 391.797419 -392.869264) (xy 391.820272 -392.919012) (xy 391.835774 -392.971517) (xy 391.843608 -393.025699)
			(xy 391.843612 -393.080444) (xy 391.835787 -393.134627) (xy 391.820292 -393.187134) (xy 391.797447 -393.236886)
			(xy 391.767721 -393.282858) (xy 391.750042 -393.30376) (xy 391.743946 -393.310872) (xy 391.737596 -393.32789)
			(xy 391.737596 -393.413234) (xy 391.743946 -393.430252) (xy 391.750042 -393.437364) (xy 391.767683 -393.458295)
			(xy 391.797406 -393.504262) (xy 391.820244 -393.554009) (xy 391.835728 -393.606513) (xy 391.843539 -393.660692)
			(xy 391.844022 -393.688062) (xy 391.843557 -393.714967) (xy 391.835989 -393.768243) (xy 391.821012 -393.819928)
			(xy 391.798923 -393.868997) (xy 391.770161 -393.914475) (xy 391.735294 -393.955463) (xy 391.695016 -393.991146)
			(xy 391.650125 -394.020817) (xy 391.60151 -394.043888) (xy 391.550137 -394.0599) (xy 391.497024 -394.068538)
			(xy 391.470134 -394.06957) (xy 391.458704 -394.069824) (xy 391.438638 -394.07973) (xy 391.375646 -394.158978)
			(xy 391.370566 -394.181076) (xy 391.372852 -394.192252) (xy 391.376755 -394.211832) (xy 391.38095 -394.251537)
			(xy 391.381234 -394.2715) (xy 391.38099 -394.291591) (xy 391.376791 -394.331553) (xy 391.372852 -394.351256)
			(xy 391.369804 -394.364718) (xy 391.378694 -394.39088) (xy 391.41507 -394.42263) (xy 392.211558 -394.42263)
			(xy 392.215629 -394.367008) (xy 392.227755 -394.312571) (xy 392.247678 -394.26048) (xy 392.274974 -394.211845)
			(xy 392.30906 -394.167702) (xy 392.349209 -394.128993) (xy 392.394567 -394.096542) (xy 392.444167 -394.071041)
			(xy 392.496951 -394.053034) (xy 392.551794 -394.042904) (xy 392.607528 -394.040867) (xy 392.662965 -394.046967)
			(xy 392.716922 -394.061073) (xy 392.768251 -394.082885) (xy 392.815857 -394.111939) (xy 392.858725 -394.147614)
			(xy 392.895942 -394.189151) (xy 392.926715 -394.235664) (xy 392.950387 -394.286161) (xy 392.966455 -394.339568)
			(xy 392.974575 -394.394744) (xy 392.975084 -394.42263) (xy 392.974575 -394.450516) (xy 392.966455 -394.505692)
			(xy 392.950387 -394.559099) (xy 392.926715 -394.609596) (xy 392.895942 -394.656109) (xy 392.858725 -394.697646)
			(xy 392.815857 -394.733321) (xy 392.768251 -394.762375) (xy 392.716922 -394.784187) (xy 392.662965 -394.798293)
			(xy 392.607528 -394.804393) (xy 392.551794 -394.802356) (xy 392.496951 -394.792226) (xy 392.444167 -394.774219)
			(xy 392.394567 -394.748718) (xy 392.349209 -394.716267) (xy 392.30906 -394.677558) (xy 392.274974 -394.633415)
			(xy 392.247678 -394.58478) (xy 392.227755 -394.532689) (xy 392.215629 -394.478252) (xy 392.211558 -394.42263)
			(xy 391.41507 -394.42263) (xy 391.466578 -394.467588) (xy 391.493756 -394.472668) (xy 391.50671 -394.468096)
			(xy 391.538104 -394.457473) (xy 391.60337 -394.445987) (xy 391.636504 -394.445236) (xy 391.663751 -394.445722)
			(xy 391.717691 -394.453478) (xy 391.769979 -394.468831) (xy 391.819549 -394.491469) (xy 391.865393 -394.520931)
			(xy 391.906577 -394.556617) (xy 391.942264 -394.597801) (xy 391.971727 -394.643644) (xy 391.994366 -394.693214)
			(xy 392.00972 -394.745501) (xy 392.017477 -394.799441) (xy 392.017479 -394.853935) (xy 392.009725 -394.907876)
			(xy 391.994374 -394.960164) (xy 391.971739 -395.009735) (xy 391.942279 -395.05558) (xy 391.906594 -395.096766)
			(xy 391.865412 -395.132455) (xy 391.81957 -395.161919) (xy 391.770001 -395.18456) (xy 391.717715 -395.199917)
			(xy 391.663775 -395.207676) (xy 391.609281 -395.20768) (xy 391.55534 -395.199929) (xy 391.503051 -395.18458)
			(xy 391.453479 -395.161946) (xy 391.407633 -395.132488) (xy 391.366445 -395.096806) (xy 391.330755 -395.055625)
			(xy 391.301288 -395.009784) (xy 391.278645 -394.960216) (xy 391.263287 -394.90793) (xy 391.255525 -394.853991)
			(xy 391.254996 -394.826744) (xy 391.255242 -394.806653) (xy 391.259447 -394.766692) (xy 391.263378 -394.746988)
			(xy 391.266426 -394.733526) (xy 391.257536 -394.707364) (xy 391.169652 -394.630656) (xy 391.142474 -394.625576)
			(xy 391.12952 -394.630148) (xy 391.098127 -394.640774) (xy 391.032861 -394.652268) (xy 390.999726 -394.653008)
			(xy 390.972472 -394.652546) (xy 390.918518 -394.644792) (xy 390.866217 -394.629439) (xy 390.816634 -394.606798)
			(xy 390.770777 -394.57733) (xy 390.729582 -394.541637) (xy 390.693885 -394.500443) (xy 390.664415 -394.454589)
			(xy 390.64177 -394.405007) (xy 390.626413 -394.352707) (xy 390.618655 -394.298754) (xy 390.618218 -394.2715)
			(xy 390.61875 -394.242607) (xy 390.627461 -394.185481) (xy 390.644684 -394.130321) (xy 390.670025 -394.078387)
			(xy 390.686036 -394.05433) (xy 390.694164 -394.042646) (xy 390.695942 -394.014452) (xy 390.647428 -393.92225)
			(xy 390.642783 -393.91426) (xy 390.628964 -393.902011) (xy 390.611703 -393.895449) (xy 390.60247 -393.895072)
			(xy 390.247632 -393.895072) (xy 390.219054 -393.894527) (xy 390.162606 -393.885558) (xy 390.108257 -393.867867)
			(xy 390.057345 -393.84189) (xy 390.011125 -393.808267) (xy 389.990584 -393.788392) (xy 389.138922 -392.93673)
			(xy 389.131521 -392.929893) (xy 389.112922 -392.922182) (xy 389.102854 -392.921744) (xy 388.993888 -392.921744)
			(xy 388.984254 -392.922209) (xy 388.966365 -392.929382) (xy 388.95909 -392.935714) (xy 388.901178 -392.990578)
			(xy 388.89305 -393.008104) (xy 388.892542 -393.01801) (xy 388.890691 -393.043018) (xy 388.880389 -393.092092)
			(xy 388.862798 -393.139048) (xy 388.83832 -393.182811) (xy 388.807517 -393.222378) (xy 388.771094 -393.256842)
			(xy 388.729887 -393.285413) (xy 388.684838 -393.307436) (xy 388.636982 -393.322407) (xy 388.587414 -393.329982)
			(xy 388.562342 -393.33043) (xy 388.53635 -393.32995) (xy 388.485005 -393.321824) (xy 388.435563 -393.305766)
			(xy 388.389243 -393.282171) (xy 388.347184 -393.25162) (xy 388.310422 -393.214865) (xy 388.279863 -393.172812)
			(xy 388.256259 -393.126496) (xy 388.240191 -393.077057) (xy 388.232055 -393.025714) (xy 388.231634 -392.999722)
			(xy 388.232904 -392.970766) (xy 388.233341 -392.962731) (xy 388.229706 -392.947064) (xy 388.225792 -392.940032)
			(xy 388.210552 -392.914886) (xy 388.206163 -392.908148) (xy 388.193991 -392.897652) (xy 388.186676 -392.894312)
			(xy 388.164801 -392.884817) (xy 388.123514 -392.860956) (xy 388.085694 -392.83191) (xy 388.068566 -392.815318)
			(xy 386.998464 -391.745216) (xy 386.978648 -391.724624) (xy 386.945037 -391.678409) (xy 386.919063 -391.627508)
			(xy 386.901363 -391.573173) (xy 386.892374 -391.51674) (xy 386.891784 -391.488168) (xy 386.891784 -391.435082)
			(xy 386.891293 -391.425078) (xy 386.883629 -391.406595) (xy 386.869476 -391.392452) (xy 386.850988 -391.384801)
			(xy 386.840984 -391.384282) (xy 386.827776 -391.384282) (xy 386.804916 -391.396982) (xy 386.797804 -391.408412)
			(xy 386.78482 -391.428678) (xy 386.753911 -391.465572) (xy 386.717977 -391.497592) (xy 386.677778 -391.52406)
			(xy 386.634164 -391.544416) (xy 386.588059 -391.558229) (xy 386.540437 -391.565208) (xy 386.516372 -391.565638)
			(xy 386.490384 -391.565126) (xy 386.439048 -391.556991) (xy 386.389617 -391.540927) (xy 386.343307 -391.517327)
			(xy 386.301259 -391.486774) (xy 386.264508 -391.45002) (xy 386.233958 -391.407969) (xy 386.210363 -391.361657)
			(xy 386.194302 -391.312225) (xy 386.186172 -391.260888) (xy 386.186172 -391.208912) (xy 386.194302 -391.157575)
			(xy 386.210363 -391.108143) (xy 386.233958 -391.061831) (xy 386.264508 -391.01978) (xy 386.301259 -390.983026)
			(xy 386.343307 -390.952473) (xy 386.389617 -390.928873) (xy 386.439048 -390.912809) (xy 386.490384 -390.904674)
			(xy 386.516372 -390.904222) (xy 386.544764 -390.904808) (xy 386.600715 -390.914506) (xy 386.654186 -390.933621)
			(xy 386.703604 -390.961592) (xy 386.725922 -390.979152) (xy 386.737352 -390.98855) (xy 386.766308 -390.992106)
			(xy 386.862828 -390.946386) (xy 386.8713 -390.941877) (xy 386.884365 -390.927839) (xy 386.891405 -390.91)
			(xy 386.891784 -390.900412) (xy 386.891784 -390.825482) (xy 386.891334 -390.815455) (xy 386.883741 -390.796899)
			(xy 386.877052 -390.789414) (xy 386.791708 -390.704324) (xy 386.784364 -390.69751) (xy 386.765902 -390.689771)
			(xy 386.755894 -390.689338) (xy 368.864896 -390.689338) (xy 368.859054 -390.69518) (xy 368.563906 -390.69518)
			(xy 368.553835 -390.695601) (xy 368.535227 -390.703312) (xy 368.527838 -390.710166) (xy 368.05616 -391.181844)
			(xy 368.049314 -391.189242) (xy 368.041586 -391.207841) (xy 368.041174 -391.217912) (xy 368.041174 -391.316035)
			(xy 369.238278 -391.316035) (xy 369.238278 -391.264061) (xy 369.246408 -391.212726) (xy 369.262469 -391.163296)
			(xy 369.286065 -391.116986) (xy 369.316615 -391.074938) (xy 369.353366 -391.038187) (xy 369.395414 -391.007637)
			(xy 369.441724 -390.984041) (xy 369.491154 -390.96798) (xy 369.542489 -390.95985) (xy 369.594463 -390.95985)
			(xy 369.645798 -390.96798) (xy 369.695228 -390.984041) (xy 369.741538 -391.007637) (xy 369.783586 -391.038187)
			(xy 369.820337 -391.074938) (xy 369.850887 -391.116986) (xy 369.874483 -391.163296) (xy 369.890544 -391.212726)
			(xy 369.898176 -391.260917) (xy 370.586256 -391.260917) (xy 370.586256 -391.208943) (xy 370.594386 -391.157608)
			(xy 370.610447 -391.108178) (xy 370.634043 -391.061868) (xy 370.664593 -391.01982) (xy 370.701344 -390.983069)
			(xy 370.743392 -390.952519) (xy 370.789702 -390.928923) (xy 370.839132 -390.912862) (xy 370.890467 -390.904732)
			(xy 370.942441 -390.904732) (xy 370.993776 -390.912862) (xy 371.043206 -390.928923) (xy 371.089516 -390.952519)
			(xy 371.131564 -390.983069) (xy 371.168315 -391.01982) (xy 371.198865 -391.061868) (xy 371.222461 -391.108178)
			(xy 371.238522 -391.157608) (xy 371.246652 -391.208943) (xy 371.247162 -391.23493) (xy 371.246652 -391.260917)
			(xy 371.786406 -391.260917) (xy 371.786406 -391.208943) (xy 371.794536 -391.157608) (xy 371.810597 -391.108178)
			(xy 371.834193 -391.061868) (xy 371.864743 -391.01982) (xy 371.901494 -390.983069) (xy 371.943542 -390.952519)
			(xy 371.989852 -390.928923) (xy 372.039282 -390.912862) (xy 372.090617 -390.904732) (xy 372.142591 -390.904732)
			(xy 372.193926 -390.912862) (xy 372.243356 -390.928923) (xy 372.289666 -390.952519) (xy 372.331714 -390.983069)
			(xy 372.368465 -391.01982) (xy 372.399015 -391.061868) (xy 372.422611 -391.108178) (xy 372.438672 -391.157608)
			(xy 372.446802 -391.208943) (xy 372.447312 -391.23493) (xy 372.446802 -391.260917) (xy 372.986302 -391.260917)
			(xy 372.986302 -391.208943) (xy 372.994432 -391.157608) (xy 373.010493 -391.108178) (xy 373.034089 -391.061868)
			(xy 373.064639 -391.01982) (xy 373.10139 -390.983069) (xy 373.143438 -390.952519) (xy 373.189748 -390.928923)
			(xy 373.239178 -390.912862) (xy 373.290513 -390.904732) (xy 373.342487 -390.904732) (xy 373.393822 -390.912862)
			(xy 373.443252 -390.928923) (xy 373.489562 -390.952519) (xy 373.53161 -390.983069) (xy 373.568361 -391.01982)
			(xy 373.598911 -391.061868) (xy 373.622507 -391.108178) (xy 373.638568 -391.157608) (xy 373.646698 -391.208943)
			(xy 373.647208 -391.23493) (xy 373.646698 -391.260917) (xy 374.186198 -391.260917) (xy 374.186198 -391.208943)
			(xy 374.194328 -391.157608) (xy 374.210389 -391.108178) (xy 374.233985 -391.061868) (xy 374.264535 -391.01982)
			(xy 374.301286 -390.983069) (xy 374.343334 -390.952519) (xy 374.389644 -390.928923) (xy 374.439074 -390.912862)
			(xy 374.490409 -390.904732) (xy 374.542383 -390.904732) (xy 374.593718 -390.912862) (xy 374.643148 -390.928923)
			(xy 374.689458 -390.952519) (xy 374.731506 -390.983069) (xy 374.768257 -391.01982) (xy 374.798807 -391.061868)
			(xy 374.822403 -391.108178) (xy 374.838464 -391.157608) (xy 374.846594 -391.208943) (xy 374.847104 -391.23493)
			(xy 374.846594 -391.260917) (xy 375.386348 -391.260917) (xy 375.386348 -391.208943) (xy 375.394478 -391.157608)
			(xy 375.410539 -391.108178) (xy 375.434135 -391.061868) (xy 375.464685 -391.01982) (xy 375.501436 -390.983069)
			(xy 375.543484 -390.952519) (xy 375.589794 -390.928923) (xy 375.639224 -390.912862) (xy 375.690559 -390.904732)
			(xy 375.742533 -390.904732) (xy 375.793868 -390.912862) (xy 375.843298 -390.928923) (xy 375.889608 -390.952519)
			(xy 375.931656 -390.983069) (xy 375.968407 -391.01982) (xy 375.998957 -391.061868) (xy 376.022553 -391.108178)
			(xy 376.038614 -391.157608) (xy 376.046744 -391.208943) (xy 376.047254 -391.23493) (xy 376.046744 -391.260917)
			(xy 376.586244 -391.260917) (xy 376.586244 -391.208943) (xy 376.594374 -391.157608) (xy 376.610435 -391.108178)
			(xy 376.634031 -391.061868) (xy 376.664581 -391.01982) (xy 376.701332 -390.983069) (xy 376.74338 -390.952519)
			(xy 376.78969 -390.928923) (xy 376.83912 -390.912862) (xy 376.890455 -390.904732) (xy 376.942429 -390.904732)
			(xy 376.993764 -390.912862) (xy 377.043194 -390.928923) (xy 377.089504 -390.952519) (xy 377.131552 -390.983069)
			(xy 377.168303 -391.01982) (xy 377.198853 -391.061868) (xy 377.222449 -391.108178) (xy 377.23851 -391.157608)
			(xy 377.24664 -391.208943) (xy 377.24715 -391.23493) (xy 377.24664 -391.260917) (xy 377.786394 -391.260917)
			(xy 377.786394 -391.208943) (xy 377.794524 -391.157608) (xy 377.810585 -391.108178) (xy 377.834181 -391.061868)
			(xy 377.864731 -391.01982) (xy 377.901482 -390.983069) (xy 377.94353 -390.952519) (xy 377.98984 -390.928923)
			(xy 378.03927 -390.912862) (xy 378.090605 -390.904732) (xy 378.142579 -390.904732) (xy 378.193914 -390.912862)
			(xy 378.243344 -390.928923) (xy 378.289654 -390.952519) (xy 378.331702 -390.983069) (xy 378.368453 -391.01982)
			(xy 378.399003 -391.061868) (xy 378.422599 -391.108178) (xy 378.43866 -391.157608) (xy 378.44679 -391.208943)
			(xy 378.4473 -391.23493) (xy 378.44679 -391.260917) (xy 378.98629 -391.260917) (xy 378.98629 -391.208943)
			(xy 378.99442 -391.157608) (xy 379.010481 -391.108178) (xy 379.034077 -391.061868) (xy 379.064627 -391.01982)
			(xy 379.101378 -390.983069) (xy 379.143426 -390.952519) (xy 379.189736 -390.928923) (xy 379.239166 -390.912862)
			(xy 379.290501 -390.904732) (xy 379.342475 -390.904732) (xy 379.39381 -390.912862) (xy 379.44324 -390.928923)
			(xy 379.48955 -390.952519) (xy 379.531598 -390.983069) (xy 379.568349 -391.01982) (xy 379.598899 -391.061868)
			(xy 379.622495 -391.108178) (xy 379.638556 -391.157608) (xy 379.646686 -391.208943) (xy 379.647196 -391.23493)
			(xy 379.646686 -391.260917) (xy 380.186186 -391.260917) (xy 380.186186 -391.208943) (xy 380.194316 -391.157608)
			(xy 380.210377 -391.108178) (xy 380.233973 -391.061868) (xy 380.264523 -391.01982) (xy 380.301274 -390.983069)
			(xy 380.343322 -390.952519) (xy 380.389632 -390.928923) (xy 380.439062 -390.912862) (xy 380.490397 -390.904732)
			(xy 380.542371 -390.904732) (xy 380.593706 -390.912862) (xy 380.643136 -390.928923) (xy 380.689446 -390.952519)
			(xy 380.731494 -390.983069) (xy 380.768245 -391.01982) (xy 380.798795 -391.061868) (xy 380.822391 -391.108178)
			(xy 380.838452 -391.157608) (xy 380.846582 -391.208943) (xy 380.847092 -391.23493) (xy 380.846582 -391.260917)
			(xy 381.386336 -391.260917) (xy 381.386336 -391.208943) (xy 381.394466 -391.157608) (xy 381.410527 -391.108178)
			(xy 381.434123 -391.061868) (xy 381.464673 -391.01982) (xy 381.501424 -390.983069) (xy 381.543472 -390.952519)
			(xy 381.589782 -390.928923) (xy 381.639212 -390.912862) (xy 381.690547 -390.904732) (xy 381.742521 -390.904732)
			(xy 381.793856 -390.912862) (xy 381.843286 -390.928923) (xy 381.889596 -390.952519) (xy 381.931644 -390.983069)
			(xy 381.968395 -391.01982) (xy 381.998945 -391.061868) (xy 382.022541 -391.108178) (xy 382.038602 -391.157608)
			(xy 382.046732 -391.208943) (xy 382.047242 -391.23493) (xy 382.046732 -391.260917) (xy 382.586232 -391.260917)
			(xy 382.586232 -391.208943) (xy 382.594362 -391.157608) (xy 382.610423 -391.108178) (xy 382.634019 -391.061868)
			(xy 382.664569 -391.01982) (xy 382.70132 -390.983069) (xy 382.743368 -390.952519) (xy 382.789678 -390.928923)
			(xy 382.839108 -390.912862) (xy 382.890443 -390.904732) (xy 382.942417 -390.904732) (xy 382.993752 -390.912862)
			(xy 383.043182 -390.928923) (xy 383.089492 -390.952519) (xy 383.13154 -390.983069) (xy 383.168291 -391.01982)
			(xy 383.198841 -391.061868) (xy 383.222437 -391.108178) (xy 383.238498 -391.157608) (xy 383.246628 -391.208943)
			(xy 383.247138 -391.23493) (xy 383.246628 -391.260917) (xy 383.786382 -391.260917) (xy 383.786382 -391.208943)
			(xy 383.794512 -391.157608) (xy 383.810573 -391.108178) (xy 383.834169 -391.061868) (xy 383.864719 -391.01982)
			(xy 383.90147 -390.983069) (xy 383.943518 -390.952519) (xy 383.989828 -390.928923) (xy 384.039258 -390.912862)
			(xy 384.090593 -390.904732) (xy 384.142567 -390.904732) (xy 384.193902 -390.912862) (xy 384.243332 -390.928923)
			(xy 384.289642 -390.952519) (xy 384.33169 -390.983069) (xy 384.368441 -391.01982) (xy 384.398991 -391.061868)
			(xy 384.422587 -391.108178) (xy 384.438648 -391.157608) (xy 384.446778 -391.208943) (xy 384.447288 -391.23493)
			(xy 384.446778 -391.260917) (xy 384.986278 -391.260917) (xy 384.986278 -391.208943) (xy 384.994408 -391.157608)
			(xy 385.010469 -391.108178) (xy 385.034065 -391.061868) (xy 385.064615 -391.01982) (xy 385.101366 -390.983069)
			(xy 385.143414 -390.952519) (xy 385.189724 -390.928923) (xy 385.239154 -390.912862) (xy 385.290489 -390.904732)
			(xy 385.342463 -390.904732) (xy 385.393798 -390.912862) (xy 385.443228 -390.928923) (xy 385.489538 -390.952519)
			(xy 385.531586 -390.983069) (xy 385.568337 -391.01982) (xy 385.598887 -391.061868) (xy 385.622483 -391.108178)
			(xy 385.638544 -391.157608) (xy 385.646674 -391.208943) (xy 385.647184 -391.23493) (xy 385.646674 -391.260917)
			(xy 385.638544 -391.312252) (xy 385.622483 -391.361682) (xy 385.598887 -391.407992) (xy 385.568337 -391.45004)
			(xy 385.531586 -391.486791) (xy 385.489538 -391.517341) (xy 385.443228 -391.540937) (xy 385.393798 -391.556998)
			(xy 385.342463 -391.565128) (xy 385.290489 -391.565128) (xy 385.239154 -391.556998) (xy 385.189724 -391.540937)
			(xy 385.143414 -391.517341) (xy 385.101366 -391.486791) (xy 385.064615 -391.45004) (xy 385.034065 -391.407992)
			(xy 385.010469 -391.361682) (xy 384.994408 -391.312252) (xy 384.986278 -391.260917) (xy 384.446778 -391.260917)
			(xy 384.438648 -391.312252) (xy 384.422587 -391.361682) (xy 384.398991 -391.407992) (xy 384.368441 -391.45004)
			(xy 384.33169 -391.486791) (xy 384.289642 -391.517341) (xy 384.243332 -391.540937) (xy 384.193902 -391.556998)
			(xy 384.142567 -391.565128) (xy 384.090593 -391.565128) (xy 384.039258 -391.556998) (xy 383.989828 -391.540937)
			(xy 383.943518 -391.517341) (xy 383.90147 -391.486791) (xy 383.864719 -391.45004) (xy 383.834169 -391.407992)
			(xy 383.810573 -391.361682) (xy 383.794512 -391.312252) (xy 383.786382 -391.260917) (xy 383.246628 -391.260917)
			(xy 383.238498 -391.312252) (xy 383.222437 -391.361682) (xy 383.198841 -391.407992) (xy 383.168291 -391.45004)
			(xy 383.13154 -391.486791) (xy 383.089492 -391.517341) (xy 383.043182 -391.540937) (xy 382.993752 -391.556998)
			(xy 382.942417 -391.565128) (xy 382.890443 -391.565128) (xy 382.839108 -391.556998) (xy 382.789678 -391.540937)
			(xy 382.743368 -391.517341) (xy 382.70132 -391.486791) (xy 382.664569 -391.45004) (xy 382.634019 -391.407992)
			(xy 382.610423 -391.361682) (xy 382.594362 -391.312252) (xy 382.586232 -391.260917) (xy 382.046732 -391.260917)
			(xy 382.038602 -391.312252) (xy 382.022541 -391.361682) (xy 381.998945 -391.407992) (xy 381.968395 -391.45004)
			(xy 381.931644 -391.486791) (xy 381.889596 -391.517341) (xy 381.843286 -391.540937) (xy 381.793856 -391.556998)
			(xy 381.742521 -391.565128) (xy 381.690547 -391.565128) (xy 381.639212 -391.556998) (xy 381.589782 -391.540937)
			(xy 381.543472 -391.517341) (xy 381.501424 -391.486791) (xy 381.464673 -391.45004) (xy 381.434123 -391.407992)
			(xy 381.410527 -391.361682) (xy 381.394466 -391.312252) (xy 381.386336 -391.260917) (xy 380.846582 -391.260917)
			(xy 380.838452 -391.312252) (xy 380.822391 -391.361682) (xy 380.798795 -391.407992) (xy 380.768245 -391.45004)
			(xy 380.731494 -391.486791) (xy 380.689446 -391.517341) (xy 380.643136 -391.540937) (xy 380.593706 -391.556998)
			(xy 380.542371 -391.565128) (xy 380.490397 -391.565128) (xy 380.439062 -391.556998) (xy 380.389632 -391.540937)
			(xy 380.343322 -391.517341) (xy 380.301274 -391.486791) (xy 380.264523 -391.45004) (xy 380.233973 -391.407992)
			(xy 380.210377 -391.361682) (xy 380.194316 -391.312252) (xy 380.186186 -391.260917) (xy 379.646686 -391.260917)
			(xy 379.638556 -391.312252) (xy 379.622495 -391.361682) (xy 379.598899 -391.407992) (xy 379.568349 -391.45004)
			(xy 379.531598 -391.486791) (xy 379.48955 -391.517341) (xy 379.44324 -391.540937) (xy 379.39381 -391.556998)
			(xy 379.342475 -391.565128) (xy 379.290501 -391.565128) (xy 379.239166 -391.556998) (xy 379.189736 -391.540937)
			(xy 379.143426 -391.517341) (xy 379.101378 -391.486791) (xy 379.064627 -391.45004) (xy 379.034077 -391.407992)
			(xy 379.010481 -391.361682) (xy 378.99442 -391.312252) (xy 378.98629 -391.260917) (xy 378.44679 -391.260917)
			(xy 378.43866 -391.312252) (xy 378.422599 -391.361682) (xy 378.399003 -391.407992) (xy 378.368453 -391.45004)
			(xy 378.331702 -391.486791) (xy 378.289654 -391.517341) (xy 378.243344 -391.540937) (xy 378.193914 -391.556998)
			(xy 378.142579 -391.565128) (xy 378.090605 -391.565128) (xy 378.03927 -391.556998) (xy 377.98984 -391.540937)
			(xy 377.94353 -391.517341) (xy 377.901482 -391.486791) (xy 377.864731 -391.45004) (xy 377.834181 -391.407992)
			(xy 377.810585 -391.361682) (xy 377.794524 -391.312252) (xy 377.786394 -391.260917) (xy 377.24664 -391.260917)
			(xy 377.23851 -391.312252) (xy 377.222449 -391.361682) (xy 377.198853 -391.407992) (xy 377.168303 -391.45004)
			(xy 377.131552 -391.486791) (xy 377.089504 -391.517341) (xy 377.043194 -391.540937) (xy 376.993764 -391.556998)
			(xy 376.942429 -391.565128) (xy 376.890455 -391.565128) (xy 376.83912 -391.556998) (xy 376.78969 -391.540937)
			(xy 376.74338 -391.517341) (xy 376.701332 -391.486791) (xy 376.664581 -391.45004) (xy 376.634031 -391.407992)
			(xy 376.610435 -391.361682) (xy 376.594374 -391.312252) (xy 376.586244 -391.260917) (xy 376.046744 -391.260917)
			(xy 376.038614 -391.312252) (xy 376.022553 -391.361682) (xy 375.998957 -391.407992) (xy 375.968407 -391.45004)
			(xy 375.931656 -391.486791) (xy 375.889608 -391.517341) (xy 375.843298 -391.540937) (xy 375.793868 -391.556998)
			(xy 375.742533 -391.565128) (xy 375.690559 -391.565128) (xy 375.639224 -391.556998) (xy 375.589794 -391.540937)
			(xy 375.543484 -391.517341) (xy 375.501436 -391.486791) (xy 375.464685 -391.45004) (xy 375.434135 -391.407992)
			(xy 375.410539 -391.361682) (xy 375.394478 -391.312252) (xy 375.386348 -391.260917) (xy 374.846594 -391.260917)
			(xy 374.838464 -391.312252) (xy 374.822403 -391.361682) (xy 374.798807 -391.407992) (xy 374.768257 -391.45004)
			(xy 374.731506 -391.486791) (xy 374.689458 -391.517341) (xy 374.643148 -391.540937) (xy 374.593718 -391.556998)
			(xy 374.542383 -391.565128) (xy 374.490409 -391.565128) (xy 374.439074 -391.556998) (xy 374.389644 -391.540937)
			(xy 374.343334 -391.517341) (xy 374.301286 -391.486791) (xy 374.264535 -391.45004) (xy 374.233985 -391.407992)
			(xy 374.210389 -391.361682) (xy 374.194328 -391.312252) (xy 374.186198 -391.260917) (xy 373.646698 -391.260917)
			(xy 373.638568 -391.312252) (xy 373.622507 -391.361682) (xy 373.598911 -391.407992) (xy 373.568361 -391.45004)
			(xy 373.53161 -391.486791) (xy 373.489562 -391.517341) (xy 373.443252 -391.540937) (xy 373.393822 -391.556998)
			(xy 373.342487 -391.565128) (xy 373.290513 -391.565128) (xy 373.239178 -391.556998) (xy 373.189748 -391.540937)
			(xy 373.143438 -391.517341) (xy 373.10139 -391.486791) (xy 373.064639 -391.45004) (xy 373.034089 -391.407992)
			(xy 373.010493 -391.361682) (xy 372.994432 -391.312252) (xy 372.986302 -391.260917) (xy 372.446802 -391.260917)
			(xy 372.438672 -391.312252) (xy 372.422611 -391.361682) (xy 372.399015 -391.407992) (xy 372.368465 -391.45004)
			(xy 372.331714 -391.486791) (xy 372.289666 -391.517341) (xy 372.243356 -391.540937) (xy 372.193926 -391.556998)
			(xy 372.142591 -391.565128) (xy 372.090617 -391.565128) (xy 372.039282 -391.556998) (xy 371.989852 -391.540937)
			(xy 371.943542 -391.517341) (xy 371.901494 -391.486791) (xy 371.864743 -391.45004) (xy 371.834193 -391.407992)
			(xy 371.810597 -391.361682) (xy 371.794536 -391.312252) (xy 371.786406 -391.260917) (xy 371.246652 -391.260917)
			(xy 371.238522 -391.312252) (xy 371.222461 -391.361682) (xy 371.198865 -391.407992) (xy 371.168315 -391.45004)
			(xy 371.131564 -391.486791) (xy 371.089516 -391.517341) (xy 371.043206 -391.540937) (xy 370.993776 -391.556998)
			(xy 370.942441 -391.565128) (xy 370.890467 -391.565128) (xy 370.839132 -391.556998) (xy 370.789702 -391.540937)
			(xy 370.743392 -391.517341) (xy 370.701344 -391.486791) (xy 370.664593 -391.45004) (xy 370.634043 -391.407992)
			(xy 370.610447 -391.361682) (xy 370.594386 -391.312252) (xy 370.586256 -391.260917) (xy 369.898176 -391.260917)
			(xy 369.898674 -391.264061) (xy 369.899184 -391.290048) (xy 369.898674 -391.316035) (xy 369.890544 -391.36737)
			(xy 369.874483 -391.4168) (xy 369.850887 -391.46311) (xy 369.820337 -391.505158) (xy 369.783586 -391.541909)
			(xy 369.741538 -391.572459) (xy 369.695228 -391.596055) (xy 369.645798 -391.612116) (xy 369.594463 -391.620246)
			(xy 369.542489 -391.620246) (xy 369.491154 -391.612116) (xy 369.441724 -391.596055) (xy 369.395414 -391.572459)
			(xy 369.353366 -391.541909) (xy 369.316615 -391.505158) (xy 369.286065 -391.46311) (xy 369.262469 -391.4168)
			(xy 369.246408 -391.36737) (xy 369.238278 -391.316035) (xy 368.041174 -391.316035) (xy 368.041174 -392.765359)
			(xy 368.17097 -392.765359) (xy 368.17097 -392.713385) (xy 368.1791 -392.66205) (xy 368.195161 -392.61262)
			(xy 368.218757 -392.56631) (xy 368.249307 -392.524262) (xy 368.286058 -392.487511) (xy 368.328106 -392.456961)
			(xy 368.374416 -392.433365) (xy 368.423846 -392.417304) (xy 368.475181 -392.409174) (xy 368.527155 -392.409174)
			(xy 368.57849 -392.417304) (xy 368.62792 -392.433365) (xy 368.67423 -392.456961) (xy 368.716278 -392.487511)
			(xy 368.753029 -392.524262) (xy 368.783579 -392.56631) (xy 368.807175 -392.61262) (xy 368.823236 -392.66205)
			(xy 368.831366 -392.713385) (xy 368.831876 -392.739372) (xy 368.831366 -392.765359) (xy 368.823236 -392.816694)
			(xy 368.807175 -392.866124) (xy 368.783579 -392.912434) (xy 368.753029 -392.954482) (xy 368.716278 -392.991233)
			(xy 368.67423 -393.021783) (xy 368.666525 -393.025709) (xy 370.23218 -393.025709) (xy 370.23218 -392.973735)
			(xy 370.24031 -392.9224) (xy 370.256371 -392.87297) (xy 370.279967 -392.82666) (xy 370.310517 -392.784612)
			(xy 370.347268 -392.747861) (xy 370.389316 -392.717311) (xy 370.435626 -392.693715) (xy 370.485056 -392.677654)
			(xy 370.536391 -392.669524) (xy 370.588365 -392.669524) (xy 370.6397 -392.677654) (xy 370.68913 -392.693715)
			(xy 370.73544 -392.717311) (xy 370.777488 -392.747861) (xy 370.814239 -392.784612) (xy 370.844789 -392.82666)
			(xy 370.868385 -392.87297) (xy 370.884446 -392.9224) (xy 370.892576 -392.973735) (xy 370.893086 -392.999722)
			(xy 370.892576 -393.025709) (xy 370.884446 -393.077044) (xy 370.868385 -393.126474) (xy 370.844789 -393.172784)
			(xy 370.814239 -393.214832) (xy 370.777488 -393.251583) (xy 370.73544 -393.282133) (xy 370.68913 -393.305729)
			(xy 370.6397 -393.32179) (xy 370.588365 -393.32992) (xy 370.536391 -393.32992) (xy 370.485056 -393.32179)
			(xy 370.435626 -393.305729) (xy 370.389316 -393.282133) (xy 370.347268 -393.251583) (xy 370.310517 -393.214832)
			(xy 370.279967 -393.172784) (xy 370.256371 -393.126474) (xy 370.24031 -393.077044) (xy 370.23218 -393.025709)
			(xy 368.666525 -393.025709) (xy 368.62792 -393.045379) (xy 368.57849 -393.06144) (xy 368.527155 -393.06957)
			(xy 368.475181 -393.06957) (xy 368.423846 -393.06144) (xy 368.374416 -393.045379) (xy 368.328106 -393.021783)
			(xy 368.286058 -392.991233) (xy 368.249307 -392.954482) (xy 368.218757 -392.912434) (xy 368.195161 -392.866124)
			(xy 368.1791 -392.816694) (xy 368.17097 -392.765359) (xy 368.041174 -392.765359) (xy 368.041174 -393.582906)
			(xy 368.041614 -393.592696) (xy 368.04892 -393.61086) (xy 368.055398 -393.618212) (xy 368.076734 -393.640056)
			(xy 368.083309 -393.646338) (xy 368.099717 -393.654146) (xy 368.108738 -393.655296) (xy 368.134422 -393.658051)
			(xy 368.184549 -393.670517) (xy 368.232127 -393.690626) (xy 368.276 -393.717888) (xy 368.315101 -393.751641)
			(xy 368.348477 -393.791063) (xy 368.375318 -393.835195) (xy 368.394971 -393.882963) (xy 368.406957 -393.933207)
			(xy 368.410984 -393.984703) (xy 368.406956 -394.036199) (xy 368.394969 -394.086442) (xy 368.375316 -394.134211)
			(xy 368.348474 -394.178342) (xy 368.315096 -394.217763) (xy 368.275995 -394.251515) (xy 368.232122 -394.278777)
			(xy 368.184543 -394.298884) (xy 368.134416 -394.31135) (xy 368.108738 -394.314172) (xy 368.099731 -394.315366)
			(xy 368.083337 -394.323172) (xy 368.076734 -394.329412) (xy 368.055398 -394.351256) (xy 368.048924 -394.358611)
			(xy 368.041621 -394.376773) (xy 368.041174 -394.386562) (xy 368.041174 -394.440918) (xy 368.041719 -394.45152)
			(xy 368.050246 -394.470936) (xy 368.057684 -394.47851) (xy 368.12093 -394.536168) (xy 368.14125 -394.543026)
			(xy 368.151918 -394.54201) (xy 368.181636 -394.54074) (xy 368.207622 -394.541226) (xy 368.258953 -394.549362)
			(xy 368.30838 -394.565428) (xy 368.354685 -394.589028) (xy 368.396727 -394.619582) (xy 368.433473 -394.656337)
			(xy 368.464016 -394.698387) (xy 368.487604 -394.744698) (xy 368.503658 -394.794128) (xy 368.511781 -394.845462)
			(xy 368.512344 -394.871448) (xy 368.511785 -394.898777) (xy 368.502804 -394.952693) (xy 368.485079 -395.004398)
			(xy 368.459091 -395.052483) (xy 368.442748 -395.074394) (xy 368.43716 -395.08176) (xy 368.431572 -395.098524)
			(xy 368.435128 -395.182598) (xy 368.441986 -395.198854) (xy 368.448082 -395.205712) (xy 368.464456 -395.224121)
			(xy 368.492128 -395.264883) (xy 368.513444 -395.3093) (xy 368.52793 -395.356389) (xy 368.535266 -395.405107)
			(xy 368.535712 -395.42974) (xy 368.535199 -395.455725) (xy 368.527064 -395.507055) (xy 368.510999 -395.556481)
			(xy 368.487402 -395.602785) (xy 368.456851 -395.644828) (xy 368.4201 -395.681575) (xy 368.378054 -395.71212)
			(xy 368.331747 -395.735713) (xy 368.28232 -395.751772) (xy 368.230989 -395.759902) (xy 368.205004 -395.760448)
			(xy 368.193085 -395.760315) (xy 368.169313 -395.758533) (xy 368.157506 -395.756892) (xy 368.14633 -395.755368)
			(xy 368.125502 -395.761464) (xy 368.0587 -395.819122) (xy 368.050785 -395.826675) (xy 368.04169 -395.846549)
			(xy 368.041174 -395.857476) (xy 368.041174 -396.250414) (xy 368.041703 -396.261337) (xy 368.050803 -396.281199)
			(xy 368.0587 -396.288768) (xy 368.125502 -396.346426) (xy 368.14633 -396.352522) (xy 368.157506 -396.350998)
			(xy 368.169314 -396.349368) (xy 368.193085 -396.34759) (xy 368.205004 -396.347442) (xy 368.230987 -396.347952)
			(xy 368.282313 -396.356082) (xy 368.331736 -396.372141) (xy 368.378038 -396.395733) (xy 368.420079 -396.426279)
			(xy 368.456824 -396.463024) (xy 368.487369 -396.505066) (xy 368.510961 -396.551368) (xy 368.527019 -396.600791)
			(xy 368.535148 -396.652117) (xy 368.535148 -396.704083) (xy 368.527019 -396.755409) (xy 368.510961 -396.804832)
			(xy 368.487369 -396.851134) (xy 368.456824 -396.893176) (xy 368.420079 -396.929921) (xy 368.378038 -396.960467)
			(xy 368.331736 -396.984059) (xy 368.282313 -397.000118) (xy 368.230987 -397.008248) (xy 368.205004 -397.008858)
			(xy 368.193085 -397.008725) (xy 368.169313 -397.006943) (xy 368.157506 -397.005302) (xy 368.14633 -397.003778)
			(xy 368.125502 -397.009874) (xy 368.0587 -397.067532) (xy 368.050787 -397.075085) (xy 368.041695 -397.09496)
			(xy 368.041174 -397.105886) (xy 368.041174 -398.020032) (xy 368.041655 -398.03078) (xy 368.050472 -398.050384)
			(xy 368.058192 -398.057878) (xy 368.123216 -398.11579) (xy 368.143536 -398.12214) (xy 368.154712 -398.12087)
			(xy 368.164328 -398.1198) (xy 368.183645 -398.118653) (xy 368.19332 -398.118584) (xy 368.219306 -398.119095)
			(xy 368.270639 -398.127228) (xy 368.320067 -398.143291) (xy 368.366375 -398.166887) (xy 368.408421 -398.197437)
			(xy 368.44517 -398.234188) (xy 368.475719 -398.276236) (xy 368.499314 -398.322544) (xy 368.515375 -398.371973)
			(xy 368.523506 -398.423306) (xy 368.524028 -398.449292) (xy 368.523635 -398.472526) (xy 368.517134 -398.518537)
			(xy 368.504258 -398.563186) (xy 368.48526 -398.605594) (xy 368.460515 -398.644925) (xy 368.445796 -398.662906)
			(xy 368.4397 -398.670018) (xy 368.433604 -398.686528) (xy 368.433604 -398.770856) (xy 368.4397 -398.787366)
			(xy 368.445796 -398.794478) (xy 368.4605 -398.81247) (xy 368.485248 -398.851797) (xy 368.504245 -398.894202)
			(xy 368.517117 -398.938849) (xy 368.523611 -398.984859) (xy 368.524028 -399.008092) (xy 368.523519 -399.03408)
			(xy 368.51539 -399.085417) (xy 368.49933 -399.13485) (xy 368.475734 -399.181162) (xy 368.445185 -399.223213)
			(xy 368.408434 -399.259967) (xy 368.366386 -399.29052) (xy 368.320076 -399.314119) (xy 368.270644 -399.330183)
			(xy 368.219308 -399.338317) (xy 368.19332 -399.3388) (xy 368.183645 -399.338723) (xy 368.164328 -399.337581)
			(xy 368.154712 -399.336514) (xy 368.143536 -399.335244) (xy 368.123216 -399.341594) (xy 368.058192 -399.399506)
			(xy 368.050572 -399.407071) (xy 368.041774 -399.426631) (xy 368.041174 -399.437352) (xy 368.041174 -399.823686)
			(xy 368.041681 -399.833736) (xy 368.049404 -399.852295) (xy 368.05616 -399.859754) (xy 368.356642 -400.160236)
			(xy 368.363489 -400.167634) (xy 368.370265 -400.183937) (xy 369.264694 -400.183937) (xy 369.264694 -400.131963)
			(xy 369.272824 -400.080628) (xy 369.288885 -400.031198) (xy 369.312481 -399.984888) (xy 369.343031 -399.94284)
			(xy 369.379782 -399.906089) (xy 369.42183 -399.875539) (xy 369.46814 -399.851943) (xy 369.51757 -399.835882)
			(xy 369.568905 -399.827752) (xy 369.620879 -399.827752) (xy 369.672214 -399.835882) (xy 369.721644 -399.851943)
			(xy 369.767954 -399.875539) (xy 369.810002 -399.906089) (xy 369.846753 -399.94284) (xy 369.877303 -399.984888)
			(xy 369.900899 -400.031198) (xy 369.91696 -400.080628) (xy 369.92509 -400.131963) (xy 369.9256 -400.15795)
			(xy 369.92509 -400.183937) (xy 369.91696 -400.235272) (xy 369.900899 -400.284702) (xy 369.877303 -400.331012)
			(xy 369.846753 -400.37306) (xy 369.810002 -400.409811) (xy 369.767954 -400.440361) (xy 369.721644 -400.463957)
			(xy 369.672214 -400.480018) (xy 369.620879 -400.488148) (xy 369.568905 -400.488148) (xy 369.51757 -400.480018)
			(xy 369.46814 -400.463957) (xy 369.42183 -400.440361) (xy 369.379782 -400.409811) (xy 369.343031 -400.37306)
			(xy 369.312481 -400.331012) (xy 369.288885 -400.284702) (xy 369.272824 -400.235272) (xy 369.264694 -400.183937)
			(xy 368.370265 -400.183937) (xy 368.371219 -400.186232) (xy 368.371628 -400.196304) (xy 368.371628 -400.617436)
			(xy 368.372058 -400.627503) (xy 368.379785 -400.646095) (xy 368.386614 -400.653504) (xy 368.85753 -401.12442)
			(xy 368.864942 -401.131097) (xy 368.883378 -401.138666) (xy 368.893344 -401.139152)
		)
		(stroke
			(width 0)
			(type solid)
		)
		(fill yes)
		(layer "In2.Cu")
		(net "NCF_CPU0_P3_GND")
	)
	(gr_poly
		(pts
			(xy 401.73275 -402.80336) (xy 401.742361 -402.80295) (xy 401.760245 -402.795905) (xy 401.767548 -402.789644)
			(xy 401.82546 -402.735542) (xy 401.833588 -402.718524) (xy 401.834096 -402.708618) (xy 401.836384 -402.681364)
			(xy 401.847778 -402.627873) (xy 401.866692 -402.576556) (xy 401.892739 -402.528465) (xy 401.925385 -402.484585)
			(xy 401.96396 -402.445815) (xy 402.007676 -402.41295) (xy 402.055635 -402.386663) (xy 402.106857 -402.367491)
			(xy 402.160291 -402.355829) (xy 402.214842 -402.351915) (xy 402.269393 -402.355829) (xy 402.322827 -402.367491)
			(xy 402.374049 -402.386663) (xy 402.422008 -402.41295) (xy 402.465724 -402.445815) (xy 402.504299 -402.484585)
			(xy 402.536945 -402.528465) (xy 402.562992 -402.576556) (xy 402.581906 -402.627873) (xy 402.5933 -402.681364)
			(xy 402.595588 -402.708618) (xy 402.596096 -402.718524) (xy 402.604224 -402.735542) (xy 402.662136 -402.789644)
			(xy 402.669427 -402.795924) (xy 402.687318 -402.802969) (xy 402.696934 -402.80336) (xy 422.269158 -402.80336)
			(xy 422.279223 -402.802925) (xy 422.297808 -402.795191) (xy 422.305226 -402.788374) (xy 424.118024 -400.975576)
			(xy 424.124875 -400.96818) (xy 424.132613 -400.949581) (xy 424.13301 -400.939508) (xy 424.13301 -400.74215)
			(xy 424.132692 -400.73434) (xy 424.127918 -400.719463) (xy 424.123612 -400.71294) (xy 424.108422 -400.69055)
			(xy 424.083822 -400.642361) (xy 424.07459 -400.616928) (xy 424.071542 -400.607784) (xy 424.060112 -400.593814)
			(xy 423.985436 -400.551142) (xy 423.967656 -400.548348) (xy 423.958258 -400.55038) (xy 423.93935 -400.553977)
			(xy 423.90105 -400.557797) (xy 423.881804 -400.558) (xy 423.854551 -400.557537) (xy 423.8006 -400.54978)
			(xy 423.748302 -400.534425) (xy 423.698722 -400.511782) (xy 423.652869 -400.482314) (xy 423.611677 -400.44662)
			(xy 423.575983 -400.405428) (xy 423.546516 -400.359574) (xy 423.523874 -400.309994) (xy 423.508519 -400.257696)
			(xy 423.500763 -400.203745) (xy 423.500296 -400.176492) (xy 423.500768 -400.149122) (xy 423.508593 -400.094944)
			(xy 423.524081 -400.042441) (xy 423.546914 -399.992691) (xy 423.576623 -399.946714) (xy 423.594276 -399.925794)
			(xy 423.600372 -399.918682) (xy 423.606722 -399.901664) (xy 423.606722 -399.81632) (xy 423.600372 -399.799302)
			(xy 423.594276 -399.79219) (xy 423.576636 -399.771258) (xy 423.546913 -399.725291) (xy 423.524072 -399.675544)
			(xy 423.508584 -399.623041) (xy 423.500768 -399.568862) (xy 423.500296 -399.541492) (xy 423.500782 -399.514241)
			(xy 423.50854 -399.460295) (xy 423.523896 -399.408001) (xy 423.546537 -399.358425) (xy 423.576004 -399.312576)
			(xy 423.611695 -399.271387) (xy 423.652886 -399.235697) (xy 423.698736 -399.206232) (xy 423.748312 -399.183591)
			(xy 423.800606 -399.168237) (xy 423.854553 -399.160481) (xy 423.881804 -399.159984) (xy 423.900922 -399.16022)
			(xy 423.938966 -399.164039) (xy 423.95775 -399.167604) (xy 423.966894 -399.169382) (xy 423.985182 -399.166588)
			(xy 424.05935 -399.123662) (xy 424.071288 -399.109438) (xy 424.074082 -399.100548) (xy 424.083326 -399.074691)
			(xy 424.108191 -399.025732) (xy 424.123612 -399.003012) (xy 424.127917 -398.996486) (xy 424.132712 -398.981614)
			(xy 424.13301 -398.973802) (xy 424.13301 -398.45615) (xy 424.116754 -398.431004) (xy 424.102784 -398.424908)
			(xy 424.079718 -398.414101) (xy 424.036939 -398.386454) (xy 423.99891 -398.352568) (xy 423.966533 -398.313248)
			(xy 423.953178 -398.291558) (xy 423.946066 -398.279366) (xy 423.921428 -398.266158) (xy 423.803826 -398.271238)
			(xy 423.780458 -398.286478) (xy 423.774362 -398.299178) (xy 423.764394 -398.318975) (xy 423.739931 -398.355935)
			(xy 423.725594 -398.372838) (xy 423.719914 -398.37996) (xy 423.713538 -398.397011) (xy 423.713148 -398.406112)
			(xy 423.713148 -398.437608) (xy 423.713528 -398.44671) (xy 423.719914 -398.463758) (xy 423.725594 -398.470882)
			(xy 423.74094 -398.489043) (xy 423.766802 -398.528939) (xy 423.786676 -398.572133) (xy 423.800149 -398.617729)
			(xy 423.806945 -398.664787) (xy 423.807382 -398.68856) (xy 423.806872 -398.714547) (xy 423.798742 -398.765882)
			(xy 423.782681 -398.815312) (xy 423.759085 -398.861622) (xy 423.728535 -398.90367) (xy 423.691784 -398.940421)
			(xy 423.649736 -398.970971) (xy 423.603426 -398.994567) (xy 423.553996 -399.010628) (xy 423.502661 -399.018758)
			(xy 423.450687 -399.018758) (xy 423.399352 -399.010628) (xy 423.349922 -398.994567) (xy 423.303612 -398.970971)
			(xy 423.261564 -398.940421) (xy 423.224813 -398.90367) (xy 423.194263 -398.861622) (xy 423.170667 -398.815312)
			(xy 423.154606 -398.765882) (xy 423.146476 -398.714547) (xy 423.145966 -398.68856) (xy 423.146381 -398.664787)
			(xy 423.153197 -398.617733) (xy 423.166683 -398.572141) (xy 423.18656 -398.52895) (xy 423.212419 -398.489052)
			(xy 423.227754 -398.470882) (xy 423.233432 -398.463759) (xy 423.239808 -398.446709) (xy 423.2402 -398.437608)
			(xy 423.2402 -398.406112) (xy 423.239822 -398.397009) (xy 423.233436 -398.379961) (xy 423.227754 -398.372838)
			(xy 423.212404 -398.354679) (xy 423.186536 -398.314783) (xy 423.166658 -398.271591) (xy 423.153179 -398.225993)
			(xy 423.14638 -398.178934) (xy 423.145966 -398.15516) (xy 423.146399 -398.130749) (xy 423.153572 -398.082458)
			(xy 423.16777 -398.035747) (xy 423.188685 -397.991632) (xy 423.215861 -397.951074) (xy 423.248708 -397.914954)
			(xy 423.28651 -397.884059) (xy 423.307256 -397.871188) (xy 423.318686 -397.86433) (xy 423.331894 -397.841216)
			(xy 423.331894 -397.726916) (xy 423.31894 -397.703802) (xy 423.307256 -397.69669) (xy 423.286548 -397.683814)
			(xy 423.248814 -397.652928) (xy 423.216028 -397.616833) (xy 423.188903 -397.576312) (xy 423.168027 -397.532244)
			(xy 423.153855 -397.485587) (xy 423.146693 -397.437353) (xy 423.14622 -397.412972) (xy 423.146777 -397.385352)
			(xy 423.155955 -397.330879) (xy 423.174053 -397.278687) (xy 423.200566 -397.230225) (xy 423.23476 -397.186839)
			(xy 423.275683 -397.149734) (xy 423.29862 -397.134334) (xy 423.31005 -397.127222) (xy 423.322496 -397.1036)
			(xy 423.31894 -396.9893) (xy 423.305224 -396.966694) (xy 423.293286 -396.96009) (xy 423.271592 -396.947458)
			(xy 423.231948 -396.916663) (xy 423.197412 -396.880232) (xy 423.168777 -396.839) (xy 423.146702 -396.793915)
			(xy 423.131692 -396.746012) (xy 423.124093 -396.696392) (xy 423.123614 -396.671292) (xy 423.124098 -396.645304)
			(xy 423.13223 -396.593967) (xy 423.148293 -396.544535) (xy 423.171892 -396.498225) (xy 423.202445 -396.456176)
			(xy 423.239199 -396.419425) (xy 423.281251 -396.388876) (xy 423.327563 -396.365282) (xy 423.376997 -396.349223)
			(xy 423.428334 -396.341095) (xy 423.454322 -396.340584) (xy 423.480591 -396.341091) (xy 423.532467 -396.349401)
			(xy 423.582378 -396.365808) (xy 423.629066 -396.3899) (xy 423.671358 -396.42107) (xy 423.70819 -396.458535)
			(xy 423.738636 -396.501352) (xy 423.761929 -396.548444) (xy 423.777484 -396.598627) (xy 423.781728 -396.624556)
			(xy 423.782998 -396.633446) (xy 423.79138 -396.64894) (xy 423.85234 -396.704566) (xy 423.86885 -396.711424)
			(xy 423.87774 -396.711678) (xy 423.907103 -396.713722) (xy 423.964464 -396.726891) (xy 423.991786 -396.73784)
			(xy 424.00347 -396.742666) (xy 424.02887 -396.74038) (xy 424.11015 -396.686532) (xy 424.120338 -396.679015)
			(xy 424.132333 -396.656756) (xy 424.13301 -396.644114) (xy 424.13301 -395.776196) (xy 424.132789 -395.768718)
			(xy 424.128535 -395.754382) (xy 424.124628 -395.748002) (xy 424.109617 -395.724478) (xy 424.085894 -395.67397)
			(xy 424.06979 -395.620542) (xy 424.061648 -395.565337) (xy 424.061128 -395.537436) (xy 424.061656 -395.509537)
			(xy 424.069815 -395.454337) (xy 424.085921 -395.400912) (xy 424.10963 -395.350401) (xy 424.124628 -395.32687)
			(xy 424.128517 -395.320482) (xy 424.132773 -395.306151) (xy 424.13301 -395.298676) (xy 424.13301 -395.141196)
			(xy 424.132789 -395.133718) (xy 424.128535 -395.119382) (xy 424.124628 -395.113002) (xy 424.112983 -395.094968)
			(xy 424.093378 -395.056776) (xy 424.085512 -395.036802) (xy 424.08221 -395.028166) (xy 424.070272 -395.01445)
			(xy 423.994834 -394.974064) (xy 423.9768 -394.971524) (xy 423.967656 -394.97381) (xy 423.946549 -394.978349)
			(xy 423.903646 -394.983188) (xy 423.882058 -394.983462) (xy 423.854808 -394.982996) (xy 423.800864 -394.975234)
			(xy 423.748574 -394.959874) (xy 423.699002 -394.937228) (xy 423.653158 -394.907758) (xy 423.611974 -394.872064)
			(xy 423.576289 -394.830872) (xy 423.54683 -394.78502) (xy 423.524196 -394.735443) (xy 423.508848 -394.68315)
			(xy 423.501098 -394.629204) (xy 423.50055 -394.601954) (xy 423.501043 -394.574243) (xy 423.509062 -394.519405)
			(xy 423.524938 -394.466307) (xy 423.548337 -394.416068) (xy 423.578766 -394.369747) (xy 423.596816 -394.348716)
			(xy 423.60342 -394.341096) (xy 423.610024 -394.322554) (xy 423.605706 -394.231622) (xy 423.597578 -394.213842)
			(xy 423.590212 -394.206984) (xy 423.569726 -394.187137) (xy 423.534289 -394.142444) (xy 423.505905 -394.092971)
			(xy 423.485206 -394.039823) (xy 423.472654 -393.984184) (xy 423.47007 -393.955778) (xy 423.469308 -393.94638)
			(xy 423.461434 -393.929616) (xy 423.399712 -393.869418) (xy 423.382694 -393.862052) (xy 423.373296 -393.861798)
			(xy 423.348075 -393.860219) (xy 423.298513 -393.85036) (xy 423.251029 -393.833075) (xy 423.206729 -393.808765)
			(xy 423.166644 -393.777996) (xy 423.131708 -393.741486) (xy 423.102735 -393.700085) (xy 423.080399 -393.654757)
			(xy 423.065221 -393.606558) (xy 423.057555 -393.55661) (xy 423.057066 -393.531344) (xy 423.057492 -393.506445)
			(xy 423.064915 -393.457206) (xy 423.079645 -393.409638) (xy 423.101348 -393.364819) (xy 423.129531 -393.323766)
			(xy 423.14622 -393.305284) (xy 423.152824 -393.298426) (xy 423.159682 -393.281408) (xy 423.161968 -393.195048)
			(xy 423.155872 -393.177522) (xy 423.149776 -393.17041) (xy 423.135032 -393.152406) (xy 423.110211 -393.113043)
			(xy 423.091153 -393.07059) (xy 423.078232 -393.025884) (xy 423.071704 -392.979809) (xy 423.07129 -392.956542)
			(xy 423.0718 -392.930555) (xy 423.07993 -392.87922) (xy 423.095991 -392.82979) (xy 423.119587 -392.78348)
			(xy 423.150137 -392.741432) (xy 423.186888 -392.704681) (xy 423.228936 -392.674131) (xy 423.275246 -392.650535)
			(xy 423.324676 -392.634474) (xy 423.376011 -392.626344) (xy 423.427985 -392.626344) (xy 423.47932 -392.634474)
			(xy 423.52875 -392.650535) (xy 423.57506 -392.674131) (xy 423.617108 -392.704681) (xy 423.653859 -392.741432)
			(xy 423.684409 -392.78348) (xy 423.708005 -392.82979) (xy 423.724066 -392.87922) (xy 423.732196 -392.930555)
			(xy 423.732706 -392.956542) (xy 423.732281 -392.981441) (xy 423.724861 -393.030684) (xy 423.710135 -393.078255)
			(xy 423.688438 -393.123077) (xy 423.660259 -393.164136) (xy 423.643552 -393.182602) (xy 423.636948 -393.18946)
			(xy 423.63009 -393.206478) (xy 423.627804 -393.292838) (xy 423.6339 -393.310364) (xy 423.639996 -393.317476)
			(xy 423.657623 -393.339136) (xy 423.686091 -393.387172) (xy 423.706074 -393.439313) (xy 423.712132 -393.466574)
			(xy 423.71391 -393.475718) (xy 423.723816 -393.491466) (xy 423.79265 -393.543536) (xy 423.81043 -393.548616)
			(xy 423.819828 -393.547854) (xy 423.850562 -393.546584) (xy 423.878334 -393.547042) (xy 423.933293 -393.55508)
			(xy 423.960036 -393.562586) (xy 423.969434 -393.56538) (xy 423.988738 -393.563856) (xy 424.068494 -393.523978)
			(xy 424.081194 -393.5095) (xy 424.08475 -393.50061) (xy 424.092696 -393.479963) (xy 424.112687 -393.440495)
			(xy 424.124628 -393.42187) (xy 424.128517 -393.415482) (xy 424.132773 -393.401151) (xy 424.13301 -393.393676)
			(xy 424.13301 -393.159996) (xy 424.132789 -393.152518) (xy 424.128535 -393.138182) (xy 424.124628 -393.131802)
			(xy 424.109617 -393.108278) (xy 424.085894 -393.05777) (xy 424.06979 -393.004342) (xy 424.061648 -392.949137)
			(xy 424.061128 -392.921236) (xy 424.061656 -392.893337) (xy 424.069815 -392.838137) (xy 424.085921 -392.784712)
			(xy 424.10963 -392.734201) (xy 424.124628 -392.71067) (xy 424.128517 -392.704282) (xy 424.132773 -392.689951)
			(xy 424.13301 -392.682476) (xy 424.13301 -392.075416) (xy 424.132494 -392.065516) (xy 424.124918 -392.047216)
			(xy 424.118278 -392.039856) (xy 424.096942 -392.018012) (xy 424.090202 -392.011781) (xy 424.073545 -392.004099)
			(xy 424.06443 -392.003026) (xy 424.03671 -392.000388) (xy 423.982779 -391.98655) (xy 423.932155 -391.963372)
			(xy 423.88644 -391.931589) (xy 423.86631 -391.912348) (xy 422.834308 -390.880346) (xy 422.819051 -390.864557)
			(xy 422.792658 -390.829469) (xy 422.771425 -390.791039) (xy 422.755769 -390.75002) (xy 422.750488 -390.728708)
			(xy 422.746678 -390.711436) (xy 422.718992 -390.689338) (xy 400.706336 -390.689338) (xy 400.696272 -390.689774)
			(xy 400.677688 -390.697509) (xy 400.670268 -390.704324) (xy 400.422618 -390.951974) (xy 400.415781 -390.959376)
			(xy 400.408071 -390.977974) (xy 400.407632 -390.988042) (xy 400.407632 -391.316543) (xy 401.766026 -391.316543)
			(xy 401.766026 -391.264569) (xy 401.774156 -391.213234) (xy 401.790217 -391.163804) (xy 401.813813 -391.117494)
			(xy 401.844363 -391.075446) (xy 401.881114 -391.038695) (xy 401.923162 -391.008145) (xy 401.969472 -390.984549)
			(xy 402.018902 -390.968488) (xy 402.070237 -390.960358) (xy 402.122211 -390.960358) (xy 402.173546 -390.968488)
			(xy 402.222976 -390.984549) (xy 402.269286 -391.008145) (xy 402.311334 -391.038695) (xy 402.348085 -391.075446)
			(xy 402.378635 -391.117494) (xy 402.402231 -391.163804) (xy 402.418292 -391.213234) (xy 402.425844 -391.260917)
			(xy 403.114004 -391.260917) (xy 403.114004 -391.208943) (xy 403.122134 -391.157608) (xy 403.138195 -391.108178)
			(xy 403.161791 -391.061868) (xy 403.192341 -391.01982) (xy 403.229092 -390.983069) (xy 403.27114 -390.952519)
			(xy 403.31745 -390.928923) (xy 403.36688 -390.912862) (xy 403.418215 -390.904732) (xy 403.470189 -390.904732)
			(xy 403.521524 -390.912862) (xy 403.570954 -390.928923) (xy 403.617264 -390.952519) (xy 403.659312 -390.983069)
			(xy 403.696063 -391.01982) (xy 403.726613 -391.061868) (xy 403.750209 -391.108178) (xy 403.76627 -391.157608)
			(xy 403.7744 -391.208943) (xy 403.77491 -391.23493) (xy 403.7744 -391.260917) (xy 404.314154 -391.260917)
			(xy 404.314154 -391.208943) (xy 404.322284 -391.157608) (xy 404.338345 -391.108178) (xy 404.361941 -391.061868)
			(xy 404.392491 -391.01982) (xy 404.429242 -390.983069) (xy 404.47129 -390.952519) (xy 404.5176 -390.928923)
			(xy 404.56703 -390.912862) (xy 404.618365 -390.904732) (xy 404.670339 -390.904732) (xy 404.721674 -390.912862)
			(xy 404.771104 -390.928923) (xy 404.817414 -390.952519) (xy 404.859462 -390.983069) (xy 404.896213 -391.01982)
			(xy 404.926763 -391.061868) (xy 404.950359 -391.108178) (xy 404.96642 -391.157608) (xy 404.97455 -391.208943)
			(xy 404.97506 -391.23493) (xy 404.97455 -391.260917) (xy 405.51405 -391.260917) (xy 405.51405 -391.208943)
			(xy 405.52218 -391.157608) (xy 405.538241 -391.108178) (xy 405.561837 -391.061868) (xy 405.592387 -391.01982)
			(xy 405.629138 -390.983069) (xy 405.671186 -390.952519) (xy 405.717496 -390.928923) (xy 405.766926 -390.912862)
			(xy 405.818261 -390.904732) (xy 405.870235 -390.904732) (xy 405.92157 -390.912862) (xy 405.971 -390.928923)
			(xy 406.01731 -390.952519) (xy 406.059358 -390.983069) (xy 406.096109 -391.01982) (xy 406.126659 -391.061868)
			(xy 406.150255 -391.108178) (xy 406.166316 -391.157608) (xy 406.174446 -391.208943) (xy 406.174956 -391.23493)
			(xy 406.174446 -391.260917) (xy 406.713946 -391.260917) (xy 406.713946 -391.208943) (xy 406.722076 -391.157608)
			(xy 406.738137 -391.108178) (xy 406.761733 -391.061868) (xy 406.792283 -391.01982) (xy 406.829034 -390.983069)
			(xy 406.871082 -390.952519) (xy 406.917392 -390.928923) (xy 406.966822 -390.912862) (xy 407.018157 -390.904732)
			(xy 407.070131 -390.904732) (xy 407.121466 -390.912862) (xy 407.170896 -390.928923) (xy 407.217206 -390.952519)
			(xy 407.259254 -390.983069) (xy 407.296005 -391.01982) (xy 407.326555 -391.061868) (xy 407.350151 -391.108178)
			(xy 407.366212 -391.157608) (xy 407.374342 -391.208943) (xy 407.374852 -391.23493) (xy 407.374342 -391.260917)
			(xy 407.914096 -391.260917) (xy 407.914096 -391.208943) (xy 407.922226 -391.157608) (xy 407.938287 -391.108178)
			(xy 407.961883 -391.061868) (xy 407.992433 -391.01982) (xy 408.029184 -390.983069) (xy 408.071232 -390.952519)
			(xy 408.117542 -390.928923) (xy 408.166972 -390.912862) (xy 408.218307 -390.904732) (xy 408.270281 -390.904732)
			(xy 408.321616 -390.912862) (xy 408.371046 -390.928923) (xy 408.417356 -390.952519) (xy 408.459404 -390.983069)
			(xy 408.496155 -391.01982) (xy 408.526705 -391.061868) (xy 408.550301 -391.108178) (xy 408.566362 -391.157608)
			(xy 408.574492 -391.208943) (xy 408.575002 -391.23493) (xy 408.574492 -391.260917) (xy 409.113992 -391.260917)
			(xy 409.113992 -391.208943) (xy 409.122122 -391.157608) (xy 409.138183 -391.108178) (xy 409.161779 -391.061868)
			(xy 409.192329 -391.01982) (xy 409.22908 -390.983069) (xy 409.271128 -390.952519) (xy 409.317438 -390.928923)
			(xy 409.366868 -390.912862) (xy 409.418203 -390.904732) (xy 409.470177 -390.904732) (xy 409.521512 -390.912862)
			(xy 409.570942 -390.928923) (xy 409.617252 -390.952519) (xy 409.6593 -390.983069) (xy 409.696051 -391.01982)
			(xy 409.726601 -391.061868) (xy 409.750197 -391.108178) (xy 409.766258 -391.157608) (xy 409.774388 -391.208943)
			(xy 409.774898 -391.23493) (xy 409.774388 -391.260917) (xy 410.314142 -391.260917) (xy 410.314142 -391.208943)
			(xy 410.322272 -391.157608) (xy 410.338333 -391.108178) (xy 410.361929 -391.061868) (xy 410.392479 -391.01982)
			(xy 410.42923 -390.983069) (xy 410.471278 -390.952519) (xy 410.517588 -390.928923) (xy 410.567018 -390.912862)
			(xy 410.618353 -390.904732) (xy 410.670327 -390.904732) (xy 410.721662 -390.912862) (xy 410.771092 -390.928923)
			(xy 410.817402 -390.952519) (xy 410.85945 -390.983069) (xy 410.896201 -391.01982) (xy 410.926751 -391.061868)
			(xy 410.950347 -391.108178) (xy 410.966408 -391.157608) (xy 410.974538 -391.208943) (xy 410.975048 -391.23493)
			(xy 410.974538 -391.260917) (xy 411.514038 -391.260917) (xy 411.514038 -391.208943) (xy 411.522168 -391.157608)
			(xy 411.538229 -391.108178) (xy 411.561825 -391.061868) (xy 411.592375 -391.01982) (xy 411.629126 -390.983069)
			(xy 411.671174 -390.952519) (xy 411.717484 -390.928923) (xy 411.766914 -390.912862) (xy 411.818249 -390.904732)
			(xy 411.870223 -390.904732) (xy 411.921558 -390.912862) (xy 411.970988 -390.928923) (xy 412.017298 -390.952519)
			(xy 412.059346 -390.983069) (xy 412.096097 -391.01982) (xy 412.126647 -391.061868) (xy 412.150243 -391.108178)
			(xy 412.166304 -391.157608) (xy 412.174434 -391.208943) (xy 412.174944 -391.23493) (xy 412.174434 -391.260917)
			(xy 412.713934 -391.260917) (xy 412.713934 -391.208943) (xy 412.722064 -391.157608) (xy 412.738125 -391.108178)
			(xy 412.761721 -391.061868) (xy 412.792271 -391.01982) (xy 412.829022 -390.983069) (xy 412.87107 -390.952519)
			(xy 412.91738 -390.928923) (xy 412.96681 -390.912862) (xy 413.018145 -390.904732) (xy 413.070119 -390.904732)
			(xy 413.121454 -390.912862) (xy 413.170884 -390.928923) (xy 413.217194 -390.952519) (xy 413.259242 -390.983069)
			(xy 413.295993 -391.01982) (xy 413.326543 -391.061868) (xy 413.350139 -391.108178) (xy 413.3662 -391.157608)
			(xy 413.37433 -391.208943) (xy 413.37484 -391.23493) (xy 413.37433 -391.260917) (xy 413.914084 -391.260917)
			(xy 413.914084 -391.208943) (xy 413.922214 -391.157608) (xy 413.938275 -391.108178) (xy 413.961871 -391.061868)
			(xy 413.992421 -391.01982) (xy 414.029172 -390.983069) (xy 414.07122 -390.952519) (xy 414.11753 -390.928923)
			(xy 414.16696 -390.912862) (xy 414.218295 -390.904732) (xy 414.270269 -390.904732) (xy 414.321604 -390.912862)
			(xy 414.371034 -390.928923) (xy 414.417344 -390.952519) (xy 414.459392 -390.983069) (xy 414.496143 -391.01982)
			(xy 414.526693 -391.061868) (xy 414.550289 -391.108178) (xy 414.56635 -391.157608) (xy 414.57448 -391.208943)
			(xy 414.57499 -391.23493) (xy 414.57448 -391.260917) (xy 415.11398 -391.260917) (xy 415.11398 -391.208943)
			(xy 415.12211 -391.157608) (xy 415.138171 -391.108178) (xy 415.161767 -391.061868) (xy 415.192317 -391.01982)
			(xy 415.229068 -390.983069) (xy 415.271116 -390.952519) (xy 415.317426 -390.928923) (xy 415.366856 -390.912862)
			(xy 415.418191 -390.904732) (xy 415.470165 -390.904732) (xy 415.5215 -390.912862) (xy 415.57093 -390.928923)
			(xy 415.61724 -390.952519) (xy 415.659288 -390.983069) (xy 415.696039 -391.01982) (xy 415.726589 -391.061868)
			(xy 415.750185 -391.108178) (xy 415.766246 -391.157608) (xy 415.774376 -391.208943) (xy 415.774886 -391.23493)
			(xy 415.774376 -391.260917) (xy 416.31413 -391.260917) (xy 416.31413 -391.208943) (xy 416.32226 -391.157608)
			(xy 416.338321 -391.108178) (xy 416.361917 -391.061868) (xy 416.392467 -391.01982) (xy 416.429218 -390.983069)
			(xy 416.471266 -390.952519) (xy 416.517576 -390.928923) (xy 416.567006 -390.912862) (xy 416.618341 -390.904732)
			(xy 416.670315 -390.904732) (xy 416.72165 -390.912862) (xy 416.77108 -390.928923) (xy 416.81739 -390.952519)
			(xy 416.859438 -390.983069) (xy 416.896189 -391.01982) (xy 416.926739 -391.061868) (xy 416.950335 -391.108178)
			(xy 416.966396 -391.157608) (xy 416.974526 -391.208943) (xy 416.975036 -391.23493) (xy 416.974526 -391.260917)
			(xy 417.514026 -391.260917) (xy 417.514026 -391.208943) (xy 417.522156 -391.157608) (xy 417.538217 -391.108178)
			(xy 417.561813 -391.061868) (xy 417.592363 -391.01982) (xy 417.629114 -390.983069) (xy 417.671162 -390.952519)
			(xy 417.717472 -390.928923) (xy 417.766902 -390.912862) (xy 417.818237 -390.904732) (xy 417.870211 -390.904732)
			(xy 417.921546 -390.912862) (xy 417.970976 -390.928923) (xy 418.017286 -390.952519) (xy 418.059334 -390.983069)
			(xy 418.096085 -391.01982) (xy 418.126635 -391.061868) (xy 418.150231 -391.108178) (xy 418.166292 -391.157608)
			(xy 418.174422 -391.208943) (xy 418.174932 -391.23493) (xy 418.174422 -391.260917) (xy 418.713922 -391.260917)
			(xy 418.713922 -391.208943) (xy 418.722052 -391.157608) (xy 418.738113 -391.108178) (xy 418.761709 -391.061868)
			(xy 418.792259 -391.01982) (xy 418.82901 -390.983069) (xy 418.871058 -390.952519) (xy 418.917368 -390.928923)
			(xy 418.966798 -390.912862) (xy 419.018133 -390.904732) (xy 419.070107 -390.904732) (xy 419.121442 -390.912862)
			(xy 419.170872 -390.928923) (xy 419.217182 -390.952519) (xy 419.25923 -390.983069) (xy 419.295981 -391.01982)
			(xy 419.326531 -391.061868) (xy 419.350127 -391.108178) (xy 419.366188 -391.157608) (xy 419.374318 -391.208943)
			(xy 419.374828 -391.23493) (xy 419.374318 -391.260917) (xy 419.914072 -391.260917) (xy 419.914072 -391.208943)
			(xy 419.922202 -391.157608) (xy 419.938263 -391.108178) (xy 419.961859 -391.061868) (xy 419.992409 -391.01982)
			(xy 420.02916 -390.983069) (xy 420.071208 -390.952519) (xy 420.117518 -390.928923) (xy 420.166948 -390.912862)
			(xy 420.218283 -390.904732) (xy 420.270257 -390.904732) (xy 420.321592 -390.912862) (xy 420.371022 -390.928923)
			(xy 420.417332 -390.952519) (xy 420.45938 -390.983069) (xy 420.496131 -391.01982) (xy 420.526681 -391.061868)
			(xy 420.550277 -391.108178) (xy 420.566338 -391.157608) (xy 420.574468 -391.208943) (xy 420.574978 -391.23493)
			(xy 420.574468 -391.260917) (xy 421.113968 -391.260917) (xy 421.113968 -391.208943) (xy 421.122098 -391.157608)
			(xy 421.138159 -391.108178) (xy 421.161755 -391.061868) (xy 421.192305 -391.01982) (xy 421.229056 -390.983069)
			(xy 421.271104 -390.952519) (xy 421.317414 -390.928923) (xy 421.366844 -390.912862) (xy 421.418179 -390.904732)
			(xy 421.470153 -390.904732) (xy 421.521488 -390.912862) (xy 421.570918 -390.928923) (xy 421.617228 -390.952519)
			(xy 421.659276 -390.983069) (xy 421.696027 -391.01982) (xy 421.726577 -391.061868) (xy 421.750173 -391.108178)
			(xy 421.766234 -391.157608) (xy 421.774364 -391.208943) (xy 421.774874 -391.23493) (xy 421.774364 -391.260917)
			(xy 421.766234 -391.312252) (xy 421.750173 -391.361682) (xy 421.726577 -391.407992) (xy 421.696027 -391.45004)
			(xy 421.659276 -391.486791) (xy 421.617228 -391.517341) (xy 421.570918 -391.540937) (xy 421.521488 -391.556998)
			(xy 421.470153 -391.565128) (xy 421.418179 -391.565128) (xy 421.366844 -391.556998) (xy 421.317414 -391.540937)
			(xy 421.271104 -391.517341) (xy 421.229056 -391.486791) (xy 421.192305 -391.45004) (xy 421.161755 -391.407992)
			(xy 421.138159 -391.361682) (xy 421.122098 -391.312252) (xy 421.113968 -391.260917) (xy 420.574468 -391.260917)
			(xy 420.566338 -391.312252) (xy 420.550277 -391.361682) (xy 420.526681 -391.407992) (xy 420.496131 -391.45004)
			(xy 420.45938 -391.486791) (xy 420.417332 -391.517341) (xy 420.371022 -391.540937) (xy 420.321592 -391.556998)
			(xy 420.270257 -391.565128) (xy 420.218283 -391.565128) (xy 420.166948 -391.556998) (xy 420.117518 -391.540937)
			(xy 420.071208 -391.517341) (xy 420.02916 -391.486791) (xy 419.992409 -391.45004) (xy 419.961859 -391.407992)
			(xy 419.938263 -391.361682) (xy 419.922202 -391.312252) (xy 419.914072 -391.260917) (xy 419.374318 -391.260917)
			(xy 419.366188 -391.312252) (xy 419.350127 -391.361682) (xy 419.326531 -391.407992) (xy 419.295981 -391.45004)
			(xy 419.25923 -391.486791) (xy 419.217182 -391.517341) (xy 419.170872 -391.540937) (xy 419.121442 -391.556998)
			(xy 419.070107 -391.565128) (xy 419.018133 -391.565128) (xy 418.966798 -391.556998) (xy 418.917368 -391.540937)
			(xy 418.871058 -391.517341) (xy 418.82901 -391.486791) (xy 418.792259 -391.45004) (xy 418.761709 -391.407992)
			(xy 418.738113 -391.361682) (xy 418.722052 -391.312252) (xy 418.713922 -391.260917) (xy 418.174422 -391.260917)
			(xy 418.166292 -391.312252) (xy 418.150231 -391.361682) (xy 418.126635 -391.407992) (xy 418.096085 -391.45004)
			(xy 418.059334 -391.486791) (xy 418.017286 -391.517341) (xy 417.970976 -391.540937) (xy 417.921546 -391.556998)
			(xy 417.870211 -391.565128) (xy 417.818237 -391.565128) (xy 417.766902 -391.556998) (xy 417.717472 -391.540937)
			(xy 417.671162 -391.517341) (xy 417.629114 -391.486791) (xy 417.592363 -391.45004) (xy 417.561813 -391.407992)
			(xy 417.538217 -391.361682) (xy 417.522156 -391.312252) (xy 417.514026 -391.260917) (xy 416.974526 -391.260917)
			(xy 416.966396 -391.312252) (xy 416.950335 -391.361682) (xy 416.926739 -391.407992) (xy 416.896189 -391.45004)
			(xy 416.859438 -391.486791) (xy 416.81739 -391.517341) (xy 416.77108 -391.540937) (xy 416.72165 -391.556998)
			(xy 416.670315 -391.565128) (xy 416.618341 -391.565128) (xy 416.567006 -391.556998) (xy 416.517576 -391.540937)
			(xy 416.471266 -391.517341) (xy 416.429218 -391.486791) (xy 416.392467 -391.45004) (xy 416.361917 -391.407992)
			(xy 416.338321 -391.361682) (xy 416.32226 -391.312252) (xy 416.31413 -391.260917) (xy 415.774376 -391.260917)
			(xy 415.766246 -391.312252) (xy 415.750185 -391.361682) (xy 415.726589 -391.407992) (xy 415.696039 -391.45004)
			(xy 415.659288 -391.486791) (xy 415.61724 -391.517341) (xy 415.57093 -391.540937) (xy 415.5215 -391.556998)
			(xy 415.470165 -391.565128) (xy 415.418191 -391.565128) (xy 415.366856 -391.556998) (xy 415.317426 -391.540937)
			(xy 415.271116 -391.517341) (xy 415.229068 -391.486791) (xy 415.192317 -391.45004) (xy 415.161767 -391.407992)
			(xy 415.138171 -391.361682) (xy 415.12211 -391.312252) (xy 415.11398 -391.260917) (xy 414.57448 -391.260917)
			(xy 414.56635 -391.312252) (xy 414.550289 -391.361682) (xy 414.526693 -391.407992) (xy 414.496143 -391.45004)
			(xy 414.459392 -391.486791) (xy 414.417344 -391.517341) (xy 414.371034 -391.540937) (xy 414.321604 -391.556998)
			(xy 414.270269 -391.565128) (xy 414.218295 -391.565128) (xy 414.16696 -391.556998) (xy 414.11753 -391.540937)
			(xy 414.07122 -391.517341) (xy 414.029172 -391.486791) (xy 413.992421 -391.45004) (xy 413.961871 -391.407992)
			(xy 413.938275 -391.361682) (xy 413.922214 -391.312252) (xy 413.914084 -391.260917) (xy 413.37433 -391.260917)
			(xy 413.3662 -391.312252) (xy 413.350139 -391.361682) (xy 413.326543 -391.407992) (xy 413.295993 -391.45004)
			(xy 413.259242 -391.486791) (xy 413.217194 -391.517341) (xy 413.170884 -391.540937) (xy 413.121454 -391.556998)
			(xy 413.070119 -391.565128) (xy 413.018145 -391.565128) (xy 412.96681 -391.556998) (xy 412.91738 -391.540937)
			(xy 412.87107 -391.517341) (xy 412.829022 -391.486791) (xy 412.792271 -391.45004) (xy 412.761721 -391.407992)
			(xy 412.738125 -391.361682) (xy 412.722064 -391.312252) (xy 412.713934 -391.260917) (xy 412.174434 -391.260917)
			(xy 412.166304 -391.312252) (xy 412.150243 -391.361682) (xy 412.126647 -391.407992) (xy 412.096097 -391.45004)
			(xy 412.059346 -391.486791) (xy 412.017298 -391.517341) (xy 411.970988 -391.540937) (xy 411.921558 -391.556998)
			(xy 411.870223 -391.565128) (xy 411.818249 -391.565128) (xy 411.766914 -391.556998) (xy 411.717484 -391.540937)
			(xy 411.671174 -391.517341) (xy 411.629126 -391.486791) (xy 411.592375 -391.45004) (xy 411.561825 -391.407992)
			(xy 411.538229 -391.361682) (xy 411.522168 -391.312252) (xy 411.514038 -391.260917) (xy 410.974538 -391.260917)
			(xy 410.966408 -391.312252) (xy 410.950347 -391.361682) (xy 410.926751 -391.407992) (xy 410.896201 -391.45004)
			(xy 410.85945 -391.486791) (xy 410.817402 -391.517341) (xy 410.771092 -391.540937) (xy 410.721662 -391.556998)
			(xy 410.670327 -391.565128) (xy 410.618353 -391.565128) (xy 410.567018 -391.556998) (xy 410.517588 -391.540937)
			(xy 410.471278 -391.517341) (xy 410.42923 -391.486791) (xy 410.392479 -391.45004) (xy 410.361929 -391.407992)
			(xy 410.338333 -391.361682) (xy 410.322272 -391.312252) (xy 410.314142 -391.260917) (xy 409.774388 -391.260917)
			(xy 409.766258 -391.312252) (xy 409.750197 -391.361682) (xy 409.726601 -391.407992) (xy 409.696051 -391.45004)
			(xy 409.6593 -391.486791) (xy 409.617252 -391.517341) (xy 409.570942 -391.540937) (xy 409.521512 -391.556998)
			(xy 409.470177 -391.565128) (xy 409.418203 -391.565128) (xy 409.366868 -391.556998) (xy 409.317438 -391.540937)
			(xy 409.271128 -391.517341) (xy 409.22908 -391.486791) (xy 409.192329 -391.45004) (xy 409.161779 -391.407992)
			(xy 409.138183 -391.361682) (xy 409.122122 -391.312252) (xy 409.113992 -391.260917) (xy 408.574492 -391.260917)
			(xy 408.566362 -391.312252) (xy 408.550301 -391.361682) (xy 408.526705 -391.407992) (xy 408.496155 -391.45004)
			(xy 408.459404 -391.486791) (xy 408.417356 -391.517341) (xy 408.371046 -391.540937) (xy 408.321616 -391.556998)
			(xy 408.270281 -391.565128) (xy 408.218307 -391.565128) (xy 408.166972 -391.556998) (xy 408.117542 -391.540937)
			(xy 408.071232 -391.517341) (xy 408.029184 -391.486791) (xy 407.992433 -391.45004) (xy 407.961883 -391.407992)
			(xy 407.938287 -391.361682) (xy 407.922226 -391.312252) (xy 407.914096 -391.260917) (xy 407.374342 -391.260917)
			(xy 407.366212 -391.312252) (xy 407.350151 -391.361682) (xy 407.326555 -391.407992) (xy 407.296005 -391.45004)
			(xy 407.259254 -391.486791) (xy 407.217206 -391.517341) (xy 407.170896 -391.540937) (xy 407.121466 -391.556998)
			(xy 407.070131 -391.565128) (xy 407.018157 -391.565128) (xy 406.966822 -391.556998) (xy 406.917392 -391.540937)
			(xy 406.871082 -391.517341) (xy 406.829034 -391.486791) (xy 406.792283 -391.45004) (xy 406.761733 -391.407992)
			(xy 406.738137 -391.361682) (xy 406.722076 -391.312252) (xy 406.713946 -391.260917) (xy 406.174446 -391.260917)
			(xy 406.166316 -391.312252) (xy 406.150255 -391.361682) (xy 406.126659 -391.407992) (xy 406.096109 -391.45004)
			(xy 406.059358 -391.486791) (xy 406.01731 -391.517341) (xy 405.971 -391.540937) (xy 405.92157 -391.556998)
			(xy 405.870235 -391.565128) (xy 405.818261 -391.565128) (xy 405.766926 -391.556998) (xy 405.717496 -391.540937)
			(xy 405.671186 -391.517341) (xy 405.629138 -391.486791) (xy 405.592387 -391.45004) (xy 405.561837 -391.407992)
			(xy 405.538241 -391.361682) (xy 405.52218 -391.312252) (xy 405.51405 -391.260917) (xy 404.97455 -391.260917)
			(xy 404.96642 -391.312252) (xy 404.950359 -391.361682) (xy 404.926763 -391.407992) (xy 404.896213 -391.45004)
			(xy 404.859462 -391.486791) (xy 404.817414 -391.517341) (xy 404.771104 -391.540937) (xy 404.721674 -391.556998)
			(xy 404.670339 -391.565128) (xy 404.618365 -391.565128) (xy 404.56703 -391.556998) (xy 404.5176 -391.540937)
			(xy 404.47129 -391.517341) (xy 404.429242 -391.486791) (xy 404.392491 -391.45004) (xy 404.361941 -391.407992)
			(xy 404.338345 -391.361682) (xy 404.322284 -391.312252) (xy 404.314154 -391.260917) (xy 403.7744 -391.260917)
			(xy 403.76627 -391.312252) (xy 403.750209 -391.361682) (xy 403.726613 -391.407992) (xy 403.696063 -391.45004)
			(xy 403.659312 -391.486791) (xy 403.617264 -391.517341) (xy 403.570954 -391.540937) (xy 403.521524 -391.556998)
			(xy 403.470189 -391.565128) (xy 403.418215 -391.565128) (xy 403.36688 -391.556998) (xy 403.31745 -391.540937)
			(xy 403.27114 -391.517341) (xy 403.229092 -391.486791) (xy 403.192341 -391.45004) (xy 403.161791 -391.407992)
			(xy 403.138195 -391.361682) (xy 403.122134 -391.312252) (xy 403.114004 -391.260917) (xy 402.425844 -391.260917)
			(xy 402.426422 -391.264569) (xy 402.426932 -391.290556) (xy 402.426422 -391.316543) (xy 402.418292 -391.367878)
			(xy 402.402231 -391.417308) (xy 402.378635 -391.463618) (xy 402.348085 -391.505666) (xy 402.311334 -391.542417)
			(xy 402.269286 -391.572967) (xy 402.222976 -391.596563) (xy 402.173546 -391.612624) (xy 402.122211 -391.620754)
			(xy 402.070237 -391.620754) (xy 402.018902 -391.612624) (xy 401.969472 -391.596563) (xy 401.923162 -391.572967)
			(xy 401.881114 -391.542417) (xy 401.844363 -391.505666) (xy 401.813813 -391.463618) (xy 401.790217 -391.417308)
			(xy 401.774156 -391.367878) (xy 401.766026 -391.316543) (xy 400.407632 -391.316543) (xy 400.407632 -391.97026)
			(xy 400.408045 -391.980284) (xy 400.415709 -391.998809) (xy 400.429884 -392.012986) (xy 400.448408 -392.020653)
			(xy 400.458432 -392.02106) (xy 421.552878 -392.02106) (xy 421.562941 -392.021499) (xy 421.581519 -392.02924)
			(xy 421.588946 -392.036046) (xy 421.932354 -392.379454) (xy 421.939197 -392.386853) (xy 421.946919 -392.405452)
			(xy 421.94734 -392.415522) (xy 421.94734 -393.98321) (xy 421.947535 -393.989878) (xy 421.951009 -394.002751)
			(xy 421.954198 -394.00861) (xy 422.019984 -394.122402) (xy 422.02735 -394.128244) (xy 422.046131 -394.144047)
			(xy 422.079268 -394.180252) (xy 422.106693 -394.220956) (xy 422.127802 -394.265265) (xy 422.142134 -394.312207)
			(xy 422.149372 -394.360751) (xy 422.149778 -394.385292) (xy 422.149524 -394.396976) (xy 422.14927 -394.406882)
			(xy 422.15562 -394.424916) (xy 422.214802 -394.491972) (xy 422.232074 -394.500862) (xy 422.241726 -394.501624)
			(xy 422.266065 -394.504295) (xy 422.313632 -394.515898) (xy 422.358968 -394.534388) (xy 422.401083 -394.559361)
			(xy 422.439053 -394.590272) (xy 422.472051 -394.626444) (xy 422.499354 -394.667087) (xy 422.520365 -394.711311)
			(xy 422.534624 -394.758151) (xy 422.54182 -394.806581) (xy 422.542208 -394.831062) (xy 422.541728 -394.857053)
			(xy 422.533601 -394.908396) (xy 422.517542 -394.957836) (xy 422.493947 -395.004154) (xy 422.463395 -395.046211)
			(xy 422.42664 -395.08297) (xy 422.384587 -395.113527) (xy 422.338271 -395.137128) (xy 422.288833 -395.153192)
			(xy 422.237491 -395.161325) (xy 422.2115 -395.16177) (xy 422.179569 -395.161006) (xy 422.116896 -395.148735)
			(xy 422.08704 -395.137386) (xy 422.075356 -395.13256) (xy 422.05021 -395.135354) (xy 421.969692 -395.189456)
			(xy 421.959672 -395.196983) (xy 421.947953 -395.219102) (xy 421.94734 -395.23162) (xy 421.94734 -397.447262)
			(xy 421.947529 -397.453931) (xy 421.950992 -397.466811) (xy 421.954198 -397.472662) (xy 422.083738 -397.696944)
			(xy 422.096521 -397.720294) (xy 422.114712 -397.770318) (xy 422.123996 -397.822731) (xy 422.124632 -397.849344)
			(xy 422.124052 -397.875957) (xy 422.114822 -397.928378) (xy 422.096648 -397.978406) (xy 422.07008 -398.024528)
			(xy 422.035922 -398.065349) (xy 421.995207 -398.099634) (xy 421.972486 -398.113504) (xy 421.960802 -398.120362)
			(xy 421.94734 -398.143476) (xy 421.94734 -398.255998) (xy 421.947808 -398.266273) (xy 421.955853 -398.285182)
			(xy 421.970659 -398.299432) (xy 421.980106 -398.303496) (xy 422.083992 -398.342612) (xy 422.114472 -398.335246)
			(xy 422.12514 -398.323054) (xy 422.144144 -398.302424) (xy 422.187827 -398.267249) (xy 422.23682 -398.239952)
			(xy 422.289717 -398.221315) (xy 422.345001 -398.211873) (xy 422.373044 -398.211294) (xy 422.399029 -398.211807)
			(xy 422.450358 -398.219943) (xy 422.499782 -398.236008) (xy 422.546085 -398.259606) (xy 422.588127 -398.290156)
			(xy 422.624873 -398.326907) (xy 422.655417 -398.368952) (xy 422.679009 -398.415259) (xy 422.695067 -398.464685)
			(xy 422.703197 -398.516015) (xy 422.703197 -398.567985) (xy 422.695067 -398.619315) (xy 422.679009 -398.668741)
			(xy 422.655417 -398.715048) (xy 422.624873 -398.757093) (xy 422.588127 -398.793844) (xy 422.546085 -398.824394)
			(xy 422.499782 -398.847992) (xy 422.450358 -398.864057) (xy 422.399029 -398.872193) (xy 422.373044 -398.87271)
			(xy 422.345005 -398.872115) (xy 422.28973 -398.862653) (xy 422.23684 -398.84401) (xy 422.18785 -398.816718)
			(xy 422.144162 -398.78156) (xy 422.12514 -398.76095) (xy 422.114472 -398.748758) (xy 422.083992 -398.741392)
			(xy 421.980106 -398.780508) (xy 421.970664 -398.784589) (xy 421.955839 -398.798823) (xy 421.947783 -398.81773)
			(xy 421.94734 -398.828006) (xy 421.94734 -399.434558) (xy 421.946905 -399.444622) (xy 421.939169 -399.463206)
			(xy 421.932354 -399.470626) (xy 421.802306 -399.600674) (xy 421.794909 -399.607524) (xy 421.776311 -399.615265)
			(xy 421.766238 -399.61566) (xy 402.608542 -399.61566) (xy 402.598477 -399.615225) (xy 402.579892 -399.607491)
			(xy 402.572474 -399.600674) (xy 402.48586 -399.51406) (xy 402.478446 -399.507386) (xy 402.460011 -399.499825)
			(xy 402.450046 -399.499328) (xy 400.519646 -399.499328) (xy 400.509683 -399.499813) (xy 400.491258 -399.5074)
			(xy 400.483832 -399.51406) (xy 400.422618 -399.575274) (xy 400.415781 -399.582676) (xy 400.408071 -399.601274)
			(xy 400.407632 -399.611342) (xy 400.407632 -400.146774) (xy 400.409156 -400.148044) (xy 400.409156 -400.183937)
			(xy 401.792442 -400.183937) (xy 401.792442 -400.131963) (xy 401.800572 -400.080628) (xy 401.816633 -400.031198)
			(xy 401.840229 -399.984888) (xy 401.870779 -399.94284) (xy 401.90753 -399.906089) (xy 401.949578 -399.875539)
			(xy 401.995888 -399.851943) (xy 402.045318 -399.835882) (xy 402.096653 -399.827752) (xy 402.148627 -399.827752)
			(xy 402.199962 -399.835882) (xy 402.249392 -399.851943) (xy 402.295702 -399.875539) (xy 402.33775 -399.906089)
			(xy 402.374501 -399.94284) (xy 402.405051 -399.984888) (xy 402.428647 -400.031198) (xy 402.444708 -400.080628)
			(xy 402.452838 -400.131963) (xy 402.453348 -400.15795) (xy 402.452838 -400.183937) (xy 402.444708 -400.235272)
			(xy 402.428647 -400.284702) (xy 402.405051 -400.331012) (xy 402.374501 -400.37306) (xy 402.33775 -400.409811)
			(xy 402.295702 -400.440361) (xy 402.249392 -400.463957) (xy 402.199962 -400.480018) (xy 402.148627 -400.488148)
			(xy 402.096653 -400.488148) (xy 402.045318 -400.480018) (xy 401.995888 -400.463957) (xy 401.949578 -400.440361)
			(xy 401.90753 -400.409811) (xy 401.870779 -400.37306) (xy 401.840229 -400.331012) (xy 401.816633 -400.284702)
			(xy 401.800572 -400.235272) (xy 401.792442 -400.183937) (xy 400.409156 -400.183937) (xy 400.409156 -400.466052)
			(xy 400.41068 -400.472402) (xy 400.416368 -400.495803) (xy 400.42248 -400.543573) (xy 400.422872 -400.567652)
			(xy 400.422474 -400.591731) (xy 400.416364 -400.6395) (xy 400.41068 -400.662902) (xy 400.409156 -400.669252)
			(xy 400.409156 -400.696938) (xy 400.409603 -400.707095) (xy 400.417456 -400.725831) (xy 400.424396 -400.73326)
			(xy 400.446494 -400.75485) (xy 400.453556 -400.761219) (xy 400.471044 -400.768654) (xy 400.48053 -400.769328)
			(xy 400.507269 -400.770531) (xy 400.560037 -400.779498) (xy 400.611035 -400.795749) (xy 400.659262 -400.818968)
			(xy 400.703771 -400.848697) (xy 400.743689 -400.884354) (xy 400.778233 -400.92524) (xy 400.806725 -400.970551)
			(xy 400.828606 -401.019399) (xy 400.843447 -401.070825) (xy 400.850957 -401.12382) (xy 400.85137 -401.150582)
			(xy 400.850845 -401.178945) (xy 400.842437 -401.235044) (xy 400.825819 -401.289281) (xy 400.801355 -401.340461)
			(xy 400.769587 -401.387457) (xy 400.731212 -401.429233) (xy 400.687077 -401.464869) (xy 400.638153 -401.49358)
			(xy 400.585519 -401.514734) (xy 400.530334 -401.527865) (xy 400.50212 -401.53082) (xy 400.492468 -401.531582)
			(xy 400.47545 -401.539964) (xy 400.422618 -401.597622) (xy 400.416464 -401.604825) (xy 400.409542 -401.622446)
			(xy 400.409156 -401.631912) (xy 400.409156 -401.674838) (xy 403.06244 -401.674838) (xy 403.06244 -400.811238)
			(xy 403.06292 -400.784882) (xy 403.070183 -400.732674) (xy 403.084562 -400.681962) (xy 403.105783 -400.633711)
			(xy 403.133443 -400.58884) (xy 403.167015 -400.548202) (xy 403.186138 -400.53006) (xy 403.19325 -400.52371)
			(xy 403.201378 -400.506946) (xy 403.20976 -400.420332) (xy 403.20468 -400.402552) (xy 403.199092 -400.394678)
			(xy 403.184947 -400.374828) (xy 403.162487 -400.331571) (xy 403.147173 -400.285299) (xy 403.139393 -400.237184)
			(xy 403.138894 -400.212814) (xy 403.139416 -400.187559) (xy 403.147729 -400.137737) (xy 403.16413 -400.089963)
			(xy 403.188171 -400.04554) (xy 403.219195 -400.00568) (xy 403.256357 -399.97147) (xy 403.298643 -399.943844)
			(xy 403.344899 -399.923554) (xy 403.393864 -399.911154) (xy 403.444202 -399.906983) (xy 403.49454 -399.911154)
			(xy 403.543505 -399.923554) (xy 403.589761 -399.943844) (xy 403.632047 -399.97147) (xy 403.669209 -400.00568)
			(xy 403.700233 -400.04554) (xy 403.724274 -400.089963) (xy 403.740675 -400.137737) (xy 403.748988 -400.187559)
			(xy 403.74951 -400.212814) (xy 403.74904 -400.237187) (xy 403.74128 -400.285311) (xy 403.72596 -400.331586)
			(xy 403.703471 -400.374834) (xy 403.689312 -400.394678) (xy 403.683724 -400.402552) (xy 403.678644 -400.420332)
			(xy 403.687026 -400.506946) (xy 403.695154 -400.52371) (xy 403.702266 -400.53006) (xy 403.721403 -400.548191)
			(xy 403.75499 -400.588822) (xy 403.782661 -400.633693) (xy 403.803887 -400.681947) (xy 403.818266 -400.732665)
			(xy 403.825521 -400.78488) (xy 403.825964 -400.811238) (xy 403.825964 -401.674838) (xy 404.262336 -401.674838)
			(xy 404.262336 -400.811238) (xy 404.262817 -400.784882) (xy 404.27008 -400.732674) (xy 404.284459 -400.681962)
			(xy 404.30568 -400.633711) (xy 404.33334 -400.58884) (xy 404.366912 -400.548202) (xy 404.386034 -400.53006)
			(xy 404.393146 -400.523456) (xy 404.401528 -400.506946) (xy 404.409656 -400.420078) (xy 404.40483 -400.402298)
			(xy 404.398988 -400.394678) (xy 404.384883 -400.37481) (xy 404.36246 -400.331555) (xy 404.347202 -400.285284)
			(xy 404.339498 -400.237175) (xy 404.339044 -400.212814) (xy 404.339566 -400.187559) (xy 404.347879 -400.137737)
			(xy 404.36428 -400.089963) (xy 404.388321 -400.04554) (xy 404.419345 -400.00568) (xy 404.456507 -399.97147)
			(xy 404.498793 -399.943844) (xy 404.545049 -399.923554) (xy 404.594014 -399.911154) (xy 404.644352 -399.906983)
			(xy 404.69469 -399.911154) (xy 404.743655 -399.923554) (xy 404.789911 -399.943844) (xy 404.832197 -399.97147)
			(xy 404.869359 -400.00568) (xy 404.900383 -400.04554) (xy 404.924424 -400.089963) (xy 404.940825 -400.137737)
			(xy 404.949138 -400.187559) (xy 404.94966 -400.212814) (xy 404.949194 -400.237217) (xy 404.941434 -400.285401)
			(xy 404.926114 -400.331739) (xy 404.903624 -400.375053) (xy 404.889462 -400.394932) (xy 404.883874 -400.402552)
			(xy 404.878794 -400.420332) (xy 404.886922 -400.5072) (xy 404.895304 -400.52371) (xy 404.902416 -400.530314)
			(xy 404.921485 -400.548467) (xy 404.954975 -400.589089) (xy 404.982572 -400.633924) (xy 405.003754 -400.682122)
			(xy 405.018119 -400.732772) (xy 405.025395 -400.784915) (xy 405.02586 -400.811238) (xy 405.02586 -401.674838)
			(xy 405.46274 -401.674838) (xy 405.46274 -400.811238) (xy 405.463207 -400.784893) (xy 405.470454 -400.732705)
			(xy 405.484803 -400.682007) (xy 405.50598 -400.633761) (xy 405.533585 -400.588882) (xy 405.567094 -400.548221)
			(xy 405.586184 -400.53006) (xy 405.593296 -400.52371) (xy 405.601424 -400.506946) (xy 405.609806 -400.420332)
			(xy 405.604726 -400.402552) (xy 405.599138 -400.394678) (xy 405.584986 -400.374832) (xy 405.56253 -400.331573)
			(xy 405.547218 -400.2853) (xy 405.539438 -400.237184) (xy 405.53894 -400.212814) (xy 405.539462 -400.187559)
			(xy 405.547775 -400.137737) (xy 405.564176 -400.089963) (xy 405.588217 -400.04554) (xy 405.619241 -400.00568)
			(xy 405.656403 -399.97147) (xy 405.698689 -399.943844) (xy 405.744945 -399.923554) (xy 405.79391 -399.911154)
			(xy 405.844248 -399.906983) (xy 405.894586 -399.911154) (xy 405.943551 -399.923554) (xy 405.989807 -399.943844)
			(xy 406.032093 -399.97147) (xy 406.069255 -400.00568) (xy 406.100279 -400.04554) (xy 406.12432 -400.089963)
			(xy 406.140721 -400.137737) (xy 406.149034 -400.187559) (xy 406.149556 -400.212814) (xy 406.149077 -400.237186)
			(xy 406.141318 -400.285309) (xy 406.126001 -400.331585) (xy 406.103515 -400.374833) (xy 406.089358 -400.394678)
			(xy 406.08377 -400.402552) (xy 406.07869 -400.420332) (xy 406.087072 -400.506946) (xy 406.0952 -400.52371)
			(xy 406.102312 -400.53006) (xy 406.121407 -400.548218) (xy 406.154931 -400.588871) (xy 406.182546 -400.633748)
			(xy 406.203728 -400.681996) (xy 406.218076 -400.732698) (xy 406.225316 -400.784891) (xy 406.225756 -400.811238)
			(xy 406.225756 -401.674838) (xy 406.662636 -401.674838) (xy 406.662636 -400.811238) (xy 406.663105 -400.784893)
			(xy 406.670352 -400.732705) (xy 406.6847 -400.682007) (xy 406.705877 -400.633761) (xy 406.733482 -400.588882)
			(xy 406.76699 -400.548221) (xy 406.78608 -400.53006) (xy 406.793192 -400.52371) (xy 406.80132 -400.506946)
			(xy 406.809702 -400.420332) (xy 406.804622 -400.402552) (xy 406.799034 -400.394678) (xy 406.784882 -400.374833)
			(xy 406.762425 -400.331573) (xy 406.747114 -400.2853) (xy 406.739334 -400.237184) (xy 406.738836 -400.212814)
			(xy 406.739358 -400.187559) (xy 406.747671 -400.137737) (xy 406.764072 -400.089963) (xy 406.788113 -400.04554)
			(xy 406.819137 -400.00568) (xy 406.856299 -399.97147) (xy 406.898585 -399.943844) (xy 406.944841 -399.923554)
			(xy 406.993806 -399.911154) (xy 407.044144 -399.906983) (xy 407.094482 -399.911154) (xy 407.143447 -399.923554)
			(xy 407.189703 -399.943844) (xy 407.231989 -399.97147) (xy 407.269151 -400.00568) (xy 407.300175 -400.04554)
			(xy 407.324216 -400.089963) (xy 407.340617 -400.137737) (xy 407.34893 -400.187559) (xy 407.349452 -400.212814)
			(xy 407.348973 -400.237186) (xy 407.341215 -400.285309) (xy 407.325897 -400.331585) (xy 407.303411 -400.374833)
			(xy 407.289254 -400.394678) (xy 407.283666 -400.402552) (xy 407.278586 -400.420332) (xy 407.286968 -400.506946)
			(xy 407.295096 -400.52371) (xy 407.302208 -400.53006) (xy 407.321303 -400.548218) (xy 407.354826 -400.588872)
			(xy 407.382442 -400.633749) (xy 407.403624 -400.681996) (xy 407.417972 -400.732698) (xy 407.425212 -400.784892)
			(xy 407.425652 -400.811238) (xy 407.425652 -401.674838) (xy 407.862532 -401.674838) (xy 407.862532 -400.811238)
			(xy 407.863014 -400.784883) (xy 407.870277 -400.732674) (xy 407.884656 -400.681962) (xy 407.905877 -400.633711)
			(xy 407.933536 -400.58884) (xy 407.967108 -400.548203) (xy 407.98623 -400.53006) (xy 407.993342 -400.52371)
			(xy 408.00147 -400.506946) (xy 408.009852 -400.420332) (xy 408.004772 -400.402552) (xy 407.999184 -400.394678)
			(xy 407.985038 -400.374828) (xy 407.962579 -400.331571) (xy 407.947265 -400.285299) (xy 407.939485 -400.237184)
			(xy 407.938986 -400.212814) (xy 407.939508 -400.187559) (xy 407.947821 -400.137737) (xy 407.964222 -400.089963)
			(xy 407.988263 -400.04554) (xy 408.019287 -400.00568) (xy 408.056449 -399.97147) (xy 408.098735 -399.943844)
			(xy 408.144991 -399.923554) (xy 408.193956 -399.911154) (xy 408.244294 -399.906983) (xy 408.294632 -399.911154)
			(xy 408.343597 -399.923554) (xy 408.389853 -399.943844) (xy 408.432139 -399.97147) (xy 408.469301 -400.00568)
			(xy 408.500325 -400.04554) (xy 408.524366 -400.089963) (xy 408.540767 -400.137737) (xy 408.54908 -400.187559)
			(xy 408.549602 -400.212814) (xy 408.549133 -400.237187) (xy 408.541373 -400.285311) (xy 408.526053 -400.331586)
			(xy 408.503563 -400.374834) (xy 408.489404 -400.394678) (xy 408.483816 -400.402552) (xy 408.478736 -400.420332)
			(xy 408.487118 -400.506946) (xy 408.495246 -400.52371) (xy 408.502358 -400.53006) (xy 408.521493 -400.548192)
			(xy 408.555081 -400.588824) (xy 408.582752 -400.633694) (xy 408.603979 -400.681947) (xy 408.618358 -400.732665)
			(xy 408.625613 -400.78488) (xy 408.626056 -400.811238) (xy 408.626056 -401.674838) (xy 409.062428 -401.674838)
			(xy 409.062428 -400.811238) (xy 409.062912 -400.784883) (xy 409.070174 -400.732674) (xy 409.084553 -400.681962)
			(xy 409.105774 -400.633712) (xy 409.133433 -400.58884) (xy 409.167004 -400.548203) (xy 409.186126 -400.53006)
			(xy 409.193238 -400.52371) (xy 409.201366 -400.506946) (xy 409.209748 -400.420332) (xy 409.204668 -400.402552)
			(xy 409.19908 -400.394678) (xy 409.184933 -400.374829) (xy 409.162474 -400.331571) (xy 409.147161 -400.285299)
			(xy 409.13938 -400.237184) (xy 409.138882 -400.212814) (xy 409.139404 -400.187559) (xy 409.147717 -400.137737)
			(xy 409.164118 -400.089963) (xy 409.188159 -400.04554) (xy 409.219183 -400.00568) (xy 409.256345 -399.97147)
			(xy 409.298631 -399.943844) (xy 409.344887 -399.923554) (xy 409.393852 -399.911154) (xy 409.44419 -399.906983)
			(xy 409.494528 -399.911154) (xy 409.543493 -399.923554) (xy 409.589749 -399.943844) (xy 409.632035 -399.97147)
			(xy 409.669197 -400.00568) (xy 409.700221 -400.04554) (xy 409.724262 -400.089963) (xy 409.740663 -400.137737)
			(xy 409.748976 -400.187559) (xy 409.749498 -400.212814) (xy 409.74903 -400.237187) (xy 409.74127 -400.285311)
			(xy 409.725949 -400.331587) (xy 409.703459 -400.374834) (xy 409.6893 -400.394678) (xy 409.683712 -400.402552)
			(xy 409.678632 -400.420332) (xy 409.687014 -400.506946) (xy 409.695142 -400.52371) (xy 409.702254 -400.53006)
			(xy 409.721389 -400.548193) (xy 409.754976 -400.588824) (xy 409.782648 -400.633694) (xy 409.803875 -400.681948)
			(xy 409.818253 -400.732665) (xy 409.825509 -400.78488) (xy 409.825952 -400.811238) (xy 409.825952 -401.674838)
			(xy 410.262832 -401.674838) (xy 410.262832 -400.811238) (xy 410.263302 -400.784894) (xy 410.270549 -400.732705)
			(xy 410.284897 -400.682007) (xy 410.306074 -400.633761) (xy 410.333678 -400.588882) (xy 410.367187 -400.548221)
			(xy 410.386276 -400.53006) (xy 410.393388 -400.52371) (xy 410.401516 -400.506946) (xy 410.409898 -400.420332)
			(xy 410.404818 -400.402552) (xy 410.39923 -400.394678) (xy 410.385077 -400.374833) (xy 410.362621 -400.331573)
			(xy 410.34731 -400.2853) (xy 410.33953 -400.237184) (xy 410.339032 -400.212814) (xy 410.339554 -400.187559)
			(xy 410.347867 -400.137737) (xy 410.364268 -400.089963) (xy 410.388309 -400.04554) (xy 410.419333 -400.00568)
			(xy 410.456495 -399.97147) (xy 410.498781 -399.943844) (xy 410.545037 -399.923554) (xy 410.594002 -399.911154)
			(xy 410.64434 -399.906983) (xy 410.694678 -399.911154) (xy 410.743643 -399.923554) (xy 410.789899 -399.943844)
			(xy 410.832185 -399.97147) (xy 410.869347 -400.00568) (xy 410.900371 -400.04554) (xy 410.924412 -400.089963)
			(xy 410.940813 -400.137737) (xy 410.949126 -400.187559) (xy 410.949648 -400.212814) (xy 410.94917 -400.237186)
			(xy 410.941411 -400.28531) (xy 410.926093 -400.331585) (xy 410.903607 -400.374833) (xy 410.88945 -400.394678)
			(xy 410.883862 -400.402552) (xy 410.878782 -400.420332) (xy 410.887164 -400.506946) (xy 410.895292 -400.52371)
			(xy 410.902404 -400.53006) (xy 410.921498 -400.548219) (xy 410.955022 -400.588873) (xy 410.982637 -400.633749)
			(xy 411.00382 -400.681997) (xy 411.018168 -400.732698) (xy 411.025408 -400.784892) (xy 411.025848 -400.811238)
			(xy 411.025848 -401.674838) (xy 411.462728 -401.674838) (xy 411.462728 -400.811238) (xy 411.463167 -400.784892)
			(xy 411.470416 -400.732701) (xy 411.484768 -400.682002) (xy 411.505951 -400.633755) (xy 411.533562 -400.588877)
			(xy 411.567078 -400.548219) (xy 411.586172 -400.53006) (xy 411.593284 -400.52371) (xy 411.601412 -400.506946)
			(xy 411.609794 -400.420332) (xy 411.604714 -400.402552) (xy 411.599126 -400.394678) (xy 411.584973 -400.374833)
			(xy 411.562517 -400.331574) (xy 411.547205 -400.2853) (xy 411.539426 -400.237184) (xy 411.538928 -400.212814)
			(xy 411.53945 -400.187559) (xy 411.547763 -400.137737) (xy 411.564164 -400.089963) (xy 411.588205 -400.04554)
			(xy 411.619229 -400.00568) (xy 411.656391 -399.97147) (xy 411.698677 -399.943844) (xy 411.744933 -399.923554)
			(xy 411.793898 -399.911154) (xy 411.844236 -399.906983) (xy 411.894574 -399.911154) (xy 411.943539 -399.923554)
			(xy 411.989795 -399.943844) (xy 412.032081 -399.97147) (xy 412.069243 -400.00568) (xy 412.100267 -400.04554)
			(xy 412.124308 -400.089963) (xy 412.140709 -400.137737) (xy 412.149022 -400.187559) (xy 412.149544 -400.212814)
			(xy 412.149067 -400.237186) (xy 412.141308 -400.28531) (xy 412.12599 -400.331585) (xy 412.103503 -400.374833)
			(xy 412.089346 -400.394678) (xy 412.083758 -400.402552) (xy 412.078678 -400.420332) (xy 412.08706 -400.506946)
			(xy 412.095188 -400.52371) (xy 412.1023 -400.53006) (xy 412.121413 -400.5482) (xy 412.154931 -400.58886)
			(xy 412.182542 -400.633741) (xy 412.203721 -400.681992) (xy 412.218066 -400.732696) (xy 412.225304 -400.784891)
			(xy 412.225744 -400.811238) (xy 412.225744 -401.674838) (xy 412.662624 -401.674838) (xy 412.662624 -400.811238)
			(xy 412.663058 -400.784911) (xy 412.670308 -400.732757) (xy 412.684662 -400.682096) (xy 412.705846 -400.633891)
			(xy 412.733459 -400.589057) (xy 412.766976 -400.548447) (xy 412.786068 -400.530314) (xy 412.79318 -400.52371)
			(xy 412.801562 -400.5072) (xy 412.80969 -400.420332) (xy 412.80461 -400.402552) (xy 412.799022 -400.394932)
			(xy 412.784869 -400.375048) (xy 412.76238 -400.331735) (xy 412.747062 -400.285398) (xy 412.739302 -400.237216)
			(xy 412.738824 -400.212814) (xy 412.739346 -400.187559) (xy 412.747659 -400.137737) (xy 412.76406 -400.089963)
			(xy 412.788101 -400.04554) (xy 412.819125 -400.00568) (xy 412.856287 -399.97147) (xy 412.898573 -399.943844)
			(xy 412.944829 -399.923554) (xy 412.993794 -399.911154) (xy 413.044132 -399.906983) (xy 413.09447 -399.911154)
			(xy 413.143435 -399.923554) (xy 413.189691 -399.943844) (xy 413.231977 -399.97147) (xy 413.269139 -400.00568)
			(xy 413.300163 -400.04554) (xy 413.324204 -400.089963) (xy 413.340605 -400.137737) (xy 413.348918 -400.187559)
			(xy 413.34944 -400.212814) (xy 413.348944 -400.237172) (xy 413.341232 -400.285275) (xy 413.325988 -400.331545)
			(xy 413.303599 -400.374812) (xy 413.289496 -400.394678) (xy 413.283654 -400.402298) (xy 413.278828 -400.420078)
			(xy 413.286956 -400.506946) (xy 413.295338 -400.523456) (xy 413.30245 -400.53006) (xy 413.321584 -400.548194)
			(xy 413.355172 -400.588825) (xy 413.382843 -400.633694) (xy 413.404071 -400.681948) (xy 413.418449 -400.732665)
			(xy 413.425705 -400.78488) (xy 413.426148 -400.811238) (xy 413.426148 -401.674838) (xy 413.86252 -401.674838)
			(xy 413.86252 -400.811238) (xy 413.863006 -400.784883) (xy 413.870269 -400.732675) (xy 413.884647 -400.681963)
			(xy 413.905867 -400.633712) (xy 413.933526 -400.588841) (xy 413.967096 -400.548203) (xy 413.986218 -400.53006)
			(xy 413.99333 -400.52371) (xy 414.001458 -400.506946) (xy 414.00984 -400.420332) (xy 414.00476 -400.402552)
			(xy 413.999172 -400.394678) (xy 413.985024 -400.374829) (xy 413.962566 -400.331572) (xy 413.947253 -400.285299)
			(xy 413.939472 -400.237184) (xy 413.938974 -400.212814) (xy 413.939496 -400.187559) (xy 413.947809 -400.137737)
			(xy 413.96421 -400.089963) (xy 413.988251 -400.04554) (xy 414.019275 -400.00568) (xy 414.056437 -399.97147)
			(xy 414.098723 -399.943844) (xy 414.144979 -399.923554) (xy 414.193944 -399.911154) (xy 414.244282 -399.906983)
			(xy 414.29462 -399.911154) (xy 414.343585 -399.923554) (xy 414.389841 -399.943844) (xy 414.432127 -399.97147)
			(xy 414.469289 -400.00568) (xy 414.500313 -400.04554) (xy 414.524354 -400.089963) (xy 414.540755 -400.137737)
			(xy 414.549068 -400.187559) (xy 414.54959 -400.212814) (xy 414.549123 -400.237187) (xy 414.541363 -400.285311)
			(xy 414.526042 -400.331587) (xy 414.503552 -400.374834) (xy 414.489392 -400.394678) (xy 414.483804 -400.402552)
			(xy 414.478724 -400.420332) (xy 414.487106 -400.506946) (xy 414.495234 -400.52371) (xy 414.502346 -400.53006)
			(xy 414.521479 -400.548195) (xy 414.555067 -400.588825) (xy 414.582739 -400.633695) (xy 414.603967 -400.681948)
			(xy 414.618345 -400.732665) (xy 414.625601 -400.78488) (xy 414.626044 -400.811238) (xy 414.626044 -401.674838)
			(xy 415.062924 -401.674838) (xy 415.062924 -400.811238) (xy 415.063348 -400.784921) (xy 415.070573 -400.732785)
			(xy 415.084891 -400.682136) (xy 415.106031 -400.633934) (xy 415.133592 -400.589093) (xy 415.167051 -400.548463)
			(xy 415.186114 -400.530314) (xy 415.193226 -400.52371) (xy 415.201608 -400.5072) (xy 415.209736 -400.420332)
			(xy 415.204656 -400.402552) (xy 415.199068 -400.394932) (xy 415.184908 -400.375053) (xy 415.162423 -400.331737)
			(xy 415.147106 -400.285399) (xy 415.139348 -400.237216) (xy 415.13887 -400.212814) (xy 415.139392 -400.187559)
			(xy 415.147705 -400.137737) (xy 415.164106 -400.089963) (xy 415.188147 -400.04554) (xy 415.219171 -400.00568)
			(xy 415.256333 -399.97147) (xy 415.298619 -399.943844) (xy 415.344875 -399.923554) (xy 415.39384 -399.911154)
			(xy 415.444178 -399.906983) (xy 415.494516 -399.911154) (xy 415.543481 -399.923554) (xy 415.589737 -399.943844)
			(xy 415.632023 -399.97147) (xy 415.669185 -400.00568) (xy 415.700209 -400.04554) (xy 415.72425 -400.089963)
			(xy 415.740651 -400.137737) (xy 415.748964 -400.187559) (xy 415.749486 -400.212814) (xy 415.749 -400.237173)
			(xy 415.741286 -400.285276) (xy 415.72604 -400.331547) (xy 415.703647 -400.374813) (xy 415.689542 -400.394678)
			(xy 415.6837 -400.402298) (xy 415.678874 -400.420078) (xy 415.687002 -400.506946) (xy 415.695384 -400.523456)
			(xy 415.702496 -400.53006) (xy 415.721608 -400.548201) (xy 415.755127 -400.58886) (xy 415.782738 -400.633741)
			(xy 415.803917 -400.681992) (xy 415.818262 -400.732696) (xy 415.8255 -400.784891) (xy 415.82594 -400.811238)
			(xy 415.82594 -401.674838) (xy 416.26282 -401.674838) (xy 416.26282 -400.811238) (xy 416.263262 -400.784892)
			(xy 416.27051 -400.732702) (xy 416.284862 -400.682002) (xy 416.306044 -400.633756) (xy 416.333655 -400.588877)
			(xy 416.367171 -400.548219) (xy 416.386264 -400.53006) (xy 416.393376 -400.52371) (xy 416.401504 -400.506946)
			(xy 416.409886 -400.420332) (xy 416.404806 -400.402552) (xy 416.399218 -400.394678) (xy 416.385064 -400.374834)
			(xy 416.362608 -400.331574) (xy 416.347297 -400.2853) (xy 416.339518 -400.237184) (xy 416.33902 -400.212814)
			(xy 416.339542 -400.187559) (xy 416.347855 -400.137737) (xy 416.364256 -400.089963) (xy 416.388297 -400.04554)
			(xy 416.419321 -400.00568) (xy 416.456483 -399.97147) (xy 416.498769 -399.943844) (xy 416.545025 -399.923554)
			(xy 416.59399 -399.911154) (xy 416.644328 -399.906983) (xy 416.694666 -399.911154) (xy 416.743631 -399.923554)
			(xy 416.789887 -399.943844) (xy 416.832173 -399.97147) (xy 416.869335 -400.00568) (xy 416.900359 -400.04554)
			(xy 416.9244 -400.089963) (xy 416.940801 -400.137737) (xy 416.949114 -400.187559) (xy 416.949636 -400.212814)
			(xy 416.94916 -400.237186) (xy 416.941401 -400.28531) (xy 416.926083 -400.331585) (xy 416.903596 -400.374833)
			(xy 416.889438 -400.394678) (xy 416.88385 -400.402552) (xy 416.87877 -400.420332) (xy 416.887152 -400.506946)
			(xy 416.89528 -400.52371) (xy 416.902392 -400.53006) (xy 416.921503 -400.548201) (xy 416.955022 -400.588861)
			(xy 416.982633 -400.633742) (xy 417.003813 -400.681992) (xy 417.018158 -400.732696) (xy 417.025396 -400.784891)
			(xy 417.025836 -400.811238) (xy 417.025836 -401.674838) (xy 417.462716 -401.674838) (xy 417.462716 -400.811238)
			(xy 417.463159 -400.784892) (xy 417.470408 -400.732702) (xy 417.484759 -400.682002) (xy 417.505941 -400.633756)
			(xy 417.533552 -400.588878) (xy 417.567067 -400.548219) (xy 417.58616 -400.53006) (xy 417.593272 -400.52371)
			(xy 417.6014 -400.506946) (xy 417.609782 -400.420332) (xy 417.604702 -400.402552) (xy 417.599114 -400.394678)
			(xy 417.584959 -400.374834) (xy 417.562504 -400.331574) (xy 417.547193 -400.2853) (xy 417.539414 -400.237184)
			(xy 417.538916 -400.212814) (xy 417.539438 -400.187559) (xy 417.547751 -400.137737) (xy 417.564152 -400.089963)
			(xy 417.588193 -400.04554) (xy 417.619217 -400.00568) (xy 417.656379 -399.97147) (xy 417.698665 -399.943844)
			(xy 417.744921 -399.923554) (xy 417.793886 -399.911154) (xy 417.844224 -399.906983) (xy 417.894562 -399.911154)
			(xy 417.943527 -399.923554) (xy 417.989783 -399.943844) (xy 418.032069 -399.97147) (xy 418.069231 -400.00568)
			(xy 418.100255 -400.04554) (xy 418.124296 -400.089963) (xy 418.140697 -400.137737) (xy 418.14901 -400.187559)
			(xy 418.149532 -400.212814) (xy 418.149057 -400.237186) (xy 418.141298 -400.28531) (xy 418.125979 -400.331585)
			(xy 418.103492 -400.374833) (xy 418.089334 -400.394678) (xy 418.083746 -400.402552) (xy 418.078666 -400.420332)
			(xy 418.087048 -400.506946) (xy 418.095176 -400.52371) (xy 418.102288 -400.53006) (xy 418.121398 -400.548202)
			(xy 418.154917 -400.588861) (xy 418.182529 -400.633742) (xy 418.203708 -400.681992) (xy 418.218054 -400.732696)
			(xy 418.225292 -400.784891) (xy 418.225732 -400.811238) (xy 418.225732 -401.674838) (xy 418.662612 -401.674838)
			(xy 418.662612 -400.811238) (xy 418.663056 -400.784892) (xy 418.670305 -400.732702) (xy 418.684656 -400.682003)
			(xy 418.705838 -400.633756) (xy 418.733448 -400.588878) (xy 418.766963 -400.548219) (xy 418.786056 -400.53006)
			(xy 418.793168 -400.52371) (xy 418.801296 -400.506946) (xy 418.809678 -400.420332) (xy 418.804598 -400.402552)
			(xy 418.79901 -400.394678) (xy 418.784867 -400.374826) (xy 418.762406 -400.33157) (xy 418.747092 -400.285298)
			(xy 418.739311 -400.237184) (xy 418.738812 -400.212814) (xy 418.739334 -400.187559) (xy 418.747647 -400.137737)
			(xy 418.764048 -400.089963) (xy 418.788089 -400.04554) (xy 418.819113 -400.00568) (xy 418.856275 -399.97147)
			(xy 418.898561 -399.943844) (xy 418.944817 -399.923554) (xy 418.993782 -399.911154) (xy 419.04412 -399.906983)
			(xy 419.094458 -399.911154) (xy 419.143423 -399.923554) (xy 419.189679 -399.943844) (xy 419.231965 -399.97147)
			(xy 419.269127 -400.00568) (xy 419.300151 -400.04554) (xy 419.324192 -400.089963) (xy 419.340593 -400.137737)
			(xy 419.348906 -400.187559) (xy 419.349428 -400.212814) (xy 419.348954 -400.237187) (xy 419.341195 -400.28531)
			(xy 419.325876 -400.331586) (xy 419.303388 -400.374834) (xy 419.28923 -400.394678) (xy 419.283642 -400.402552)
			(xy 419.278562 -400.420332) (xy 419.286944 -400.506946) (xy 419.295072 -400.52371) (xy 419.302184 -400.53006)
			(xy 419.321294 -400.548203) (xy 419.354813 -400.588862) (xy 419.382425 -400.633742) (xy 419.403604 -400.681993)
			(xy 419.41795 -400.732696) (xy 419.425188 -400.784891) (xy 419.425628 -400.811238) (xy 419.425628 -401.674838)
			(xy 419.862508 -401.674838) (xy 419.862508 -400.811238) (xy 419.862966 -400.784881) (xy 419.87023 -400.732671)
			(xy 419.884612 -400.681957) (xy 419.905837 -400.633706) (xy 419.933502 -400.588836) (xy 419.96708 -400.548201)
			(xy 419.986206 -400.53006) (xy 419.993318 -400.52371) (xy 420.001446 -400.506946) (xy 420.009828 -400.420332)
			(xy 420.004748 -400.402552) (xy 419.99916 -400.394678) (xy 419.985011 -400.37483) (xy 419.962553 -400.331572)
			(xy 419.94724 -400.285299) (xy 419.93946 -400.237184) (xy 419.938962 -400.212814) (xy 419.939484 -400.187559)
			(xy 419.947797 -400.137737) (xy 419.964198 -400.089963) (xy 419.988239 -400.04554) (xy 420.019263 -400.00568)
			(xy 420.056425 -399.97147) (xy 420.098711 -399.943844) (xy 420.144967 -399.923554) (xy 420.193932 -399.911154)
			(xy 420.24427 -399.906983) (xy 420.294608 -399.911154) (xy 420.343573 -399.923554) (xy 420.389829 -399.943844)
			(xy 420.432115 -399.97147) (xy 420.469277 -400.00568) (xy 420.500301 -400.04554) (xy 420.524342 -400.089963)
			(xy 420.540743 -400.137737) (xy 420.549056 -400.187559) (xy 420.549578 -400.212814) (xy 420.549114 -400.237187)
			(xy 420.541353 -400.285311) (xy 420.526032 -400.331587) (xy 420.50354 -400.374834) (xy 420.48938 -400.394678)
			(xy 420.483792 -400.402552) (xy 420.478712 -400.420332) (xy 420.487094 -400.506946) (xy 420.495222 -400.52371)
			(xy 420.502334 -400.53006) (xy 420.521465 -400.548197) (xy 420.555054 -400.588827) (xy 420.582726 -400.633696)
			(xy 420.603954 -400.681949) (xy 420.618333 -400.732666) (xy 420.625589 -400.78488) (xy 420.626032 -400.811238)
			(xy 420.626032 -401.674838) (xy 421.062404 -401.674838) (xy 421.062404 -400.811238) (xy 421.062863 -400.784881)
			(xy 421.070127 -400.732671) (xy 421.084509 -400.681958) (xy 421.105734 -400.633706) (xy 421.133399 -400.588836)
			(xy 421.166977 -400.548201) (xy 421.186102 -400.53006) (xy 421.193214 -400.52371) (xy 421.201342 -400.506946)
			(xy 421.209724 -400.420332) (xy 421.204644 -400.402552) (xy 421.199056 -400.394678) (xy 421.184906 -400.374831)
			(xy 421.162449 -400.331572) (xy 421.147136 -400.2853) (xy 421.139356 -400.237184) (xy 421.138858 -400.212814)
			(xy 421.13938 -400.187559) (xy 421.147693 -400.137737) (xy 421.164094 -400.089963) (xy 421.188135 -400.04554)
			(xy 421.219159 -400.00568) (xy 421.256321 -399.97147) (xy 421.298607 -399.943844) (xy 421.344863 -399.923554)
			(xy 421.393828 -399.911154) (xy 421.444166 -399.906983) (xy 421.494504 -399.911154) (xy 421.543469 -399.923554)
			(xy 421.589725 -399.943844) (xy 421.632011 -399.97147) (xy 421.669173 -400.00568) (xy 421.700197 -400.04554)
			(xy 421.724238 -400.089963) (xy 421.740639 -400.137737) (xy 421.748952 -400.187559) (xy 421.749474 -400.212814)
			(xy 421.748991 -400.237186) (xy 421.741233 -400.285309) (xy 421.725916 -400.331584) (xy 421.703432 -400.374833)
			(xy 421.689276 -400.394678) (xy 421.683688 -400.402552) (xy 421.678608 -400.420332) (xy 421.68699 -400.506946)
			(xy 421.695118 -400.52371) (xy 421.70223 -400.53006) (xy 421.72136 -400.548198) (xy 421.754949 -400.588827)
			(xy 421.782622 -400.633696) (xy 421.80385 -400.681949) (xy 421.818229 -400.732666) (xy 421.825485 -400.78488)
			(xy 421.825928 -400.811238) (xy 421.825928 -401.461986) (xy 421.826311 -401.470962) (xy 421.832546 -401.487798)
			(xy 421.844191 -401.501464) (xy 421.851836 -401.506182) (xy 421.941244 -401.55622) (xy 421.96893 -401.555712)
			(xy 421.980614 -401.548346) (xy 422.003289 -401.534927) (xy 422.051537 -401.513754) (xy 422.102234 -401.499406)
			(xy 422.154422 -401.492154) (xy 422.180766 -401.491704) (xy 422.208021 -401.492141) (xy 422.261978 -401.499894)
			(xy 422.314281 -401.515247) (xy 422.363867 -401.537889) (xy 422.409726 -401.567357) (xy 422.450924 -401.603052)
			(xy 422.486623 -401.644247) (xy 422.516095 -401.690103) (xy 422.538741 -401.739687) (xy 422.554099 -401.791989)
			(xy 422.561857 -401.845945) (xy 422.561857 -401.900455) (xy 422.554099 -401.954411) (xy 422.538741 -402.006713)
			(xy 422.516095 -402.056297) (xy 422.486623 -402.102153) (xy 422.450924 -402.143348) (xy 422.409726 -402.179043)
			(xy 422.363867 -402.208511) (xy 422.314281 -402.231153) (xy 422.261978 -402.246506) (xy 422.208021 -402.254259)
			(xy 422.180766 -402.25472) (xy 422.153811 -402.25425) (xy 422.100439 -402.246644) (xy 422.048669 -402.231603)
			(xy 421.999531 -402.209425) (xy 421.954003 -402.180553) (xy 421.912992 -402.14556) (xy 421.877313 -402.105144)
			(xy 421.847678 -402.060109) (xy 421.824676 -402.011352) (xy 421.816276 -401.985734) (xy 421.813444 -401.977653)
			(xy 421.803283 -401.963883) (xy 421.789148 -401.954237) (xy 421.78097 -401.951698) (xy 421.72255 -401.93595)
			(xy 421.712898 -401.945856) (xy 421.706294 -401.95246) (xy 421.698674 -401.969224) (xy 421.69334 -402.05533)
			(xy 421.698674 -402.07311) (xy 421.704516 -402.080476) (xy 421.721017 -402.102469) (xy 421.747294 -402.15076)
			(xy 421.765228 -402.20273) (xy 421.774325 -402.256949) (xy 421.774874 -402.284438) (xy 421.774364 -402.310425)
			(xy 421.766234 -402.36176) (xy 421.750173 -402.41119) (xy 421.726577 -402.4575) (xy 421.696027 -402.499548)
			(xy 421.659276 -402.536299) (xy 421.617228 -402.566849) (xy 421.570918 -402.590445) (xy 421.521488 -402.606506)
			(xy 421.470153 -402.614636) (xy 421.418179 -402.614636) (xy 421.366844 -402.606506) (xy 421.317414 -402.590445)
			(xy 421.271104 -402.566849) (xy 421.229056 -402.536299) (xy 421.192305 -402.499548) (xy 421.161755 -402.4575)
			(xy 421.138159 -402.41119) (xy 421.122098 -402.36176) (xy 421.113968 -402.310425) (xy 421.113458 -402.284438)
			(xy 421.11402 -402.256948) (xy 421.123094 -402.202723) (xy 421.141017 -402.150747) (xy 421.167293 -402.102453)
			(xy 421.183816 -402.080476) (xy 421.189658 -402.07311) (xy 421.194992 -402.05533) (xy 421.189658 -401.969224)
			(xy 421.182038 -401.95246) (xy 421.175434 -401.945856) (xy 421.154383 -401.924248) (xy 421.11874 -401.875581)
			(xy 421.091203 -401.82191) (xy 421.072457 -401.764573) (xy 421.062971 -401.705) (xy 421.062404 -401.674838)
			(xy 420.626032 -401.674838) (xy 420.625607 -401.701012) (xy 420.61841 -401.752864) (xy 420.604197 -401.803247)
			(xy 420.583236 -401.851216) (xy 420.555918 -401.895872) (xy 420.522757 -401.936378) (xy 420.503858 -401.954492)
			(xy 420.496492 -401.96135) (xy 420.488364 -401.978876) (xy 420.48303 -402.069046) (xy 420.489126 -402.087334)
			(xy 420.49573 -402.094954) (xy 420.510635 -402.112995) (xy 420.535697 -402.152514) (xy 420.554944 -402.195169)
			(xy 420.56799 -402.240109) (xy 420.574576 -402.28644) (xy 420.574978 -402.309838) (xy 420.574468 -402.335825)
			(xy 420.566338 -402.38716) (xy 420.550277 -402.43659) (xy 420.526681 -402.4829) (xy 420.496131 -402.524948)
			(xy 420.45938 -402.561699) (xy 420.417332 -402.592249) (xy 420.371022 -402.615845) (xy 420.321592 -402.631906)
			(xy 420.270257 -402.640036) (xy 420.218283 -402.640036) (xy 420.166948 -402.631906) (xy 420.117518 -402.615845)
			(xy 420.071208 -402.592249) (xy 420.02916 -402.561699) (xy 419.992409 -402.524948) (xy 419.961859 -402.4829)
			(xy 419.938263 -402.43659) (xy 419.922202 -402.38716) (xy 419.914072 -402.335825) (xy 419.913562 -402.309838)
			(xy 419.913984 -402.286442) (xy 419.92057 -402.240114) (xy 419.933617 -402.195177) (xy 419.952864 -402.152526)
			(xy 419.977928 -402.113012) (xy 419.99281 -402.094954) (xy 419.999414 -402.087334) (xy 420.00551 -402.069046)
			(xy 420.000176 -401.978876) (xy 419.992048 -401.96135) (xy 419.984682 -401.954492) (xy 419.965782 -401.936379)
			(xy 419.93262 -401.895875) (xy 419.905304 -401.851219) (xy 419.884347 -401.803249) (xy 419.870142 -401.752865)
			(xy 419.862956 -401.701012) (xy 419.862508 -401.674838) (xy 419.425628 -401.674838) (xy 419.425147 -401.701)
			(xy 419.417998 -401.752834) (xy 419.403839 -401.803207) (xy 419.382935 -401.851175) (xy 419.355677 -401.895839)
			(xy 419.322577 -401.936364) (xy 419.303708 -401.954492) (xy 419.296342 -401.96135) (xy 419.288214 -401.978876)
			(xy 419.28288 -402.069046) (xy 419.288976 -402.087334) (xy 419.29558 -402.094954) (xy 419.310477 -402.113001)
			(xy 419.335542 -402.152517) (xy 419.354791 -402.195171) (xy 419.367839 -402.24011) (xy 419.374426 -402.28644)
			(xy 419.374828 -402.309838) (xy 419.374318 -402.335825) (xy 419.366188 -402.38716) (xy 419.350127 -402.43659)
			(xy 419.326531 -402.4829) (xy 419.295981 -402.524948) (xy 419.25923 -402.561699) (xy 419.217182 -402.592249)
			(xy 419.170872 -402.615845) (xy 419.121442 -402.631906) (xy 419.070107 -402.640036) (xy 419.018133 -402.640036)
			(xy 418.966798 -402.631906) (xy 418.917368 -402.615845) (xy 418.871058 -402.592249) (xy 418.82901 -402.561699)
			(xy 418.792259 -402.524948) (xy 418.761709 -402.4829) (xy 418.738113 -402.43659) (xy 418.722052 -402.38716)
			(xy 418.713922 -402.335825) (xy 418.713412 -402.309838) (xy 418.713846 -402.286442) (xy 418.720431 -402.240116)
			(xy 418.733476 -402.195179) (xy 418.75272 -402.152528) (xy 418.77778 -402.113013) (xy 418.79266 -402.094954)
			(xy 418.799264 -402.087334) (xy 418.80536 -402.069046) (xy 418.800026 -401.978876) (xy 418.791898 -401.96135)
			(xy 418.784532 -401.954492) (xy 418.765644 -401.93638) (xy 418.732525 -401.895861) (xy 418.705254 -401.851197)
			(xy 418.684342 -401.803225) (xy 418.670182 -401.752846) (xy 418.663039 -401.701004) (xy 418.662612 -401.674838)
			(xy 418.225732 -401.674838) (xy 418.225199 -401.703743) (xy 418.216494 -401.760893) (xy 418.199273 -401.816077)
			(xy 418.17393 -401.868035) (xy 418.141044 -401.915579) (xy 418.121592 -401.936966) (xy 418.115496 -401.94357)
			(xy 418.108384 -401.959572) (xy 418.102796 -402.041868) (xy 418.107622 -402.058886) (xy 418.112702 -402.065998)
			(xy 418.127345 -402.087224) (xy 418.150595 -402.133247) (xy 418.166419 -402.182321) (xy 418.174433 -402.233257)
			(xy 418.174932 -402.259038) (xy 418.174422 -402.285025) (xy 418.166292 -402.33636) (xy 418.150231 -402.38579)
			(xy 418.126635 -402.4321) (xy 418.096085 -402.474148) (xy 418.059334 -402.510899) (xy 418.017286 -402.541449)
			(xy 417.970976 -402.565045) (xy 417.921546 -402.581106) (xy 417.870211 -402.589236) (xy 417.818237 -402.589236)
			(xy 417.766902 -402.581106) (xy 417.717472 -402.565045) (xy 417.671162 -402.541449) (xy 417.629114 -402.510899)
			(xy 417.592363 -402.474148) (xy 417.561813 -402.4321) (xy 417.538217 -402.38579) (xy 417.522156 -402.33636)
			(xy 417.514026 -402.285025) (xy 417.513516 -402.259038) (xy 417.513986 -402.233254) (xy 417.521994 -402.182313)
			(xy 417.537821 -402.133234) (xy 417.561083 -402.087212) (xy 417.575746 -402.065998) (xy 417.580826 -402.058886)
			(xy 417.585652 -402.041868) (xy 417.580064 -401.959572) (xy 417.572952 -401.94357) (xy 417.566856 -401.936966)
			(xy 417.547366 -401.91561) (xy 417.51446 -401.86807) (xy 417.489111 -401.816106) (xy 417.471901 -401.760909)
			(xy 417.463224 -401.703747) (xy 417.462716 -401.674838) (xy 417.025836 -401.674838) (xy 417.025384 -401.701002)
			(xy 417.018233 -401.752838) (xy 417.00407 -401.803212) (xy 416.983161 -401.851181) (xy 416.955897 -401.895844)
			(xy 416.922789 -401.936366) (xy 416.903916 -401.954492) (xy 416.89655 -401.96135) (xy 416.888422 -401.978876)
			(xy 416.883088 -402.069046) (xy 416.889184 -402.087334) (xy 416.895788 -402.094954) (xy 416.910686 -402.113)
			(xy 416.935751 -402.152517) (xy 416.955 -402.19517) (xy 416.968047 -402.24011) (xy 416.974634 -402.28644)
			(xy 416.975036 -402.309838) (xy 416.974526 -402.335825) (xy 416.966396 -402.38716) (xy 416.950335 -402.43659)
			(xy 416.926739 -402.4829) (xy 416.896189 -402.524948) (xy 416.859438 -402.561699) (xy 416.81739 -402.592249)
			(xy 416.77108 -402.615845) (xy 416.72165 -402.631906) (xy 416.670315 -402.640036) (xy 416.618341 -402.640036)
			(xy 416.567006 -402.631906) (xy 416.517576 -402.615845) (xy 416.471266 -402.592249) (xy 416.429218 -402.561699)
			(xy 416.392467 -402.524948) (xy 416.361917 -402.4829) (xy 416.338321 -402.43659) (xy 416.32226 -402.38716)
			(xy 416.31413 -402.335825) (xy 416.31362 -402.309838) (xy 416.314052 -402.286442) (xy 416.320637 -402.240116)
			(xy 416.333683 -402.195179) (xy 416.352927 -402.152528) (xy 416.377987 -402.113012) (xy 416.392868 -402.094954)
			(xy 416.399472 -402.087334) (xy 416.405568 -402.069046) (xy 416.400234 -401.978876) (xy 416.392106 -401.96135)
			(xy 416.38474 -401.954492) (xy 416.365853 -401.936378) (xy 416.332734 -401.89586) (xy 416.305462 -401.851196)
			(xy 416.28455 -401.803225) (xy 416.27039 -401.752846) (xy 416.263247 -401.701004) (xy 416.26282 -401.674838)
			(xy 415.82594 -401.674838) (xy 415.825486 -401.701002) (xy 415.818335 -401.752838) (xy 415.804173 -401.803212)
			(xy 415.783264 -401.85118) (xy 415.756 -401.895844) (xy 415.722893 -401.936366) (xy 415.70402 -401.954492)
			(xy 415.696654 -401.96135) (xy 415.688526 -401.978876) (xy 415.683192 -402.069046) (xy 415.689288 -402.087334)
			(xy 415.695892 -402.094954) (xy 415.710791 -402.112999) (xy 415.735856 -402.152516) (xy 415.755104 -402.19517)
			(xy 415.768151 -402.24011) (xy 415.774738 -402.28644) (xy 415.77514 -402.309838) (xy 415.77463 -402.335825)
			(xy 415.7665 -402.38716) (xy 415.750439 -402.43659) (xy 415.726843 -402.4829) (xy 415.696293 -402.524948)
			(xy 415.659542 -402.561699) (xy 415.617494 -402.592249) (xy 415.571184 -402.615845) (xy 415.521754 -402.631906)
			(xy 415.470419 -402.640036) (xy 415.418445 -402.640036) (xy 415.36711 -402.631906) (xy 415.31768 -402.615845)
			(xy 415.27137 -402.592249) (xy 415.229322 -402.561699) (xy 415.192571 -402.524948) (xy 415.162021 -402.4829)
			(xy 415.138425 -402.43659) (xy 415.122364 -402.38716) (xy 415.114234 -402.335825) (xy 415.113724 -402.309838)
			(xy 415.114155 -402.286442) (xy 415.120741 -402.240116) (xy 415.133786 -402.195179) (xy 415.153031 -402.152528)
			(xy 415.178091 -402.113012) (xy 415.192972 -402.094954) (xy 415.199576 -402.087334) (xy 415.205672 -402.069046)
			(xy 415.200338 -401.978876) (xy 415.19221 -401.96135) (xy 415.184844 -401.954492) (xy 415.165958 -401.936377)
			(xy 415.132838 -401.89586) (xy 415.105567 -401.851196) (xy 415.084654 -401.803225) (xy 415.070494 -401.752845)
			(xy 415.063351 -401.701004) (xy 415.062924 -401.674838) (xy 414.626044 -401.674838) (xy 414.625615 -401.701012)
			(xy 414.618418 -401.752864) (xy 414.604206 -401.803246) (xy 414.583246 -401.851215) (xy 414.555929 -401.895871)
			(xy 414.522768 -401.936378) (xy 414.50387 -401.954492) (xy 414.496504 -401.96135) (xy 414.488376 -401.978876)
			(xy 414.483042 -402.069046) (xy 414.489138 -402.087334) (xy 414.495742 -402.094954) (xy 414.510648 -402.112993)
			(xy 414.53571 -402.152513) (xy 414.554956 -402.195168) (xy 414.568002 -402.240109) (xy 414.574588 -402.28644)
			(xy 414.57499 -402.309838) (xy 414.57448 -402.335825) (xy 414.56635 -402.38716) (xy 414.550289 -402.43659)
			(xy 414.526693 -402.4829) (xy 414.496143 -402.524948) (xy 414.459392 -402.561699) (xy 414.417344 -402.592249)
			(xy 414.371034 -402.615845) (xy 414.321604 -402.631906) (xy 414.270269 -402.640036) (xy 414.218295 -402.640036)
			(xy 414.16696 -402.631906) (xy 414.11753 -402.615845) (xy 414.07122 -402.592249) (xy 414.029172 -402.561699)
			(xy 413.992421 -402.524948) (xy 413.961871 -402.4829) (xy 413.938275 -402.43659) (xy 413.922214 -402.38716)
			(xy 413.914084 -402.335825) (xy 413.913574 -402.309838) (xy 413.913993 -402.286441) (xy 413.92058 -402.240114)
			(xy 413.933627 -402.195177) (xy 413.952875 -402.152526) (xy 413.977939 -402.113011) (xy 413.992822 -402.094954)
			(xy 413.999426 -402.087334) (xy 414.005522 -402.069046) (xy 414.000188 -401.978876) (xy 413.99206 -401.96135)
			(xy 413.984694 -401.954492) (xy 413.965797 -401.936377) (xy 413.932633 -401.895873) (xy 413.905317 -401.851218)
			(xy 413.884359 -401.803248) (xy 413.870154 -401.752864) (xy 413.862968 -401.701012) (xy 413.86252 -401.674838)
			(xy 413.426148 -401.674838) (xy 413.425718 -401.701012) (xy 413.418521 -401.752863) (xy 413.404309 -401.803246)
			(xy 413.383349 -401.851215) (xy 413.356032 -401.895871) (xy 413.322872 -401.936377) (xy 413.303974 -401.954492)
			(xy 413.296608 -401.96135) (xy 413.28848 -401.978876) (xy 413.283146 -402.069046) (xy 413.289242 -402.087334)
			(xy 413.295846 -402.094954) (xy 413.310753 -402.112993) (xy 413.335815 -402.152512) (xy 413.35506 -402.195168)
			(xy 413.368106 -402.240109) (xy 413.374692 -402.28644) (xy 413.375094 -402.309838) (xy 413.374584 -402.335825)
			(xy 413.366454 -402.38716) (xy 413.350393 -402.43659) (xy 413.326797 -402.4829) (xy 413.296247 -402.524948)
			(xy 413.259496 -402.561699) (xy 413.217448 -402.592249) (xy 413.171138 -402.615845) (xy 413.121708 -402.631906)
			(xy 413.070373 -402.640036) (xy 413.018399 -402.640036) (xy 412.967064 -402.631906) (xy 412.917634 -402.615845)
			(xy 412.871324 -402.592249) (xy 412.829276 -402.561699) (xy 412.792525 -402.524948) (xy 412.761975 -402.4829)
			(xy 412.738379 -402.43659) (xy 412.722318 -402.38716) (xy 412.714188 -402.335825) (xy 412.713678 -402.309838)
			(xy 412.714096 -402.286441) (xy 412.720683 -402.240114) (xy 412.73373 -402.195177) (xy 412.752978 -402.152525)
			(xy 412.778043 -402.113011) (xy 412.792926 -402.094954) (xy 412.79953 -402.087334) (xy 412.805626 -402.069046)
			(xy 412.800292 -401.978876) (xy 412.792164 -401.96135) (xy 412.784798 -401.954492) (xy 412.765901 -401.936376)
			(xy 412.732738 -401.895873) (xy 412.705421 -401.851218) (xy 412.684464 -401.803248) (xy 412.670258 -401.752864)
			(xy 412.663072 -401.701012) (xy 412.662624 -401.674838) (xy 412.225744 -401.674838) (xy 412.225188 -401.704987)
			(xy 412.215732 -401.764539) (xy 412.197029 -401.821862) (xy 412.169545 -401.875532) (xy 412.133963 -401.924212)
			(xy 412.112968 -401.945856) (xy 412.106364 -401.95246) (xy 412.098744 -401.969224) (xy 412.09341 -402.05533)
			(xy 412.098744 -402.07311) (xy 412.104586 -402.080476) (xy 412.121096 -402.102462) (xy 412.147369 -402.150756)
			(xy 412.1653 -402.202728) (xy 412.174396 -402.256949) (xy 412.174944 -402.284438) (xy 412.174434 -402.310425)
			(xy 412.166304 -402.36176) (xy 412.150243 -402.41119) (xy 412.126647 -402.4575) (xy 412.096097 -402.499548)
			(xy 412.059346 -402.536299) (xy 412.017298 -402.566849) (xy 411.970988 -402.590445) (xy 411.921558 -402.606506)
			(xy 411.870223 -402.614636) (xy 411.818249 -402.614636) (xy 411.766914 -402.606506) (xy 411.717484 -402.590445)
			(xy 411.671174 -402.566849) (xy 411.629126 -402.536299) (xy 411.592375 -402.499548) (xy 411.561825 -402.4575)
			(xy 411.538229 -402.41119) (xy 411.522168 -402.36176) (xy 411.514038 -402.310425) (xy 411.513528 -402.284438)
			(xy 411.514075 -402.256947) (xy 411.523152 -402.202721) (xy 411.541078 -402.150744) (xy 411.56736 -402.102451)
			(xy 411.583886 -402.080476) (xy 411.589728 -402.07311) (xy 411.595062 -402.05533) (xy 411.589728 -401.969224)
			(xy 411.582108 -401.95246) (xy 411.575504 -401.945856) (xy 411.554509 -401.92421) (xy 411.518917 -401.875536)
			(xy 411.491428 -401.821867) (xy 411.472726 -401.764542) (xy 411.463278 -401.704988) (xy 411.462728 -401.674838)
			(xy 411.025848 -401.674838) (xy 411.025311 -401.703742) (xy 411.016606 -401.760892) (xy 410.999386 -401.816077)
			(xy 410.974044 -401.868035) (xy 410.941159 -401.915579) (xy 410.921708 -401.936966) (xy 410.915612 -401.94357)
			(xy 410.9085 -401.959572) (xy 410.902912 -402.041868) (xy 410.907738 -402.058886) (xy 410.912818 -402.065998)
			(xy 410.92745 -402.087231) (xy 410.950706 -402.13325) (xy 410.966533 -402.182322) (xy 410.974549 -402.233257)
			(xy 410.975048 -402.259038) (xy 410.974538 -402.285025) (xy 410.966408 -402.33636) (xy 410.950347 -402.38579)
			(xy 410.926751 -402.4321) (xy 410.896201 -402.474148) (xy 410.85945 -402.510899) (xy 410.817402 -402.541449)
			(xy 410.771092 -402.565045) (xy 410.721662 -402.581106) (xy 410.670327 -402.589236) (xy 410.618353 -402.589236)
			(xy 410.567018 -402.581106) (xy 410.517588 -402.565045) (xy 410.471278 -402.541449) (xy 410.42923 -402.510899)
			(xy 410.392479 -402.474148) (xy 410.361929 -402.4321) (xy 410.338333 -402.38579) (xy 410.322272 -402.33636)
			(xy 410.314142 -402.285025) (xy 410.313632 -402.259038) (xy 410.314117 -402.233255) (xy 410.322123 -402.182315)
			(xy 410.337946 -402.133237) (xy 410.361202 -402.087213) (xy 410.375862 -402.065998) (xy 410.380942 -402.058886)
			(xy 410.385768 -402.041868) (xy 410.38018 -401.959572) (xy 410.373068 -401.94357) (xy 410.366972 -401.936966)
			(xy 410.347484 -401.915607) (xy 410.314578 -401.868068) (xy 410.289228 -401.816105) (xy 410.272017 -401.760909)
			(xy 410.26334 -401.703747) (xy 410.262832 -401.674838) (xy 409.825952 -401.674838) (xy 409.82552 -401.701012)
			(xy 409.818324 -401.752863) (xy 409.804112 -401.803246) (xy 409.783152 -401.851215) (xy 409.755836 -401.895871)
			(xy 409.722676 -401.936377) (xy 409.703778 -401.954492) (xy 409.696412 -401.96135) (xy 409.688284 -401.978876)
			(xy 409.68295 -402.069046) (xy 409.689046 -402.087334) (xy 409.69565 -402.094954) (xy 409.710558 -402.112992)
			(xy 409.735619 -402.152512) (xy 409.754865 -402.195168) (xy 409.76791 -402.240109) (xy 409.774496 -402.28644)
			(xy 409.774898 -402.309838) (xy 409.774388 -402.335825) (xy 409.766258 -402.38716) (xy 409.750197 -402.43659)
			(xy 409.726601 -402.4829) (xy 409.696051 -402.524948) (xy 409.6593 -402.561699) (xy 409.617252 -402.592249)
			(xy 409.570942 -402.615845) (xy 409.521512 -402.631906) (xy 409.470177 -402.640036) (xy 409.418203 -402.640036)
			(xy 409.366868 -402.631906) (xy 409.317438 -402.615845) (xy 409.271128 -402.592249) (xy 409.22908 -402.561699)
			(xy 409.192329 -402.524948) (xy 409.161779 -402.4829) (xy 409.138183 -402.43659) (xy 409.122122 -402.38716)
			(xy 409.113992 -402.335825) (xy 409.113482 -402.309838) (xy 409.113923 -402.286442) (xy 409.120508 -402.240117)
			(xy 409.133551 -402.195181) (xy 409.152793 -402.152529) (xy 409.177851 -402.113013) (xy 409.19273 -402.094954)
			(xy 409.199334 -402.087334) (xy 409.20543 -402.069046) (xy 409.200096 -401.978876) (xy 409.191968 -401.96135)
			(xy 409.184602 -401.954492) (xy 409.165706 -401.936375) (xy 409.132543 -401.895872) (xy 409.105226 -401.851217)
			(xy 409.084268 -401.803248) (xy 409.070062 -401.752864) (xy 409.062876 -401.701012) (xy 409.062428 -401.674838)
			(xy 408.626056 -401.674838) (xy 408.625624 -401.701012) (xy 408.618427 -401.752863) (xy 408.604216 -401.803246)
			(xy 408.583256 -401.851215) (xy 408.55594 -401.895871) (xy 408.52278 -401.936378) (xy 408.503882 -401.954492)
			(xy 408.496516 -401.96135) (xy 408.488388 -401.978876) (xy 408.483054 -402.069046) (xy 408.48915 -402.087334)
			(xy 408.495754 -402.094954) (xy 408.510647 -402.113004) (xy 408.535714 -402.152519) (xy 408.554964 -402.195172)
			(xy 408.568013 -402.240111) (xy 408.5746 -402.28644) (xy 408.575002 -402.309838) (xy 408.574492 -402.335825)
			(xy 408.566362 -402.38716) (xy 408.550301 -402.43659) (xy 408.526705 -402.4829) (xy 408.496155 -402.524948)
			(xy 408.459404 -402.561699) (xy 408.417356 -402.592249) (xy 408.371046 -402.615845) (xy 408.321616 -402.631906)
			(xy 408.270281 -402.640036) (xy 408.218307 -402.640036) (xy 408.166972 -402.631906) (xy 408.117542 -402.615845)
			(xy 408.071232 -402.592249) (xy 408.029184 -402.561699) (xy 407.992433 -402.524948) (xy 407.961883 -402.4829)
			(xy 407.938287 -402.43659) (xy 407.922226 -402.38716) (xy 407.914096 -402.335825) (xy 407.913586 -402.309838)
			(xy 407.914026 -402.286442) (xy 407.920611 -402.240117) (xy 407.933654 -402.19518) (xy 407.952897 -402.152529)
			(xy 407.977955 -402.113013) (xy 407.992834 -402.094954) (xy 407.999438 -402.087334) (xy 408.005534 -402.069046)
			(xy 408.0002 -401.978876) (xy 407.992072 -401.96135) (xy 407.984706 -401.954492) (xy 407.965811 -401.936375)
			(xy 407.932647 -401.895872) (xy 407.90533 -401.851217) (xy 407.884372 -401.803247) (xy 407.870166 -401.752864)
			(xy 407.86298 -401.701012) (xy 407.862532 -401.674838) (xy 407.425652 -401.674838) (xy 407.425114 -401.703742)
			(xy 407.416409 -401.760892) (xy 407.399189 -401.816076) (xy 407.373847 -401.868034) (xy 407.340963 -401.915579)
			(xy 407.321512 -401.936966) (xy 407.315416 -401.94357) (xy 407.308304 -401.959572) (xy 407.302716 -402.041868)
			(xy 407.307542 -402.058886) (xy 407.312622 -402.065998) (xy 407.327255 -402.08723) (xy 407.35051 -402.13325)
			(xy 407.366337 -402.182322) (xy 407.374353 -402.233257) (xy 407.374852 -402.259038) (xy 407.374342 -402.285025)
			(xy 407.366212 -402.33636) (xy 407.350151 -402.38579) (xy 407.326555 -402.4321) (xy 407.296005 -402.474148)
			(xy 407.259254 -402.510899) (xy 407.217206 -402.541449) (xy 407.170896 -402.565045) (xy 407.121466 -402.581106)
			(xy 407.070131 -402.589236) (xy 407.018157 -402.589236) (xy 406.966822 -402.581106) (xy 406.917392 -402.565045)
			(xy 406.871082 -402.541449) (xy 406.829034 -402.510899) (xy 406.792283 -402.474148) (xy 406.761733 -402.4321)
			(xy 406.738137 -402.38579) (xy 406.722076 -402.33636) (xy 406.713946 -402.285025) (xy 406.713436 -402.259038)
			(xy 406.71392 -402.233255) (xy 406.721926 -402.182315) (xy 406.737749 -402.133237) (xy 406.761006 -402.087213)
			(xy 406.775666 -402.065998) (xy 406.780746 -402.058886) (xy 406.785572 -402.041868) (xy 406.779984 -401.959572)
			(xy 406.772872 -401.94357) (xy 406.766776 -401.936966) (xy 406.747289 -401.915607) (xy 406.714382 -401.868068)
			(xy 406.689033 -401.816105) (xy 406.671821 -401.760909) (xy 406.663144 -401.703747) (xy 406.662636 -401.674838)
			(xy 406.225756 -401.674838) (xy 406.225297 -401.701001) (xy 406.218147 -401.752837) (xy 406.203985 -401.803211)
			(xy 406.183077 -401.851179) (xy 406.155814 -401.895843) (xy 406.122708 -401.936366) (xy 406.103836 -401.954492)
			(xy 406.09647 -401.96135) (xy 406.088342 -401.978876) (xy 406.083008 -402.069046) (xy 406.089104 -402.087334)
			(xy 406.095708 -402.094954) (xy 406.110609 -402.112997) (xy 406.135673 -402.152515) (xy 406.154921 -402.19517)
			(xy 406.167968 -402.24011) (xy 406.174554 -402.28644) (xy 406.174956 -402.309838) (xy 406.174446 -402.335825)
			(xy 406.166316 -402.38716) (xy 406.150255 -402.43659) (xy 406.126659 -402.4829) (xy 406.096109 -402.524948)
			(xy 406.059358 -402.561699) (xy 406.01731 -402.592249) (xy 405.971 -402.615845) (xy 405.92157 -402.631906)
			(xy 405.870235 -402.640036) (xy 405.818261 -402.640036) (xy 405.766926 -402.631906) (xy 405.717496 -402.615845)
			(xy 405.671186 -402.592249) (xy 405.629138 -402.561699) (xy 405.592387 -402.524948) (xy 405.561837 -402.4829)
			(xy 405.538241 -402.43659) (xy 405.52218 -402.38716) (xy 405.51405 -402.335825) (xy 405.51354 -402.309838)
			(xy 405.513967 -402.286442) (xy 405.520553 -402.240115) (xy 405.533599 -402.195178) (xy 405.552845 -402.152527)
			(xy 405.577907 -402.113012) (xy 405.592788 -402.094954) (xy 405.599392 -402.087334) (xy 405.605488 -402.069046)
			(xy 405.600154 -401.978876) (xy 405.592026 -401.96135) (xy 405.58466 -401.954492) (xy 405.565758 -401.936394)
			(xy 405.532643 -401.895871) (xy 405.505376 -401.851203) (xy 405.484467 -401.803229) (xy 405.470308 -401.752848)
			(xy 405.463167 -401.701004) (xy 405.46274 -401.674838) (xy 405.02586 -401.674838) (xy 405.025245 -401.704996)
			(xy 405.015752 -401.764559) (xy 404.997007 -401.821888) (xy 404.969477 -401.875554) (xy 404.933848 -401.924222)
			(xy 404.91283 -401.945856) (xy 404.906226 -401.95246) (xy 404.898606 -401.969224) (xy 404.893272 -402.05533)
			(xy 404.898606 -402.07311) (xy 404.904448 -402.080476) (xy 404.920953 -402.102466) (xy 404.947228 -402.150758)
			(xy 404.965161 -402.202729) (xy 404.974257 -402.256949) (xy 404.974806 -402.284438) (xy 404.974296 -402.310425)
			(xy 404.966166 -402.36176) (xy 404.950105 -402.41119) (xy 404.926509 -402.4575) (xy 404.895959 -402.499548)
			(xy 404.859208 -402.536299) (xy 404.81716 -402.566849) (xy 404.77085 -402.590445) (xy 404.72142 -402.606506)
			(xy 404.670085 -402.614636) (xy 404.618111 -402.614636) (xy 404.566776 -402.606506) (xy 404.517346 -402.590445)
			(xy 404.471036 -402.566849) (xy 404.428988 -402.536299) (xy 404.392237 -402.499548) (xy 404.361687 -402.4575)
			(xy 404.338091 -402.41119) (xy 404.32203 -402.36176) (xy 404.3139 -402.310425) (xy 404.31339 -402.284438)
			(xy 404.313945 -402.256948) (xy 404.323021 -402.202722) (xy 404.340945 -402.150745) (xy 404.367224 -402.102452)
			(xy 404.383748 -402.080476) (xy 404.38959 -402.07311) (xy 404.394924 -402.05533) (xy 404.38959 -401.969224)
			(xy 404.38197 -401.95246) (xy 404.375366 -401.945856) (xy 404.354321 -401.924243) (xy 404.318676 -401.875578)
			(xy 404.291137 -401.821908) (xy 404.27239 -401.764572) (xy 404.262903 -401.705) (xy 404.262336 -401.674838)
			(xy 403.825964 -401.674838) (xy 403.825349 -401.704996) (xy 403.815855 -401.764559) (xy 403.79711 -401.821888)
			(xy 403.769581 -401.875554) (xy 403.733953 -401.924222) (xy 403.712934 -401.945856) (xy 403.70633 -401.95246)
			(xy 403.69871 -401.969224) (xy 403.693376 -402.05533) (xy 403.69871 -402.07311) (xy 403.704552 -402.080476)
			(xy 403.721058 -402.102465) (xy 403.747333 -402.150758) (xy 403.765265 -402.202729) (xy 403.774361 -402.256949)
			(xy 403.77491 -402.284438) (xy 403.7744 -402.310425) (xy 403.76627 -402.36176) (xy 403.750209 -402.41119)
			(xy 403.726613 -402.4575) (xy 403.696063 -402.499548) (xy 403.659312 -402.536299) (xy 403.617264 -402.566849)
			(xy 403.570954 -402.590445) (xy 403.521524 -402.606506) (xy 403.470189 -402.614636) (xy 403.418215 -402.614636)
			(xy 403.36688 -402.606506) (xy 403.31745 -402.590445) (xy 403.27114 -402.566849) (xy 403.229092 -402.536299)
			(xy 403.192341 -402.499548) (xy 403.161791 -402.4575) (xy 403.138195 -402.41119) (xy 403.122134 -402.36176)
			(xy 403.114004 -402.310425) (xy 403.113494 -402.284438) (xy 403.114048 -402.256948) (xy 403.123124 -402.202722)
			(xy 403.141048 -402.150745) (xy 403.167327 -402.102452) (xy 403.183852 -402.080476) (xy 403.189694 -402.07311)
			(xy 403.195028 -402.05533) (xy 403.189694 -401.969224) (xy 403.182074 -401.95246) (xy 403.17547 -401.945856)
			(xy 403.154426 -401.924242) (xy 403.11878 -401.875577) (xy 403.091241 -401.821908) (xy 403.072494 -401.764572)
			(xy 403.063007 -401.705) (xy 403.06244 -401.674838) (xy 400.409156 -401.674838) (xy 400.409156 -401.932394)
			(xy 400.40958 -401.942463) (xy 400.417299 -401.961064) (xy 400.424142 -401.968462) (xy 401.244054 -402.788374)
			(xy 401.251454 -402.795215) (xy 401.270053 -402.802933) (xy 401.280122 -402.80336)
		)
		(stroke
			(width 0)
			(type solid)
		)
		(fill yes)
		(layer "In2.Cu")
		(net "NCF_CPU0_P2_GND")
	)
	(gr_poly
		(pts
			(xy 373.316246 -263.08431) (xy 373.325613 -263.083931) (xy 373.343121 -263.077276) (xy 373.35706 -263.064764)
			(xy 373.361712 -263.056624) (xy 373.408194 -262.965184) (xy 373.406162 -262.936736) (xy 373.39778 -262.925052)
			(xy 373.384097 -262.905404) (xy 373.362374 -262.86274) (xy 373.347583 -262.817206) (xy 373.34009 -262.76992)
			(xy 373.339614 -262.745982) (xy 373.340136 -262.720727) (xy 373.348449 -262.670905) (xy 373.36485 -262.623131)
			(xy 373.388891 -262.578708) (xy 373.419915 -262.538848) (xy 373.457077 -262.504638) (xy 373.499363 -262.477012)
			(xy 373.545619 -262.456722) (xy 373.594584 -262.444322) (xy 373.644922 -262.440151) (xy 373.69526 -262.444322)
			(xy 373.744225 -262.456722) (xy 373.790481 -262.477012) (xy 373.832767 -262.504638) (xy 373.869929 -262.538848)
			(xy 373.900953 -262.578708) (xy 373.924994 -262.623131) (xy 373.941395 -262.670905) (xy 373.949708 -262.720727)
			(xy 373.95023 -262.745982) (xy 373.949743 -262.769919) (xy 373.942237 -262.817201) (xy 373.927453 -262.862736)
			(xy 373.905752 -262.90541) (xy 373.892064 -262.925052) (xy 373.883682 -262.936736) (xy 373.88165 -262.965184)
			(xy 373.928132 -263.056624) (xy 373.93277 -263.064774) (xy 373.946718 -263.077283) (xy 373.964229 -263.083946)
			(xy 373.973598 -263.08431) (xy 374.804178 -263.08431) (xy 374.814015 -263.083773) (xy 374.832175 -263.076185)
			(xy 374.839484 -263.069578) (xy 375.220738 -262.688324) (xy 375.227342 -262.676894) (xy 375.22912 -262.670036)
			(xy 375.235886 -262.645806) (xy 375.256232 -262.599801) (xy 375.283832 -262.557745) (xy 375.317942 -262.520773)
			(xy 375.357643 -262.489881) (xy 375.401863 -262.465902) (xy 375.425462 -262.457184) (xy 375.440956 -262.45185)
			(xy 375.459752 -262.425688) (xy 375.459752 -262.098536) (xy 375.45772 -262.091424) (xy 375.447396 -262.053394)
			(xy 375.4363 -261.975377) (xy 375.435622 -261.935976) (xy 375.436316 -261.896576) (xy 375.44741 -261.818561)
			(xy 375.45772 -261.780528) (xy 375.459752 -261.773416) (xy 375.459752 -261.446264) (xy 375.440956 -261.420102)
			(xy 375.425462 -261.414768) (xy 375.401768 -261.406051) (xy 375.357395 -261.381975) (xy 375.317585 -261.350931)
			(xy 375.283422 -261.313763) (xy 375.255836 -261.271484) (xy 375.235577 -261.225244) (xy 375.223198 -261.176302)
			(xy 375.219035 -261.12599) (xy 375.223201 -261.075679) (xy 375.235584 -261.026738) (xy 375.255845 -260.980499)
			(xy 375.283434 -260.938221) (xy 375.3176 -260.901056) (xy 375.357411 -260.870014) (xy 375.401785 -260.845941)
			(xy 375.425462 -260.837172) (xy 375.440956 -260.831838) (xy 375.459752 -260.805676) (xy 375.459752 -256.376932)
			(xy 375.459512 -256.369981) (xy 375.455775 -256.35659) (xy 375.452386 -256.350516) (xy 375.436638 -256.324354)
			(xy 375.427494 -256.315464) (xy 375.421398 -256.312162) (xy 375.393764 -256.29614) (xy 375.341975 -256.258744)
			(xy 375.294784 -256.215691) (xy 375.252806 -256.167541) (xy 375.216588 -256.114921) (xy 375.186601 -256.058518)
			(xy 375.17451 -256.028952) (xy 375.16943 -256.015998) (xy 375.147586 -255.99898) (xy 375.033794 -255.983994)
			(xy 375.008394 -255.994916) (xy 375.000266 -256.006092) (xy 374.985749 -256.024898) (xy 374.951875 -256.058205)
			(xy 374.913254 -256.085868) (xy 374.870818 -256.107221) (xy 374.825588 -256.121748) (xy 374.778655 -256.129101)
			(xy 374.754902 -256.129536) (xy 374.729642 -256.129043) (xy 374.679811 -256.120728) (xy 374.632028 -256.104325)
			(xy 374.587596 -256.08028) (xy 374.547728 -256.04925) (xy 374.513512 -256.012081) (xy 374.48588 -255.969787)
			(xy 374.465586 -255.923522) (xy 374.453184 -255.874548) (xy 374.449012 -255.8242) (xy 374.453184 -255.773852)
			(xy 374.465586 -255.724878) (xy 374.48588 -255.678613) (xy 374.513512 -255.636319) (xy 374.547728 -255.59915)
			(xy 374.587596 -255.56812) (xy 374.632028 -255.544075) (xy 374.679811 -255.527672) (xy 374.729642 -255.519357)
			(xy 374.754902 -255.51892) (xy 374.778654 -255.519371) (xy 374.825586 -255.526722) (xy 374.870815 -255.541248)
			(xy 374.913251 -255.562597) (xy 374.951873 -255.590257) (xy 374.985749 -255.62356) (xy 375.000266 -255.642364)
			(xy 375.008394 -255.65354) (xy 375.033794 -255.664462) (xy 375.147586 -255.649476) (xy 375.16943 -255.632458)
			(xy 375.17451 -255.619504) (xy 375.182434 -255.599798) (xy 375.200872 -255.561531) (xy 375.21134 -255.54305)
			(xy 375.360438 -255.286764) (xy 375.377312 -255.258647) (xy 375.416655 -255.206185) (xy 375.438924 -255.182116)
			(xy 375.445274 -255.175258) (xy 375.455942 -255.149858) (xy 375.457735 -255.14517) (xy 375.459643 -255.135318)
			(xy 375.459752 -255.1303) (xy 375.459752 -254.75692) (xy 375.459511 -254.749969) (xy 375.455771 -254.73658)
			(xy 375.452386 -254.730504) (xy 375.436638 -254.704342) (xy 375.427494 -254.695452) (xy 375.421398 -254.69215)
			(xy 375.393764 -254.676127) (xy 375.341976 -254.638731) (xy 375.294786 -254.595678) (xy 375.252809 -254.547527)
			(xy 375.216591 -254.494908) (xy 375.186606 -254.438504) (xy 375.17451 -254.40894) (xy 375.16943 -254.395986)
			(xy 375.147586 -254.378968) (xy 375.033794 -254.363982) (xy 375.008394 -254.374904) (xy 375.000266 -254.38608)
			(xy 374.985749 -254.404886) (xy 374.951876 -254.438195) (xy 374.913256 -254.465859) (xy 374.870819 -254.487213)
			(xy 374.825589 -254.501741) (xy 374.778655 -254.509094) (xy 374.754902 -254.509524) (xy 374.729643 -254.509031)
			(xy 374.679814 -254.500717) (xy 374.632032 -254.484314) (xy 374.587603 -254.46027) (xy 374.547737 -254.429241)
			(xy 374.513521 -254.392074) (xy 374.48589 -254.349781) (xy 374.465597 -254.303518) (xy 374.453196 -254.254546)
			(xy 374.449024 -254.2042) (xy 374.453196 -254.153854) (xy 374.465597 -254.104882) (xy 374.48589 -254.058619)
			(xy 374.513521 -254.016326) (xy 374.547737 -253.979159) (xy 374.587603 -253.94813) (xy 374.632032 -253.924086)
			(xy 374.679814 -253.907683) (xy 374.729643 -253.899369) (xy 374.754902 -253.898908) (xy 374.778654 -253.899359)
			(xy 374.825586 -253.90671) (xy 374.870816 -253.921235) (xy 374.913253 -253.942584) (xy 374.951875 -253.970243)
			(xy 374.985752 -254.003545) (xy 375.000266 -254.022352) (xy 375.008394 -254.033528) (xy 375.033794 -254.04445)
			(xy 375.147586 -254.029464) (xy 375.16943 -254.012446) (xy 375.17451 -253.999492) (xy 375.182434 -253.979786)
			(xy 375.200873 -253.94152) (xy 375.21134 -253.923038) (xy 375.360438 -253.666752) (xy 375.377312 -253.638636)
			(xy 375.416656 -253.586175) (xy 375.438924 -253.562104) (xy 375.445274 -253.555246) (xy 375.455942 -253.529846)
			(xy 375.457743 -253.52516) (xy 375.459669 -253.515308) (xy 375.459752 -253.510288) (xy 375.459752 -252.804676)
			(xy 375.4597 -252.800604) (xy 375.458427 -252.792561) (xy 375.457212 -252.788674) (xy 375.449846 -252.76683)
			(xy 375.445528 -252.760734) (xy 375.432274 -252.741273) (xy 375.411275 -252.699133) (xy 375.396993 -252.654269)
			(xy 375.389765 -252.607745) (xy 375.389765 -252.560662) (xy 375.396991 -252.514137) (xy 375.411272 -252.469273)
			(xy 375.432271 -252.427132) (xy 375.445528 -252.407674) (xy 375.449846 -252.401578) (xy 375.457212 -252.379734)
			(xy 375.458395 -252.375839) (xy 375.459677 -252.367801) (xy 375.459752 -252.363732) (xy 375.459752 -252.087634)
			(xy 375.459498 -252.085094) (xy 375.458274 -252.071475) (xy 375.457004 -252.044158) (xy 375.456958 -252.030484)
			(xy 375.457012 -252.016811) (xy 375.458281 -251.989493) (xy 375.459498 -251.975874) (xy 375.459752 -251.973334)
			(xy 375.459752 -251.675392) (xy 375.459326 -251.665324) (xy 375.451604 -251.646726) (xy 375.444766 -251.639324)
			(xy 375.026174 -251.220732) (xy 375.019314 -251.214484) (xy 375.002387 -251.206914) (xy 374.993154 -251.206)
			(xy 374.963436 -251.204222) (xy 374.954865 -251.20404) (xy 374.938383 -251.208719) (xy 374.931178 -251.213366)
			(xy 374.911749 -251.22661) (xy 374.869673 -251.247596) (xy 374.824873 -251.261869) (xy 374.778412 -251.269092)
			(xy 374.754902 -251.2695) (xy 374.730909 -251.269054) (xy 374.683514 -251.261547) (xy 374.637876 -251.246719)
			(xy 374.59512 -251.224934) (xy 374.556299 -251.196728) (xy 374.522368 -251.162796) (xy 374.494163 -251.123974)
			(xy 374.472379 -251.081218) (xy 374.457551 -251.03558) (xy 374.450046 -250.988185) (xy 374.449594 -250.964192)
			(xy 374.450119 -250.938543) (xy 374.458688 -250.887967) (xy 374.475583 -250.839531) (xy 374.500331 -250.794598)
			(xy 374.515888 -250.7742) (xy 374.52808 -250.75896) (xy 374.525794 -250.720352) (xy 374.419368 -250.613926)
			(xy 374.411969 -250.607082) (xy 374.393371 -250.599355) (xy 374.3833 -250.59894) (xy 373.252746 -250.59894)
			(xy 373.242906 -250.599471) (xy 373.224735 -250.607048) (xy 373.21744 -250.613672) (xy 373.13362 -250.697492)
			(xy 373.127414 -250.704303) (xy 373.11986 -250.721095) (xy 373.118888 -250.730258) (xy 373.117618 -250.752356)
			(xy 373.117397 -250.75698) (xy 373.11842 -250.766181) (xy 373.11965 -250.770644) (xy 373.126 -250.790456)
			(xy 373.12981 -250.796298) (xy 373.141762 -250.815161) (xy 373.160617 -250.855638) (xy 373.173372 -250.898431)
			(xy 373.179756 -250.942626) (xy 373.180102 -250.964954) (xy 373.180102 -250.97105) (xy 373.179127 -250.994686)
			(xy 373.170783 -251.041249) (xy 373.155357 -251.085968) (xy 373.133218 -251.127771) (xy 373.104895 -251.16566)
			(xy 373.071067 -251.198726) (xy 373.032543 -251.226178) (xy 372.990246 -251.247359) (xy 372.945187 -251.261762)
			(xy 372.898446 -251.269043) (xy 372.874794 -251.2695) (xy 372.87454 -251.2695) (xy 372.849448 -251.26897)
			(xy 372.799947 -251.260715) (xy 372.752464 -251.24447) (xy 372.70828 -251.220674) (xy 372.688104 -251.205746)
			(xy 372.672864 -251.194062) (xy 372.634764 -251.196348) (xy 372.498366 -251.332746) (xy 372.490183 -251.342044)
			(xy 372.48287 -251.365668) (xy 372.484396 -251.377958) (xy 372.501922 -251.470668) (xy 372.517162 -251.489972)
			(xy 372.528846 -251.495052) (xy 372.551626 -251.505748) (xy 372.59363 -251.533459) (xy 372.630528 -251.567677)
			(xy 372.661323 -251.607476) (xy 372.685182 -251.651782) (xy 372.701461 -251.699398) (xy 372.709721 -251.749037)
			(xy 372.710202 -251.774198) (xy 373.978944 -251.774198) (xy 373.982904 -251.725144) (xy 373.994681 -251.67736)
			(xy 374.013972 -251.632084) (xy 374.040275 -251.590488) (xy 374.07291 -251.553651) (xy 374.111031 -251.522526)
			(xy 374.153652 -251.497919) (xy 374.199668 -251.480467) (xy 374.247887 -251.470623) (xy 374.297062 -251.468642)
			(xy 374.345917 -251.474574) (xy 374.393188 -251.488266) (xy 374.43765 -251.509364) (xy 374.478153 -251.53732)
			(xy 374.513646 -251.571412) (xy 374.543211 -251.610756) (xy 374.566082 -251.654333) (xy 374.581666 -251.701014)
			(xy 374.589561 -251.749591) (xy 374.590056 -251.774198) (xy 374.589561 -251.798805) (xy 374.581666 -251.847382)
			(xy 374.566082 -251.894063) (xy 374.543211 -251.93764) (xy 374.513646 -251.976984) (xy 374.478153 -252.011076)
			(xy 374.43765 -252.039032) (xy 374.393188 -252.06013) (xy 374.345917 -252.073822) (xy 374.297062 -252.079754)
			(xy 374.247887 -252.077773) (xy 374.199668 -252.067929) (xy 374.153652 -252.050477) (xy 374.111031 -252.02587)
			(xy 374.07291 -251.994745) (xy 374.040275 -251.957908) (xy 374.013972 -251.916312) (xy 373.994681 -251.871036)
			(xy 373.982904 -251.823252) (xy 373.978944 -251.774198) (xy 372.710202 -251.774198) (xy 372.70968 -251.799453)
			(xy 372.701367 -251.849275) (xy 372.684966 -251.897049) (xy 372.660925 -251.941472) (xy 372.629901 -251.981332)
			(xy 372.592739 -252.015542) (xy 372.550453 -252.043168) (xy 372.504197 -252.063458) (xy 372.455232 -252.075858)
			(xy 372.404894 -252.080029) (xy 372.354556 -252.075858) (xy 372.305591 -252.063458) (xy 372.259335 -252.043168)
			(xy 372.217049 -252.015542) (xy 372.179887 -251.981332) (xy 372.148863 -251.941472) (xy 372.124822 -251.897049)
			(xy 372.108421 -251.849275) (xy 372.100108 -251.799453) (xy 372.099586 -251.774198) (xy 372.100239 -251.745499)
			(xy 372.110982 -251.689115) (xy 372.120922 -251.662184) (xy 372.125494 -251.650246) (xy 372.1227 -251.625354)
			(xy 372.069614 -251.547122) (xy 372.062134 -251.537144) (xy 372.040158 -251.525416) (xy 372.027704 -251.52477)
			(xy 371.359176 -251.52477) (xy 371.349335 -251.524242) (xy 371.331165 -251.516663) (xy 371.32387 -251.510038)
			(xy 371.08384 -251.270008) (xy 371.060218 -251.262642) (xy 371.048026 -251.264928) (xy 371.034798 -251.267091)
			(xy 371.008089 -251.269378) (xy 370.994686 -251.2695) (xy 370.970696 -251.269028) (xy 370.923306 -251.26152)
			(xy 370.877675 -251.246692) (xy 370.834924 -251.224907) (xy 370.796108 -251.196704) (xy 370.762182 -251.162775)
			(xy 370.733981 -251.123957) (xy 370.7122 -251.081205) (xy 370.697374 -251.035572) (xy 370.68987 -250.988182)
			(xy 370.689378 -250.964192) (xy 370.68949 -250.950788) (xy 370.691782 -250.92408) (xy 370.69395 -250.910852)
			(xy 370.696236 -250.89866) (xy 370.68887 -250.875038) (xy 370.427758 -250.613926) (xy 370.420359 -250.607083)
			(xy 370.40176 -250.59936) (xy 370.39169 -250.59894) (xy 369.485926 -250.59894) (xy 369.476088 -250.599475)
			(xy 369.457922 -250.607056) (xy 369.45062 -250.613672) (xy 369.34394 -250.720352) (xy 369.341654 -250.75896)
			(xy 369.353846 -250.7742) (xy 369.369396 -250.794604) (xy 369.394157 -250.839531) (xy 369.411057 -250.887965)
			(xy 369.41962 -250.938543) (xy 369.42014 -250.964192) (xy 369.41967 -250.988185) (xy 369.412165 -251.035579)
			(xy 369.397339 -251.081216) (xy 369.375556 -251.123972) (xy 369.347353 -251.162795) (xy 369.313425 -251.196727)
			(xy 369.274606 -251.224935) (xy 369.231853 -251.246723) (xy 369.186218 -251.261556) (xy 369.138824 -251.269067)
			(xy 369.114832 -251.2695) (xy 369.089185 -251.26897) (xy 369.038613 -251.260392) (xy 368.990184 -251.243489)
			(xy 368.945259 -251.218735) (xy 368.92484 -251.203206) (xy 368.9096 -251.191014) (xy 368.870992 -251.1933)
			(xy 368.733832 -251.33046) (xy 368.725616 -251.339815) (xy 368.718305 -251.363574) (xy 368.719862 -251.375926)
			(xy 368.737896 -251.469144) (xy 368.753644 -251.488702) (xy 368.765328 -251.493782) (xy 368.788468 -251.50429)
			(xy 368.831177 -251.531829) (xy 368.868739 -251.566058) (xy 368.900117 -251.606031) (xy 368.924445 -251.650647)
			(xy 368.941052 -251.698675) (xy 368.949481 -251.748789) (xy 368.949986 -251.774198) (xy 370.218982 -251.774198)
			(xy 370.222942 -251.725144) (xy 370.234719 -251.67736) (xy 370.25401 -251.632084) (xy 370.280313 -251.590488)
			(xy 370.312948 -251.553651) (xy 370.351069 -251.522526) (xy 370.39369 -251.497919) (xy 370.439706 -251.480467)
			(xy 370.487925 -251.470623) (xy 370.5371 -251.468642) (xy 370.585955 -251.474574) (xy 370.633226 -251.488266)
			(xy 370.677688 -251.509364) (xy 370.718191 -251.53732) (xy 370.753684 -251.571412) (xy 370.783249 -251.610756)
			(xy 370.80612 -251.654333) (xy 370.821704 -251.701014) (xy 370.829599 -251.749591) (xy 370.830094 -251.774198)
			(xy 370.829599 -251.798805) (xy 370.821704 -251.847382) (xy 370.80612 -251.894063) (xy 370.783249 -251.93764)
			(xy 370.753684 -251.976984) (xy 370.718191 -252.011076) (xy 370.677688 -252.039032) (xy 370.633226 -252.06013)
			(xy 370.585955 -252.073822) (xy 370.5371 -252.079754) (xy 370.487925 -252.077773) (xy 370.439706 -252.067929)
			(xy 370.39369 -252.050477) (xy 370.351069 -252.02587) (xy 370.312948 -251.994745) (xy 370.280313 -251.957908)
			(xy 370.25401 -251.916312) (xy 370.234719 -251.871036) (xy 370.222942 -251.823252) (xy 370.218982 -251.774198)
			(xy 368.949986 -251.774198) (xy 368.949464 -251.799453) (xy 368.941151 -251.849275) (xy 368.92475 -251.897049)
			(xy 368.900709 -251.941472) (xy 368.869685 -251.981332) (xy 368.832523 -252.015542) (xy 368.790237 -252.043168)
			(xy 368.743981 -252.063458) (xy 368.695016 -252.075858) (xy 368.644678 -252.080029) (xy 368.59434 -252.075858)
			(xy 368.545375 -252.063458) (xy 368.499119 -252.043168) (xy 368.456833 -252.015542) (xy 368.419671 -251.981332)
			(xy 368.388647 -251.941472) (xy 368.364606 -251.897049) (xy 368.348205 -251.849275) (xy 368.339892 -251.799453)
			(xy 368.33937 -251.774198) (xy 368.339914 -251.747974) (xy 368.348876 -251.696297) (xy 368.366536 -251.646912)
			(xy 368.378994 -251.62383) (xy 368.385598 -251.611892) (xy 368.385598 -251.584968) (xy 368.33556 -251.499116)
			(xy 368.330814 -251.49161) (xy 368.317189 -251.480237) (xy 368.300493 -251.474219) (xy 368.291618 -251.47397)
			(xy 367.650776 -251.47397) (xy 367.640935 -251.473442) (xy 367.622765 -251.465863) (xy 367.61547 -251.459238)
			(xy 367.400586 -251.244354) (xy 367.369852 -251.238258) (xy 367.355628 -251.244608) (xy 367.336453 -251.252477)
			(xy 367.296515 -251.263559) (xy 367.255448 -251.269154) (xy 367.234724 -251.2695) (xy 367.21073 -251.269056)
			(xy 367.163332 -251.261552) (xy 367.117692 -251.246725) (xy 367.074933 -251.224941) (xy 367.036108 -251.196736)
			(xy 367.002175 -251.162804) (xy 366.973967 -251.123981) (xy 366.952181 -251.081223) (xy 366.937352 -251.035584)
			(xy 366.929846 -250.988186) (xy 366.929416 -250.964192) (xy 366.929739 -250.943466) (xy 366.935312 -250.902391)
			(xy 366.946407 -250.862452) (xy 366.954308 -250.843288) (xy 366.960658 -250.829064) (xy 366.954562 -250.79833)
			(xy 366.818418 -250.662186) (xy 366.811019 -250.655343) (xy 366.79242 -250.647625) (xy 366.78235 -250.6472)
			(xy 365.744506 -250.6472) (xy 365.734759 -250.647722) (xy 365.716742 -250.655183) (xy 365.709454 -250.661678)
			(xy 365.612426 -250.758706) (xy 365.608108 -250.792996) (xy 365.617252 -250.807982) (xy 365.630725 -250.831788)
			(xy 365.649888 -250.883017) (xy 365.659599 -250.936844) (xy 365.660178 -250.964192) (xy 365.659732 -250.988185)
			(xy 365.652226 -251.035579) (xy 365.637398 -251.081216) (xy 365.615613 -251.123971) (xy 365.587407 -251.162792)
			(xy 365.553475 -251.196721) (xy 365.514652 -251.224924) (xy 365.471896 -251.246707) (xy 365.426258 -251.261532)
			(xy 365.378863 -251.269034) (xy 365.35487 -251.2695) (xy 365.327526 -251.268886) (xy 365.273712 -251.259151)
			(xy 365.222481 -251.240013) (xy 365.19866 -251.226574) (xy 365.183674 -251.21743) (xy 365.149384 -251.221748)
			(xy 365.01832 -251.352812) (xy 365.010493 -251.361486) (xy 365.00297 -251.383578) (xy 365.003842 -251.39523)
			(xy 365.015526 -251.485146) (xy 365.02848 -251.50445) (xy 365.03864 -251.510546) (xy 365.061268 -251.524418)
			(xy 365.101785 -251.558697) (xy 365.135766 -251.599463) (xy 365.16219 -251.645489) (xy 365.180261 -251.695389)
			(xy 365.189434 -251.747662) (xy 365.190024 -251.774198) (xy 366.45902 -251.774198) (xy 366.46298 -251.725144)
			(xy 366.474757 -251.67736) (xy 366.494048 -251.632084) (xy 366.520351 -251.590488) (xy 366.552986 -251.553651)
			(xy 366.591107 -251.522526) (xy 366.633728 -251.497919) (xy 366.679744 -251.480467) (xy 366.727963 -251.470623)
			(xy 366.777138 -251.468642) (xy 366.825993 -251.474574) (xy 366.873264 -251.488266) (xy 366.917726 -251.509364)
			(xy 366.958229 -251.53732) (xy 366.993722 -251.571412) (xy 367.023287 -251.610756) (xy 367.046158 -251.654333)
			(xy 367.061742 -251.701014) (xy 367.069637 -251.749591) (xy 367.070132 -251.774198) (xy 367.069637 -251.798805)
			(xy 367.061742 -251.847382) (xy 367.046158 -251.894063) (xy 367.023287 -251.93764) (xy 366.993722 -251.976984)
			(xy 366.958229 -252.011076) (xy 366.917726 -252.039032) (xy 366.873264 -252.06013) (xy 366.825993 -252.073822)
			(xy 366.777138 -252.079754) (xy 366.727963 -252.077773) (xy 366.679744 -252.067929) (xy 366.633728 -252.050477)
			(xy 366.591107 -252.02587) (xy 366.552986 -251.994745) (xy 366.520351 -251.957908) (xy 366.494048 -251.916312)
			(xy 366.474757 -251.871036) (xy 366.46298 -251.823252) (xy 366.45902 -251.774198) (xy 365.190024 -251.774198)
			(xy 365.189502 -251.799453) (xy 365.181189 -251.849275) (xy 365.164788 -251.897049) (xy 365.140747 -251.941472)
			(xy 365.109723 -251.981332) (xy 365.072561 -252.015542) (xy 365.030275 -252.043168) (xy 364.984019 -252.063458)
			(xy 364.935054 -252.075858) (xy 364.884716 -252.080029) (xy 364.834378 -252.075858) (xy 364.785413 -252.063458)
			(xy 364.739157 -252.043168) (xy 364.696871 -252.015542) (xy 364.659709 -251.981332) (xy 364.628685 -251.941472)
			(xy 364.604644 -251.897049) (xy 364.588243 -251.849275) (xy 364.57993 -251.799453) (xy 364.579408 -251.774198)
			(xy 364.579952 -251.747974) (xy 364.588915 -251.696298) (xy 364.606577 -251.646914) (xy 364.619032 -251.62383)
			(xy 364.625636 -251.611892) (xy 364.625636 -251.584968) (xy 364.575598 -251.499116) (xy 364.570849 -251.491617)
			(xy 364.557221 -251.480261) (xy 364.540527 -251.474262) (xy 364.531656 -251.47397) (xy 364.163356 -251.47397)
			(xy 364.153517 -251.473438) (xy 364.135352 -251.465854) (xy 364.12805 -251.459238) (xy 363.840776 -251.171964)
			(xy 363.833214 -251.165018) (xy 363.81421 -251.157296) (xy 363.803946 -251.156978) (xy 363.722158 -251.158248)
			(xy 363.70387 -251.166376) (xy 363.696504 -251.173996) (xy 363.67909 -251.191713) (xy 363.63957 -251.221811)
			(xy 363.595694 -251.245104) (xy 363.548622 -251.260976) (xy 363.4996 -251.269007) (xy 363.474762 -251.2695)
			(xy 363.450773 -251.269027) (xy 363.403386 -251.261516) (xy 363.357758 -251.246685) (xy 363.315011 -251.224899)
			(xy 363.276198 -251.196695) (xy 363.242275 -251.162767) (xy 363.214077 -251.12395) (xy 363.192298 -251.0812)
			(xy 363.177474 -251.035569) (xy 363.16997 -250.988181) (xy 363.169454 -250.964192) (xy 363.169892 -250.940099)
			(xy 363.177428 -250.892505) (xy 363.18444 -250.86945) (xy 363.18825 -250.857766) (xy 363.184694 -250.834144)
			(xy 363.130338 -250.759214) (xy 363.122723 -250.749839) (xy 363.101249 -250.738857) (xy 363.08919 -250.738132)
			(xy 361.98048 -250.738132) (xy 361.968408 -250.738796) (xy 361.946918 -250.7498) (xy 361.939332 -250.759214)
			(xy 361.884976 -250.834144) (xy 361.88142 -250.857766) (xy 361.88523 -250.86945) (xy 361.892254 -250.892502)
			(xy 361.89978 -250.940098) (xy 361.900216 -250.964192) (xy 361.899694 -250.989447) (xy 361.891381 -251.039269)
			(xy 361.87498 -251.087043) (xy 361.850939 -251.131466) (xy 361.819915 -251.171326) (xy 361.782753 -251.205536)
			(xy 361.740467 -251.233162) (xy 361.694211 -251.253452) (xy 361.645246 -251.265852) (xy 361.594908 -251.270023)
			(xy 361.54457 -251.265852) (xy 361.495605 -251.253452) (xy 361.449349 -251.233162) (xy 361.407063 -251.205536)
			(xy 361.369901 -251.171326) (xy 361.338877 -251.131466) (xy 361.314836 -251.087043) (xy 361.298435 -251.039269)
			(xy 361.290122 -250.989447) (xy 361.2896 -250.964192) (xy 361.290038 -250.940098) (xy 361.297573 -250.892505)
			(xy 361.304586 -250.86945) (xy 361.308396 -250.857766) (xy 361.30484 -250.834144) (xy 361.250484 -250.759214)
			(xy 361.242872 -250.749831) (xy 361.221398 -250.73883) (xy 361.209336 -250.738132) (xy 357.265224 -250.738132)
			(xy 357.255388 -250.73867) (xy 357.237231 -250.746262) (xy 357.229918 -250.752864) (xy 357.182166 -250.800616)
			(xy 357.176324 -250.830842) (xy 357.18242 -250.84532) (xy 357.193628 -250.873753) (xy 357.205774 -250.933639)
			(xy 357.20655 -250.964192) (xy 357.20608 -250.988185) (xy 357.198575 -251.03558) (xy 357.183749 -251.081218)
			(xy 357.161967 -251.123975) (xy 357.133764 -251.162798) (xy 357.099836 -251.196732) (xy 357.061017 -251.22494)
			(xy 357.018264 -251.24673) (xy 356.972629 -251.261563) (xy 356.925235 -251.269076) (xy 356.901242 -251.2695)
			(xy 356.870687 -251.268756) (xy 356.810801 -251.256589) (xy 356.78237 -251.24537) (xy 356.767892 -251.239274)
			(xy 356.737666 -251.245116) (xy 356.627176 -251.355606) (xy 356.619938 -251.362318) (xy 356.601732 -251.369909)
			(xy 356.59187 -251.370338) (xy 355.759766 -251.370338) (xy 355.749495 -251.370813) (xy 355.730597 -251.378865)
			(xy 355.716358 -251.393671) (xy 355.713479 -251.40031) (xy 359.872791 -251.40031) (xy 359.876821 -251.347812)
			(xy 359.888818 -251.296544) (xy 359.908501 -251.247709) (xy 359.935407 -251.20245) (xy 359.968907 -251.161829)
			(xy 360.008215 -251.126798) (xy 360.05241 -251.098178) (xy 360.100455 -251.076639) (xy 360.151226 -251.062687)
			(xy 360.203531 -251.056649) (xy 360.256145 -251.058666) (xy 360.307835 -251.06869) (xy 360.357388 -251.086488)
			(xy 360.403644 -251.111641) (xy 360.445518 -251.14356) (xy 360.48203 -251.181498) (xy 360.512322 -251.224564)
			(xy 360.535685 -251.271749) (xy 360.551571 -251.321948) (xy 360.559608 -251.373984) (xy 360.560112 -251.40031)
			(xy 360.559608 -251.426636) (xy 360.551571 -251.478672) (xy 360.535685 -251.528871) (xy 360.512322 -251.576056)
			(xy 360.48203 -251.619122) (xy 360.445518 -251.65706) (xy 360.403644 -251.688979) (xy 360.357388 -251.714132)
			(xy 360.307835 -251.73193) (xy 360.256145 -251.741954) (xy 360.203531 -251.743971) (xy 360.151226 -251.737933)
			(xy 360.100455 -251.723981) (xy 360.05241 -251.702442) (xy 360.008215 -251.673822) (xy 359.968907 -251.638791)
			(xy 359.935407 -251.59817) (xy 359.908501 -251.552911) (xy 359.888818 -251.504076) (xy 359.876821 -251.452808)
			(xy 359.872791 -251.40031) (xy 355.713479 -251.40031) (xy 355.712268 -251.403104) (xy 355.674168 -251.50445)
			(xy 355.681534 -251.53493) (xy 355.693472 -251.545598) (xy 355.712447 -251.563152) (xy 355.744796 -251.603466)
			(xy 355.769904 -251.648646) (xy 355.787057 -251.697405) (xy 355.795766 -251.748354) (xy 355.796342 -251.774198)
			(xy 357.065338 -251.774198) (xy 357.069298 -251.725144) (xy 357.081075 -251.67736) (xy 357.100366 -251.632084)
			(xy 357.126669 -251.590488) (xy 357.159304 -251.553651) (xy 357.197425 -251.522526) (xy 357.240046 -251.497919)
			(xy 357.286062 -251.480467) (xy 357.334281 -251.470623) (xy 357.383456 -251.468642) (xy 357.432311 -251.474574)
			(xy 357.479582 -251.488266) (xy 357.524044 -251.509364) (xy 357.564547 -251.53732) (xy 357.60004 -251.571412)
			(xy 357.629605 -251.610756) (xy 357.652476 -251.654333) (xy 357.66806 -251.701014) (xy 357.675955 -251.749591)
			(xy 357.67645 -251.774198) (xy 360.81895 -251.774198) (xy 360.82291 -251.725144) (xy 360.834687 -251.67736)
			(xy 360.853978 -251.632084) (xy 360.880281 -251.590488) (xy 360.912916 -251.553651) (xy 360.951037 -251.522526)
			(xy 360.993658 -251.497919) (xy 361.039674 -251.480467) (xy 361.087893 -251.470623) (xy 361.137068 -251.468642)
			(xy 361.185923 -251.474574) (xy 361.233194 -251.488266) (xy 361.277656 -251.509364) (xy 361.318159 -251.53732)
			(xy 361.353652 -251.571412) (xy 361.383217 -251.610756) (xy 361.406088 -251.654333) (xy 361.421672 -251.701014)
			(xy 361.429567 -251.749591) (xy 361.430062 -251.774198) (xy 362.699058 -251.774198) (xy 362.703018 -251.725144)
			(xy 362.714795 -251.67736) (xy 362.734086 -251.632084) (xy 362.760389 -251.590488) (xy 362.793024 -251.553651)
			(xy 362.831145 -251.522526) (xy 362.873766 -251.497919) (xy 362.919782 -251.480467) (xy 362.968001 -251.470623)
			(xy 363.017176 -251.468642) (xy 363.066031 -251.474574) (xy 363.113302 -251.488266) (xy 363.157764 -251.509364)
			(xy 363.198267 -251.53732) (xy 363.23376 -251.571412) (xy 363.263325 -251.610756) (xy 363.286196 -251.654333)
			(xy 363.30178 -251.701014) (xy 363.309675 -251.749591) (xy 363.31017 -251.774198) (xy 363.309675 -251.798805)
			(xy 363.30178 -251.847382) (xy 363.286196 -251.894063) (xy 363.263325 -251.93764) (xy 363.23376 -251.976984)
			(xy 363.198267 -252.011076) (xy 363.157764 -252.039032) (xy 363.113302 -252.06013) (xy 363.066031 -252.073822)
			(xy 363.017176 -252.079754) (xy 362.968001 -252.077773) (xy 362.919782 -252.067929) (xy 362.873766 -252.050477)
			(xy 362.831145 -252.02587) (xy 362.793024 -251.994745) (xy 362.760389 -251.957908) (xy 362.734086 -251.916312)
			(xy 362.714795 -251.871036) (xy 362.703018 -251.823252) (xy 362.699058 -251.774198) (xy 361.430062 -251.774198)
			(xy 361.429567 -251.798805) (xy 361.421672 -251.847382) (xy 361.406088 -251.894063) (xy 361.383217 -251.93764)
			(xy 361.353652 -251.976984) (xy 361.318159 -252.011076) (xy 361.277656 -252.039032) (xy 361.233194 -252.06013)
			(xy 361.185923 -252.073822) (xy 361.137068 -252.079754) (xy 361.087893 -252.077773) (xy 361.039674 -252.067929)
			(xy 360.993658 -252.050477) (xy 360.951037 -252.02587) (xy 360.912916 -251.994745) (xy 360.880281 -251.957908)
			(xy 360.853978 -251.916312) (xy 360.834687 -251.871036) (xy 360.82291 -251.823252) (xy 360.81895 -251.774198)
			(xy 357.67645 -251.774198) (xy 357.675955 -251.798805) (xy 357.66806 -251.847382) (xy 357.652476 -251.894063)
			(xy 357.629605 -251.93764) (xy 357.60004 -251.976984) (xy 357.564547 -252.011076) (xy 357.524044 -252.039032)
			(xy 357.479582 -252.06013) (xy 357.432311 -252.073822) (xy 357.383456 -252.079754) (xy 357.334281 -252.077773)
			(xy 357.286062 -252.067929) (xy 357.240046 -252.050477) (xy 357.197425 -252.02587) (xy 357.159304 -251.994745)
			(xy 357.126669 -251.957908) (xy 357.100366 -251.916312) (xy 357.081075 -251.871036) (xy 357.069298 -251.823252)
			(xy 357.065338 -251.774198) (xy 355.796342 -251.774198) (xy 355.79582 -251.799453) (xy 355.787507 -251.849275)
			(xy 355.771106 -251.897049) (xy 355.747065 -251.941472) (xy 355.716041 -251.981332) (xy 355.678879 -252.015542)
			(xy 355.636593 -252.043168) (xy 355.590337 -252.063458) (xy 355.541372 -252.075858) (xy 355.491034 -252.080029)
			(xy 355.440696 -252.075858) (xy 355.391731 -252.063458) (xy 355.345475 -252.043168) (xy 355.303189 -252.015542)
			(xy 355.266027 -251.981332) (xy 355.235003 -251.941472) (xy 355.210962 -251.897049) (xy 355.194561 -251.849275)
			(xy 355.186248 -251.799453) (xy 355.185726 -251.774198) (xy 355.18626 -251.748349) (xy 355.194951 -251.697388)
			(xy 355.212102 -251.648619) (xy 355.237222 -251.603436) (xy 355.269594 -251.563129) (xy 355.288596 -251.545598)
			(xy 355.300534 -251.53493) (xy 355.3079 -251.50445) (xy 355.2698 -251.403104) (xy 355.265719 -251.393661)
			(xy 355.251485 -251.378835) (xy 355.232578 -251.370777) (xy 355.222302 -251.370338) (xy 353.879912 -251.370338)
			(xy 353.869636 -251.370805) (xy 353.850723 -251.378847) (xy 353.83647 -251.393653) (xy 353.832414 -251.403104)
			(xy 353.794314 -251.50445) (xy 353.80168 -251.53493) (xy 353.813618 -251.545598) (xy 353.832591 -251.563153)
			(xy 353.864935 -251.603469) (xy 353.890039 -251.648649) (xy 353.907189 -251.697407) (xy 353.915897 -251.748355)
			(xy 353.916488 -251.774198) (xy 353.915966 -251.799453) (xy 353.907653 -251.849275) (xy 353.891252 -251.897049)
			(xy 353.867211 -251.941472) (xy 353.836187 -251.981332) (xy 353.799025 -252.015542) (xy 353.756739 -252.043168)
			(xy 353.710483 -252.063458) (xy 353.661518 -252.075858) (xy 353.61118 -252.080029) (xy 353.560842 -252.075858)
			(xy 353.511877 -252.063458) (xy 353.465621 -252.043168) (xy 353.423335 -252.015542) (xy 353.386173 -251.981332)
			(xy 353.355149 -251.941472) (xy 353.331108 -251.897049) (xy 353.314707 -251.849275) (xy 353.306394 -251.799453)
			(xy 353.305872 -251.774198) (xy 353.306009 -251.761435) (xy 353.308168 -251.736001) (xy 353.31019 -251.723398)
			(xy 353.309936 -251.723398) (xy 353.314814 -251.697919) (xy 353.331998 -251.648978) (xy 353.357199 -251.60364)
			(xy 353.389693 -251.563208) (xy 353.408742 -251.545598) (xy 353.42068 -251.53493) (xy 353.428046 -251.50445)
			(xy 353.389946 -251.403104) (xy 353.385862 -251.393667) (xy 353.371626 -251.378856) (xy 353.35272 -251.370817)
			(xy 353.342448 -251.370338) (xy 351.999804 -251.370338) (xy 351.989529 -251.370806) (xy 351.970619 -251.37885)
			(xy 351.956368 -251.393656) (xy 351.952306 -251.403104) (xy 351.914206 -251.50445) (xy 351.921572 -251.53493)
			(xy 351.93351 -251.545598) (xy 351.952483 -251.563153) (xy 351.984828 -251.603469) (xy 352.009933 -251.648649)
			(xy 352.027084 -251.697407) (xy 352.035792 -251.748355) (xy 352.03638 -251.774198) (xy 352.035858 -251.799453)
			(xy 352.027545 -251.849275) (xy 352.011144 -251.897049) (xy 351.987103 -251.941472) (xy 351.956079 -251.981332)
			(xy 351.918917 -252.015542) (xy 351.876631 -252.043168) (xy 351.830375 -252.063458) (xy 351.78141 -252.075858)
			(xy 351.731072 -252.080029) (xy 351.680734 -252.075858) (xy 351.631769 -252.063458) (xy 351.585513 -252.043168)
			(xy 351.543227 -252.015542) (xy 351.506065 -251.981332) (xy 351.475041 -251.941472) (xy 351.451 -251.897049)
			(xy 351.434599 -251.849275) (xy 351.426286 -251.799453) (xy 351.425764 -251.774198) (xy 351.426298 -251.748349)
			(xy 351.434988 -251.697386) (xy 351.452136 -251.648615) (xy 351.477252 -251.603428) (xy 351.50962 -251.563116)
			(xy 351.528634 -251.545598) (xy 351.540572 -251.53493) (xy 351.547938 -251.50445) (xy 351.509838 -251.403104)
			(xy 351.505753 -251.393668) (xy 351.491517 -251.37886) (xy 351.472612 -251.370823) (xy 351.46234 -251.370338)
			(xy 350.764094 -251.370338) (xy 350.75425 -251.370861) (xy 350.736066 -251.378424) (xy 350.728788 -251.38507)
			(xy 350.629474 -251.484638) (xy 350.622766 -251.491878) (xy 350.615184 -251.510083) (xy 350.614742 -251.519944)
			(xy 350.614742 -251.807218) (xy 350.61517 -251.817286) (xy 350.622893 -251.835881) (xy 350.629728 -251.843286)
			(xy 351.202752 -252.41631) (xy 359.853741 -252.41631) (xy 359.857771 -252.363812) (xy 359.869768 -252.312544)
			(xy 359.889451 -252.263709) (xy 359.916357 -252.21845) (xy 359.949857 -252.177829) (xy 359.989165 -252.142798)
			(xy 360.03336 -252.114178) (xy 360.081405 -252.092639) (xy 360.132176 -252.078687) (xy 360.184481 -252.072649)
			(xy 360.237095 -252.074666) (xy 360.288785 -252.08469) (xy 360.338338 -252.102488) (xy 360.384594 -252.127641)
			(xy 360.426468 -252.15956) (xy 360.46298 -252.197498) (xy 360.493272 -252.240564) (xy 360.516635 -252.287749)
			(xy 360.532521 -252.337948) (xy 360.540558 -252.389984) (xy 360.541062 -252.41631) (xy 360.540558 -252.442636)
			(xy 360.532521 -252.494672) (xy 360.516635 -252.544871) (xy 360.49716 -252.584204) (xy 368.809028 -252.584204)
			(xy 368.812988 -252.53515) (xy 368.824765 -252.487366) (xy 368.844056 -252.44209) (xy 368.870359 -252.400494)
			(xy 368.902994 -252.363657) (xy 368.941115 -252.332532) (xy 368.983736 -252.307925) (xy 369.029752 -252.290473)
			(xy 369.077971 -252.280629) (xy 369.127146 -252.278648) (xy 369.176001 -252.28458) (xy 369.223272 -252.298272)
			(xy 369.267734 -252.31937) (xy 369.308237 -252.347326) (xy 369.34373 -252.381418) (xy 369.373295 -252.420762)
			(xy 369.396166 -252.464339) (xy 369.41175 -252.51102) (xy 369.419645 -252.559597) (xy 369.42014 -252.584204)
			(xy 370.688882 -252.584204) (xy 370.692842 -252.53515) (xy 370.704619 -252.487366) (xy 370.72391 -252.44209)
			(xy 370.750213 -252.400494) (xy 370.782848 -252.363657) (xy 370.820969 -252.332532) (xy 370.86359 -252.307925)
			(xy 370.909606 -252.290473) (xy 370.957825 -252.280629) (xy 371.007 -252.278648) (xy 371.055855 -252.28458)
			(xy 371.103126 -252.298272) (xy 371.147588 -252.31937) (xy 371.188091 -252.347326) (xy 371.223584 -252.381418)
			(xy 371.253149 -252.420762) (xy 371.27602 -252.464339) (xy 371.291604 -252.51102) (xy 371.299499 -252.559597)
			(xy 371.299994 -252.584204) (xy 372.56899 -252.584204) (xy 372.57295 -252.53515) (xy 372.584727 -252.487366)
			(xy 372.604018 -252.44209) (xy 372.630321 -252.400494) (xy 372.662956 -252.363657) (xy 372.701077 -252.332532)
			(xy 372.743698 -252.307925) (xy 372.789714 -252.290473) (xy 372.837933 -252.280629) (xy 372.887108 -252.278648)
			(xy 372.935963 -252.28458) (xy 372.983234 -252.298272) (xy 373.027696 -252.31937) (xy 373.068199 -252.347326)
			(xy 373.103692 -252.381418) (xy 373.133257 -252.420762) (xy 373.156128 -252.464339) (xy 373.171712 -252.51102)
			(xy 373.179607 -252.559597) (xy 373.180102 -252.584204) (xy 374.449098 -252.584204) (xy 374.453058 -252.53515)
			(xy 374.464835 -252.487366) (xy 374.484126 -252.44209) (xy 374.510429 -252.400494) (xy 374.543064 -252.363657)
			(xy 374.581185 -252.332532) (xy 374.623806 -252.307925) (xy 374.669822 -252.290473) (xy 374.718041 -252.280629)
			(xy 374.767216 -252.278648) (xy 374.816071 -252.28458) (xy 374.863342 -252.298272) (xy 374.907804 -252.31937)
			(xy 374.948307 -252.347326) (xy 374.9838 -252.381418) (xy 375.013365 -252.420762) (xy 375.036236 -252.464339)
			(xy 375.05182 -252.51102) (xy 375.059715 -252.559597) (xy 375.06021 -252.584204) (xy 375.059715 -252.608811)
			(xy 375.05182 -252.657388) (xy 375.036236 -252.704069) (xy 375.013365 -252.747646) (xy 374.9838 -252.78699)
			(xy 374.948307 -252.821082) (xy 374.907804 -252.849038) (xy 374.863342 -252.870136) (xy 374.816071 -252.883828)
			(xy 374.767216 -252.88976) (xy 374.718041 -252.887779) (xy 374.669822 -252.877935) (xy 374.623806 -252.860483)
			(xy 374.581185 -252.835876) (xy 374.543064 -252.804751) (xy 374.510429 -252.767914) (xy 374.484126 -252.726318)
			(xy 374.464835 -252.681042) (xy 374.453058 -252.633258) (xy 374.449098 -252.584204) (xy 373.180102 -252.584204)
			(xy 373.179607 -252.608811) (xy 373.171712 -252.657388) (xy 373.156128 -252.704069) (xy 373.133257 -252.747646)
			(xy 373.103692 -252.78699) (xy 373.068199 -252.821082) (xy 373.027696 -252.849038) (xy 372.983234 -252.870136)
			(xy 372.935963 -252.883828) (xy 372.887108 -252.88976) (xy 372.837933 -252.887779) (xy 372.789714 -252.877935)
			(xy 372.743698 -252.860483) (xy 372.701077 -252.835876) (xy 372.662956 -252.804751) (xy 372.630321 -252.767914)
			(xy 372.604018 -252.726318) (xy 372.584727 -252.681042) (xy 372.57295 -252.633258) (xy 372.56899 -252.584204)
			(xy 371.299994 -252.584204) (xy 371.299499 -252.608811) (xy 371.291604 -252.657388) (xy 371.27602 -252.704069)
			(xy 371.253149 -252.747646) (xy 371.223584 -252.78699) (xy 371.188091 -252.821082) (xy 371.147588 -252.849038)
			(xy 371.103126 -252.870136) (xy 371.055855 -252.883828) (xy 371.007 -252.88976) (xy 370.957825 -252.887779)
			(xy 370.909606 -252.877935) (xy 370.86359 -252.860483) (xy 370.820969 -252.835876) (xy 370.782848 -252.804751)
			(xy 370.750213 -252.767914) (xy 370.72391 -252.726318) (xy 370.704619 -252.681042) (xy 370.692842 -252.633258)
			(xy 370.688882 -252.584204) (xy 369.42014 -252.584204) (xy 369.419645 -252.608811) (xy 369.41175 -252.657388)
			(xy 369.396166 -252.704069) (xy 369.373295 -252.747646) (xy 369.34373 -252.78699) (xy 369.308237 -252.821082)
			(xy 369.267734 -252.849038) (xy 369.223272 -252.870136) (xy 369.176001 -252.883828) (xy 369.127146 -252.88976)
			(xy 369.077971 -252.887779) (xy 369.029752 -252.877935) (xy 368.983736 -252.860483) (xy 368.941115 -252.835876)
			(xy 368.902994 -252.804751) (xy 368.870359 -252.767914) (xy 368.844056 -252.726318) (xy 368.824765 -252.681042)
			(xy 368.812988 -252.633258) (xy 368.809028 -252.584204) (xy 360.49716 -252.584204) (xy 360.493272 -252.592056)
			(xy 360.46298 -252.635122) (xy 360.426468 -252.67306) (xy 360.384594 -252.704979) (xy 360.338338 -252.730132)
			(xy 360.288785 -252.74793) (xy 360.237095 -252.757954) (xy 360.184481 -252.759971) (xy 360.132176 -252.753933)
			(xy 360.081405 -252.739981) (xy 360.03336 -252.718442) (xy 359.989165 -252.689822) (xy 359.949857 -252.654791)
			(xy 359.916357 -252.61417) (xy 359.889451 -252.568911) (xy 359.869768 -252.520076) (xy 359.857771 -252.468808)
			(xy 359.853741 -252.41631) (xy 351.202752 -252.41631) (xy 352.17862 -253.392178) (xy 353.302074 -253.392178)
			(xy 353.306034 -253.343124) (xy 353.317811 -253.29534) (xy 353.337102 -253.250064) (xy 353.363405 -253.208468)
			(xy 353.39604 -253.171631) (xy 353.434161 -253.140506) (xy 353.476782 -253.115899) (xy 353.522798 -253.098447)
			(xy 353.571017 -253.088603) (xy 353.620192 -253.086622) (xy 353.669047 -253.092554) (xy 353.716318 -253.106246)
			(xy 353.76078 -253.127344) (xy 353.801283 -253.1553) (xy 353.836776 -253.189392) (xy 353.866341 -253.228736)
			(xy 353.889212 -253.272313) (xy 353.904796 -253.318994) (xy 353.912691 -253.367571) (xy 353.913186 -253.392178)
			(xy 355.182182 -253.392178) (xy 355.186142 -253.343124) (xy 355.197919 -253.29534) (xy 355.21721 -253.250064)
			(xy 355.243513 -253.208468) (xy 355.276148 -253.171631) (xy 355.314269 -253.140506) (xy 355.35689 -253.115899)
			(xy 355.402906 -253.098447) (xy 355.451125 -253.088603) (xy 355.5003 -253.086622) (xy 355.549155 -253.092554)
			(xy 355.596426 -253.106246) (xy 355.640888 -253.127344) (xy 355.681391 -253.1553) (xy 355.716884 -253.189392)
			(xy 355.746449 -253.228736) (xy 355.76932 -253.272313) (xy 355.784904 -253.318994) (xy 355.792799 -253.367571)
			(xy 355.793294 -253.392178) (xy 357.06229 -253.392178) (xy 357.06625 -253.343124) (xy 357.078027 -253.29534)
			(xy 357.097318 -253.250064) (xy 357.123621 -253.208468) (xy 357.156256 -253.171631) (xy 357.194377 -253.140506)
			(xy 357.236998 -253.115899) (xy 357.283014 -253.098447) (xy 357.331233 -253.088603) (xy 357.380408 -253.086622)
			(xy 357.429263 -253.092554) (xy 357.476534 -253.106246) (xy 357.520996 -253.127344) (xy 357.561499 -253.1553)
			(xy 357.596992 -253.189392) (xy 357.626557 -253.228736) (xy 357.649428 -253.272313) (xy 357.665012 -253.318994)
			(xy 357.672907 -253.367571) (xy 357.673402 -253.392178) (xy 357.672907 -253.416785) (xy 357.670384 -253.43231)
			(xy 359.853741 -253.43231) (xy 359.857771 -253.379812) (xy 359.869768 -253.328544) (xy 359.889451 -253.279709)
			(xy 359.916357 -253.23445) (xy 359.949857 -253.193829) (xy 359.989165 -253.158798) (xy 360.03336 -253.130178)
			(xy 360.081405 -253.108639) (xy 360.132176 -253.094687) (xy 360.184481 -253.088649) (xy 360.237095 -253.090666)
			(xy 360.288785 -253.10069) (xy 360.338338 -253.118488) (xy 360.384594 -253.143641) (xy 360.426468 -253.17556)
			(xy 360.46298 -253.213498) (xy 360.493272 -253.256564) (xy 360.516635 -253.303749) (xy 360.532521 -253.353948)
			(xy 360.538426 -253.392178) (xy 360.822252 -253.392178) (xy 360.826212 -253.343124) (xy 360.837989 -253.29534)
			(xy 360.85728 -253.250064) (xy 360.883583 -253.208468) (xy 360.916218 -253.171631) (xy 360.954339 -253.140506)
			(xy 360.99696 -253.115899) (xy 361.042976 -253.098447) (xy 361.091195 -253.088603) (xy 361.14037 -253.086622)
			(xy 361.189225 -253.092554) (xy 361.236496 -253.106246) (xy 361.280958 -253.127344) (xy 361.321461 -253.1553)
			(xy 361.356954 -253.189392) (xy 361.386519 -253.228736) (xy 361.40939 -253.272313) (xy 361.424974 -253.318994)
			(xy 361.432869 -253.367571) (xy 361.433364 -253.392178) (xy 362.702106 -253.392178) (xy 362.706066 -253.343124)
			(xy 362.717843 -253.29534) (xy 362.737134 -253.250064) (xy 362.763437 -253.208468) (xy 362.796072 -253.171631)
			(xy 362.834193 -253.140506) (xy 362.876814 -253.115899) (xy 362.92283 -253.098447) (xy 362.971049 -253.088603)
			(xy 363.020224 -253.086622) (xy 363.069079 -253.092554) (xy 363.11635 -253.106246) (xy 363.160812 -253.127344)
			(xy 363.201315 -253.1553) (xy 363.236808 -253.189392) (xy 363.266373 -253.228736) (xy 363.289244 -253.272313)
			(xy 363.304828 -253.318994) (xy 363.312723 -253.367571) (xy 363.313218 -253.392178) (xy 364.582214 -253.392178)
			(xy 364.586174 -253.343124) (xy 364.597951 -253.29534) (xy 364.617242 -253.250064) (xy 364.643545 -253.208468)
			(xy 364.67618 -253.171631) (xy 364.714301 -253.140506) (xy 364.756922 -253.115899) (xy 364.802938 -253.098447)
			(xy 364.851157 -253.088603) (xy 364.900332 -253.086622) (xy 364.949187 -253.092554) (xy 364.996458 -253.106246)
			(xy 365.04092 -253.127344) (xy 365.081423 -253.1553) (xy 365.116916 -253.189392) (xy 365.146481 -253.228736)
			(xy 365.169352 -253.272313) (xy 365.184936 -253.318994) (xy 365.192831 -253.367571) (xy 365.193326 -253.392178)
			(xy 366.462068 -253.392178) (xy 366.466028 -253.343124) (xy 366.477805 -253.29534) (xy 366.497096 -253.250064)
			(xy 366.523399 -253.208468) (xy 366.556034 -253.171631) (xy 366.594155 -253.140506) (xy 366.636776 -253.115899)
			(xy 366.682792 -253.098447) (xy 366.731011 -253.088603) (xy 366.780186 -253.086622) (xy 366.829041 -253.092554)
			(xy 366.876312 -253.106246) (xy 366.920774 -253.127344) (xy 366.961277 -253.1553) (xy 366.99677 -253.189392)
			(xy 367.026335 -253.228736) (xy 367.049206 -253.272313) (xy 367.06479 -253.318994) (xy 367.072685 -253.367571)
			(xy 367.07318 -253.392178) (xy 367.073139 -253.39421) (xy 370.218982 -253.39421) (xy 370.222942 -253.345156)
			(xy 370.234719 -253.297372) (xy 370.25401 -253.252096) (xy 370.280313 -253.2105) (xy 370.312948 -253.173663)
			(xy 370.351069 -253.142538) (xy 370.39369 -253.117931) (xy 370.439706 -253.100479) (xy 370.487925 -253.090635)
			(xy 370.5371 -253.088654) (xy 370.585955 -253.094586) (xy 370.633226 -253.108278) (xy 370.677688 -253.129376)
			(xy 370.718191 -253.157332) (xy 370.753684 -253.191424) (xy 370.783249 -253.230768) (xy 370.80612 -253.274345)
			(xy 370.821704 -253.321026) (xy 370.829599 -253.369603) (xy 370.830094 -253.39421) (xy 372.09909 -253.39421)
			(xy 372.10305 -253.345156) (xy 372.114827 -253.297372) (xy 372.134118 -253.252096) (xy 372.160421 -253.2105)
			(xy 372.193056 -253.173663) (xy 372.231177 -253.142538) (xy 372.273798 -253.117931) (xy 372.319814 -253.100479)
			(xy 372.368033 -253.090635) (xy 372.417208 -253.088654) (xy 372.466063 -253.094586) (xy 372.513334 -253.108278)
			(xy 372.557796 -253.129376) (xy 372.598299 -253.157332) (xy 372.633792 -253.191424) (xy 372.663357 -253.230768)
			(xy 372.686228 -253.274345) (xy 372.701812 -253.321026) (xy 372.709707 -253.369603) (xy 372.710202 -253.39421)
			(xy 373.978944 -253.39421) (xy 373.982904 -253.345156) (xy 373.994681 -253.297372) (xy 374.013972 -253.252096)
			(xy 374.040275 -253.2105) (xy 374.07291 -253.173663) (xy 374.111031 -253.142538) (xy 374.153652 -253.117931)
			(xy 374.199668 -253.100479) (xy 374.247887 -253.090635) (xy 374.297062 -253.088654) (xy 374.345917 -253.094586)
			(xy 374.393188 -253.108278) (xy 374.43765 -253.129376) (xy 374.478153 -253.157332) (xy 374.513646 -253.191424)
			(xy 374.543211 -253.230768) (xy 374.566082 -253.274345) (xy 374.581666 -253.321026) (xy 374.589561 -253.369603)
			(xy 374.590056 -253.39421) (xy 374.589561 -253.418817) (xy 374.581666 -253.467394) (xy 374.566082 -253.514075)
			(xy 374.543211 -253.557652) (xy 374.513646 -253.596996) (xy 374.478153 -253.631088) (xy 374.43765 -253.659044)
			(xy 374.393188 -253.680142) (xy 374.345917 -253.693834) (xy 374.297062 -253.699766) (xy 374.247887 -253.697785)
			(xy 374.199668 -253.687941) (xy 374.153652 -253.670489) (xy 374.111031 -253.645882) (xy 374.07291 -253.614757)
			(xy 374.040275 -253.57792) (xy 374.013972 -253.536324) (xy 373.994681 -253.491048) (xy 373.982904 -253.443264)
			(xy 373.978944 -253.39421) (xy 372.710202 -253.39421) (xy 372.709707 -253.418817) (xy 372.701812 -253.467394)
			(xy 372.686228 -253.514075) (xy 372.663357 -253.557652) (xy 372.633792 -253.596996) (xy 372.598299 -253.631088)
			(xy 372.557796 -253.659044) (xy 372.513334 -253.680142) (xy 372.466063 -253.693834) (xy 372.417208 -253.699766)
			(xy 372.368033 -253.697785) (xy 372.319814 -253.687941) (xy 372.273798 -253.670489) (xy 372.231177 -253.645882)
			(xy 372.193056 -253.614757) (xy 372.160421 -253.57792) (xy 372.134118 -253.536324) (xy 372.114827 -253.491048)
			(xy 372.10305 -253.443264) (xy 372.09909 -253.39421) (xy 370.830094 -253.39421) (xy 370.829599 -253.418817)
			(xy 370.821704 -253.467394) (xy 370.80612 -253.514075) (xy 370.783249 -253.557652) (xy 370.753684 -253.596996)
			(xy 370.718191 -253.631088) (xy 370.677688 -253.659044) (xy 370.633226 -253.680142) (xy 370.585955 -253.693834)
			(xy 370.5371 -253.699766) (xy 370.487925 -253.697785) (xy 370.439706 -253.687941) (xy 370.39369 -253.670489)
			(xy 370.351069 -253.645882) (xy 370.312948 -253.614757) (xy 370.280313 -253.57792) (xy 370.25401 -253.536324)
			(xy 370.234719 -253.491048) (xy 370.222942 -253.443264) (xy 370.218982 -253.39421) (xy 367.073139 -253.39421)
			(xy 367.072685 -253.416785) (xy 367.06479 -253.465362) (xy 367.049206 -253.512043) (xy 367.026335 -253.55562)
			(xy 366.99677 -253.594964) (xy 366.961277 -253.629056) (xy 366.920774 -253.657012) (xy 366.876312 -253.67811)
			(xy 366.829041 -253.691802) (xy 366.780186 -253.697734) (xy 366.731011 -253.695753) (xy 366.682792 -253.685909)
			(xy 366.636776 -253.668457) (xy 366.594155 -253.64385) (xy 366.556034 -253.612725) (xy 366.523399 -253.575888)
			(xy 366.497096 -253.534292) (xy 366.477805 -253.489016) (xy 366.466028 -253.441232) (xy 366.462068 -253.392178)
			(xy 365.193326 -253.392178) (xy 365.192831 -253.416785) (xy 365.184936 -253.465362) (xy 365.169352 -253.512043)
			(xy 365.146481 -253.55562) (xy 365.116916 -253.594964) (xy 365.081423 -253.629056) (xy 365.04092 -253.657012)
			(xy 364.996458 -253.67811) (xy 364.949187 -253.691802) (xy 364.900332 -253.697734) (xy 364.851157 -253.695753)
			(xy 364.802938 -253.685909) (xy 364.756922 -253.668457) (xy 364.714301 -253.64385) (xy 364.67618 -253.612725)
			(xy 364.643545 -253.575888) (xy 364.617242 -253.534292) (xy 364.597951 -253.489016) (xy 364.586174 -253.441232)
			(xy 364.582214 -253.392178) (xy 363.313218 -253.392178) (xy 363.312723 -253.416785) (xy 363.304828 -253.465362)
			(xy 363.289244 -253.512043) (xy 363.266373 -253.55562) (xy 363.236808 -253.594964) (xy 363.201315 -253.629056)
			(xy 363.160812 -253.657012) (xy 363.11635 -253.67811) (xy 363.069079 -253.691802) (xy 363.020224 -253.697734)
			(xy 362.971049 -253.695753) (xy 362.92283 -253.685909) (xy 362.876814 -253.668457) (xy 362.834193 -253.64385)
			(xy 362.796072 -253.612725) (xy 362.763437 -253.575888) (xy 362.737134 -253.534292) (xy 362.717843 -253.489016)
			(xy 362.706066 -253.441232) (xy 362.702106 -253.392178) (xy 361.433364 -253.392178) (xy 361.432869 -253.416785)
			(xy 361.424974 -253.465362) (xy 361.40939 -253.512043) (xy 361.386519 -253.55562) (xy 361.356954 -253.594964)
			(xy 361.321461 -253.629056) (xy 361.280958 -253.657012) (xy 361.236496 -253.67811) (xy 361.189225 -253.691802)
			(xy 361.14037 -253.697734) (xy 361.091195 -253.695753) (xy 361.042976 -253.685909) (xy 360.99696 -253.668457)
			(xy 360.954339 -253.64385) (xy 360.916218 -253.612725) (xy 360.883583 -253.575888) (xy 360.85728 -253.534292)
			(xy 360.837989 -253.489016) (xy 360.826212 -253.441232) (xy 360.822252 -253.392178) (xy 360.538426 -253.392178)
			(xy 360.540558 -253.405984) (xy 360.541062 -253.43231) (xy 360.540558 -253.458636) (xy 360.532521 -253.510672)
			(xy 360.516635 -253.560871) (xy 360.493272 -253.608056) (xy 360.46298 -253.651122) (xy 360.426468 -253.68906)
			(xy 360.384594 -253.720979) (xy 360.338338 -253.746132) (xy 360.288785 -253.76393) (xy 360.237095 -253.773954)
			(xy 360.184481 -253.775971) (xy 360.132176 -253.769933) (xy 360.081405 -253.755981) (xy 360.03336 -253.734442)
			(xy 359.989165 -253.705822) (xy 359.949857 -253.670791) (xy 359.916357 -253.63017) (xy 359.889451 -253.584911)
			(xy 359.869768 -253.536076) (xy 359.857771 -253.484808) (xy 359.853741 -253.43231) (xy 357.670384 -253.43231)
			(xy 357.665012 -253.465362) (xy 357.649428 -253.512043) (xy 357.626557 -253.55562) (xy 357.596992 -253.594964)
			(xy 357.561499 -253.629056) (xy 357.520996 -253.657012) (xy 357.476534 -253.67811) (xy 357.429263 -253.691802)
			(xy 357.380408 -253.697734) (xy 357.331233 -253.695753) (xy 357.283014 -253.685909) (xy 357.236998 -253.668457)
			(xy 357.194377 -253.64385) (xy 357.156256 -253.612725) (xy 357.123621 -253.575888) (xy 357.097318 -253.534292)
			(xy 357.078027 -253.489016) (xy 357.06625 -253.441232) (xy 357.06229 -253.392178) (xy 355.793294 -253.392178)
			(xy 355.792799 -253.416785) (xy 355.784904 -253.465362) (xy 355.76932 -253.512043) (xy 355.746449 -253.55562)
			(xy 355.716884 -253.594964) (xy 355.681391 -253.629056) (xy 355.640888 -253.657012) (xy 355.596426 -253.67811)
			(xy 355.549155 -253.691802) (xy 355.5003 -253.697734) (xy 355.451125 -253.695753) (xy 355.402906 -253.685909)
			(xy 355.35689 -253.668457) (xy 355.314269 -253.64385) (xy 355.276148 -253.612725) (xy 355.243513 -253.575888)
			(xy 355.21721 -253.534292) (xy 355.197919 -253.489016) (xy 355.186142 -253.441232) (xy 355.182182 -253.392178)
			(xy 353.913186 -253.392178) (xy 353.912691 -253.416785) (xy 353.904796 -253.465362) (xy 353.889212 -253.512043)
			(xy 353.866341 -253.55562) (xy 353.836776 -253.594964) (xy 353.801283 -253.629056) (xy 353.76078 -253.657012)
			(xy 353.716318 -253.67811) (xy 353.669047 -253.691802) (xy 353.620192 -253.697734) (xy 353.571017 -253.695753)
			(xy 353.522798 -253.685909) (xy 353.476782 -253.668457) (xy 353.434161 -253.64385) (xy 353.39604 -253.612725)
			(xy 353.363405 -253.575888) (xy 353.337102 -253.534292) (xy 353.317811 -253.489016) (xy 353.306034 -253.441232)
			(xy 353.302074 -253.392178) (xy 352.17862 -253.392178) (xy 353.234752 -254.44831) (xy 359.853741 -254.44831)
			(xy 359.857771 -254.395812) (xy 359.869768 -254.344544) (xy 359.889451 -254.295709) (xy 359.916357 -254.25045)
			(xy 359.949857 -254.209829) (xy 359.989165 -254.174798) (xy 360.03336 -254.146178) (xy 360.081405 -254.124639)
			(xy 360.132176 -254.110687) (xy 360.184481 -254.104649) (xy 360.237095 -254.106666) (xy 360.288785 -254.11669)
			(xy 360.338338 -254.134488) (xy 360.384594 -254.159641) (xy 360.426468 -254.19156) (xy 360.438648 -254.204216)
			(xy 368.809028 -254.204216) (xy 368.812988 -254.155162) (xy 368.824765 -254.107378) (xy 368.844056 -254.062102)
			(xy 368.870359 -254.020506) (xy 368.902994 -253.983669) (xy 368.941115 -253.952544) (xy 368.983736 -253.927937)
			(xy 369.029752 -253.910485) (xy 369.077971 -253.900641) (xy 369.127146 -253.89866) (xy 369.176001 -253.904592)
			(xy 369.223272 -253.918284) (xy 369.267734 -253.939382) (xy 369.308237 -253.967338) (xy 369.34373 -254.00143)
			(xy 369.373295 -254.040774) (xy 369.396166 -254.084351) (xy 369.41175 -254.131032) (xy 369.419645 -254.179609)
			(xy 369.42014 -254.204216) (xy 370.688882 -254.204216) (xy 370.692842 -254.155162) (xy 370.704619 -254.107378)
			(xy 370.72391 -254.062102) (xy 370.750213 -254.020506) (xy 370.782848 -253.983669) (xy 370.820969 -253.952544)
			(xy 370.86359 -253.927937) (xy 370.909606 -253.910485) (xy 370.957825 -253.900641) (xy 371.007 -253.89866)
			(xy 371.055855 -253.904592) (xy 371.103126 -253.918284) (xy 371.147588 -253.939382) (xy 371.188091 -253.967338)
			(xy 371.223584 -254.00143) (xy 371.253149 -254.040774) (xy 371.27602 -254.084351) (xy 371.291604 -254.131032)
			(xy 371.299499 -254.179609) (xy 371.299994 -254.204216) (xy 372.56899 -254.204216) (xy 372.57295 -254.155162)
			(xy 372.584727 -254.107378) (xy 372.604018 -254.062102) (xy 372.630321 -254.020506) (xy 372.662956 -253.983669)
			(xy 372.701077 -253.952544) (xy 372.743698 -253.927937) (xy 372.789714 -253.910485) (xy 372.837933 -253.900641)
			(xy 372.887108 -253.89866) (xy 372.935963 -253.904592) (xy 372.983234 -253.918284) (xy 373.027696 -253.939382)
			(xy 373.068199 -253.967338) (xy 373.103692 -254.00143) (xy 373.133257 -254.040774) (xy 373.156128 -254.084351)
			(xy 373.171712 -254.131032) (xy 373.179607 -254.179609) (xy 373.180102 -254.204216) (xy 373.179607 -254.228823)
			(xy 373.171712 -254.2774) (xy 373.156128 -254.324081) (xy 373.133257 -254.367658) (xy 373.103692 -254.407002)
			(xy 373.068199 -254.441094) (xy 373.027696 -254.46905) (xy 372.983234 -254.490148) (xy 372.935963 -254.50384)
			(xy 372.887108 -254.509772) (xy 372.837933 -254.507791) (xy 372.789714 -254.497947) (xy 372.743698 -254.480495)
			(xy 372.701077 -254.455888) (xy 372.662956 -254.424763) (xy 372.630321 -254.387926) (xy 372.604018 -254.34633)
			(xy 372.584727 -254.301054) (xy 372.57295 -254.25327) (xy 372.56899 -254.204216) (xy 371.299994 -254.204216)
			(xy 371.299499 -254.228823) (xy 371.291604 -254.2774) (xy 371.27602 -254.324081) (xy 371.253149 -254.367658)
			(xy 371.223584 -254.407002) (xy 371.188091 -254.441094) (xy 371.147588 -254.46905) (xy 371.103126 -254.490148)
			(xy 371.055855 -254.50384) (xy 371.007 -254.509772) (xy 370.957825 -254.507791) (xy 370.909606 -254.497947)
			(xy 370.86359 -254.480495) (xy 370.820969 -254.455888) (xy 370.782848 -254.424763) (xy 370.750213 -254.387926)
			(xy 370.72391 -254.34633) (xy 370.704619 -254.301054) (xy 370.692842 -254.25327) (xy 370.688882 -254.204216)
			(xy 369.42014 -254.204216) (xy 369.419645 -254.228823) (xy 369.41175 -254.2774) (xy 369.396166 -254.324081)
			(xy 369.373295 -254.367658) (xy 369.34373 -254.407002) (xy 369.308237 -254.441094) (xy 369.267734 -254.46905)
			(xy 369.223272 -254.490148) (xy 369.176001 -254.50384) (xy 369.127146 -254.509772) (xy 369.077971 -254.507791)
			(xy 369.029752 -254.497947) (xy 368.983736 -254.480495) (xy 368.941115 -254.455888) (xy 368.902994 -254.424763)
			(xy 368.870359 -254.387926) (xy 368.844056 -254.34633) (xy 368.824765 -254.301054) (xy 368.812988 -254.25327)
			(xy 368.809028 -254.204216) (xy 360.438648 -254.204216) (xy 360.46298 -254.229498) (xy 360.493272 -254.272564)
			(xy 360.516635 -254.319749) (xy 360.532521 -254.369948) (xy 360.540558 -254.421984) (xy 360.541062 -254.44831)
			(xy 360.540558 -254.474636) (xy 360.532521 -254.526672) (xy 360.516635 -254.576871) (xy 360.493272 -254.624056)
			(xy 360.46298 -254.667122) (xy 360.426468 -254.70506) (xy 360.384594 -254.736979) (xy 360.338338 -254.762132)
			(xy 360.288785 -254.77993) (xy 360.237095 -254.789954) (xy 360.184481 -254.791971) (xy 360.132176 -254.785933)
			(xy 360.081405 -254.771981) (xy 360.03336 -254.750442) (xy 359.989165 -254.721822) (xy 359.949857 -254.686791)
			(xy 359.916357 -254.64617) (xy 359.889451 -254.600911) (xy 359.869768 -254.552076) (xy 359.857771 -254.500808)
			(xy 359.853741 -254.44831) (xy 353.234752 -254.44831) (xy 353.800664 -255.014222) (xy 370.218982 -255.014222)
			(xy 370.222942 -254.965168) (xy 370.234719 -254.917384) (xy 370.25401 -254.872108) (xy 370.280313 -254.830512)
			(xy 370.312948 -254.793675) (xy 370.351069 -254.76255) (xy 370.39369 -254.737943) (xy 370.439706 -254.720491)
			(xy 370.487925 -254.710647) (xy 370.5371 -254.708666) (xy 370.585955 -254.714598) (xy 370.633226 -254.72829)
			(xy 370.677688 -254.749388) (xy 370.718191 -254.777344) (xy 370.753684 -254.811436) (xy 370.783249 -254.85078)
			(xy 370.80612 -254.894357) (xy 370.821704 -254.941038) (xy 370.829599 -254.989615) (xy 370.830094 -255.014222)
			(xy 372.09909 -255.014222) (xy 372.10305 -254.965168) (xy 372.114827 -254.917384) (xy 372.134118 -254.872108)
			(xy 372.160421 -254.830512) (xy 372.193056 -254.793675) (xy 372.231177 -254.76255) (xy 372.273798 -254.737943)
			(xy 372.319814 -254.720491) (xy 372.368033 -254.710647) (xy 372.417208 -254.708666) (xy 372.466063 -254.714598)
			(xy 372.513334 -254.72829) (xy 372.557796 -254.749388) (xy 372.598299 -254.777344) (xy 372.633792 -254.811436)
			(xy 372.663357 -254.85078) (xy 372.686228 -254.894357) (xy 372.701812 -254.941038) (xy 372.709707 -254.989615)
			(xy 372.710202 -255.014222) (xy 373.978944 -255.014222) (xy 373.982904 -254.965168) (xy 373.994681 -254.917384)
			(xy 374.013972 -254.872108) (xy 374.040275 -254.830512) (xy 374.07291 -254.793675) (xy 374.111031 -254.76255)
			(xy 374.153652 -254.737943) (xy 374.199668 -254.720491) (xy 374.247887 -254.710647) (xy 374.297062 -254.708666)
			(xy 374.345917 -254.714598) (xy 374.393188 -254.72829) (xy 374.43765 -254.749388) (xy 374.478153 -254.777344)
			(xy 374.513646 -254.811436) (xy 374.543211 -254.85078) (xy 374.566082 -254.894357) (xy 374.581666 -254.941038)
			(xy 374.589561 -254.989615) (xy 374.590056 -255.014222) (xy 374.589561 -255.038829) (xy 374.581666 -255.087406)
			(xy 374.566082 -255.134087) (xy 374.543211 -255.177664) (xy 374.513646 -255.217008) (xy 374.478153 -255.2511)
			(xy 374.43765 -255.279056) (xy 374.393188 -255.300154) (xy 374.345917 -255.313846) (xy 374.297062 -255.319778)
			(xy 374.247887 -255.317797) (xy 374.199668 -255.307953) (xy 374.153652 -255.290501) (xy 374.111031 -255.265894)
			(xy 374.07291 -255.234769) (xy 374.040275 -255.197932) (xy 374.013972 -255.156336) (xy 373.994681 -255.11106)
			(xy 373.982904 -255.063276) (xy 373.978944 -255.014222) (xy 372.710202 -255.014222) (xy 372.709707 -255.038829)
			(xy 372.701812 -255.087406) (xy 372.686228 -255.134087) (xy 372.663357 -255.177664) (xy 372.633792 -255.217008)
			(xy 372.598299 -255.2511) (xy 372.557796 -255.279056) (xy 372.513334 -255.300154) (xy 372.466063 -255.313846)
			(xy 372.417208 -255.319778) (xy 372.368033 -255.317797) (xy 372.319814 -255.307953) (xy 372.273798 -255.290501)
			(xy 372.231177 -255.265894) (xy 372.193056 -255.234769) (xy 372.160421 -255.197932) (xy 372.134118 -255.156336)
			(xy 372.114827 -255.11106) (xy 372.10305 -255.063276) (xy 372.09909 -255.014222) (xy 370.830094 -255.014222)
			(xy 370.829599 -255.038829) (xy 370.821704 -255.087406) (xy 370.80612 -255.134087) (xy 370.783249 -255.177664)
			(xy 370.753684 -255.217008) (xy 370.718191 -255.2511) (xy 370.677688 -255.279056) (xy 370.633226 -255.300154)
			(xy 370.585955 -255.313846) (xy 370.5371 -255.319778) (xy 370.487925 -255.317797) (xy 370.439706 -255.307953)
			(xy 370.39369 -255.290501) (xy 370.351069 -255.265894) (xy 370.312948 -255.234769) (xy 370.280313 -255.197932)
			(xy 370.25401 -255.156336) (xy 370.234719 -255.11106) (xy 370.222942 -255.063276) (xy 370.218982 -255.014222)
			(xy 353.800664 -255.014222) (xy 354.039424 -255.252982) (xy 354.046391 -255.259294) (xy 354.063591 -255.266843)
			(xy 354.072952 -255.267714) (xy 354.094796 -255.26873) (xy 354.099579 -255.26881) (xy 354.109038 -255.267401)
			(xy 354.113592 -255.265936) (xy 354.134674 -255.258824) (xy 354.141024 -255.253998) (xy 354.16333 -255.238157)
			(xy 354.211914 -255.213009) (xy 354.263871 -255.195883) (xy 354.317887 -255.187213) (xy 354.34524 -255.186688)
			(xy 354.372223 -255.18722) (xy 354.425524 -255.195668) (xy 354.476848 -255.212349) (xy 354.524931 -255.236853)
			(xy 354.568588 -255.268577) (xy 354.606747 -255.306739) (xy 354.638466 -255.3504) (xy 354.662965 -255.398485)
			(xy 354.67964 -255.449811) (xy 354.688083 -255.503113) (xy 354.688648 -255.530096) (xy 365.036865 -255.530096)
			(xy 365.040895 -255.477598) (xy 365.052892 -255.42633) (xy 365.072575 -255.377495) (xy 365.099481 -255.332236)
			(xy 365.132981 -255.291615) (xy 365.172289 -255.256584) (xy 365.216484 -255.227964) (xy 365.264529 -255.206425)
			(xy 365.3153 -255.192473) (xy 365.367605 -255.186435) (xy 365.420219 -255.188452) (xy 365.471909 -255.198476)
			(xy 365.521462 -255.216274) (xy 365.567718 -255.241427) (xy 365.609592 -255.273346) (xy 365.646104 -255.311284)
			(xy 365.676396 -255.35435) (xy 365.699759 -255.401535) (xy 365.715645 -255.451734) (xy 365.723682 -255.50377)
			(xy 365.724186 -255.530096) (xy 365.723682 -255.556422) (xy 365.715645 -255.608458) (xy 365.699759 -255.658657)
			(xy 365.676396 -255.705842) (xy 365.646104 -255.748908) (xy 365.609592 -255.786846) (xy 365.567718 -255.818765)
			(xy 365.557672 -255.824228) (xy 368.809028 -255.824228) (xy 368.812988 -255.775174) (xy 368.824765 -255.72739)
			(xy 368.844056 -255.682114) (xy 368.870359 -255.640518) (xy 368.902994 -255.603681) (xy 368.941115 -255.572556)
			(xy 368.983736 -255.547949) (xy 369.029752 -255.530497) (xy 369.077971 -255.520653) (xy 369.127146 -255.518672)
			(xy 369.176001 -255.524604) (xy 369.223272 -255.538296) (xy 369.267734 -255.559394) (xy 369.308237 -255.58735)
			(xy 369.34373 -255.621442) (xy 369.373295 -255.660786) (xy 369.396166 -255.704363) (xy 369.41175 -255.751044)
			(xy 369.419645 -255.799621) (xy 369.42014 -255.824228) (xy 370.688882 -255.824228) (xy 370.692842 -255.775174)
			(xy 370.704619 -255.72739) (xy 370.72391 -255.682114) (xy 370.750213 -255.640518) (xy 370.782848 -255.603681)
			(xy 370.820969 -255.572556) (xy 370.86359 -255.547949) (xy 370.909606 -255.530497) (xy 370.957825 -255.520653)
			(xy 371.007 -255.518672) (xy 371.055855 -255.524604) (xy 371.103126 -255.538296) (xy 371.147588 -255.559394)
			(xy 371.188091 -255.58735) (xy 371.223584 -255.621442) (xy 371.253149 -255.660786) (xy 371.27602 -255.704363)
			(xy 371.291604 -255.751044) (xy 371.299499 -255.799621) (xy 371.299994 -255.824228) (xy 372.56899 -255.824228)
			(xy 372.57295 -255.775174) (xy 372.584727 -255.72739) (xy 372.604018 -255.682114) (xy 372.630321 -255.640518)
			(xy 372.662956 -255.603681) (xy 372.701077 -255.572556) (xy 372.743698 -255.547949) (xy 372.789714 -255.530497)
			(xy 372.837933 -255.520653) (xy 372.887108 -255.518672) (xy 372.935963 -255.524604) (xy 372.983234 -255.538296)
			(xy 373.027696 -255.559394) (xy 373.068199 -255.58735) (xy 373.103692 -255.621442) (xy 373.133257 -255.660786)
			(xy 373.156128 -255.704363) (xy 373.171712 -255.751044) (xy 373.179607 -255.799621) (xy 373.180102 -255.824228)
			(xy 373.179607 -255.848835) (xy 373.171712 -255.897412) (xy 373.156128 -255.944093) (xy 373.133257 -255.98767)
			(xy 373.103692 -256.027014) (xy 373.068199 -256.061106) (xy 373.027696 -256.089062) (xy 372.983234 -256.11016)
			(xy 372.935963 -256.123852) (xy 372.887108 -256.129784) (xy 372.837933 -256.127803) (xy 372.789714 -256.117959)
			(xy 372.743698 -256.100507) (xy 372.701077 -256.0759) (xy 372.662956 -256.044775) (xy 372.630321 -256.007938)
			(xy 372.604018 -255.966342) (xy 372.584727 -255.921066) (xy 372.57295 -255.873282) (xy 372.56899 -255.824228)
			(xy 371.299994 -255.824228) (xy 371.299499 -255.848835) (xy 371.291604 -255.897412) (xy 371.27602 -255.944093)
			(xy 371.253149 -255.98767) (xy 371.223584 -256.027014) (xy 371.188091 -256.061106) (xy 371.147588 -256.089062)
			(xy 371.103126 -256.11016) (xy 371.055855 -256.123852) (xy 371.007 -256.129784) (xy 370.957825 -256.127803)
			(xy 370.909606 -256.117959) (xy 370.86359 -256.100507) (xy 370.820969 -256.0759) (xy 370.782848 -256.044775)
			(xy 370.750213 -256.007938) (xy 370.72391 -255.966342) (xy 370.704619 -255.921066) (xy 370.692842 -255.873282)
			(xy 370.688882 -255.824228) (xy 369.42014 -255.824228) (xy 369.419645 -255.848835) (xy 369.41175 -255.897412)
			(xy 369.396166 -255.944093) (xy 369.373295 -255.98767) (xy 369.34373 -256.027014) (xy 369.308237 -256.061106)
			(xy 369.267734 -256.089062) (xy 369.223272 -256.11016) (xy 369.176001 -256.123852) (xy 369.127146 -256.129784)
			(xy 369.077971 -256.127803) (xy 369.029752 -256.117959) (xy 368.983736 -256.100507) (xy 368.941115 -256.0759)
			(xy 368.902994 -256.044775) (xy 368.870359 -256.007938) (xy 368.844056 -255.966342) (xy 368.824765 -255.921066)
			(xy 368.812988 -255.873282) (xy 368.809028 -255.824228) (xy 365.557672 -255.824228) (xy 365.521462 -255.843918)
			(xy 365.471909 -255.861716) (xy 365.420219 -255.87174) (xy 365.367605 -255.873757) (xy 365.3153 -255.867719)
			(xy 365.264529 -255.853767) (xy 365.216484 -255.832228) (xy 365.172289 -255.803608) (xy 365.132981 -255.768577)
			(xy 365.099481 -255.727956) (xy 365.072575 -255.682697) (xy 365.052892 -255.633862) (xy 365.040895 -255.582594)
			(xy 365.036865 -255.530096) (xy 354.688648 -255.530096) (xy 354.688155 -255.55637) (xy 354.68016 -255.608305)
			(xy 354.664339 -255.658414) (xy 354.641065 -255.705525) (xy 354.610879 -255.748538) (xy 354.574489 -255.786445)
			(xy 354.532745 -255.818361) (xy 354.486623 -255.84354) (xy 354.46208 -255.85293) (xy 354.44684 -255.858518)
			(xy 354.428552 -255.88468) (xy 354.428552 -256.049526) (xy 354.428981 -256.059593) (xy 354.436708 -256.078186)
			(xy 354.443538 -256.085594) (xy 354.74529 -256.387346) (xy 355.244149 -256.387346) (xy 355.248179 -256.334848)
			(xy 355.260176 -256.28358) (xy 355.279859 -256.234745) (xy 355.306765 -256.189486) (xy 355.340265 -256.148865)
			(xy 355.379573 -256.113834) (xy 355.423768 -256.085214) (xy 355.471813 -256.063675) (xy 355.522584 -256.049723)
			(xy 355.574889 -256.043685) (xy 355.627503 -256.045702) (xy 355.679193 -256.055726) (xy 355.728746 -256.073524)
			(xy 355.775002 -256.098677) (xy 355.816876 -256.130596) (xy 355.853388 -256.168534) (xy 355.88368 -256.2116)
			(xy 355.907043 -256.258785) (xy 355.922929 -256.308984) (xy 355.930966 -256.36102) (xy 355.93147 -256.387346)
			(xy 356.194109 -256.387346) (xy 356.198139 -256.334848) (xy 356.210136 -256.28358) (xy 356.229819 -256.234745)
			(xy 356.256725 -256.189486) (xy 356.290225 -256.148865) (xy 356.329533 -256.113834) (xy 356.373728 -256.085214)
			(xy 356.421773 -256.063675) (xy 356.472544 -256.049723) (xy 356.524849 -256.043685) (xy 356.577463 -256.045702)
			(xy 356.629153 -256.055726) (xy 356.678706 -256.073524) (xy 356.724962 -256.098677) (xy 356.766836 -256.130596)
			(xy 356.803348 -256.168534) (xy 356.83364 -256.2116) (xy 356.857003 -256.258785) (xy 356.872889 -256.308984)
			(xy 356.880926 -256.36102) (xy 356.88143 -256.387346) (xy 357.144069 -256.387346) (xy 357.148099 -256.334848)
			(xy 357.160096 -256.28358) (xy 357.179779 -256.234745) (xy 357.206685 -256.189486) (xy 357.240185 -256.148865)
			(xy 357.279493 -256.113834) (xy 357.323688 -256.085214) (xy 357.371733 -256.063675) (xy 357.422504 -256.049723)
			(xy 357.474809 -256.043685) (xy 357.527423 -256.045702) (xy 357.579113 -256.055726) (xy 357.628666 -256.073524)
			(xy 357.674922 -256.098677) (xy 357.716796 -256.130596) (xy 357.753308 -256.168534) (xy 357.7836 -256.2116)
			(xy 357.806963 -256.258785) (xy 357.822849 -256.308984) (xy 357.830886 -256.36102) (xy 357.83139 -256.387346)
			(xy 358.094029 -256.387346) (xy 358.098059 -256.334848) (xy 358.110056 -256.28358) (xy 358.129739 -256.234745)
			(xy 358.156645 -256.189486) (xy 358.190145 -256.148865) (xy 358.229453 -256.113834) (xy 358.273648 -256.085214)
			(xy 358.321693 -256.063675) (xy 358.372464 -256.049723) (xy 358.424769 -256.043685) (xy 358.477383 -256.045702)
			(xy 358.529073 -256.055726) (xy 358.578626 -256.073524) (xy 358.624882 -256.098677) (xy 358.666756 -256.130596)
			(xy 358.703268 -256.168534) (xy 358.73356 -256.2116) (xy 358.756923 -256.258785) (xy 358.772809 -256.308984)
			(xy 358.780846 -256.36102) (xy 358.78135 -256.387346) (xy 359.043989 -256.387346) (xy 359.048019 -256.334848)
			(xy 359.060016 -256.28358) (xy 359.079699 -256.234745) (xy 359.106605 -256.189486) (xy 359.140105 -256.148865)
			(xy 359.179413 -256.113834) (xy 359.223608 -256.085214) (xy 359.271653 -256.063675) (xy 359.322424 -256.049723)
			(xy 359.374729 -256.043685) (xy 359.427343 -256.045702) (xy 359.479033 -256.055726) (xy 359.528586 -256.073524)
			(xy 359.574842 -256.098677) (xy 359.616716 -256.130596) (xy 359.653228 -256.168534) (xy 359.68352 -256.2116)
			(xy 359.706883 -256.258785) (xy 359.722769 -256.308984) (xy 359.730806 -256.36102) (xy 359.73131 -256.387346)
			(xy 359.993949 -256.387346) (xy 359.997979 -256.334848) (xy 360.009976 -256.28358) (xy 360.029659 -256.234745)
			(xy 360.056565 -256.189486) (xy 360.090065 -256.148865) (xy 360.129373 -256.113834) (xy 360.173568 -256.085214)
			(xy 360.221613 -256.063675) (xy 360.272384 -256.049723) (xy 360.324689 -256.043685) (xy 360.377303 -256.045702)
			(xy 360.428993 -256.055726) (xy 360.478546 -256.073524) (xy 360.524802 -256.098677) (xy 360.566676 -256.130596)
			(xy 360.603188 -256.168534) (xy 360.63348 -256.2116) (xy 360.656843 -256.258785) (xy 360.672729 -256.308984)
			(xy 360.680766 -256.36102) (xy 360.68127 -256.387346) (xy 360.944163 -256.387346) (xy 360.948193 -256.334848)
			(xy 360.96019 -256.28358) (xy 360.979873 -256.234745) (xy 361.006779 -256.189486) (xy 361.040279 -256.148865)
			(xy 361.079587 -256.113834) (xy 361.123782 -256.085214) (xy 361.171827 -256.063675) (xy 361.222598 -256.049723)
			(xy 361.274903 -256.043685) (xy 361.327517 -256.045702) (xy 361.379207 -256.055726) (xy 361.42876 -256.073524)
			(xy 361.475016 -256.098677) (xy 361.51689 -256.130596) (xy 361.553402 -256.168534) (xy 361.583694 -256.2116)
			(xy 361.607057 -256.258785) (xy 361.622943 -256.308984) (xy 361.63098 -256.36102) (xy 361.631484 -256.387346)
			(xy 361.894123 -256.387346) (xy 361.898153 -256.334848) (xy 361.91015 -256.28358) (xy 361.929833 -256.234745)
			(xy 361.956739 -256.189486) (xy 361.990239 -256.148865) (xy 362.029547 -256.113834) (xy 362.073742 -256.085214)
			(xy 362.121787 -256.063675) (xy 362.172558 -256.049723) (xy 362.224863 -256.043685) (xy 362.277477 -256.045702)
			(xy 362.329167 -256.055726) (xy 362.37872 -256.073524) (xy 362.424976 -256.098677) (xy 362.46685 -256.130596)
			(xy 362.503362 -256.168534) (xy 362.533654 -256.2116) (xy 362.557017 -256.258785) (xy 362.572903 -256.308984)
			(xy 362.58094 -256.36102) (xy 362.581444 -256.387346) (xy 362.844083 -256.387346) (xy 362.848113 -256.334848)
			(xy 362.86011 -256.28358) (xy 362.879793 -256.234745) (xy 362.906699 -256.189486) (xy 362.940199 -256.148865)
			(xy 362.979507 -256.113834) (xy 363.023702 -256.085214) (xy 363.071747 -256.063675) (xy 363.122518 -256.049723)
			(xy 363.174823 -256.043685) (xy 363.227437 -256.045702) (xy 363.279127 -256.055726) (xy 363.32868 -256.073524)
			(xy 363.374936 -256.098677) (xy 363.41681 -256.130596) (xy 363.453322 -256.168534) (xy 363.483614 -256.2116)
			(xy 363.506977 -256.258785) (xy 363.522863 -256.308984) (xy 363.5309 -256.36102) (xy 363.531404 -256.387346)
			(xy 363.794043 -256.387346) (xy 363.798073 -256.334848) (xy 363.81007 -256.28358) (xy 363.829753 -256.234745)
			(xy 363.856659 -256.189486) (xy 363.890159 -256.148865) (xy 363.929467 -256.113834) (xy 363.973662 -256.085214)
			(xy 364.021707 -256.063675) (xy 364.072478 -256.049723) (xy 364.124783 -256.043685) (xy 364.177397 -256.045702)
			(xy 364.229087 -256.055726) (xy 364.27864 -256.073524) (xy 364.324896 -256.098677) (xy 364.36677 -256.130596)
			(xy 364.403282 -256.168534) (xy 364.433574 -256.2116) (xy 364.456937 -256.258785) (xy 364.472823 -256.308984)
			(xy 364.48086 -256.36102) (xy 364.481364 -256.387346) (xy 364.48086 -256.413672) (xy 364.472823 -256.465708)
			(xy 364.468282 -256.480056) (xy 365.036865 -256.480056) (xy 365.040895 -256.427558) (xy 365.052892 -256.37629)
			(xy 365.072575 -256.327455) (xy 365.099481 -256.282196) (xy 365.132981 -256.241575) (xy 365.172289 -256.206544)
			(xy 365.216484 -256.177924) (xy 365.264529 -256.156385) (xy 365.3153 -256.142433) (xy 365.367605 -256.136395)
			(xy 365.420219 -256.138412) (xy 365.471909 -256.148436) (xy 365.521462 -256.166234) (xy 365.567718 -256.191387)
			(xy 365.609592 -256.223306) (xy 365.646104 -256.261244) (xy 365.676396 -256.30431) (xy 365.699759 -256.351495)
			(xy 365.715645 -256.401694) (xy 365.723682 -256.45373) (xy 365.724186 -256.480056) (xy 365.723682 -256.506382)
			(xy 365.715645 -256.558418) (xy 365.699759 -256.608617) (xy 365.687075 -256.634234) (xy 370.218982 -256.634234)
			(xy 370.222942 -256.58518) (xy 370.234719 -256.537396) (xy 370.25401 -256.49212) (xy 370.280313 -256.450524)
			(xy 370.312948 -256.413687) (xy 370.351069 -256.382562) (xy 370.39369 -256.357955) (xy 370.439706 -256.340503)
			(xy 370.487925 -256.330659) (xy 370.5371 -256.328678) (xy 370.585955 -256.33461) (xy 370.633226 -256.348302)
			(xy 370.677688 -256.3694) (xy 370.718191 -256.397356) (xy 370.753684 -256.431448) (xy 370.783249 -256.470792)
			(xy 370.80612 -256.514369) (xy 370.821704 -256.56105) (xy 370.829599 -256.609627) (xy 370.830094 -256.634234)
			(xy 372.09909 -256.634234) (xy 372.10305 -256.58518) (xy 372.114827 -256.537396) (xy 372.134118 -256.49212)
			(xy 372.160421 -256.450524) (xy 372.193056 -256.413687) (xy 372.231177 -256.382562) (xy 372.273798 -256.357955)
			(xy 372.319814 -256.340503) (xy 372.368033 -256.330659) (xy 372.417208 -256.328678) (xy 372.466063 -256.33461)
			(xy 372.513334 -256.348302) (xy 372.557796 -256.3694) (xy 372.598299 -256.397356) (xy 372.633792 -256.431448)
			(xy 372.663357 -256.470792) (xy 372.686228 -256.514369) (xy 372.701812 -256.56105) (xy 372.709707 -256.609627)
			(xy 372.710202 -256.634234) (xy 373.978944 -256.634234) (xy 373.982904 -256.58518) (xy 373.994681 -256.537396)
			(xy 374.013972 -256.49212) (xy 374.040275 -256.450524) (xy 374.07291 -256.413687) (xy 374.111031 -256.382562)
			(xy 374.153652 -256.357955) (xy 374.199668 -256.340503) (xy 374.247887 -256.330659) (xy 374.297062 -256.328678)
			(xy 374.345917 -256.33461) (xy 374.393188 -256.348302) (xy 374.43765 -256.3694) (xy 374.478153 -256.397356)
			(xy 374.513646 -256.431448) (xy 374.543211 -256.470792) (xy 374.566082 -256.514369) (xy 374.581666 -256.56105)
			(xy 374.589561 -256.609627) (xy 374.590056 -256.634234) (xy 374.589561 -256.658841) (xy 374.581666 -256.707418)
			(xy 374.566082 -256.754099) (xy 374.543211 -256.797676) (xy 374.513646 -256.83702) (xy 374.478153 -256.871112)
			(xy 374.43765 -256.899068) (xy 374.393188 -256.920166) (xy 374.345917 -256.933858) (xy 374.297062 -256.93979)
			(xy 374.247887 -256.937809) (xy 374.199668 -256.927965) (xy 374.153652 -256.910513) (xy 374.111031 -256.885906)
			(xy 374.07291 -256.854781) (xy 374.040275 -256.817944) (xy 374.013972 -256.776348) (xy 373.994681 -256.731072)
			(xy 373.982904 -256.683288) (xy 373.978944 -256.634234) (xy 372.710202 -256.634234) (xy 372.709707 -256.658841)
			(xy 372.701812 -256.707418) (xy 372.686228 -256.754099) (xy 372.663357 -256.797676) (xy 372.633792 -256.83702)
			(xy 372.598299 -256.871112) (xy 372.557796 -256.899068) (xy 372.513334 -256.920166) (xy 372.466063 -256.933858)
			(xy 372.417208 -256.93979) (xy 372.368033 -256.937809) (xy 372.319814 -256.927965) (xy 372.273798 -256.910513)
			(xy 372.231177 -256.885906) (xy 372.193056 -256.854781) (xy 372.160421 -256.817944) (xy 372.134118 -256.776348)
			(xy 372.114827 -256.731072) (xy 372.10305 -256.683288) (xy 372.09909 -256.634234) (xy 370.830094 -256.634234)
			(xy 370.829599 -256.658841) (xy 370.821704 -256.707418) (xy 370.80612 -256.754099) (xy 370.783249 -256.797676)
			(xy 370.753684 -256.83702) (xy 370.718191 -256.871112) (xy 370.677688 -256.899068) (xy 370.633226 -256.920166)
			(xy 370.585955 -256.933858) (xy 370.5371 -256.93979) (xy 370.487925 -256.937809) (xy 370.439706 -256.927965)
			(xy 370.39369 -256.910513) (xy 370.351069 -256.885906) (xy 370.312948 -256.854781) (xy 370.280313 -256.817944)
			(xy 370.25401 -256.776348) (xy 370.234719 -256.731072) (xy 370.222942 -256.683288) (xy 370.218982 -256.634234)
			(xy 365.687075 -256.634234) (xy 365.676396 -256.655802) (xy 365.646104 -256.698868) (xy 365.609592 -256.736806)
			(xy 365.567718 -256.768725) (xy 365.521462 -256.793878) (xy 365.471909 -256.811676) (xy 365.420219 -256.8217)
			(xy 365.367605 -256.823717) (xy 365.3153 -256.817679) (xy 365.264529 -256.803727) (xy 365.216484 -256.782188)
			(xy 365.172289 -256.753568) (xy 365.132981 -256.718537) (xy 365.099481 -256.677916) (xy 365.072575 -256.632657)
			(xy 365.052892 -256.583822) (xy 365.040895 -256.532554) (xy 365.036865 -256.480056) (xy 364.468282 -256.480056)
			(xy 364.456937 -256.515907) (xy 364.433574 -256.563092) (xy 364.403282 -256.606158) (xy 364.36677 -256.644096)
			(xy 364.324896 -256.676015) (xy 364.27864 -256.701168) (xy 364.229087 -256.718966) (xy 364.177397 -256.72899)
			(xy 364.124783 -256.731007) (xy 364.072478 -256.724969) (xy 364.021707 -256.711017) (xy 363.973662 -256.689478)
			(xy 363.929467 -256.660858) (xy 363.890159 -256.625827) (xy 363.856659 -256.585206) (xy 363.829753 -256.539947)
			(xy 363.81007 -256.491112) (xy 363.798073 -256.439844) (xy 363.794043 -256.387346) (xy 363.531404 -256.387346)
			(xy 363.5309 -256.413672) (xy 363.522863 -256.465708) (xy 363.506977 -256.515907) (xy 363.483614 -256.563092)
			(xy 363.453322 -256.606158) (xy 363.41681 -256.644096) (xy 363.374936 -256.676015) (xy 363.32868 -256.701168)
			(xy 363.279127 -256.718966) (xy 363.227437 -256.72899) (xy 363.174823 -256.731007) (xy 363.122518 -256.724969)
			(xy 363.071747 -256.711017) (xy 363.023702 -256.689478) (xy 362.979507 -256.660858) (xy 362.940199 -256.625827)
			(xy 362.906699 -256.585206) (xy 362.879793 -256.539947) (xy 362.86011 -256.491112) (xy 362.848113 -256.439844)
			(xy 362.844083 -256.387346) (xy 362.581444 -256.387346) (xy 362.58094 -256.413672) (xy 362.572903 -256.465708)
			(xy 362.557017 -256.515907) (xy 362.533654 -256.563092) (xy 362.503362 -256.606158) (xy 362.46685 -256.644096)
			(xy 362.424976 -256.676015) (xy 362.37872 -256.701168) (xy 362.329167 -256.718966) (xy 362.277477 -256.72899)
			(xy 362.224863 -256.731007) (xy 362.172558 -256.724969) (xy 362.121787 -256.711017) (xy 362.073742 -256.689478)
			(xy 362.029547 -256.660858) (xy 361.990239 -256.625827) (xy 361.956739 -256.585206) (xy 361.929833 -256.539947)
			(xy 361.91015 -256.491112) (xy 361.898153 -256.439844) (xy 361.894123 -256.387346) (xy 361.631484 -256.387346)
			(xy 361.63098 -256.413672) (xy 361.622943 -256.465708) (xy 361.607057 -256.515907) (xy 361.583694 -256.563092)
			(xy 361.553402 -256.606158) (xy 361.51689 -256.644096) (xy 361.475016 -256.676015) (xy 361.42876 -256.701168)
			(xy 361.379207 -256.718966) (xy 361.327517 -256.72899) (xy 361.274903 -256.731007) (xy 361.222598 -256.724969)
			(xy 361.171827 -256.711017) (xy 361.123782 -256.689478) (xy 361.079587 -256.660858) (xy 361.040279 -256.625827)
			(xy 361.006779 -256.585206) (xy 360.979873 -256.539947) (xy 360.96019 -256.491112) (xy 360.948193 -256.439844)
			(xy 360.944163 -256.387346) (xy 360.68127 -256.387346) (xy 360.680766 -256.413672) (xy 360.672729 -256.465708)
			(xy 360.656843 -256.515907) (xy 360.63348 -256.563092) (xy 360.603188 -256.606158) (xy 360.566676 -256.644096)
			(xy 360.524802 -256.676015) (xy 360.478546 -256.701168) (xy 360.428993 -256.718966) (xy 360.377303 -256.72899)
			(xy 360.324689 -256.731007) (xy 360.272384 -256.724969) (xy 360.221613 -256.711017) (xy 360.173568 -256.689478)
			(xy 360.129373 -256.660858) (xy 360.090065 -256.625827) (xy 360.056565 -256.585206) (xy 360.029659 -256.539947)
			(xy 360.009976 -256.491112) (xy 359.997979 -256.439844) (xy 359.993949 -256.387346) (xy 359.73131 -256.387346)
			(xy 359.730806 -256.413672) (xy 359.722769 -256.465708) (xy 359.706883 -256.515907) (xy 359.68352 -256.563092)
			(xy 359.653228 -256.606158) (xy 359.616716 -256.644096) (xy 359.574842 -256.676015) (xy 359.528586 -256.701168)
			(xy 359.479033 -256.718966) (xy 359.427343 -256.72899) (xy 359.374729 -256.731007) (xy 359.322424 -256.724969)
			(xy 359.271653 -256.711017) (xy 359.223608 -256.689478) (xy 359.179413 -256.660858) (xy 359.140105 -256.625827)
			(xy 359.106605 -256.585206) (xy 359.079699 -256.539947) (xy 359.060016 -256.491112) (xy 359.048019 -256.439844)
			(xy 359.043989 -256.387346) (xy 358.78135 -256.387346) (xy 358.780846 -256.413672) (xy 358.772809 -256.465708)
			(xy 358.756923 -256.515907) (xy 358.73356 -256.563092) (xy 358.703268 -256.606158) (xy 358.666756 -256.644096)
			(xy 358.624882 -256.676015) (xy 358.578626 -256.701168) (xy 358.529073 -256.718966) (xy 358.477383 -256.72899)
			(xy 358.424769 -256.731007) (xy 358.372464 -256.724969) (xy 358.321693 -256.711017) (xy 358.273648 -256.689478)
			(xy 358.229453 -256.660858) (xy 358.190145 -256.625827) (xy 358.156645 -256.585206) (xy 358.129739 -256.539947)
			(xy 358.110056 -256.491112) (xy 358.098059 -256.439844) (xy 358.094029 -256.387346) (xy 357.83139 -256.387346)
			(xy 357.830886 -256.413672) (xy 357.822849 -256.465708) (xy 357.806963 -256.515907) (xy 357.7836 -256.563092)
			(xy 357.753308 -256.606158) (xy 357.716796 -256.644096) (xy 357.674922 -256.676015) (xy 357.628666 -256.701168)
			(xy 357.579113 -256.718966) (xy 357.527423 -256.72899) (xy 357.474809 -256.731007) (xy 357.422504 -256.724969)
			(xy 357.371733 -256.711017) (xy 357.323688 -256.689478) (xy 357.279493 -256.660858) (xy 357.240185 -256.625827)
			(xy 357.206685 -256.585206) (xy 357.179779 -256.539947) (xy 357.160096 -256.491112) (xy 357.148099 -256.439844)
			(xy 357.144069 -256.387346) (xy 356.88143 -256.387346) (xy 356.880926 -256.413672) (xy 356.872889 -256.465708)
			(xy 356.857003 -256.515907) (xy 356.83364 -256.563092) (xy 356.803348 -256.606158) (xy 356.766836 -256.644096)
			(xy 356.724962 -256.676015) (xy 356.678706 -256.701168) (xy 356.629153 -256.718966) (xy 356.577463 -256.72899)
			(xy 356.524849 -256.731007) (xy 356.472544 -256.724969) (xy 356.421773 -256.711017) (xy 356.373728 -256.689478)
			(xy 356.329533 -256.660858) (xy 356.290225 -256.625827) (xy 356.256725 -256.585206) (xy 356.229819 -256.539947)
			(xy 356.210136 -256.491112) (xy 356.198139 -256.439844) (xy 356.194109 -256.387346) (xy 355.93147 -256.387346)
			(xy 355.930966 -256.413672) (xy 355.922929 -256.465708) (xy 355.907043 -256.515907) (xy 355.88368 -256.563092)
			(xy 355.853388 -256.606158) (xy 355.816876 -256.644096) (xy 355.775002 -256.676015) (xy 355.728746 -256.701168)
			(xy 355.679193 -256.718966) (xy 355.627503 -256.72899) (xy 355.574889 -256.731007) (xy 355.522584 -256.724969)
			(xy 355.471813 -256.711017) (xy 355.423768 -256.689478) (xy 355.379573 -256.660858) (xy 355.340265 -256.625827)
			(xy 355.306765 -256.585206) (xy 355.279859 -256.539947) (xy 355.260176 -256.491112) (xy 355.248179 -256.439844)
			(xy 355.244149 -256.387346) (xy 354.74529 -256.387346) (xy 355.305868 -256.947924) (xy 355.313267 -256.954768)
			(xy 355.331866 -256.962489) (xy 355.341936 -256.96291) (xy 356.90048 -256.96291) (xy 356.910316 -256.963448)
			(xy 356.928474 -256.971039) (xy 356.935786 -256.977642) (xy 357.70312 -257.744976) (xy 358.928419 -257.744976)
			(xy 358.932449 -257.692478) (xy 358.944446 -257.64121) (xy 358.964129 -257.592375) (xy 358.991035 -257.547116)
			(xy 359.024535 -257.506495) (xy 359.063843 -257.471464) (xy 359.108038 -257.442844) (xy 359.156083 -257.421305)
			(xy 359.206854 -257.407353) (xy 359.259159 -257.401315) (xy 359.311773 -257.403332) (xy 359.363463 -257.413356)
			(xy 359.413016 -257.431154) (xy 359.459272 -257.456307) (xy 359.501146 -257.488226) (xy 359.537658 -257.526164)
			(xy 359.56795 -257.56923) (xy 359.591313 -257.616415) (xy 359.607199 -257.666614) (xy 359.615236 -257.71865)
			(xy 359.61574 -257.744976) (xy 361.178351 -257.744976) (xy 361.182381 -257.692478) (xy 361.194378 -257.64121)
			(xy 361.214061 -257.592375) (xy 361.240967 -257.547116) (xy 361.274467 -257.506495) (xy 361.313775 -257.471464)
			(xy 361.35797 -257.442844) (xy 361.406015 -257.421305) (xy 361.456786 -257.407353) (xy 361.509091 -257.401315)
			(xy 361.561705 -257.403332) (xy 361.613395 -257.413356) (xy 361.662948 -257.431154) (xy 361.709204 -257.456307)
			(xy 361.751078 -257.488226) (xy 361.78759 -257.526164) (xy 361.817882 -257.56923) (xy 361.841245 -257.616415)
			(xy 361.857131 -257.666614) (xy 361.865168 -257.71865) (xy 361.865672 -257.744976) (xy 363.778295 -257.744976)
			(xy 363.782325 -257.692478) (xy 363.794322 -257.64121) (xy 363.814005 -257.592375) (xy 363.840911 -257.547116)
			(xy 363.874411 -257.506495) (xy 363.913719 -257.471464) (xy 363.957914 -257.442844) (xy 364.005959 -257.421305)
			(xy 364.05673 -257.407353) (xy 364.109035 -257.401315) (xy 364.161649 -257.403332) (xy 364.213339 -257.413356)
			(xy 364.259724 -257.430016) (xy 365.036865 -257.430016) (xy 365.040895 -257.377518) (xy 365.052892 -257.32625)
			(xy 365.072575 -257.277415) (xy 365.099481 -257.232156) (xy 365.132981 -257.191535) (xy 365.172289 -257.156504)
			(xy 365.216484 -257.127884) (xy 365.264529 -257.106345) (xy 365.3153 -257.092393) (xy 365.367605 -257.086355)
			(xy 365.420219 -257.088372) (xy 365.471909 -257.098396) (xy 365.521462 -257.116194) (xy 365.567718 -257.141347)
			(xy 365.609592 -257.173266) (xy 365.646104 -257.211204) (xy 365.676396 -257.25427) (xy 365.699759 -257.301455)
			(xy 365.715645 -257.351654) (xy 365.723682 -257.40369) (xy 365.724186 -257.430016) (xy 365.723682 -257.456342)
			(xy 365.715645 -257.508378) (xy 365.699759 -257.558577) (xy 365.676396 -257.605762) (xy 365.646104 -257.648828)
			(xy 365.609592 -257.686766) (xy 365.567718 -257.718685) (xy 365.521462 -257.743838) (xy 365.471909 -257.761636)
			(xy 365.420219 -257.77166) (xy 365.367605 -257.773677) (xy 365.3153 -257.767639) (xy 365.264529 -257.753687)
			(xy 365.216484 -257.732148) (xy 365.172289 -257.703528) (xy 365.132981 -257.668497) (xy 365.099481 -257.627876)
			(xy 365.072575 -257.582617) (xy 365.052892 -257.533782) (xy 365.040895 -257.482514) (xy 365.036865 -257.430016)
			(xy 364.259724 -257.430016) (xy 364.262892 -257.431154) (xy 364.309148 -257.456307) (xy 364.351022 -257.488226)
			(xy 364.387534 -257.526164) (xy 364.417826 -257.56923) (xy 364.441189 -257.616415) (xy 364.457075 -257.666614)
			(xy 364.465112 -257.71865) (xy 364.465616 -257.744976) (xy 364.465112 -257.771302) (xy 364.457075 -257.823338)
			(xy 364.441189 -257.873537) (xy 364.417826 -257.920722) (xy 364.4112 -257.930142) (xy 368.805717 -257.930142)
			(xy 368.809747 -257.877644) (xy 368.821744 -257.826376) (xy 368.841427 -257.777541) (xy 368.868333 -257.732282)
			(xy 368.901833 -257.691661) (xy 368.941141 -257.65663) (xy 368.985336 -257.62801) (xy 369.033381 -257.606471)
			(xy 369.084152 -257.592519) (xy 369.136457 -257.586481) (xy 369.189071 -257.588498) (xy 369.240761 -257.598522)
			(xy 369.290314 -257.61632) (xy 369.33657 -257.641473) (xy 369.378444 -257.673392) (xy 369.414956 -257.71133)
			(xy 369.445248 -257.754396) (xy 369.468611 -257.801581) (xy 369.484497 -257.85178) (xy 369.492534 -257.903816)
			(xy 369.493038 -257.930142) (xy 370.731291 -257.930142) (xy 370.735321 -257.877644) (xy 370.747318 -257.826376)
			(xy 370.767001 -257.777541) (xy 370.793907 -257.732282) (xy 370.827407 -257.691661) (xy 370.866715 -257.65663)
			(xy 370.91091 -257.62801) (xy 370.958955 -257.606471) (xy 371.009726 -257.592519) (xy 371.062031 -257.586481)
			(xy 371.114645 -257.588498) (xy 371.166335 -257.598522) (xy 371.215888 -257.61632) (xy 371.262144 -257.641473)
			(xy 371.304018 -257.673392) (xy 371.34053 -257.71133) (xy 371.370822 -257.754396) (xy 371.394185 -257.801581)
			(xy 371.410071 -257.85178) (xy 371.418108 -257.903816) (xy 371.418612 -257.930142) (xy 372.509291 -257.930142)
			(xy 372.513321 -257.877644) (xy 372.525318 -257.826376) (xy 372.545001 -257.777541) (xy 372.571907 -257.732282)
			(xy 372.605407 -257.691661) (xy 372.644715 -257.65663) (xy 372.68891 -257.62801) (xy 372.736955 -257.606471)
			(xy 372.787726 -257.592519) (xy 372.840031 -257.586481) (xy 372.892645 -257.588498) (xy 372.944335 -257.598522)
			(xy 372.993888 -257.61632) (xy 373.040144 -257.641473) (xy 373.082018 -257.673392) (xy 373.11853 -257.71133)
			(xy 373.148822 -257.754396) (xy 373.172185 -257.801581) (xy 373.188071 -257.85178) (xy 373.196108 -257.903816)
			(xy 373.196612 -257.930142) (xy 373.196108 -257.956468) (xy 373.188071 -258.008504) (xy 373.172185 -258.058703)
			(xy 373.148822 -258.105888) (xy 373.11853 -258.148954) (xy 373.082018 -258.186892) (xy 373.040144 -258.218811)
			(xy 372.993888 -258.243964) (xy 372.944335 -258.261762) (xy 372.892645 -258.271786) (xy 372.840031 -258.273803)
			(xy 372.787726 -258.267765) (xy 372.736955 -258.253813) (xy 372.68891 -258.232274) (xy 372.644715 -258.203654)
			(xy 372.605407 -258.168623) (xy 372.571907 -258.128002) (xy 372.545001 -258.082743) (xy 372.525318 -258.033908)
			(xy 372.513321 -257.98264) (xy 372.509291 -257.930142) (xy 371.418612 -257.930142) (xy 371.418108 -257.956468)
			(xy 371.410071 -258.008504) (xy 371.394185 -258.058703) (xy 371.370822 -258.105888) (xy 371.34053 -258.148954)
			(xy 371.304018 -258.186892) (xy 371.262144 -258.218811) (xy 371.215888 -258.243964) (xy 371.166335 -258.261762)
			(xy 371.114645 -258.271786) (xy 371.062031 -258.273803) (xy 371.009726 -258.267765) (xy 370.958955 -258.253813)
			(xy 370.91091 -258.232274) (xy 370.866715 -258.203654) (xy 370.827407 -258.168623) (xy 370.793907 -258.128002)
			(xy 370.767001 -258.082743) (xy 370.747318 -258.033908) (xy 370.735321 -257.98264) (xy 370.731291 -257.930142)
			(xy 369.493038 -257.930142) (xy 369.492534 -257.956468) (xy 369.484497 -258.008504) (xy 369.468611 -258.058703)
			(xy 369.445248 -258.105888) (xy 369.414956 -258.148954) (xy 369.378444 -258.186892) (xy 369.33657 -258.218811)
			(xy 369.290314 -258.243964) (xy 369.240761 -258.261762) (xy 369.189071 -258.271786) (xy 369.136457 -258.273803)
			(xy 369.084152 -258.267765) (xy 369.033381 -258.253813) (xy 368.985336 -258.232274) (xy 368.941141 -258.203654)
			(xy 368.901833 -258.168623) (xy 368.868333 -258.128002) (xy 368.841427 -258.082743) (xy 368.821744 -258.033908)
			(xy 368.809747 -257.98264) (xy 368.805717 -257.930142) (xy 364.4112 -257.930142) (xy 364.387534 -257.963788)
			(xy 364.351022 -258.001726) (xy 364.309148 -258.033645) (xy 364.262892 -258.058798) (xy 364.213339 -258.076596)
			(xy 364.161649 -258.08662) (xy 364.109035 -258.088637) (xy 364.05673 -258.082599) (xy 364.005959 -258.068647)
			(xy 363.957914 -258.047108) (xy 363.913719 -258.018488) (xy 363.874411 -257.983457) (xy 363.840911 -257.942836)
			(xy 363.814005 -257.897577) (xy 363.794322 -257.848742) (xy 363.782325 -257.797474) (xy 363.778295 -257.744976)
			(xy 361.865672 -257.744976) (xy 361.865168 -257.771302) (xy 361.857131 -257.823338) (xy 361.841245 -257.873537)
			(xy 361.817882 -257.920722) (xy 361.78759 -257.963788) (xy 361.751078 -258.001726) (xy 361.709204 -258.033645)
			(xy 361.662948 -258.058798) (xy 361.613395 -258.076596) (xy 361.561705 -258.08662) (xy 361.509091 -258.088637)
			(xy 361.456786 -258.082599) (xy 361.406015 -258.068647) (xy 361.35797 -258.047108) (xy 361.313775 -258.018488)
			(xy 361.274467 -257.983457) (xy 361.240967 -257.942836) (xy 361.214061 -257.897577) (xy 361.194378 -257.848742)
			(xy 361.182381 -257.797474) (xy 361.178351 -257.744976) (xy 359.61574 -257.744976) (xy 359.615236 -257.771302)
			(xy 359.607199 -257.823338) (xy 359.591313 -257.873537) (xy 359.56795 -257.920722) (xy 359.537658 -257.963788)
			(xy 359.501146 -258.001726) (xy 359.459272 -258.033645) (xy 359.413016 -258.058798) (xy 359.363463 -258.076596)
			(xy 359.311773 -258.08662) (xy 359.259159 -258.088637) (xy 359.206854 -258.082599) (xy 359.156083 -258.068647)
			(xy 359.108038 -258.047108) (xy 359.063843 -258.018488) (xy 359.024535 -257.983457) (xy 358.991035 -257.942836)
			(xy 358.964129 -257.897577) (xy 358.944446 -257.848742) (xy 358.932449 -257.797474) (xy 358.928419 -257.744976)
			(xy 357.70312 -257.744976) (xy 358.201468 -258.243324) (xy 358.208867 -258.250168) (xy 358.227466 -258.257889)
			(xy 358.237536 -258.25831) (xy 359.44048 -258.25831) (xy 359.450316 -258.258848) (xy 359.468474 -258.266439)
			(xy 359.475786 -258.273042) (xy 359.58272 -258.379976) (xy 365.036865 -258.379976) (xy 365.040895 -258.327478)
			(xy 365.052892 -258.27621) (xy 365.072575 -258.227375) (xy 365.099481 -258.182116) (xy 365.132981 -258.141495)
			(xy 365.172289 -258.106464) (xy 365.216484 -258.077844) (xy 365.264529 -258.056305) (xy 365.3153 -258.042353)
			(xy 365.367605 -258.036315) (xy 365.420219 -258.038332) (xy 365.471909 -258.048356) (xy 365.521462 -258.066154)
			(xy 365.567718 -258.091307) (xy 365.609592 -258.123226) (xy 365.646104 -258.161164) (xy 365.676396 -258.20423)
			(xy 365.699759 -258.251415) (xy 365.715645 -258.301614) (xy 365.723682 -258.35365) (xy 365.724186 -258.379976)
			(xy 365.723682 -258.406302) (xy 365.715645 -258.458338) (xy 365.699759 -258.508537) (xy 365.676396 -258.555722)
			(xy 365.646104 -258.598788) (xy 365.609592 -258.636726) (xy 365.567718 -258.668645) (xy 365.521462 -258.693798)
			(xy 365.471909 -258.711596) (xy 365.420219 -258.72162) (xy 365.367605 -258.723637) (xy 365.3153 -258.717599)
			(xy 365.264529 -258.703647) (xy 365.216484 -258.682108) (xy 365.172289 -258.653488) (xy 365.132981 -258.618457)
			(xy 365.099481 -258.577836) (xy 365.072575 -258.532577) (xy 365.052892 -258.483742) (xy 365.040895 -258.432474)
			(xy 365.036865 -258.379976) (xy 359.58272 -258.379976) (xy 360.335068 -259.132324) (xy 360.342467 -259.139168)
			(xy 360.361066 -259.146889) (xy 360.371136 -259.14731) (xy 361.156758 -259.14731) (xy 361.165991 -259.146916)
			(xy 361.183259 -259.140374) (xy 361.197078 -259.128126) (xy 361.201716 -259.120132) (xy 361.249468 -259.029962)
			(xy 361.24769 -259.001768) (xy 361.239562 -258.990084) (xy 361.225211 -258.968464) (xy 361.202495 -258.921809)
			(xy 361.187072 -258.872263) (xy 361.179293 -258.820958) (xy 361.178856 -258.795012) (xy 361.179336 -258.769313)
			(xy 361.186997 -258.718489) (xy 361.202146 -258.669375) (xy 361.224447 -258.623067) (xy 361.2534 -258.5806)
			(xy 361.28836 -258.542923) (xy 361.328544 -258.510877) (xy 361.373056 -258.485178) (xy 361.420901 -258.466401)
			(xy 361.47101 -258.454963) (xy 361.522264 -258.451123) (xy 361.573518 -258.454963) (xy 361.623627 -258.466401)
			(xy 361.671472 -258.485178) (xy 361.715984 -258.510877) (xy 361.756168 -258.542923) (xy 361.791128 -258.5806)
			(xy 361.820081 -258.623067) (xy 361.842382 -258.669375) (xy 361.857531 -258.718489) (xy 361.865192 -258.769313)
			(xy 361.865672 -258.795012) (xy 361.865192 -258.820953) (xy 361.857386 -258.872246) (xy 361.841967 -258.921784)
			(xy 361.819284 -258.968447) (xy 361.804966 -258.990084) (xy 361.796838 -259.001768) (xy 361.79506 -259.029962)
			(xy 361.842812 -259.120132) (xy 361.847457 -259.128119) (xy 361.861278 -259.140362) (xy 361.878539 -259.146914)
			(xy 361.88777 -259.14731) (xy 363.756702 -259.14731) (xy 363.765931 -259.146909) (xy 363.783187 -259.140357)
			(xy 363.796994 -259.128106) (xy 363.80166 -259.120132) (xy 363.849412 -259.029962) (xy 363.847634 -259.001768)
			(xy 363.839506 -258.990084) (xy 363.825157 -258.968463) (xy 363.802445 -258.921807) (xy 363.787024 -258.872261)
			(xy 363.779247 -258.820957) (xy 363.7788 -258.795012) (xy 363.77928 -258.769313) (xy 363.786941 -258.718489)
			(xy 363.80209 -258.669375) (xy 363.824391 -258.623067) (xy 363.853344 -258.5806) (xy 363.888304 -258.542923)
			(xy 363.928488 -258.510877) (xy 363.973 -258.485178) (xy 364.020845 -258.466401) (xy 364.070954 -258.454963)
			(xy 364.122208 -258.451123) (xy 364.173462 -258.454963) (xy 364.223571 -258.466401) (xy 364.271416 -258.485178)
			(xy 364.315928 -258.510877) (xy 364.356112 -258.542923) (xy 364.391072 -258.5806) (xy 364.420025 -258.623067)
			(xy 364.442326 -258.669375) (xy 364.457475 -258.718489) (xy 364.465136 -258.769313) (xy 364.465616 -258.795012)
			(xy 364.465108 -258.82171) (xy 364.463799 -258.830064) (xy 368.805717 -258.830064) (xy 368.809747 -258.777566)
			(xy 368.821744 -258.726298) (xy 368.841427 -258.677463) (xy 368.868333 -258.632204) (xy 368.901833 -258.591583)
			(xy 368.941141 -258.556552) (xy 368.985336 -258.527932) (xy 369.033381 -258.506393) (xy 369.084152 -258.492441)
			(xy 369.136457 -258.486403) (xy 369.189071 -258.48842) (xy 369.240761 -258.498444) (xy 369.290314 -258.516242)
			(xy 369.33657 -258.541395) (xy 369.378444 -258.573314) (xy 369.414956 -258.611252) (xy 369.445248 -258.654318)
			(xy 369.468611 -258.701503) (xy 369.484497 -258.751702) (xy 369.492534 -258.803738) (xy 369.493038 -258.830064)
			(xy 370.731291 -258.830064) (xy 370.735321 -258.777566) (xy 370.747318 -258.726298) (xy 370.767001 -258.677463)
			(xy 370.793907 -258.632204) (xy 370.827407 -258.591583) (xy 370.866715 -258.556552) (xy 370.91091 -258.527932)
			(xy 370.958955 -258.506393) (xy 371.009726 -258.492441) (xy 371.062031 -258.486403) (xy 371.114645 -258.48842)
			(xy 371.166335 -258.498444) (xy 371.215888 -258.516242) (xy 371.262144 -258.541395) (xy 371.304018 -258.573314)
			(xy 371.34053 -258.611252) (xy 371.370822 -258.654318) (xy 371.394185 -258.701503) (xy 371.410071 -258.751702)
			(xy 371.418108 -258.803738) (xy 371.418612 -258.830064) (xy 372.509291 -258.830064) (xy 372.513321 -258.777566)
			(xy 372.525318 -258.726298) (xy 372.545001 -258.677463) (xy 372.571907 -258.632204) (xy 372.605407 -258.591583)
			(xy 372.644715 -258.556552) (xy 372.68891 -258.527932) (xy 372.736955 -258.506393) (xy 372.787726 -258.492441)
			(xy 372.840031 -258.486403) (xy 372.892645 -258.48842) (xy 372.944335 -258.498444) (xy 372.993888 -258.516242)
			(xy 373.040144 -258.541395) (xy 373.082018 -258.573314) (xy 373.11853 -258.611252) (xy 373.148822 -258.654318)
			(xy 373.172185 -258.701503) (xy 373.188071 -258.751702) (xy 373.196108 -258.803738) (xy 373.196612 -258.830064)
			(xy 373.196108 -258.85639) (xy 373.188071 -258.908426) (xy 373.172185 -258.958625) (xy 373.148822 -259.00581)
			(xy 373.11853 -259.048876) (xy 373.082018 -259.086814) (xy 373.040144 -259.118733) (xy 372.993888 -259.143886)
			(xy 372.944335 -259.161684) (xy 372.892645 -259.171708) (xy 372.840031 -259.173725) (xy 372.787726 -259.167687)
			(xy 372.736955 -259.153735) (xy 372.68891 -259.132196) (xy 372.644715 -259.103576) (xy 372.605407 -259.068545)
			(xy 372.571907 -259.027924) (xy 372.545001 -258.982665) (xy 372.525318 -258.93383) (xy 372.513321 -258.882562)
			(xy 372.509291 -258.830064) (xy 371.418612 -258.830064) (xy 371.418108 -258.85639) (xy 371.410071 -258.908426)
			(xy 371.394185 -258.958625) (xy 371.370822 -259.00581) (xy 371.34053 -259.048876) (xy 371.304018 -259.086814)
			(xy 371.262144 -259.118733) (xy 371.215888 -259.143886) (xy 371.166335 -259.161684) (xy 371.114645 -259.171708)
			(xy 371.062031 -259.173725) (xy 371.009726 -259.167687) (xy 370.958955 -259.153735) (xy 370.91091 -259.132196)
			(xy 370.866715 -259.103576) (xy 370.827407 -259.068545) (xy 370.793907 -259.027924) (xy 370.767001 -258.982665)
			(xy 370.747318 -258.93383) (xy 370.735321 -258.882562) (xy 370.731291 -258.830064) (xy 369.493038 -258.830064)
			(xy 369.492534 -258.85639) (xy 369.484497 -258.908426) (xy 369.468611 -258.958625) (xy 369.445248 -259.00581)
			(xy 369.414956 -259.048876) (xy 369.378444 -259.086814) (xy 369.33657 -259.118733) (xy 369.290314 -259.143886)
			(xy 369.240761 -259.161684) (xy 369.189071 -259.171708) (xy 369.136457 -259.173725) (xy 369.084152 -259.167687)
			(xy 369.033381 -259.153735) (xy 368.985336 -259.132196) (xy 368.941141 -259.103576) (xy 368.901833 -259.068545)
			(xy 368.868333 -259.027924) (xy 368.841427 -258.982665) (xy 368.821744 -258.93383) (xy 368.809747 -258.882562)
			(xy 368.805717 -258.830064) (xy 364.463799 -258.830064) (xy 364.456842 -258.874462) (xy 364.440511 -258.925299)
			(xy 364.416508 -258.972996) (xy 364.385412 -259.016403) (xy 364.367064 -259.035804) (xy 364.359952 -259.042916)
			(xy 364.352586 -259.061204) (xy 364.35284 -259.141468) (xy 364.353373 -259.151457) (xy 364.361083 -259.169894)
			(xy 364.367826 -259.177282) (xy 364.520734 -259.33019) (xy 365.036865 -259.33019) (xy 365.040895 -259.277692)
			(xy 365.052892 -259.226424) (xy 365.072575 -259.177589) (xy 365.099481 -259.13233) (xy 365.132981 -259.091709)
			(xy 365.172289 -259.056678) (xy 365.216484 -259.028058) (xy 365.264529 -259.006519) (xy 365.3153 -258.992567)
			(xy 365.367605 -258.986529) (xy 365.420219 -258.988546) (xy 365.471909 -258.99857) (xy 365.521462 -259.016368)
			(xy 365.567718 -259.041521) (xy 365.609592 -259.07344) (xy 365.646104 -259.111378) (xy 365.676396 -259.154444)
			(xy 365.699759 -259.201629) (xy 365.715645 -259.251828) (xy 365.723682 -259.303864) (xy 365.724186 -259.33019)
			(xy 365.723682 -259.356516) (xy 365.715645 -259.408552) (xy 365.699759 -259.458751) (xy 365.676396 -259.505936)
			(xy 365.646104 -259.549002) (xy 365.609592 -259.58694) (xy 365.567718 -259.618859) (xy 365.521462 -259.644012)
			(xy 365.471909 -259.66181) (xy 365.420219 -259.671834) (xy 365.367605 -259.673851) (xy 365.3153 -259.667813)
			(xy 365.264529 -259.653861) (xy 365.216484 -259.632322) (xy 365.172289 -259.603702) (xy 365.132981 -259.568671)
			(xy 365.099481 -259.52805) (xy 365.072575 -259.482791) (xy 365.052892 -259.433956) (xy 365.040895 -259.382688)
			(xy 365.036865 -259.33019) (xy 364.520734 -259.33019) (xy 364.627922 -259.437378) (xy 364.634639 -259.444615)
			(xy 364.642244 -259.462819) (xy 364.642654 -259.472684) (xy 364.642654 -259.729986) (xy 368.805717 -259.729986)
			(xy 368.809747 -259.677488) (xy 368.821744 -259.62622) (xy 368.841427 -259.577385) (xy 368.868333 -259.532126)
			(xy 368.901833 -259.491505) (xy 368.941141 -259.456474) (xy 368.985336 -259.427854) (xy 369.033381 -259.406315)
			(xy 369.084152 -259.392363) (xy 369.136457 -259.386325) (xy 369.189071 -259.388342) (xy 369.240761 -259.398366)
			(xy 369.290314 -259.416164) (xy 369.33657 -259.441317) (xy 369.378444 -259.473236) (xy 369.414956 -259.511174)
			(xy 369.445248 -259.55424) (xy 369.468611 -259.601425) (xy 369.484497 -259.651624) (xy 369.492534 -259.70366)
			(xy 369.493038 -259.729986) (xy 370.731291 -259.729986) (xy 370.735321 -259.677488) (xy 370.747318 -259.62622)
			(xy 370.767001 -259.577385) (xy 370.793907 -259.532126) (xy 370.827407 -259.491505) (xy 370.866715 -259.456474)
			(xy 370.91091 -259.427854) (xy 370.958955 -259.406315) (xy 371.009726 -259.392363) (xy 371.062031 -259.386325)
			(xy 371.114645 -259.388342) (xy 371.166335 -259.398366) (xy 371.215888 -259.416164) (xy 371.262144 -259.441317)
			(xy 371.304018 -259.473236) (xy 371.34053 -259.511174) (xy 371.370822 -259.55424) (xy 371.394185 -259.601425)
			(xy 371.410071 -259.651624) (xy 371.418108 -259.70366) (xy 371.418612 -259.729986) (xy 372.509291 -259.729986)
			(xy 372.513321 -259.677488) (xy 372.525318 -259.62622) (xy 372.545001 -259.577385) (xy 372.571907 -259.532126)
			(xy 372.605407 -259.491505) (xy 372.644715 -259.456474) (xy 372.68891 -259.427854) (xy 372.736955 -259.406315)
			(xy 372.787726 -259.392363) (xy 372.840031 -259.386325) (xy 372.892645 -259.388342) (xy 372.944335 -259.398366)
			(xy 372.993888 -259.416164) (xy 373.040144 -259.441317) (xy 373.082018 -259.473236) (xy 373.11853 -259.511174)
			(xy 373.148822 -259.55424) (xy 373.172185 -259.601425) (xy 373.188071 -259.651624) (xy 373.196108 -259.70366)
			(xy 373.196612 -259.729986) (xy 373.196108 -259.756312) (xy 373.188071 -259.808348) (xy 373.172185 -259.858547)
			(xy 373.148822 -259.905732) (xy 373.11853 -259.948798) (xy 373.082018 -259.986736) (xy 373.040144 -260.018655)
			(xy 372.993888 -260.043808) (xy 372.944335 -260.061606) (xy 372.892645 -260.07163) (xy 372.840031 -260.073647)
			(xy 372.787726 -260.067609) (xy 372.736955 -260.053657) (xy 372.68891 -260.032118) (xy 372.644715 -260.003498)
			(xy 372.605407 -259.968467) (xy 372.571907 -259.927846) (xy 372.545001 -259.882587) (xy 372.525318 -259.833752)
			(xy 372.513321 -259.782484) (xy 372.509291 -259.729986) (xy 371.418612 -259.729986) (xy 371.418108 -259.756312)
			(xy 371.410071 -259.808348) (xy 371.394185 -259.858547) (xy 371.370822 -259.905732) (xy 371.34053 -259.948798)
			(xy 371.304018 -259.986736) (xy 371.262144 -260.018655) (xy 371.215888 -260.043808) (xy 371.166335 -260.061606)
			(xy 371.114645 -260.07163) (xy 371.062031 -260.073647) (xy 371.009726 -260.067609) (xy 370.958955 -260.053657)
			(xy 370.91091 -260.032118) (xy 370.866715 -260.003498) (xy 370.827407 -259.968467) (xy 370.793907 -259.927846)
			(xy 370.767001 -259.882587) (xy 370.747318 -259.833752) (xy 370.735321 -259.782484) (xy 370.731291 -259.729986)
			(xy 369.493038 -259.729986) (xy 369.492534 -259.756312) (xy 369.484497 -259.808348) (xy 369.468611 -259.858547)
			(xy 369.445248 -259.905732) (xy 369.414956 -259.948798) (xy 369.378444 -259.986736) (xy 369.33657 -260.018655)
			(xy 369.290314 -260.043808) (xy 369.240761 -260.061606) (xy 369.189071 -260.07163) (xy 369.136457 -260.073647)
			(xy 369.084152 -260.067609) (xy 369.033381 -260.053657) (xy 368.985336 -260.032118) (xy 368.941141 -260.003498)
			(xy 368.901833 -259.968467) (xy 368.868333 -259.927846) (xy 368.841427 -259.882587) (xy 368.821744 -259.833752)
			(xy 368.809747 -259.782484) (xy 368.805717 -259.729986) (xy 364.642654 -259.729986) (xy 364.642654 -260.28015)
			(xy 365.036865 -260.28015) (xy 365.040895 -260.227652) (xy 365.052892 -260.176384) (xy 365.072575 -260.127549)
			(xy 365.099481 -260.08229) (xy 365.132981 -260.041669) (xy 365.172289 -260.006638) (xy 365.216484 -259.978018)
			(xy 365.264529 -259.956479) (xy 365.3153 -259.942527) (xy 365.367605 -259.936489) (xy 365.420219 -259.938506)
			(xy 365.471909 -259.94853) (xy 365.521462 -259.966328) (xy 365.567718 -259.991481) (xy 365.609592 -260.0234)
			(xy 365.646104 -260.061338) (xy 365.676396 -260.104404) (xy 365.699759 -260.151589) (xy 365.715645 -260.201788)
			(xy 365.723682 -260.253824) (xy 365.724186 -260.28015) (xy 365.723682 -260.306476) (xy 365.715645 -260.358512)
			(xy 365.699759 -260.408711) (xy 365.676396 -260.455896) (xy 365.646104 -260.498962) (xy 365.609592 -260.5369)
			(xy 365.567718 -260.568819) (xy 365.521462 -260.593972) (xy 365.471909 -260.61177) (xy 365.420219 -260.621794)
			(xy 365.367605 -260.623811) (xy 365.3153 -260.617773) (xy 365.264529 -260.603821) (xy 365.216484 -260.582282)
			(xy 365.172289 -260.553662) (xy 365.132981 -260.518631) (xy 365.099481 -260.47801) (xy 365.072575 -260.432751)
			(xy 365.052892 -260.383916) (xy 365.040895 -260.332648) (xy 365.036865 -260.28015) (xy 364.642654 -260.28015)
			(xy 364.642654 -261.140448) (xy 364.643087 -261.150513) (xy 364.65082 -261.1691) (xy 364.65764 -261.176516)
			(xy 365.008668 -261.527544) (xy 365.016067 -261.534386) (xy 365.034666 -261.542104) (xy 365.044736 -261.54253)
			(xy 365.085884 -261.54253) (xy 365.095896 -261.542045) (xy 365.114398 -261.53439) (xy 365.128564 -261.520237)
			(xy 365.136236 -261.501742) (xy 365.136684 -261.49173) (xy 365.136684 -261.482332) (xy 365.13008 -261.46506)
			(xy 365.123984 -261.457948) (xy 365.107759 -261.439015) (xy 365.080385 -261.397342) (xy 365.059333 -261.352144)
			(xy 365.045046 -261.304375) (xy 365.037826 -261.25504) (xy 365.03737 -261.23011) (xy 365.03785 -261.204411)
			(xy 365.045511 -261.153587) (xy 365.06066 -261.104473) (xy 365.082961 -261.058165) (xy 365.111914 -261.015698)
			(xy 365.146874 -260.978021) (xy 365.187058 -260.945975) (xy 365.23157 -260.920276) (xy 365.279415 -260.901499)
			(xy 365.329524 -260.890061) (xy 365.380778 -260.886221) (xy 365.432032 -260.890061) (xy 365.482141 -260.901499)
			(xy 365.529986 -260.920276) (xy 365.574498 -260.945975) (xy 365.614682 -260.978021) (xy 365.649642 -261.015698)
			(xy 365.678595 -261.058165) (xy 365.700896 -261.104473) (xy 365.707527 -261.12597) (xy 369.578902 -261.12597)
			(xy 369.582862 -261.076916) (xy 369.594639 -261.029132) (xy 369.61393 -260.983856) (xy 369.640233 -260.94226)
			(xy 369.672868 -260.905423) (xy 369.710989 -260.874298) (xy 369.75361 -260.849691) (xy 369.799626 -260.832239)
			(xy 369.847845 -260.822395) (xy 369.89702 -260.820414) (xy 369.945875 -260.826346) (xy 369.993146 -260.840038)
			(xy 370.037608 -260.861136) (xy 370.078111 -260.889092) (xy 370.113604 -260.923184) (xy 370.143169 -260.962528)
			(xy 370.16604 -261.006105) (xy 370.181624 -261.052786) (xy 370.189519 -261.101363) (xy 370.190014 -261.12597)
			(xy 371.45901 -261.12597) (xy 371.46297 -261.076916) (xy 371.474747 -261.029132) (xy 371.494038 -260.983856)
			(xy 371.520341 -260.94226) (xy 371.552976 -260.905423) (xy 371.591097 -260.874298) (xy 371.633718 -260.849691)
			(xy 371.679734 -260.832239) (xy 371.727953 -260.822395) (xy 371.777128 -260.820414) (xy 371.825983 -260.826346)
			(xy 371.873254 -260.840038) (xy 371.917716 -260.861136) (xy 371.958219 -260.889092) (xy 371.993712 -260.923184)
			(xy 372.023277 -260.962528) (xy 372.046148 -261.006105) (xy 372.061732 -261.052786) (xy 372.069627 -261.101363)
			(xy 372.070122 -261.12597) (xy 373.339118 -261.12597) (xy 373.343078 -261.076916) (xy 373.354855 -261.029132)
			(xy 373.374146 -260.983856) (xy 373.400449 -260.94226) (xy 373.433084 -260.905423) (xy 373.471205 -260.874298)
			(xy 373.513826 -260.849691) (xy 373.559842 -260.832239) (xy 373.608061 -260.822395) (xy 373.657236 -260.820414)
			(xy 373.706091 -260.826346) (xy 373.753362 -260.840038) (xy 373.797824 -260.861136) (xy 373.838327 -260.889092)
			(xy 373.87382 -260.923184) (xy 373.903385 -260.962528) (xy 373.926256 -261.006105) (xy 373.94184 -261.052786)
			(xy 373.949735 -261.101363) (xy 373.95023 -261.12597) (xy 373.949735 -261.150577) (xy 373.94184 -261.199154)
			(xy 373.926256 -261.245835) (xy 373.903385 -261.289412) (xy 373.87382 -261.328756) (xy 373.838327 -261.362848)
			(xy 373.797824 -261.390804) (xy 373.753362 -261.411902) (xy 373.706091 -261.425594) (xy 373.657236 -261.431526)
			(xy 373.608061 -261.429545) (xy 373.559842 -261.419701) (xy 373.513826 -261.402249) (xy 373.471205 -261.377642)
			(xy 373.433084 -261.346517) (xy 373.400449 -261.30968) (xy 373.374146 -261.268084) (xy 373.354855 -261.222808)
			(xy 373.343078 -261.175024) (xy 373.339118 -261.12597) (xy 372.070122 -261.12597) (xy 372.069627 -261.150577)
			(xy 372.061732 -261.199154) (xy 372.046148 -261.245835) (xy 372.023277 -261.289412) (xy 371.993712 -261.328756)
			(xy 371.958219 -261.362848) (xy 371.917716 -261.390804) (xy 371.873254 -261.411902) (xy 371.825983 -261.425594)
			(xy 371.777128 -261.431526) (xy 371.727953 -261.429545) (xy 371.679734 -261.419701) (xy 371.633718 -261.402249)
			(xy 371.591097 -261.377642) (xy 371.552976 -261.346517) (xy 371.520341 -261.30968) (xy 371.494038 -261.268084)
			(xy 371.474747 -261.222808) (xy 371.46297 -261.175024) (xy 371.45901 -261.12597) (xy 370.190014 -261.12597)
			(xy 370.189519 -261.150577) (xy 370.181624 -261.199154) (xy 370.16604 -261.245835) (xy 370.143169 -261.289412)
			(xy 370.113604 -261.328756) (xy 370.078111 -261.362848) (xy 370.037608 -261.390804) (xy 369.993146 -261.411902)
			(xy 369.945875 -261.425594) (xy 369.89702 -261.431526) (xy 369.847845 -261.429545) (xy 369.799626 -261.419701)
			(xy 369.75361 -261.402249) (xy 369.710989 -261.377642) (xy 369.672868 -261.346517) (xy 369.640233 -261.30968)
			(xy 369.61393 -261.268084) (xy 369.594639 -261.222808) (xy 369.582862 -261.175024) (xy 369.578902 -261.12597)
			(xy 365.707527 -261.12597) (xy 365.716045 -261.153587) (xy 365.723706 -261.204411) (xy 365.724186 -261.23011)
			(xy 365.72365 -261.25864) (xy 365.714261 -261.314921) (xy 365.695677 -261.368868) (xy 365.68253 -261.394194)
			(xy 365.675926 -261.406132) (xy 365.676434 -261.432548) (xy 365.726726 -261.517638) (xy 365.731529 -261.525006)
			(xy 365.745086 -261.53619) (xy 365.761626 -261.54213) (xy 365.770414 -261.54253) (xy 366.023398 -261.54253)
			(xy 366.03092 -261.542816) (xy 366.045271 -261.547333) (xy 366.051592 -261.55142) (xy 366.058196 -261.555738)
			(xy 366.07242 -261.56031) (xy 367.057178 -261.56031) (xy 367.067015 -261.560848) (xy 367.085173 -261.568438)
			(xy 367.092484 -261.575042) (xy 367.697766 -262.180324) (xy 367.705164 -262.187168) (xy 367.723764 -262.19489)
			(xy 367.733834 -262.19531) (xy 369.981734 -262.19531) (xy 369.994374 -262.194629) (xy 370.016625 -262.182628)
			(xy 370.024152 -262.17245) (xy 370.07673 -262.09244) (xy 370.079016 -262.067294) (xy 370.073936 -262.05561)
			(xy 370.062586 -262.027012) (xy 370.050303 -261.966735) (xy 370.049552 -261.935976) (xy 370.050074 -261.910721)
			(xy 370.058387 -261.860899) (xy 370.074788 -261.813125) (xy 370.098829 -261.768702) (xy 370.129853 -261.728842)
			(xy 370.167015 -261.694632) (xy 370.209301 -261.667006) (xy 370.255557 -261.646716) (xy 370.304522 -261.634316)
			(xy 370.35486 -261.630145) (xy 370.405198 -261.634316) (xy 370.454163 -261.646716) (xy 370.500419 -261.667006)
			(xy 370.542705 -261.694632) (xy 370.579867 -261.728842) (xy 370.610891 -261.768702) (xy 370.634932 -261.813125)
			(xy 370.651333 -261.860899) (xy 370.659646 -261.910721) (xy 370.660168 -261.935976) (xy 371.92891 -261.935976)
			(xy 371.93287 -261.886922) (xy 371.944647 -261.839138) (xy 371.963938 -261.793862) (xy 371.990241 -261.752266)
			(xy 372.022876 -261.715429) (xy 372.060997 -261.684304) (xy 372.103618 -261.659697) (xy 372.149634 -261.642245)
			(xy 372.197853 -261.632401) (xy 372.247028 -261.63042) (xy 372.295883 -261.636352) (xy 372.343154 -261.650044)
			(xy 372.387616 -261.671142) (xy 372.428119 -261.699098) (xy 372.463612 -261.73319) (xy 372.493177 -261.772534)
			(xy 372.516048 -261.816111) (xy 372.531632 -261.862792) (xy 372.539527 -261.911369) (xy 372.540022 -261.935976)
			(xy 373.809018 -261.935976) (xy 373.812978 -261.886922) (xy 373.824755 -261.839138) (xy 373.844046 -261.793862)
			(xy 373.870349 -261.752266) (xy 373.902984 -261.715429) (xy 373.941105 -261.684304) (xy 373.983726 -261.659697)
			(xy 374.029742 -261.642245) (xy 374.077961 -261.632401) (xy 374.127136 -261.63042) (xy 374.175991 -261.636352)
			(xy 374.223262 -261.650044) (xy 374.267724 -261.671142) (xy 374.308227 -261.699098) (xy 374.34372 -261.73319)
			(xy 374.373285 -261.772534) (xy 374.396156 -261.816111) (xy 374.41174 -261.862792) (xy 374.419635 -261.911369)
			(xy 374.42013 -261.935976) (xy 374.419635 -261.960583) (xy 374.41174 -262.00916) (xy 374.396156 -262.055841)
			(xy 374.373285 -262.099418) (xy 374.34372 -262.138762) (xy 374.308227 -262.172854) (xy 374.267724 -262.20081)
			(xy 374.223262 -262.221908) (xy 374.175991 -262.2356) (xy 374.127136 -262.241532) (xy 374.077961 -262.239551)
			(xy 374.029742 -262.229707) (xy 373.983726 -262.212255) (xy 373.941105 -262.187648) (xy 373.902984 -262.156523)
			(xy 373.870349 -262.119686) (xy 373.844046 -262.07809) (xy 373.824755 -262.032814) (xy 373.812978 -261.98503)
			(xy 373.809018 -261.935976) (xy 372.540022 -261.935976) (xy 372.539527 -261.960583) (xy 372.531632 -262.00916)
			(xy 372.516048 -262.055841) (xy 372.493177 -262.099418) (xy 372.463612 -262.138762) (xy 372.428119 -262.172854)
			(xy 372.387616 -262.20081) (xy 372.343154 -262.221908) (xy 372.295883 -262.2356) (xy 372.247028 -262.241532)
			(xy 372.197853 -262.239551) (xy 372.149634 -262.229707) (xy 372.103618 -262.212255) (xy 372.060997 -262.187648)
			(xy 372.022876 -262.156523) (xy 371.990241 -262.119686) (xy 371.963938 -262.07809) (xy 371.944647 -262.032814)
			(xy 371.93287 -261.98503) (xy 371.92891 -261.935976) (xy 370.660168 -261.935976) (xy 370.659404 -261.966733)
			(xy 370.64712 -262.027008) (xy 370.635784 -262.05561) (xy 370.630704 -262.067294) (xy 370.63299 -262.09244)
			(xy 370.685568 -262.17245) (xy 370.693085 -262.182638) (xy 370.715344 -262.194633) (xy 370.727986 -262.19531)
			(xy 371.375178 -262.19531) (xy 371.385015 -262.195848) (xy 371.403173 -262.203438) (xy 371.410484 -262.210042)
			(xy 371.64772 -262.447278) (xy 371.673628 -262.45439) (xy 371.686836 -262.450834) (xy 371.705982 -262.446097)
			(xy 371.745093 -262.441) (xy 371.764814 -262.440674) (xy 371.767862 -262.440674) (xy 371.791544 -262.441358)
			(xy 371.838276 -262.449145) (xy 371.883244 -262.464055) (xy 371.92537 -262.485732) (xy 371.963642 -262.513656)
			(xy 371.997142 -262.547155) (xy 372.025065 -262.585427) (xy 372.046743 -262.627552) (xy 372.061654 -262.67252)
			(xy 372.069441 -262.719252) (xy 372.070122 -262.742934) (xy 372.070122 -262.745982) (xy 372.069814 -262.765704)
			(xy 372.064718 -262.804817) (xy 372.059962 -262.82396) (xy 372.056406 -262.837168) (xy 372.063518 -262.863076)
			(xy 372.269766 -263.069324) (xy 372.277164 -263.076168) (xy 372.295764 -263.08389) (xy 372.305834 -263.08431)
		)
		(stroke
			(width 0)
			(type solid)
		)
		(fill yes)
		(layer "In2.Cu")
		(net "PVDDCR_SOC_P0")
	)
	(gr_poly
		(pts
			(xy 463.103976 -82.634328) (xy 463.111136 -82.632625) (xy 463.124166 -82.625797) (xy 463.12963 -82.620866)
			(xy 469.658954 -76.091542) (xy 469.663934 -76.086039) (xy 469.670762 -76.07287) (xy 469.672416 -76.065634)
			(xy 469.673432 -76.055982) (xy 469.673432 -41.365932) (xy 469.673364 -41.361924) (xy 469.67209 -41.35401)
			(xy 469.670892 -41.350184) (xy 469.66378 -41.32834) (xy 469.660986 -41.324022) (xy 469.659462 -41.32199)
			(xy 469.643601 -41.298014) (xy 469.618494 -41.246301) (xy 469.601432 -41.191406) (xy 469.592801 -41.134572)
			(xy 469.592797 -41.077087) (xy 469.601419 -41.020252) (xy 469.618472 -40.965354) (xy 469.643571 -40.913637)
			(xy 469.659462 -40.889682) (xy 469.660986 -40.88765) (xy 469.66378 -40.883332) (xy 469.670892 -40.861488)
			(xy 469.672057 -40.857655) (xy 469.673332 -40.849745) (xy 469.673432 -40.84574) (xy 469.673432 -38.49624)
			(xy 469.673092 -38.487546) (xy 469.667255 -38.47117) (xy 469.662002 -38.464236) (xy 469.6587 -38.460426)
			(xy 467.987888 -36.789614) (xy 467.984159 -36.786091) (xy 467.975586 -36.780458) (xy 467.97087 -36.778438)
			(xy 467.962234 -36.774882) (xy 465.666836 -36.774882) (xy 465.66201 -36.775136) (xy 465.656168 -36.776152)
			(xy 465.586686 -36.796357) (xy 465.446144 -36.830865) (xy 465.304102 -36.858561) (xy 465.160891 -36.87938)
			(xy 465.016843 -36.893274) (xy 464.872292 -36.90021) (xy 464.799934 -36.900612) (xy 464.727576 -36.900202)
			(xy 464.583025 -36.893274) (xy 464.438976 -36.879384) (xy 464.295765 -36.858565) (xy 464.153724 -36.830864)
			(xy 464.013184 -36.796347) (xy 463.9437 -36.776152) (xy 463.937858 -36.775136) (xy 463.933032 -36.774882)
			(xy 457.616814 -36.774882) (xy 457.608122 -36.775227) (xy 457.591752 -36.781071) (xy 457.58481 -36.786312)
			(xy 457.581 -36.789614) (xy 456.99299 -37.377624) (xy 456.973357 -37.396432) (xy 456.928854 -37.427656)
			(xy 456.879628 -37.450728) (xy 456.853544 -37.458396) (xy 456.851512 -37.458904) (xy 456.8444 -37.461444)
			(xy 456.837542 -37.465508) (xy 456.83551 -37.466778) (xy 456.811107 -37.483533) (xy 456.758211 -37.510098)
			(xy 456.701845 -37.528169) (xy 456.643364 -37.537312) (xy 456.613768 -37.537898) (xy 456.586519 -37.53741)
			(xy 456.532575 -37.529649) (xy 456.480285 -37.514291) (xy 456.430712 -37.491648) (xy 456.384866 -37.462181)
			(xy 456.343681 -37.426489) (xy 456.307994 -37.3853) (xy 456.278532 -37.339451) (xy 456.255894 -37.289876)
			(xy 456.240542 -37.237584) (xy 456.232787 -37.18364) (xy 456.23226 -37.15639) (xy 456.23226 -37.155882)
			(xy 456.232765 -37.128283) (xy 456.240756 -37.073667) (xy 456.256541 -37.020774) (xy 456.279788 -36.97071)
			(xy 456.29449 -36.947348) (xy 456.299062 -36.940236) (xy 456.30084 -36.934648) (xy 456.301806 -36.931107)
			(xy 456.302828 -36.92384) (xy 456.302872 -36.92017) (xy 456.302872 -36.887658) (xy 456.302872 -36.885626)
			(xy 456.302557 -36.880558) (xy 456.300122 -36.870702) (xy 456.298046 -36.866068) (xy 456.281282 -36.833556)
			(xy 456.26528 -36.802568) (xy 456.26147 -36.796218) (xy 456.254611 -36.787516) (xy 456.235372 -36.776577)
			(xy 456.224386 -36.775136) (xy 456.22337 -36.775136) (xy 456.220068 -36.774882) (xy 451.68693 -36.774882)
			(xy 451.67693 -36.775362) (xy 451.658445 -36.782996) (xy 451.644282 -36.797116) (xy 451.636592 -36.815577)
			(xy 451.636543 -36.835577) (xy 451.644143 -36.854076) (xy 451.650862 -36.861496) (xy 452.718141 -37.92855)
			(xy 460.629252 -37.92855) (xy 460.633323 -37.872928) (xy 460.645449 -37.818491) (xy 460.665372 -37.7664)
			(xy 460.692668 -37.717765) (xy 460.726754 -37.673622) (xy 460.766903 -37.634913) (xy 460.812261 -37.602462)
			(xy 460.861861 -37.576961) (xy 460.914645 -37.558954) (xy 460.969488 -37.548824) (xy 461.025222 -37.546787)
			(xy 461.080659 -37.552887) (xy 461.134616 -37.566993) (xy 461.185945 -37.588805) (xy 461.233551 -37.617859)
			(xy 461.276419 -37.653534) (xy 461.313636 -37.695071) (xy 461.344409 -37.741584) (xy 461.368081 -37.792081)
			(xy 461.384149 -37.845488) (xy 461.392269 -37.900664) (xy 461.392778 -37.92855) (xy 461.392269 -37.956436)
			(xy 461.384149 -38.011612) (xy 461.368081 -38.065019) (xy 461.35335 -38.096444) (xy 464.734146 -38.096444)
			(xy 464.738217 -38.040822) (xy 464.750343 -37.986385) (xy 464.770266 -37.934294) (xy 464.797562 -37.885659)
			(xy 464.831648 -37.841516) (xy 464.871797 -37.802807) (xy 464.917155 -37.770356) (xy 464.966755 -37.744855)
			(xy 465.019539 -37.726848) (xy 465.074382 -37.716718) (xy 465.130116 -37.714681) (xy 465.185553 -37.720781)
			(xy 465.23951 -37.734887) (xy 465.290839 -37.756699) (xy 465.338445 -37.785753) (xy 465.381313 -37.821428)
			(xy 465.41853 -37.862965) (xy 465.449303 -37.909478) (xy 465.472975 -37.959975) (xy 465.489043 -38.013382)
			(xy 465.497163 -38.068558) (xy 465.497672 -38.096444) (xy 465.497163 -38.12433) (xy 465.489043 -38.179506)
			(xy 465.472975 -38.232913) (xy 465.449303 -38.28341) (xy 465.41853 -38.329923) (xy 465.381313 -38.37146)
			(xy 465.338445 -38.407135) (xy 465.290839 -38.436189) (xy 465.23951 -38.458001) (xy 465.185553 -38.472107)
			(xy 465.130116 -38.478207) (xy 465.074382 -38.47617) (xy 465.019539 -38.46604) (xy 464.966755 -38.448033)
			(xy 464.917155 -38.422532) (xy 464.871797 -38.390081) (xy 464.831648 -38.351372) (xy 464.797562 -38.307229)
			(xy 464.770266 -38.258594) (xy 464.750343 -38.206503) (xy 464.738217 -38.152066) (xy 464.734146 -38.096444)
			(xy 461.35335 -38.096444) (xy 461.344409 -38.115516) (xy 461.313636 -38.162029) (xy 461.276419 -38.203566)
			(xy 461.233551 -38.239241) (xy 461.185945 -38.268295) (xy 461.134616 -38.290107) (xy 461.080659 -38.304213)
			(xy 461.025222 -38.310313) (xy 460.969488 -38.308276) (xy 460.914645 -38.298146) (xy 460.861861 -38.280139)
			(xy 460.812261 -38.254638) (xy 460.766903 -38.222187) (xy 460.726754 -38.183478) (xy 460.692668 -38.139335)
			(xy 460.665372 -38.0907) (xy 460.645449 -38.038609) (xy 460.633323 -37.984172) (xy 460.629252 -37.92855)
			(xy 452.718141 -37.92855) (xy 452.85787 -38.06825) (xy 452.863373 -38.073229) (xy 452.876543 -38.080055)
			(xy 452.883778 -38.081712) (xy 452.89343 -38.082728) (xy 453.99706 -38.082728) (xy 454.028691 -38.08322)
			(xy 454.091414 -38.091473) (xy 454.152522 -38.107843) (xy 454.210971 -38.132049) (xy 454.26576 -38.163677)
			(xy 454.315952 -38.202187) (xy 454.360687 -38.246918) (xy 454.399201 -38.297107) (xy 454.430834 -38.351893)
			(xy 454.455045 -38.41034) (xy 454.471419 -38.471447) (xy 454.479677 -38.534169) (xy 454.479677 -38.565836)
			(xy 463.823302 -38.565836) (xy 463.827373 -38.510214) (xy 463.839499 -38.455777) (xy 463.859422 -38.403686)
			(xy 463.886718 -38.355051) (xy 463.920804 -38.310908) (xy 463.960953 -38.272199) (xy 464.006311 -38.239748)
			(xy 464.055911 -38.214247) (xy 464.108695 -38.19624) (xy 464.163538 -38.18611) (xy 464.219272 -38.184073)
			(xy 464.274709 -38.190173) (xy 464.328666 -38.204279) (xy 464.379995 -38.226091) (xy 464.427601 -38.255145)
			(xy 464.470469 -38.29082) (xy 464.507686 -38.332357) (xy 464.538459 -38.37887) (xy 464.562131 -38.429367)
			(xy 464.578199 -38.482774) (xy 464.586319 -38.53795) (xy 464.586828 -38.565836) (xy 464.586319 -38.593722)
			(xy 464.578199 -38.648898) (xy 464.562131 -38.702305) (xy 464.538459 -38.752802) (xy 464.507686 -38.799315)
			(xy 464.470469 -38.840852) (xy 464.427601 -38.876527) (xy 464.379995 -38.905581) (xy 464.328666 -38.927393)
			(xy 464.274709 -38.941499) (xy 464.219272 -38.947599) (xy 464.163538 -38.945562) (xy 464.108695 -38.935432)
			(xy 464.055911 -38.917425) (xy 464.006311 -38.891924) (xy 463.960953 -38.859473) (xy 463.920804 -38.820764)
			(xy 463.886718 -38.776621) (xy 463.859422 -38.727986) (xy 463.839499 -38.675895) (xy 463.827373 -38.621458)
			(xy 463.823302 -38.565836) (xy 454.479677 -38.565836) (xy 454.479677 -38.597431) (xy 454.471419 -38.660153)
			(xy 454.455045 -38.72126) (xy 454.430834 -38.779707) (xy 454.399201 -38.834493) (xy 454.360687 -38.884682)
			(xy 454.315952 -38.929413) (xy 454.26576 -38.967923) (xy 454.210971 -38.999551) (xy 454.152522 -39.023757)
			(xy 454.091414 -39.040127) (xy 454.028691 -39.04838) (xy 453.99706 -39.048944) (xy 452.672196 -39.048944)
			(xy 452.640564 -39.048427) (xy 452.57784 -39.040173) (xy 452.51673 -39.023805) (xy 452.458278 -38.999605)
			(xy 452.403482 -38.967985) (xy 452.35328 -38.929486) (xy 452.330566 -38.907466) (xy 450.641212 -37.218112)
			(xy 450.637484 -37.214587) (xy 450.628912 -37.208951) (xy 450.624194 -37.206936) (xy 450.615558 -37.20338)
			(xy 438.211722 -37.20338) (xy 438.20303 -37.203723) (xy 438.186658 -37.209566) (xy 438.179718 -37.21481)
			(xy 438.175908 -37.218112) (xy 437.635142 -37.758878) (xy 437.612425 -37.780898) (xy 437.562233 -37.819416)
			(xy 437.507441 -37.85105) (xy 437.448988 -37.875259) (xy 437.387874 -37.891629) (xy 437.325146 -37.899878)
			(xy 437.293512 -37.900356) (xy 437.26188 -37.89984) (xy 437.199156 -37.891584) (xy 437.138046 -37.875212)
			(xy 437.079596 -37.851004) (xy 437.024806 -37.819375) (xy 436.974613 -37.780865) (xy 436.929875 -37.736132)
			(xy 436.891359 -37.685944) (xy 436.859722 -37.631157) (xy 436.835507 -37.57271) (xy 436.819128 -37.511603)
			(xy 436.810864 -37.44888) (xy 436.810404 -37.417248) (xy 436.810924 -37.385617) (xy 436.819185 -37.322898)
			(xy 436.835558 -37.261792) (xy 436.859765 -37.203345) (xy 436.89139 -37.148556) (xy 436.929894 -37.098362)
			(xy 436.951882 -37.075618) (xy 437.166258 -36.861496) (xy 437.172955 -36.854061) (xy 437.180548 -36.835569)
			(xy 437.180498 -36.81558) (xy 437.172813 -36.797126) (xy 437.158659 -36.78301) (xy 437.140185 -36.775375)
			(xy 437.13019 -36.774882) (xy 435.395878 -36.774882) (xy 435.387189 -36.775233) (xy 435.370826 -36.781086)
			(xy 435.363874 -36.786312) (xy 435.360064 -36.789614) (xy 433.850796 -38.298882) (xy 433.840563 -38.309849)
			(xy 433.826407 -38.336276) (xy 433.820528 -38.365674) (xy 433.823432 -38.395513) (xy 433.83487 -38.423226)
			(xy 433.853857 -38.446427) (xy 433.87876 -38.46312) (xy 433.907435 -38.471869) (xy 433.922424 -38.472364)
			(xy 441.00242 -38.472364) (xy 441.012448 -38.472813) (xy 441.031009 -38.480401) (xy 441.038488 -38.487096)
			(xy 441.121038 -38.569646) (xy 441.284614 -38.733222) (xy 441.286392 -38.735) (xy 441.286646 -38.735508)
			(xy 441.287662 -38.736524) (xy 441.291726 -38.740588) (xy 441.2996 -38.75913) (xy 441.2996 -39.835836)
			(xy 453.615042 -39.835836) (xy 453.619113 -39.780214) (xy 453.631239 -39.725777) (xy 453.651162 -39.673686)
			(xy 453.678458 -39.625051) (xy 453.712544 -39.580908) (xy 453.752693 -39.542199) (xy 453.798051 -39.509748)
			(xy 453.847651 -39.484247) (xy 453.900435 -39.46624) (xy 453.955278 -39.45611) (xy 454.011012 -39.454073)
			(xy 454.066449 -39.460173) (xy 454.120406 -39.474279) (xy 454.171735 -39.496091) (xy 454.219341 -39.525145)
			(xy 454.262209 -39.56082) (xy 454.299426 -39.602357) (xy 454.330199 -39.64887) (xy 454.353871 -39.699367)
			(xy 454.369939 -39.752774) (xy 454.371809 -39.765478) (xy 457.469492 -39.765478) (xy 457.473563 -39.709856)
			(xy 457.485689 -39.655419) (xy 457.505612 -39.603328) (xy 457.532908 -39.554693) (xy 457.566994 -39.51055)
			(xy 457.607143 -39.471841) (xy 457.652501 -39.43939) (xy 457.702101 -39.413889) (xy 457.754885 -39.395882)
			(xy 457.809728 -39.385752) (xy 457.865462 -39.383715) (xy 457.920899 -39.389815) (xy 457.974856 -39.403921)
			(xy 458.026185 -39.425733) (xy 458.073791 -39.454787) (xy 458.116659 -39.490462) (xy 458.153876 -39.531999)
			(xy 458.184649 -39.578512) (xy 458.208321 -39.629009) (xy 458.224389 -39.682416) (xy 458.232509 -39.737592)
			(xy 458.233018 -39.765478) (xy 458.232509 -39.793364) (xy 458.224389 -39.84854) (xy 458.208321 -39.901947)
			(xy 458.184649 -39.952444) (xy 458.153876 -39.998957) (xy 458.116659 -40.040494) (xy 458.073791 -40.076169)
			(xy 458.026185 -40.105223) (xy 457.974856 -40.127035) (xy 457.920899 -40.141141) (xy 457.865462 -40.147241)
			(xy 457.809728 -40.145204) (xy 457.754885 -40.135074) (xy 457.702101 -40.117067) (xy 457.652501 -40.091566)
			(xy 457.607143 -40.059115) (xy 457.566994 -40.020406) (xy 457.532908 -39.976263) (xy 457.505612 -39.927628)
			(xy 457.485689 -39.875537) (xy 457.473563 -39.8211) (xy 457.469492 -39.765478) (xy 454.371809 -39.765478)
			(xy 454.378059 -39.80795) (xy 454.378568 -39.835836) (xy 454.378059 -39.863722) (xy 454.369939 -39.918898)
			(xy 454.353871 -39.972305) (xy 454.330199 -40.022802) (xy 454.299426 -40.069315) (xy 454.262209 -40.110852)
			(xy 454.219341 -40.146527) (xy 454.171735 -40.175581) (xy 454.120406 -40.197393) (xy 454.066449 -40.211499)
			(xy 454.011012 -40.217599) (xy 453.955278 -40.215562) (xy 453.900435 -40.205432) (xy 453.847651 -40.187425)
			(xy 453.798051 -40.161924) (xy 453.752693 -40.129473) (xy 453.712544 -40.090764) (xy 453.678458 -40.046621)
			(xy 453.651162 -39.997986) (xy 453.631239 -39.945895) (xy 453.619113 -39.891458) (xy 453.615042 -39.835836)
			(xy 441.2996 -39.835836) (xy 441.2996 -40.626538) (xy 461.185766 -40.626538) (xy 461.189837 -40.570916)
			(xy 461.201963 -40.516479) (xy 461.221886 -40.464388) (xy 461.249182 -40.415753) (xy 461.283268 -40.37161)
			(xy 461.323417 -40.332901) (xy 461.368775 -40.30045) (xy 461.418375 -40.274949) (xy 461.471159 -40.256942)
			(xy 461.526002 -40.246812) (xy 461.581736 -40.244775) (xy 461.637173 -40.250875) (xy 461.69113 -40.264981)
			(xy 461.742459 -40.286793) (xy 461.790065 -40.315847) (xy 461.832933 -40.351522) (xy 461.87015 -40.393059)
			(xy 461.900923 -40.439572) (xy 461.924595 -40.490069) (xy 461.940663 -40.543476) (xy 461.948783 -40.598652)
			(xy 461.949292 -40.626538) (xy 461.948783 -40.654424) (xy 461.940663 -40.7096) (xy 461.924595 -40.763007)
			(xy 461.900923 -40.813504) (xy 461.87015 -40.860017) (xy 461.832933 -40.901554) (xy 461.790065 -40.937229)
			(xy 461.742459 -40.966283) (xy 461.69113 -40.988095) (xy 461.637173 -41.002201) (xy 461.581736 -41.008301)
			(xy 461.526002 -41.006264) (xy 461.471159 -40.996134) (xy 461.418375 -40.978127) (xy 461.368775 -40.952626)
			(xy 461.323417 -40.920175) (xy 461.283268 -40.881466) (xy 461.249182 -40.837323) (xy 461.221886 -40.788688)
			(xy 461.201963 -40.736597) (xy 461.189837 -40.68216) (xy 461.185766 -40.626538) (xy 441.2996 -40.626538)
			(xy 441.2996 -41.357296) (xy 452.085454 -41.357296) (xy 452.089525 -41.301674) (xy 452.101651 -41.247237)
			(xy 452.121574 -41.195146) (xy 452.14887 -41.146511) (xy 452.182956 -41.102368) (xy 452.223105 -41.063659)
			(xy 452.268463 -41.031208) (xy 452.318063 -41.005707) (xy 452.370847 -40.9877) (xy 452.42569 -40.97757)
			(xy 452.481424 -40.975533) (xy 452.536861 -40.981633) (xy 452.590818 -40.995739) (xy 452.642147 -41.017551)
			(xy 452.689753 -41.046605) (xy 452.732621 -41.08228) (xy 452.769838 -41.123817) (xy 452.800611 -41.17033)
			(xy 452.824283 -41.220827) (xy 452.840351 -41.274234) (xy 452.848471 -41.32941) (xy 452.84898 -41.357296)
			(xy 452.848471 -41.385182) (xy 452.840351 -41.440358) (xy 452.824283 -41.493765) (xy 452.800611 -41.544262)
			(xy 452.769838 -41.590775) (xy 452.757596 -41.604438) (xy 461.185766 -41.604438) (xy 461.189837 -41.548816)
			(xy 461.201963 -41.494379) (xy 461.221886 -41.442288) (xy 461.249182 -41.393653) (xy 461.283268 -41.34951)
			(xy 461.323417 -41.310801) (xy 461.368775 -41.27835) (xy 461.418375 -41.252849) (xy 461.471159 -41.234842)
			(xy 461.526002 -41.224712) (xy 461.581736 -41.222675) (xy 461.637173 -41.228775) (xy 461.69113 -41.242881)
			(xy 461.742459 -41.264693) (xy 461.790065 -41.293747) (xy 461.832933 -41.329422) (xy 461.87015 -41.370959)
			(xy 461.900923 -41.417472) (xy 461.924595 -41.467969) (xy 461.940663 -41.521376) (xy 461.948783 -41.576552)
			(xy 461.949292 -41.604438) (xy 461.948783 -41.632324) (xy 461.940663 -41.6875) (xy 461.924595 -41.740907)
			(xy 461.900923 -41.791404) (xy 461.87015 -41.837917) (xy 461.832933 -41.879454) (xy 461.790065 -41.915129)
			(xy 461.742459 -41.944183) (xy 461.69113 -41.965995) (xy 461.637173 -41.980101) (xy 461.581736 -41.986201)
			(xy 461.526002 -41.984164) (xy 461.471159 -41.974034) (xy 461.418375 -41.956027) (xy 461.368775 -41.930526)
			(xy 461.323417 -41.898075) (xy 461.283268 -41.859366) (xy 461.249182 -41.815223) (xy 461.221886 -41.766588)
			(xy 461.201963 -41.714497) (xy 461.189837 -41.66006) (xy 461.185766 -41.604438) (xy 452.757596 -41.604438)
			(xy 452.732621 -41.632312) (xy 452.689753 -41.667987) (xy 452.642147 -41.697041) (xy 452.590818 -41.718853)
			(xy 452.536861 -41.732959) (xy 452.481424 -41.739059) (xy 452.42569 -41.737022) (xy 452.370847 -41.726892)
			(xy 452.318063 -41.708885) (xy 452.268463 -41.683384) (xy 452.223105 -41.650933) (xy 452.182956 -41.612224)
			(xy 452.14887 -41.568081) (xy 452.121574 -41.519446) (xy 452.101651 -41.467355) (xy 452.089525 -41.412918)
			(xy 452.085454 -41.357296) (xy 441.2996 -41.357296) (xy 441.2996 -42.121836) (xy 453.615042 -42.121836)
			(xy 453.619113 -42.066214) (xy 453.631239 -42.011777) (xy 453.651162 -41.959686) (xy 453.678458 -41.911051)
			(xy 453.712544 -41.866908) (xy 453.752693 -41.828199) (xy 453.798051 -41.795748) (xy 453.847651 -41.770247)
			(xy 453.900435 -41.75224) (xy 453.955278 -41.74211) (xy 454.011012 -41.740073) (xy 454.066449 -41.746173)
			(xy 454.120406 -41.760279) (xy 454.171735 -41.782091) (xy 454.219341 -41.811145) (xy 454.262209 -41.84682)
			(xy 454.299426 -41.888357) (xy 454.330199 -41.93487) (xy 454.353871 -41.985367) (xy 454.369939 -42.038774)
			(xy 454.378059 -42.09395) (xy 454.378568 -42.121836) (xy 454.378059 -42.149722) (xy 454.369939 -42.204898)
			(xy 454.353871 -42.258305) (xy 454.330199 -42.308802) (xy 454.299426 -42.355315) (xy 454.262209 -42.396852)
			(xy 454.219341 -42.432527) (xy 454.171735 -42.461581) (xy 454.120406 -42.483393) (xy 454.066449 -42.497499)
			(xy 454.011012 -42.503599) (xy 453.955278 -42.501562) (xy 453.900435 -42.491432) (xy 453.847651 -42.473425)
			(xy 453.798051 -42.447924) (xy 453.752693 -42.415473) (xy 453.712544 -42.376764) (xy 453.678458 -42.332621)
			(xy 453.651162 -42.283986) (xy 453.631239 -42.231895) (xy 453.619113 -42.177458) (xy 453.615042 -42.121836)
			(xy 441.2996 -42.121836) (xy 441.2996 -43.400726) (xy 459.00797 -43.400726) (xy 459.012041 -43.345104)
			(xy 459.024167 -43.290667) (xy 459.04409 -43.238576) (xy 459.071386 -43.189941) (xy 459.105472 -43.145798)
			(xy 459.145621 -43.107089) (xy 459.190979 -43.074638) (xy 459.240579 -43.049137) (xy 459.293363 -43.03113)
			(xy 459.348206 -43.021) (xy 459.40394 -43.018963) (xy 459.459377 -43.025063) (xy 459.513334 -43.039169)
			(xy 459.564663 -43.060981) (xy 459.612269 -43.090035) (xy 459.655137 -43.12571) (xy 459.692354 -43.167247)
			(xy 459.723127 -43.21376) (xy 459.746799 -43.264257) (xy 459.762867 -43.317664) (xy 459.770987 -43.37284)
			(xy 459.771496 -43.400726) (xy 459.770987 -43.428612) (xy 459.762867 -43.483788) (xy 459.746799 -43.537195)
			(xy 459.723127 -43.587692) (xy 459.692354 -43.634205) (xy 459.655137 -43.675742) (xy 459.612269 -43.711417)
			(xy 459.564663 -43.740471) (xy 459.513334 -43.762283) (xy 459.459377 -43.776389) (xy 459.40394 -43.782489)
			(xy 459.348206 -43.780452) (xy 459.293363 -43.770322) (xy 459.240579 -43.752315) (xy 459.190979 -43.726814)
			(xy 459.145621 -43.694363) (xy 459.105472 -43.655654) (xy 459.071386 -43.611511) (xy 459.04409 -43.562876)
			(xy 459.024167 -43.510785) (xy 459.012041 -43.456348) (xy 459.00797 -43.400726) (xy 441.2996 -43.400726)
			(xy 441.2996 -43.672506) (xy 441.291726 -43.691048) (xy 441.287662 -43.695112) (xy 441.286646 -43.696128)
			(xy 441.286392 -43.696636) (xy 441.284614 -43.698414) (xy 441.077096 -43.905932) (xy 440.972448 -44.01058)
			(xy 440.965027 -44.017368) (xy 440.94643 -44.024982) (xy 440.93638 -44.025312) (xy 433.686204 -44.025312)
			(xy 433.667662 -44.017692) (xy 433.66055 -44.01058) (xy 433.38877 -43.739054) (xy 433.386992 -43.737276)
			(xy 433.386738 -43.736768) (xy 433.385722 -43.735752) (xy 433.381658 -43.731688) (xy 433.373784 -43.713146)
			(xy 433.373784 -39.021004) (xy 433.373212 -39.006025) (xy 433.364445 -38.977375) (xy 433.34775 -38.952496)
			(xy 433.324562 -38.933524) (xy 433.296869 -38.922086) (xy 433.267051 -38.919166) (xy 433.237666 -38.925013)
			(xy 433.211237 -38.939126) (xy 433.200302 -38.949376) (xy 433.00904 -39.140638) (xy 433.005517 -39.144367)
			(xy 432.999886 -39.152941) (xy 432.997864 -39.157656) (xy 432.994308 -39.166292) (xy 432.994308 -44.511214)
			(xy 461.600294 -44.511214) (xy 461.604365 -44.455592) (xy 461.616491 -44.401155) (xy 461.636414 -44.349064)
			(xy 461.66371 -44.300429) (xy 461.697796 -44.256286) (xy 461.737945 -44.217577) (xy 461.783303 -44.185126)
			(xy 461.832903 -44.159625) (xy 461.885687 -44.141618) (xy 461.94053 -44.131488) (xy 461.996264 -44.129451)
			(xy 462.051701 -44.135551) (xy 462.105658 -44.149657) (xy 462.156987 -44.171469) (xy 462.204593 -44.200523)
			(xy 462.247461 -44.236198) (xy 462.284678 -44.277735) (xy 462.315451 -44.324248) (xy 462.339123 -44.374745)
			(xy 462.355191 -44.428152) (xy 462.363311 -44.483328) (xy 462.36382 -44.511214) (xy 462.363311 -44.5391)
			(xy 462.355191 -44.594276) (xy 462.339123 -44.647683) (xy 462.315451 -44.69818) (xy 462.284678 -44.744693)
			(xy 462.247461 -44.78623) (xy 462.204593 -44.821905) (xy 462.156987 -44.850959) (xy 462.105658 -44.872771)
			(xy 462.051701 -44.886877) (xy 461.996264 -44.892977) (xy 461.94053 -44.89094) (xy 461.885687 -44.88081)
			(xy 461.832903 -44.862803) (xy 461.783303 -44.837302) (xy 461.737945 -44.804851) (xy 461.697796 -44.766142)
			(xy 461.66371 -44.721999) (xy 461.636414 -44.673364) (xy 461.616491 -44.621273) (xy 461.604365 -44.566836)
			(xy 461.600294 -44.511214) (xy 432.994308 -44.511214) (xy 432.994308 -45.20692) (xy 432.993882 -45.216989)
			(xy 432.986163 -45.235589) (xy 432.979322 -45.242988) (xy 432.743356 -45.478954) (xy 450.958202 -45.478954)
			(xy 450.962273 -45.423332) (xy 450.974399 -45.368895) (xy 450.994322 -45.316804) (xy 451.021618 -45.268169)
			(xy 451.055704 -45.224026) (xy 451.095853 -45.185317) (xy 451.141211 -45.152866) (xy 451.190811 -45.127365)
			(xy 451.243595 -45.109358) (xy 451.298438 -45.099228) (xy 451.354172 -45.097191) (xy 451.409609 -45.103291)
			(xy 451.463566 -45.117397) (xy 451.514895 -45.139209) (xy 451.562501 -45.168263) (xy 451.605369 -45.203938)
			(xy 451.642586 -45.245475) (xy 451.673359 -45.291988) (xy 451.697031 -45.342485) (xy 451.713099 -45.395892)
			(xy 451.721219 -45.451068) (xy 451.721728 -45.478954) (xy 451.721219 -45.50684) (xy 451.713099 -45.562016)
			(xy 451.710808 -45.569632) (xy 451.973948 -45.569632) (xy 451.978019 -45.51401) (xy 451.990145 -45.459573)
			(xy 452.010068 -45.407482) (xy 452.037364 -45.358847) (xy 452.07145 -45.314704) (xy 452.111599 -45.275995)
			(xy 452.156957 -45.243544) (xy 452.206557 -45.218043) (xy 452.259341 -45.200036) (xy 452.314184 -45.189906)
			(xy 452.369918 -45.187869) (xy 452.425355 -45.193969) (xy 452.479312 -45.208075) (xy 452.530641 -45.229887)
			(xy 452.535876 -45.233082) (xy 455.152758 -45.233082) (xy 455.156829 -45.17746) (xy 455.168955 -45.123023)
			(xy 455.188878 -45.070932) (xy 455.216174 -45.022297) (xy 455.25026 -44.978154) (xy 455.290409 -44.939445)
			(xy 455.335767 -44.906994) (xy 455.385367 -44.881493) (xy 455.438151 -44.863486) (xy 455.492994 -44.853356)
			(xy 455.548728 -44.851319) (xy 455.604165 -44.857419) (xy 455.658122 -44.871525) (xy 455.709451 -44.893337)
			(xy 455.757057 -44.922391) (xy 455.799925 -44.958066) (xy 455.837142 -44.999603) (xy 455.8481 -45.016166)
			(xy 456.958698 -45.016166) (xy 456.962769 -44.960544) (xy 456.974895 -44.906107) (xy 456.994818 -44.854016)
			(xy 457.022114 -44.805381) (xy 457.0562 -44.761238) (xy 457.096349 -44.722529) (xy 457.141707 -44.690078)
			(xy 457.191307 -44.664577) (xy 457.244091 -44.64657) (xy 457.298934 -44.63644) (xy 457.354668 -44.634403)
			(xy 457.410105 -44.640503) (xy 457.464062 -44.654609) (xy 457.515391 -44.676421) (xy 457.562997 -44.705475)
			(xy 457.605865 -44.74115) (xy 457.643082 -44.782687) (xy 457.673855 -44.8292) (xy 457.697527 -44.879697)
			(xy 457.713595 -44.933104) (xy 457.721715 -44.98828) (xy 457.722224 -45.016166) (xy 457.721715 -45.044052)
			(xy 457.713595 -45.099228) (xy 457.697527 -45.152635) (xy 457.673855 -45.203132) (xy 457.643082 -45.249645)
			(xy 457.605865 -45.291182) (xy 457.562997 -45.326857) (xy 457.515391 -45.355911) (xy 457.464062 -45.377723)
			(xy 457.410105 -45.391829) (xy 457.354668 -45.397929) (xy 457.298934 -45.395892) (xy 457.244091 -45.385762)
			(xy 457.191307 -45.367755) (xy 457.141707 -45.342254) (xy 457.096349 -45.309803) (xy 457.0562 -45.271094)
			(xy 457.022114 -45.226951) (xy 456.994818 -45.178316) (xy 456.974895 -45.126225) (xy 456.962769 -45.071788)
			(xy 456.958698 -45.016166) (xy 455.8481 -45.016166) (xy 455.867915 -45.046116) (xy 455.891587 -45.096613)
			(xy 455.907655 -45.15002) (xy 455.915775 -45.205196) (xy 455.916284 -45.233082) (xy 455.915775 -45.260968)
			(xy 455.907655 -45.316144) (xy 455.891587 -45.369551) (xy 455.867915 -45.420048) (xy 455.837142 -45.466561)
			(xy 455.799925 -45.508098) (xy 455.757057 -45.543773) (xy 455.709451 -45.572827) (xy 455.658122 -45.594639)
			(xy 455.604165 -45.608745) (xy 455.548728 -45.614845) (xy 455.492994 -45.612808) (xy 455.438151 -45.602678)
			(xy 455.385367 -45.584671) (xy 455.335767 -45.55917) (xy 455.290409 -45.526719) (xy 455.25026 -45.48801)
			(xy 455.216174 -45.443867) (xy 455.188878 -45.395232) (xy 455.168955 -45.343141) (xy 455.156829 -45.288704)
			(xy 455.152758 -45.233082) (xy 452.535876 -45.233082) (xy 452.578247 -45.258941) (xy 452.621115 -45.294616)
			(xy 452.658332 -45.336153) (xy 452.689105 -45.382666) (xy 452.712777 -45.433163) (xy 452.728845 -45.48657)
			(xy 452.736965 -45.541746) (xy 452.737474 -45.569632) (xy 452.736965 -45.597518) (xy 452.728845 -45.652694)
			(xy 452.712777 -45.706101) (xy 452.689105 -45.756598) (xy 452.658332 -45.803111) (xy 452.621115 -45.844648)
			(xy 452.581968 -45.877226) (xy 461.205832 -45.877226) (xy 461.209903 -45.821604) (xy 461.222029 -45.767167)
			(xy 461.241952 -45.715076) (xy 461.269248 -45.666441) (xy 461.303334 -45.622298) (xy 461.343483 -45.583589)
			(xy 461.388841 -45.551138) (xy 461.438441 -45.525637) (xy 461.491225 -45.50763) (xy 461.546068 -45.4975)
			(xy 461.601802 -45.495463) (xy 461.657239 -45.501563) (xy 461.711196 -45.515669) (xy 461.762525 -45.537481)
			(xy 461.810131 -45.566535) (xy 461.852999 -45.60221) (xy 461.890216 -45.643747) (xy 461.920989 -45.69026)
			(xy 461.944661 -45.740757) (xy 461.960729 -45.794164) (xy 461.968849 -45.84934) (xy 461.969358 -45.877226)
			(xy 461.968849 -45.905112) (xy 461.960729 -45.960288) (xy 461.944661 -46.013695) (xy 461.920989 -46.064192)
			(xy 461.890216 -46.110705) (xy 461.852999 -46.152242) (xy 461.810131 -46.187917) (xy 461.762525 -46.216971)
			(xy 461.711196 -46.238783) (xy 461.657239 -46.252889) (xy 461.601802 -46.258989) (xy 461.546068 -46.256952)
			(xy 461.491225 -46.246822) (xy 461.438441 -46.228815) (xy 461.388841 -46.203314) (xy 461.343483 -46.170863)
			(xy 461.303334 -46.132154) (xy 461.269248 -46.088011) (xy 461.241952 -46.039376) (xy 461.222029 -45.987285)
			(xy 461.209903 -45.932848) (xy 461.205832 -45.877226) (xy 452.581968 -45.877226) (xy 452.578247 -45.880323)
			(xy 452.530641 -45.909377) (xy 452.479312 -45.931189) (xy 452.425355 -45.945295) (xy 452.369918 -45.951395)
			(xy 452.314184 -45.949358) (xy 452.259341 -45.939228) (xy 452.206557 -45.921221) (xy 452.156957 -45.89572)
			(xy 452.111599 -45.863269) (xy 452.07145 -45.82456) (xy 452.037364 -45.780417) (xy 452.010068 -45.731782)
			(xy 451.990145 -45.679691) (xy 451.978019 -45.625254) (xy 451.973948 -45.569632) (xy 451.710808 -45.569632)
			(xy 451.697031 -45.615423) (xy 451.673359 -45.66592) (xy 451.642586 -45.712433) (xy 451.605369 -45.75397)
			(xy 451.562501 -45.789645) (xy 451.514895 -45.818699) (xy 451.463566 -45.840511) (xy 451.409609 -45.854617)
			(xy 451.354172 -45.860717) (xy 451.298438 -45.85868) (xy 451.243595 -45.84855) (xy 451.190811 -45.830543)
			(xy 451.141211 -45.805042) (xy 451.095853 -45.772591) (xy 451.055704 -45.733882) (xy 451.021618 -45.689739)
			(xy 450.994322 -45.641104) (xy 450.974399 -45.589013) (xy 450.962273 -45.534576) (xy 450.958202 -45.478954)
			(xy 432.743356 -45.478954) (xy 430.964848 -47.257462) (xy 452.986392 -47.257462) (xy 452.990463 -47.20184)
			(xy 453.002589 -47.147403) (xy 453.022512 -47.095312) (xy 453.049808 -47.046677) (xy 453.083894 -47.002534)
			(xy 453.124043 -46.963825) (xy 453.169401 -46.931374) (xy 453.219001 -46.905873) (xy 453.271785 -46.887866)
			(xy 453.326628 -46.877736) (xy 453.382362 -46.875699) (xy 453.437799 -46.881799) (xy 453.491756 -46.895905)
			(xy 453.543085 -46.917717) (xy 453.590691 -46.946771) (xy 453.633559 -46.982446) (xy 453.670776 -47.023983)
			(xy 453.701549 -47.070496) (xy 453.725221 -47.120993) (xy 453.741289 -47.1744) (xy 453.749409 -47.229576)
			(xy 453.749918 -47.257462) (xy 453.749409 -47.285348) (xy 453.741289 -47.340524) (xy 453.725221 -47.393931)
			(xy 453.701549 -47.444428) (xy 453.680726 -47.475902) (xy 457.470762 -47.475902) (xy 457.474833 -47.42028)
			(xy 457.486959 -47.365843) (xy 457.506882 -47.313752) (xy 457.534178 -47.265117) (xy 457.568264 -47.220974)
			(xy 457.608413 -47.182265) (xy 457.653771 -47.149814) (xy 457.703371 -47.124313) (xy 457.756155 -47.106306)
			(xy 457.810998 -47.096176) (xy 457.866732 -47.094139) (xy 457.922169 -47.100239) (xy 457.976126 -47.114345)
			(xy 458.027455 -47.136157) (xy 458.075061 -47.165211) (xy 458.117929 -47.200886) (xy 458.155146 -47.242423)
			(xy 458.185919 -47.288936) (xy 458.209591 -47.339433) (xy 458.225659 -47.39284) (xy 458.233779 -47.448016)
			(xy 458.23407 -47.463964) (xy 458.461362 -47.463964) (xy 458.465433 -47.408342) (xy 458.477559 -47.353905)
			(xy 458.497482 -47.301814) (xy 458.524778 -47.253179) (xy 458.558864 -47.209036) (xy 458.599013 -47.170327)
			(xy 458.644371 -47.137876) (xy 458.693971 -47.112375) (xy 458.746755 -47.094368) (xy 458.801598 -47.084238)
			(xy 458.857332 -47.082201) (xy 458.912769 -47.088301) (xy 458.966726 -47.102407) (xy 459.018055 -47.124219)
			(xy 459.065661 -47.153273) (xy 459.108529 -47.188948) (xy 459.145746 -47.230485) (xy 459.176519 -47.276998)
			(xy 459.200191 -47.327495) (xy 459.216259 -47.380902) (xy 459.224379 -47.436078) (xy 459.224888 -47.463964)
			(xy 459.224379 -47.49185) (xy 459.216259 -47.547026) (xy 459.200191 -47.600433) (xy 459.176519 -47.65093)
			(xy 459.145746 -47.697443) (xy 459.108529 -47.73898) (xy 459.065661 -47.774655) (xy 459.018055 -47.803709)
			(xy 458.966726 -47.825521) (xy 458.912769 -47.839627) (xy 458.857332 -47.845727) (xy 458.801598 -47.84369)
			(xy 458.746755 -47.83356) (xy 458.693971 -47.815553) (xy 458.644371 -47.790052) (xy 458.599013 -47.757601)
			(xy 458.558864 -47.718892) (xy 458.524778 -47.674749) (xy 458.497482 -47.626114) (xy 458.477559 -47.574023)
			(xy 458.465433 -47.519586) (xy 458.461362 -47.463964) (xy 458.23407 -47.463964) (xy 458.234288 -47.475902)
			(xy 458.233779 -47.503788) (xy 458.225659 -47.558964) (xy 458.209591 -47.612371) (xy 458.185919 -47.662868)
			(xy 458.155146 -47.709381) (xy 458.117929 -47.750918) (xy 458.075061 -47.786593) (xy 458.027455 -47.815647)
			(xy 457.976126 -47.837459) (xy 457.922169 -47.851565) (xy 457.866732 -47.857665) (xy 457.810998 -47.855628)
			(xy 457.756155 -47.845498) (xy 457.703371 -47.827491) (xy 457.653771 -47.80199) (xy 457.608413 -47.769539)
			(xy 457.568264 -47.73083) (xy 457.534178 -47.686687) (xy 457.506882 -47.638052) (xy 457.486959 -47.585961)
			(xy 457.474833 -47.531524) (xy 457.470762 -47.475902) (xy 453.680726 -47.475902) (xy 453.670776 -47.490941)
			(xy 453.633559 -47.532478) (xy 453.590691 -47.568153) (xy 453.543085 -47.597207) (xy 453.491756 -47.619019)
			(xy 453.437799 -47.633125) (xy 453.382362 -47.639225) (xy 453.326628 -47.637188) (xy 453.271785 -47.627058)
			(xy 453.219001 -47.609051) (xy 453.169401 -47.58355) (xy 453.124043 -47.551099) (xy 453.083894 -47.51239)
			(xy 453.049808 -47.468247) (xy 453.022512 -47.419612) (xy 453.002589 -47.367521) (xy 452.990463 -47.313084)
			(xy 452.986392 -47.257462) (xy 430.964848 -47.257462) (xy 430.239932 -47.982378) (xy 430.236406 -47.986105)
			(xy 430.230766 -47.994675) (xy 430.228756 -47.999396) (xy 430.2252 -48.008032) (xy 430.2252 -49.333751)
			(xy 449.466958 -49.333751) (xy 449.466958 -49.279249) (xy 449.474714 -49.225301) (xy 449.490068 -49.173006)
			(xy 449.512708 -49.123428) (xy 449.542173 -49.077576) (xy 449.577864 -49.036385) (xy 449.619052 -49.000691)
			(xy 449.664901 -48.971223) (xy 449.714478 -48.948579) (xy 449.766771 -48.93322) (xy 449.820719 -48.92546)
			(xy 449.84797 -48.924972) (xy 449.87568 -48.925455) (xy 449.930515 -48.933487) (xy 449.983609 -48.949372)
			(xy 450.033845 -48.972775) (xy 450.080164 -49.003203) (xy 450.101208 -49.021238) (xy 450.10836 -49.027025)
			(xy 450.125545 -49.033545) (xy 450.134736 -49.033938) (xy 450.212206 -49.033938) (xy 450.229224 -49.027588)
			(xy 450.236336 -49.021238) (xy 450.257401 -49.003229) (xy 450.303712 -48.972794) (xy 450.353943 -48.949387)
			(xy 450.407034 -48.933501) (xy 450.461866 -48.925472) (xy 450.489574 -48.924972) (xy 450.516827 -48.925474)
			(xy 450.570778 -48.933227) (xy 450.623076 -48.94858) (xy 450.672657 -48.97122) (xy 450.718511 -49.000686)
			(xy 450.759704 -49.036377) (xy 450.763093 -49.040288) (xy 453.089262 -49.040288) (xy 453.093333 -48.984666)
			(xy 453.105459 -48.930229) (xy 453.125382 -48.878138) (xy 453.152678 -48.829503) (xy 453.186764 -48.78536)
			(xy 453.226913 -48.746651) (xy 453.272271 -48.7142) (xy 453.321871 -48.688699) (xy 453.374655 -48.670692)
			(xy 453.429498 -48.660562) (xy 453.485232 -48.658525) (xy 453.540669 -48.664625) (xy 453.594626 -48.678731)
			(xy 453.645955 -48.700543) (xy 453.693561 -48.729597) (xy 453.736429 -48.765272) (xy 453.773646 -48.806809)
			(xy 453.804419 -48.853322) (xy 453.828091 -48.903819) (xy 453.844159 -48.957226) (xy 453.852279 -49.012402)
			(xy 453.852788 -49.040288) (xy 453.852279 -49.068174) (xy 453.844159 -49.12335) (xy 453.828091 -49.176757)
			(xy 453.804419 -49.227254) (xy 453.773646 -49.273767) (xy 453.736429 -49.315304) (xy 453.693561 -49.350979)
			(xy 453.645955 -49.380033) (xy 453.594626 -49.401845) (xy 453.540669 -49.415951) (xy 453.485232 -49.422051)
			(xy 453.429498 -49.420014) (xy 453.374655 -49.409884) (xy 453.321871 -49.391877) (xy 453.272271 -49.366376)
			(xy 453.226913 -49.333925) (xy 453.186764 -49.295216) (xy 453.152678 -49.251073) (xy 453.125382 -49.202438)
			(xy 453.105459 -49.150347) (xy 453.093333 -49.09591) (xy 453.089262 -49.040288) (xy 450.763093 -49.040288)
			(xy 450.795399 -49.077569) (xy 450.824868 -49.123421) (xy 450.847511 -49.173) (xy 450.862867 -49.225297)
			(xy 450.870625 -49.279247) (xy 450.870625 -49.333753) (xy 450.862867 -49.387703) (xy 450.847511 -49.44)
			(xy 450.841324 -49.453546) (xy 460.176878 -49.453546) (xy 460.180949 -49.397924) (xy 460.193075 -49.343487)
			(xy 460.212998 -49.291396) (xy 460.240294 -49.242761) (xy 460.27438 -49.198618) (xy 460.314529 -49.159909)
			(xy 460.359887 -49.127458) (xy 460.409487 -49.101957) (xy 460.462271 -49.08395) (xy 460.517114 -49.07382)
			(xy 460.572848 -49.071783) (xy 460.628285 -49.077883) (xy 460.682242 -49.091989) (xy 460.733571 -49.113801)
			(xy 460.781177 -49.142855) (xy 460.824045 -49.17853) (xy 460.861262 -49.220067) (xy 460.892035 -49.26658)
			(xy 460.915707 -49.317077) (xy 460.931775 -49.370484) (xy 460.939895 -49.42566) (xy 460.940404 -49.453546)
			(xy 460.939895 -49.481432) (xy 460.931775 -49.536608) (xy 460.915707 -49.590015) (xy 460.892035 -49.640512)
			(xy 460.861262 -49.687025) (xy 460.824045 -49.728562) (xy 460.781177 -49.764237) (xy 460.733571 -49.793291)
			(xy 460.682242 -49.815103) (xy 460.628285 -49.829209) (xy 460.572848 -49.835309) (xy 460.517114 -49.833272)
			(xy 460.462271 -49.823142) (xy 460.409487 -49.805135) (xy 460.359887 -49.779634) (xy 460.314529 -49.747183)
			(xy 460.27438 -49.708474) (xy 460.240294 -49.664331) (xy 460.212998 -49.615696) (xy 460.193075 -49.563605)
			(xy 460.180949 -49.509168) (xy 460.176878 -49.453546) (xy 450.841324 -49.453546) (xy 450.824868 -49.489579)
			(xy 450.795399 -49.535431) (xy 450.759704 -49.576623) (xy 450.718511 -49.612314) (xy 450.672657 -49.64178)
			(xy 450.623076 -49.66442) (xy 450.570778 -49.679773) (xy 450.516827 -49.687526) (xy 450.489574 -49.687988)
			(xy 450.461865 -49.687489) (xy 450.40703 -49.679462) (xy 450.353935 -49.663582) (xy 450.303699 -49.640182)
			(xy 450.257379 -49.609756) (xy 450.236336 -49.591722) (xy 450.229196 -49.585918) (xy 450.212002 -49.579407)
			(xy 450.202808 -49.579022) (xy 450.125338 -49.579022) (xy 450.10832 -49.585372) (xy 450.101208 -49.591722)
			(xy 450.080173 -49.609767) (xy 450.033853 -49.640195) (xy 449.983614 -49.663594) (xy 449.930517 -49.679472)
			(xy 449.87568 -49.687493) (xy 449.84797 -49.687988) (xy 449.820719 -49.68754) (xy 449.766771 -49.67978)
			(xy 449.714478 -49.664421) (xy 449.664901 -49.641777) (xy 449.619052 -49.612309) (xy 449.577864 -49.576615)
			(xy 449.542173 -49.535424) (xy 449.512708 -49.489572) (xy 449.490068 -49.439994) (xy 449.474714 -49.387699)
			(xy 449.466958 -49.333751) (xy 430.2252 -49.333751) (xy 430.2252 -50.489796) (xy 431.237386 -50.489796)
			(xy 431.237386 -50.4051) (xy 431.245437 -50.320786) (xy 431.261466 -50.23762) (xy 431.285327 -50.156353)
			(xy 431.316806 -50.077723) (xy 431.355617 -50.002442) (xy 431.401407 -49.93119) (xy 431.453763 -49.864614)
			(xy 431.512211 -49.803316) (xy 431.576221 -49.747851) (xy 431.645213 -49.698722) (xy 431.718563 -49.656373)
			(xy 431.795606 -49.621189) (xy 431.875645 -49.593487) (xy 431.957954 -49.573519) (xy 432.041789 -49.561466)
			(xy 432.12639 -49.557436) (xy 432.210991 -49.561466) (xy 432.294826 -49.573519) (xy 432.377135 -49.593487)
			(xy 432.457174 -49.621189) (xy 432.534217 -49.656373) (xy 432.607567 -49.698722) (xy 432.676559 -49.747851)
			(xy 432.740569 -49.803316) (xy 432.799017 -49.864614) (xy 432.851373 -49.93119) (xy 432.897163 -50.002442)
			(xy 432.935974 -50.077723) (xy 432.967453 -50.156353) (xy 432.991314 -50.23762) (xy 433.007343 -50.320786)
			(xy 433.015394 -50.4051) (xy 433.015898 -50.447448) (xy 433.015394 -50.489796) (xy 438.952636 -50.489796)
			(xy 438.952636 -50.4051) (xy 438.960687 -50.320786) (xy 438.976716 -50.23762) (xy 439.000577 -50.156353)
			(xy 439.032056 -50.077723) (xy 439.070867 -50.002442) (xy 439.116657 -49.93119) (xy 439.169013 -49.864614)
			(xy 439.227461 -49.803316) (xy 439.291471 -49.747851) (xy 439.360463 -49.698722) (xy 439.433813 -49.656373)
			(xy 439.510856 -49.621189) (xy 439.590895 -49.593487) (xy 439.673204 -49.573519) (xy 439.757039 -49.561466)
			(xy 439.84164 -49.557436) (xy 439.926241 -49.561466) (xy 440.010076 -49.573519) (xy 440.092385 -49.593487)
			(xy 440.172424 -49.621189) (xy 440.249467 -49.656373) (xy 440.322817 -49.698722) (xy 440.391809 -49.747851)
			(xy 440.455819 -49.803316) (xy 440.514267 -49.864614) (xy 440.566623 -49.93119) (xy 440.612413 -50.002442)
			(xy 440.651224 -50.077723) (xy 440.682703 -50.156353) (xy 440.706564 -50.23762) (xy 440.721842 -50.316892)
			(xy 459.681578 -50.316892) (xy 459.685649 -50.26127) (xy 459.697775 -50.206833) (xy 459.717698 -50.154742)
			(xy 459.744994 -50.106107) (xy 459.77908 -50.061964) (xy 459.819229 -50.023255) (xy 459.864587 -49.990804)
			(xy 459.914187 -49.965303) (xy 459.966971 -49.947296) (xy 460.021814 -49.937166) (xy 460.077548 -49.935129)
			(xy 460.132985 -49.941229) (xy 460.186942 -49.955335) (xy 460.238271 -49.977147) (xy 460.285877 -50.006201)
			(xy 460.328745 -50.041876) (xy 460.365962 -50.083413) (xy 460.396735 -50.129926) (xy 460.420407 -50.180423)
			(xy 460.436475 -50.23383) (xy 460.444595 -50.289006) (xy 460.445104 -50.316892) (xy 460.444595 -50.344778)
			(xy 460.436475 -50.399954) (xy 460.420407 -50.453361) (xy 460.396735 -50.503858) (xy 460.365962 -50.550371)
			(xy 460.328745 -50.591908) (xy 460.285877 -50.627583) (xy 460.238271 -50.656637) (xy 460.186942 -50.678449)
			(xy 460.132985 -50.692555) (xy 460.077548 -50.698655) (xy 460.021814 -50.696618) (xy 459.966971 -50.686488)
			(xy 459.914187 -50.668481) (xy 459.864587 -50.64298) (xy 459.819229 -50.610529) (xy 459.77908 -50.57182)
			(xy 459.744994 -50.527677) (xy 459.717698 -50.479042) (xy 459.697775 -50.426951) (xy 459.685649 -50.372514)
			(xy 459.681578 -50.316892) (xy 440.721842 -50.316892) (xy 440.722593 -50.320786) (xy 440.730644 -50.4051)
			(xy 440.731148 -50.447448) (xy 440.730644 -50.489796) (xy 440.722593 -50.57411) (xy 440.706564 -50.657276)
			(xy 440.682703 -50.738543) (xy 440.651224 -50.817173) (xy 440.612413 -50.892454) (xy 440.566623 -50.963706)
			(xy 440.514267 -51.030282) (xy 440.455819 -51.09158) (xy 440.391809 -51.147045) (xy 440.322817 -51.196174)
			(xy 440.249467 -51.238523) (xy 440.172424 -51.273707) (xy 440.092385 -51.301409) (xy 440.010076 -51.321377)
			(xy 439.926241 -51.33343) (xy 439.84164 -51.337461) (xy 439.757039 -51.33343) (xy 439.673204 -51.321377)
			(xy 439.590895 -51.301409) (xy 439.510856 -51.273707) (xy 439.433813 -51.238523) (xy 439.360463 -51.196174)
			(xy 439.291471 -51.147045) (xy 439.227461 -51.09158) (xy 439.169013 -51.030282) (xy 439.116657 -50.963706)
			(xy 439.070867 -50.892454) (xy 439.032056 -50.817173) (xy 439.000577 -50.738543) (xy 438.976716 -50.657276)
			(xy 438.960687 -50.57411) (xy 438.952636 -50.489796) (xy 433.015394 -50.489796) (xy 433.007343 -50.57411)
			(xy 432.991314 -50.657276) (xy 432.967453 -50.738543) (xy 432.935974 -50.817173) (xy 432.897163 -50.892454)
			(xy 432.851373 -50.963706) (xy 432.799017 -51.030282) (xy 432.740569 -51.09158) (xy 432.676559 -51.147045)
			(xy 432.607567 -51.196174) (xy 432.534217 -51.238523) (xy 432.457174 -51.273707) (xy 432.377135 -51.301409)
			(xy 432.294826 -51.321377) (xy 432.210991 -51.33343) (xy 432.12639 -51.337461) (xy 432.041789 -51.33343)
			(xy 431.957954 -51.321377) (xy 431.875645 -51.301409) (xy 431.795606 -51.273707) (xy 431.718563 -51.238523)
			(xy 431.645213 -51.196174) (xy 431.576221 -51.147045) (xy 431.512211 -51.09158) (xy 431.453763 -51.030282)
			(xy 431.401407 -50.963706) (xy 431.355617 -50.892454) (xy 431.316806 -50.817173) (xy 431.285327 -50.738543)
			(xy 431.261466 -50.657276) (xy 431.245437 -50.57411) (xy 431.237386 -50.489796) (xy 430.2252 -50.489796)
			(xy 430.2252 -51.402053) (xy 445.516957 -51.402053) (xy 445.516957 -51.347547) (xy 445.524715 -51.293595)
			(xy 445.540071 -51.241296) (xy 445.562715 -51.191715) (xy 445.592184 -51.145861) (xy 445.62788 -51.104668)
			(xy 445.669074 -51.068975) (xy 445.714929 -51.039507) (xy 445.764511 -51.016866) (xy 445.81681 -51.001511)
			(xy 445.870763 -50.993756) (xy 445.898016 -50.993294) (xy 445.925725 -50.993804) (xy 445.980559 -51.001828)
			(xy 446.033653 -51.017707) (xy 446.08389 -51.041104) (xy 446.13021 -51.071527) (xy 446.151254 -51.08956)
			(xy 446.15839 -51.095369) (xy 446.175588 -51.101875) (xy 446.184782 -51.10226) (xy 446.262252 -51.10226)
			(xy 446.27927 -51.09591) (xy 446.286382 -51.08956) (xy 446.307418 -51.071517) (xy 446.353739 -51.041089)
			(xy 446.403977 -51.01769) (xy 446.457073 -51.001812) (xy 446.51191 -50.99379) (xy 446.53962 -50.993294)
			(xy 446.56687 -50.993777) (xy 446.620816 -51.001536) (xy 446.673109 -51.016893) (xy 446.722684 -51.039535)
			(xy 446.768532 -51.069002) (xy 446.80972 -51.104694) (xy 446.84541 -51.145884) (xy 446.874874 -51.191734)
			(xy 446.897514 -51.24131) (xy 446.912868 -51.293603) (xy 446.920624 -51.34755) (xy 446.920624 -51.40205)
			(xy 446.918324 -51.418049) (xy 447.310282 -51.418049) (xy 447.310282 -51.363551) (xy 447.318037 -51.309608)
			(xy 447.33339 -51.257317) (xy 447.356027 -51.207743) (xy 447.385489 -51.161895) (xy 447.421176 -51.120707)
			(xy 447.46236 -51.085016) (xy 447.508205 -51.055548) (xy 447.557776 -51.032905) (xy 447.610065 -51.017546)
			(xy 447.664007 -51.009785) (xy 447.691256 -51.009296) (xy 447.718966 -51.009781) (xy 447.773801 -51.017812)
			(xy 447.826895 -51.033696) (xy 447.877132 -51.057099) (xy 447.923451 -51.087527) (xy 447.944494 -51.105562)
			(xy 447.951648 -51.111346) (xy 447.968832 -51.117867) (xy 447.978022 -51.118262) (xy 448.055492 -51.118262)
			(xy 448.07251 -51.111912) (xy 448.079622 -51.105562) (xy 448.100643 -51.0875) (xy 448.146968 -51.057076)
			(xy 448.197209 -51.03368) (xy 448.25031 -51.017806) (xy 448.305149 -51.009789) (xy 448.33286 -51.009296)
			(xy 448.360115 -51.009749) (xy 448.414071 -51.017501) (xy 448.466374 -51.032854) (xy 448.51596 -51.055494)
			(xy 448.524452 -51.060951) (xy 449.047858 -51.060951) (xy 449.047858 -51.006449) (xy 449.055614 -50.952501)
			(xy 449.070968 -50.900206) (xy 449.093608 -50.850628) (xy 449.123073 -50.804776) (xy 449.158764 -50.763585)
			(xy 449.199952 -50.727891) (xy 449.245801 -50.698423) (xy 449.295378 -50.675779) (xy 449.347671 -50.66042)
			(xy 449.401619 -50.65266) (xy 449.42887 -50.652172) (xy 449.45658 -50.652655) (xy 449.511415 -50.660687)
			(xy 449.564509 -50.676572) (xy 449.614745 -50.699975) (xy 449.661064 -50.730403) (xy 449.682108 -50.748438)
			(xy 449.68926 -50.754225) (xy 449.706445 -50.760745) (xy 449.715636 -50.761138) (xy 449.793106 -50.761138)
			(xy 449.810124 -50.754788) (xy 449.817236 -50.748438) (xy 449.838301 -50.730429) (xy 449.884612 -50.699994)
			(xy 449.934843 -50.676587) (xy 449.987934 -50.660701) (xy 450.042766 -50.652672) (xy 450.070474 -50.652172)
			(xy 450.096709 -50.652656) (xy 450.148683 -50.659847) (xy 450.199181 -50.674097) (xy 450.247247 -50.695137)
			(xy 450.291975 -50.722569) (xy 450.332518 -50.755875) (xy 450.350636 -50.774854) (xy 450.357801 -50.781955)
			(xy 450.376138 -50.79033) (xy 450.386196 -50.79111) (xy 450.459094 -50.793142) (xy 450.469199 -50.793029)
			(xy 450.488061 -50.785822) (xy 450.49567 -50.779172) (xy 450.517104 -50.759388) (xy 450.564862 -50.725905)
			(xy 450.617157 -50.700074) (xy 450.672772 -50.682494) (xy 450.730413 -50.673576) (xy 450.759576 -50.673)
			(xy 450.787286 -50.673473) (xy 450.842122 -50.681506) (xy 450.895217 -50.697393) (xy 450.945453 -50.720799)
			(xy 450.991771 -50.75123) (xy 451.012814 -50.769266) (xy 451.019961 -50.775059) (xy 451.03715 -50.781574)
			(xy 451.046342 -50.781966) (xy 451.123812 -50.781966) (xy 451.14083 -50.775616) (xy 451.147942 -50.769266)
			(xy 451.168995 -50.751243) (xy 451.21531 -50.720812) (xy 451.265544 -50.697409) (xy 451.318637 -50.681526)
			(xy 451.373471 -50.673499) (xy 451.40118 -50.673) (xy 451.428434 -50.673446) (xy 451.482389 -50.681201)
			(xy 451.53469 -50.696555) (xy 451.584274 -50.719197) (xy 451.63013 -50.748665) (xy 451.671326 -50.78436)
			(xy 451.707023 -50.825554) (xy 451.736493 -50.871409) (xy 451.759138 -50.920991) (xy 451.774495 -50.973292)
			(xy 451.782253 -51.027246) (xy 451.782253 -51.081754) (xy 451.774495 -51.135708) (xy 451.759138 -51.188009)
			(xy 451.736493 -51.237591) (xy 451.707023 -51.283446) (xy 451.671326 -51.32464) (xy 451.63013 -51.360335)
			(xy 451.584274 -51.389803) (xy 451.53469 -51.412445) (xy 451.482389 -51.427799) (xy 451.428434 -51.435554)
			(xy 451.40118 -51.436016) (xy 451.373471 -51.435506) (xy 451.318637 -51.427481) (xy 451.265543 -51.411603)
			(xy 451.215307 -51.388206) (xy 451.168986 -51.357783) (xy 451.147942 -51.33975) (xy 451.140806 -51.33394)
			(xy 451.123608 -51.327435) (xy 451.114414 -51.32705) (xy 451.036944 -51.32705) (xy 451.019926 -51.3334)
			(xy 451.012814 -51.33975) (xy 450.99178 -51.357797) (xy 450.945459 -51.388223) (xy 450.895221 -51.411622)
			(xy 450.842123 -51.427499) (xy 450.787286 -51.435521) (xy 450.759576 -51.436016) (xy 450.73334 -51.435569)
			(xy 450.681364 -51.428371) (xy 450.630865 -51.414114) (xy 450.582799 -51.393067) (xy 450.538072 -51.365628)
			(xy 450.497531 -51.332316) (xy 450.479414 -51.313334) (xy 450.472233 -51.306252) (xy 450.453908 -51.297866)
			(xy 450.443854 -51.297078) (xy 450.370956 -51.295046) (xy 450.360849 -51.295135) (xy 450.341987 -51.302359)
			(xy 450.33438 -51.309016) (xy 450.312924 -51.328774) (xy 450.265171 -51.362261) (xy 450.212882 -51.388098)
			(xy 450.157272 -51.405683) (xy 450.099635 -51.414608) (xy 450.070474 -51.415188) (xy 450.042765 -51.414689)
			(xy 449.98793 -51.406662) (xy 449.934835 -51.390782) (xy 449.884599 -51.367382) (xy 449.838279 -51.336956)
			(xy 449.817236 -51.318922) (xy 449.810096 -51.313118) (xy 449.792902 -51.306607) (xy 449.783708 -51.306222)
			(xy 449.706238 -51.306222) (xy 449.68922 -51.312572) (xy 449.682108 -51.318922) (xy 449.661073 -51.336967)
			(xy 449.614753 -51.367395) (xy 449.564514 -51.390794) (xy 449.511417 -51.406672) (xy 449.45658 -51.414693)
			(xy 449.42887 -51.415188) (xy 449.401619 -51.41474) (xy 449.347671 -51.40698) (xy 449.295378 -51.391621)
			(xy 449.245801 -51.368977) (xy 449.199952 -51.339509) (xy 449.158764 -51.303815) (xy 449.123073 -51.262624)
			(xy 449.093608 -51.216772) (xy 449.070968 -51.167194) (xy 449.055614 -51.114899) (xy 449.047858 -51.060951)
			(xy 448.524452 -51.060951) (xy 448.561818 -51.084961) (xy 448.603016 -51.120655) (xy 448.638715 -51.16185)
			(xy 448.668187 -51.207705) (xy 448.690832 -51.257288) (xy 448.70619 -51.30959) (xy 448.713949 -51.363545)
			(xy 448.713949 -51.418055) (xy 448.70619 -51.47201) (xy 448.690832 -51.524312) (xy 448.668187 -51.573895)
			(xy 448.638715 -51.61975) (xy 448.603016 -51.660945) (xy 448.561818 -51.696639) (xy 448.51596 -51.726106)
			(xy 448.466374 -51.748746) (xy 448.414071 -51.764099) (xy 448.360115 -51.771851) (xy 448.33286 -51.772312)
			(xy 448.305151 -51.771815) (xy 448.250316 -51.763787) (xy 448.197222 -51.747906) (xy 448.146986 -51.724506)
			(xy 448.100666 -51.69408) (xy 448.079622 -51.676046) (xy 448.072493 -51.670227) (xy 448.05529 -51.663727)
			(xy 448.046094 -51.663346) (xy 447.968624 -51.663346) (xy 447.951606 -51.669696) (xy 447.944494 -51.676046)
			(xy 447.923468 -51.694101) (xy 447.877145 -51.724527) (xy 447.826904 -51.747924) (xy 447.773805 -51.763799)
			(xy 447.718967 -51.771818) (xy 447.691256 -51.772312) (xy 447.664007 -51.771815) (xy 447.610065 -51.764054)
			(xy 447.557776 -51.748695) (xy 447.508205 -51.726052) (xy 447.46236 -51.696584) (xy 447.421176 -51.660893)
			(xy 447.385489 -51.619705) (xy 447.356027 -51.573857) (xy 447.33339 -51.524283) (xy 447.318037 -51.471992)
			(xy 447.310282 -51.418049) (xy 446.918324 -51.418049) (xy 446.912868 -51.455997) (xy 446.897514 -51.50829)
			(xy 446.874874 -51.557866) (xy 446.84541 -51.603716) (xy 446.80972 -51.644906) (xy 446.768532 -51.680598)
			(xy 446.722684 -51.710065) (xy 446.673109 -51.732707) (xy 446.620816 -51.748064) (xy 446.56687 -51.755823)
			(xy 446.53962 -51.75631) (xy 446.51191 -51.755837) (xy 446.457074 -51.747803) (xy 446.40398 -51.731916)
			(xy 446.353744 -51.708511) (xy 446.307425 -51.67808) (xy 446.286382 -51.660044) (xy 446.279235 -51.65425)
			(xy 446.262046 -51.647735) (xy 446.252854 -51.647344) (xy 446.175384 -51.647344) (xy 446.158366 -51.653694)
			(xy 446.151254 -51.660044) (xy 446.130204 -51.678071) (xy 446.083888 -51.708501) (xy 446.033653 -51.731903)
			(xy 445.980559 -51.747785) (xy 445.925725 -51.755812) (xy 445.898016 -51.75631) (xy 445.870763 -51.755844)
			(xy 445.81681 -51.748089) (xy 445.764511 -51.732734) (xy 445.714929 -51.710093) (xy 445.669074 -51.680625)
			(xy 445.62788 -51.644932) (xy 445.592184 -51.603739) (xy 445.562715 -51.557885) (xy 445.540071 -51.508304)
			(xy 445.524715 -51.456005) (xy 445.516957 -51.402053) (xy 430.2252 -51.402053) (xy 430.2252 -53.055266)
			(xy 460.930242 -53.055266) (xy 460.934313 -52.999644) (xy 460.946439 -52.945207) (xy 460.966362 -52.893116)
			(xy 460.993658 -52.844481) (xy 461.027744 -52.800338) (xy 461.067893 -52.761629) (xy 461.113251 -52.729178)
			(xy 461.162851 -52.703677) (xy 461.215635 -52.68567) (xy 461.270478 -52.67554) (xy 461.326212 -52.673503)
			(xy 461.381649 -52.679603) (xy 461.435606 -52.693709) (xy 461.486935 -52.715521) (xy 461.534541 -52.744575)
			(xy 461.577409 -52.78025) (xy 461.614626 -52.821787) (xy 461.645399 -52.8683) (xy 461.669071 -52.918797)
			(xy 461.685139 -52.972204) (xy 461.693259 -53.02738) (xy 461.693768 -53.055266) (xy 461.693259 -53.083152)
			(xy 461.685139 -53.138328) (xy 461.669071 -53.191735) (xy 461.645399 -53.242232) (xy 461.614626 -53.288745)
			(xy 461.577409 -53.330282) (xy 461.534541 -53.365957) (xy 461.486935 -53.395011) (xy 461.435606 -53.416823)
			(xy 461.381649 -53.430929) (xy 461.326212 -53.437029) (xy 461.270478 -53.434992) (xy 461.215635 -53.424862)
			(xy 461.162851 -53.406855) (xy 461.113251 -53.381354) (xy 461.067893 -53.348903) (xy 461.027744 -53.310194)
			(xy 460.993658 -53.266051) (xy 460.966362 -53.217416) (xy 460.946439 -53.165325) (xy 460.934313 -53.110888)
			(xy 460.930242 -53.055266) (xy 430.2252 -53.055266) (xy 430.2252 -54.971696) (xy 430.226216 -54.981602)
			(xy 430.227923 -54.98876) (xy 430.234761 -55.001781) (xy 430.239678 -55.007256) (xy 437.576722 -62.344046)
			(xy 437.58357 -62.351443) (xy 437.5913 -62.370042) (xy 437.591708 -62.380114) (xy 437.591708 -68.527676)
			(xy 444.63208 -68.527676) (xy 444.632623 -68.49876) (xy 444.641342 -68.441588) (xy 444.658594 -68.386389)
			(xy 444.68398 -68.334426) (xy 444.716921 -68.286892) (xy 444.756661 -68.244876) (xy 444.779146 -68.226686)
			(xy 444.787957 -68.219083) (xy 444.798137 -68.198179) (xy 444.798704 -68.186554) (xy 444.798704 -68.106798)
			(xy 444.79815 -68.095168) (xy 444.787972 -68.074258) (xy 444.779146 -68.066666) (xy 444.756635 -68.048508)
			(xy 444.716904 -68.00648) (xy 444.68397 -67.958937) (xy 444.658587 -67.90697) (xy 444.641336 -67.851767)
			(xy 444.632612 -67.794594) (xy 444.63208 -67.765676) (xy 444.632555 -67.738425) (xy 444.640315 -67.684477)
			(xy 444.655672 -67.632183) (xy 444.678316 -67.582607) (xy 444.707783 -67.536757) (xy 444.743476 -67.495567)
			(xy 444.784666 -67.459876) (xy 444.830517 -67.43041) (xy 444.880094 -67.407768) (xy 444.932389 -67.392412)
			(xy 444.986337 -67.384655) (xy 445.013588 -67.384168) (xy 445.042506 -67.384669) (xy 445.099679 -67.393398)
			(xy 445.154879 -67.410658) (xy 445.206842 -67.436052) (xy 445.254375 -67.469) (xy 445.29639 -67.508746)
			(xy 445.314578 -67.531234) (xy 445.322199 -67.540027) (xy 445.343089 -67.550217) (xy 445.35471 -67.550792)
			(xy 445.434466 -67.550792) (xy 445.446094 -67.550222) (xy 445.467004 -67.540055) (xy 445.474598 -67.531234)
			(xy 445.491351 -67.510451) (xy 445.529705 -67.473321) (xy 445.572859 -67.441899) (xy 445.619973 -67.4168)
			(xy 445.670125 -67.398514) (xy 445.722336 -67.387397) (xy 445.775588 -67.383667) (xy 445.82884 -67.387397)
			(xy 445.881051 -67.398514) (xy 445.931203 -67.4168) (xy 445.978317 -67.441899) (xy 446.021471 -67.473321)
			(xy 446.059825 -67.510451) (xy 446.076578 -67.531234) (xy 446.084199 -67.540027) (xy 446.105089 -67.550217)
			(xy 446.11671 -67.550792) (xy 446.196466 -67.550792) (xy 446.208094 -67.550222) (xy 446.229004 -67.540055)
			(xy 446.236598 -67.531234) (xy 446.254799 -67.508759) (xy 446.296815 -67.469021) (xy 446.344348 -67.43608)
			(xy 446.396308 -67.41069) (xy 446.451504 -67.393433) (xy 446.508672 -67.384703) (xy 446.537588 -67.384168)
			(xy 446.564838 -67.384689) (xy 446.618783 -67.392444) (xy 446.671076 -67.407796) (xy 446.720651 -67.430434)
			(xy 446.7665 -67.459897) (xy 446.80769 -67.495584) (xy 446.843382 -67.536771) (xy 446.872849 -67.582617)
			(xy 446.895491 -67.632191) (xy 446.910849 -67.684482) (xy 446.918608 -67.738426) (xy 446.919096 -67.765676)
			(xy 446.918562 -67.794592) (xy 446.909836 -67.851763) (xy 446.892582 -67.906961) (xy 446.867193 -67.958923)
			(xy 446.834252 -68.006458) (xy 446.794514 -68.048475) (xy 446.77203 -68.066666) (xy 446.763237 -68.074286)
			(xy 446.753048 -68.095177) (xy 446.752472 -68.106798) (xy 446.752472 -68.186554) (xy 446.752969 -68.198192)
			(xy 446.763185 -68.219103) (xy 446.77203 -68.226686) (xy 446.794513 -68.244877) (xy 446.834247 -68.286898)
			(xy 446.867185 -68.334433) (xy 446.892573 -68.386394) (xy 446.90983 -68.441591) (xy 446.917662 -68.492878)
			(xy 447.058034 -68.492878) (xy 447.058596 -68.463963) (xy 447.067314 -68.406793) (xy 447.084562 -68.351594)
			(xy 447.109946 -68.299632) (xy 447.142883 -68.252097) (xy 447.182617 -68.210079) (xy 447.2051 -68.191888)
			(xy 447.213903 -68.184276) (xy 447.224089 -68.163379) (xy 447.224658 -68.151756) (xy 447.224658 -68.072)
			(xy 447.224119 -68.060368) (xy 447.213932 -68.039457) (xy 447.2051 -68.031868) (xy 447.182601 -68.013695)
			(xy 447.142867 -67.971672) (xy 447.10993 -67.924133) (xy 447.084544 -67.872168) (xy 447.067291 -67.816967)
			(xy 447.058567 -67.759795) (xy 447.058034 -67.730878) (xy 447.058435 -67.703623) (xy 447.066196 -67.649667)
			(xy 447.081557 -67.597366) (xy 447.104205 -67.547783) (xy 447.133679 -67.501927) (xy 447.169379 -67.460734)
			(xy 447.210579 -67.425041) (xy 447.256439 -67.395574) (xy 447.306026 -67.372934) (xy 447.35833 -67.357582)
			(xy 447.412287 -67.34983) (xy 447.439542 -67.34937) (xy 447.468459 -67.349904) (xy 447.52563 -67.358626)
			(xy 447.58083 -67.375879) (xy 447.632792 -67.401268) (xy 447.680326 -67.43421) (xy 447.722342 -67.473951)
			(xy 447.740532 -67.496436) (xy 447.748129 -67.505254) (xy 447.769038 -67.51543) (xy 447.780664 -67.515994)
			(xy 447.86042 -67.515994) (xy 447.872052 -67.515454) (xy 447.892961 -67.505266) (xy 447.900552 -67.496436)
			(xy 447.917305 -67.475653) (xy 447.955659 -67.438523) (xy 447.998813 -67.407101) (xy 448.045927 -67.382002)
			(xy 448.096079 -67.363716) (xy 448.14829 -67.352599) (xy 448.201542 -67.348869) (xy 448.254794 -67.352599)
			(xy 448.307005 -67.363716) (xy 448.357157 -67.382002) (xy 448.404271 -67.407101) (xy 448.447425 -67.438523)
			(xy 448.485779 -67.475653) (xy 448.502532 -67.496436) (xy 448.510129 -67.505254) (xy 448.531038 -67.51543)
			(xy 448.542664 -67.515994) (xy 448.62242 -67.515994) (xy 448.634052 -67.515454) (xy 448.654961 -67.505266)
			(xy 448.662552 -67.496436) (xy 448.680779 -67.473983) (xy 448.72279 -67.434244) (xy 448.770317 -67.401301)
			(xy 448.822272 -67.375907) (xy 448.877463 -67.358644) (xy 448.934628 -67.349908) (xy 448.963542 -67.34937)
			(xy 448.990793 -67.349839) (xy 449.04474 -67.3576) (xy 449.097034 -67.37296) (xy 449.14661 -67.395604)
			(xy 449.192459 -67.425073) (xy 449.233648 -67.460766) (xy 449.269339 -67.501957) (xy 449.298806 -67.547807)
			(xy 449.321447 -67.597385) (xy 449.336804 -67.649679) (xy 449.344563 -67.703627) (xy 449.34505 -67.730878)
			(xy 449.344535 -67.759795) (xy 449.335808 -67.816967) (xy 449.318551 -67.872167) (xy 449.293158 -67.924129)
			(xy 449.260213 -67.971663) (xy 449.220471 -68.013679) (xy 449.197984 -68.031868) (xy 449.189198 -68.039496)
			(xy 449.179003 -68.060381) (xy 449.178426 -68.072) (xy 449.178426 -68.151756) (xy 449.178938 -68.163392)
			(xy 449.189145 -68.184301) (xy 449.197984 -68.191888) (xy 449.220458 -68.21009) (xy 449.260195 -68.252107)
			(xy 449.293135 -68.299639) (xy 449.318526 -68.351599) (xy 449.335784 -68.406794) (xy 449.344514 -68.463963)
			(xy 449.34505 -68.492878) (xy 449.344501 -68.520127) (xy 449.336749 -68.57407) (xy 449.321399 -68.626361)
			(xy 449.298763 -68.675935) (xy 449.269303 -68.721784) (xy 449.233618 -68.762973) (xy 449.192435 -68.798665)
			(xy 449.146591 -68.828133) (xy 449.097021 -68.850776) (xy 449.044733 -68.866135) (xy 448.990791 -68.873897)
			(xy 448.963542 -68.874386) (xy 448.934626 -68.873843) (xy 448.877456 -68.86512) (xy 448.822257 -68.847867)
			(xy 448.770295 -68.82248) (xy 448.722761 -68.789541) (xy 448.680743 -68.749804) (xy 448.662552 -68.72732)
			(xy 448.65497 -68.718488) (xy 448.63405 -68.708321) (xy 448.62242 -68.707762) (xy 448.542664 -68.707762)
			(xy 448.531028 -68.708273) (xy 448.510118 -68.71848) (xy 448.502532 -68.72732) (xy 448.485779 -68.748103)
			(xy 448.447425 -68.785233) (xy 448.404271 -68.816655) (xy 448.357157 -68.841754) (xy 448.307005 -68.86004)
			(xy 448.254794 -68.871157) (xy 448.201542 -68.874887) (xy 448.14829 -68.871157) (xy 448.096079 -68.86004)
			(xy 448.045927 -68.841754) (xy 447.998813 -68.816655) (xy 447.955659 -68.785233) (xy 447.917305 -68.748103)
			(xy 447.900552 -68.72732) (xy 447.89297 -68.718488) (xy 447.87205 -68.708321) (xy 447.86042 -68.707762)
			(xy 447.780664 -68.707762) (xy 447.769028 -68.708273) (xy 447.748118 -68.71848) (xy 447.740532 -68.72732)
			(xy 447.722328 -68.749792) (xy 447.68031 -68.789527) (xy 447.632778 -68.822467) (xy 447.580819 -68.847857)
			(xy 447.525624 -68.865116) (xy 447.468457 -68.873849) (xy 447.439542 -68.874386) (xy 447.412289 -68.873906)
			(xy 447.358338 -68.866154) (xy 447.306039 -68.850802) (xy 447.256457 -68.828163) (xy 447.210603 -68.798697)
			(xy 447.169409 -68.763005) (xy 447.133715 -68.721813) (xy 447.104247 -68.67596) (xy 447.081605 -68.62638)
			(xy 447.066251 -68.574082) (xy 447.058496 -68.520131) (xy 447.058034 -68.492878) (xy 446.917662 -68.492878)
			(xy 446.91856 -68.49876) (xy 446.919096 -68.527676) (xy 446.918622 -68.554929) (xy 446.910868 -68.60888)
			(xy 446.895515 -68.661178) (xy 446.872874 -68.710759) (xy 446.843408 -68.756613) (xy 446.807715 -68.797806)
			(xy 446.766523 -68.8335) (xy 446.72067 -68.862968) (xy 446.67109 -68.885611) (xy 446.618792 -68.900966)
			(xy 446.564841 -68.908721) (xy 446.537588 -68.909184) (xy 446.508673 -68.908609) (xy 446.451504 -68.899892)
			(xy 446.396306 -68.882646) (xy 446.344344 -68.857265) (xy 446.296809 -68.824331) (xy 446.25479 -68.784599)
			(xy 446.236598 -68.762118) (xy 446.228996 -68.753306) (xy 446.208091 -68.743128) (xy 446.196466 -68.74256)
			(xy 446.11671 -68.74256) (xy 446.105077 -68.743098) (xy 446.084167 -68.753286) (xy 446.076578 -68.762118)
			(xy 446.059825 -68.782901) (xy 446.021471 -68.820031) (xy 445.978317 -68.851453) (xy 445.931203 -68.876552)
			(xy 445.881051 -68.894838) (xy 445.82884 -68.905955) (xy 445.775588 -68.909685) (xy 445.722336 -68.905955)
			(xy 445.670125 -68.894838) (xy 445.619973 -68.876552) (xy 445.572859 -68.851453) (xy 445.529705 -68.820031)
			(xy 445.491351 -68.782901) (xy 445.474598 -68.762118) (xy 445.466996 -68.753306) (xy 445.446091 -68.743128)
			(xy 445.434466 -68.74256) (xy 445.35471 -68.74256) (xy 445.343077 -68.743098) (xy 445.322167 -68.753286)
			(xy 445.314578 -68.762118) (xy 445.296404 -68.784616) (xy 445.25438 -68.824349) (xy 445.206842 -68.857286)
			(xy 445.154877 -68.882672) (xy 445.099677 -68.899925) (xy 445.042505 -68.908651) (xy 445.013588 -68.909184)
			(xy 444.986334 -68.908756) (xy 444.93238 -68.900997) (xy 444.88008 -68.885638) (xy 444.830498 -68.862993)
			(xy 444.784644 -68.833521) (xy 444.743451 -68.797824) (xy 444.707757 -68.756627) (xy 444.67829 -68.71077)
			(xy 444.655649 -68.661186) (xy 444.640295 -68.608885) (xy 444.632541 -68.55493) (xy 444.63208 -68.527676)
			(xy 437.591708 -68.527676) (xy 437.591708 -69.003164) (xy 450.629274 -69.003164) (xy 450.629701 -68.975792)
			(xy 450.637525 -68.921611) (xy 450.653023 -68.869106) (xy 450.675874 -68.81936) (xy 450.705608 -68.773396)
			(xy 450.723254 -68.752466) (xy 450.723508 -68.752212) (xy 450.729097 -68.745127) (xy 450.735342 -68.728209)
			(xy 450.7357 -68.719192) (xy 450.7357 -68.652136) (xy 450.735326 -68.643121) (xy 450.72909 -68.626204)
			(xy 450.723508 -68.619116) (xy 450.723254 -68.619116) (xy 450.723254 -68.618862) (xy 450.705577 -68.597958)
			(xy 450.675852 -68.551986) (xy 450.653007 -68.502235) (xy 450.637512 -68.449729) (xy 450.629686 -68.395546)
			(xy 450.62969 -68.3408) (xy 450.637524 -68.286618) (xy 450.653026 -68.234114) (xy 450.675878 -68.184366)
			(xy 450.70561 -68.138398) (xy 450.723254 -68.117466) (xy 450.723508 -68.117212) (xy 450.729097 -68.110127)
			(xy 450.735342 -68.093209) (xy 450.7357 -68.084192) (xy 450.7357 -68.017136) (xy 450.735326 -68.008121)
			(xy 450.72909 -67.991204) (xy 450.723508 -67.984116) (xy 450.723254 -67.984116) (xy 450.723254 -67.983862)
			(xy 450.705577 -67.962958) (xy 450.675852 -67.916986) (xy 450.653007 -67.867235) (xy 450.637512 -67.814729)
			(xy 450.629686 -67.760546) (xy 450.62969 -67.7058) (xy 450.637524 -67.651618) (xy 450.653026 -67.599114)
			(xy 450.675878 -67.549366) (xy 450.70561 -67.503398) (xy 450.723254 -67.482466) (xy 450.723508 -67.482212)
			(xy 450.729097 -67.475127) (xy 450.735342 -67.458209) (xy 450.7357 -67.449192) (xy 450.7357 -67.382136)
			(xy 450.735326 -67.373121) (xy 450.72909 -67.356204) (xy 450.723508 -67.349116) (xy 450.723254 -67.349116)
			(xy 450.723254 -67.348862) (xy 450.705577 -67.327958) (xy 450.675852 -67.281986) (xy 450.653007 -67.232235)
			(xy 450.637512 -67.179729) (xy 450.629686 -67.125546) (xy 450.62969 -67.0708) (xy 450.637524 -67.016618)
			(xy 450.653026 -66.964114) (xy 450.675878 -66.914366) (xy 450.70561 -66.868398) (xy 450.723254 -66.847466)
			(xy 450.723508 -66.847212) (xy 450.729097 -66.840127) (xy 450.735342 -66.823209) (xy 450.7357 -66.814192)
			(xy 450.7357 -66.747136) (xy 450.735326 -66.738121) (xy 450.72909 -66.721204) (xy 450.723508 -66.714116)
			(xy 450.723254 -66.714116) (xy 450.723254 -66.713862) (xy 450.705639 -66.69291) (xy 450.675922 -66.646944)
			(xy 450.65308 -66.597201) (xy 450.637584 -66.544705) (xy 450.62975 -66.490532) (xy 450.629274 -66.463164)
			(xy 450.629744 -66.435913) (xy 450.637505 -66.381965) (xy 450.652864 -66.329671) (xy 450.675508 -66.280095)
			(xy 450.704976 -66.234246) (xy 450.740669 -66.193057) (xy 450.78186 -66.157366) (xy 450.827711 -66.127899)
			(xy 450.877288 -66.105258) (xy 450.929583 -66.089901) (xy 450.983531 -66.082143) (xy 451.010782 -66.081656)
			(xy 451.037266 -66.082125) (xy 451.089726 -66.089444) (xy 451.140667 -66.103956) (xy 451.189108 -66.125383)
			(xy 451.234115 -66.153311) (xy 451.274821 -66.187202) (xy 451.310442 -66.226404) (xy 451.325742 -66.248026)
			(xy 451.325996 -66.24828) (xy 451.333593 -66.258166) (xy 451.355703 -66.269623) (xy 451.36816 -66.270124)
			(xy 451.465696 -66.269108) (xy 451.487794 -66.256916) (xy 451.494652 -66.246248) (xy 451.509819 -66.223831)
			(xy 451.545524 -66.183154) (xy 451.586616 -66.147929) (xy 451.632272 -66.118861) (xy 451.681577 -66.096533)
			(xy 451.733541 -66.081394) (xy 451.787122 -66.073747) (xy 451.814184 -66.073274) (xy 451.841434 -66.073793)
			(xy 451.89538 -66.081547) (xy 451.947673 -66.096899) (xy 451.997248 -66.119537) (xy 452.043098 -66.149)
			(xy 452.084288 -66.184688) (xy 452.11998 -66.225875) (xy 452.149447 -66.271722) (xy 452.172089 -66.321296)
			(xy 452.187446 -66.373587) (xy 452.195204 -66.427532) (xy 452.195692 -66.454782) (xy 452.195217 -66.482152)
			(xy 452.187402 -66.536331) (xy 452.171915 -66.588834) (xy 452.149075 -66.638581) (xy 452.119352 -66.684548)
			(xy 452.101712 -66.70548) (xy 452.101458 -66.705734) (xy 452.095888 -66.712832) (xy 452.089632 -66.72974)
			(xy 452.089266 -66.738754) (xy 452.089266 -66.80581) (xy 452.089625 -66.814826) (xy 452.095872 -66.831743)
			(xy 452.101458 -66.83883) (xy 452.101712 -66.83883) (xy 452.101712 -66.839084) (xy 452.119333 -66.860032)
			(xy 452.149056 -66.905998) (xy 452.1719 -66.955742) (xy 452.187396 -67.008241) (xy 452.195225 -67.062417)
			(xy 452.195227 -67.117156) (xy 452.187402 -67.171332) (xy 452.17191 -67.223833) (xy 452.149069 -67.273578)
			(xy 452.11935 -67.319547) (xy 452.101712 -67.34048) (xy 452.101458 -67.340734) (xy 452.095888 -67.347832)
			(xy 452.089632 -67.36474) (xy 452.089266 -67.373754) (xy 452.089266 -67.44081) (xy 452.089625 -67.449826)
			(xy 452.095872 -67.466743) (xy 452.101458 -67.47383) (xy 452.101712 -67.47383) (xy 452.101712 -67.474084)
			(xy 452.119333 -67.495032) (xy 452.149056 -67.540998) (xy 452.1719 -67.590742) (xy 452.187396 -67.643241)
			(xy 452.195225 -67.697417) (xy 452.195227 -67.752156) (xy 452.187402 -67.806332) (xy 452.17191 -67.858833)
			(xy 452.149069 -67.908578) (xy 452.11935 -67.954547) (xy 452.101712 -67.97548) (xy 452.101458 -67.975734)
			(xy 452.095888 -67.982832) (xy 452.089632 -67.99974) (xy 452.089266 -68.008754) (xy 452.089266 -68.07581)
			(xy 452.089625 -68.084826) (xy 452.095872 -68.101743) (xy 452.101458 -68.10883) (xy 452.101712 -68.10883)
			(xy 452.101712 -68.109084) (xy 452.119333 -68.130032) (xy 452.149056 -68.175998) (xy 452.1719 -68.225742)
			(xy 452.187396 -68.278241) (xy 452.195225 -68.332417) (xy 452.195227 -68.387156) (xy 452.187402 -68.441332)
			(xy 452.17191 -68.493833) (xy 452.149069 -68.543578) (xy 452.11935 -68.589547) (xy 452.101712 -68.61048)
			(xy 452.101458 -68.610734) (xy 452.095888 -68.617832) (xy 452.089632 -68.63474) (xy 452.089266 -68.643754)
			(xy 452.089266 -68.71081) (xy 452.089625 -68.719826) (xy 452.095872 -68.736743) (xy 452.101458 -68.74383)
			(xy 452.101712 -68.74383) (xy 452.101712 -68.744084) (xy 452.119359 -68.76501) (xy 452.149069 -68.810984)
			(xy 452.171903 -68.860734) (xy 452.187393 -68.913236) (xy 452.195219 -68.967412) (xy 452.195692 -68.994782)
			(xy 452.728076 -68.994782) (xy 452.728513 -68.967411) (xy 452.736335 -68.913229) (xy 452.75183 -68.860725)
			(xy 452.774679 -68.810979) (xy 452.804411 -68.765014) (xy 452.822056 -68.744084) (xy 452.82231 -68.74383)
			(xy 452.827891 -68.73674) (xy 452.834141 -68.719826) (xy 452.834502 -68.71081) (xy 452.834502 -68.643754)
			(xy 452.834118 -68.63474) (xy 452.827889 -68.617823) (xy 452.82231 -68.610734) (xy 452.822056 -68.610734)
			(xy 452.822056 -68.61048) (xy 452.804396 -68.589562) (xy 452.77467 -68.543592) (xy 452.751824 -68.493844)
			(xy 452.736328 -68.441339) (xy 452.7285 -68.387158) (xy 452.728502 -68.332415) (xy 452.736334 -68.278234)
			(xy 452.751834 -68.225731) (xy 452.774683 -68.175984) (xy 452.804413 -68.130016) (xy 452.822056 -68.109084)
			(xy 452.82231 -68.10883) (xy 452.827891 -68.10174) (xy 452.834141 -68.084826) (xy 452.834502 -68.07581)
			(xy 452.834502 -68.008754) (xy 452.834118 -67.99974) (xy 452.827889 -67.982823) (xy 452.82231 -67.975734)
			(xy 452.822056 -67.975734) (xy 452.822056 -67.97548) (xy 452.804434 -67.954535) (xy 452.774721 -67.908565)
			(xy 452.751882 -67.858821) (xy 452.736387 -67.806323) (xy 452.728553 -67.75215) (xy 452.728076 -67.724782)
			(xy 452.728562 -67.697531) (xy 452.736318 -67.643583) (xy 452.751673 -67.591288) (xy 452.774315 -67.541711)
			(xy 452.803781 -67.495861) (xy 452.839472 -67.45467) (xy 452.880663 -67.418979) (xy 452.926513 -67.389513)
			(xy 452.97609 -67.366871) (xy 453.028385 -67.351516) (xy 453.082333 -67.34376) (xy 453.136835 -67.34376)
			(xy 453.190783 -67.351516) (xy 453.243078 -67.366871) (xy 453.292655 -67.389513) (xy 453.338505 -67.418979)
			(xy 453.379696 -67.45467) (xy 453.415387 -67.495861) (xy 453.444853 -67.541711) (xy 453.467495 -67.591288)
			(xy 453.48285 -67.643583) (xy 453.490606 -67.697531) (xy 453.491092 -67.724782) (xy 453.490617 -67.752152)
			(xy 453.482802 -67.806331) (xy 453.467315 -67.858834) (xy 453.444475 -67.908581) (xy 453.414752 -67.954548)
			(xy 453.397112 -67.97548) (xy 453.396858 -67.975734) (xy 453.391288 -67.982832) (xy 453.385032 -67.99974)
			(xy 453.384666 -68.008754) (xy 453.384666 -68.07581) (xy 453.385025 -68.084826) (xy 453.391272 -68.101743)
			(xy 453.396858 -68.10883) (xy 453.397112 -68.10883) (xy 453.397112 -68.109084) (xy 453.414733 -68.130032)
			(xy 453.444456 -68.175998) (xy 453.4673 -68.225742) (xy 453.482796 -68.278241) (xy 453.490625 -68.332417)
			(xy 453.490627 -68.387156) (xy 453.482802 -68.441332) (xy 453.46731 -68.493833) (xy 453.444469 -68.543578)
			(xy 453.41475 -68.589547) (xy 453.397112 -68.61048) (xy 453.396858 -68.610734) (xy 453.391288 -68.617832)
			(xy 453.385032 -68.63474) (xy 453.384666 -68.643754) (xy 453.384666 -68.71081) (xy 453.385025 -68.719826)
			(xy 453.391272 -68.736743) (xy 453.396858 -68.74383) (xy 453.397112 -68.74383) (xy 453.397112 -68.744084)
			(xy 453.414759 -68.76501) (xy 453.444469 -68.810984) (xy 453.467303 -68.860734) (xy 453.482793 -68.913236)
			(xy 453.490619 -68.967412) (xy 453.491092 -68.994782) (xy 458.747876 -68.994782) (xy 458.748313 -68.967411)
			(xy 458.756135 -68.913229) (xy 458.77163 -68.860725) (xy 458.794479 -68.810979) (xy 458.824211 -68.765014)
			(xy 458.841856 -68.744084) (xy 458.84211 -68.74383) (xy 458.847691 -68.73674) (xy 458.853941 -68.719826)
			(xy 458.854302 -68.71081) (xy 458.854302 -68.643754) (xy 458.853918 -68.63474) (xy 458.847689 -68.617823)
			(xy 458.84211 -68.610734) (xy 458.841856 -68.610734) (xy 458.841856 -68.61048) (xy 458.824196 -68.589562)
			(xy 458.79447 -68.543592) (xy 458.771624 -68.493844) (xy 458.756128 -68.441339) (xy 458.7483 -68.387158)
			(xy 458.748302 -68.332415) (xy 458.756134 -68.278234) (xy 458.771634 -68.225731) (xy 458.794483 -68.175984)
			(xy 458.824213 -68.130016) (xy 458.841856 -68.109084) (xy 458.84211 -68.10883) (xy 458.847691 -68.10174)
			(xy 458.853941 -68.084826) (xy 458.854302 -68.07581) (xy 458.854302 -68.008754) (xy 458.853918 -67.99974)
			(xy 458.847689 -67.982823) (xy 458.84211 -67.975734) (xy 458.841856 -67.975734) (xy 458.841856 -67.97548)
			(xy 458.824196 -67.954562) (xy 458.79447 -67.908592) (xy 458.771624 -67.858844) (xy 458.756128 -67.806339)
			(xy 458.7483 -67.752158) (xy 458.748302 -67.697415) (xy 458.756134 -67.643234) (xy 458.771634 -67.590731)
			(xy 458.794483 -67.540984) (xy 458.824213 -67.495016) (xy 458.841856 -67.474084) (xy 458.84211 -67.47383)
			(xy 458.847691 -67.46674) (xy 458.853941 -67.449826) (xy 458.854302 -67.44081) (xy 458.854302 -67.373754)
			(xy 458.853918 -67.36474) (xy 458.847689 -67.347823) (xy 458.84211 -67.340734) (xy 458.841856 -67.340734)
			(xy 458.841856 -67.34048) (xy 458.824234 -67.319535) (xy 458.794521 -67.273565) (xy 458.771682 -67.223821)
			(xy 458.756187 -67.171323) (xy 458.748353 -67.11715) (xy 458.747876 -67.089782) (xy 458.748362 -67.062531)
			(xy 458.756118 -67.008583) (xy 458.771473 -66.956288) (xy 458.794115 -66.906711) (xy 458.823581 -66.860861)
			(xy 458.859272 -66.81967) (xy 458.900463 -66.783979) (xy 458.946313 -66.754513) (xy 458.99589 -66.731871)
			(xy 459.048185 -66.716516) (xy 459.102133 -66.70876) (xy 459.156635 -66.70876) (xy 459.210583 -66.716516)
			(xy 459.262878 -66.731871) (xy 459.312455 -66.754513) (xy 459.358305 -66.783979) (xy 459.399496 -66.81967)
			(xy 459.435187 -66.860861) (xy 459.464653 -66.906711) (xy 459.487295 -66.956288) (xy 459.50265 -67.008583)
			(xy 459.510406 -67.062531) (xy 459.510892 -67.089782) (xy 459.510417 -67.117152) (xy 459.502602 -67.171331)
			(xy 459.487115 -67.223834) (xy 459.464275 -67.273581) (xy 459.434552 -67.319548) (xy 459.416912 -67.34048)
			(xy 459.416658 -67.340734) (xy 459.411088 -67.347832) (xy 459.404832 -67.36474) (xy 459.404466 -67.373754)
			(xy 459.404466 -67.44081) (xy 459.404825 -67.449826) (xy 459.411072 -67.466743) (xy 459.416658 -67.47383)
			(xy 459.416912 -67.47383) (xy 459.416912 -67.474084) (xy 459.434533 -67.495032) (xy 459.464256 -67.540998)
			(xy 459.4871 -67.590742) (xy 459.502596 -67.643241) (xy 459.510425 -67.697417) (xy 459.510427 -67.752156)
			(xy 459.502602 -67.806332) (xy 459.48711 -67.858833) (xy 459.464269 -67.908578) (xy 459.43455 -67.954547)
			(xy 459.416912 -67.97548) (xy 459.416658 -67.975734) (xy 459.411088 -67.982832) (xy 459.404832 -67.99974)
			(xy 459.404466 -68.008754) (xy 459.404466 -68.07581) (xy 459.404825 -68.084826) (xy 459.411072 -68.101743)
			(xy 459.416658 -68.10883) (xy 459.416912 -68.10883) (xy 459.416912 -68.109084) (xy 459.434533 -68.130032)
			(xy 459.464256 -68.175998) (xy 459.4871 -68.225742) (xy 459.502596 -68.278241) (xy 459.510425 -68.332417)
			(xy 459.510427 -68.387156) (xy 459.502602 -68.441332) (xy 459.48711 -68.493833) (xy 459.464269 -68.543578)
			(xy 459.43455 -68.589547) (xy 459.416912 -68.61048) (xy 459.416658 -68.610734) (xy 459.411088 -68.617832)
			(xy 459.404832 -68.63474) (xy 459.404466 -68.643754) (xy 459.404466 -68.71081) (xy 459.404825 -68.719826)
			(xy 459.411072 -68.736743) (xy 459.416658 -68.74383) (xy 459.416912 -68.74383) (xy 459.416912 -68.744084)
			(xy 459.434559 -68.76501) (xy 459.464269 -68.810984) (xy 459.487103 -68.860734) (xy 459.502593 -68.913236)
			(xy 459.510419 -68.967412) (xy 459.510892 -68.994782) (xy 459.510406 -69.022033) (xy 459.50265 -69.075981)
			(xy 459.487295 -69.128276) (xy 459.464653 -69.177853) (xy 459.435187 -69.223703) (xy 459.399496 -69.264894)
			(xy 459.358305 -69.300585) (xy 459.312455 -69.330051) (xy 459.262878 -69.352693) (xy 459.210583 -69.368048)
			(xy 459.156635 -69.375804) (xy 459.102133 -69.375804) (xy 459.048185 -69.368048) (xy 458.99589 -69.352693)
			(xy 458.946313 -69.330051) (xy 458.900463 -69.300585) (xy 458.859272 -69.264894) (xy 458.823581 -69.223703)
			(xy 458.794115 -69.177853) (xy 458.771473 -69.128276) (xy 458.756118 -69.075981) (xy 458.748362 -69.022033)
			(xy 458.747876 -68.994782) (xy 453.491092 -68.994782) (xy 453.490606 -69.022033) (xy 453.48285 -69.075981)
			(xy 453.467495 -69.128276) (xy 453.444853 -69.177853) (xy 453.415387 -69.223703) (xy 453.379696 -69.264894)
			(xy 453.338505 -69.300585) (xy 453.292655 -69.330051) (xy 453.243078 -69.352693) (xy 453.190783 -69.368048)
			(xy 453.136835 -69.375804) (xy 453.082333 -69.375804) (xy 453.028385 -69.368048) (xy 452.97609 -69.352693)
			(xy 452.926513 -69.330051) (xy 452.880663 -69.300585) (xy 452.839472 -69.264894) (xy 452.803781 -69.223703)
			(xy 452.774315 -69.177853) (xy 452.751673 -69.128276) (xy 452.736318 -69.075981) (xy 452.728562 -69.022033)
			(xy 452.728076 -68.994782) (xy 452.195692 -68.994782) (xy 452.195228 -69.022035) (xy 452.187473 -69.075987)
			(xy 452.172118 -69.128286) (xy 452.149477 -69.177867) (xy 452.120009 -69.223721) (xy 452.084315 -69.264914)
			(xy 452.043122 -69.300608) (xy 451.997269 -69.330076) (xy 451.947688 -69.352718) (xy 451.895389 -69.368073)
			(xy 451.841437 -69.375828) (xy 451.814184 -69.37629) (xy 451.7877 -69.375826) (xy 451.735241 -69.368504)
			(xy 451.6843 -69.353989) (xy 451.63586 -69.332561) (xy 451.590853 -69.304633) (xy 451.550147 -69.270742)
			(xy 451.514525 -69.231541) (xy 451.499224 -69.20992) (xy 451.49897 -69.209666) (xy 451.491381 -69.199772)
			(xy 451.469266 -69.188317) (xy 451.456806 -69.187822) (xy 451.35927 -69.188838) (xy 451.337172 -69.20103)
			(xy 451.330314 -69.211698) (xy 451.315087 -69.234072) (xy 451.279394 -69.274752) (xy 451.238313 -69.309983)
			(xy 451.192667 -69.339057) (xy 451.143372 -69.361391) (xy 451.091416 -69.376538) (xy 451.037841 -69.384194)
			(xy 451.010782 -69.384672) (xy 450.983527 -69.384262) (xy 450.929572 -69.376501) (xy 450.877271 -69.361141)
			(xy 450.827689 -69.338494) (xy 450.781834 -69.309021) (xy 450.74064 -69.273321) (xy 450.704947 -69.232123)
			(xy 450.67548 -69.186264) (xy 450.65284 -69.136678) (xy 450.637487 -69.084375) (xy 450.629734 -69.030419)
			(xy 450.629274 -69.003164) (xy 437.591708 -69.003164) (xy 437.591708 -69.722746) (xy 454.449178 -69.722746)
			(xy 454.453249 -69.667124) (xy 454.465375 -69.612687) (xy 454.485298 -69.560596) (xy 454.512594 -69.511961)
			(xy 454.54668 -69.467818) (xy 454.586829 -69.429109) (xy 454.632187 -69.396658) (xy 454.681787 -69.371157)
			(xy 454.734571 -69.35315) (xy 454.789414 -69.34302) (xy 454.845148 -69.340983) (xy 454.900585 -69.347083)
			(xy 454.954542 -69.361189) (xy 455.005871 -69.383001) (xy 455.053477 -69.412055) (xy 455.096345 -69.44773)
			(xy 455.133562 -69.489267) (xy 455.164335 -69.53578) (xy 455.188007 -69.586277) (xy 455.204075 -69.639684)
			(xy 455.212195 -69.69486) (xy 455.212704 -69.722746) (xy 455.338178 -69.722746) (xy 455.342249 -69.667124)
			(xy 455.354375 -69.612687) (xy 455.374298 -69.560596) (xy 455.401594 -69.511961) (xy 455.43568 -69.467818)
			(xy 455.475829 -69.429109) (xy 455.521187 -69.396658) (xy 455.570787 -69.371157) (xy 455.623571 -69.35315)
			(xy 455.678414 -69.34302) (xy 455.734148 -69.340983) (xy 455.789585 -69.347083) (xy 455.843542 -69.361189)
			(xy 455.894871 -69.383001) (xy 455.942477 -69.412055) (xy 455.985345 -69.44773) (xy 456.022562 -69.489267)
			(xy 456.053335 -69.53578) (xy 456.077007 -69.586277) (xy 456.093075 -69.639684) (xy 456.101195 -69.69486)
			(xy 456.101704 -69.722746) (xy 456.227178 -69.722746) (xy 456.231249 -69.667124) (xy 456.243375 -69.612687)
			(xy 456.263298 -69.560596) (xy 456.290594 -69.511961) (xy 456.32468 -69.467818) (xy 456.364829 -69.429109)
			(xy 456.410187 -69.396658) (xy 456.459787 -69.371157) (xy 456.512571 -69.35315) (xy 456.567414 -69.34302)
			(xy 456.623148 -69.340983) (xy 456.678585 -69.347083) (xy 456.732542 -69.361189) (xy 456.783871 -69.383001)
			(xy 456.831477 -69.412055) (xy 456.874345 -69.44773) (xy 456.911562 -69.489267) (xy 456.942335 -69.53578)
			(xy 456.966007 -69.586277) (xy 456.982075 -69.639684) (xy 456.990195 -69.69486) (xy 456.990704 -69.722746)
			(xy 457.116178 -69.722746) (xy 457.120249 -69.667124) (xy 457.132375 -69.612687) (xy 457.152298 -69.560596)
			(xy 457.179594 -69.511961) (xy 457.21368 -69.467818) (xy 457.253829 -69.429109) (xy 457.299187 -69.396658)
			(xy 457.348787 -69.371157) (xy 457.401571 -69.35315) (xy 457.456414 -69.34302) (xy 457.512148 -69.340983)
			(xy 457.567585 -69.347083) (xy 457.621542 -69.361189) (xy 457.672871 -69.383001) (xy 457.720477 -69.412055)
			(xy 457.763345 -69.44773) (xy 457.800562 -69.489267) (xy 457.831335 -69.53578) (xy 457.855007 -69.586277)
			(xy 457.871075 -69.639684) (xy 457.879195 -69.69486) (xy 457.879704 -69.722746) (xy 457.879195 -69.750632)
			(xy 457.871075 -69.805808) (xy 457.855007 -69.859215) (xy 457.831335 -69.909712) (xy 457.800562 -69.956225)
			(xy 457.763345 -69.997762) (xy 457.720477 -70.033437) (xy 457.672871 -70.062491) (xy 457.621542 -70.084303)
			(xy 457.567585 -70.098409) (xy 457.512148 -70.104509) (xy 457.456414 -70.102472) (xy 457.401571 -70.092342)
			(xy 457.348787 -70.074335) (xy 457.299187 -70.048834) (xy 457.253829 -70.016383) (xy 457.21368 -69.977674)
			(xy 457.179594 -69.933531) (xy 457.152298 -69.884896) (xy 457.132375 -69.832805) (xy 457.120249 -69.778368)
			(xy 457.116178 -69.722746) (xy 456.990704 -69.722746) (xy 456.990195 -69.750632) (xy 456.982075 -69.805808)
			(xy 456.966007 -69.859215) (xy 456.942335 -69.909712) (xy 456.911562 -69.956225) (xy 456.874345 -69.997762)
			(xy 456.831477 -70.033437) (xy 456.783871 -70.062491) (xy 456.732542 -70.084303) (xy 456.678585 -70.098409)
			(xy 456.623148 -70.104509) (xy 456.567414 -70.102472) (xy 456.512571 -70.092342) (xy 456.459787 -70.074335)
			(xy 456.410187 -70.048834) (xy 456.364829 -70.016383) (xy 456.32468 -69.977674) (xy 456.290594 -69.933531)
			(xy 456.263298 -69.884896) (xy 456.243375 -69.832805) (xy 456.231249 -69.778368) (xy 456.227178 -69.722746)
			(xy 456.101704 -69.722746) (xy 456.101195 -69.750632) (xy 456.093075 -69.805808) (xy 456.077007 -69.859215)
			(xy 456.053335 -69.909712) (xy 456.022562 -69.956225) (xy 455.985345 -69.997762) (xy 455.942477 -70.033437)
			(xy 455.894871 -70.062491) (xy 455.843542 -70.084303) (xy 455.789585 -70.098409) (xy 455.734148 -70.104509)
			(xy 455.678414 -70.102472) (xy 455.623571 -70.092342) (xy 455.570787 -70.074335) (xy 455.521187 -70.048834)
			(xy 455.475829 -70.016383) (xy 455.43568 -69.977674) (xy 455.401594 -69.933531) (xy 455.374298 -69.884896)
			(xy 455.354375 -69.832805) (xy 455.342249 -69.778368) (xy 455.338178 -69.722746) (xy 455.212704 -69.722746)
			(xy 455.212195 -69.750632) (xy 455.204075 -69.805808) (xy 455.188007 -69.859215) (xy 455.164335 -69.909712)
			(xy 455.133562 -69.956225) (xy 455.096345 -69.997762) (xy 455.053477 -70.033437) (xy 455.005871 -70.062491)
			(xy 454.954542 -70.084303) (xy 454.900585 -70.098409) (xy 454.845148 -70.104509) (xy 454.789414 -70.102472)
			(xy 454.734571 -70.092342) (xy 454.681787 -70.074335) (xy 454.632187 -70.048834) (xy 454.586829 -70.016383)
			(xy 454.54668 -69.977674) (xy 454.512594 -69.933531) (xy 454.485298 -69.884896) (xy 454.465375 -69.832805)
			(xy 454.453249 -69.778368) (xy 454.449178 -69.722746) (xy 437.591708 -69.722746) (xy 437.591708 -71.592186)
			(xy 444.82258 -71.592186) (xy 444.82313 -71.56327) (xy 444.831848 -71.506099) (xy 444.849098 -71.450899)
			(xy 444.874483 -71.398937) (xy 444.907423 -71.351402) (xy 444.947162 -71.309386) (xy 444.969646 -71.291196)
			(xy 444.978453 -71.283589) (xy 444.988635 -71.262688) (xy 444.989204 -71.251064) (xy 444.989204 -71.171308)
			(xy 444.988645 -71.159679) (xy 444.97847 -71.138769) (xy 444.969646 -71.131176) (xy 444.94714 -71.113012)
			(xy 444.907408 -71.070985) (xy 444.874474 -71.023444) (xy 444.84909 -70.971478) (xy 444.831838 -70.916276)
			(xy 444.823113 -70.859103) (xy 444.82258 -70.830186) (xy 444.823065 -70.802935) (xy 444.830823 -70.748988)
			(xy 444.846179 -70.696694) (xy 444.868821 -70.647117) (xy 444.898288 -70.601268) (xy 444.933979 -70.560078)
			(xy 444.975169 -70.524386) (xy 445.021019 -70.49492) (xy 445.070596 -70.472278) (xy 445.12289 -70.456922)
			(xy 445.176837 -70.449165) (xy 445.204088 -70.448678) (xy 445.233006 -70.449175) (xy 445.29018 -70.457904)
			(xy 445.34538 -70.475165) (xy 445.397342 -70.50056) (xy 445.444876 -70.533509) (xy 445.48689 -70.573256)
			(xy 445.505078 -70.595744) (xy 445.512697 -70.604538) (xy 445.533589 -70.614727) (xy 445.54521 -70.615302)
			(xy 445.624966 -70.615302) (xy 445.636594 -70.614728) (xy 445.657503 -70.604564) (xy 445.665098 -70.595744)
			(xy 445.681851 -70.574961) (xy 445.720205 -70.537831) (xy 445.763359 -70.506409) (xy 445.810473 -70.48131)
			(xy 445.860625 -70.463024) (xy 445.912836 -70.451907) (xy 445.966088 -70.448177) (xy 446.01934 -70.451907)
			(xy 446.071551 -70.463024) (xy 446.121703 -70.48131) (xy 446.168817 -70.506409) (xy 446.211971 -70.537831)
			(xy 446.250325 -70.574961) (xy 446.267078 -70.595744) (xy 446.274697 -70.604538) (xy 446.295589 -70.614727)
			(xy 446.30721 -70.615302) (xy 446.386966 -70.615302) (xy 446.398594 -70.614728) (xy 446.419503 -70.604564)
			(xy 446.427098 -70.595744) (xy 446.443851 -70.574961) (xy 446.482205 -70.537831) (xy 446.525359 -70.506409)
			(xy 446.572473 -70.48131) (xy 446.622625 -70.463024) (xy 446.674836 -70.451907) (xy 446.728088 -70.448177)
			(xy 446.78134 -70.451907) (xy 446.833551 -70.463024) (xy 446.883703 -70.48131) (xy 446.930817 -70.506409)
			(xy 446.973971 -70.537831) (xy 447.012325 -70.574961) (xy 447.029078 -70.595744) (xy 447.036697 -70.604538)
			(xy 447.057589 -70.614727) (xy 447.06921 -70.615302) (xy 447.148966 -70.615302) (xy 447.160594 -70.614728)
			(xy 447.181503 -70.604564) (xy 447.189098 -70.595744) (xy 447.207301 -70.573271) (xy 447.249317 -70.533533)
			(xy 447.296849 -70.500591) (xy 447.348808 -70.475201) (xy 447.404004 -70.457943) (xy 447.461173 -70.449213)
			(xy 447.490088 -70.448678) (xy 447.517338 -70.449189) (xy 447.571284 -70.456944) (xy 447.623578 -70.472297)
			(xy 447.673154 -70.494935) (xy 447.719004 -70.524399) (xy 447.760194 -70.560088) (xy 447.795885 -70.601276)
			(xy 447.825352 -70.647123) (xy 447.847994 -70.696698) (xy 447.863351 -70.74899) (xy 447.871109 -70.802936)
			(xy 447.871596 -70.830186) (xy 447.871069 -70.859103) (xy 447.862342 -70.916273) (xy 447.845086 -70.971472)
			(xy 447.819696 -71.023434) (xy 447.786754 -71.070968) (xy 447.747015 -71.112985) (xy 447.72453 -71.131176)
			(xy 447.715732 -71.138791) (xy 447.705546 -71.159686) (xy 447.704972 -71.171308) (xy 447.704972 -71.251064)
			(xy 447.705463 -71.262703) (xy 447.715683 -71.283613) (xy 447.72453 -71.291196) (xy 447.747018 -71.309382)
			(xy 447.786751 -71.351403) (xy 447.819689 -71.39894) (xy 447.845076 -71.450902) (xy 447.862332 -71.5061)
			(xy 447.871061 -71.56327) (xy 447.871596 -71.592186) (xy 447.871132 -71.619439) (xy 447.863376 -71.673391)
			(xy 447.848021 -71.725689) (xy 447.82538 -71.77527) (xy 447.795912 -71.821124) (xy 447.760218 -71.862317)
			(xy 447.719025 -71.898011) (xy 447.673172 -71.927479) (xy 447.623591 -71.950121) (xy 447.571293 -71.965476)
			(xy 447.517341 -71.973231) (xy 447.490088 -71.973694) (xy 447.461173 -71.973115) (xy 447.404005 -71.964399)
			(xy 447.348807 -71.947153) (xy 447.296845 -71.921773) (xy 447.24931 -71.88884) (xy 447.20729 -71.849109)
			(xy 447.189098 -71.826628) (xy 447.181494 -71.817818) (xy 447.16059 -71.807639) (xy 447.148966 -71.80707)
			(xy 447.06921 -71.80707) (xy 447.057577 -71.807605) (xy 447.036666 -71.817794) (xy 447.029078 -71.826628)
			(xy 447.012325 -71.847411) (xy 446.973971 -71.884541) (xy 446.930817 -71.915963) (xy 446.883703 -71.941062)
			(xy 446.833551 -71.959348) (xy 446.78134 -71.970465) (xy 446.728088 -71.974195) (xy 446.674836 -71.970465)
			(xy 446.622625 -71.959348) (xy 446.572473 -71.941062) (xy 446.525359 -71.915963) (xy 446.482205 -71.884541)
			(xy 446.443851 -71.847411) (xy 446.427098 -71.826628) (xy 446.419494 -71.817818) (xy 446.39859 -71.807639)
			(xy 446.386966 -71.80707) (xy 446.30721 -71.80707) (xy 446.295577 -71.807605) (xy 446.274666 -71.817794)
			(xy 446.267078 -71.826628) (xy 446.250325 -71.847411) (xy 446.211971 -71.884541) (xy 446.168817 -71.915963)
			(xy 446.121703 -71.941062) (xy 446.071551 -71.959348) (xy 446.01934 -71.970465) (xy 445.966088 -71.974195)
			(xy 445.912836 -71.970465) (xy 445.860625 -71.959348) (xy 445.810473 -71.941062) (xy 445.763359 -71.915963)
			(xy 445.720205 -71.884541) (xy 445.681851 -71.847411) (xy 445.665098 -71.826628) (xy 445.657494 -71.817818)
			(xy 445.63659 -71.807639) (xy 445.624966 -71.80707) (xy 445.54521 -71.80707) (xy 445.533577 -71.807605)
			(xy 445.512666 -71.817794) (xy 445.505078 -71.826628) (xy 445.486906 -71.849128) (xy 445.444882 -71.888861)
			(xy 445.397343 -71.921797) (xy 445.345378 -71.947182) (xy 445.290177 -71.964435) (xy 445.233005 -71.973161)
			(xy 445.204088 -71.973694) (xy 445.176834 -71.973256) (xy 445.122882 -71.965497) (xy 445.070582 -71.950139)
			(xy 445.021001 -71.927494) (xy 444.975147 -71.898023) (xy 444.933954 -71.862327) (xy 444.898261 -71.821132)
			(xy 444.868793 -71.775276) (xy 444.846152 -71.725693) (xy 444.830797 -71.673393) (xy 444.823042 -71.61944)
			(xy 444.82258 -71.592186) (xy 437.591708 -71.592186) (xy 437.591708 -72.415584) (xy 448.803264 -72.415584)
			(xy 448.803264 -72.330888) (xy 448.811315 -72.246574) (xy 448.827344 -72.163408) (xy 448.851205 -72.082141)
			(xy 448.882684 -72.003511) (xy 448.921495 -71.92823) (xy 448.967285 -71.856978) (xy 449.019641 -71.790402)
			(xy 449.078089 -71.729104) (xy 449.142099 -71.673639) (xy 449.211091 -71.62451) (xy 449.284441 -71.582161)
			(xy 449.361484 -71.546977) (xy 449.441523 -71.519275) (xy 449.523832 -71.499307) (xy 449.607667 -71.487254)
			(xy 449.692268 -71.483224) (xy 449.776869 -71.487254) (xy 449.860704 -71.499307) (xy 449.943013 -71.519275)
			(xy 450.023052 -71.546977) (xy 450.100095 -71.582161) (xy 450.173445 -71.62451) (xy 450.242437 -71.673639)
			(xy 450.306447 -71.729104) (xy 450.364895 -71.790402) (xy 450.417251 -71.856978) (xy 450.463041 -71.92823)
			(xy 450.501852 -72.003511) (xy 450.533331 -72.082141) (xy 450.557192 -72.163408) (xy 450.573221 -72.246574)
			(xy 450.581272 -72.330888) (xy 450.581776 -72.373236) (xy 450.581272 -72.415584) (xy 456.311504 -72.415584)
			(xy 456.311504 -72.330888) (xy 456.319555 -72.246574) (xy 456.335584 -72.163408) (xy 456.359445 -72.082141)
			(xy 456.390924 -72.003511) (xy 456.429735 -71.92823) (xy 456.475525 -71.856978) (xy 456.527881 -71.790402)
			(xy 456.586329 -71.729104) (xy 456.650339 -71.673639) (xy 456.719331 -71.62451) (xy 456.792681 -71.582161)
			(xy 456.869724 -71.546977) (xy 456.949763 -71.519275) (xy 457.032072 -71.499307) (xy 457.115907 -71.487254)
			(xy 457.200508 -71.483224) (xy 457.285109 -71.487254) (xy 457.368944 -71.499307) (xy 457.451253 -71.519275)
			(xy 457.531292 -71.546977) (xy 457.608335 -71.582161) (xy 457.681685 -71.62451) (xy 457.750677 -71.673639)
			(xy 457.814687 -71.729104) (xy 457.873135 -71.790402) (xy 457.925491 -71.856978) (xy 457.971281 -71.92823)
			(xy 458.010092 -72.003511) (xy 458.041571 -72.082141) (xy 458.065432 -72.163408) (xy 458.081461 -72.246574)
			(xy 458.089512 -72.330888) (xy 458.090016 -72.373236) (xy 458.089512 -72.415584) (xy 458.081461 -72.499898)
			(xy 458.065432 -72.583064) (xy 458.041571 -72.664331) (xy 458.010092 -72.742961) (xy 457.971281 -72.818242)
			(xy 457.925491 -72.889494) (xy 457.873135 -72.95607) (xy 457.814687 -73.017368) (xy 457.750677 -73.072833)
			(xy 457.681685 -73.121962) (xy 457.608335 -73.164311) (xy 457.531292 -73.199495) (xy 457.451253 -73.227197)
			(xy 457.368944 -73.247165) (xy 457.285109 -73.259218) (xy 457.200508 -73.263249) (xy 457.115907 -73.259218)
			(xy 457.032072 -73.247165) (xy 456.949763 -73.227197) (xy 456.869724 -73.199495) (xy 456.792681 -73.164311)
			(xy 456.719331 -73.121962) (xy 456.650339 -73.072833) (xy 456.586329 -73.017368) (xy 456.527881 -72.95607)
			(xy 456.475525 -72.889494) (xy 456.429735 -72.818242) (xy 456.390924 -72.742961) (xy 456.359445 -72.664331)
			(xy 456.335584 -72.583064) (xy 456.319555 -72.499898) (xy 456.311504 -72.415584) (xy 450.581272 -72.415584)
			(xy 450.573221 -72.499898) (xy 450.557192 -72.583064) (xy 450.533331 -72.664331) (xy 450.501852 -72.742961)
			(xy 450.463041 -72.818242) (xy 450.417251 -72.889494) (xy 450.364895 -72.95607) (xy 450.306447 -73.017368)
			(xy 450.242437 -73.072833) (xy 450.173445 -73.121962) (xy 450.100095 -73.164311) (xy 450.023052 -73.199495)
			(xy 449.943013 -73.227197) (xy 449.860704 -73.247165) (xy 449.776869 -73.259218) (xy 449.692268 -73.263249)
			(xy 449.607667 -73.259218) (xy 449.523832 -73.247165) (xy 449.441523 -73.227197) (xy 449.361484 -73.199495)
			(xy 449.284441 -73.164311) (xy 449.211091 -73.121962) (xy 449.142099 -73.072833) (xy 449.078089 -73.017368)
			(xy 449.019641 -72.95607) (xy 448.967285 -72.889494) (xy 448.921495 -72.818242) (xy 448.882684 -72.742961)
			(xy 448.851205 -72.664331) (xy 448.827344 -72.583064) (xy 448.811315 -72.499898) (xy 448.803264 -72.415584)
			(xy 437.591708 -72.415584) (xy 437.591708 -73.961498) (xy 437.592248 -73.972516) (xy 437.601468 -73.992531)
			(xy 437.609488 -74.000106) (xy 437.676544 -74.057764) (xy 437.697626 -74.06386) (xy 437.700674 -74.063352)
			(xy 437.717111 -74.060619) (xy 437.750306 -74.057691) (xy 437.766968 -74.05751) (xy 437.794242 -74.057971)
			(xy 437.848237 -74.06573) (xy 437.900577 -74.081095) (xy 437.950198 -74.103752) (xy 437.996089 -74.133241)
			(xy 438.037316 -74.168961) (xy 438.073039 -74.210185) (xy 438.102532 -74.256074) (xy 438.125194 -74.305693)
			(xy 438.140563 -74.358032) (xy 438.148326 -74.412026) (xy 438.148326 -74.466574) (xy 438.140563 -74.520568)
			(xy 438.125194 -74.572907) (xy 438.102532 -74.622526) (xy 438.073039 -74.668415) (xy 438.037316 -74.709639)
			(xy 437.996089 -74.745359) (xy 437.950198 -74.774848) (xy 437.900577 -74.797505) (xy 437.848237 -74.81287)
			(xy 437.794242 -74.820629) (xy 437.766968 -74.821034) (xy 437.750434 -74.820827) (xy 437.717493 -74.817906)
			(xy 437.701182 -74.815192) (xy 437.700166 -74.815192) (xy 437.697626 -74.814684) (xy 437.676544 -74.82078)
			(xy 437.609488 -74.878438) (xy 437.601472 -74.886013) (xy 437.592269 -74.90603) (xy 437.591708 -74.917046)
			(xy 437.591708 -77.655928) (xy 439.102246 -77.655928) (xy 439.102767 -77.627011) (xy 439.111493 -77.569839)
			(xy 439.128749 -77.51464) (xy 439.15414 -77.462677) (xy 439.187084 -77.415144) (xy 439.226826 -77.373127)
			(xy 439.249312 -77.354938) (xy 439.258094 -77.347306) (xy 439.268291 -77.326424) (xy 439.26887 -77.314806)
			(xy 439.26887 -77.23505) (xy 439.268356 -77.223415) (xy 439.25815 -77.202505) (xy 439.249312 -77.194918)
			(xy 439.22684 -77.176714) (xy 439.187103 -77.134697) (xy 439.154163 -77.087165) (xy 439.128772 -77.035206)
			(xy 439.111514 -76.980011) (xy 439.102782 -76.922843) (xy 439.102246 -76.893928) (xy 439.102828 -76.864027)
			(xy 439.112143 -76.804956) (xy 439.130564 -76.748063) (xy 439.15764 -76.694743) (xy 439.192707 -76.646303)
			(xy 439.234906 -76.60393) (xy 439.25871 -76.585826) (xy 439.267783 -76.578485) (xy 439.278618 -76.557838)
			(xy 439.279538 -76.546202) (xy 439.282078 -76.453746) (xy 439.272172 -76.432664) (xy 439.263028 -76.425044)
			(xy 439.24149 -76.406825) (xy 439.203482 -76.365138) (xy 439.17203 -76.318308) (xy 439.147821 -76.267355)
			(xy 439.131383 -76.213391) (xy 439.123074 -76.157594) (xy 439.122566 -76.129388) (xy 439.123123 -76.100472)
			(xy 439.13184 -76.043302) (xy 439.149089 -75.988103) (xy 439.174473 -75.93614) (xy 439.207411 -75.888605)
			(xy 439.247148 -75.846588) (xy 439.269632 -75.828398) (xy 439.278436 -75.820787) (xy 439.28862 -75.799889)
			(xy 439.28919 -75.788266) (xy 439.28919 -75.70851) (xy 439.288634 -75.69688) (xy 439.278457 -75.67597)
			(xy 439.269632 -75.668378) (xy 439.248838 -75.651638) (xy 439.21171 -75.613282) (xy 439.180291 -75.570125)
			(xy 439.155194 -75.52301) (xy 439.13691 -75.472857) (xy 439.125795 -75.420645) (xy 439.122066 -75.367393)
			(xy 439.125797 -75.314141) (xy 439.136914 -75.261929) (xy 439.1552 -75.211776) (xy 439.180299 -75.164662)
			(xy 439.21172 -75.121507) (xy 439.248849 -75.083152) (xy 439.269632 -75.066398) (xy 439.278436 -75.058787)
			(xy 439.28862 -75.037889) (xy 439.28919 -75.026266) (xy 439.28919 -74.94651) (xy 439.288634 -74.93488)
			(xy 439.278457 -74.91397) (xy 439.269632 -74.906378) (xy 439.247145 -74.888191) (xy 439.207408 -74.846172)
			(xy 439.174469 -74.798636) (xy 439.149081 -74.746674) (xy 439.131826 -74.691475) (xy 439.123099 -74.634304)
			(xy 439.122566 -74.605388) (xy 439.123067 -74.578138) (xy 439.130824 -74.524192) (xy 439.146179 -74.471899)
			(xy 439.16882 -74.422323) (xy 439.198285 -74.376474) (xy 439.233975 -74.335285) (xy 439.275163 -74.299594)
			(xy 439.321011 -74.270127) (xy 439.370586 -74.247484) (xy 439.422878 -74.232127) (xy 439.476824 -74.224368)
			(xy 439.504074 -74.22388) (xy 439.531445 -74.224342) (xy 439.585625 -74.232158) (xy 439.638129 -74.247647)
			(xy 439.687875 -74.27049) (xy 439.733841 -74.300217) (xy 439.754772 -74.31786) (xy 439.755026 -74.318114)
			(xy 439.762128 -74.323677) (xy 439.779033 -74.329938) (xy 439.788046 -74.330306) (xy 439.855102 -74.330306)
			(xy 439.864119 -74.329949) (xy 439.881036 -74.323701) (xy 439.888122 -74.318114) (xy 439.888122 -74.31786)
			(xy 439.888376 -74.31786) (xy 439.909301 -74.300212) (xy 439.955276 -74.270503) (xy 440.005026 -74.247669)
			(xy 440.057528 -74.23218) (xy 440.111704 -74.224353) (xy 440.139074 -74.22388) (xy 440.167778 -74.224384)
			(xy 440.224539 -74.232984) (xy 440.27937 -74.249992) (xy 440.331033 -74.275026) (xy 440.378361 -74.307519)
			(xy 440.399678 -74.32675) (xy 440.407079 -74.333093) (xy 440.425241 -74.340133) (xy 440.434984 -74.340466)
			(xy 440.515502 -74.33945) (xy 440.53379 -74.331576) (xy 440.540648 -74.324718) (xy 440.548874 -74.316646)
			(xy 440.566159 -74.301397) (xy 440.575192 -74.294238) (xy 440.583971 -74.286603) (xy 440.59417 -74.265724)
			(xy 440.59475 -74.254106) (xy 440.59475 -74.17435) (xy 440.594243 -74.162714) (xy 440.584033 -74.141803)
			(xy 440.575192 -74.134218) (xy 440.552715 -74.116019) (xy 440.51298 -74.074001) (xy 440.480041 -74.026467)
			(xy 440.454651 -73.974508) (xy 440.437393 -73.919312) (xy 440.428662 -73.862143) (xy 440.428126 -73.833228)
			(xy 440.428581 -73.805974) (xy 440.436336 -73.752021) (xy 440.45169 -73.699721) (xy 440.474331 -73.650139)
			(xy 440.5038 -73.604284) (xy 440.539494 -73.56309) (xy 440.580689 -73.527396) (xy 440.626544 -73.497929)
			(xy 440.676127 -73.475288) (xy 440.728427 -73.459934) (xy 440.78238 -73.452181) (xy 440.809634 -73.45172)
			(xy 440.837005 -73.452161) (xy 440.891186 -73.459984) (xy 440.943689 -73.475479) (xy 440.993436 -73.498326)
			(xy 441.039401 -73.528056) (xy 441.060332 -73.5457) (xy 441.060586 -73.545954) (xy 441.067668 -73.551547)
			(xy 441.084588 -73.557789) (xy 441.093606 -73.558146) (xy 441.160662 -73.558146) (xy 441.169678 -73.557783)
			(xy 441.186596 -73.551541) (xy 441.193682 -73.545954) (xy 441.193682 -73.5457) (xy 441.193936 -73.5457)
			(xy 441.214869 -73.528059) (xy 441.260837 -73.498335) (xy 441.310583 -73.475489) (xy 441.363085 -73.459993)
			(xy 441.417263 -73.452164) (xy 441.472005 -73.452164) (xy 441.526183 -73.459993) (xy 441.578685 -73.475489)
			(xy 441.628431 -73.498335) (xy 441.674399 -73.528059) (xy 441.695332 -73.5457) (xy 441.695586 -73.545954)
			(xy 441.702668 -73.551547) (xy 441.719588 -73.557789) (xy 441.728606 -73.558146) (xy 441.795662 -73.558146)
			(xy 441.804678 -73.557783) (xy 441.821596 -73.551541) (xy 441.828682 -73.545954) (xy 441.828682 -73.5457)
			(xy 441.828936 -73.5457) (xy 441.849869 -73.528059) (xy 441.895837 -73.498335) (xy 441.945583 -73.475489)
			(xy 441.998085 -73.459993) (xy 442.052263 -73.452164) (xy 442.107005 -73.452164) (xy 442.161183 -73.459993)
			(xy 442.213685 -73.475489) (xy 442.263431 -73.498335) (xy 442.309399 -73.528059) (xy 442.330332 -73.5457)
			(xy 442.330586 -73.545954) (xy 442.337668 -73.551547) (xy 442.354588 -73.557789) (xy 442.363606 -73.558146)
			(xy 442.430662 -73.558146) (xy 442.439678 -73.557783) (xy 442.456596 -73.551541) (xy 442.463682 -73.545954)
			(xy 442.463682 -73.5457) (xy 442.463936 -73.5457) (xy 442.484881 -73.528077) (xy 442.530851 -73.498363)
			(xy 442.580595 -73.475524) (xy 442.633092 -73.460029) (xy 442.687266 -73.452196) (xy 442.714634 -73.45172)
			(xy 442.744758 -73.452278) (xy 442.804254 -73.461763) (xy 442.861522 -73.480478) (xy 442.915139 -73.507956)
			(xy 442.963773 -73.543516) (xy 442.985398 -73.564496) (xy 442.992805 -73.571327) (xy 443.011399 -73.579052)
			(xy 443.021466 -73.579482) (xy 443.093602 -73.579482) (xy 443.103672 -73.579062) (xy 443.12227 -73.571338)
			(xy 443.12967 -73.564496) (xy 443.151284 -73.543504) (xy 443.199916 -73.507938) (xy 443.253535 -73.48046)
			(xy 443.310808 -73.461754) (xy 443.370309 -73.452287) (xy 443.400434 -73.45172) (xy 443.427687 -73.452146)
			(xy 443.481639 -73.459908) (xy 443.533936 -73.475269) (xy 443.583515 -73.497916) (xy 443.629367 -73.527389)
			(xy 443.670558 -73.563086) (xy 443.706249 -73.604283) (xy 443.735714 -73.650139) (xy 443.758353 -73.699722)
			(xy 443.773705 -73.752022) (xy 443.781458 -73.805975) (xy 443.781942 -73.833228) (xy 443.781394 -73.862144)
			(xy 443.772674 -73.919315) (xy 443.755423 -73.974514) (xy 443.730037 -74.026476) (xy 443.697098 -74.074011)
			(xy 443.65736 -74.116028) (xy 443.634876 -74.134218) (xy 443.626066 -74.141823) (xy 443.615885 -74.162725)
			(xy 443.615318 -74.17435) (xy 443.615318 -74.254106) (xy 443.615861 -74.265738) (xy 443.626046 -74.286648)
			(xy 443.634876 -74.294238) (xy 443.657373 -74.312414) (xy 443.697108 -74.354436) (xy 443.730046 -74.401974)
			(xy 443.755433 -74.453938) (xy 443.772686 -74.509139) (xy 443.77435 -74.520044) (xy 444.46139 -74.520044)
			(xy 444.465461 -74.464422) (xy 444.477587 -74.409985) (xy 444.49751 -74.357894) (xy 444.524806 -74.309259)
			(xy 444.558892 -74.265116) (xy 444.599041 -74.226407) (xy 444.644399 -74.193956) (xy 444.693999 -74.168455)
			(xy 444.746783 -74.150448) (xy 444.801626 -74.140318) (xy 444.85736 -74.138281) (xy 444.912797 -74.144381)
			(xy 444.966754 -74.158487) (xy 445.018083 -74.180299) (xy 445.065689 -74.209353) (xy 445.108557 -74.245028)
			(xy 445.145774 -74.286565) (xy 445.176547 -74.333078) (xy 445.200219 -74.383575) (xy 445.216287 -74.436982)
			(xy 445.224407 -74.492158) (xy 445.224916 -74.520044) (xy 445.224407 -74.54793) (xy 445.216287 -74.603106)
			(xy 445.200219 -74.656513) (xy 445.176547 -74.70701) (xy 445.145774 -74.753523) (xy 445.108557 -74.79506)
			(xy 445.065689 -74.830735) (xy 445.018083 -74.859789) (xy 444.966754 -74.881601) (xy 444.912797 -74.895707)
			(xy 444.85736 -74.901807) (xy 444.801626 -74.89977) (xy 444.746783 -74.88964) (xy 444.693999 -74.871633)
			(xy 444.644399 -74.846132) (xy 444.599041 -74.813681) (xy 444.558892 -74.774972) (xy 444.524806 -74.730829)
			(xy 444.49751 -74.682194) (xy 444.477587 -74.630103) (xy 444.465461 -74.575666) (xy 444.46139 -74.520044)
			(xy 443.77435 -74.520044) (xy 443.78141 -74.566311) (xy 443.781942 -74.595228) (xy 443.781448 -74.622478)
			(xy 443.773689 -74.676424) (xy 443.758332 -74.728717) (xy 443.73569 -74.778292) (xy 443.706224 -74.82414)
			(xy 443.670534 -74.865329) (xy 443.629345 -74.90102) (xy 443.606495 -74.915706) (xy 448.803264 -74.915706)
			(xy 448.803264 -74.83101) (xy 448.811315 -74.746696) (xy 448.827344 -74.66353) (xy 448.851205 -74.582263)
			(xy 448.882684 -74.503633) (xy 448.921495 -74.428352) (xy 448.967285 -74.3571) (xy 449.019641 -74.290524)
			(xy 449.078089 -74.229226) (xy 449.142099 -74.173761) (xy 449.211091 -74.124632) (xy 449.284441 -74.082283)
			(xy 449.361484 -74.047099) (xy 449.441523 -74.019397) (xy 449.523832 -73.999429) (xy 449.607667 -73.987376)
			(xy 449.692268 -73.983346) (xy 449.776869 -73.987376) (xy 449.860704 -73.999429) (xy 449.943013 -74.019397)
			(xy 450.023052 -74.047099) (xy 450.100095 -74.082283) (xy 450.173445 -74.124632) (xy 450.242437 -74.173761)
			(xy 450.306447 -74.229226) (xy 450.364895 -74.290524) (xy 450.417251 -74.3571) (xy 450.463041 -74.428352)
			(xy 450.501852 -74.503633) (xy 450.533331 -74.582263) (xy 450.557192 -74.66353) (xy 450.573221 -74.746696)
			(xy 450.581272 -74.83101) (xy 450.581776 -74.873358) (xy 450.581272 -74.915706) (xy 456.311504 -74.915706)
			(xy 456.311504 -74.83101) (xy 456.319555 -74.746696) (xy 456.335584 -74.66353) (xy 456.359445 -74.582263)
			(xy 456.390924 -74.503633) (xy 456.429735 -74.428352) (xy 456.475525 -74.3571) (xy 456.527881 -74.290524)
			(xy 456.586329 -74.229226) (xy 456.650339 -74.173761) (xy 456.719331 -74.124632) (xy 456.792681 -74.082283)
			(xy 456.869724 -74.047099) (xy 456.949763 -74.019397) (xy 457.032072 -73.999429) (xy 457.115907 -73.987376)
			(xy 457.200508 -73.983346) (xy 457.285109 -73.987376) (xy 457.368944 -73.999429) (xy 457.451253 -74.019397)
			(xy 457.531292 -74.047099) (xy 457.608335 -74.082283) (xy 457.681685 -74.124632) (xy 457.750677 -74.173761)
			(xy 457.814687 -74.229226) (xy 457.873135 -74.290524) (xy 457.925491 -74.3571) (xy 457.971281 -74.428352)
			(xy 458.010092 -74.503633) (xy 458.041571 -74.582263) (xy 458.065432 -74.66353) (xy 458.081461 -74.746696)
			(xy 458.089512 -74.83101) (xy 458.090016 -74.873358) (xy 458.089512 -74.915706) (xy 458.081461 -75.00002)
			(xy 458.065432 -75.083186) (xy 458.041571 -75.164453) (xy 458.010092 -75.243083) (xy 457.971281 -75.318364)
			(xy 457.925491 -75.389616) (xy 457.873135 -75.456192) (xy 457.814687 -75.51749) (xy 457.750677 -75.572955)
			(xy 457.681685 -75.622084) (xy 457.608335 -75.664433) (xy 457.531292 -75.699617) (xy 457.451253 -75.727319)
			(xy 457.368944 -75.747287) (xy 457.285109 -75.75934) (xy 457.200508 -75.763371) (xy 457.115907 -75.75934)
			(xy 457.032072 -75.747287) (xy 456.949763 -75.727319) (xy 456.869724 -75.699617) (xy 456.792681 -75.664433)
			(xy 456.719331 -75.622084) (xy 456.650339 -75.572955) (xy 456.586329 -75.51749) (xy 456.527881 -75.456192)
			(xy 456.475525 -75.389616) (xy 456.429735 -75.318364) (xy 456.390924 -75.243083) (xy 456.359445 -75.164453)
			(xy 456.335584 -75.083186) (xy 456.319555 -75.00002) (xy 456.311504 -74.915706) (xy 450.581272 -74.915706)
			(xy 450.573221 -75.00002) (xy 450.557192 -75.083186) (xy 450.533331 -75.164453) (xy 450.501852 -75.243083)
			(xy 450.463041 -75.318364) (xy 450.417251 -75.389616) (xy 450.364895 -75.456192) (xy 450.306447 -75.51749)
			(xy 450.242437 -75.572955) (xy 450.173445 -75.622084) (xy 450.100095 -75.664433) (xy 450.023052 -75.699617)
			(xy 449.943013 -75.727319) (xy 449.860704 -75.747287) (xy 449.776869 -75.75934) (xy 449.692268 -75.763371)
			(xy 449.607667 -75.75934) (xy 449.523832 -75.747287) (xy 449.441523 -75.727319) (xy 449.361484 -75.699617)
			(xy 449.284441 -75.664433) (xy 449.211091 -75.622084) (xy 449.142099 -75.572955) (xy 449.078089 -75.51749)
			(xy 449.019641 -75.456192) (xy 448.967285 -75.389616) (xy 448.921495 -75.318364) (xy 448.882684 -75.243083)
			(xy 448.851205 -75.164453) (xy 448.827344 -75.083186) (xy 448.811315 -75.00002) (xy 448.803264 -74.915706)
			(xy 443.606495 -74.915706) (xy 443.583497 -74.930487) (xy 443.533922 -74.95313) (xy 443.48163 -74.968488)
			(xy 443.427684 -74.976248) (xy 443.400434 -74.976736) (xy 443.370311 -74.976148) (xy 443.310815 -74.966672)
			(xy 443.253548 -74.947965) (xy 443.19993 -74.920493) (xy 443.151295 -74.884938) (xy 443.12967 -74.86396)
			(xy 443.122279 -74.857109) (xy 443.103673 -74.849397) (xy 443.093602 -74.848974) (xy 443.021466 -74.848974)
			(xy 443.011392 -74.849362) (xy 442.992793 -74.857107) (xy 442.985398 -74.86396) (xy 442.963791 -74.884959)
			(xy 442.915158 -74.920527) (xy 442.861537 -74.948004) (xy 442.804263 -74.966708) (xy 442.74476 -74.976172)
			(xy 442.714634 -74.976736) (xy 442.687264 -74.976266) (xy 442.633084 -74.968451) (xy 442.580581 -74.952964)
			(xy 442.530834 -74.930123) (xy 442.484867 -74.900398) (xy 442.463936 -74.882756) (xy 442.463682 -74.882502)
			(xy 442.456605 -74.876902) (xy 442.439681 -74.870663) (xy 442.430662 -74.87031) (xy 442.363606 -74.87031)
			(xy 442.354589 -74.870668) (xy 442.337672 -74.876914) (xy 442.330586 -74.882502) (xy 442.330586 -74.882756)
			(xy 442.330078 -74.882756) (xy 442.314076 -74.896218) (xy 442.305266 -74.903823) (xy 442.295085 -74.924725)
			(xy 442.294518 -74.93635) (xy 442.294518 -75.016106) (xy 442.295061 -75.027738) (xy 442.305246 -75.048648)
			(xy 442.314076 -75.056238) (xy 442.334885 -75.072959) (xy 442.372013 -75.111318) (xy 442.403431 -75.154477)
			(xy 442.428527 -75.201594) (xy 442.44681 -75.25175) (xy 442.457924 -75.303964) (xy 442.461651 -75.357217)
			(xy 442.457919 -75.41047) (xy 442.446801 -75.462684) (xy 442.428513 -75.512837) (xy 442.403413 -75.559952)
			(xy 442.37199 -75.603108) (xy 442.334859 -75.641464) (xy 442.314076 -75.658218) (xy 442.305266 -75.665823)
			(xy 442.295085 -75.686725) (xy 442.294518 -75.69835) (xy 442.294518 -75.778106) (xy 442.295061 -75.789738)
			(xy 442.305246 -75.810648) (xy 442.314076 -75.818238) (xy 442.336573 -75.836414) (xy 442.376308 -75.878436)
			(xy 442.409246 -75.925974) (xy 442.434633 -75.977938) (xy 442.451886 -76.033139) (xy 442.46061 -76.090311)
			(xy 442.461142 -76.119228) (xy 442.460565 -76.149128) (xy 442.451244 -76.208198) (xy 442.432819 -76.26509)
			(xy 442.405742 -76.318409) (xy 442.370676 -76.366849) (xy 442.32848 -76.409224) (xy 442.304678 -76.42733)
			(xy 442.295622 -76.434688) (xy 442.284778 -76.455323) (xy 442.28385 -76.466954) (xy 442.28131 -76.55941)
			(xy 442.291216 -76.580492) (xy 442.30036 -76.588112) (xy 442.321923 -76.606304) (xy 442.359929 -76.647995)
			(xy 442.391378 -76.694832) (xy 442.415583 -76.74579) (xy 442.432016 -76.799759) (xy 442.440318 -76.85556)
			(xy 442.440822 -76.883768) (xy 442.44031 -76.912686) (xy 442.431584 -76.969858) (xy 442.414327 -77.025059)
			(xy 442.388934 -77.077021) (xy 442.355988 -77.124555) (xy 442.316243 -77.166569) (xy 442.293756 -77.184758)
			(xy 442.284971 -77.192386) (xy 442.274777 -77.213271) (xy 442.274198 -77.22489) (xy 442.274198 -77.304646)
			(xy 442.274726 -77.316279) (xy 442.284923 -77.337189) (xy 442.293756 -77.344778) (xy 442.31622 -77.362993)
			(xy 442.355958 -77.405006) (xy 442.388901 -77.452536) (xy 442.414293 -77.504493) (xy 442.431553 -77.559687)
			(xy 442.440285 -77.616853) (xy 442.440822 -77.645768) (xy 442.440315 -77.673019) (xy 442.432563 -77.726968)
			(xy 442.417211 -77.779264) (xy 442.394574 -77.828843) (xy 442.36511 -77.874696) (xy 442.329421 -77.915889)
			(xy 442.288233 -77.951583) (xy 442.242384 -77.981052) (xy 442.192807 -78.003695) (xy 442.140513 -78.019053)
			(xy 442.086565 -78.026812) (xy 442.059314 -78.027276) (xy 442.031944 -78.026808) (xy 441.977765 -78.018991)
			(xy 441.925261 -78.003503) (xy 441.875514 -77.980662) (xy 441.829548 -77.950937) (xy 441.808616 -77.933296)
			(xy 441.808362 -77.933042) (xy 441.801267 -77.927468) (xy 441.784356 -77.921215) (xy 441.775342 -77.92085)
			(xy 441.708286 -77.92085) (xy 441.699267 -77.92119) (xy 441.68235 -77.927448) (xy 441.675266 -77.933042)
			(xy 441.675266 -77.933296) (xy 441.675012 -77.933296) (xy 441.654079 -77.950937) (xy 441.608111 -77.980661)
			(xy 441.558365 -78.003507) (xy 441.505863 -78.019003) (xy 441.451685 -78.026832) (xy 441.396943 -78.026832)
			(xy 441.342765 -78.019003) (xy 441.290263 -78.003507) (xy 441.240517 -77.980661) (xy 441.194549 -77.950937)
			(xy 441.173616 -77.933296) (xy 441.173362 -77.933042) (xy 441.166267 -77.927468) (xy 441.149356 -77.921215)
			(xy 441.140342 -77.92085) (xy 441.073286 -77.92085) (xy 441.064267 -77.92119) (xy 441.04735 -77.927448)
			(xy 441.040266 -77.933042) (xy 441.040266 -77.933296) (xy 441.040012 -77.933296) (xy 441.019086 -77.950942)
			(xy 440.973111 -77.980653) (xy 440.923362 -78.003488) (xy 440.87086 -78.018977) (xy 440.816684 -78.026803)
			(xy 440.789314 -78.027276) (xy 440.76061 -78.026765) (xy 440.70385 -78.018165) (xy 440.649019 -78.001157)
			(xy 440.597356 -77.976125) (xy 440.550027 -77.943635) (xy 440.52871 -77.924406) (xy 440.521285 -77.918096)
			(xy 440.503141 -77.911038) (xy 440.493404 -77.91069) (xy 440.412886 -77.911706) (xy 440.394598 -77.91958)
			(xy 440.38774 -77.926438) (xy 440.366159 -77.947099) (xy 440.317752 -77.982114) (xy 440.264478 -78.009151)
			(xy 440.207639 -78.02755) (xy 440.148625 -78.036859) (xy 440.118754 -78.037436) (xy 440.091384 -78.036954)
			(xy 440.037205 -78.029142) (xy 439.984702 -78.013658) (xy 439.934954 -77.990819) (xy 439.888988 -77.961097)
			(xy 439.868056 -77.943456) (xy 439.867802 -77.943202) (xy 439.860719 -77.93761) (xy 439.843799 -77.931367)
			(xy 439.834782 -77.93101) (xy 439.767726 -77.93101) (xy 439.75871 -77.931377) (xy 439.741793 -77.937617)
			(xy 439.734706 -77.943202) (xy 439.734706 -77.943456) (xy 439.734452 -77.943456) (xy 439.713505 -77.961077)
			(xy 439.667537 -77.990793) (xy 439.617794 -78.013633) (xy 439.565296 -78.029128) (xy 439.511122 -78.03696)
			(xy 439.483754 -78.037436) (xy 439.456503 -78.036965) (xy 439.402556 -78.029203) (xy 439.350263 -78.013843)
			(xy 439.300687 -77.991199) (xy 439.254838 -77.961731) (xy 439.213649 -77.926038) (xy 439.177959 -77.884847)
			(xy 439.148492 -77.838997) (xy 439.12585 -77.78942) (xy 439.110493 -77.737126) (xy 439.102734 -77.683179)
			(xy 439.102246 -77.655928) (xy 437.591708 -77.655928) (xy 437.591708 -78.719426) (xy 437.592724 -78.729332)
			(xy 437.594435 -78.736487) (xy 437.601279 -78.749503) (xy 437.606186 -78.754986) (xy 438.483502 -79.632302)
			(xy 438.489 -79.637292) (xy 438.502165 -79.644142) (xy 438.50941 -79.645764) (xy 438.519062 -79.64678)
			(xy 441.886848 -79.64678) (xy 441.896915 -79.647211) (xy 441.915509 -79.654936) (xy 441.922916 -79.661766)
			(xy 444.882016 -82.620866) (xy 444.887517 -82.625849) (xy 444.900685 -82.632687) (xy 444.907924 -82.634328)
			(xy 444.917576 -82.635344) (xy 463.09407 -82.635344)
		)
		(stroke
			(width 0)
			(type solid)
		)
		(fill yes)
		(layer "In2.Cu")
		(net "GND")
	)
	(gr_poly
		(pts
			(xy 125.376178 -263.084564) (xy 125.385554 -263.084198) (xy 125.403086 -263.077561) (xy 125.417056 -263.065059)
			(xy 125.421644 -263.056878) (xy 125.468126 -262.965438) (xy 125.466094 -262.93699) (xy 125.457712 -262.925306)
			(xy 125.444031 -262.905658) (xy 125.422312 -262.862993) (xy 125.407527 -262.817459) (xy 125.400039 -262.770173)
			(xy 125.399546 -262.746236) (xy 125.400068 -262.720981) (xy 125.408381 -262.671159) (xy 125.424782 -262.623385)
			(xy 125.448823 -262.578962) (xy 125.479847 -262.539102) (xy 125.517009 -262.504892) (xy 125.559295 -262.477266)
			(xy 125.605551 -262.456976) (xy 125.654516 -262.444576) (xy 125.704854 -262.440405) (xy 125.755192 -262.444576)
			(xy 125.804157 -262.456976) (xy 125.850413 -262.477266) (xy 125.892699 -262.504892) (xy 125.929861 -262.539102)
			(xy 125.960885 -262.578962) (xy 125.984926 -262.623385) (xy 126.001327 -262.671159) (xy 126.00964 -262.720981)
			(xy 126.010162 -262.746236) (xy 126.009671 -262.770171) (xy 126.002156 -262.817449) (xy 125.987363 -262.862977)
			(xy 125.965653 -262.905643) (xy 125.951996 -262.925306) (xy 125.943614 -262.93699) (xy 125.941582 -262.965438)
			(xy 125.988064 -263.056878) (xy 125.992709 -263.065017) (xy 126.006661 -263.077504) (xy 126.024166 -263.084148)
			(xy 126.03353 -263.084564) (xy 126.83871 -263.084564) (xy 126.848554 -263.084041) (xy 126.866736 -263.076476)
			(xy 126.874016 -263.069832) (xy 127.295148 -262.6487) (xy 127.298958 -262.63854) (xy 127.298958 -262.638286)
			(xy 127.308092 -262.615565) (xy 127.332534 -262.573133) (xy 127.363427 -262.53514) (xy 127.399981 -262.502557)
			(xy 127.441262 -262.476218) (xy 127.46355 -262.466074) (xy 127.477774 -262.459978) (xy 127.494284 -262.434578)
			(xy 127.494284 -261.437882) (xy 127.477774 -261.412482) (xy 127.46355 -261.406386) (xy 127.440465 -261.395858)
			(xy 127.397868 -261.3683) (xy 127.360412 -261.33408) (xy 127.32913 -261.294137) (xy 127.304882 -261.249573)
			(xy 127.288336 -261.201612) (xy 127.279946 -261.151577) (xy 127.279945 -261.100842) (xy 127.288331 -261.050806)
			(xy 127.304874 -261.002845) (xy 127.32912 -260.958279) (xy 127.360399 -260.918334) (xy 127.397853 -260.884111)
			(xy 127.440449 -260.856551) (xy 127.46355 -260.846062) (xy 127.477774 -260.839966) (xy 127.494284 -260.814566)
			(xy 127.494284 -256.3622) (xy 127.494103 -256.355554) (xy 127.490765 -256.342689) (xy 127.48768 -256.3368)
			(xy 127.472948 -256.3114) (xy 127.464312 -256.30251) (xy 127.458978 -256.298954) (xy 127.428964 -256.279589)
			(xy 127.373645 -256.234403) (xy 127.324535 -256.182536) (xy 127.282433 -256.124835) (xy 127.248026 -256.06224)
			(xy 127.234442 -256.029206) (xy 127.229362 -256.016252) (xy 127.207518 -255.999234) (xy 127.093726 -255.984248)
			(xy 127.068326 -255.99517) (xy 127.060198 -256.006346) (xy 127.045679 -256.02515) (xy 127.011804 -256.058456)
			(xy 126.973184 -256.086118) (xy 126.930748 -256.107471) (xy 126.885519 -256.122001) (xy 126.838587 -256.129357)
			(xy 126.814834 -256.12979) (xy 126.789576 -256.1293) (xy 126.739748 -256.12099) (xy 126.691968 -256.104592)
			(xy 126.647538 -256.080552) (xy 126.607672 -256.049527) (xy 126.573456 -256.012363) (xy 126.545825 -255.970074)
			(xy 126.525532 -255.923814) (xy 126.51313 -255.874843) (xy 126.508958 -255.8245) (xy 126.51313 -255.774157)
			(xy 126.525532 -255.725186) (xy 126.545825 -255.678926) (xy 126.573456 -255.636637) (xy 126.607672 -255.599473)
			(xy 126.647538 -255.568448) (xy 126.691968 -255.544408) (xy 126.739748 -255.52801) (xy 126.789576 -255.5197)
			(xy 126.814834 -255.519174) (xy 126.838585 -255.519627) (xy 126.885516 -255.526982) (xy 126.930743 -255.541509)
			(xy 126.973178 -255.56286) (xy 127.011798 -255.590518) (xy 127.045674 -255.623819) (xy 127.060198 -255.642618)
			(xy 127.068326 -255.653794) (xy 127.093726 -255.664716) (xy 127.207518 -255.64973) (xy 127.229362 -255.632712)
			(xy 127.234442 -255.619758) (xy 127.242363 -255.600051) (xy 127.260796 -255.561781) (xy 127.271272 -255.543304)
			(xy 127.42037 -255.287018) (xy 127.432855 -255.266092) (xy 127.46096 -255.226282) (xy 127.476504 -255.207516)
			(xy 127.482092 -255.200658) (xy 127.490982 -255.176782) (xy 127.492501 -255.172494) (xy 127.494159 -255.16355)
			(xy 127.494284 -255.159002) (xy 127.494284 -254.742188) (xy 127.494102 -254.735542) (xy 127.490761 -254.722679)
			(xy 127.48768 -254.716788) (xy 127.472948 -254.691388) (xy 127.464312 -254.682498) (xy 127.458978 -254.678942)
			(xy 127.428965 -254.659577) (xy 127.373647 -254.61439) (xy 127.324537 -254.562523) (xy 127.282436 -254.504822)
			(xy 127.248031 -254.442226) (xy 127.234442 -254.409194) (xy 127.229362 -254.39624) (xy 127.207518 -254.379222)
			(xy 127.093726 -254.364236) (xy 127.068326 -254.375158) (xy 127.060198 -254.386334) (xy 127.04568 -254.405139)
			(xy 127.011805 -254.438445) (xy 126.973185 -254.466109) (xy 126.930749 -254.487463) (xy 126.88552 -254.501993)
			(xy 126.838587 -254.509349) (xy 126.814834 -254.509778) (xy 126.789577 -254.509288) (xy 126.739751 -254.500979)
			(xy 126.691972 -254.484581) (xy 126.647545 -254.460542) (xy 126.60768 -254.429519) (xy 126.573466 -254.392356)
			(xy 126.545836 -254.350068) (xy 126.525543 -254.30381) (xy 126.513142 -254.254842) (xy 126.50897 -254.2045)
			(xy 126.513142 -254.154159) (xy 126.525543 -254.10519) (xy 126.545836 -254.058932) (xy 126.573466 -254.016644)
			(xy 126.60768 -253.979481) (xy 126.647545 -253.948458) (xy 126.691972 -253.924419) (xy 126.739751 -253.908021)
			(xy 126.789577 -253.899712) (xy 126.814834 -253.899162) (xy 126.838585 -253.899615) (xy 126.885513 -253.906972)
			(xy 126.930737 -253.921502) (xy 126.973167 -253.942856) (xy 127.011782 -253.97052) (xy 127.04565 -254.003826)
			(xy 127.060198 -254.022606) (xy 127.068326 -254.033782) (xy 127.093726 -254.044704) (xy 127.207518 -254.029718)
			(xy 127.229362 -254.0127) (xy 127.234442 -253.999746) (xy 127.242364 -253.980039) (xy 127.260797 -253.941769)
			(xy 127.271272 -253.923292) (xy 127.42037 -253.667006) (xy 127.432855 -253.646081) (xy 127.460961 -253.606271)
			(xy 127.476504 -253.587504) (xy 127.482092 -253.580646) (xy 127.490982 -253.55677) (xy 127.4925 -253.552482)
			(xy 127.494156 -253.543538) (xy 127.494284 -253.53899) (xy 127.494284 -252.757686) (xy 127.492506 -252.744732)
			(xy 127.490982 -252.738382) (xy 127.487934 -252.732794) (xy 127.475837 -252.709957) (xy 127.458654 -252.661224)
			(xy 127.449916 -252.610294) (xy 127.449326 -252.584458) (xy 127.449889 -252.55862) (xy 127.458633 -252.507688)
			(xy 127.47583 -252.458957) (xy 127.487934 -252.436122) (xy 127.490982 -252.430534) (xy 127.492506 -252.424184)
			(xy 127.494284 -252.41123) (xy 127.494284 -251.675646) (xy 127.493851 -251.665581) (xy 127.486121 -251.646992)
			(xy 127.479298 -251.639578) (xy 127.05969 -251.21997) (xy 127.052819 -251.213639) (xy 127.035782 -251.206013)
			(xy 127.017141 -251.205055) (xy 127.008128 -251.207524) (xy 126.993396 -251.212096) (xy 126.9873 -251.216414)
			(xy 126.968149 -251.229011) (xy 126.926869 -251.24894) (xy 126.883077 -251.262482) (xy 126.837753 -251.269332)
			(xy 126.814834 -251.269754) (xy 126.79084 -251.269286) (xy 126.743441 -251.261784) (xy 126.6978 -251.246961)
			(xy 126.655039 -251.22518) (xy 126.616212 -251.196978) (xy 126.582274 -251.163049) (xy 126.554062 -251.124229)
			(xy 126.53227 -251.081474) (xy 126.517434 -251.035837) (xy 126.50992 -250.98844) (xy 126.509526 -250.964446)
			(xy 126.50997 -250.94075) (xy 126.517284 -250.893925) (xy 126.531745 -250.848793) (xy 126.553004 -250.806436)
			(xy 126.566422 -250.7869) (xy 126.571408 -250.779418) (xy 126.576264 -250.762118) (xy 126.574819 -250.744208)
			(xy 126.567253 -250.72791) (xy 126.561088 -250.721368) (xy 126.4539 -250.61418) (xy 126.446505 -250.607325)
			(xy 126.427906 -250.599578) (xy 126.417832 -250.599194) (xy 125.287278 -250.599194) (xy 125.277437 -250.599721)
			(xy 125.259263 -250.607295) (xy 125.251972 -250.613926) (xy 125.154944 -250.710954) (xy 125.15342 -250.750324)
			(xy 125.166628 -250.765818) (xy 125.183782 -250.786741) (xy 125.211183 -250.83339) (xy 125.229931 -250.884138)
			(xy 125.239442 -250.937395) (xy 125.240034 -250.964446) (xy 125.23956 -250.988436) (xy 125.232048 -251.035823)
			(xy 125.217217 -251.081453) (xy 125.195432 -251.124201) (xy 125.167228 -251.163015) (xy 125.1333 -251.196941)
			(xy 125.094484 -251.225142) (xy 125.051734 -251.246925) (xy 125.006104 -251.261753) (xy 124.958716 -251.269262)
			(xy 124.934726 -251.269754) (xy 124.90988 -251.269238) (xy 124.860851 -251.261145) (xy 124.813774 -251.245232)
			(xy 124.76989 -251.221918) (xy 124.749814 -251.20727) (xy 124.742616 -251.2022) (xy 124.725852 -251.196867)
			(xy 124.717048 -251.196856) (xy 124.686822 -251.198126) (xy 124.677376 -251.198881) (xy 124.660016 -251.206445)
			(xy 124.65304 -251.212858) (xy 124.540772 -251.325126) (xy 124.534986 -251.331306) (xy 124.527505 -251.346483)
			(xy 124.52536 -251.363267) (xy 124.526802 -251.371608) (xy 124.546614 -251.465588) (xy 124.56287 -251.485146)
			(xy 124.575316 -251.489718) (xy 124.599542 -251.49972) (xy 124.644431 -251.526769) (xy 124.684051 -251.561075)
			(xy 124.717241 -251.601634) (xy 124.743031 -251.647258) (xy 124.760664 -251.696611) (xy 124.769624 -251.748248)
			(xy 124.770134 -251.774452) (xy 126.038876 -251.774452) (xy 126.042836 -251.725398) (xy 126.054613 -251.677614)
			(xy 126.073904 -251.632338) (xy 126.100207 -251.590742) (xy 126.132842 -251.553905) (xy 126.170963 -251.52278)
			(xy 126.213584 -251.498173) (xy 126.2596 -251.480721) (xy 126.307819 -251.470877) (xy 126.356994 -251.468896)
			(xy 126.405849 -251.474828) (xy 126.45312 -251.48852) (xy 126.497582 -251.509618) (xy 126.538085 -251.537574)
			(xy 126.573578 -251.571666) (xy 126.603143 -251.61101) (xy 126.626014 -251.654587) (xy 126.641598 -251.701268)
			(xy 126.649493 -251.749845) (xy 126.649988 -251.774452) (xy 126.649493 -251.799059) (xy 126.641598 -251.847636)
			(xy 126.626014 -251.894317) (xy 126.603143 -251.937894) (xy 126.573578 -251.977238) (xy 126.538085 -252.01133)
			(xy 126.497582 -252.039286) (xy 126.45312 -252.060384) (xy 126.405849 -252.074076) (xy 126.356994 -252.080008)
			(xy 126.307819 -252.078027) (xy 126.2596 -252.068183) (xy 126.213584 -252.050731) (xy 126.170963 -252.026124)
			(xy 126.132842 -251.994999) (xy 126.100207 -251.958162) (xy 126.073904 -251.916566) (xy 126.054613 -251.87129)
			(xy 126.042836 -251.823506) (xy 126.038876 -251.774452) (xy 124.770134 -251.774452) (xy 124.769612 -251.799707)
			(xy 124.761299 -251.849529) (xy 124.744898 -251.897303) (xy 124.720857 -251.941726) (xy 124.689833 -251.981586)
			(xy 124.652671 -252.015796) (xy 124.610385 -252.043422) (xy 124.564129 -252.063712) (xy 124.515164 -252.076112)
			(xy 124.464826 -252.080283) (xy 124.414488 -252.076112) (xy 124.365523 -252.063712) (xy 124.319267 -252.043422)
			(xy 124.276981 -252.015796) (xy 124.239819 -251.981586) (xy 124.208795 -251.941726) (xy 124.184754 -251.897303)
			(xy 124.168353 -251.849529) (xy 124.16004 -251.799707) (xy 124.159518 -251.774452) (xy 124.160166 -251.745752)
			(xy 124.170901 -251.689365) (xy 124.180854 -251.662438) (xy 124.185426 -251.6505) (xy 124.182632 -251.625608)
			(xy 124.129546 -251.547376) (xy 124.122065 -251.537401) (xy 124.100087 -251.525689) (xy 124.087636 -251.525024)
			(xy 123.393708 -251.525024) (xy 123.383872 -251.524485) (xy 123.365714 -251.516895) (xy 123.358402 -251.510292)
			(xy 123.122182 -251.274072) (xy 123.100592 -251.266452) (xy 123.088908 -251.267722) (xy 123.054618 -251.269754)
			(xy 123.030625 -251.269285) (xy 122.983228 -251.261781) (xy 122.937589 -251.246956) (xy 122.89483 -251.225174)
			(xy 122.856005 -251.196972) (xy 122.82207 -251.163044) (xy 122.793859 -251.124225) (xy 122.772069 -251.081471)
			(xy 122.757234 -251.035834) (xy 122.74972 -250.988439) (xy 122.74931 -250.964446) (xy 122.751342 -250.930156)
			(xy 122.752612 -250.918472) (xy 122.744992 -250.896882) (xy 122.46229 -250.61418) (xy 122.454895 -250.607327)
			(xy 122.436296 -250.599583) (xy 122.426222 -250.599194) (xy 122.263662 -250.599194) (xy 122.259598 -250.599448)
			(xy 121.520966 -250.599448) (xy 121.5109 -250.599879) (xy 121.492309 -250.607607) (xy 121.484898 -250.614434)
			(xy 121.47931 -250.620022) (xy 121.4755 -250.623578) (xy 121.474738 -250.62434) (xy 121.41962 -250.679458)
			(xy 121.413184 -250.686496) (xy 121.405607 -250.703984) (xy 121.404888 -250.713494) (xy 121.404126 -250.73483)
			(xy 121.40407 -250.739549) (xy 121.405473 -250.74888) (xy 121.40692 -250.753372) (xy 121.414794 -250.77547)
			(xy 121.419366 -250.781566) (xy 121.433653 -250.801499) (xy 121.456349 -250.84497) (xy 121.471798 -250.891512)
			(xy 121.479604 -250.939926) (xy 121.480072 -250.964446) (xy 121.479598 -250.988434) (xy 121.472086 -251.035818)
			(xy 121.457254 -251.081443) (xy 121.435467 -251.124187) (xy 121.407263 -251.162996) (xy 121.373334 -251.196916)
			(xy 121.334517 -251.22511) (xy 121.291768 -251.246885) (xy 121.246138 -251.261705) (xy 121.198752 -251.269204)
			(xy 121.174764 -251.269754) (xy 121.162001 -251.269616) (xy 121.136567 -251.267453) (xy 121.123964 -251.265436)
			(xy 121.123964 -251.26569) (xy 121.09617 -251.260354) (xy 121.043067 -251.240794) (xy 120.994465 -251.211805)
			(xy 120.972834 -251.193554) (xy 120.957594 -251.180092) (xy 120.917716 -251.181362) (xy 120.775476 -251.323602)
			(xy 120.76699 -251.333175) (xy 120.759808 -251.357694) (xy 120.76176 -251.370338) (xy 120.782334 -251.464318)
			(xy 120.799098 -251.483876) (xy 120.81129 -251.488448) (xy 120.835904 -251.498237) (xy 120.881592 -251.525035)
			(xy 120.921973 -251.559311) (xy 120.955839 -251.600037) (xy 120.982176 -251.645992) (xy 121.000193 -251.6958)
			(xy 121.009352 -251.747969) (xy 121.009918 -251.774452) (xy 122.278914 -251.774452) (xy 122.282874 -251.725398)
			(xy 122.294651 -251.677614) (xy 122.313942 -251.632338) (xy 122.340245 -251.590742) (xy 122.37288 -251.553905)
			(xy 122.411001 -251.52278) (xy 122.453622 -251.498173) (xy 122.499638 -251.480721) (xy 122.547857 -251.470877)
			(xy 122.597032 -251.468896) (xy 122.645887 -251.474828) (xy 122.693158 -251.48852) (xy 122.73762 -251.509618)
			(xy 122.778123 -251.537574) (xy 122.813616 -251.571666) (xy 122.843181 -251.61101) (xy 122.866052 -251.654587)
			(xy 122.881636 -251.701268) (xy 122.889531 -251.749845) (xy 122.890026 -251.774452) (xy 122.889531 -251.799059)
			(xy 122.881636 -251.847636) (xy 122.866052 -251.894317) (xy 122.843181 -251.937894) (xy 122.813616 -251.977238)
			(xy 122.778123 -252.01133) (xy 122.73762 -252.039286) (xy 122.693158 -252.060384) (xy 122.645887 -252.074076)
			(xy 122.597032 -252.080008) (xy 122.547857 -252.078027) (xy 122.499638 -252.068183) (xy 122.453622 -252.050731)
			(xy 122.411001 -252.026124) (xy 122.37288 -251.994999) (xy 122.340245 -251.958162) (xy 122.313942 -251.916566)
			(xy 122.294651 -251.87129) (xy 122.282874 -251.823506) (xy 122.278914 -251.774452) (xy 121.009918 -251.774452)
			(xy 121.009396 -251.799707) (xy 121.001083 -251.849529) (xy 120.984682 -251.897303) (xy 120.960641 -251.941726)
			(xy 120.929617 -251.981586) (xy 120.892455 -252.015796) (xy 120.850169 -252.043422) (xy 120.803913 -252.063712)
			(xy 120.754948 -252.076112) (xy 120.70461 -252.080283) (xy 120.654272 -252.076112) (xy 120.605307 -252.063712)
			(xy 120.559051 -252.043422) (xy 120.516765 -252.015796) (xy 120.479603 -251.981586) (xy 120.448579 -251.941726)
			(xy 120.424538 -251.897303) (xy 120.408137 -251.849529) (xy 120.399824 -251.799707) (xy 120.399302 -251.774452)
			(xy 120.39985 -251.748229) (xy 120.40882 -251.696556) (xy 120.426488 -251.647176) (xy 120.438926 -251.624084)
			(xy 120.44553 -251.612146) (xy 120.44553 -251.585222) (xy 120.395492 -251.49937) (xy 120.390739 -251.491877)
			(xy 120.377109 -251.480533) (xy 120.360418 -251.474542) (xy 120.35155 -251.474224) (xy 119.685308 -251.474224)
			(xy 119.675472 -251.473685) (xy 119.657314 -251.466095) (xy 119.650002 -251.459492) (xy 119.442738 -251.252228)
			(xy 119.414036 -251.245878) (xy 119.399812 -251.250958) (xy 119.374406 -251.259704) (xy 119.321519 -251.269162)
			(xy 119.294656 -251.269754) (xy 119.290592 -251.269754) (xy 119.267013 -251.268998) (xy 119.220503 -251.261117)
			(xy 119.175757 -251.246178) (xy 119.133841 -251.224536) (xy 119.095752 -251.196706) (xy 119.062395 -251.16335)
			(xy 119.034565 -251.12526) (xy 119.012922 -251.083344) (xy 118.997983 -251.038599) (xy 118.990102 -250.992089)
			(xy 118.989348 -250.96851) (xy 118.989348 -250.964192) (xy 118.989947 -250.937392) (xy 118.999394 -250.884628)
			(xy 119.008144 -250.85929) (xy 119.013224 -250.845066) (xy 119.006874 -250.816364) (xy 118.80469 -250.61418)
			(xy 118.797295 -250.607327) (xy 118.778696 -250.599583) (xy 118.768622 -250.599194) (xy 117.827298 -250.599194)
			(xy 117.817463 -250.599736) (xy 117.79931 -250.60733) (xy 117.791992 -250.613926) (xy 117.675152 -250.730766)
			(xy 117.667231 -250.739453) (xy 117.659644 -250.761673) (xy 117.662752 -250.784947) (xy 117.668802 -250.795028)
			(xy 117.680935 -250.813934) (xy 117.700117 -250.854554) (xy 117.713137 -250.897548) (xy 117.719715 -250.941985)
			(xy 117.72011 -250.964446) (xy 117.72011 -250.97105) (xy 117.719157 -250.994702) (xy 117.710849 -251.041301)
			(xy 117.695449 -251.086059) (xy 117.673325 -251.127905) (xy 117.645007 -251.165833) (xy 117.611175 -251.198937)
			(xy 117.572638 -251.226422) (xy 117.530321 -251.24763) (xy 117.485238 -251.262052) (xy 117.438469 -251.269343)
			(xy 117.414802 -251.269754) (xy 117.414548 -251.269754) (xy 117.392119 -251.269341) (xy 117.347748 -251.262743)
			(xy 117.30482 -251.249727) (xy 117.264257 -251.230572) (xy 117.245384 -251.218446) (xy 117.235298 -251.212427)
			(xy 117.212035 -251.209372) (xy 117.189813 -251.216898) (xy 117.181122 -251.224796) (xy 117.061742 -251.344176)
			(xy 117.053799 -251.353082) (xy 117.04638 -251.375731) (xy 117.047518 -251.38761) (xy 117.061488 -251.478796)
			(xy 117.075458 -251.498354) (xy 117.086126 -251.503942) (xy 117.106967 -251.515354) (xy 117.145149 -251.543633)
			(xy 117.17849 -251.577485) (xy 117.206185 -251.616093) (xy 117.227565 -251.658524) (xy 117.242115 -251.703756)
			(xy 117.249482 -251.750695) (xy 117.249956 -251.774452) (xy 118.518952 -251.774452) (xy 118.522912 -251.725398)
			(xy 118.534689 -251.677614) (xy 118.55398 -251.632338) (xy 118.580283 -251.590742) (xy 118.612918 -251.553905)
			(xy 118.651039 -251.52278) (xy 118.69366 -251.498173) (xy 118.739676 -251.480721) (xy 118.787895 -251.470877)
			(xy 118.83707 -251.468896) (xy 118.885925 -251.474828) (xy 118.933196 -251.48852) (xy 118.977658 -251.509618)
			(xy 119.018161 -251.537574) (xy 119.053654 -251.571666) (xy 119.083219 -251.61101) (xy 119.10609 -251.654587)
			(xy 119.121674 -251.701268) (xy 119.129569 -251.749845) (xy 119.130064 -251.774452) (xy 119.129569 -251.799059)
			(xy 119.121674 -251.847636) (xy 119.10609 -251.894317) (xy 119.083219 -251.937894) (xy 119.053654 -251.977238)
			(xy 119.018161 -252.01133) (xy 118.977658 -252.039286) (xy 118.933196 -252.060384) (xy 118.885925 -252.074076)
			(xy 118.83707 -252.080008) (xy 118.787895 -252.078027) (xy 118.739676 -252.068183) (xy 118.69366 -252.050731)
			(xy 118.651039 -252.026124) (xy 118.612918 -251.994999) (xy 118.580283 -251.958162) (xy 118.55398 -251.916566)
			(xy 118.534689 -251.87129) (xy 118.522912 -251.823506) (xy 118.518952 -251.774452) (xy 117.249956 -251.774452)
			(xy 117.249434 -251.799707) (xy 117.241121 -251.849529) (xy 117.22472 -251.897303) (xy 117.200679 -251.941726)
			(xy 117.169655 -251.981586) (xy 117.132493 -252.015796) (xy 117.090207 -252.043422) (xy 117.043951 -252.063712)
			(xy 116.994986 -252.076112) (xy 116.944648 -252.080283) (xy 116.89431 -252.076112) (xy 116.845345 -252.063712)
			(xy 116.799089 -252.043422) (xy 116.756803 -252.015796) (xy 116.719641 -251.981586) (xy 116.688617 -251.941726)
			(xy 116.664576 -251.897303) (xy 116.648175 -251.849529) (xy 116.639862 -251.799707) (xy 116.63934 -251.774452)
			(xy 116.639888 -251.748229) (xy 116.648859 -251.696557) (xy 116.666529 -251.647178) (xy 116.678964 -251.624084)
			(xy 116.685568 -251.612146) (xy 116.685568 -251.585222) (xy 116.63553 -251.49937) (xy 116.630779 -251.491873)
			(xy 116.61715 -251.480518) (xy 116.600459 -251.474515) (xy 116.591588 -251.474224) (xy 116.197888 -251.474224)
			(xy 116.188045 -251.473699) (xy 116.169867 -251.46613) (xy 116.162582 -251.459492) (xy 115.888008 -251.184918)
			(xy 115.880664 -251.178104) (xy 115.862202 -251.170366) (xy 115.852194 -251.169932) (xy 115.772692 -251.169424)
			(xy 115.754404 -251.17679) (xy 115.747038 -251.183902) (xy 115.729846 -251.199913) (xy 115.691462 -251.226997)
			(xy 115.649385 -251.24789) (xy 115.604608 -251.262097) (xy 115.558183 -251.269285) (xy 115.534694 -251.269754)
			(xy 115.510702 -251.269283) (xy 115.463308 -251.261776) (xy 115.417672 -251.246949) (xy 115.374917 -251.225166)
			(xy 115.336095 -251.196963) (xy 115.302163 -251.163035) (xy 115.273955 -251.124217) (xy 115.252166 -251.081465)
			(xy 115.237333 -251.035831) (xy 115.22982 -250.988438) (xy 115.229386 -250.964446) (xy 115.229873 -250.939572)
			(xy 115.237936 -250.890482) (xy 115.253856 -250.84335) (xy 115.277212 -250.799425) (xy 115.307383 -250.759871)
			(xy 115.325144 -250.74245) (xy 115.332002 -250.7361) (xy 115.34394 -250.711208) (xy 115.346053 -250.706643)
			(xy 115.34861 -250.696917) (xy 115.34902 -250.691904) (xy 115.35029 -250.67133) (xy 115.350461 -250.660554)
			(xy 115.342832 -250.64042) (xy 115.335558 -250.632468) (xy 115.31727 -250.61418) (xy 115.309874 -250.60733)
			(xy 115.291275 -250.599593) (xy 115.281202 -250.599194) (xy 113.961926 -250.599194) (xy 113.95221 -250.59962)
			(xy 113.93417 -250.606837) (xy 113.920107 -250.620245) (xy 113.915698 -250.628912) (xy 113.87201 -250.724416)
			(xy 113.876328 -250.753626) (xy 113.88598 -250.765056) (xy 113.903299 -250.786016) (xy 113.930983 -250.832804)
			(xy 113.949938 -250.883757) (xy 113.959564 -250.937263) (xy 113.960148 -250.964446) (xy 113.959626 -250.989701)
			(xy 113.951313 -251.039523) (xy 113.934912 -251.087297) (xy 113.910871 -251.13172) (xy 113.879847 -251.17158)
			(xy 113.842685 -251.20579) (xy 113.800399 -251.233416) (xy 113.754143 -251.253706) (xy 113.705178 -251.266106)
			(xy 113.65484 -251.270277) (xy 113.604502 -251.266106) (xy 113.555537 -251.253706) (xy 113.509281 -251.233416)
			(xy 113.466995 -251.20579) (xy 113.429833 -251.17158) (xy 113.398809 -251.13172) (xy 113.374768 -251.087297)
			(xy 113.358367 -251.039523) (xy 113.350054 -250.989701) (xy 113.349532 -250.964446) (xy 113.350131 -250.937266)
			(xy 113.359766 -250.883765) (xy 113.378722 -250.832817) (xy 113.406401 -250.78603) (xy 113.4237 -250.765056)
			(xy 113.433352 -250.753626) (xy 113.43767 -250.724416) (xy 113.393982 -250.628912) (xy 113.389557 -250.620258)
			(xy 113.375498 -250.60686) (xy 113.357465 -250.599653) (xy 113.347754 -250.599194) (xy 111.918496 -250.599194)
			(xy 111.910622 -250.601988) (xy 111.883849 -250.610427) (xy 111.828453 -250.619492) (xy 111.800386 -250.620022)
			(xy 111.772318 -250.619506) (xy 111.71692 -250.610442) (xy 111.69015 -250.601988) (xy 111.682276 -250.599194)
			(xy 109.438948 -250.599194) (xy 109.429109 -250.599727) (xy 109.410943 -250.607308) (xy 109.403642 -250.613926)
			(xy 109.233716 -250.783852) (xy 109.228382 -250.815856) (xy 109.235494 -250.830588) (xy 109.245262 -250.851536)
			(xy 109.259062 -250.895647) (xy 109.266039 -250.941336) (xy 109.266482 -250.964446) (xy 109.266008 -250.988434)
			(xy 109.258496 -251.035819) (xy 109.243664 -251.081445) (xy 109.221878 -251.124189) (xy 109.193673 -251.163)
			(xy 109.159745 -251.19692) (xy 109.120928 -251.225115) (xy 109.078178 -251.246892) (xy 109.032549 -251.261713)
			(xy 108.985162 -251.269214) (xy 108.961174 -251.269754) (xy 108.938066 -251.269308) (xy 108.892381 -251.26231)
			(xy 108.848268 -251.248522) (xy 108.827316 -251.238766) (xy 108.812584 -251.231654) (xy 108.78058 -251.236988)
			(xy 108.661708 -251.35586) (xy 108.654469 -251.362571) (xy 108.636264 -251.370165) (xy 108.626402 -251.370592)
			(xy 107.819698 -251.370592) (xy 107.809426 -251.371062) (xy 107.790525 -251.379112) (xy 107.776289 -251.393923)
			(xy 107.773411 -251.400564) (xy 111.932723 -251.400564) (xy 111.936753 -251.348066) (xy 111.94875 -251.296798)
			(xy 111.968433 -251.247963) (xy 111.995339 -251.202704) (xy 112.028839 -251.162083) (xy 112.068147 -251.127052)
			(xy 112.112342 -251.098432) (xy 112.160387 -251.076893) (xy 112.211158 -251.062941) (xy 112.263463 -251.056903)
			(xy 112.316077 -251.05892) (xy 112.367767 -251.068944) (xy 112.41732 -251.086742) (xy 112.463576 -251.111895)
			(xy 112.50545 -251.143814) (xy 112.541962 -251.181752) (xy 112.572254 -251.224818) (xy 112.595617 -251.272003)
			(xy 112.611503 -251.322202) (xy 112.61954 -251.374238) (xy 112.620044 -251.400564) (xy 112.61954 -251.42689)
			(xy 112.611503 -251.478926) (xy 112.595617 -251.529125) (xy 112.572254 -251.57631) (xy 112.541962 -251.619376)
			(xy 112.50545 -251.657314) (xy 112.463576 -251.689233) (xy 112.41732 -251.714386) (xy 112.367767 -251.732184)
			(xy 112.316077 -251.742208) (xy 112.263463 -251.744225) (xy 112.211158 -251.738187) (xy 112.160387 -251.724235)
			(xy 112.112342 -251.702696) (xy 112.068147 -251.674076) (xy 112.028839 -251.639045) (xy 111.995339 -251.598424)
			(xy 111.968433 -251.553165) (xy 111.94875 -251.50433) (xy 111.936753 -251.453062) (xy 111.932723 -251.400564)
			(xy 107.773411 -251.400564) (xy 107.7722 -251.403358) (xy 107.7341 -251.504704) (xy 107.741466 -251.535184)
			(xy 107.753404 -251.545852) (xy 107.772381 -251.563406) (xy 107.804732 -251.60372) (xy 107.829845 -251.648899)
			(xy 107.847003 -251.697658) (xy 107.855719 -251.748607) (xy 107.856274 -251.774452) (xy 109.12527 -251.774452)
			(xy 109.12923 -251.725398) (xy 109.141007 -251.677614) (xy 109.160298 -251.632338) (xy 109.186601 -251.590742)
			(xy 109.219236 -251.553905) (xy 109.257357 -251.52278) (xy 109.299978 -251.498173) (xy 109.345994 -251.480721)
			(xy 109.394213 -251.470877) (xy 109.443388 -251.468896) (xy 109.492243 -251.474828) (xy 109.539514 -251.48852)
			(xy 109.583976 -251.509618) (xy 109.624479 -251.537574) (xy 109.659972 -251.571666) (xy 109.689537 -251.61101)
			(xy 109.712408 -251.654587) (xy 109.727992 -251.701268) (xy 109.735887 -251.749845) (xy 109.736382 -251.774452)
			(xy 112.878882 -251.774452) (xy 112.882842 -251.725398) (xy 112.894619 -251.677614) (xy 112.91391 -251.632338)
			(xy 112.940213 -251.590742) (xy 112.972848 -251.553905) (xy 113.010969 -251.52278) (xy 113.05359 -251.498173)
			(xy 113.099606 -251.480721) (xy 113.147825 -251.470877) (xy 113.197 -251.468896) (xy 113.245855 -251.474828)
			(xy 113.293126 -251.48852) (xy 113.337588 -251.509618) (xy 113.378091 -251.537574) (xy 113.413584 -251.571666)
			(xy 113.443149 -251.61101) (xy 113.46602 -251.654587) (xy 113.481604 -251.701268) (xy 113.489499 -251.749845)
			(xy 113.489994 -251.774452) (xy 114.75899 -251.774452) (xy 114.76295 -251.725398) (xy 114.774727 -251.677614)
			(xy 114.794018 -251.632338) (xy 114.820321 -251.590742) (xy 114.852956 -251.553905) (xy 114.891077 -251.52278)
			(xy 114.933698 -251.498173) (xy 114.979714 -251.480721) (xy 115.027933 -251.470877) (xy 115.077108 -251.468896)
			(xy 115.125963 -251.474828) (xy 115.173234 -251.48852) (xy 115.217696 -251.509618) (xy 115.258199 -251.537574)
			(xy 115.293692 -251.571666) (xy 115.323257 -251.61101) (xy 115.346128 -251.654587) (xy 115.361712 -251.701268)
			(xy 115.369607 -251.749845) (xy 115.370102 -251.774452) (xy 115.369607 -251.799059) (xy 115.361712 -251.847636)
			(xy 115.346128 -251.894317) (xy 115.323257 -251.937894) (xy 115.293692 -251.977238) (xy 115.258199 -252.01133)
			(xy 115.217696 -252.039286) (xy 115.173234 -252.060384) (xy 115.125963 -252.074076) (xy 115.077108 -252.080008)
			(xy 115.027933 -252.078027) (xy 114.979714 -252.068183) (xy 114.933698 -252.050731) (xy 114.891077 -252.026124)
			(xy 114.852956 -251.994999) (xy 114.820321 -251.958162) (xy 114.794018 -251.916566) (xy 114.774727 -251.87129)
			(xy 114.76295 -251.823506) (xy 114.75899 -251.774452) (xy 113.489994 -251.774452) (xy 113.489499 -251.799059)
			(xy 113.481604 -251.847636) (xy 113.46602 -251.894317) (xy 113.443149 -251.937894) (xy 113.413584 -251.977238)
			(xy 113.378091 -252.01133) (xy 113.337588 -252.039286) (xy 113.293126 -252.060384) (xy 113.245855 -252.074076)
			(xy 113.197 -252.080008) (xy 113.147825 -252.078027) (xy 113.099606 -252.068183) (xy 113.05359 -252.050731)
			(xy 113.010969 -252.026124) (xy 112.972848 -251.994999) (xy 112.940213 -251.958162) (xy 112.91391 -251.916566)
			(xy 112.894619 -251.87129) (xy 112.882842 -251.823506) (xy 112.878882 -251.774452) (xy 109.736382 -251.774452)
			(xy 109.735887 -251.799059) (xy 109.727992 -251.847636) (xy 109.712408 -251.894317) (xy 109.689537 -251.937894)
			(xy 109.659972 -251.977238) (xy 109.624479 -252.01133) (xy 109.583976 -252.039286) (xy 109.539514 -252.060384)
			(xy 109.492243 -252.074076) (xy 109.443388 -252.080008) (xy 109.394213 -252.078027) (xy 109.345994 -252.068183)
			(xy 109.299978 -252.050731) (xy 109.257357 -252.026124) (xy 109.219236 -251.994999) (xy 109.186601 -251.958162)
			(xy 109.160298 -251.916566) (xy 109.141007 -251.87129) (xy 109.12923 -251.823506) (xy 109.12527 -251.774452)
			(xy 107.856274 -251.774452) (xy 107.855752 -251.799707) (xy 107.847439 -251.849529) (xy 107.831038 -251.897303)
			(xy 107.806997 -251.941726) (xy 107.775973 -251.981586) (xy 107.738811 -252.015796) (xy 107.696525 -252.043422)
			(xy 107.650269 -252.063712) (xy 107.601304 -252.076112) (xy 107.550966 -252.080283) (xy 107.500628 -252.076112)
			(xy 107.451663 -252.063712) (xy 107.405407 -252.043422) (xy 107.363121 -252.015796) (xy 107.325959 -251.981586)
			(xy 107.294935 -251.941726) (xy 107.270894 -251.897303) (xy 107.254493 -251.849529) (xy 107.24618 -251.799707)
			(xy 107.245658 -251.774452) (xy 107.246196 -251.748604) (xy 107.254892 -251.697646) (xy 107.272045 -251.64888)
			(xy 107.297165 -251.603698) (xy 107.329535 -251.563392) (xy 107.348528 -251.545852) (xy 107.360466 -251.535184)
			(xy 107.367832 -251.504704) (xy 107.329732 -251.403358) (xy 107.325647 -251.393918) (xy 107.311412 -251.379097)
			(xy 107.292509 -251.371035) (xy 107.282234 -251.370592) (xy 105.939844 -251.370592) (xy 105.929567 -251.371054)
			(xy 105.910651 -251.379094) (xy 105.896401 -251.393905) (xy 105.892346 -251.403358) (xy 105.854246 -251.504704)
			(xy 105.861612 -251.535184) (xy 105.87355 -251.545852) (xy 105.892529 -251.563404) (xy 105.924886 -251.603716)
			(xy 105.950003 -251.648896) (xy 105.967165 -251.697655) (xy 105.975882 -251.748606) (xy 105.97642 -251.774452)
			(xy 105.975898 -251.799707) (xy 105.967585 -251.849529) (xy 105.951184 -251.897303) (xy 105.927143 -251.941726)
			(xy 105.896119 -251.981586) (xy 105.858957 -252.015796) (xy 105.816671 -252.043422) (xy 105.770415 -252.063712)
			(xy 105.72145 -252.076112) (xy 105.671112 -252.080283) (xy 105.620774 -252.076112) (xy 105.571809 -252.063712)
			(xy 105.525553 -252.043422) (xy 105.483267 -252.015796) (xy 105.446105 -251.981586) (xy 105.415081 -251.941726)
			(xy 105.39104 -251.897303) (xy 105.374639 -251.849529) (xy 105.366326 -251.799707) (xy 105.365804 -251.774452)
			(xy 105.366342 -251.748605) (xy 105.375039 -251.697647) (xy 105.392194 -251.648883) (xy 105.417317 -251.603704)
			(xy 105.44969 -251.563401) (xy 105.468674 -251.545852) (xy 105.480612 -251.535184) (xy 105.487978 -251.504704)
			(xy 105.449878 -251.403358) (xy 105.44579 -251.393924) (xy 105.431552 -251.379118) (xy 105.412651 -251.371075)
			(xy 105.40238 -251.370592) (xy 104.059736 -251.370592) (xy 104.04946 -251.371055) (xy 104.030547 -251.379097)
			(xy 104.016299 -251.393908) (xy 104.012238 -251.403358) (xy 103.974138 -251.504704) (xy 103.981504 -251.535184)
			(xy 103.993442 -251.545852) (xy 104.012417 -251.563407) (xy 104.044764 -251.603722) (xy 104.069874 -251.648902)
			(xy 104.08703 -251.69766) (xy 104.095744 -251.748608) (xy 104.096312 -251.774452) (xy 104.09579 -251.799707)
			(xy 104.087477 -251.849529) (xy 104.071076 -251.897303) (xy 104.047035 -251.941726) (xy 104.016011 -251.981586)
			(xy 103.978849 -252.015796) (xy 103.936563 -252.043422) (xy 103.890307 -252.063712) (xy 103.841342 -252.076112)
			(xy 103.791004 -252.080283) (xy 103.740666 -252.076112) (xy 103.691701 -252.063712) (xy 103.645445 -252.043422)
			(xy 103.603159 -252.015796) (xy 103.565997 -251.981586) (xy 103.534973 -251.941726) (xy 103.510932 -251.897303)
			(xy 103.494531 -251.849529) (xy 103.486218 -251.799707) (xy 103.485696 -251.774452) (xy 103.486234 -251.748605)
			(xy 103.494931 -251.697647) (xy 103.512086 -251.648882) (xy 103.537208 -251.603703) (xy 103.56958 -251.5634)
			(xy 103.588566 -251.545852) (xy 103.600504 -251.535184) (xy 103.60787 -251.504704) (xy 103.56977 -251.403358)
			(xy 103.565682 -251.393925) (xy 103.551444 -251.379121) (xy 103.532542 -251.371081) (xy 103.522272 -251.370592)
			(xy 102.798626 -251.370592) (xy 102.788789 -251.371128) (xy 102.770628 -251.378715) (xy 102.76332 -251.385324)
			(xy 102.664006 -251.484892) (xy 102.657288 -251.492128) (xy 102.649684 -251.510333) (xy 102.649274 -251.520198)
			(xy 102.649274 -251.807472) (xy 102.649778 -251.817523) (xy 102.657498 -251.836086) (xy 102.66426 -251.84354)
			(xy 103.237284 -252.416564) (xy 111.913673 -252.416564) (xy 111.917703 -252.364066) (xy 111.9297 -252.312798)
			(xy 111.949383 -252.263963) (xy 111.976289 -252.218704) (xy 112.009789 -252.178083) (xy 112.049097 -252.143052)
			(xy 112.093292 -252.114432) (xy 112.141337 -252.092893) (xy 112.192108 -252.078941) (xy 112.244413 -252.072903)
			(xy 112.297027 -252.07492) (xy 112.348717 -252.084944) (xy 112.39827 -252.102742) (xy 112.444526 -252.127895)
			(xy 112.4864 -252.159814) (xy 112.522912 -252.197752) (xy 112.553204 -252.240818) (xy 112.576567 -252.288003)
			(xy 112.592453 -252.338202) (xy 112.60049 -252.390238) (xy 112.600994 -252.416564) (xy 112.60049 -252.44289)
			(xy 112.592453 -252.494926) (xy 112.576567 -252.545125) (xy 112.557092 -252.584458) (xy 120.86896 -252.584458)
			(xy 120.87292 -252.535404) (xy 120.884697 -252.48762) (xy 120.903988 -252.442344) (xy 120.930291 -252.400748)
			(xy 120.962926 -252.363911) (xy 121.001047 -252.332786) (xy 121.043668 -252.308179) (xy 121.089684 -252.290727)
			(xy 121.137903 -252.280883) (xy 121.187078 -252.278902) (xy 121.235933 -252.284834) (xy 121.283204 -252.298526)
			(xy 121.327666 -252.319624) (xy 121.368169 -252.34758) (xy 121.403662 -252.381672) (xy 121.433227 -252.421016)
			(xy 121.456098 -252.464593) (xy 121.471682 -252.511274) (xy 121.479577 -252.559851) (xy 121.480072 -252.584458)
			(xy 122.748814 -252.584458) (xy 122.752774 -252.535404) (xy 122.764551 -252.48762) (xy 122.783842 -252.442344)
			(xy 122.810145 -252.400748) (xy 122.84278 -252.363911) (xy 122.880901 -252.332786) (xy 122.923522 -252.308179)
			(xy 122.969538 -252.290727) (xy 123.017757 -252.280883) (xy 123.066932 -252.278902) (xy 123.115787 -252.284834)
			(xy 123.163058 -252.298526) (xy 123.20752 -252.319624) (xy 123.248023 -252.34758) (xy 123.283516 -252.381672)
			(xy 123.313081 -252.421016) (xy 123.335952 -252.464593) (xy 123.351536 -252.511274) (xy 123.359431 -252.559851)
			(xy 123.359926 -252.584458) (xy 124.628922 -252.584458) (xy 124.632882 -252.535404) (xy 124.644659 -252.48762)
			(xy 124.66395 -252.442344) (xy 124.690253 -252.400748) (xy 124.722888 -252.363911) (xy 124.761009 -252.332786)
			(xy 124.80363 -252.308179) (xy 124.849646 -252.290727) (xy 124.897865 -252.280883) (xy 124.94704 -252.278902)
			(xy 124.995895 -252.284834) (xy 125.043166 -252.298526) (xy 125.087628 -252.319624) (xy 125.128131 -252.34758)
			(xy 125.163624 -252.381672) (xy 125.193189 -252.421016) (xy 125.21606 -252.464593) (xy 125.231644 -252.511274)
			(xy 125.239539 -252.559851) (xy 125.240034 -252.584458) (xy 126.50903 -252.584458) (xy 126.51299 -252.535404)
			(xy 126.524767 -252.48762) (xy 126.544058 -252.442344) (xy 126.570361 -252.400748) (xy 126.602996 -252.363911)
			(xy 126.641117 -252.332786) (xy 126.683738 -252.308179) (xy 126.729754 -252.290727) (xy 126.777973 -252.280883)
			(xy 126.827148 -252.278902) (xy 126.876003 -252.284834) (xy 126.923274 -252.298526) (xy 126.967736 -252.319624)
			(xy 127.008239 -252.34758) (xy 127.043732 -252.381672) (xy 127.073297 -252.421016) (xy 127.096168 -252.464593)
			(xy 127.111752 -252.511274) (xy 127.119647 -252.559851) (xy 127.120142 -252.584458) (xy 127.119647 -252.609065)
			(xy 127.111752 -252.657642) (xy 127.096168 -252.704323) (xy 127.073297 -252.7479) (xy 127.043732 -252.787244)
			(xy 127.008239 -252.821336) (xy 126.967736 -252.849292) (xy 126.923274 -252.87039) (xy 126.876003 -252.884082)
			(xy 126.827148 -252.890014) (xy 126.777973 -252.888033) (xy 126.729754 -252.878189) (xy 126.683738 -252.860737)
			(xy 126.641117 -252.83613) (xy 126.602996 -252.805005) (xy 126.570361 -252.768168) (xy 126.544058 -252.726572)
			(xy 126.524767 -252.681296) (xy 126.51299 -252.633512) (xy 126.50903 -252.584458) (xy 125.240034 -252.584458)
			(xy 125.239539 -252.609065) (xy 125.231644 -252.657642) (xy 125.21606 -252.704323) (xy 125.193189 -252.7479)
			(xy 125.163624 -252.787244) (xy 125.128131 -252.821336) (xy 125.087628 -252.849292) (xy 125.043166 -252.87039)
			(xy 124.995895 -252.884082) (xy 124.94704 -252.890014) (xy 124.897865 -252.888033) (xy 124.849646 -252.878189)
			(xy 124.80363 -252.860737) (xy 124.761009 -252.83613) (xy 124.722888 -252.805005) (xy 124.690253 -252.768168)
			(xy 124.66395 -252.726572) (xy 124.644659 -252.681296) (xy 124.632882 -252.633512) (xy 124.628922 -252.584458)
			(xy 123.359926 -252.584458) (xy 123.359431 -252.609065) (xy 123.351536 -252.657642) (xy 123.335952 -252.704323)
			(xy 123.313081 -252.7479) (xy 123.283516 -252.787244) (xy 123.248023 -252.821336) (xy 123.20752 -252.849292)
			(xy 123.163058 -252.87039) (xy 123.115787 -252.884082) (xy 123.066932 -252.890014) (xy 123.017757 -252.888033)
			(xy 122.969538 -252.878189) (xy 122.923522 -252.860737) (xy 122.880901 -252.83613) (xy 122.84278 -252.805005)
			(xy 122.810145 -252.768168) (xy 122.783842 -252.726572) (xy 122.764551 -252.681296) (xy 122.752774 -252.633512)
			(xy 122.748814 -252.584458) (xy 121.480072 -252.584458) (xy 121.479577 -252.609065) (xy 121.471682 -252.657642)
			(xy 121.456098 -252.704323) (xy 121.433227 -252.7479) (xy 121.403662 -252.787244) (xy 121.368169 -252.821336)
			(xy 121.327666 -252.849292) (xy 121.283204 -252.87039) (xy 121.235933 -252.884082) (xy 121.187078 -252.890014)
			(xy 121.137903 -252.888033) (xy 121.089684 -252.878189) (xy 121.043668 -252.860737) (xy 121.001047 -252.83613)
			(xy 120.962926 -252.805005) (xy 120.930291 -252.768168) (xy 120.903988 -252.726572) (xy 120.884697 -252.681296)
			(xy 120.87292 -252.633512) (xy 120.86896 -252.584458) (xy 112.557092 -252.584458) (xy 112.553204 -252.59231)
			(xy 112.522912 -252.635376) (xy 112.4864 -252.673314) (xy 112.444526 -252.705233) (xy 112.39827 -252.730386)
			(xy 112.348717 -252.748184) (xy 112.297027 -252.758208) (xy 112.244413 -252.760225) (xy 112.192108 -252.754187)
			(xy 112.141337 -252.740235) (xy 112.093292 -252.718696) (xy 112.049097 -252.690076) (xy 112.009789 -252.655045)
			(xy 111.976289 -252.614424) (xy 111.949383 -252.569165) (xy 111.9297 -252.52033) (xy 111.917703 -252.469062)
			(xy 111.913673 -252.416564) (xy 103.237284 -252.416564) (xy 103.960168 -253.139448) (xy 103.966264 -253.144528)
			(xy 103.967534 -253.145544) (xy 103.987008 -253.160268) (xy 104.021463 -253.19485) (xy 104.036114 -253.214378)
			(xy 104.041448 -253.220728) (xy 104.213152 -253.392432) (xy 105.362006 -253.392432) (xy 105.365966 -253.343378)
			(xy 105.377743 -253.295594) (xy 105.397034 -253.250318) (xy 105.423337 -253.208722) (xy 105.455972 -253.171885)
			(xy 105.494093 -253.14076) (xy 105.536714 -253.116153) (xy 105.58273 -253.098701) (xy 105.630949 -253.088857)
			(xy 105.680124 -253.086876) (xy 105.728979 -253.092808) (xy 105.77625 -253.1065) (xy 105.820712 -253.127598)
			(xy 105.861215 -253.155554) (xy 105.896708 -253.189646) (xy 105.926273 -253.22899) (xy 105.949144 -253.272567)
			(xy 105.964728 -253.319248) (xy 105.972623 -253.367825) (xy 105.973118 -253.392432) (xy 107.242114 -253.392432)
			(xy 107.246074 -253.343378) (xy 107.257851 -253.295594) (xy 107.277142 -253.250318) (xy 107.303445 -253.208722)
			(xy 107.33608 -253.171885) (xy 107.374201 -253.14076) (xy 107.416822 -253.116153) (xy 107.462838 -253.098701)
			(xy 107.511057 -253.088857) (xy 107.560232 -253.086876) (xy 107.609087 -253.092808) (xy 107.656358 -253.1065)
			(xy 107.70082 -253.127598) (xy 107.741323 -253.155554) (xy 107.776816 -253.189646) (xy 107.806381 -253.22899)
			(xy 107.829252 -253.272567) (xy 107.844836 -253.319248) (xy 107.852731 -253.367825) (xy 107.853226 -253.392432)
			(xy 109.122222 -253.392432) (xy 109.126182 -253.343378) (xy 109.137959 -253.295594) (xy 109.15725 -253.250318)
			(xy 109.183553 -253.208722) (xy 109.216188 -253.171885) (xy 109.254309 -253.14076) (xy 109.29693 -253.116153)
			(xy 109.342946 -253.098701) (xy 109.391165 -253.088857) (xy 109.44034 -253.086876) (xy 109.489195 -253.092808)
			(xy 109.536466 -253.1065) (xy 109.580928 -253.127598) (xy 109.621431 -253.155554) (xy 109.656924 -253.189646)
			(xy 109.686489 -253.22899) (xy 109.70936 -253.272567) (xy 109.724944 -253.319248) (xy 109.732839 -253.367825)
			(xy 109.733334 -253.392432) (xy 109.732839 -253.417039) (xy 109.730316 -253.432564) (xy 111.913673 -253.432564)
			(xy 111.917703 -253.380066) (xy 111.9297 -253.328798) (xy 111.949383 -253.279963) (xy 111.976289 -253.234704)
			(xy 112.009789 -253.194083) (xy 112.049097 -253.159052) (xy 112.093292 -253.130432) (xy 112.141337 -253.108893)
			(xy 112.192108 -253.094941) (xy 112.244413 -253.088903) (xy 112.297027 -253.09092) (xy 112.348717 -253.100944)
			(xy 112.39827 -253.118742) (xy 112.444526 -253.143895) (xy 112.4864 -253.175814) (xy 112.522912 -253.213752)
			(xy 112.553204 -253.256818) (xy 112.576567 -253.304003) (xy 112.592453 -253.354202) (xy 112.598358 -253.392432)
			(xy 112.882184 -253.392432) (xy 112.886144 -253.343378) (xy 112.897921 -253.295594) (xy 112.917212 -253.250318)
			(xy 112.943515 -253.208722) (xy 112.97615 -253.171885) (xy 113.014271 -253.14076) (xy 113.056892 -253.116153)
			(xy 113.102908 -253.098701) (xy 113.151127 -253.088857) (xy 113.200302 -253.086876) (xy 113.249157 -253.092808)
			(xy 113.296428 -253.1065) (xy 113.34089 -253.127598) (xy 113.381393 -253.155554) (xy 113.416886 -253.189646)
			(xy 113.446451 -253.22899) (xy 113.469322 -253.272567) (xy 113.484906 -253.319248) (xy 113.492801 -253.367825)
			(xy 113.493296 -253.392432) (xy 114.762038 -253.392432) (xy 114.765998 -253.343378) (xy 114.777775 -253.295594)
			(xy 114.797066 -253.250318) (xy 114.823369 -253.208722) (xy 114.856004 -253.171885) (xy 114.894125 -253.14076)
			(xy 114.936746 -253.116153) (xy 114.982762 -253.098701) (xy 115.030981 -253.088857) (xy 115.080156 -253.086876)
			(xy 115.129011 -253.092808) (xy 115.176282 -253.1065) (xy 115.220744 -253.127598) (xy 115.261247 -253.155554)
			(xy 115.29674 -253.189646) (xy 115.326305 -253.22899) (xy 115.349176 -253.272567) (xy 115.36476 -253.319248)
			(xy 115.372655 -253.367825) (xy 115.37315 -253.392432) (xy 116.642146 -253.392432) (xy 116.646106 -253.343378)
			(xy 116.657883 -253.295594) (xy 116.677174 -253.250318) (xy 116.703477 -253.208722) (xy 116.736112 -253.171885)
			(xy 116.774233 -253.14076) (xy 116.816854 -253.116153) (xy 116.86287 -253.098701) (xy 116.911089 -253.088857)
			(xy 116.960264 -253.086876) (xy 117.009119 -253.092808) (xy 117.05639 -253.1065) (xy 117.100852 -253.127598)
			(xy 117.141355 -253.155554) (xy 117.176848 -253.189646) (xy 117.206413 -253.22899) (xy 117.229284 -253.272567)
			(xy 117.244868 -253.319248) (xy 117.252763 -253.367825) (xy 117.253258 -253.392432) (xy 118.522 -253.392432)
			(xy 118.52596 -253.343378) (xy 118.537737 -253.295594) (xy 118.557028 -253.250318) (xy 118.583331 -253.208722)
			(xy 118.615966 -253.171885) (xy 118.654087 -253.14076) (xy 118.696708 -253.116153) (xy 118.742724 -253.098701)
			(xy 118.790943 -253.088857) (xy 118.840118 -253.086876) (xy 118.888973 -253.092808) (xy 118.936244 -253.1065)
			(xy 118.980706 -253.127598) (xy 119.021209 -253.155554) (xy 119.056702 -253.189646) (xy 119.086267 -253.22899)
			(xy 119.109138 -253.272567) (xy 119.124722 -253.319248) (xy 119.132617 -253.367825) (xy 119.133112 -253.392432)
			(xy 119.133071 -253.394464) (xy 122.278914 -253.394464) (xy 122.282874 -253.34541) (xy 122.294651 -253.297626)
			(xy 122.313942 -253.25235) (xy 122.340245 -253.210754) (xy 122.37288 -253.173917) (xy 122.411001 -253.142792)
			(xy 122.453622 -253.118185) (xy 122.499638 -253.100733) (xy 122.547857 -253.090889) (xy 122.597032 -253.088908)
			(xy 122.645887 -253.09484) (xy 122.693158 -253.108532) (xy 122.73762 -253.12963) (xy 122.778123 -253.157586)
			(xy 122.813616 -253.191678) (xy 122.843181 -253.231022) (xy 122.866052 -253.274599) (xy 122.881636 -253.32128)
			(xy 122.889531 -253.369857) (xy 122.890026 -253.394464) (xy 124.159022 -253.394464) (xy 124.162982 -253.34541)
			(xy 124.174759 -253.297626) (xy 124.19405 -253.25235) (xy 124.220353 -253.210754) (xy 124.252988 -253.173917)
			(xy 124.291109 -253.142792) (xy 124.33373 -253.118185) (xy 124.379746 -253.100733) (xy 124.427965 -253.090889)
			(xy 124.47714 -253.088908) (xy 124.525995 -253.09484) (xy 124.573266 -253.108532) (xy 124.617728 -253.12963)
			(xy 124.658231 -253.157586) (xy 124.693724 -253.191678) (xy 124.723289 -253.231022) (xy 124.74616 -253.274599)
			(xy 124.761744 -253.32128) (xy 124.769639 -253.369857) (xy 124.770134 -253.394464) (xy 126.038876 -253.394464)
			(xy 126.042836 -253.34541) (xy 126.054613 -253.297626) (xy 126.073904 -253.25235) (xy 126.100207 -253.210754)
			(xy 126.132842 -253.173917) (xy 126.170963 -253.142792) (xy 126.213584 -253.118185) (xy 126.2596 -253.100733)
			(xy 126.307819 -253.090889) (xy 126.356994 -253.088908) (xy 126.405849 -253.09484) (xy 126.45312 -253.108532)
			(xy 126.497582 -253.12963) (xy 126.538085 -253.157586) (xy 126.573578 -253.191678) (xy 126.603143 -253.231022)
			(xy 126.626014 -253.274599) (xy 126.641598 -253.32128) (xy 126.649493 -253.369857) (xy 126.649988 -253.394464)
			(xy 126.649493 -253.419071) (xy 126.641598 -253.467648) (xy 126.626014 -253.514329) (xy 126.603143 -253.557906)
			(xy 126.573578 -253.59725) (xy 126.538085 -253.631342) (xy 126.497582 -253.659298) (xy 126.45312 -253.680396)
			(xy 126.405849 -253.694088) (xy 126.356994 -253.70002) (xy 126.307819 -253.698039) (xy 126.2596 -253.688195)
			(xy 126.213584 -253.670743) (xy 126.170963 -253.646136) (xy 126.132842 -253.615011) (xy 126.100207 -253.578174)
			(xy 126.073904 -253.536578) (xy 126.054613 -253.491302) (xy 126.042836 -253.443518) (xy 126.038876 -253.394464)
			(xy 124.770134 -253.394464) (xy 124.769639 -253.419071) (xy 124.761744 -253.467648) (xy 124.74616 -253.514329)
			(xy 124.723289 -253.557906) (xy 124.693724 -253.59725) (xy 124.658231 -253.631342) (xy 124.617728 -253.659298)
			(xy 124.573266 -253.680396) (xy 124.525995 -253.694088) (xy 124.47714 -253.70002) (xy 124.427965 -253.698039)
			(xy 124.379746 -253.688195) (xy 124.33373 -253.670743) (xy 124.291109 -253.646136) (xy 124.252988 -253.615011)
			(xy 124.220353 -253.578174) (xy 124.19405 -253.536578) (xy 124.174759 -253.491302) (xy 124.162982 -253.443518)
			(xy 124.159022 -253.394464) (xy 122.890026 -253.394464) (xy 122.889531 -253.419071) (xy 122.881636 -253.467648)
			(xy 122.866052 -253.514329) (xy 122.843181 -253.557906) (xy 122.813616 -253.59725) (xy 122.778123 -253.631342)
			(xy 122.73762 -253.659298) (xy 122.693158 -253.680396) (xy 122.645887 -253.694088) (xy 122.597032 -253.70002)
			(xy 122.547857 -253.698039) (xy 122.499638 -253.688195) (xy 122.453622 -253.670743) (xy 122.411001 -253.646136)
			(xy 122.37288 -253.615011) (xy 122.340245 -253.578174) (xy 122.313942 -253.536578) (xy 122.294651 -253.491302)
			(xy 122.282874 -253.443518) (xy 122.278914 -253.394464) (xy 119.133071 -253.394464) (xy 119.132617 -253.417039)
			(xy 119.124722 -253.465616) (xy 119.109138 -253.512297) (xy 119.086267 -253.555874) (xy 119.056702 -253.595218)
			(xy 119.021209 -253.62931) (xy 118.980706 -253.657266) (xy 118.936244 -253.678364) (xy 118.888973 -253.692056)
			(xy 118.840118 -253.697988) (xy 118.790943 -253.696007) (xy 118.742724 -253.686163) (xy 118.696708 -253.668711)
			(xy 118.654087 -253.644104) (xy 118.615966 -253.612979) (xy 118.583331 -253.576142) (xy 118.557028 -253.534546)
			(xy 118.537737 -253.48927) (xy 118.52596 -253.441486) (xy 118.522 -253.392432) (xy 117.253258 -253.392432)
			(xy 117.252763 -253.417039) (xy 117.244868 -253.465616) (xy 117.229284 -253.512297) (xy 117.206413 -253.555874)
			(xy 117.176848 -253.595218) (xy 117.141355 -253.62931) (xy 117.100852 -253.657266) (xy 117.05639 -253.678364)
			(xy 117.009119 -253.692056) (xy 116.960264 -253.697988) (xy 116.911089 -253.696007) (xy 116.86287 -253.686163)
			(xy 116.816854 -253.668711) (xy 116.774233 -253.644104) (xy 116.736112 -253.612979) (xy 116.703477 -253.576142)
			(xy 116.677174 -253.534546) (xy 116.657883 -253.48927) (xy 116.646106 -253.441486) (xy 116.642146 -253.392432)
			(xy 115.37315 -253.392432) (xy 115.372655 -253.417039) (xy 115.36476 -253.465616) (xy 115.349176 -253.512297)
			(xy 115.326305 -253.555874) (xy 115.29674 -253.595218) (xy 115.261247 -253.62931) (xy 115.220744 -253.657266)
			(xy 115.176282 -253.678364) (xy 115.129011 -253.692056) (xy 115.080156 -253.697988) (xy 115.030981 -253.696007)
			(xy 114.982762 -253.686163) (xy 114.936746 -253.668711) (xy 114.894125 -253.644104) (xy 114.856004 -253.612979)
			(xy 114.823369 -253.576142) (xy 114.797066 -253.534546) (xy 114.777775 -253.48927) (xy 114.765998 -253.441486)
			(xy 114.762038 -253.392432) (xy 113.493296 -253.392432) (xy 113.492801 -253.417039) (xy 113.484906 -253.465616)
			(xy 113.469322 -253.512297) (xy 113.446451 -253.555874) (xy 113.416886 -253.595218) (xy 113.381393 -253.62931)
			(xy 113.34089 -253.657266) (xy 113.296428 -253.678364) (xy 113.249157 -253.692056) (xy 113.200302 -253.697988)
			(xy 113.151127 -253.696007) (xy 113.102908 -253.686163) (xy 113.056892 -253.668711) (xy 113.014271 -253.644104)
			(xy 112.97615 -253.612979) (xy 112.943515 -253.576142) (xy 112.917212 -253.534546) (xy 112.897921 -253.48927)
			(xy 112.886144 -253.441486) (xy 112.882184 -253.392432) (xy 112.598358 -253.392432) (xy 112.60049 -253.406238)
			(xy 112.600994 -253.432564) (xy 112.60049 -253.45889) (xy 112.592453 -253.510926) (xy 112.576567 -253.561125)
			(xy 112.553204 -253.60831) (xy 112.522912 -253.651376) (xy 112.4864 -253.689314) (xy 112.444526 -253.721233)
			(xy 112.39827 -253.746386) (xy 112.348717 -253.764184) (xy 112.297027 -253.774208) (xy 112.244413 -253.776225)
			(xy 112.192108 -253.770187) (xy 112.141337 -253.756235) (xy 112.093292 -253.734696) (xy 112.049097 -253.706076)
			(xy 112.009789 -253.671045) (xy 111.976289 -253.630424) (xy 111.949383 -253.585165) (xy 111.9297 -253.53633)
			(xy 111.917703 -253.485062) (xy 111.913673 -253.432564) (xy 109.730316 -253.432564) (xy 109.724944 -253.465616)
			(xy 109.70936 -253.512297) (xy 109.686489 -253.555874) (xy 109.656924 -253.595218) (xy 109.621431 -253.62931)
			(xy 109.580928 -253.657266) (xy 109.536466 -253.678364) (xy 109.489195 -253.692056) (xy 109.44034 -253.697988)
			(xy 109.391165 -253.696007) (xy 109.342946 -253.686163) (xy 109.29693 -253.668711) (xy 109.254309 -253.644104)
			(xy 109.216188 -253.612979) (xy 109.183553 -253.576142) (xy 109.15725 -253.534546) (xy 109.137959 -253.48927)
			(xy 109.126182 -253.441486) (xy 109.122222 -253.392432) (xy 107.853226 -253.392432) (xy 107.852731 -253.417039)
			(xy 107.844836 -253.465616) (xy 107.829252 -253.512297) (xy 107.806381 -253.555874) (xy 107.776816 -253.595218)
			(xy 107.741323 -253.62931) (xy 107.70082 -253.657266) (xy 107.656358 -253.678364) (xy 107.609087 -253.692056)
			(xy 107.560232 -253.697988) (xy 107.511057 -253.696007) (xy 107.462838 -253.686163) (xy 107.416822 -253.668711)
			(xy 107.374201 -253.644104) (xy 107.33608 -253.612979) (xy 107.303445 -253.576142) (xy 107.277142 -253.534546)
			(xy 107.257851 -253.48927) (xy 107.246074 -253.441486) (xy 107.242114 -253.392432) (xy 105.973118 -253.392432)
			(xy 105.972623 -253.417039) (xy 105.964728 -253.465616) (xy 105.949144 -253.512297) (xy 105.926273 -253.555874)
			(xy 105.896708 -253.595218) (xy 105.861215 -253.62931) (xy 105.820712 -253.657266) (xy 105.77625 -253.678364)
			(xy 105.728979 -253.692056) (xy 105.680124 -253.697988) (xy 105.630949 -253.696007) (xy 105.58273 -253.686163)
			(xy 105.536714 -253.668711) (xy 105.494093 -253.644104) (xy 105.455972 -253.612979) (xy 105.423337 -253.576142)
			(xy 105.397034 -253.534546) (xy 105.377743 -253.48927) (xy 105.365966 -253.441486) (xy 105.362006 -253.392432)
			(xy 104.213152 -253.392432) (xy 105.269284 -254.448564) (xy 111.913673 -254.448564) (xy 111.917703 -254.396066)
			(xy 111.9297 -254.344798) (xy 111.949383 -254.295963) (xy 111.976289 -254.250704) (xy 112.009789 -254.210083)
			(xy 112.049097 -254.175052) (xy 112.093292 -254.146432) (xy 112.141337 -254.124893) (xy 112.192108 -254.110941)
			(xy 112.244413 -254.104903) (xy 112.297027 -254.10692) (xy 112.348717 -254.116944) (xy 112.39827 -254.134742)
			(xy 112.444526 -254.159895) (xy 112.4864 -254.191814) (xy 112.49858 -254.20447) (xy 120.86896 -254.20447)
			(xy 120.87292 -254.155416) (xy 120.884697 -254.107632) (xy 120.903988 -254.062356) (xy 120.930291 -254.02076)
			(xy 120.962926 -253.983923) (xy 121.001047 -253.952798) (xy 121.043668 -253.928191) (xy 121.089684 -253.910739)
			(xy 121.137903 -253.900895) (xy 121.187078 -253.898914) (xy 121.235933 -253.904846) (xy 121.283204 -253.918538)
			(xy 121.327666 -253.939636) (xy 121.368169 -253.967592) (xy 121.403662 -254.001684) (xy 121.433227 -254.041028)
			(xy 121.456098 -254.084605) (xy 121.471682 -254.131286) (xy 121.479577 -254.179863) (xy 121.480072 -254.20447)
			(xy 122.748814 -254.20447) (xy 122.752774 -254.155416) (xy 122.764551 -254.107632) (xy 122.783842 -254.062356)
			(xy 122.810145 -254.02076) (xy 122.84278 -253.983923) (xy 122.880901 -253.952798) (xy 122.923522 -253.928191)
			(xy 122.969538 -253.910739) (xy 123.017757 -253.900895) (xy 123.066932 -253.898914) (xy 123.115787 -253.904846)
			(xy 123.163058 -253.918538) (xy 123.20752 -253.939636) (xy 123.248023 -253.967592) (xy 123.283516 -254.001684)
			(xy 123.313081 -254.041028) (xy 123.335952 -254.084605) (xy 123.351536 -254.131286) (xy 123.359431 -254.179863)
			(xy 123.359926 -254.20447) (xy 124.628922 -254.20447) (xy 124.632882 -254.155416) (xy 124.644659 -254.107632)
			(xy 124.66395 -254.062356) (xy 124.690253 -254.02076) (xy 124.722888 -253.983923) (xy 124.761009 -253.952798)
			(xy 124.80363 -253.928191) (xy 124.849646 -253.910739) (xy 124.897865 -253.900895) (xy 124.94704 -253.898914)
			(xy 124.995895 -253.904846) (xy 125.043166 -253.918538) (xy 125.087628 -253.939636) (xy 125.128131 -253.967592)
			(xy 125.163624 -254.001684) (xy 125.193189 -254.041028) (xy 125.21606 -254.084605) (xy 125.231644 -254.131286)
			(xy 125.239539 -254.179863) (xy 125.240034 -254.20447) (xy 125.239539 -254.229077) (xy 125.231644 -254.277654)
			(xy 125.21606 -254.324335) (xy 125.193189 -254.367912) (xy 125.163624 -254.407256) (xy 125.128131 -254.441348)
			(xy 125.087628 -254.469304) (xy 125.043166 -254.490402) (xy 124.995895 -254.504094) (xy 124.94704 -254.510026)
			(xy 124.897865 -254.508045) (xy 124.849646 -254.498201) (xy 124.80363 -254.480749) (xy 124.761009 -254.456142)
			(xy 124.722888 -254.425017) (xy 124.690253 -254.38818) (xy 124.66395 -254.346584) (xy 124.644659 -254.301308)
			(xy 124.632882 -254.253524) (xy 124.628922 -254.20447) (xy 123.359926 -254.20447) (xy 123.359431 -254.229077)
			(xy 123.351536 -254.277654) (xy 123.335952 -254.324335) (xy 123.313081 -254.367912) (xy 123.283516 -254.407256)
			(xy 123.248023 -254.441348) (xy 123.20752 -254.469304) (xy 123.163058 -254.490402) (xy 123.115787 -254.504094)
			(xy 123.066932 -254.510026) (xy 123.017757 -254.508045) (xy 122.969538 -254.498201) (xy 122.923522 -254.480749)
			(xy 122.880901 -254.456142) (xy 122.84278 -254.425017) (xy 122.810145 -254.38818) (xy 122.783842 -254.346584)
			(xy 122.764551 -254.301308) (xy 122.752774 -254.253524) (xy 122.748814 -254.20447) (xy 121.480072 -254.20447)
			(xy 121.479577 -254.229077) (xy 121.471682 -254.277654) (xy 121.456098 -254.324335) (xy 121.433227 -254.367912)
			(xy 121.403662 -254.407256) (xy 121.368169 -254.441348) (xy 121.327666 -254.469304) (xy 121.283204 -254.490402)
			(xy 121.235933 -254.504094) (xy 121.187078 -254.510026) (xy 121.137903 -254.508045) (xy 121.089684 -254.498201)
			(xy 121.043668 -254.480749) (xy 121.001047 -254.456142) (xy 120.962926 -254.425017) (xy 120.930291 -254.38818)
			(xy 120.903988 -254.346584) (xy 120.884697 -254.301308) (xy 120.87292 -254.253524) (xy 120.86896 -254.20447)
			(xy 112.49858 -254.20447) (xy 112.522912 -254.229752) (xy 112.553204 -254.272818) (xy 112.576567 -254.320003)
			(xy 112.592453 -254.370202) (xy 112.60049 -254.422238) (xy 112.600994 -254.448564) (xy 112.60049 -254.47489)
			(xy 112.592453 -254.526926) (xy 112.576567 -254.577125) (xy 112.553204 -254.62431) (xy 112.522912 -254.667376)
			(xy 112.4864 -254.705314) (xy 112.444526 -254.737233) (xy 112.39827 -254.762386) (xy 112.348717 -254.780184)
			(xy 112.297027 -254.790208) (xy 112.244413 -254.792225) (xy 112.192108 -254.786187) (xy 112.141337 -254.772235)
			(xy 112.093292 -254.750696) (xy 112.049097 -254.722076) (xy 112.009789 -254.687045) (xy 111.976289 -254.646424)
			(xy 111.949383 -254.601165) (xy 111.9297 -254.55233) (xy 111.917703 -254.501062) (xy 111.913673 -254.448564)
			(xy 105.269284 -254.448564) (xy 105.835196 -255.014476) (xy 122.278914 -255.014476) (xy 122.282874 -254.965422)
			(xy 122.294651 -254.917638) (xy 122.313942 -254.872362) (xy 122.340245 -254.830766) (xy 122.37288 -254.793929)
			(xy 122.411001 -254.762804) (xy 122.453622 -254.738197) (xy 122.499638 -254.720745) (xy 122.547857 -254.710901)
			(xy 122.597032 -254.70892) (xy 122.645887 -254.714852) (xy 122.693158 -254.728544) (xy 122.73762 -254.749642)
			(xy 122.778123 -254.777598) (xy 122.813616 -254.81169) (xy 122.843181 -254.851034) (xy 122.866052 -254.894611)
			(xy 122.881636 -254.941292) (xy 122.889531 -254.989869) (xy 122.890026 -255.014476) (xy 124.159022 -255.014476)
			(xy 124.162982 -254.965422) (xy 124.174759 -254.917638) (xy 124.19405 -254.872362) (xy 124.220353 -254.830766)
			(xy 124.252988 -254.793929) (xy 124.291109 -254.762804) (xy 124.33373 -254.738197) (xy 124.379746 -254.720745)
			(xy 124.427965 -254.710901) (xy 124.47714 -254.70892) (xy 124.525995 -254.714852) (xy 124.573266 -254.728544)
			(xy 124.617728 -254.749642) (xy 124.658231 -254.777598) (xy 124.693724 -254.81169) (xy 124.723289 -254.851034)
			(xy 124.74616 -254.894611) (xy 124.761744 -254.941292) (xy 124.769639 -254.989869) (xy 124.770134 -255.014476)
			(xy 126.038876 -255.014476) (xy 126.042836 -254.965422) (xy 126.054613 -254.917638) (xy 126.073904 -254.872362)
			(xy 126.100207 -254.830766) (xy 126.132842 -254.793929) (xy 126.170963 -254.762804) (xy 126.213584 -254.738197)
			(xy 126.2596 -254.720745) (xy 126.307819 -254.710901) (xy 126.356994 -254.70892) (xy 126.405849 -254.714852)
			(xy 126.45312 -254.728544) (xy 126.497582 -254.749642) (xy 126.538085 -254.777598) (xy 126.573578 -254.81169)
			(xy 126.603143 -254.851034) (xy 126.626014 -254.894611) (xy 126.641598 -254.941292) (xy 126.649493 -254.989869)
			(xy 126.649988 -255.014476) (xy 126.649493 -255.039083) (xy 126.641598 -255.08766) (xy 126.626014 -255.134341)
			(xy 126.603143 -255.177918) (xy 126.573578 -255.217262) (xy 126.538085 -255.251354) (xy 126.497582 -255.27931)
			(xy 126.45312 -255.300408) (xy 126.405849 -255.3141) (xy 126.356994 -255.320032) (xy 126.307819 -255.318051)
			(xy 126.2596 -255.308207) (xy 126.213584 -255.290755) (xy 126.170963 -255.266148) (xy 126.132842 -255.235023)
			(xy 126.100207 -255.198186) (xy 126.073904 -255.15659) (xy 126.054613 -255.111314) (xy 126.042836 -255.06353)
			(xy 126.038876 -255.014476) (xy 124.770134 -255.014476) (xy 124.769639 -255.039083) (xy 124.761744 -255.08766)
			(xy 124.74616 -255.134341) (xy 124.723289 -255.177918) (xy 124.693724 -255.217262) (xy 124.658231 -255.251354)
			(xy 124.617728 -255.27931) (xy 124.573266 -255.300408) (xy 124.525995 -255.3141) (xy 124.47714 -255.320032)
			(xy 124.427965 -255.318051) (xy 124.379746 -255.308207) (xy 124.33373 -255.290755) (xy 124.291109 -255.266148)
			(xy 124.252988 -255.235023) (xy 124.220353 -255.198186) (xy 124.19405 -255.15659) (xy 124.174759 -255.111314)
			(xy 124.162982 -255.06353) (xy 124.159022 -255.014476) (xy 122.890026 -255.014476) (xy 122.889531 -255.039083)
			(xy 122.881636 -255.08766) (xy 122.866052 -255.134341) (xy 122.843181 -255.177918) (xy 122.813616 -255.217262)
			(xy 122.778123 -255.251354) (xy 122.73762 -255.27931) (xy 122.693158 -255.300408) (xy 122.645887 -255.3141)
			(xy 122.597032 -255.320032) (xy 122.547857 -255.318051) (xy 122.499638 -255.308207) (xy 122.453622 -255.290755)
			(xy 122.411001 -255.266148) (xy 122.37288 -255.235023) (xy 122.340245 -255.198186) (xy 122.313942 -255.15659)
			(xy 122.294651 -255.111314) (xy 122.282874 -255.06353) (xy 122.278914 -255.014476) (xy 105.835196 -255.014476)
			(xy 106.084878 -255.264158) (xy 106.092153 -255.270847) (xy 106.11032 -255.278577) (xy 106.120184 -255.279144)
			(xy 106.15041 -255.279652) (xy 106.15953 -255.279402) (xy 106.176699 -255.27327) (xy 106.183938 -255.267714)
			(xy 106.202593 -255.252529) (xy 106.243346 -255.226977) (xy 106.287265 -255.207362) (xy 106.333492 -255.194067)
			(xy 106.381122 -255.187351) (xy 106.405172 -255.186942) (xy 106.43216 -255.187469) (xy 106.485472 -255.195908)
			(xy 106.536808 -255.212583) (xy 106.584903 -255.237082) (xy 106.628574 -255.268804) (xy 106.666745 -255.306966)
			(xy 106.698477 -255.35063) (xy 106.722987 -255.39872) (xy 106.739674 -255.450052) (xy 106.748125 -255.503362)
			(xy 106.74858 -255.53035) (xy 117.096797 -255.53035) (xy 117.100827 -255.477852) (xy 117.112824 -255.426584)
			(xy 117.132507 -255.377749) (xy 117.159413 -255.33249) (xy 117.192913 -255.291869) (xy 117.232221 -255.256838)
			(xy 117.276416 -255.228218) (xy 117.324461 -255.206679) (xy 117.375232 -255.192727) (xy 117.427537 -255.186689)
			(xy 117.480151 -255.188706) (xy 117.531841 -255.19873) (xy 117.581394 -255.216528) (xy 117.62765 -255.241681)
			(xy 117.669524 -255.2736) (xy 117.706036 -255.311538) (xy 117.736328 -255.354604) (xy 117.759691 -255.401789)
			(xy 117.775577 -255.451988) (xy 117.783614 -255.504024) (xy 117.784118 -255.53035) (xy 117.783614 -255.556676)
			(xy 117.775577 -255.608712) (xy 117.759691 -255.658911) (xy 117.736328 -255.706096) (xy 117.706036 -255.749162)
			(xy 117.669524 -255.7871) (xy 117.62765 -255.819019) (xy 117.617604 -255.824482) (xy 120.86896 -255.824482)
			(xy 120.87292 -255.775428) (xy 120.884697 -255.727644) (xy 120.903988 -255.682368) (xy 120.930291 -255.640772)
			(xy 120.962926 -255.603935) (xy 121.001047 -255.57281) (xy 121.043668 -255.548203) (xy 121.089684 -255.530751)
			(xy 121.137903 -255.520907) (xy 121.187078 -255.518926) (xy 121.235933 -255.524858) (xy 121.283204 -255.53855)
			(xy 121.327666 -255.559648) (xy 121.368169 -255.587604) (xy 121.403662 -255.621696) (xy 121.433227 -255.66104)
			(xy 121.456098 -255.704617) (xy 121.471682 -255.751298) (xy 121.479577 -255.799875) (xy 121.480072 -255.824482)
			(xy 122.748814 -255.824482) (xy 122.752774 -255.775428) (xy 122.764551 -255.727644) (xy 122.783842 -255.682368)
			(xy 122.810145 -255.640772) (xy 122.84278 -255.603935) (xy 122.880901 -255.57281) (xy 122.923522 -255.548203)
			(xy 122.969538 -255.530751) (xy 123.017757 -255.520907) (xy 123.066932 -255.518926) (xy 123.115787 -255.524858)
			(xy 123.163058 -255.53855) (xy 123.20752 -255.559648) (xy 123.248023 -255.587604) (xy 123.283516 -255.621696)
			(xy 123.313081 -255.66104) (xy 123.335952 -255.704617) (xy 123.351536 -255.751298) (xy 123.359431 -255.799875)
			(xy 123.359926 -255.824482) (xy 124.628922 -255.824482) (xy 124.632882 -255.775428) (xy 124.644659 -255.727644)
			(xy 124.66395 -255.682368) (xy 124.690253 -255.640772) (xy 124.722888 -255.603935) (xy 124.761009 -255.57281)
			(xy 124.80363 -255.548203) (xy 124.849646 -255.530751) (xy 124.897865 -255.520907) (xy 124.94704 -255.518926)
			(xy 124.995895 -255.524858) (xy 125.043166 -255.53855) (xy 125.087628 -255.559648) (xy 125.128131 -255.587604)
			(xy 125.163624 -255.621696) (xy 125.193189 -255.66104) (xy 125.21606 -255.704617) (xy 125.231644 -255.751298)
			(xy 125.239539 -255.799875) (xy 125.240034 -255.824482) (xy 125.239539 -255.849089) (xy 125.231644 -255.897666)
			(xy 125.21606 -255.944347) (xy 125.193189 -255.987924) (xy 125.163624 -256.027268) (xy 125.128131 -256.06136)
			(xy 125.087628 -256.089316) (xy 125.043166 -256.110414) (xy 124.995895 -256.124106) (xy 124.94704 -256.130038)
			(xy 124.897865 -256.128057) (xy 124.849646 -256.118213) (xy 124.80363 -256.100761) (xy 124.761009 -256.076154)
			(xy 124.722888 -256.045029) (xy 124.690253 -256.008192) (xy 124.66395 -255.966596) (xy 124.644659 -255.92132)
			(xy 124.632882 -255.873536) (xy 124.628922 -255.824482) (xy 123.359926 -255.824482) (xy 123.359431 -255.849089)
			(xy 123.351536 -255.897666) (xy 123.335952 -255.944347) (xy 123.313081 -255.987924) (xy 123.283516 -256.027268)
			(xy 123.248023 -256.06136) (xy 123.20752 -256.089316) (xy 123.163058 -256.110414) (xy 123.115787 -256.124106)
			(xy 123.066932 -256.130038) (xy 123.017757 -256.128057) (xy 122.969538 -256.118213) (xy 122.923522 -256.100761)
			(xy 122.880901 -256.076154) (xy 122.84278 -256.045029) (xy 122.810145 -256.008192) (xy 122.783842 -255.966596)
			(xy 122.764551 -255.92132) (xy 122.752774 -255.873536) (xy 122.748814 -255.824482) (xy 121.480072 -255.824482)
			(xy 121.479577 -255.849089) (xy 121.471682 -255.897666) (xy 121.456098 -255.944347) (xy 121.433227 -255.987924)
			(xy 121.403662 -256.027268) (xy 121.368169 -256.06136) (xy 121.327666 -256.089316) (xy 121.283204 -256.110414)
			(xy 121.235933 -256.124106) (xy 121.187078 -256.130038) (xy 121.137903 -256.128057) (xy 121.089684 -256.118213)
			(xy 121.043668 -256.100761) (xy 121.001047 -256.076154) (xy 120.962926 -256.045029) (xy 120.930291 -256.008192)
			(xy 120.903988 -255.966596) (xy 120.884697 -255.92132) (xy 120.87292 -255.873536) (xy 120.86896 -255.824482)
			(xy 117.617604 -255.824482) (xy 117.581394 -255.844172) (xy 117.531841 -255.86197) (xy 117.480151 -255.871994)
			(xy 117.427537 -255.874011) (xy 117.375232 -255.867973) (xy 117.324461 -255.854021) (xy 117.276416 -255.832482)
			(xy 117.232221 -255.803862) (xy 117.192913 -255.768831) (xy 117.159413 -255.72821) (xy 117.132507 -255.682951)
			(xy 117.112824 -255.634116) (xy 117.100827 -255.582848) (xy 117.096797 -255.53035) (xy 106.74858 -255.53035)
			(xy 106.748053 -255.558088) (xy 106.739145 -255.612844) (xy 106.721553 -255.665457) (xy 106.695735 -255.714559)
			(xy 106.662361 -255.758873) (xy 106.622299 -255.797248) (xy 106.57659 -255.828685) (xy 106.526424 -255.852369)
			(xy 106.499914 -255.86055) (xy 106.483404 -255.865122) (xy 106.463084 -255.892046) (xy 106.463084 -256.04978)
			(xy 106.463521 -256.059844) (xy 106.471254 -256.078429) (xy 106.47807 -256.085848) (xy 106.5657 -256.173478)
			(xy 106.570526 -256.177796) (xy 106.578146 -256.183638) (xy 106.580686 -256.185162) (xy 106.604904 -256.200217)
			(xy 106.648428 -256.237054) (xy 106.685269 -256.280576) (xy 106.70032 -256.304796) (xy 106.701844 -256.307336)
			(xy 106.707686 -256.314956) (xy 106.712004 -256.319782) (xy 106.779822 -256.3876) (xy 107.304081 -256.3876)
			(xy 107.308111 -256.335102) (xy 107.320108 -256.283834) (xy 107.339791 -256.234999) (xy 107.366697 -256.18974)
			(xy 107.400197 -256.149119) (xy 107.439505 -256.114088) (xy 107.4837 -256.085468) (xy 107.531745 -256.063929)
			(xy 107.582516 -256.049977) (xy 107.634821 -256.043939) (xy 107.687435 -256.045956) (xy 107.739125 -256.05598)
			(xy 107.788678 -256.073778) (xy 107.834934 -256.098931) (xy 107.876808 -256.13085) (xy 107.91332 -256.168788)
			(xy 107.943612 -256.211854) (xy 107.966975 -256.259039) (xy 107.982861 -256.309238) (xy 107.990898 -256.361274)
			(xy 107.991402 -256.3876) (xy 108.254041 -256.3876) (xy 108.258071 -256.335102) (xy 108.270068 -256.283834)
			(xy 108.289751 -256.234999) (xy 108.316657 -256.18974) (xy 108.350157 -256.149119) (xy 108.389465 -256.114088)
			(xy 108.43366 -256.085468) (xy 108.481705 -256.063929) (xy 108.532476 -256.049977) (xy 108.584781 -256.043939)
			(xy 108.637395 -256.045956) (xy 108.689085 -256.05598) (xy 108.738638 -256.073778) (xy 108.784894 -256.098931)
			(xy 108.826768 -256.13085) (xy 108.86328 -256.168788) (xy 108.893572 -256.211854) (xy 108.916935 -256.259039)
			(xy 108.932821 -256.309238) (xy 108.940858 -256.361274) (xy 108.941362 -256.3876) (xy 109.204001 -256.3876)
			(xy 109.208031 -256.335102) (xy 109.220028 -256.283834) (xy 109.239711 -256.234999) (xy 109.266617 -256.18974)
			(xy 109.300117 -256.149119) (xy 109.339425 -256.114088) (xy 109.38362 -256.085468) (xy 109.431665 -256.063929)
			(xy 109.482436 -256.049977) (xy 109.534741 -256.043939) (xy 109.587355 -256.045956) (xy 109.639045 -256.05598)
			(xy 109.688598 -256.073778) (xy 109.734854 -256.098931) (xy 109.776728 -256.13085) (xy 109.81324 -256.168788)
			(xy 109.843532 -256.211854) (xy 109.866895 -256.259039) (xy 109.882781 -256.309238) (xy 109.890818 -256.361274)
			(xy 109.891322 -256.3876) (xy 110.153961 -256.3876) (xy 110.157991 -256.335102) (xy 110.169988 -256.283834)
			(xy 110.189671 -256.234999) (xy 110.216577 -256.18974) (xy 110.250077 -256.149119) (xy 110.289385 -256.114088)
			(xy 110.33358 -256.085468) (xy 110.381625 -256.063929) (xy 110.432396 -256.049977) (xy 110.484701 -256.043939)
			(xy 110.537315 -256.045956) (xy 110.589005 -256.05598) (xy 110.638558 -256.073778) (xy 110.684814 -256.098931)
			(xy 110.726688 -256.13085) (xy 110.7632 -256.168788) (xy 110.793492 -256.211854) (xy 110.816855 -256.259039)
			(xy 110.832741 -256.309238) (xy 110.840778 -256.361274) (xy 110.841282 -256.3876) (xy 111.103921 -256.3876)
			(xy 111.107951 -256.335102) (xy 111.119948 -256.283834) (xy 111.139631 -256.234999) (xy 111.166537 -256.18974)
			(xy 111.200037 -256.149119) (xy 111.239345 -256.114088) (xy 111.28354 -256.085468) (xy 111.331585 -256.063929)
			(xy 111.382356 -256.049977) (xy 111.434661 -256.043939) (xy 111.487275 -256.045956) (xy 111.538965 -256.05598)
			(xy 111.588518 -256.073778) (xy 111.634774 -256.098931) (xy 111.676648 -256.13085) (xy 111.71316 -256.168788)
			(xy 111.743452 -256.211854) (xy 111.766815 -256.259039) (xy 111.782701 -256.309238) (xy 111.790738 -256.361274)
			(xy 111.791242 -256.3876) (xy 112.053881 -256.3876) (xy 112.057911 -256.335102) (xy 112.069908 -256.283834)
			(xy 112.089591 -256.234999) (xy 112.116497 -256.18974) (xy 112.149997 -256.149119) (xy 112.189305 -256.114088)
			(xy 112.2335 -256.085468) (xy 112.281545 -256.063929) (xy 112.332316 -256.049977) (xy 112.384621 -256.043939)
			(xy 112.437235 -256.045956) (xy 112.488925 -256.05598) (xy 112.538478 -256.073778) (xy 112.584734 -256.098931)
			(xy 112.626608 -256.13085) (xy 112.66312 -256.168788) (xy 112.693412 -256.211854) (xy 112.716775 -256.259039)
			(xy 112.732661 -256.309238) (xy 112.740698 -256.361274) (xy 112.741202 -256.3876) (xy 113.004095 -256.3876)
			(xy 113.008125 -256.335102) (xy 113.020122 -256.283834) (xy 113.039805 -256.234999) (xy 113.066711 -256.18974)
			(xy 113.100211 -256.149119) (xy 113.139519 -256.114088) (xy 113.183714 -256.085468) (xy 113.231759 -256.063929)
			(xy 113.28253 -256.049977) (xy 113.334835 -256.043939) (xy 113.387449 -256.045956) (xy 113.439139 -256.05598)
			(xy 113.488692 -256.073778) (xy 113.534948 -256.098931) (xy 113.576822 -256.13085) (xy 113.613334 -256.168788)
			(xy 113.643626 -256.211854) (xy 113.666989 -256.259039) (xy 113.682875 -256.309238) (xy 113.690912 -256.361274)
			(xy 113.691416 -256.3876) (xy 113.954055 -256.3876) (xy 113.958085 -256.335102) (xy 113.970082 -256.283834)
			(xy 113.989765 -256.234999) (xy 114.016671 -256.18974) (xy 114.050171 -256.149119) (xy 114.089479 -256.114088)
			(xy 114.133674 -256.085468) (xy 114.181719 -256.063929) (xy 114.23249 -256.049977) (xy 114.284795 -256.043939)
			(xy 114.337409 -256.045956) (xy 114.389099 -256.05598) (xy 114.438652 -256.073778) (xy 114.484908 -256.098931)
			(xy 114.526782 -256.13085) (xy 114.563294 -256.168788) (xy 114.593586 -256.211854) (xy 114.616949 -256.259039)
			(xy 114.632835 -256.309238) (xy 114.640872 -256.361274) (xy 114.641376 -256.3876) (xy 114.904015 -256.3876)
			(xy 114.908045 -256.335102) (xy 114.920042 -256.283834) (xy 114.939725 -256.234999) (xy 114.966631 -256.18974)
			(xy 115.000131 -256.149119) (xy 115.039439 -256.114088) (xy 115.083634 -256.085468) (xy 115.131679 -256.063929)
			(xy 115.18245 -256.049977) (xy 115.234755 -256.043939) (xy 115.287369 -256.045956) (xy 115.339059 -256.05598)
			(xy 115.388612 -256.073778) (xy 115.434868 -256.098931) (xy 115.476742 -256.13085) (xy 115.513254 -256.168788)
			(xy 115.543546 -256.211854) (xy 115.566909 -256.259039) (xy 115.582795 -256.309238) (xy 115.590832 -256.361274)
			(xy 115.591336 -256.3876) (xy 115.853975 -256.3876) (xy 115.858005 -256.335102) (xy 115.870002 -256.283834)
			(xy 115.889685 -256.234999) (xy 115.916591 -256.18974) (xy 115.950091 -256.149119) (xy 115.989399 -256.114088)
			(xy 116.033594 -256.085468) (xy 116.081639 -256.063929) (xy 116.13241 -256.049977) (xy 116.184715 -256.043939)
			(xy 116.237329 -256.045956) (xy 116.289019 -256.05598) (xy 116.338572 -256.073778) (xy 116.384828 -256.098931)
			(xy 116.426702 -256.13085) (xy 116.463214 -256.168788) (xy 116.493506 -256.211854) (xy 116.516869 -256.259039)
			(xy 116.532755 -256.309238) (xy 116.540792 -256.361274) (xy 116.541296 -256.3876) (xy 116.540792 -256.413926)
			(xy 116.532755 -256.465962) (xy 116.528214 -256.48031) (xy 117.096797 -256.48031) (xy 117.100827 -256.427812)
			(xy 117.112824 -256.376544) (xy 117.132507 -256.327709) (xy 117.159413 -256.28245) (xy 117.192913 -256.241829)
			(xy 117.232221 -256.206798) (xy 117.276416 -256.178178) (xy 117.324461 -256.156639) (xy 117.375232 -256.142687)
			(xy 117.427537 -256.136649) (xy 117.480151 -256.138666) (xy 117.531841 -256.14869) (xy 117.581394 -256.166488)
			(xy 117.62765 -256.191641) (xy 117.669524 -256.22356) (xy 117.706036 -256.261498) (xy 117.736328 -256.304564)
			(xy 117.759691 -256.351749) (xy 117.775577 -256.401948) (xy 117.783614 -256.453984) (xy 117.784118 -256.48031)
			(xy 117.783614 -256.506636) (xy 117.775577 -256.558672) (xy 117.759691 -256.608871) (xy 117.747007 -256.634488)
			(xy 122.278914 -256.634488) (xy 122.282874 -256.585434) (xy 122.294651 -256.53765) (xy 122.313942 -256.492374)
			(xy 122.340245 -256.450778) (xy 122.37288 -256.413941) (xy 122.411001 -256.382816) (xy 122.453622 -256.358209)
			(xy 122.499638 -256.340757) (xy 122.547857 -256.330913) (xy 122.597032 -256.328932) (xy 122.645887 -256.334864)
			(xy 122.693158 -256.348556) (xy 122.73762 -256.369654) (xy 122.778123 -256.39761) (xy 122.813616 -256.431702)
			(xy 122.843181 -256.471046) (xy 122.866052 -256.514623) (xy 122.881636 -256.561304) (xy 122.889531 -256.609881)
			(xy 122.890026 -256.634488) (xy 124.159022 -256.634488) (xy 124.162982 -256.585434) (xy 124.174759 -256.53765)
			(xy 124.19405 -256.492374) (xy 124.220353 -256.450778) (xy 124.252988 -256.413941) (xy 124.291109 -256.382816)
			(xy 124.33373 -256.358209) (xy 124.379746 -256.340757) (xy 124.427965 -256.330913) (xy 124.47714 -256.328932)
			(xy 124.525995 -256.334864) (xy 124.573266 -256.348556) (xy 124.617728 -256.369654) (xy 124.658231 -256.39761)
			(xy 124.693724 -256.431702) (xy 124.723289 -256.471046) (xy 124.74616 -256.514623) (xy 124.761744 -256.561304)
			(xy 124.769639 -256.609881) (xy 124.770134 -256.634488) (xy 126.038876 -256.634488) (xy 126.042836 -256.585434)
			(xy 126.054613 -256.53765) (xy 126.073904 -256.492374) (xy 126.100207 -256.450778) (xy 126.132842 -256.413941)
			(xy 126.170963 -256.382816) (xy 126.213584 -256.358209) (xy 126.2596 -256.340757) (xy 126.307819 -256.330913)
			(xy 126.356994 -256.328932) (xy 126.405849 -256.334864) (xy 126.45312 -256.348556) (xy 126.497582 -256.369654)
			(xy 126.538085 -256.39761) (xy 126.573578 -256.431702) (xy 126.603143 -256.471046) (xy 126.626014 -256.514623)
			(xy 126.641598 -256.561304) (xy 126.649493 -256.609881) (xy 126.649988 -256.634488) (xy 126.649493 -256.659095)
			(xy 126.641598 -256.707672) (xy 126.626014 -256.754353) (xy 126.603143 -256.79793) (xy 126.573578 -256.837274)
			(xy 126.538085 -256.871366) (xy 126.497582 -256.899322) (xy 126.45312 -256.92042) (xy 126.405849 -256.934112)
			(xy 126.356994 -256.940044) (xy 126.307819 -256.938063) (xy 126.2596 -256.928219) (xy 126.213584 -256.910767)
			(xy 126.170963 -256.88616) (xy 126.132842 -256.855035) (xy 126.100207 -256.818198) (xy 126.073904 -256.776602)
			(xy 126.054613 -256.731326) (xy 126.042836 -256.683542) (xy 126.038876 -256.634488) (xy 124.770134 -256.634488)
			(xy 124.769639 -256.659095) (xy 124.761744 -256.707672) (xy 124.74616 -256.754353) (xy 124.723289 -256.79793)
			(xy 124.693724 -256.837274) (xy 124.658231 -256.871366) (xy 124.617728 -256.899322) (xy 124.573266 -256.92042)
			(xy 124.525995 -256.934112) (xy 124.47714 -256.940044) (xy 124.427965 -256.938063) (xy 124.379746 -256.928219)
			(xy 124.33373 -256.910767) (xy 124.291109 -256.88616) (xy 124.252988 -256.855035) (xy 124.220353 -256.818198)
			(xy 124.19405 -256.776602) (xy 124.174759 -256.731326) (xy 124.162982 -256.683542) (xy 124.159022 -256.634488)
			(xy 122.890026 -256.634488) (xy 122.889531 -256.659095) (xy 122.881636 -256.707672) (xy 122.866052 -256.754353)
			(xy 122.843181 -256.79793) (xy 122.813616 -256.837274) (xy 122.778123 -256.871366) (xy 122.73762 -256.899322)
			(xy 122.693158 -256.92042) (xy 122.645887 -256.934112) (xy 122.597032 -256.940044) (xy 122.547857 -256.938063)
			(xy 122.499638 -256.928219) (xy 122.453622 -256.910767) (xy 122.411001 -256.88616) (xy 122.37288 -256.855035)
			(xy 122.340245 -256.818198) (xy 122.313942 -256.776602) (xy 122.294651 -256.731326) (xy 122.282874 -256.683542)
			(xy 122.278914 -256.634488) (xy 117.747007 -256.634488) (xy 117.736328 -256.656056) (xy 117.706036 -256.699122)
			(xy 117.669524 -256.73706) (xy 117.62765 -256.768979) (xy 117.581394 -256.794132) (xy 117.531841 -256.81193)
			(xy 117.480151 -256.821954) (xy 117.427537 -256.823971) (xy 117.375232 -256.817933) (xy 117.324461 -256.803981)
			(xy 117.276416 -256.782442) (xy 117.232221 -256.753822) (xy 117.192913 -256.718791) (xy 117.159413 -256.67817)
			(xy 117.132507 -256.632911) (xy 117.112824 -256.584076) (xy 117.100827 -256.532808) (xy 117.096797 -256.48031)
			(xy 116.528214 -256.48031) (xy 116.516869 -256.516161) (xy 116.493506 -256.563346) (xy 116.463214 -256.606412)
			(xy 116.426702 -256.64435) (xy 116.384828 -256.676269) (xy 116.338572 -256.701422) (xy 116.289019 -256.71922)
			(xy 116.237329 -256.729244) (xy 116.184715 -256.731261) (xy 116.13241 -256.725223) (xy 116.081639 -256.711271)
			(xy 116.033594 -256.689732) (xy 115.989399 -256.661112) (xy 115.950091 -256.626081) (xy 115.916591 -256.58546)
			(xy 115.889685 -256.540201) (xy 115.870002 -256.491366) (xy 115.858005 -256.440098) (xy 115.853975 -256.3876)
			(xy 115.591336 -256.3876) (xy 115.590832 -256.413926) (xy 115.582795 -256.465962) (xy 115.566909 -256.516161)
			(xy 115.543546 -256.563346) (xy 115.513254 -256.606412) (xy 115.476742 -256.64435) (xy 115.434868 -256.676269)
			(xy 115.388612 -256.701422) (xy 115.339059 -256.71922) (xy 115.287369 -256.729244) (xy 115.234755 -256.731261)
			(xy 115.18245 -256.725223) (xy 115.131679 -256.711271) (xy 115.083634 -256.689732) (xy 115.039439 -256.661112)
			(xy 115.000131 -256.626081) (xy 114.966631 -256.58546) (xy 114.939725 -256.540201) (xy 114.920042 -256.491366)
			(xy 114.908045 -256.440098) (xy 114.904015 -256.3876) (xy 114.641376 -256.3876) (xy 114.640872 -256.413926)
			(xy 114.632835 -256.465962) (xy 114.616949 -256.516161) (xy 114.593586 -256.563346) (xy 114.563294 -256.606412)
			(xy 114.526782 -256.64435) (xy 114.484908 -256.676269) (xy 114.438652 -256.701422) (xy 114.389099 -256.71922)
			(xy 114.337409 -256.729244) (xy 114.284795 -256.731261) (xy 114.23249 -256.725223) (xy 114.181719 -256.711271)
			(xy 114.133674 -256.689732) (xy 114.089479 -256.661112) (xy 114.050171 -256.626081) (xy 114.016671 -256.58546)
			(xy 113.989765 -256.540201) (xy 113.970082 -256.491366) (xy 113.958085 -256.440098) (xy 113.954055 -256.3876)
			(xy 113.691416 -256.3876) (xy 113.690912 -256.413926) (xy 113.682875 -256.465962) (xy 113.666989 -256.516161)
			(xy 113.643626 -256.563346) (xy 113.613334 -256.606412) (xy 113.576822 -256.64435) (xy 113.534948 -256.676269)
			(xy 113.488692 -256.701422) (xy 113.439139 -256.71922) (xy 113.387449 -256.729244) (xy 113.334835 -256.731261)
			(xy 113.28253 -256.725223) (xy 113.231759 -256.711271) (xy 113.183714 -256.689732) (xy 113.139519 -256.661112)
			(xy 113.100211 -256.626081) (xy 113.066711 -256.58546) (xy 113.039805 -256.540201) (xy 113.020122 -256.491366)
			(xy 113.008125 -256.440098) (xy 113.004095 -256.3876) (xy 112.741202 -256.3876) (xy 112.740698 -256.413926)
			(xy 112.732661 -256.465962) (xy 112.716775 -256.516161) (xy 112.693412 -256.563346) (xy 112.66312 -256.606412)
			(xy 112.626608 -256.64435) (xy 112.584734 -256.676269) (xy 112.538478 -256.701422) (xy 112.488925 -256.71922)
			(xy 112.437235 -256.729244) (xy 112.384621 -256.731261) (xy 112.332316 -256.725223) (xy 112.281545 -256.711271)
			(xy 112.2335 -256.689732) (xy 112.189305 -256.661112) (xy 112.149997 -256.626081) (xy 112.116497 -256.58546)
			(xy 112.089591 -256.540201) (xy 112.069908 -256.491366) (xy 112.057911 -256.440098) (xy 112.053881 -256.3876)
			(xy 111.791242 -256.3876) (xy 111.790738 -256.413926) (xy 111.782701 -256.465962) (xy 111.766815 -256.516161)
			(xy 111.743452 -256.563346) (xy 111.71316 -256.606412) (xy 111.676648 -256.64435) (xy 111.634774 -256.676269)
			(xy 111.588518 -256.701422) (xy 111.538965 -256.71922) (xy 111.487275 -256.729244) (xy 111.434661 -256.731261)
			(xy 111.382356 -256.725223) (xy 111.331585 -256.711271) (xy 111.28354 -256.689732) (xy 111.239345 -256.661112)
			(xy 111.200037 -256.626081) (xy 111.166537 -256.58546) (xy 111.139631 -256.540201) (xy 111.119948 -256.491366)
			(xy 111.107951 -256.440098) (xy 111.103921 -256.3876) (xy 110.841282 -256.3876) (xy 110.840778 -256.413926)
			(xy 110.832741 -256.465962) (xy 110.816855 -256.516161) (xy 110.793492 -256.563346) (xy 110.7632 -256.606412)
			(xy 110.726688 -256.64435) (xy 110.684814 -256.676269) (xy 110.638558 -256.701422) (xy 110.589005 -256.71922)
			(xy 110.537315 -256.729244) (xy 110.484701 -256.731261) (xy 110.432396 -256.725223) (xy 110.381625 -256.711271)
			(xy 110.33358 -256.689732) (xy 110.289385 -256.661112) (xy 110.250077 -256.626081) (xy 110.216577 -256.58546)
			(xy 110.189671 -256.540201) (xy 110.169988 -256.491366) (xy 110.157991 -256.440098) (xy 110.153961 -256.3876)
			(xy 109.891322 -256.3876) (xy 109.890818 -256.413926) (xy 109.882781 -256.465962) (xy 109.866895 -256.516161)
			(xy 109.843532 -256.563346) (xy 109.81324 -256.606412) (xy 109.776728 -256.64435) (xy 109.734854 -256.676269)
			(xy 109.688598 -256.701422) (xy 109.639045 -256.71922) (xy 109.587355 -256.729244) (xy 109.534741 -256.731261)
			(xy 109.482436 -256.725223) (xy 109.431665 -256.711271) (xy 109.38362 -256.689732) (xy 109.339425 -256.661112)
			(xy 109.300117 -256.626081) (xy 109.266617 -256.58546) (xy 109.239711 -256.540201) (xy 109.220028 -256.491366)
			(xy 109.208031 -256.440098) (xy 109.204001 -256.3876) (xy 108.941362 -256.3876) (xy 108.940858 -256.413926)
			(xy 108.932821 -256.465962) (xy 108.916935 -256.516161) (xy 108.893572 -256.563346) (xy 108.86328 -256.606412)
			(xy 108.826768 -256.64435) (xy 108.784894 -256.676269) (xy 108.738638 -256.701422) (xy 108.689085 -256.71922)
			(xy 108.637395 -256.729244) (xy 108.584781 -256.731261) (xy 108.532476 -256.725223) (xy 108.481705 -256.711271)
			(xy 108.43366 -256.689732) (xy 108.389465 -256.661112) (xy 108.350157 -256.626081) (xy 108.316657 -256.58546)
			(xy 108.289751 -256.540201) (xy 108.270068 -256.491366) (xy 108.258071 -256.440098) (xy 108.254041 -256.3876)
			(xy 107.991402 -256.3876) (xy 107.990898 -256.413926) (xy 107.982861 -256.465962) (xy 107.966975 -256.516161)
			(xy 107.943612 -256.563346) (xy 107.91332 -256.606412) (xy 107.876808 -256.64435) (xy 107.834934 -256.676269)
			(xy 107.788678 -256.701422) (xy 107.739125 -256.71922) (xy 107.687435 -256.729244) (xy 107.634821 -256.731261)
			(xy 107.582516 -256.725223) (xy 107.531745 -256.711271) (xy 107.4837 -256.689732) (xy 107.439505 -256.661112)
			(xy 107.400197 -256.626081) (xy 107.366697 -256.58546) (xy 107.339791 -256.540201) (xy 107.320108 -256.491366)
			(xy 107.308111 -256.440098) (xy 107.304081 -256.3876) (xy 106.779822 -256.3876) (xy 107.3404 -256.948178)
			(xy 107.347798 -256.955027) (xy 107.366396 -256.962765) (xy 107.376468 -256.963164) (xy 108.935012 -256.963164)
			(xy 108.944855 -256.963689) (xy 108.963034 -256.971257) (xy 108.970318 -256.977896) (xy 109.737652 -257.74523)
			(xy 110.988351 -257.74523) (xy 110.992381 -257.692732) (xy 111.004378 -257.641464) (xy 111.024061 -257.592629)
			(xy 111.050967 -257.54737) (xy 111.084467 -257.506749) (xy 111.123775 -257.471718) (xy 111.16797 -257.443098)
			(xy 111.216015 -257.421559) (xy 111.266786 -257.407607) (xy 111.319091 -257.401569) (xy 111.371705 -257.403586)
			(xy 111.423395 -257.41361) (xy 111.472948 -257.431408) (xy 111.519204 -257.456561) (xy 111.561078 -257.48848)
			(xy 111.59759 -257.526418) (xy 111.627882 -257.569484) (xy 111.651245 -257.616669) (xy 111.667131 -257.666868)
			(xy 111.675168 -257.718904) (xy 111.675672 -257.74523) (xy 113.238283 -257.74523) (xy 113.242313 -257.692732)
			(xy 113.25431 -257.641464) (xy 113.273993 -257.592629) (xy 113.300899 -257.54737) (xy 113.334399 -257.506749)
			(xy 113.373707 -257.471718) (xy 113.417902 -257.443098) (xy 113.465947 -257.421559) (xy 113.516718 -257.407607)
			(xy 113.569023 -257.401569) (xy 113.621637 -257.403586) (xy 113.673327 -257.41361) (xy 113.72288 -257.431408)
			(xy 113.769136 -257.456561) (xy 113.81101 -257.48848) (xy 113.847522 -257.526418) (xy 113.877814 -257.569484)
			(xy 113.901177 -257.616669) (xy 113.917063 -257.666868) (xy 113.9251 -257.718904) (xy 113.925604 -257.74523)
			(xy 115.838227 -257.74523) (xy 115.842257 -257.692732) (xy 115.854254 -257.641464) (xy 115.873937 -257.592629)
			(xy 115.900843 -257.54737) (xy 115.934343 -257.506749) (xy 115.973651 -257.471718) (xy 116.017846 -257.443098)
			(xy 116.065891 -257.421559) (xy 116.116662 -257.407607) (xy 116.168967 -257.401569) (xy 116.221581 -257.403586)
			(xy 116.273271 -257.41361) (xy 116.319656 -257.43027) (xy 117.096797 -257.43027) (xy 117.100827 -257.377772)
			(xy 117.112824 -257.326504) (xy 117.132507 -257.277669) (xy 117.159413 -257.23241) (xy 117.192913 -257.191789)
			(xy 117.232221 -257.156758) (xy 117.276416 -257.128138) (xy 117.324461 -257.106599) (xy 117.375232 -257.092647)
			(xy 117.427537 -257.086609) (xy 117.480151 -257.088626) (xy 117.531841 -257.09865) (xy 117.581394 -257.116448)
			(xy 117.62765 -257.141601) (xy 117.669524 -257.17352) (xy 117.706036 -257.211458) (xy 117.736328 -257.254524)
			(xy 117.759691 -257.301709) (xy 117.775577 -257.351908) (xy 117.783614 -257.403944) (xy 117.784118 -257.43027)
			(xy 117.783614 -257.456596) (xy 117.775577 -257.508632) (xy 117.759691 -257.558831) (xy 117.736328 -257.606016)
			(xy 117.706036 -257.649082) (xy 117.669524 -257.68702) (xy 117.62765 -257.718939) (xy 117.581394 -257.744092)
			(xy 117.531841 -257.76189) (xy 117.480151 -257.771914) (xy 117.427537 -257.773931) (xy 117.375232 -257.767893)
			(xy 117.324461 -257.753941) (xy 117.276416 -257.732402) (xy 117.232221 -257.703782) (xy 117.192913 -257.668751)
			(xy 117.159413 -257.62813) (xy 117.132507 -257.582871) (xy 117.112824 -257.534036) (xy 117.100827 -257.482768)
			(xy 117.096797 -257.43027) (xy 116.319656 -257.43027) (xy 116.322824 -257.431408) (xy 116.36908 -257.456561)
			(xy 116.410954 -257.48848) (xy 116.447466 -257.526418) (xy 116.477758 -257.569484) (xy 116.501121 -257.616669)
			(xy 116.517007 -257.666868) (xy 116.525044 -257.718904) (xy 116.525548 -257.74523) (xy 116.525044 -257.771556)
			(xy 116.517007 -257.823592) (xy 116.501121 -257.873791) (xy 116.477758 -257.920976) (xy 116.471132 -257.930396)
			(xy 120.865649 -257.930396) (xy 120.869679 -257.877898) (xy 120.881676 -257.82663) (xy 120.901359 -257.777795)
			(xy 120.928265 -257.732536) (xy 120.961765 -257.691915) (xy 121.001073 -257.656884) (xy 121.045268 -257.628264)
			(xy 121.093313 -257.606725) (xy 121.144084 -257.592773) (xy 121.196389 -257.586735) (xy 121.249003 -257.588752)
			(xy 121.300693 -257.598776) (xy 121.350246 -257.616574) (xy 121.396502 -257.641727) (xy 121.438376 -257.673646)
			(xy 121.474888 -257.711584) (xy 121.50518 -257.75465) (xy 121.528543 -257.801835) (xy 121.544429 -257.852034)
			(xy 121.552466 -257.90407) (xy 121.55297 -257.930396) (xy 122.791223 -257.930396) (xy 122.795253 -257.877898)
			(xy 122.80725 -257.82663) (xy 122.826933 -257.777795) (xy 122.853839 -257.732536) (xy 122.887339 -257.691915)
			(xy 122.926647 -257.656884) (xy 122.970842 -257.628264) (xy 123.018887 -257.606725) (xy 123.069658 -257.592773)
			(xy 123.121963 -257.586735) (xy 123.174577 -257.588752) (xy 123.226267 -257.598776) (xy 123.27582 -257.616574)
			(xy 123.322076 -257.641727) (xy 123.36395 -257.673646) (xy 123.400462 -257.711584) (xy 123.430754 -257.75465)
			(xy 123.454117 -257.801835) (xy 123.470003 -257.852034) (xy 123.47804 -257.90407) (xy 123.478544 -257.930396)
			(xy 124.696223 -257.930396) (xy 124.700253 -257.877898) (xy 124.71225 -257.82663) (xy 124.731933 -257.777795)
			(xy 124.758839 -257.732536) (xy 124.792339 -257.691915) (xy 124.831647 -257.656884) (xy 124.875842 -257.628264)
			(xy 124.923887 -257.606725) (xy 124.974658 -257.592773) (xy 125.026963 -257.586735) (xy 125.079577 -257.588752)
			(xy 125.131267 -257.598776) (xy 125.18082 -257.616574) (xy 125.227076 -257.641727) (xy 125.26895 -257.673646)
			(xy 125.305462 -257.711584) (xy 125.335754 -257.75465) (xy 125.359117 -257.801835) (xy 125.375003 -257.852034)
			(xy 125.38304 -257.90407) (xy 125.383544 -257.930396) (xy 125.38304 -257.956722) (xy 125.375003 -258.008758)
			(xy 125.359117 -258.058957) (xy 125.335754 -258.106142) (xy 125.305462 -258.149208) (xy 125.26895 -258.187146)
			(xy 125.227076 -258.219065) (xy 125.18082 -258.244218) (xy 125.131267 -258.262016) (xy 125.079577 -258.27204)
			(xy 125.026963 -258.274057) (xy 124.974658 -258.268019) (xy 124.923887 -258.254067) (xy 124.875842 -258.232528)
			(xy 124.831647 -258.203908) (xy 124.792339 -258.168877) (xy 124.758839 -258.128256) (xy 124.731933 -258.082997)
			(xy 124.71225 -258.034162) (xy 124.700253 -257.982894) (xy 124.696223 -257.930396) (xy 123.478544 -257.930396)
			(xy 123.47804 -257.956722) (xy 123.470003 -258.008758) (xy 123.454117 -258.058957) (xy 123.430754 -258.106142)
			(xy 123.400462 -258.149208) (xy 123.36395 -258.187146) (xy 123.322076 -258.219065) (xy 123.27582 -258.244218)
			(xy 123.226267 -258.262016) (xy 123.174577 -258.27204) (xy 123.121963 -258.274057) (xy 123.069658 -258.268019)
			(xy 123.018887 -258.254067) (xy 122.970842 -258.232528) (xy 122.926647 -258.203908) (xy 122.887339 -258.168877)
			(xy 122.853839 -258.128256) (xy 122.826933 -258.082997) (xy 122.80725 -258.034162) (xy 122.795253 -257.982894)
			(xy 122.791223 -257.930396) (xy 121.55297 -257.930396) (xy 121.552466 -257.956722) (xy 121.544429 -258.008758)
			(xy 121.528543 -258.058957) (xy 121.50518 -258.106142) (xy 121.474888 -258.149208) (xy 121.438376 -258.187146)
			(xy 121.396502 -258.219065) (xy 121.350246 -258.244218) (xy 121.300693 -258.262016) (xy 121.249003 -258.27204)
			(xy 121.196389 -258.274057) (xy 121.144084 -258.268019) (xy 121.093313 -258.254067) (xy 121.045268 -258.232528)
			(xy 121.001073 -258.203908) (xy 120.961765 -258.168877) (xy 120.928265 -258.128256) (xy 120.901359 -258.082997)
			(xy 120.881676 -258.034162) (xy 120.869679 -257.982894) (xy 120.865649 -257.930396) (xy 116.471132 -257.930396)
			(xy 116.447466 -257.964042) (xy 116.410954 -258.00198) (xy 116.36908 -258.033899) (xy 116.322824 -258.059052)
			(xy 116.273271 -258.07685) (xy 116.221581 -258.086874) (xy 116.168967 -258.088891) (xy 116.116662 -258.082853)
			(xy 116.065891 -258.068901) (xy 116.017846 -258.047362) (xy 115.973651 -258.018742) (xy 115.934343 -257.983711)
			(xy 115.900843 -257.94309) (xy 115.873937 -257.897831) (xy 115.854254 -257.848996) (xy 115.842257 -257.797728)
			(xy 115.838227 -257.74523) (xy 113.925604 -257.74523) (xy 113.9251 -257.771556) (xy 113.917063 -257.823592)
			(xy 113.901177 -257.873791) (xy 113.877814 -257.920976) (xy 113.847522 -257.964042) (xy 113.81101 -258.00198)
			(xy 113.769136 -258.033899) (xy 113.72288 -258.059052) (xy 113.673327 -258.07685) (xy 113.621637 -258.086874)
			(xy 113.569023 -258.088891) (xy 113.516718 -258.082853) (xy 113.465947 -258.068901) (xy 113.417902 -258.047362)
			(xy 113.373707 -258.018742) (xy 113.334399 -257.983711) (xy 113.300899 -257.94309) (xy 113.273993 -257.897831)
			(xy 113.25431 -257.848996) (xy 113.242313 -257.797728) (xy 113.238283 -257.74523) (xy 111.675672 -257.74523)
			(xy 111.675168 -257.771556) (xy 111.667131 -257.823592) (xy 111.651245 -257.873791) (xy 111.627882 -257.920976)
			(xy 111.59759 -257.964042) (xy 111.561078 -258.00198) (xy 111.519204 -258.033899) (xy 111.472948 -258.059052)
			(xy 111.423395 -258.07685) (xy 111.371705 -258.086874) (xy 111.319091 -258.088891) (xy 111.266786 -258.082853)
			(xy 111.216015 -258.068901) (xy 111.16797 -258.047362) (xy 111.123775 -258.018742) (xy 111.084467 -257.983711)
			(xy 111.050967 -257.94309) (xy 111.024061 -257.897831) (xy 111.004378 -257.848996) (xy 110.992381 -257.797728)
			(xy 110.988351 -257.74523) (xy 109.737652 -257.74523) (xy 110.236 -258.243578) (xy 110.243398 -258.250427)
			(xy 110.261996 -258.258165) (xy 110.272068 -258.258564) (xy 111.475012 -258.258564) (xy 111.484855 -258.259089)
			(xy 111.503034 -258.266657) (xy 111.510318 -258.273296) (xy 111.617252 -258.38023) (xy 117.096797 -258.38023)
			(xy 117.100827 -258.327732) (xy 117.112824 -258.276464) (xy 117.132507 -258.227629) (xy 117.159413 -258.18237)
			(xy 117.192913 -258.141749) (xy 117.232221 -258.106718) (xy 117.276416 -258.078098) (xy 117.324461 -258.056559)
			(xy 117.375232 -258.042607) (xy 117.427537 -258.036569) (xy 117.480151 -258.038586) (xy 117.531841 -258.04861)
			(xy 117.581394 -258.066408) (xy 117.62765 -258.091561) (xy 117.669524 -258.12348) (xy 117.706036 -258.161418)
			(xy 117.736328 -258.204484) (xy 117.759691 -258.251669) (xy 117.775577 -258.301868) (xy 117.783614 -258.353904)
			(xy 117.784118 -258.38023) (xy 117.783614 -258.406556) (xy 117.775577 -258.458592) (xy 117.759691 -258.508791)
			(xy 117.736328 -258.555976) (xy 117.706036 -258.599042) (xy 117.669524 -258.63698) (xy 117.62765 -258.668899)
			(xy 117.581394 -258.694052) (xy 117.531841 -258.71185) (xy 117.480151 -258.721874) (xy 117.427537 -258.723891)
			(xy 117.375232 -258.717853) (xy 117.324461 -258.703901) (xy 117.276416 -258.682362) (xy 117.232221 -258.653742)
			(xy 117.192913 -258.618711) (xy 117.159413 -258.57809) (xy 117.132507 -258.532831) (xy 117.112824 -258.483996)
			(xy 117.100827 -258.432728) (xy 117.096797 -258.38023) (xy 111.617252 -258.38023) (xy 112.3696 -259.132578)
			(xy 112.376998 -259.139427) (xy 112.395596 -259.147165) (xy 112.405668 -259.147564) (xy 113.21669 -259.147564)
			(xy 113.225922 -259.147166) (xy 113.243187 -259.140621) (xy 113.257008 -259.128377) (xy 113.261648 -259.120386)
			(xy 113.3094 -259.030216) (xy 113.307622 -259.002022) (xy 113.299494 -258.990338) (xy 113.285148 -258.968716)
			(xy 113.262443 -258.922059) (xy 113.24703 -258.872513) (xy 113.23926 -258.82121) (xy 113.238788 -258.795266)
			(xy 113.239268 -258.769567) (xy 113.246929 -258.718743) (xy 113.262078 -258.669629) (xy 113.284379 -258.623321)
			(xy 113.313332 -258.580854) (xy 113.348292 -258.543177) (xy 113.388476 -258.511131) (xy 113.432988 -258.485432)
			(xy 113.480833 -258.466655) (xy 113.530942 -258.455217) (xy 113.582196 -258.451377) (xy 113.63345 -258.455217)
			(xy 113.683559 -258.466655) (xy 113.731404 -258.485432) (xy 113.775916 -258.511131) (xy 113.8161 -258.543177)
			(xy 113.85106 -258.580854) (xy 113.880013 -258.623321) (xy 113.902314 -258.669629) (xy 113.917463 -258.718743)
			(xy 113.925124 -258.769567) (xy 113.925604 -258.795266) (xy 113.925128 -258.821209) (xy 113.917328 -258.872504)
			(xy 113.901916 -258.922047) (xy 113.87924 -258.968715) (xy 113.864898 -258.990338) (xy 113.85677 -259.002022)
			(xy 113.854992 -259.030216) (xy 113.902744 -259.120386) (xy 113.907396 -259.128363) (xy 113.92122 -259.140584)
			(xy 113.938476 -259.147117) (xy 113.947702 -259.147564) (xy 115.816634 -259.147564) (xy 115.825862 -259.147159)
			(xy 115.843115 -259.140604) (xy 115.856923 -259.128357) (xy 115.861592 -259.120386) (xy 115.909344 -259.030216)
			(xy 115.907566 -259.002022) (xy 115.899438 -258.990338) (xy 115.88509 -258.968717) (xy 115.862383 -258.92206)
			(xy 115.846967 -258.872514) (xy 115.839196 -258.821211) (xy 115.838732 -258.795266) (xy 115.839212 -258.769567)
			(xy 115.846873 -258.718743) (xy 115.862022 -258.669629) (xy 115.884323 -258.623321) (xy 115.913276 -258.580854)
			(xy 115.948236 -258.543177) (xy 115.98842 -258.511131) (xy 116.032932 -258.485432) (xy 116.080777 -258.466655)
			(xy 116.130886 -258.455217) (xy 116.18214 -258.451377) (xy 116.233394 -258.455217) (xy 116.283503 -258.466655)
			(xy 116.331348 -258.485432) (xy 116.37586 -258.511131) (xy 116.416044 -258.543177) (xy 116.451004 -258.580854)
			(xy 116.479957 -258.623321) (xy 116.502258 -258.669629) (xy 116.517407 -258.718743) (xy 116.525068 -258.769567)
			(xy 116.525548 -258.795266) (xy 116.524991 -258.82335) (xy 116.523842 -258.830318) (xy 120.865649 -258.830318)
			(xy 120.869679 -258.77782) (xy 120.881676 -258.726552) (xy 120.901359 -258.677717) (xy 120.928265 -258.632458)
			(xy 120.961765 -258.591837) (xy 121.001073 -258.556806) (xy 121.045268 -258.528186) (xy 121.093313 -258.506647)
			(xy 121.144084 -258.492695) (xy 121.196389 -258.486657) (xy 121.249003 -258.488674) (xy 121.300693 -258.498698)
			(xy 121.350246 -258.516496) (xy 121.396502 -258.541649) (xy 121.438376 -258.573568) (xy 121.474888 -258.611506)
			(xy 121.50518 -258.654572) (xy 121.528543 -258.701757) (xy 121.544429 -258.751956) (xy 121.552466 -258.803992)
			(xy 121.55297 -258.830318) (xy 122.791223 -258.830318) (xy 122.795253 -258.77782) (xy 122.80725 -258.726552)
			(xy 122.826933 -258.677717) (xy 122.853839 -258.632458) (xy 122.887339 -258.591837) (xy 122.926647 -258.556806)
			(xy 122.970842 -258.528186) (xy 123.018887 -258.506647) (xy 123.069658 -258.492695) (xy 123.121963 -258.486657)
			(xy 123.174577 -258.488674) (xy 123.226267 -258.498698) (xy 123.27582 -258.516496) (xy 123.322076 -258.541649)
			(xy 123.36395 -258.573568) (xy 123.400462 -258.611506) (xy 123.430754 -258.654572) (xy 123.454117 -258.701757)
			(xy 123.470003 -258.751956) (xy 123.47804 -258.803992) (xy 123.478544 -258.830318) (xy 124.696223 -258.830318)
			(xy 124.700253 -258.77782) (xy 124.71225 -258.726552) (xy 124.731933 -258.677717) (xy 124.758839 -258.632458)
			(xy 124.792339 -258.591837) (xy 124.831647 -258.556806) (xy 124.875842 -258.528186) (xy 124.923887 -258.506647)
			(xy 124.974658 -258.492695) (xy 125.026963 -258.486657) (xy 125.079577 -258.488674) (xy 125.131267 -258.498698)
			(xy 125.18082 -258.516496) (xy 125.227076 -258.541649) (xy 125.26895 -258.573568) (xy 125.305462 -258.611506)
			(xy 125.335754 -258.654572) (xy 125.359117 -258.701757) (xy 125.375003 -258.751956) (xy 125.38304 -258.803992)
			(xy 125.383544 -258.830318) (xy 125.38304 -258.856644) (xy 125.375003 -258.90868) (xy 125.359117 -258.958879)
			(xy 125.335754 -259.006064) (xy 125.305462 -259.04913) (xy 125.26895 -259.087068) (xy 125.227076 -259.118987)
			(xy 125.18082 -259.14414) (xy 125.131267 -259.161938) (xy 125.079577 -259.171962) (xy 125.026963 -259.173979)
			(xy 124.974658 -259.167941) (xy 124.923887 -259.153989) (xy 124.875842 -259.13245) (xy 124.831647 -259.10383)
			(xy 124.792339 -259.068799) (xy 124.758839 -259.028178) (xy 124.731933 -258.982919) (xy 124.71225 -258.934084)
			(xy 124.700253 -258.882816) (xy 124.696223 -258.830318) (xy 123.478544 -258.830318) (xy 123.47804 -258.856644)
			(xy 123.470003 -258.90868) (xy 123.454117 -258.958879) (xy 123.430754 -259.006064) (xy 123.400462 -259.04913)
			(xy 123.36395 -259.087068) (xy 123.322076 -259.118987) (xy 123.27582 -259.14414) (xy 123.226267 -259.161938)
			(xy 123.174577 -259.171962) (xy 123.121963 -259.173979) (xy 123.069658 -259.167941) (xy 123.018887 -259.153989)
			(xy 122.970842 -259.13245) (xy 122.926647 -259.10383) (xy 122.887339 -259.068799) (xy 122.853839 -259.028178)
			(xy 122.826933 -258.982919) (xy 122.80725 -258.934084) (xy 122.795253 -258.882816) (xy 122.791223 -258.830318)
			(xy 121.55297 -258.830318) (xy 121.552466 -258.856644) (xy 121.544429 -258.90868) (xy 121.528543 -258.958879)
			(xy 121.50518 -259.006064) (xy 121.474888 -259.04913) (xy 121.438376 -259.087068) (xy 121.396502 -259.118987)
			(xy 121.350246 -259.14414) (xy 121.300693 -259.161938) (xy 121.249003 -259.171962) (xy 121.196389 -259.173979)
			(xy 121.144084 -259.167941) (xy 121.093313 -259.153989) (xy 121.045268 -259.13245) (xy 121.001073 -259.10383)
			(xy 120.961765 -259.068799) (xy 120.928265 -259.028178) (xy 120.901359 -258.982919) (xy 120.881676 -258.934084)
			(xy 120.869679 -258.882816) (xy 120.865649 -258.830318) (xy 116.523842 -258.830318) (xy 116.515854 -258.878771)
			(xy 116.497818 -258.931965) (xy 116.471365 -258.981515) (xy 116.437199 -259.026098) (xy 116.41709 -259.04571)
			(xy 116.40947 -259.052822) (xy 116.401342 -259.071364) (xy 116.399818 -259.152898) (xy 116.400092 -259.163226)
			(xy 116.407827 -259.182362) (xy 116.414804 -259.189982) (xy 116.555266 -259.330444) (xy 117.096797 -259.330444)
			(xy 117.100827 -259.277946) (xy 117.112824 -259.226678) (xy 117.132507 -259.177843) (xy 117.159413 -259.132584)
			(xy 117.192913 -259.091963) (xy 117.232221 -259.056932) (xy 117.276416 -259.028312) (xy 117.324461 -259.006773)
			(xy 117.375232 -258.992821) (xy 117.427537 -258.986783) (xy 117.480151 -258.9888) (xy 117.531841 -258.998824)
			(xy 117.581394 -259.016622) (xy 117.62765 -259.041775) (xy 117.669524 -259.073694) (xy 117.706036 -259.111632)
			(xy 117.736328 -259.154698) (xy 117.759691 -259.201883) (xy 117.775577 -259.252082) (xy 117.783614 -259.304118)
			(xy 117.784118 -259.330444) (xy 117.783614 -259.35677) (xy 117.775577 -259.408806) (xy 117.759691 -259.459005)
			(xy 117.736328 -259.50619) (xy 117.706036 -259.549256) (xy 117.669524 -259.587194) (xy 117.62765 -259.619113)
			(xy 117.581394 -259.644266) (xy 117.531841 -259.662064) (xy 117.480151 -259.672088) (xy 117.427537 -259.674105)
			(xy 117.375232 -259.668067) (xy 117.324461 -259.654115) (xy 117.276416 -259.632576) (xy 117.232221 -259.603956)
			(xy 117.192913 -259.568925) (xy 117.159413 -259.528304) (xy 117.132507 -259.483045) (xy 117.112824 -259.43421)
			(xy 117.100827 -259.382942) (xy 117.096797 -259.330444) (xy 116.555266 -259.330444) (xy 116.723922 -259.4991)
			(xy 116.730636 -259.506338) (xy 116.738233 -259.524543) (xy 116.738654 -259.534406) (xy 116.738654 -259.73024)
			(xy 120.865649 -259.73024) (xy 120.869679 -259.677742) (xy 120.881676 -259.626474) (xy 120.901359 -259.577639)
			(xy 120.928265 -259.53238) (xy 120.961765 -259.491759) (xy 121.001073 -259.456728) (xy 121.045268 -259.428108)
			(xy 121.093313 -259.406569) (xy 121.144084 -259.392617) (xy 121.196389 -259.386579) (xy 121.249003 -259.388596)
			(xy 121.300693 -259.39862) (xy 121.350246 -259.416418) (xy 121.396502 -259.441571) (xy 121.438376 -259.47349)
			(xy 121.474888 -259.511428) (xy 121.50518 -259.554494) (xy 121.528543 -259.601679) (xy 121.544429 -259.651878)
			(xy 121.552466 -259.703914) (xy 121.55297 -259.73024) (xy 122.791223 -259.73024) (xy 122.795253 -259.677742)
			(xy 122.80725 -259.626474) (xy 122.826933 -259.577639) (xy 122.853839 -259.53238) (xy 122.887339 -259.491759)
			(xy 122.926647 -259.456728) (xy 122.970842 -259.428108) (xy 123.018887 -259.406569) (xy 123.069658 -259.392617)
			(xy 123.121963 -259.386579) (xy 123.174577 -259.388596) (xy 123.226267 -259.39862) (xy 123.27582 -259.416418)
			(xy 123.322076 -259.441571) (xy 123.36395 -259.47349) (xy 123.400462 -259.511428) (xy 123.430754 -259.554494)
			(xy 123.454117 -259.601679) (xy 123.470003 -259.651878) (xy 123.47804 -259.703914) (xy 123.478544 -259.73024)
			(xy 124.696223 -259.73024) (xy 124.700253 -259.677742) (xy 124.71225 -259.626474) (xy 124.731933 -259.577639)
			(xy 124.758839 -259.53238) (xy 124.792339 -259.491759) (xy 124.831647 -259.456728) (xy 124.875842 -259.428108)
			(xy 124.923887 -259.406569) (xy 124.974658 -259.392617) (xy 125.026963 -259.386579) (xy 125.079577 -259.388596)
			(xy 125.131267 -259.39862) (xy 125.18082 -259.416418) (xy 125.227076 -259.441571) (xy 125.26895 -259.47349)
			(xy 125.305462 -259.511428) (xy 125.335754 -259.554494) (xy 125.359117 -259.601679) (xy 125.375003 -259.651878)
			(xy 125.38304 -259.703914) (xy 125.383544 -259.73024) (xy 125.38304 -259.756566) (xy 125.375003 -259.808602)
			(xy 125.359117 -259.858801) (xy 125.335754 -259.905986) (xy 125.305462 -259.949052) (xy 125.26895 -259.98699)
			(xy 125.227076 -260.018909) (xy 125.18082 -260.044062) (xy 125.131267 -260.06186) (xy 125.079577 -260.071884)
			(xy 125.026963 -260.073901) (xy 124.974658 -260.067863) (xy 124.923887 -260.053911) (xy 124.875842 -260.032372)
			(xy 124.831647 -260.003752) (xy 124.792339 -259.968721) (xy 124.758839 -259.9281) (xy 124.731933 -259.882841)
			(xy 124.71225 -259.834006) (xy 124.700253 -259.782738) (xy 124.696223 -259.73024) (xy 123.478544 -259.73024)
			(xy 123.47804 -259.756566) (xy 123.470003 -259.808602) (xy 123.454117 -259.858801) (xy 123.430754 -259.905986)
			(xy 123.400462 -259.949052) (xy 123.36395 -259.98699) (xy 123.322076 -260.018909) (xy 123.27582 -260.044062)
			(xy 123.226267 -260.06186) (xy 123.174577 -260.071884) (xy 123.121963 -260.073901) (xy 123.069658 -260.067863)
			(xy 123.018887 -260.053911) (xy 122.970842 -260.032372) (xy 122.926647 -260.003752) (xy 122.887339 -259.968721)
			(xy 122.853839 -259.9281) (xy 122.826933 -259.882841) (xy 122.80725 -259.834006) (xy 122.795253 -259.782738)
			(xy 122.791223 -259.73024) (xy 121.55297 -259.73024) (xy 121.552466 -259.756566) (xy 121.544429 -259.808602)
			(xy 121.528543 -259.858801) (xy 121.50518 -259.905986) (xy 121.474888 -259.949052) (xy 121.438376 -259.98699)
			(xy 121.396502 -260.018909) (xy 121.350246 -260.044062) (xy 121.300693 -260.06186) (xy 121.249003 -260.071884)
			(xy 121.196389 -260.073901) (xy 121.144084 -260.067863) (xy 121.093313 -260.053911) (xy 121.045268 -260.032372)
			(xy 121.001073 -260.003752) (xy 120.961765 -259.968721) (xy 120.928265 -259.9281) (xy 120.901359 -259.882841)
			(xy 120.881676 -259.834006) (xy 120.869679 -259.782738) (xy 120.865649 -259.73024) (xy 116.738654 -259.73024)
			(xy 116.738654 -260.280404) (xy 117.096797 -260.280404) (xy 117.100827 -260.227906) (xy 117.112824 -260.176638)
			(xy 117.132507 -260.127803) (xy 117.159413 -260.082544) (xy 117.192913 -260.041923) (xy 117.232221 -260.006892)
			(xy 117.276416 -259.978272) (xy 117.324461 -259.956733) (xy 117.375232 -259.942781) (xy 117.427537 -259.936743)
			(xy 117.480151 -259.93876) (xy 117.531841 -259.948784) (xy 117.581394 -259.966582) (xy 117.62765 -259.991735)
			(xy 117.669524 -260.023654) (xy 117.706036 -260.061592) (xy 117.736328 -260.104658) (xy 117.759691 -260.151843)
			(xy 117.775577 -260.202042) (xy 117.783614 -260.254078) (xy 117.784118 -260.280404) (xy 117.783614 -260.30673)
			(xy 117.775577 -260.358766) (xy 117.759691 -260.408965) (xy 117.736328 -260.45615) (xy 117.706036 -260.499216)
			(xy 117.669524 -260.537154) (xy 117.62765 -260.569073) (xy 117.581394 -260.594226) (xy 117.531841 -260.612024)
			(xy 117.480151 -260.622048) (xy 117.427537 -260.624065) (xy 117.375232 -260.618027) (xy 117.324461 -260.604075)
			(xy 117.276416 -260.582536) (xy 117.232221 -260.553916) (xy 117.192913 -260.518885) (xy 117.159413 -260.478264)
			(xy 117.132507 -260.433005) (xy 117.112824 -260.38417) (xy 117.100827 -260.332902) (xy 117.096797 -260.280404)
			(xy 116.738654 -260.280404) (xy 116.738654 -261.20217) (xy 116.739091 -261.212233) (xy 116.74683 -261.230814)
			(xy 116.75364 -261.238238) (xy 117.0432 -261.527798) (xy 117.050598 -261.534645) (xy 117.069196 -261.54238)
			(xy 117.079268 -261.542784) (xy 117.114574 -261.542784) (xy 117.124325 -261.542362) (xy 117.142417 -261.535085)
			(xy 117.156453 -261.521549) (xy 117.160802 -261.512812) (xy 117.170454 -261.49173) (xy 117.174018 -261.482868)
			(xy 117.174945 -261.463803) (xy 117.172232 -261.454646) (xy 117.16639 -261.43712) (xy 117.162072 -261.431024)
			(xy 117.146817 -261.408978) (xy 117.122615 -261.361143) (xy 117.106148 -261.310126) (xy 117.097815 -261.257168)
			(xy 117.097302 -261.230364) (xy 117.097302 -261.222998) (xy 117.098369 -261.196391) (xy 117.107706 -261.143969)
			(xy 117.125022 -261.093616) (xy 117.149904 -261.046541) (xy 117.181754 -261.00387) (xy 117.21981 -260.966627)
			(xy 117.263158 -260.935705) (xy 117.31076 -260.911845) (xy 117.361475 -260.89562) (xy 117.414086 -260.887417)
			(xy 117.44071 -260.886956) (xy 117.467696 -260.887486) (xy 117.521002 -260.89593) (xy 117.572332 -260.912608)
			(xy 117.620421 -260.93711) (xy 117.664086 -260.968832) (xy 117.702251 -261.006994) (xy 117.733976 -261.050657)
			(xy 117.758482 -261.098744) (xy 117.767413 -261.126224) (xy 121.638834 -261.126224) (xy 121.642794 -261.07717)
			(xy 121.654571 -261.029386) (xy 121.673862 -260.98411) (xy 121.700165 -260.942514) (xy 121.7328 -260.905677)
			(xy 121.770921 -260.874552) (xy 121.813542 -260.849945) (xy 121.859558 -260.832493) (xy 121.907777 -260.822649)
			(xy 121.956952 -260.820668) (xy 122.005807 -260.8266) (xy 122.053078 -260.840292) (xy 122.09754 -260.86139)
			(xy 122.138043 -260.889346) (xy 122.173536 -260.923438) (xy 122.203101 -260.962782) (xy 122.225972 -261.006359)
			(xy 122.241556 -261.05304) (xy 122.249451 -261.101617) (xy 122.249946 -261.126224) (xy 123.518942 -261.126224)
			(xy 123.522902 -261.07717) (xy 123.534679 -261.029386) (xy 123.55397 -260.98411) (xy 123.580273 -260.942514)
			(xy 123.612908 -260.905677) (xy 123.651029 -260.874552) (xy 123.69365 -260.849945) (xy 123.739666 -260.832493)
			(xy 123.787885 -260.822649) (xy 123.83706 -260.820668) (xy 123.885915 -260.8266) (xy 123.933186 -260.840292)
			(xy 123.977648 -260.86139) (xy 124.018151 -260.889346) (xy 124.053644 -260.923438) (xy 124.083209 -260.962782)
			(xy 124.10608 -261.006359) (xy 124.121664 -261.05304) (xy 124.129559 -261.101617) (xy 124.130054 -261.126224)
			(xy 125.39905 -261.126224) (xy 125.40301 -261.07717) (xy 125.414787 -261.029386) (xy 125.434078 -260.98411)
			(xy 125.460381 -260.942514) (xy 125.493016 -260.905677) (xy 125.531137 -260.874552) (xy 125.573758 -260.849945)
			(xy 125.619774 -260.832493) (xy 125.667993 -260.822649) (xy 125.717168 -260.820668) (xy 125.766023 -260.8266)
			(xy 125.813294 -260.840292) (xy 125.857756 -260.86139) (xy 125.898259 -260.889346) (xy 125.933752 -260.923438)
			(xy 125.963317 -260.962782) (xy 125.986188 -261.006359) (xy 126.001772 -261.05304) (xy 126.009667 -261.101617)
			(xy 126.010162 -261.126224) (xy 126.009667 -261.150831) (xy 126.001772 -261.199408) (xy 125.986188 -261.246089)
			(xy 125.963317 -261.289666) (xy 125.933752 -261.32901) (xy 125.898259 -261.363102) (xy 125.857756 -261.391058)
			(xy 125.813294 -261.412156) (xy 125.766023 -261.425848) (xy 125.717168 -261.43178) (xy 125.667993 -261.429799)
			(xy 125.619774 -261.419955) (xy 125.573758 -261.402503) (xy 125.531137 -261.377896) (xy 125.493016 -261.346771)
			(xy 125.460381 -261.309934) (xy 125.434078 -261.268338) (xy 125.414787 -261.223062) (xy 125.40301 -261.175278)
			(xy 125.39905 -261.126224) (xy 124.130054 -261.126224) (xy 124.129559 -261.150831) (xy 124.121664 -261.199408)
			(xy 124.10608 -261.246089) (xy 124.083209 -261.289666) (xy 124.053644 -261.32901) (xy 124.018151 -261.363102)
			(xy 123.977648 -261.391058) (xy 123.933186 -261.412156) (xy 123.885915 -261.425848) (xy 123.83706 -261.43178)
			(xy 123.787885 -261.429799) (xy 123.739666 -261.419955) (xy 123.69365 -261.402503) (xy 123.651029 -261.377896)
			(xy 123.612908 -261.346771) (xy 123.580273 -261.309934) (xy 123.55397 -261.268338) (xy 123.534679 -261.223062)
			(xy 123.522902 -261.175278) (xy 123.518942 -261.126224) (xy 122.249946 -261.126224) (xy 122.249451 -261.150831)
			(xy 122.241556 -261.199408) (xy 122.225972 -261.246089) (xy 122.203101 -261.289666) (xy 122.173536 -261.32901)
			(xy 122.138043 -261.363102) (xy 122.09754 -261.391058) (xy 122.053078 -261.412156) (xy 122.005807 -261.425848)
			(xy 121.956952 -261.43178) (xy 121.907777 -261.429799) (xy 121.859558 -261.419955) (xy 121.813542 -261.402503)
			(xy 121.770921 -261.377896) (xy 121.7328 -261.346771) (xy 121.700165 -261.309934) (xy 121.673862 -261.268338)
			(xy 121.654571 -261.223062) (xy 121.642794 -261.175278) (xy 121.638834 -261.126224) (xy 117.767413 -261.126224)
			(xy 117.775164 -261.150072) (xy 117.783612 -261.203378) (xy 117.784118 -261.230364) (xy 117.783578 -261.258893)
			(xy 117.774181 -261.315171) (xy 117.755592 -261.369114) (xy 117.742462 -261.394448) (xy 117.735858 -261.406386)
			(xy 117.736366 -261.432802) (xy 117.786658 -261.517892) (xy 117.791455 -261.525272) (xy 117.805006 -261.536485)
			(xy 117.821552 -261.542453) (xy 117.830346 -261.542784) (xy 118.05793 -261.542784) (xy 118.065451 -261.543074)
			(xy 118.079799 -261.547595) (xy 118.086124 -261.551674) (xy 118.092728 -261.555992) (xy 118.106952 -261.560564)
			(xy 119.09171 -261.560564) (xy 119.101553 -261.561088) (xy 119.119733 -261.568656) (xy 119.127016 -261.575296)
			(xy 119.732298 -262.180578) (xy 119.739695 -262.187427) (xy 119.758294 -262.195166) (xy 119.768366 -262.195564)
			(xy 122.041666 -262.195564) (xy 122.054312 -262.194896) (xy 122.076581 -262.182905) (xy 122.084084 -262.172704)
			(xy 122.136662 -262.092694) (xy 122.138948 -262.067548) (xy 122.133868 -262.055864) (xy 122.122511 -262.027268)
			(xy 122.110217 -261.96699) (xy 122.109484 -261.93623) (xy 122.110006 -261.910975) (xy 122.118319 -261.861153)
			(xy 122.13472 -261.813379) (xy 122.158761 -261.768956) (xy 122.189785 -261.729096) (xy 122.226947 -261.694886)
			(xy 122.269233 -261.66726) (xy 122.315489 -261.64697) (xy 122.364454 -261.63457) (xy 122.414792 -261.630399)
			(xy 122.46513 -261.63457) (xy 122.514095 -261.64697) (xy 122.560351 -261.66726) (xy 122.602637 -261.694886)
			(xy 122.639799 -261.729096) (xy 122.670823 -261.768956) (xy 122.694864 -261.813379) (xy 122.711265 -261.861153)
			(xy 122.719578 -261.910975) (xy 122.7201 -261.93623) (xy 123.988842 -261.93623) (xy 123.992802 -261.887176)
			(xy 124.004579 -261.839392) (xy 124.02387 -261.794116) (xy 124.050173 -261.75252) (xy 124.082808 -261.715683)
			(xy 124.120929 -261.684558) (xy 124.16355 -261.659951) (xy 124.209566 -261.642499) (xy 124.257785 -261.632655)
			(xy 124.30696 -261.630674) (xy 124.355815 -261.636606) (xy 124.403086 -261.650298) (xy 124.447548 -261.671396)
			(xy 124.488051 -261.699352) (xy 124.523544 -261.733444) (xy 124.553109 -261.772788) (xy 124.57598 -261.816365)
			(xy 124.591564 -261.863046) (xy 124.599459 -261.911623) (xy 124.599954 -261.93623) (xy 125.86895 -261.93623)
			(xy 125.87291 -261.887176) (xy 125.884687 -261.839392) (xy 125.903978 -261.794116) (xy 125.930281 -261.75252)
			(xy 125.962916 -261.715683) (xy 126.001037 -261.684558) (xy 126.043658 -261.659951) (xy 126.089674 -261.642499)
			(xy 126.137893 -261.632655) (xy 126.187068 -261.630674) (xy 126.235923 -261.636606) (xy 126.283194 -261.650298)
			(xy 126.327656 -261.671396) (xy 126.368159 -261.699352) (xy 126.403652 -261.733444) (xy 126.433217 -261.772788)
			(xy 126.456088 -261.816365) (xy 126.471672 -261.863046) (xy 126.479567 -261.911623) (xy 126.480062 -261.93623)
			(xy 126.479567 -261.960837) (xy 126.471672 -262.009414) (xy 126.456088 -262.056095) (xy 126.433217 -262.099672)
			(xy 126.403652 -262.139016) (xy 126.368159 -262.173108) (xy 126.327656 -262.201064) (xy 126.283194 -262.222162)
			(xy 126.235923 -262.235854) (xy 126.187068 -262.241786) (xy 126.137893 -262.239805) (xy 126.089674 -262.229961)
			(xy 126.043658 -262.212509) (xy 126.001037 -262.187902) (xy 125.962916 -262.156777) (xy 125.930281 -262.11994)
			(xy 125.903978 -262.078344) (xy 125.884687 -262.033068) (xy 125.87291 -261.985284) (xy 125.86895 -261.93623)
			(xy 124.599954 -261.93623) (xy 124.599459 -261.960837) (xy 124.591564 -262.009414) (xy 124.57598 -262.056095)
			(xy 124.553109 -262.099672) (xy 124.523544 -262.139016) (xy 124.488051 -262.173108) (xy 124.447548 -262.201064)
			(xy 124.403086 -262.222162) (xy 124.355815 -262.235854) (xy 124.30696 -262.241786) (xy 124.257785 -262.239805)
			(xy 124.209566 -262.229961) (xy 124.16355 -262.212509) (xy 124.120929 -262.187902) (xy 124.082808 -262.156777)
			(xy 124.050173 -262.11994) (xy 124.02387 -262.078344) (xy 124.004579 -262.033068) (xy 123.992802 -261.985284)
			(xy 123.988842 -261.93623) (xy 122.7201 -261.93623) (xy 122.71934 -261.966988) (xy 122.707062 -262.027266)
			(xy 122.695716 -262.055864) (xy 122.690636 -262.067548) (xy 122.692922 -262.092694) (xy 122.7455 -262.172704)
			(xy 122.753024 -262.182878) (xy 122.775282 -262.194846) (xy 122.787918 -262.195564) (xy 123.40971 -262.195564)
			(xy 123.419553 -262.196088) (xy 123.437733 -262.203656) (xy 123.445016 -262.210296) (xy 123.688602 -262.453882)
			(xy 123.716288 -262.460486) (xy 123.730004 -262.455914) (xy 123.753055 -262.448888) (xy 123.800651 -262.441356)
			(xy 123.824746 -262.440928) (xy 123.848734 -262.441402) (xy 123.896118 -262.448914) (xy 123.941743 -262.463746)
			(xy 123.984487 -262.485533) (xy 124.023296 -262.513737) (xy 124.057216 -262.547666) (xy 124.08541 -262.586483)
			(xy 124.107185 -262.629232) (xy 124.122005 -262.674862) (xy 124.129504 -262.722248) (xy 124.130054 -262.746236)
			(xy 124.129622 -262.77033) (xy 124.122097 -262.817928) (xy 124.115068 -262.840978) (xy 124.110496 -262.854694)
			(xy 124.1171 -262.88238) (xy 124.304298 -263.069578) (xy 124.311695 -263.076427) (xy 124.330294 -263.084166)
			(xy 124.340366 -263.084564)
		)
		(stroke
			(width 0)
			(type solid)
		)
		(fill yes)
		(layer "In2.Cu")
		(net "PVDDCR_SOC_P1")
	)
	(gr_poly
		(pts
			(xy 250.810268 -319.879472) (xy 250.820332 -319.879036) (xy 250.838916 -319.871301) (xy 250.846336 -319.864486)
			(xy 253.38151 -317.329312) (xy 253.388368 -317.321918) (xy 253.396121 -317.303319) (xy 253.396496 -317.293244)
			(xy 253.396496 -269.599664) (xy 253.39548 -269.589758) (xy 252.842776 -266.812014) (xy 252.841034 -266.804677)
			(xy 252.833936 -266.791379) (xy 252.828806 -266.785852) (xy 251.877576 -265.834622) (xy 251.870464 -265.827256)
			(xy 251.851668 -265.819636) (xy 251.84227 -265.819636) (xy 251.823728 -265.812016) (xy 242.104672 -256.09296)
			(xy 242.097275 -256.086112) (xy 242.078676 -256.078378) (xy 242.068604 -256.077974) (xy 219.909644 -256.077974)
			(xy 219.899578 -256.078407) (xy 219.880986 -256.086132) (xy 219.873576 -256.09296) (xy 218.580208 -257.386328)
			(xy 218.573365 -257.393728) (xy 218.56564 -257.412326) (xy 218.565222 -257.422396) (xy 218.565222 -269.770955)
			(xy 221.508737 -269.770955) (xy 221.508737 -269.716445) (xy 221.516495 -269.662489) (xy 221.531853 -269.610186)
			(xy 221.554499 -269.560602) (xy 221.583971 -269.514745) (xy 221.619669 -269.473549) (xy 221.660867 -269.437854)
			(xy 221.706726 -269.408385) (xy 221.756312 -269.385743) (xy 221.808616 -269.370389) (xy 221.862573 -269.362635)
			(xy 221.889828 -269.362174) (xy 221.918744 -269.362716) (xy 221.975916 -269.371436) (xy 222.031115 -269.388688)
			(xy 222.083078 -269.414075) (xy 222.130612 -269.447016) (xy 222.172628 -269.486755) (xy 222.190818 -269.50924)
			(xy 222.19837 -269.518012) (xy 222.219136 -269.528188) (xy 222.230696 -269.528798) (xy 222.31096 -269.528798)
			(xy 222.322525 -269.528205) (xy 222.343296 -269.518027) (xy 222.350838 -269.50924) (xy 222.367591 -269.488457)
			(xy 222.405945 -269.451327) (xy 222.449099 -269.419905) (xy 222.496213 -269.394806) (xy 222.546365 -269.37652)
			(xy 222.598576 -269.365403) (xy 222.651828 -269.361673) (xy 222.70508 -269.365403) (xy 222.757291 -269.37652)
			(xy 222.807443 -269.394806) (xy 222.854557 -269.419905) (xy 222.897711 -269.451327) (xy 222.936065 -269.488457)
			(xy 222.952818 -269.50924) (xy 222.96037 -269.518012) (xy 222.981136 -269.528188) (xy 222.992696 -269.528798)
			(xy 223.07296 -269.528798) (xy 223.084525 -269.528205) (xy 223.105296 -269.518027) (xy 223.112838 -269.50924)
			(xy 223.129591 -269.488457) (xy 223.167945 -269.451327) (xy 223.211099 -269.419905) (xy 223.258213 -269.394806)
			(xy 223.308365 -269.37652) (xy 223.360576 -269.365403) (xy 223.413828 -269.361673) (xy 223.46708 -269.365403)
			(xy 223.519291 -269.37652) (xy 223.569443 -269.394806) (xy 223.616557 -269.419905) (xy 223.659711 -269.451327)
			(xy 223.698065 -269.488457) (xy 223.714818 -269.50924) (xy 223.72237 -269.518012) (xy 223.743136 -269.528188)
			(xy 223.754696 -269.528798) (xy 223.83496 -269.528798) (xy 223.846525 -269.528205) (xy 223.867296 -269.518027)
			(xy 223.874838 -269.50924) (xy 223.893018 -269.486747) (xy 223.935039 -269.44701) (xy 223.982575 -269.414071)
			(xy 224.034539 -269.388684) (xy 224.089739 -269.371431) (xy 224.146911 -269.362706) (xy 224.175828 -269.362174)
			(xy 224.203077 -269.362698) (xy 224.257019 -269.370458) (xy 224.309308 -269.385814) (xy 224.358879 -269.408456)
			(xy 224.404724 -269.437922) (xy 224.445908 -269.473611) (xy 224.481595 -269.514799) (xy 224.511057 -269.560646)
			(xy 224.533695 -269.610219) (xy 224.549048 -269.662509) (xy 224.556804 -269.716451) (xy 224.556804 -269.770949)
			(xy 224.549048 -269.824891) (xy 224.533695 -269.877181) (xy 224.511057 -269.926754) (xy 224.481595 -269.972601)
			(xy 224.445908 -270.013789) (xy 224.404724 -270.049478) (xy 224.358879 -270.078944) (xy 224.309308 -270.101586)
			(xy 224.257019 -270.116942) (xy 224.203077 -270.124702) (xy 224.175828 -270.12519) (xy 224.146912 -270.124655)
			(xy 224.089741 -270.11593) (xy 224.034542 -270.098676) (xy 223.982581 -270.073287) (xy 223.935046 -270.040346)
			(xy 223.893029 -270.000608) (xy 223.874838 -269.978124) (xy 223.867268 -269.969371) (xy 223.846515 -269.959186)
			(xy 223.83496 -269.958566) (xy 223.754696 -269.958566) (xy 223.743124 -269.959111) (xy 223.722352 -269.969321)
			(xy 223.714818 -269.978124) (xy 223.698065 -269.998907) (xy 223.659711 -270.036037) (xy 223.616557 -270.067459)
			(xy 223.569443 -270.092558) (xy 223.519291 -270.110844) (xy 223.46708 -270.121961) (xy 223.413828 -270.125691)
			(xy 223.360576 -270.121961) (xy 223.308365 -270.110844) (xy 223.258213 -270.092558) (xy 223.211099 -270.067459)
			(xy 223.167945 -270.036037) (xy 223.129591 -269.998907) (xy 223.112838 -269.978124) (xy 223.105268 -269.969371)
			(xy 223.084515 -269.959186) (xy 223.07296 -269.958566) (xy 222.992696 -269.958566) (xy 222.981124 -269.959111)
			(xy 222.960352 -269.969321) (xy 222.952818 -269.978124) (xy 222.936065 -269.998907) (xy 222.897711 -270.036037)
			(xy 222.854557 -270.067459) (xy 222.807443 -270.092558) (xy 222.757291 -270.110844) (xy 222.70508 -270.121961)
			(xy 222.651828 -270.125691) (xy 222.598576 -270.121961) (xy 222.546365 -270.110844) (xy 222.496213 -270.092558)
			(xy 222.449099 -270.067459) (xy 222.405945 -270.036037) (xy 222.367591 -269.998907) (xy 222.350838 -269.978124)
			(xy 222.343268 -269.969371) (xy 222.322515 -269.959186) (xy 222.31096 -269.958566) (xy 222.230696 -269.958566)
			(xy 222.219124 -269.959111) (xy 222.198352 -269.969321) (xy 222.190818 -269.978124) (xy 222.172623 -270.000604)
			(xy 222.130603 -270.040338) (xy 222.083069 -270.073277) (xy 222.031109 -270.098666) (xy 221.975912 -270.115923)
			(xy 221.918744 -270.124654) (xy 221.889828 -270.12519) (xy 221.862573 -270.124765) (xy 221.808616 -270.117011)
			(xy 221.756312 -270.101657) (xy 221.706726 -270.079015) (xy 221.660867 -270.049546) (xy 221.619669 -270.013851)
			(xy 221.583971 -269.972655) (xy 221.554499 -269.926798) (xy 221.531853 -269.877214) (xy 221.516495 -269.824911)
			(xy 221.508737 -269.770955) (xy 218.565222 -269.770955) (xy 218.565222 -271.407389) (xy 221.507795 -271.407389)
			(xy 221.511527 -271.354135) (xy 221.522646 -271.301921) (xy 221.540936 -271.251767) (xy 221.566039 -271.204652)
			(xy 221.597465 -271.161497) (xy 221.6346 -271.123145) (xy 221.655386 -271.106392) (xy 221.664145 -271.098827)
			(xy 221.674331 -271.078071) (xy 221.674944 -271.066514) (xy 221.674944 -270.98625) (xy 221.674365 -270.974683)
			(xy 221.664178 -270.95391) (xy 221.655386 -270.946372) (xy 221.632886 -270.9282) (xy 221.593153 -270.886176)
			(xy 221.560216 -270.838637) (xy 221.534831 -270.786672) (xy 221.517578 -270.731471) (xy 221.508853 -270.674299)
			(xy 221.50832 -270.645382) (xy 221.508738 -270.618127) (xy 221.516498 -270.564173) (xy 221.531858 -270.511873)
			(xy 221.554505 -270.462291) (xy 221.583977 -270.416436) (xy 221.619676 -270.375243) (xy 221.660873 -270.33955)
			(xy 221.706731 -270.310083) (xy 221.756316 -270.287442) (xy 221.808618 -270.272089) (xy 221.862573 -270.264335)
			(xy 221.889828 -270.263874) (xy 221.918744 -270.264416) (xy 221.975916 -270.273136) (xy 222.031115 -270.290388)
			(xy 222.083078 -270.315775) (xy 222.130612 -270.348716) (xy 222.172628 -270.388455) (xy 222.190818 -270.41094)
			(xy 222.19837 -270.419712) (xy 222.219136 -270.429888) (xy 222.230696 -270.430498) (xy 222.31096 -270.430498)
			(xy 222.322525 -270.429905) (xy 222.343296 -270.419727) (xy 222.350838 -270.41094) (xy 222.369018 -270.388447)
			(xy 222.411039 -270.34871) (xy 222.458575 -270.315771) (xy 222.510539 -270.290384) (xy 222.565739 -270.273131)
			(xy 222.622911 -270.264406) (xy 222.651828 -270.263874) (xy 222.679079 -270.264352) (xy 222.733026 -270.272112)
			(xy 222.78532 -270.287469) (xy 222.834896 -270.310112) (xy 222.880746 -270.33958) (xy 222.921935 -270.375272)
			(xy 222.957626 -270.416463) (xy 222.987092 -270.462313) (xy 223.009734 -270.511889) (xy 223.025091 -270.564184)
			(xy 223.032849 -270.618131) (xy 223.033336 -270.645382) (xy 223.032829 -270.6743) (xy 223.024101 -270.731472)
			(xy 223.006843 -270.786673) (xy 222.981449 -270.838635) (xy 222.948502 -270.886168) (xy 222.908757 -270.928183)
			(xy 222.88627 -270.946372) (xy 222.87752 -270.953945) (xy 222.867331 -270.974696) (xy 222.866712 -270.98625)
			(xy 222.866712 -271.066514) (xy 222.86727 -271.078084) (xy 222.877473 -271.098855) (xy 222.88627 -271.106392)
			(xy 222.907034 -271.123167) (xy 222.944161 -271.161519) (xy 222.975581 -271.204672) (xy 223.000678 -271.251783)
			(xy 223.018964 -271.301932) (xy 223.03008 -271.354141) (xy 223.033811 -271.407389) (xy 223.030083 -271.460638)
			(xy 223.01897 -271.512847) (xy 223.000687 -271.562997) (xy 222.975592 -271.610109) (xy 222.944176 -271.653264)
			(xy 222.90705 -271.691618) (xy 222.88627 -271.708372) (xy 222.87752 -271.715945) (xy 222.867331 -271.736696)
			(xy 222.866712 -271.74825) (xy 222.866712 -271.828514) (xy 222.86727 -271.840084) (xy 222.877473 -271.860855)
			(xy 222.88627 -271.868392) (xy 222.908743 -271.886595) (xy 222.948481 -271.928611) (xy 222.981422 -271.976144)
			(xy 223.006812 -272.028103) (xy 223.02407 -272.083298) (xy 223.0328 -272.140467) (xy 223.033336 -272.169382)
			(xy 223.032805 -272.196631) (xy 223.025052 -272.250576) (xy 223.0097 -272.302868) (xy 222.987063 -272.352443)
			(xy 222.957602 -272.398293) (xy 222.921915 -272.439482) (xy 222.880729 -272.475174) (xy 222.84236 -272.499836)
			(xy 231.378258 -272.499836) (xy 231.382272 -272.294152) (xy 231.394308 -272.088782) (xy 231.414347 -271.884038)
			(xy 231.44236 -271.680231) (xy 231.478303 -271.477672) (xy 231.522122 -271.27667) (xy 231.573749 -271.077531)
			(xy 231.633107 -270.880558) (xy 231.700105 -270.68605) (xy 231.774641 -270.494305) (xy 231.856601 -270.305614)
			(xy 231.945861 -270.120264) (xy 232.042284 -269.938538) (xy 232.145725 -269.760712) (xy 232.256024 -269.587058)
			(xy 232.373015 -269.417839) (xy 232.496519 -269.253313) (xy 232.626348 -269.093732) (xy 232.762305 -268.939337)
			(xy 232.904182 -268.790365) (xy 233.051763 -268.647041) (xy 233.204824 -268.509585) (xy 233.363131 -268.378205)
			(xy 233.526444 -268.253102) (xy 233.694513 -268.134465) (xy 233.867083 -268.022477) (xy 234.043891 -267.917306)
			(xy 234.224668 -267.819115) (xy 234.409138 -267.728051) (xy 234.59702 -267.644254) (xy 234.78803 -267.567851)
			(xy 234.981874 -267.498958) (xy 235.178259 -267.437681) (xy 235.376885 -267.384113) (xy 235.57745 -267.338336)
			(xy 235.779648 -267.300418) (xy 235.983172 -267.270419) (xy 236.187711 -267.248382) (xy 236.392954 -267.234343)
			(xy 236.598589 -267.228323) (xy 236.804302 -267.23033) (xy 237.00978 -267.240362) (xy 237.21471 -267.258403)
			(xy 237.41878 -267.284426) (xy 237.62168 -267.318391) (xy 237.8231 -267.360246) (xy 238.022733 -267.409928)
			(xy 238.220276 -267.467362) (xy 238.415428 -267.532459) (xy 238.607892 -267.60512) (xy 238.797374 -267.685236)
			(xy 238.983585 -267.772683) (xy 239.166244 -267.867329) (xy 239.34507 -267.969029) (xy 239.519792 -268.077629)
			(xy 239.690145 -268.192964) (xy 239.855867 -268.314857) (xy 240.016708 -268.443123) (xy 240.172421 -268.577566)
			(xy 240.322771 -268.717983) (xy 240.467528 -268.864159) (xy 240.606471 -269.015871) (xy 240.739389 -269.172889)
			(xy 240.86608 -269.334974) (xy 240.98635 -269.501877) (xy 241.072241 -269.631446) (xy 249.332814 -269.631446)
			(xy 249.332814 -269.576954) (xy 249.340569 -269.523015) (xy 249.35592 -269.47073) (xy 249.378555 -269.421161)
			(xy 249.408014 -269.375317) (xy 249.443696 -269.334132) (xy 249.484877 -269.298444) (xy 249.530717 -269.268979)
			(xy 249.580283 -269.246337) (xy 249.632567 -269.230979) (xy 249.686504 -269.223218) (xy 249.71375 -269.222728)
			(xy 249.742666 -269.223272) (xy 249.799837 -269.231994) (xy 249.855035 -269.249246) (xy 249.906997 -269.274633)
			(xy 249.954532 -269.307573) (xy 249.99655 -269.34731) (xy 250.01474 -269.369794) (xy 250.02229 -269.378569)
			(xy 250.043058 -269.388745) (xy 250.054618 -269.389352) (xy 250.134882 -269.389352) (xy 250.146451 -269.388788)
			(xy 250.167223 -269.37859) (xy 250.17476 -269.369794) (xy 250.191513 -269.349011) (xy 250.229867 -269.311881)
			(xy 250.273021 -269.280459) (xy 250.320135 -269.25536) (xy 250.370287 -269.237074) (xy 250.422498 -269.225957)
			(xy 250.47575 -269.222227) (xy 250.529002 -269.225957) (xy 250.581213 -269.237074) (xy 250.631365 -269.25536)
			(xy 250.678479 -269.280459) (xy 250.721633 -269.311881) (xy 250.759987 -269.349011) (xy 250.77674 -269.369794)
			(xy 250.78429 -269.378569) (xy 250.805058 -269.388745) (xy 250.816618 -269.389352) (xy 250.896882 -269.389352)
			(xy 250.908451 -269.388788) (xy 250.929223 -269.37859) (xy 250.93676 -269.369794) (xy 250.953513 -269.349011)
			(xy 250.991867 -269.311881) (xy 251.035021 -269.280459) (xy 251.082135 -269.25536) (xy 251.132287 -269.237074)
			(xy 251.184498 -269.225957) (xy 251.23775 -269.222227) (xy 251.291002 -269.225957) (xy 251.343213 -269.237074)
			(xy 251.393365 -269.25536) (xy 251.440479 -269.280459) (xy 251.483633 -269.311881) (xy 251.521987 -269.349011)
			(xy 251.53874 -269.369794) (xy 251.54629 -269.378569) (xy 251.567058 -269.388745) (xy 251.578618 -269.389352)
			(xy 251.658882 -269.389352) (xy 251.670451 -269.388788) (xy 251.691223 -269.37859) (xy 251.69876 -269.369794)
			(xy 251.716972 -269.347328) (xy 251.758988 -269.307592) (xy 251.806518 -269.274651) (xy 251.858475 -269.24926)
			(xy 251.913669 -269.232) (xy 251.970835 -269.223266) (xy 251.99975 -269.222728) (xy 252.027008 -269.223116)
			(xy 252.080969 -269.230867) (xy 252.133278 -269.246221) (xy 252.182869 -269.268862) (xy 252.228733 -269.298332)
			(xy 252.269936 -269.334029) (xy 252.305638 -269.375227) (xy 252.335114 -269.421087) (xy 252.357762 -269.470675)
			(xy 252.373122 -269.522982) (xy 252.380881 -269.576942) (xy 252.380881 -269.631458) (xy 252.373122 -269.685418)
			(xy 252.357762 -269.737725) (xy 252.335114 -269.787313) (xy 252.305638 -269.833173) (xy 252.269936 -269.874371)
			(xy 252.228733 -269.910068) (xy 252.182869 -269.939538) (xy 252.133278 -269.962179) (xy 252.080969 -269.977533)
			(xy 252.027008 -269.985284) (xy 251.99975 -269.985744) (xy 251.970833 -269.985211) (xy 251.913662 -269.976488)
			(xy 251.858462 -269.959235) (xy 251.8065 -269.933846) (xy 251.758966 -269.900904) (xy 251.71695 -269.861163)
			(xy 251.69876 -269.838678) (xy 251.691215 -269.829899) (xy 251.670443 -269.819726) (xy 251.658882 -269.81912)
			(xy 251.578618 -269.81912) (xy 251.56705 -269.819694) (xy 251.546279 -269.829885) (xy 251.53874 -269.838678)
			(xy 251.521987 -269.859461) (xy 251.483633 -269.896591) (xy 251.440479 -269.928013) (xy 251.393365 -269.953112)
			(xy 251.343213 -269.971398) (xy 251.291002 -269.982515) (xy 251.23775 -269.986245) (xy 251.184498 -269.982515)
			(xy 251.132287 -269.971398) (xy 251.082135 -269.953112) (xy 251.035021 -269.928013) (xy 250.991867 -269.896591)
			(xy 250.953513 -269.859461) (xy 250.93676 -269.838678) (xy 250.929215 -269.829899) (xy 250.908443 -269.819726)
			(xy 250.896882 -269.81912) (xy 250.816618 -269.81912) (xy 250.80505 -269.819694) (xy 250.784279 -269.829885)
			(xy 250.77674 -269.838678) (xy 250.759987 -269.859461) (xy 250.721633 -269.896591) (xy 250.678479 -269.928013)
			(xy 250.631365 -269.953112) (xy 250.581213 -269.971398) (xy 250.529002 -269.982515) (xy 250.47575 -269.986245)
			(xy 250.422498 -269.982515) (xy 250.370287 -269.971398) (xy 250.320135 -269.953112) (xy 250.273021 -269.928013)
			(xy 250.229867 -269.896591) (xy 250.191513 -269.859461) (xy 250.17476 -269.838678) (xy 250.167215 -269.829899)
			(xy 250.146443 -269.819726) (xy 250.134882 -269.81912) (xy 250.054618 -269.81912) (xy 250.04305 -269.819694)
			(xy 250.022279 -269.829885) (xy 250.01474 -269.838678) (xy 249.996521 -269.861138) (xy 249.954508 -269.900875)
			(xy 249.906979 -269.933818) (xy 249.855023 -269.959211) (xy 249.79983 -269.976472) (xy 249.742664 -269.985206)
			(xy 249.71375 -269.985744) (xy 249.686504 -269.985182) (xy 249.632567 -269.977421) (xy 249.580283 -269.962063)
			(xy 249.530717 -269.939421) (xy 249.484877 -269.909956) (xy 249.443697 -269.874268) (xy 249.408014 -269.833083)
			(xy 249.378555 -269.787239) (xy 249.35592 -269.73767) (xy 249.340569 -269.685385) (xy 249.332814 -269.631446)
			(xy 241.072241 -269.631446) (xy 241.100017 -269.673347) (xy 241.206907 -269.84912) (xy 241.306858 -270.02893)
			(xy 241.399717 -270.212503) (xy 241.485344 -270.399559) (xy 241.563606 -270.589814) (xy 241.634387 -270.782977)
			(xy 241.697577 -270.978755) (xy 241.75308 -271.176849) (xy 241.774804 -271.267922) (xy 250.855751 -271.267922)
			(xy 250.859478 -271.214673) (xy 250.870593 -271.162463) (xy 250.888877 -271.112313) (xy 250.913975 -271.065201)
			(xy 250.945396 -271.022049) (xy 250.982526 -270.983698) (xy 251.003308 -270.966946) (xy 251.012046 -270.959361)
			(xy 251.022242 -270.93862) (xy 251.022866 -270.927068) (xy 251.022866 -270.846804) (xy 251.022305 -270.835235)
			(xy 251.012105 -270.814463) (xy 251.003308 -270.806926) (xy 250.980839 -270.788718) (xy 250.941102 -270.746702)
			(xy 250.908161 -270.699171) (xy 250.88277 -270.647213) (xy 250.865511 -270.592018) (xy 250.856779 -270.534851)
			(xy 250.856242 -270.505936) (xy 250.856689 -270.478682) (xy 250.864442 -270.424728) (xy 250.879796 -270.372426)
			(xy 250.902438 -270.322843) (xy 250.931907 -270.276987) (xy 250.967603 -270.235793) (xy 251.008799 -270.200099)
			(xy 251.054655 -270.170632) (xy 251.10424 -270.147991) (xy 251.156541 -270.132639) (xy 251.210496 -270.124888)
			(xy 251.23775 -270.124428) (xy 251.266666 -270.124972) (xy 251.323837 -270.133694) (xy 251.379035 -270.150946)
			(xy 251.430997 -270.176333) (xy 251.478532 -270.209273) (xy 251.52055 -270.24901) (xy 251.53874 -270.271494)
			(xy 251.54629 -270.280269) (xy 251.567058 -270.290445) (xy 251.578618 -270.291052) (xy 251.658882 -270.291052)
			(xy 251.670451 -270.290488) (xy 251.691223 -270.28029) (xy 251.69876 -270.271494) (xy 251.716972 -270.249028)
			(xy 251.758988 -270.209292) (xy 251.806518 -270.176351) (xy 251.858475 -270.15096) (xy 251.913669 -270.1337)
			(xy 251.970835 -270.124966) (xy 251.99975 -270.124428) (xy 252.027003 -270.124902) (xy 252.080956 -270.132653)
			(xy 252.133256 -270.148005) (xy 252.182838 -270.170644) (xy 252.228693 -270.20011) (xy 252.269887 -270.235803)
			(xy 252.305582 -270.276996) (xy 252.335049 -270.32285) (xy 252.357691 -270.372431) (xy 252.373044 -270.424731)
			(xy 252.380797 -270.478683) (xy 252.381258 -270.505936) (xy 252.38071 -270.534852) (xy 252.371989 -270.592023)
			(xy 252.354738 -270.647221) (xy 252.329352 -270.699184) (xy 252.296413 -270.746718) (xy 252.256676 -270.788736)
			(xy 252.234192 -270.806926) (xy 252.225422 -270.81448) (xy 252.215243 -270.835245) (xy 252.214634 -270.846804)
			(xy 252.214634 -270.927068) (xy 252.215211 -270.938635) (xy 252.2254 -270.959407) (xy 252.234192 -270.966946)
			(xy 252.255013 -270.983656) (xy 252.292148 -271.022012) (xy 252.323574 -271.065171) (xy 252.348675 -271.112289)
			(xy 252.366962 -271.162447) (xy 252.378078 -271.214665) (xy 252.381806 -271.267922) (xy 252.378072 -271.321179)
			(xy 252.36695 -271.373395) (xy 252.348657 -271.423551) (xy 252.32355 -271.470667) (xy 252.29212 -271.513822)
			(xy 252.25498 -271.552174) (xy 252.234192 -271.568926) (xy 252.225422 -271.57648) (xy 252.215243 -271.597245)
			(xy 252.214634 -271.608804) (xy 252.214634 -271.689068) (xy 252.215211 -271.700635) (xy 252.2254 -271.721407)
			(xy 252.234192 -271.728946) (xy 252.256648 -271.74717) (xy 252.296385 -271.789182) (xy 252.329328 -271.83671)
			(xy 252.354721 -271.888665) (xy 252.371983 -271.943857) (xy 252.380719 -272.001022) (xy 252.381258 -272.029936)
			(xy 252.380878 -272.057192) (xy 252.373115 -272.111149) (xy 252.357752 -272.163451) (xy 252.335102 -272.213035)
			(xy 252.305625 -272.25889) (xy 252.269923 -272.300084) (xy 252.228721 -272.335777) (xy 252.182859 -272.365243)
			(xy 252.13327 -272.387882) (xy 252.080964 -272.403234) (xy 252.027006 -272.410985) (xy 251.99975 -272.411444)
			(xy 251.970833 -272.410911) (xy 251.913662 -272.402188) (xy 251.858462 -272.384935) (xy 251.8065 -272.359546)
			(xy 251.758966 -272.326604) (xy 251.71695 -272.286863) (xy 251.69876 -272.264378) (xy 251.691215 -272.255599)
			(xy 251.670443 -272.245426) (xy 251.658882 -272.24482) (xy 251.578618 -272.24482) (xy 251.56705 -272.245394)
			(xy 251.546279 -272.255585) (xy 251.53874 -272.264378) (xy 251.520521 -272.286838) (xy 251.478508 -272.326575)
			(xy 251.430979 -272.359518) (xy 251.379023 -272.384911) (xy 251.32383 -272.402172) (xy 251.266664 -272.410906)
			(xy 251.23775 -272.411444) (xy 251.2105 -272.410898) (xy 251.156554 -272.403149) (xy 251.10426 -272.387801)
			(xy 251.054682 -272.365167) (xy 251.008831 -272.335708) (xy 250.967638 -272.300023) (xy 250.931944 -272.258838)
			(xy 250.902474 -272.212993) (xy 250.879829 -272.163421) (xy 250.864469 -272.11113) (xy 250.856708 -272.057186)
			(xy 250.856242 -272.029936) (xy 250.85677 -272.001019) (xy 250.865495 -271.943848) (xy 250.88275 -271.888648)
			(xy 250.90814 -271.836686) (xy 250.941082 -271.789152) (xy 250.980823 -271.747136) (xy 251.003308 -271.728946)
			(xy 251.012046 -271.721361) (xy 251.022242 -271.70062) (xy 251.022866 -271.689068) (xy 251.022866 -271.608804)
			(xy 251.022305 -271.597235) (xy 251.012105 -271.576463) (xy 251.003308 -271.568926) (xy 250.982558 -271.552131)
			(xy 250.945424 -271.513785) (xy 250.913999 -271.470636) (xy 250.888895 -271.423528) (xy 250.870605 -271.37338)
			(xy 250.859485 -271.321171) (xy 250.855751 -271.267922) (xy 241.774804 -271.267922) (xy 241.800812 -271.376958)
			(xy 241.840701 -271.578776) (xy 241.872685 -271.781998) (xy 241.896715 -271.986312) (xy 241.912756 -272.191408)
			(xy 241.920782 -272.396975) (xy 241.921284 -272.499836) (xy 241.920782 -272.602697) (xy 241.912756 -272.808264)
			(xy 241.900979 -272.958846) (xy 249.332814 -272.958846) (xy 249.332814 -272.904354) (xy 249.340569 -272.850415)
			(xy 249.35592 -272.79813) (xy 249.378555 -272.748561) (xy 249.408014 -272.702717) (xy 249.443696 -272.661532)
			(xy 249.484877 -272.625844) (xy 249.530717 -272.596379) (xy 249.580283 -272.573737) (xy 249.632567 -272.558379)
			(xy 249.686504 -272.550618) (xy 249.71375 -272.550128) (xy 249.742666 -272.550672) (xy 249.799837 -272.559394)
			(xy 249.855035 -272.576646) (xy 249.906997 -272.602033) (xy 249.954532 -272.634973) (xy 249.99655 -272.67471)
			(xy 250.01474 -272.697194) (xy 250.02229 -272.705969) (xy 250.043058 -272.716145) (xy 250.054618 -272.716752)
			(xy 250.134882 -272.716752) (xy 250.146451 -272.716188) (xy 250.167223 -272.70599) (xy 250.17476 -272.697194)
			(xy 250.191513 -272.676411) (xy 250.229867 -272.639281) (xy 250.273021 -272.607859) (xy 250.320135 -272.58276)
			(xy 250.370287 -272.564474) (xy 250.422498 -272.553357) (xy 250.47575 -272.549627) (xy 250.529002 -272.553357)
			(xy 250.581213 -272.564474) (xy 250.631365 -272.58276) (xy 250.678479 -272.607859) (xy 250.721633 -272.639281)
			(xy 250.759987 -272.676411) (xy 250.77674 -272.697194) (xy 250.78429 -272.705969) (xy 250.805058 -272.716145)
			(xy 250.816618 -272.716752) (xy 250.896882 -272.716752) (xy 250.908451 -272.716188) (xy 250.929223 -272.70599)
			(xy 250.93676 -272.697194) (xy 250.953513 -272.676411) (xy 250.991867 -272.639281) (xy 251.035021 -272.607859)
			(xy 251.082135 -272.58276) (xy 251.132287 -272.564474) (xy 251.184498 -272.553357) (xy 251.23775 -272.549627)
			(xy 251.291002 -272.553357) (xy 251.343213 -272.564474) (xy 251.393365 -272.58276) (xy 251.440479 -272.607859)
			(xy 251.483633 -272.639281) (xy 251.521987 -272.676411) (xy 251.53874 -272.697194) (xy 251.54629 -272.705969)
			(xy 251.567058 -272.716145) (xy 251.578618 -272.716752) (xy 251.658882 -272.716752) (xy 251.670451 -272.716188)
			(xy 251.691223 -272.70599) (xy 251.69876 -272.697194) (xy 251.716972 -272.674728) (xy 251.758988 -272.634992)
			(xy 251.806518 -272.602051) (xy 251.858475 -272.57666) (xy 251.913669 -272.5594) (xy 251.970835 -272.550666)
			(xy 251.99975 -272.550128) (xy 252.027008 -272.550516) (xy 252.080969 -272.558267) (xy 252.133278 -272.573621)
			(xy 252.182869 -272.596262) (xy 252.228733 -272.625732) (xy 252.269936 -272.661429) (xy 252.305638 -272.702627)
			(xy 252.335114 -272.748487) (xy 252.357762 -272.798075) (xy 252.373122 -272.850382) (xy 252.380881 -272.904342)
			(xy 252.380881 -272.958858) (xy 252.373122 -273.012818) (xy 252.357762 -273.065125) (xy 252.335114 -273.114713)
			(xy 252.305638 -273.160573) (xy 252.269936 -273.201771) (xy 252.228733 -273.237468) (xy 252.182869 -273.266938)
			(xy 252.133278 -273.289579) (xy 252.080969 -273.304933) (xy 252.027008 -273.312684) (xy 251.99975 -273.313144)
			(xy 251.970833 -273.312611) (xy 251.913662 -273.303888) (xy 251.858462 -273.286635) (xy 251.8065 -273.261246)
			(xy 251.758966 -273.228304) (xy 251.71695 -273.188563) (xy 251.69876 -273.166078) (xy 251.691215 -273.157299)
			(xy 251.670443 -273.147126) (xy 251.658882 -273.14652) (xy 251.578618 -273.14652) (xy 251.56705 -273.147094)
			(xy 251.546279 -273.157285) (xy 251.53874 -273.166078) (xy 251.521987 -273.186861) (xy 251.483633 -273.223991)
			(xy 251.440479 -273.255413) (xy 251.393365 -273.280512) (xy 251.343213 -273.298798) (xy 251.291002 -273.309915)
			(xy 251.23775 -273.313645) (xy 251.184498 -273.309915) (xy 251.132287 -273.298798) (xy 251.082135 -273.280512)
			(xy 251.035021 -273.255413) (xy 250.991867 -273.223991) (xy 250.953513 -273.186861) (xy 250.93676 -273.166078)
			(xy 250.929215 -273.157299) (xy 250.908443 -273.147126) (xy 250.896882 -273.14652) (xy 250.816618 -273.14652)
			(xy 250.80505 -273.147094) (xy 250.784279 -273.157285) (xy 250.77674 -273.166078) (xy 250.759987 -273.186861)
			(xy 250.721633 -273.223991) (xy 250.678479 -273.255413) (xy 250.631365 -273.280512) (xy 250.581213 -273.298798)
			(xy 250.529002 -273.309915) (xy 250.47575 -273.313645) (xy 250.422498 -273.309915) (xy 250.370287 -273.298798)
			(xy 250.320135 -273.280512) (xy 250.273021 -273.255413) (xy 250.229867 -273.223991) (xy 250.191513 -273.186861)
			(xy 250.17476 -273.166078) (xy 250.167215 -273.157299) (xy 250.146443 -273.147126) (xy 250.134882 -273.14652)
			(xy 250.054618 -273.14652) (xy 250.04305 -273.147094) (xy 250.022279 -273.157285) (xy 250.01474 -273.166078)
			(xy 249.996521 -273.188538) (xy 249.954508 -273.228275) (xy 249.906979 -273.261218) (xy 249.855023 -273.286611)
			(xy 249.79983 -273.303872) (xy 249.742664 -273.312606) (xy 249.71375 -273.313144) (xy 249.686504 -273.312582)
			(xy 249.632567 -273.304821) (xy 249.580283 -273.289463) (xy 249.530717 -273.266821) (xy 249.484877 -273.237356)
			(xy 249.443697 -273.201668) (xy 249.408014 -273.160483) (xy 249.378555 -273.114639) (xy 249.35592 -273.06507)
			(xy 249.340569 -273.012785) (xy 249.332814 -272.958846) (xy 241.900979 -272.958846) (xy 241.896715 -273.01336)
			(xy 241.872685 -273.217674) (xy 241.840701 -273.420896) (xy 241.800812 -273.622714) (xy 241.75308 -273.822823)
			(xy 241.697577 -274.020917) (xy 241.634387 -274.216695) (xy 241.563606 -274.409858) (xy 241.485344 -274.600113)
			(xy 241.399717 -274.787169) (xy 241.306858 -274.970742) (xy 241.206907 -275.150552) (xy 241.100017 -275.326325)
			(xy 240.98635 -275.497795) (xy 240.86608 -275.664698) (xy 240.739389 -275.826783) (xy 240.606471 -275.983801)
			(xy 240.467528 -276.135513) (xy 240.322771 -276.281689) (xy 240.172421 -276.422106) (xy 240.016708 -276.556549)
			(xy 239.855867 -276.684815) (xy 239.690145 -276.806708) (xy 239.519792 -276.922043) (xy 239.34507 -277.030643)
			(xy 239.166244 -277.132343) (xy 238.983585 -277.226989) (xy 238.797374 -277.314436) (xy 238.607892 -277.394552)
			(xy 238.415428 -277.467213) (xy 238.220276 -277.53231) (xy 238.022733 -277.589744) (xy 237.8231 -277.639426)
			(xy 237.62168 -277.681281) (xy 237.41878 -277.715246) (xy 237.21471 -277.741269) (xy 237.00978 -277.75931)
			(xy 236.804302 -277.769342) (xy 236.598589 -277.771349) (xy 236.392954 -277.765329) (xy 236.187711 -277.75129)
			(xy 235.983172 -277.729253) (xy 235.779648 -277.699254) (xy 235.57745 -277.661336) (xy 235.376885 -277.615559)
			(xy 235.178259 -277.561991) (xy 234.981874 -277.500714) (xy 234.78803 -277.431821) (xy 234.59702 -277.355418)
			(xy 234.409138 -277.271621) (xy 234.224668 -277.180557) (xy 234.043891 -277.082366) (xy 233.867083 -276.977195)
			(xy 233.694513 -276.865207) (xy 233.526444 -276.74657) (xy 233.363131 -276.621467) (xy 233.204824 -276.490087)
			(xy 233.051763 -276.352631) (xy 232.904182 -276.209307) (xy 232.762305 -276.060335) (xy 232.626348 -275.90594)
			(xy 232.496519 -275.746359) (xy 232.373015 -275.581833) (xy 232.256024 -275.412614) (xy 232.145725 -275.23896)
			(xy 232.042284 -275.061134) (xy 231.945861 -274.879408) (xy 231.856601 -274.694058) (xy 231.774641 -274.505367)
			(xy 231.700105 -274.313622) (xy 231.633107 -274.119114) (xy 231.573749 -273.922141) (xy 231.522122 -273.723002)
			(xy 231.478303 -273.522) (xy 231.44236 -273.319441) (xy 231.414347 -273.115634) (xy 231.394308 -272.91089)
			(xy 231.382272 -272.70552) (xy 231.378258 -272.499836) (xy 222.84236 -272.499836) (xy 222.834884 -272.504641)
			(xy 222.785311 -272.527284) (xy 222.733021 -272.542642) (xy 222.679077 -272.550402) (xy 222.651828 -272.55089)
			(xy 222.622912 -272.550355) (xy 222.565741 -272.54163) (xy 222.510542 -272.524376) (xy 222.458581 -272.498987)
			(xy 222.411046 -272.466046) (xy 222.369029 -272.426308) (xy 222.350838 -272.403824) (xy 222.343268 -272.395071)
			(xy 222.322515 -272.384886) (xy 222.31096 -272.384266) (xy 222.230696 -272.384266) (xy 222.219124 -272.384811)
			(xy 222.198352 -272.395021) (xy 222.190818 -272.403824) (xy 222.172623 -272.426304) (xy 222.130603 -272.466038)
			(xy 222.083069 -272.498977) (xy 222.031109 -272.524366) (xy 221.975912 -272.541623) (xy 221.918744 -272.550354)
			(xy 221.889828 -272.55089) (xy 221.862575 -272.550419) (xy 221.808623 -272.542665) (xy 221.756325 -272.527312)
			(xy 221.706743 -272.504671) (xy 221.660889 -272.475204) (xy 221.619696 -272.439511) (xy 221.584002 -272.398319)
			(xy 221.554534 -272.352465) (xy 221.531892 -272.302885) (xy 221.516537 -272.250586) (xy 221.508782 -272.196635)
			(xy 221.50832 -272.169382) (xy 221.508889 -272.140467) (xy 221.517607 -272.083298) (xy 221.534854 -272.0281)
			(xy 221.560236 -271.976137) (xy 221.593171 -271.928602) (xy 221.632904 -271.886583) (xy 221.655386 -271.868392)
			(xy 221.664145 -271.860827) (xy 221.674331 -271.840071) (xy 221.674944 -271.828514) (xy 221.674944 -271.74825)
			(xy 221.674365 -271.736683) (xy 221.664178 -271.71591) (xy 221.655386 -271.708372) (xy 221.634584 -271.691641)
			(xy 221.597451 -271.653286) (xy 221.566027 -271.610129) (xy 221.540927 -271.563013) (xy 221.52264 -271.512858)
			(xy 221.511524 -271.460643) (xy 221.507795 -271.407389) (xy 218.565222 -271.407389) (xy 218.565222 -273.098355)
			(xy 221.508737 -273.098355) (xy 221.508737 -273.043845) (xy 221.516495 -272.989889) (xy 221.531853 -272.937586)
			(xy 221.554499 -272.888002) (xy 221.583971 -272.842145) (xy 221.619669 -272.800949) (xy 221.660867 -272.765254)
			(xy 221.706726 -272.735785) (xy 221.756312 -272.713143) (xy 221.808616 -272.697789) (xy 221.862573 -272.690035)
			(xy 221.889828 -272.689574) (xy 221.918744 -272.690116) (xy 221.975916 -272.698836) (xy 222.031115 -272.716088)
			(xy 222.083078 -272.741475) (xy 222.130612 -272.774416) (xy 222.172628 -272.814155) (xy 222.190818 -272.83664)
			(xy 222.19837 -272.845412) (xy 222.219136 -272.855588) (xy 222.230696 -272.856198) (xy 222.31096 -272.856198)
			(xy 222.322525 -272.855605) (xy 222.343296 -272.845427) (xy 222.350838 -272.83664) (xy 222.367591 -272.815857)
			(xy 222.405945 -272.778727) (xy 222.449099 -272.747305) (xy 222.496213 -272.722206) (xy 222.546365 -272.70392)
			(xy 222.598576 -272.692803) (xy 222.651828 -272.689073) (xy 222.70508 -272.692803) (xy 222.757291 -272.70392)
			(xy 222.807443 -272.722206) (xy 222.854557 -272.747305) (xy 222.897711 -272.778727) (xy 222.936065 -272.815857)
			(xy 222.952818 -272.83664) (xy 222.96037 -272.845412) (xy 222.981136 -272.855588) (xy 222.992696 -272.856198)
			(xy 223.07296 -272.856198) (xy 223.084525 -272.855605) (xy 223.105296 -272.845427) (xy 223.112838 -272.83664)
			(xy 223.129591 -272.815857) (xy 223.167945 -272.778727) (xy 223.211099 -272.747305) (xy 223.258213 -272.722206)
			(xy 223.308365 -272.70392) (xy 223.360576 -272.692803) (xy 223.413828 -272.689073) (xy 223.46708 -272.692803)
			(xy 223.519291 -272.70392) (xy 223.569443 -272.722206) (xy 223.616557 -272.747305) (xy 223.659711 -272.778727)
			(xy 223.698065 -272.815857) (xy 223.714818 -272.83664) (xy 223.72237 -272.845412) (xy 223.743136 -272.855588)
			(xy 223.754696 -272.856198) (xy 223.83496 -272.856198) (xy 223.846525 -272.855605) (xy 223.867296 -272.845427)
			(xy 223.874838 -272.83664) (xy 223.893018 -272.814147) (xy 223.935039 -272.77441) (xy 223.982575 -272.741471)
			(xy 224.034539 -272.716084) (xy 224.089739 -272.698831) (xy 224.146911 -272.690106) (xy 224.175828 -272.689574)
			(xy 224.203077 -272.690098) (xy 224.257019 -272.697858) (xy 224.309308 -272.713214) (xy 224.358879 -272.735856)
			(xy 224.404724 -272.765322) (xy 224.445908 -272.801011) (xy 224.481595 -272.842199) (xy 224.511057 -272.888046)
			(xy 224.533695 -272.937619) (xy 224.549048 -272.989909) (xy 224.556804 -273.043851) (xy 224.556804 -273.098349)
			(xy 224.549048 -273.152291) (xy 224.533695 -273.204581) (xy 224.511057 -273.254154) (xy 224.481595 -273.300001)
			(xy 224.445908 -273.341189) (xy 224.404724 -273.376878) (xy 224.358879 -273.406344) (xy 224.309308 -273.428986)
			(xy 224.257019 -273.444342) (xy 224.203077 -273.452102) (xy 224.175828 -273.45259) (xy 224.146912 -273.452055)
			(xy 224.089741 -273.44333) (xy 224.034542 -273.426076) (xy 223.982581 -273.400687) (xy 223.935046 -273.367746)
			(xy 223.893029 -273.328008) (xy 223.874838 -273.305524) (xy 223.867268 -273.296771) (xy 223.846515 -273.286586)
			(xy 223.83496 -273.285966) (xy 223.754696 -273.285966) (xy 223.743124 -273.286511) (xy 223.722352 -273.296721)
			(xy 223.714818 -273.305524) (xy 223.698065 -273.326307) (xy 223.659711 -273.363437) (xy 223.616557 -273.394859)
			(xy 223.569443 -273.419958) (xy 223.519291 -273.438244) (xy 223.46708 -273.449361) (xy 223.413828 -273.453091)
			(xy 223.360576 -273.449361) (xy 223.308365 -273.438244) (xy 223.258213 -273.419958) (xy 223.211099 -273.394859)
			(xy 223.167945 -273.363437) (xy 223.129591 -273.326307) (xy 223.112838 -273.305524) (xy 223.105268 -273.296771)
			(xy 223.084515 -273.286586) (xy 223.07296 -273.285966) (xy 222.992696 -273.285966) (xy 222.981124 -273.286511)
			(xy 222.960352 -273.296721) (xy 222.952818 -273.305524) (xy 222.936065 -273.326307) (xy 222.897711 -273.363437)
			(xy 222.854557 -273.394859) (xy 222.807443 -273.419958) (xy 222.757291 -273.438244) (xy 222.70508 -273.449361)
			(xy 222.651828 -273.453091) (xy 222.598576 -273.449361) (xy 222.546365 -273.438244) (xy 222.496213 -273.419958)
			(xy 222.449099 -273.394859) (xy 222.405945 -273.363437) (xy 222.367591 -273.326307) (xy 222.350838 -273.305524)
			(xy 222.343268 -273.296771) (xy 222.322515 -273.286586) (xy 222.31096 -273.285966) (xy 222.230696 -273.285966)
			(xy 222.219124 -273.286511) (xy 222.198352 -273.296721) (xy 222.190818 -273.305524) (xy 222.172623 -273.328004)
			(xy 222.130603 -273.367738) (xy 222.083069 -273.400677) (xy 222.031109 -273.426066) (xy 221.975912 -273.443323)
			(xy 221.918744 -273.452054) (xy 221.889828 -273.45259) (xy 221.862573 -273.452165) (xy 221.808616 -273.444411)
			(xy 221.756312 -273.429057) (xy 221.706726 -273.406415) (xy 221.660867 -273.376946) (xy 221.619669 -273.341251)
			(xy 221.583971 -273.300055) (xy 221.554499 -273.254198) (xy 221.531853 -273.204614) (xy 221.516495 -273.152311)
			(xy 221.508737 -273.098355) (xy 218.565222 -273.098355) (xy 218.565222 -288.15538) (xy 225.493324 -288.15538)
			(xy 225.497395 -288.099758) (xy 225.509521 -288.045321) (xy 225.529444 -287.99323) (xy 225.55674 -287.944595)
			(xy 225.590826 -287.900452) (xy 225.630975 -287.861743) (xy 225.676333 -287.829292) (xy 225.725933 -287.803791)
			(xy 225.778717 -287.785784) (xy 225.83356 -287.775654) (xy 225.889294 -287.773617) (xy 225.944731 -287.779717)
			(xy 225.998688 -287.793823) (xy 226.050017 -287.815635) (xy 226.097623 -287.844689) (xy 226.140491 -287.880364)
			(xy 226.177708 -287.921901) (xy 226.208481 -287.968414) (xy 226.232153 -288.018911) (xy 226.248221 -288.072318)
			(xy 226.255698 -288.123122) (xy 237.653574 -288.123122) (xy 237.657645 -288.0675) (xy 237.669771 -288.013063)
			(xy 237.689694 -287.960972) (xy 237.71699 -287.912337) (xy 237.751076 -287.868194) (xy 237.791225 -287.829485)
			(xy 237.836583 -287.797034) (xy 237.886183 -287.771533) (xy 237.938967 -287.753526) (xy 237.99381 -287.743396)
			(xy 238.049544 -287.741359) (xy 238.104981 -287.747459) (xy 238.158938 -287.761565) (xy 238.210267 -287.783377)
			(xy 238.257873 -287.812431) (xy 238.300741 -287.848106) (xy 238.337958 -287.889643) (xy 238.368731 -287.936156)
			(xy 238.392403 -287.986653) (xy 238.408471 -288.04006) (xy 238.416591 -288.095236) (xy 238.4171 -288.123122)
			(xy 238.416591 -288.151008) (xy 238.408471 -288.206184) (xy 238.392403 -288.259591) (xy 238.368731 -288.310088)
			(xy 238.337958 -288.356601) (xy 238.300741 -288.398138) (xy 238.257873 -288.433813) (xy 238.210267 -288.462867)
			(xy 238.158938 -288.484679) (xy 238.104981 -288.498785) (xy 238.049544 -288.504885) (xy 237.99381 -288.502848)
			(xy 237.938967 -288.492718) (xy 237.886183 -288.474711) (xy 237.836583 -288.44921) (xy 237.791225 -288.416759)
			(xy 237.751076 -288.37805) (xy 237.71699 -288.333907) (xy 237.689694 -288.285272) (xy 237.669771 -288.233181)
			(xy 237.657645 -288.178744) (xy 237.653574 -288.123122) (xy 226.255698 -288.123122) (xy 226.256341 -288.127494)
			(xy 226.25685 -288.15538) (xy 226.256341 -288.183266) (xy 226.248221 -288.238442) (xy 226.232153 -288.291849)
			(xy 226.208481 -288.342346) (xy 226.177708 -288.388859) (xy 226.140491 -288.430396) (xy 226.097623 -288.466071)
			(xy 226.050017 -288.495125) (xy 225.998688 -288.516937) (xy 225.944731 -288.531043) (xy 225.889294 -288.537143)
			(xy 225.83356 -288.535106) (xy 225.778717 -288.524976) (xy 225.725933 -288.506969) (xy 225.676333 -288.481468)
			(xy 225.630975 -288.449017) (xy 225.590826 -288.410308) (xy 225.55674 -288.366165) (xy 225.529444 -288.31753)
			(xy 225.509521 -288.265439) (xy 225.497395 -288.211002) (xy 225.493324 -288.15538) (xy 218.565222 -288.15538)
			(xy 218.565222 -288.939732) (xy 228.82352 -288.939732) (xy 228.824006 -288.912481) (xy 228.831762 -288.858533)
			(xy 228.847117 -288.806238) (xy 228.869759 -288.756661) (xy 228.899225 -288.710811) (xy 228.934916 -288.66962)
			(xy 228.976107 -288.633929) (xy 229.021957 -288.604463) (xy 229.071534 -288.581821) (xy 229.123829 -288.566466)
			(xy 229.177777 -288.55871) (xy 229.232279 -288.55871) (xy 229.286227 -288.566466) (xy 229.338522 -288.581821)
			(xy 229.388099 -288.604463) (xy 229.433949 -288.633929) (xy 229.47514 -288.66962) (xy 229.510831 -288.710811)
			(xy 229.540297 -288.756661) (xy 229.562939 -288.806238) (xy 229.578294 -288.858533) (xy 229.58605 -288.912481)
			(xy 229.586536 -288.939732) (xy 240.76787 -288.939732) (xy 240.768356 -288.912481) (xy 240.776112 -288.858533)
			(xy 240.791467 -288.806238) (xy 240.814109 -288.756661) (xy 240.843575 -288.710811) (xy 240.879266 -288.66962)
			(xy 240.920457 -288.633929) (xy 240.966307 -288.604463) (xy 241.015884 -288.581821) (xy 241.068179 -288.566466)
			(xy 241.122127 -288.55871) (xy 241.176629 -288.55871) (xy 241.230577 -288.566466) (xy 241.282872 -288.581821)
			(xy 241.332449 -288.604463) (xy 241.378299 -288.633929) (xy 241.41949 -288.66962) (xy 241.455181 -288.710811)
			(xy 241.484647 -288.756661) (xy 241.507289 -288.806238) (xy 241.522644 -288.858533) (xy 241.5304 -288.912481)
			(xy 241.530886 -288.939732) (xy 241.530366 -288.967593) (xy 241.522273 -289.022725) (xy 241.506249 -289.076094)
			(xy 241.482635 -289.126566) (xy 241.451932 -289.173067) (xy 241.414794 -289.214609) (xy 241.393726 -289.232848)
			(xy 241.393472 -289.232848) (xy 241.384934 -289.240783) (xy 241.375541 -289.262087) (xy 241.375438 -289.273742)
			(xy 241.377978 -289.353752) (xy 241.378916 -289.36527) (xy 241.389786 -289.385641) (xy 241.398806 -289.392868)
			(xy 241.39906 -289.393122) (xy 241.41961 -289.408545) (xy 241.456743 -289.444058) (xy 241.488774 -289.484233)
			(xy 241.515123 -289.528344) (xy 241.535312 -289.575593) (xy 241.548976 -289.625124) (xy 241.555869 -289.676041)
			(xy 241.556286 -289.701732) (xy 241.5558 -289.728983) (xy 241.548044 -289.782931) (xy 241.532689 -289.835226)
			(xy 241.510047 -289.884803) (xy 241.480581 -289.930653) (xy 241.44489 -289.971844) (xy 241.403699 -290.007535)
			(xy 241.357849 -290.037001) (xy 241.308272 -290.059643) (xy 241.255977 -290.074998) (xy 241.202029 -290.082754)
			(xy 241.147527 -290.082754) (xy 241.093579 -290.074998) (xy 241.041284 -290.059643) (xy 240.991707 -290.037001)
			(xy 240.945857 -290.007535) (xy 240.904666 -289.971844) (xy 240.868975 -289.930653) (xy 240.839509 -289.884803)
			(xy 240.816867 -289.835226) (xy 240.801512 -289.782931) (xy 240.793756 -289.728983) (xy 240.79327 -289.701732)
			(xy 240.793781 -289.67387) (xy 240.801878 -289.618739) (xy 240.817905 -289.565371) (xy 240.841521 -289.514899)
			(xy 240.872224 -289.468398) (xy 240.909363 -289.426856) (xy 240.93043 -289.408616) (xy 240.930684 -289.408616)
			(xy 240.939232 -289.40069) (xy 240.948622 -289.37938) (xy 240.948718 -289.367722) (xy 240.946178 -289.287712)
			(xy 240.945184 -289.276204) (xy 240.934353 -289.255831) (xy 240.92535 -289.248596) (xy 240.925096 -289.248342)
			(xy 240.904589 -289.232864) (xy 240.867451 -289.197363) (xy 240.835415 -289.157198) (xy 240.809061 -289.113096)
			(xy 240.788864 -289.065855) (xy 240.775192 -289.016331) (xy 240.768292 -288.96542) (xy 240.76787 -288.939732)
			(xy 229.586536 -288.939732) (xy 229.585998 -288.967593) (xy 229.577906 -289.022723) (xy 229.561885 -289.076091)
			(xy 229.538274 -289.126562) (xy 229.507575 -289.173063) (xy 229.470441 -289.214608) (xy 229.449376 -289.232848)
			(xy 229.449122 -289.232848) (xy 229.440592 -289.24079) (xy 229.431192 -289.262088) (xy 229.431088 -289.273742)
			(xy 229.433628 -289.353752) (xy 229.434585 -289.365267) (xy 229.445443 -289.385637) (xy 229.454456 -289.392868)
			(xy 229.45471 -289.393122) (xy 229.475249 -289.408559) (xy 229.512385 -289.444068) (xy 229.544418 -289.48424)
			(xy 229.570769 -289.528349) (xy 229.59096 -289.575596) (xy 229.604625 -289.625126) (xy 229.611519 -289.676042)
			(xy 229.611936 -289.701732) (xy 229.61145 -289.728983) (xy 229.603694 -289.782931) (xy 229.588339 -289.835226)
			(xy 229.565697 -289.884803) (xy 229.536231 -289.930653) (xy 229.50054 -289.971844) (xy 229.459349 -290.007535)
			(xy 229.413499 -290.037001) (xy 229.363922 -290.059643) (xy 229.311627 -290.074998) (xy 229.257679 -290.082754)
			(xy 229.203177 -290.082754) (xy 229.149229 -290.074998) (xy 229.096934 -290.059643) (xy 229.047357 -290.037001)
			(xy 229.001507 -290.007535) (xy 228.960316 -289.971844) (xy 228.924625 -289.930653) (xy 228.895159 -289.884803)
			(xy 228.872517 -289.835226) (xy 228.857162 -289.782931) (xy 228.849406 -289.728983) (xy 228.84892 -289.701732)
			(xy 228.849448 -289.673871) (xy 228.857544 -289.618741) (xy 228.873569 -289.565374) (xy 228.897182 -289.514903)
			(xy 228.927881 -289.468402) (xy 228.965015 -289.426857) (xy 228.98608 -289.408616) (xy 228.986334 -289.408616)
			(xy 228.99489 -289.400698) (xy 229.004273 -289.379381) (xy 229.004368 -289.367722) (xy 229.001828 -289.287712)
			(xy 229.000852 -289.2762) (xy 228.99001 -289.255827) (xy 228.981 -289.248596) (xy 228.980746 -289.248342)
			(xy 228.960228 -289.232879) (xy 228.923093 -289.197373) (xy 228.891059 -289.157205) (xy 228.864707 -289.1131)
			(xy 228.844512 -289.065858) (xy 228.830842 -289.016333) (xy 228.823942 -288.965421) (xy 228.82352 -288.939732)
			(xy 218.565222 -288.939732) (xy 218.565222 -290.844732) (xy 236.659418 -290.844732) (xy 236.663489 -290.78911)
			(xy 236.675615 -290.734673) (xy 236.695538 -290.682582) (xy 236.722834 -290.633947) (xy 236.75692 -290.589804)
			(xy 236.797069 -290.551095) (xy 236.842427 -290.518644) (xy 236.892027 -290.493143) (xy 236.944811 -290.475136)
			(xy 236.999654 -290.465006) (xy 237.055388 -290.462969) (xy 237.110825 -290.469069) (xy 237.164782 -290.483175)
			(xy 237.216111 -290.504987) (xy 237.263717 -290.534041) (xy 237.306585 -290.569716) (xy 237.343802 -290.611253)
			(xy 237.374575 -290.657766) (xy 237.398247 -290.708263) (xy 237.414315 -290.76167) (xy 237.422435 -290.816846)
			(xy 237.422944 -290.844732) (xy 237.422435 -290.872618) (xy 237.414315 -290.927794) (xy 237.398247 -290.981201)
			(xy 237.374575 -291.031698) (xy 237.343802 -291.078211) (xy 237.306585 -291.119748) (xy 237.263717 -291.155423)
			(xy 237.216111 -291.184477) (xy 237.164782 -291.206289) (xy 237.110825 -291.220395) (xy 237.055388 -291.226495)
			(xy 236.999654 -291.224458) (xy 236.944811 -291.214328) (xy 236.892027 -291.196321) (xy 236.842427 -291.17082)
			(xy 236.797069 -291.138369) (xy 236.75692 -291.09966) (xy 236.722834 -291.055517) (xy 236.695538 -291.006882)
			(xy 236.675615 -290.954791) (xy 236.663489 -290.900354) (xy 236.659418 -290.844732) (xy 218.565222 -290.844732)
			(xy 218.565222 -291.614098) (xy 237.461804 -291.614098) (xy 237.465875 -291.558476) (xy 237.478001 -291.504039)
			(xy 237.497924 -291.451948) (xy 237.52522 -291.403313) (xy 237.559306 -291.35917) (xy 237.599455 -291.320461)
			(xy 237.644813 -291.28801) (xy 237.694413 -291.262509) (xy 237.747197 -291.244502) (xy 237.80204 -291.234372)
			(xy 237.857774 -291.232335) (xy 237.913211 -291.238435) (xy 237.967168 -291.252541) (xy 238.018497 -291.274353)
			(xy 238.066103 -291.303407) (xy 238.108971 -291.339082) (xy 238.146188 -291.380619) (xy 238.176961 -291.427132)
			(xy 238.200633 -291.477629) (xy 238.216701 -291.531036) (xy 238.224821 -291.586212) (xy 238.22533 -291.614098)
			(xy 238.224821 -291.641984) (xy 238.216701 -291.69716) (xy 238.200633 -291.750567) (xy 238.176961 -291.801064)
			(xy 238.146188 -291.847577) (xy 238.108971 -291.889114) (xy 238.066103 -291.924789) (xy 238.018497 -291.953843)
			(xy 237.967168 -291.975655) (xy 237.913211 -291.989761) (xy 237.857774 -291.995861) (xy 237.80204 -291.993824)
			(xy 237.747197 -291.983694) (xy 237.694413 -291.965687) (xy 237.644813 -291.940186) (xy 237.599455 -291.907735)
			(xy 237.559306 -291.869026) (xy 237.52522 -291.824883) (xy 237.497924 -291.776248) (xy 237.478001 -291.724157)
			(xy 237.465875 -291.66972) (xy 237.461804 -291.614098) (xy 218.565222 -291.614098) (xy 218.565222 -292.025578)
			(xy 226.184966 -292.025578) (xy 226.189037 -291.969956) (xy 226.201163 -291.915519) (xy 226.221086 -291.863428)
			(xy 226.248382 -291.814793) (xy 226.282468 -291.77065) (xy 226.322617 -291.731941) (xy 226.367975 -291.69949)
			(xy 226.417575 -291.673989) (xy 226.470359 -291.655982) (xy 226.525202 -291.645852) (xy 226.580936 -291.643815)
			(xy 226.636373 -291.649915) (xy 226.69033 -291.664021) (xy 226.741659 -291.685833) (xy 226.789265 -291.714887)
			(xy 226.832133 -291.750562) (xy 226.86935 -291.792099) (xy 226.900123 -291.838612) (xy 226.923795 -291.889109)
			(xy 226.939863 -291.942516) (xy 226.947983 -291.997692) (xy 226.948492 -292.025578) (xy 226.947983 -292.053464)
			(xy 226.939863 -292.10864) (xy 226.923795 -292.162047) (xy 226.900123 -292.212544) (xy 226.86935 -292.259057)
			(xy 226.836853 -292.295326) (xy 228.289102 -292.295326) (xy 228.293173 -292.239704) (xy 228.305299 -292.185267)
			(xy 228.325222 -292.133176) (xy 228.352518 -292.084541) (xy 228.386604 -292.040398) (xy 228.426753 -292.001689)
			(xy 228.472111 -291.969238) (xy 228.521711 -291.943737) (xy 228.574495 -291.92573) (xy 228.629338 -291.9156)
			(xy 228.685072 -291.913563) (xy 228.740509 -291.919663) (xy 228.794466 -291.933769) (xy 228.845795 -291.955581)
			(xy 228.893401 -291.984635) (xy 228.936269 -292.02031) (xy 228.973486 -292.061847) (xy 229.004259 -292.10836)
			(xy 229.027931 -292.158857) (xy 229.043999 -292.212264) (xy 229.052119 -292.26744) (xy 229.052628 -292.295326)
			(xy 240.233452 -292.295326) (xy 240.237523 -292.239704) (xy 240.249649 -292.185267) (xy 240.269572 -292.133176)
			(xy 240.296868 -292.084541) (xy 240.330954 -292.040398) (xy 240.371103 -292.001689) (xy 240.416461 -291.969238)
			(xy 240.466061 -291.943737) (xy 240.518845 -291.92573) (xy 240.573688 -291.9156) (xy 240.629422 -291.913563)
			(xy 240.684859 -291.919663) (xy 240.738816 -291.933769) (xy 240.790145 -291.955581) (xy 240.837751 -291.984635)
			(xy 240.880619 -292.02031) (xy 240.917836 -292.061847) (xy 240.948609 -292.10836) (xy 240.972281 -292.158857)
			(xy 240.988349 -292.212264) (xy 240.996469 -292.26744) (xy 240.996978 -292.295326) (xy 240.996469 -292.323212)
			(xy 240.988349 -292.378388) (xy 240.972281 -292.431795) (xy 240.948609 -292.482292) (xy 240.917836 -292.528805)
			(xy 240.880619 -292.570342) (xy 240.837751 -292.606017) (xy 240.790145 -292.635071) (xy 240.738816 -292.656883)
			(xy 240.684859 -292.670989) (xy 240.629422 -292.677089) (xy 240.573688 -292.675052) (xy 240.518845 -292.664922)
			(xy 240.466061 -292.646915) (xy 240.416461 -292.621414) (xy 240.371103 -292.588963) (xy 240.330954 -292.550254)
			(xy 240.296868 -292.506111) (xy 240.269572 -292.457476) (xy 240.249649 -292.405385) (xy 240.237523 -292.350948)
			(xy 240.233452 -292.295326) (xy 229.052628 -292.295326) (xy 229.052119 -292.323212) (xy 229.043999 -292.378388)
			(xy 229.027931 -292.431795) (xy 229.004259 -292.482292) (xy 228.973486 -292.528805) (xy 228.936269 -292.570342)
			(xy 228.893401 -292.606017) (xy 228.845795 -292.635071) (xy 228.794466 -292.656883) (xy 228.740509 -292.670989)
			(xy 228.685072 -292.677089) (xy 228.629338 -292.675052) (xy 228.574495 -292.664922) (xy 228.521711 -292.646915)
			(xy 228.472111 -292.621414) (xy 228.426753 -292.588963) (xy 228.386604 -292.550254) (xy 228.352518 -292.506111)
			(xy 228.325222 -292.457476) (xy 228.305299 -292.405385) (xy 228.293173 -292.350948) (xy 228.289102 -292.295326)
			(xy 226.836853 -292.295326) (xy 226.832133 -292.300594) (xy 226.789265 -292.336269) (xy 226.741659 -292.365323)
			(xy 226.69033 -292.387135) (xy 226.636373 -292.401241) (xy 226.580936 -292.407341) (xy 226.525202 -292.405304)
			(xy 226.470359 -292.395174) (xy 226.417575 -292.377167) (xy 226.367975 -292.351666) (xy 226.322617 -292.319215)
			(xy 226.282468 -292.280506) (xy 226.248382 -292.236363) (xy 226.221086 -292.187728) (xy 226.201163 -292.135637)
			(xy 226.189037 -292.0812) (xy 226.184966 -292.025578) (xy 218.565222 -292.025578) (xy 218.565222 -293.537132)
			(xy 233.241848 -293.537132) (xy 233.245919 -293.48151) (xy 233.258045 -293.427073) (xy 233.277968 -293.374982)
			(xy 233.305264 -293.326347) (xy 233.33935 -293.282204) (xy 233.379499 -293.243495) (xy 233.424857 -293.211044)
			(xy 233.474457 -293.185543) (xy 233.527241 -293.167536) (xy 233.582084 -293.157406) (xy 233.637818 -293.155369)
			(xy 233.693255 -293.161469) (xy 233.747212 -293.175575) (xy 233.798541 -293.197387) (xy 233.846147 -293.226441)
			(xy 233.889015 -293.262116) (xy 233.926232 -293.303653) (xy 233.957005 -293.350166) (xy 233.980677 -293.400663)
			(xy 233.996745 -293.45407) (xy 234.004865 -293.509246) (xy 234.005374 -293.537132) (xy 245.186198 -293.537132)
			(xy 245.190269 -293.48151) (xy 245.202395 -293.427073) (xy 245.222318 -293.374982) (xy 245.249614 -293.326347)
			(xy 245.2837 -293.282204) (xy 245.323849 -293.243495) (xy 245.369207 -293.211044) (xy 245.418807 -293.185543)
			(xy 245.471591 -293.167536) (xy 245.526434 -293.157406) (xy 245.582168 -293.155369) (xy 245.637605 -293.161469)
			(xy 245.691562 -293.175575) (xy 245.742891 -293.197387) (xy 245.790497 -293.226441) (xy 245.833365 -293.262116)
			(xy 245.870582 -293.303653) (xy 245.901355 -293.350166) (xy 245.925027 -293.400663) (xy 245.941095 -293.45407)
			(xy 245.949215 -293.509246) (xy 245.949724 -293.537132) (xy 245.949215 -293.565018) (xy 245.941095 -293.620194)
			(xy 245.925027 -293.673601) (xy 245.901355 -293.724098) (xy 245.870582 -293.770611) (xy 245.833365 -293.812148)
			(xy 245.790497 -293.847823) (xy 245.742891 -293.876877) (xy 245.691562 -293.898689) (xy 245.637605 -293.912795)
			(xy 245.582168 -293.918895) (xy 245.526434 -293.916858) (xy 245.471591 -293.906728) (xy 245.418807 -293.888721)
			(xy 245.369207 -293.86322) (xy 245.323849 -293.830769) (xy 245.2837 -293.79206) (xy 245.249614 -293.747917)
			(xy 245.222318 -293.699282) (xy 245.202395 -293.647191) (xy 245.190269 -293.592754) (xy 245.186198 -293.537132)
			(xy 234.005374 -293.537132) (xy 234.004865 -293.565018) (xy 233.996745 -293.620194) (xy 233.980677 -293.673601)
			(xy 233.957005 -293.724098) (xy 233.926232 -293.770611) (xy 233.889015 -293.812148) (xy 233.846147 -293.847823)
			(xy 233.798541 -293.876877) (xy 233.747212 -293.898689) (xy 233.693255 -293.912795) (xy 233.637818 -293.918895)
			(xy 233.582084 -293.916858) (xy 233.527241 -293.906728) (xy 233.474457 -293.888721) (xy 233.424857 -293.86322)
			(xy 233.379499 -293.830769) (xy 233.33935 -293.79206) (xy 233.305264 -293.747917) (xy 233.277968 -293.699282)
			(xy 233.258045 -293.647191) (xy 233.245919 -293.592754) (xy 233.241848 -293.537132) (xy 218.565222 -293.537132)
			(xy 218.565222 -293.948104) (xy 218.565646 -293.958173) (xy 218.573364 -293.976775) (xy 218.580208 -293.984172)
			(xy 221.549214 -296.953178) (xy 221.556057 -296.960577) (xy 221.563777 -296.979176) (xy 221.5642 -296.989246)
			(xy 221.5642 -310.520088) (xy 225.232699 -310.520088) (xy 225.236431 -310.466833) (xy 225.247551 -310.414618)
			(xy 225.265842 -310.364464) (xy 225.290946 -310.317349) (xy 225.322373 -310.274194) (xy 225.35951 -310.235842)
			(xy 225.380296 -310.21909) (xy 225.389057 -310.211527) (xy 225.399241 -310.190769) (xy 225.399854 -310.179212)
			(xy 225.399854 -310.098948) (xy 225.399272 -310.087381) (xy 225.389087 -310.066609) (xy 225.380296 -310.05907)
			(xy 225.357797 -310.040897) (xy 225.318063 -309.998873) (xy 225.285126 -309.951335) (xy 225.25974 -309.89937)
			(xy 225.242488 -309.844169) (xy 225.233763 -309.786997) (xy 225.23323 -309.75808) (xy 225.233636 -309.730825)
			(xy 225.241397 -309.67687) (xy 225.256758 -309.624569) (xy 225.279405 -309.574986) (xy 225.308879 -309.529131)
			(xy 225.344579 -309.487937) (xy 225.385777 -309.452244) (xy 225.431637 -309.422777) (xy 225.481223 -309.400137)
			(xy 225.533527 -309.384785) (xy 225.587483 -309.377032) (xy 225.614738 -309.376572) (xy 225.643655 -309.377108)
			(xy 225.700826 -309.385829) (xy 225.756026 -309.403082) (xy 225.807988 -309.42847) (xy 225.855522 -309.461412)
			(xy 225.897538 -309.501153) (xy 225.915728 -309.523638) (xy 225.923276 -309.532414) (xy 225.944045 -309.542588)
			(xy 225.955606 -309.543196) (xy 226.03587 -309.543196) (xy 226.047436 -309.54261) (xy 226.068207 -309.532426)
			(xy 226.075748 -309.523638) (xy 226.093978 -309.501187) (xy 226.135988 -309.461448) (xy 226.183515 -309.428504)
			(xy 226.235469 -309.40311) (xy 226.29066 -309.385847) (xy 226.347824 -309.377111) (xy 226.376738 -309.376572)
			(xy 226.403989 -309.377042) (xy 226.457937 -309.384804) (xy 226.51023 -309.400163) (xy 226.559806 -309.422807)
			(xy 226.605656 -309.452275) (xy 226.646845 -309.487968) (xy 226.682536 -309.529159) (xy 226.712002 -309.575009)
			(xy 226.734644 -309.624587) (xy 226.75 -309.676881) (xy 226.757759 -309.730829) (xy 226.758246 -309.75808)
			(xy 226.757734 -309.786997) (xy 226.749006 -309.84417) (xy 226.731749 -309.89937) (xy 226.706356 -309.951332)
			(xy 226.67341 -309.998865) (xy 226.633667 -310.040881) (xy 226.61118 -310.05907) (xy 226.602433 -310.066646)
			(xy 226.592242 -310.087394) (xy 226.591622 -310.098948) (xy 226.591622 -310.179212) (xy 226.592178 -310.190782)
			(xy 226.602382 -310.211553) (xy 226.61118 -310.21909) (xy 226.631941 -310.235868) (xy 226.669068 -310.27422)
			(xy 226.700486 -310.317372) (xy 226.725583 -310.364483) (xy 226.743868 -310.414632) (xy 226.754985 -310.46684)
			(xy 226.758716 -310.520088) (xy 231.279453 -310.520088) (xy 231.283184 -310.466835) (xy 231.294301 -310.414623)
			(xy 231.312588 -310.36447) (xy 231.337687 -310.317356) (xy 231.369108 -310.2742) (xy 231.406237 -310.235845)
			(xy 231.42702 -310.21909) (xy 231.435785 -310.211532) (xy 231.445966 -310.19077) (xy 231.446578 -310.179212)
			(xy 231.446578 -310.098948) (xy 231.445988 -310.087383) (xy 231.435808 -310.066611) (xy 231.42702 -310.05907)
			(xy 231.404526 -310.040891) (xy 231.364791 -309.998869) (xy 231.331852 -309.951332) (xy 231.306466 -309.899368)
			(xy 231.289212 -309.844168) (xy 231.280487 -309.786997) (xy 231.279954 -309.75808) (xy 231.280459 -309.73083)
			(xy 231.288217 -309.676885) (xy 231.303573 -309.624593) (xy 231.326214 -309.575018) (xy 231.355679 -309.52917)
			(xy 231.391368 -309.487981) (xy 231.432555 -309.452289) (xy 231.478402 -309.422822) (xy 231.527976 -309.400179)
			(xy 231.580267 -309.384821) (xy 231.634212 -309.37706) (xy 231.661462 -309.376572) (xy 231.690379 -309.37709)
			(xy 231.747552 -309.385815) (xy 231.802752 -309.403071) (xy 231.854714 -309.428463) (xy 231.902248 -309.461408)
			(xy 231.944263 -309.501151) (xy 231.962452 -309.523638) (xy 231.970033 -309.53238) (xy 231.990777 -309.542573)
			(xy 232.00233 -309.543196) (xy 232.082594 -309.543196) (xy 232.094162 -309.542624) (xy 232.114933 -309.532431)
			(xy 232.122472 -309.523638) (xy 232.140688 -309.501176) (xy 232.182702 -309.461438) (xy 232.230231 -309.428495)
			(xy 232.282188 -309.403103) (xy 232.337381 -309.385842) (xy 232.394547 -309.377109) (xy 232.423462 -309.376572)
			(xy 232.450713 -309.377091) (xy 232.504661 -309.384842) (xy 232.556957 -309.400192) (xy 232.606535 -309.422829)
			(xy 232.652388 -309.452291) (xy 232.69358 -309.487979) (xy 232.729274 -309.529166) (xy 232.758743 -309.575014)
			(xy 232.781388 -309.624589) (xy 232.796746 -309.676882) (xy 232.804505 -309.730829) (xy 232.80497 -309.75808)
			(xy 232.804449 -309.786997) (xy 232.795722 -309.844169) (xy 232.778465 -309.899368) (xy 232.753074 -309.95133)
			(xy 232.720131 -309.998864) (xy 232.68039 -310.04088) (xy 232.657904 -310.05907) (xy 232.649161 -310.06665)
			(xy 232.638967 -310.087395) (xy 232.638346 -310.098948) (xy 232.638346 -310.179212) (xy 232.638894 -310.190783)
			(xy 232.649103 -310.211555) (xy 232.657904 -310.21909) (xy 232.678669 -310.235866) (xy 232.715802 -310.274215)
			(xy 232.747227 -310.317366) (xy 232.772329 -310.364477) (xy 232.790618 -310.414627) (xy 232.801737 -310.466837)
			(xy 232.805469 -310.520088) (xy 239.165648 -310.520088) (xy 239.169379 -310.466836) (xy 239.180496 -310.414624)
			(xy 239.198782 -310.364471) (xy 239.223881 -310.317356) (xy 239.255301 -310.2742) (xy 239.29243 -310.235845)
			(xy 239.313212 -310.21909) (xy 239.321976 -310.21153) (xy 239.332158 -310.19077) (xy 239.33277 -310.179212)
			(xy 239.33277 -310.098948) (xy 239.332182 -310.087382) (xy 239.322001 -310.06661) (xy 239.313212 -310.05907)
			(xy 239.290717 -310.040893) (xy 239.250982 -309.998871) (xy 239.218044 -309.951333) (xy 239.192657 -309.899369)
			(xy 239.175404 -309.844169) (xy 239.166679 -309.786997) (xy 239.166146 -309.75808) (xy 239.166659 -309.73083)
			(xy 239.174417 -309.676886) (xy 239.189772 -309.624595) (xy 239.212413 -309.57502) (xy 239.241877 -309.529172)
			(xy 239.277565 -309.487983) (xy 239.318751 -309.452292) (xy 239.364597 -309.422825) (xy 239.41417 -309.400182)
			(xy 239.466461 -309.384823) (xy 239.520404 -309.377061) (xy 239.547654 -309.376572) (xy 239.576571 -309.377096)
			(xy 239.633743 -309.38582) (xy 239.688943 -309.403075) (xy 239.740905 -309.428466) (xy 239.788439 -309.46141)
			(xy 239.830455 -309.501152) (xy 239.848644 -309.523638) (xy 239.856185 -309.532422) (xy 239.87696 -309.542592)
			(xy 239.888522 -309.543196) (xy 239.968786 -309.543196) (xy 239.980353 -309.542619) (xy 240.001124 -309.532429)
			(xy 240.008664 -309.523638) (xy 240.026885 -309.50118) (xy 240.068897 -309.461441) (xy 240.116426 -309.428498)
			(xy 240.168381 -309.403105) (xy 240.223574 -309.385844) (xy 240.28074 -309.37711) (xy 240.309654 -309.376572)
			(xy 240.336905 -309.377098) (xy 240.390852 -309.384848) (xy 240.443148 -309.400197) (xy 240.492727 -309.422833)
			(xy 240.538579 -309.452294) (xy 240.579772 -309.487982) (xy 240.615466 -309.529168) (xy 240.644935 -309.575015)
			(xy 240.667579 -309.62459) (xy 240.682938 -309.676883) (xy 240.690697 -309.730829) (xy 240.691162 -309.75808)
			(xy 240.690644 -309.786997) (xy 240.681917 -309.844169) (xy 240.66466 -309.899368) (xy 240.639268 -309.95133)
			(xy 240.606324 -309.998864) (xy 240.566582 -310.04088) (xy 240.544096 -310.05907) (xy 240.535351 -310.066649)
			(xy 240.525159 -310.087395) (xy 240.524538 -310.098948) (xy 240.524538 -310.179212) (xy 240.525089 -310.190783)
			(xy 240.535296 -310.211554) (xy 240.544096 -310.21909) (xy 240.564861 -310.235866) (xy 240.601995 -310.274214)
			(xy 240.63342 -310.317366) (xy 240.658523 -310.364476) (xy 240.676813 -310.414627) (xy 240.687932 -310.466837)
			(xy 240.691664 -310.520088) (xy 245.212363 -310.520088) (xy 245.216094 -310.466835) (xy 245.227212 -310.414622)
			(xy 245.245499 -310.364469) (xy 245.270599 -310.317354) (xy 245.302022 -310.274199) (xy 245.339153 -310.235844)
			(xy 245.359936 -310.21909) (xy 245.368704 -310.211534) (xy 245.378883 -310.190771) (xy 245.379494 -310.179212)
			(xy 245.379494 -310.098948) (xy 245.378898 -310.087383) (xy 245.368722 -310.066612) (xy 245.359936 -310.05907)
			(xy 245.337446 -310.040887) (xy 245.297709 -309.998867) (xy 245.26477 -309.95133) (xy 245.239382 -309.899367)
			(xy 245.222128 -309.844168) (xy 245.213403 -309.786997) (xy 245.21287 -309.75808) (xy 245.213359 -309.730829)
			(xy 245.221118 -309.676883) (xy 245.236474 -309.624589) (xy 245.259116 -309.575014) (xy 245.288583 -309.529164)
			(xy 245.324274 -309.487975) (xy 245.365463 -309.452284) (xy 245.411312 -309.422817) (xy 245.460888 -309.400175)
			(xy 245.513181 -309.384818) (xy 245.567127 -309.377059) (xy 245.594378 -309.376572) (xy 245.623296 -309.377079)
			(xy 245.680469 -309.385806) (xy 245.735669 -309.403065) (xy 245.787631 -309.428458) (xy 245.835165 -309.461405)
			(xy 245.877179 -309.50115) (xy 245.895368 -309.523638) (xy 245.902942 -309.532387) (xy 245.923692 -309.542576)
			(xy 245.935246 -309.543196) (xy 246.01551 -309.543196) (xy 246.027079 -309.542633) (xy 246.04785 -309.532433)
			(xy 246.055388 -309.523638) (xy 246.073595 -309.501168) (xy 246.115611 -309.46143) (xy 246.163142 -309.428489)
			(xy 246.2151 -309.403098) (xy 246.270295 -309.385839) (xy 246.327463 -309.377108) (xy 246.356378 -309.376572)
			(xy 246.383629 -309.377076) (xy 246.437578 -309.384829) (xy 246.489874 -309.400181) (xy 246.539452 -309.42282)
			(xy 246.585305 -309.452284) (xy 246.626497 -309.487973) (xy 246.662191 -309.529162) (xy 246.69166 -309.575011)
			(xy 246.714304 -309.624587) (xy 246.729662 -309.676881) (xy 246.737421 -309.730829) (xy 246.737886 -309.75808)
			(xy 246.737359 -309.786997) (xy 246.728632 -309.844168) (xy 246.711376 -309.899366) (xy 246.685986 -309.951328)
			(xy 246.653044 -309.998862) (xy 246.613305 -310.04088) (xy 246.59082 -310.05907) (xy 246.582063 -310.066636)
			(xy 246.57188 -310.087392) (xy 246.571262 -310.098948) (xy 246.571262 -310.179212) (xy 246.571804 -310.190784)
			(xy 246.582017 -310.211556) (xy 246.59082 -310.21909) (xy 246.611584 -310.235867) (xy 246.648716 -310.274216)
			(xy 246.680139 -310.317368) (xy 246.70524 -310.364478) (xy 246.723528 -310.414628) (xy 246.734647 -310.466838)
			(xy 246.738378 -310.520088) (xy 246.73465 -310.573338) (xy 246.723535 -310.625548) (xy 246.70525 -310.675699)
			(xy 246.680152 -310.722812) (xy 246.648732 -310.765965) (xy 246.611602 -310.804317) (xy 246.59082 -310.82107)
			(xy 246.582063 -310.828636) (xy 246.57188 -310.849392) (xy 246.571262 -310.860948) (xy 246.571262 -310.941212)
			(xy 246.571804 -310.952784) (xy 246.582017 -310.973556) (xy 246.59082 -310.98109) (xy 246.613303 -310.999282)
			(xy 246.653037 -311.041302) (xy 246.685976 -311.088837) (xy 246.711364 -311.140798) (xy 246.728621 -311.195995)
			(xy 246.73735 -311.253164) (xy 246.737886 -311.28208) (xy 246.737426 -311.309333) (xy 246.729671 -311.363286)
			(xy 246.714317 -311.415585) (xy 246.691675 -311.465166) (xy 246.662207 -311.511021) (xy 246.626513 -311.552214)
			(xy 246.585319 -311.587908) (xy 246.539465 -311.617376) (xy 246.489883 -311.640017) (xy 246.437584 -311.655372)
			(xy 246.383631 -311.663126) (xy 246.356378 -311.663588) (xy 246.327463 -311.663018) (xy 246.270294 -311.654301)
			(xy 246.215096 -311.637053) (xy 246.163134 -311.611671) (xy 246.115599 -311.578737) (xy 246.07358 -311.539004)
			(xy 246.055388 -311.516522) (xy 246.04784 -311.507746) (xy 246.02707 -311.497574) (xy 246.01551 -311.496964)
			(xy 245.935246 -311.496964) (xy 245.923678 -311.497538) (xy 245.902905 -311.507728) (xy 245.895368 -311.516522)
			(xy 245.877201 -311.539025) (xy 245.835175 -311.578758) (xy 245.787635 -311.611694) (xy 245.735669 -311.637079)
			(xy 245.680468 -311.654331) (xy 245.623295 -311.663056) (xy 245.594378 -311.663588) (xy 245.567125 -311.663143)
			(xy 245.513175 -311.655383) (xy 245.460878 -311.640024) (xy 245.4113 -311.617378) (xy 245.365448 -311.587908)
			(xy 245.324258 -311.552212) (xy 245.288567 -311.511018) (xy 245.259101 -311.465163) (xy 245.236462 -311.415582)
			(xy 245.221108 -311.363284) (xy 245.213354 -311.309333) (xy 245.21287 -311.28208) (xy 245.213419 -311.253164)
			(xy 245.222138 -311.195993) (xy 245.239388 -311.140794) (xy 245.264774 -311.088831) (xy 245.297714 -311.041297)
			(xy 245.337452 -310.99928) (xy 245.359936 -310.98109) (xy 245.368704 -310.973534) (xy 245.378883 -310.952771)
			(xy 245.379494 -310.941212) (xy 245.379494 -310.860948) (xy 245.378898 -310.849383) (xy 245.368722 -310.828612)
			(xy 245.359936 -310.82107) (xy 245.339134 -310.80434) (xy 245.302006 -310.765983) (xy 245.270586 -310.722825)
			(xy 245.245489 -310.675709) (xy 245.227205 -310.625554) (xy 245.216091 -310.573341) (xy 245.212363 -310.520088)
			(xy 240.691664 -310.520088) (xy 240.687935 -310.573339) (xy 240.676819 -310.62555) (xy 240.658533 -310.675701)
			(xy 240.633434 -310.722814) (xy 240.602011 -310.765967) (xy 240.564879 -310.804318) (xy 240.544096 -310.82107)
			(xy 240.535351 -310.828649) (xy 240.525159 -310.849395) (xy 240.524538 -310.860948) (xy 240.524538 -310.941212)
			(xy 240.525089 -310.952783) (xy 240.535296 -310.973554) (xy 240.544096 -310.98109) (xy 240.566574 -310.999288)
			(xy 240.60631 -311.041306) (xy 240.639249 -311.088839) (xy 240.664639 -311.140799) (xy 240.681896 -311.195996)
			(xy 240.690626 -311.253164) (xy 240.691162 -311.28208) (xy 240.690726 -311.309334) (xy 240.68297 -311.363289)
			(xy 240.667615 -311.41559) (xy 240.644971 -311.465173) (xy 240.615501 -311.511028) (xy 240.579804 -311.552223)
			(xy 240.538608 -311.587917) (xy 240.49275 -311.617384) (xy 240.443166 -311.640024) (xy 240.390863 -311.655376)
			(xy 240.336908 -311.663128) (xy 240.309654 -311.663588) (xy 240.280738 -311.663035) (xy 240.223568 -311.654314)
			(xy 240.16837 -311.637063) (xy 240.116408 -311.611678) (xy 240.068873 -311.57874) (xy 240.026855 -311.539005)
			(xy 240.008664 -311.516522) (xy 240.001127 -311.507735) (xy 239.980349 -311.497569) (xy 239.968786 -311.496964)
			(xy 239.888522 -311.496964) (xy 239.876952 -311.497525) (xy 239.85618 -311.507724) (xy 239.848644 -311.516522)
			(xy 239.830434 -311.538989) (xy 239.788417 -311.578724) (xy 239.740886 -311.611665) (xy 239.688929 -311.637055)
			(xy 239.633735 -311.654316) (xy 239.576569 -311.66305) (xy 239.547654 -311.663588) (xy 239.520401 -311.663165)
			(xy 239.46645 -311.655402) (xy 239.414153 -311.64004) (xy 239.364574 -311.617392) (xy 239.318723 -311.587919)
			(xy 239.277532 -311.552221) (xy 239.241842 -311.511024) (xy 239.212377 -311.465168) (xy 239.189737 -311.415586)
			(xy 239.174384 -311.363286) (xy 239.16663 -311.309333) (xy 239.166146 -311.28208) (xy 239.166705 -311.253164)
			(xy 239.175423 -311.195994) (xy 239.192672 -311.140796) (xy 239.218056 -311.088833) (xy 239.250993 -311.041299)
			(xy 239.290729 -310.999281) (xy 239.313212 -310.98109) (xy 239.321976 -310.97353) (xy 239.332158 -310.95277)
			(xy 239.33277 -310.941212) (xy 239.33277 -310.860948) (xy 239.332182 -310.849382) (xy 239.322001 -310.82861)
			(xy 239.313212 -310.82107) (xy 239.292411 -310.804339) (xy 239.255285 -310.765981) (xy 239.223868 -310.722823)
			(xy 239.198772 -310.675707) (xy 239.180489 -310.625553) (xy 239.169376 -310.57334) (xy 239.165648 -310.520088)
			(xy 232.805469 -310.520088) (xy 232.80174 -310.573338) (xy 232.790625 -310.625549) (xy 232.772339 -310.675701)
			(xy 232.74724 -310.722813) (xy 232.715818 -310.765966) (xy 232.678687 -310.804317) (xy 232.657904 -310.82107)
			(xy 232.649161 -310.82865) (xy 232.638967 -310.849395) (xy 232.638346 -310.860948) (xy 232.638346 -310.941212)
			(xy 232.638894 -310.952783) (xy 232.649103 -310.973555) (xy 232.657904 -310.98109) (xy 232.680384 -310.999286)
			(xy 232.720119 -311.041305) (xy 232.753058 -311.088839) (xy 232.778447 -311.140799) (xy 232.795704 -311.195996)
			(xy 232.804434 -311.253164) (xy 232.80497 -311.28208) (xy 232.804526 -311.309334) (xy 232.796771 -311.363288)
			(xy 232.781415 -311.415588) (xy 232.758772 -311.465171) (xy 232.729303 -311.511026) (xy 232.693607 -311.55222)
			(xy 232.652411 -311.587914) (xy 232.606555 -311.617381) (xy 232.556971 -311.640022) (xy 232.50467 -311.655375)
			(xy 232.450716 -311.663127) (xy 232.423462 -311.663588) (xy 232.394547 -311.66303) (xy 232.337377 -311.65431)
			(xy 232.282179 -311.63706) (xy 232.230217 -311.611676) (xy 232.182682 -311.578739) (xy 232.140663 -311.539005)
			(xy 232.122472 -311.516522) (xy 232.114931 -311.507739) (xy 232.094156 -311.49757) (xy 232.082594 -311.496964)
			(xy 232.00233 -311.496964) (xy 231.990761 -311.497529) (xy 231.969988 -311.507725) (xy 231.962452 -311.516522)
			(xy 231.944237 -311.538985) (xy 231.902222 -311.578721) (xy 231.854692 -311.611661) (xy 231.802735 -311.637053)
			(xy 231.747542 -311.654314) (xy 231.690376 -311.663049) (xy 231.661462 -311.663588) (xy 231.634209 -311.663157)
			(xy 231.580258 -311.655395) (xy 231.527961 -311.640034) (xy 231.478382 -311.617387) (xy 231.432531 -311.587915)
			(xy 231.391341 -311.552218) (xy 231.35565 -311.511022) (xy 231.326185 -311.465167) (xy 231.303545 -311.415584)
			(xy 231.288192 -311.363285) (xy 231.280438 -311.309333) (xy 231.279954 -311.28208) (xy 231.280509 -311.253164)
			(xy 231.289228 -311.195994) (xy 231.306477 -311.140795) (xy 231.331862 -311.088833) (xy 231.3648 -311.041298)
			(xy 231.404537 -310.999281) (xy 231.42702 -310.98109) (xy 231.435785 -310.973532) (xy 231.445966 -310.95277)
			(xy 231.446578 -310.941212) (xy 231.446578 -310.860948) (xy 231.445988 -310.849383) (xy 231.435808 -310.828611)
			(xy 231.42702 -310.82107) (xy 231.406219 -310.804339) (xy 231.369092 -310.765981) (xy 231.337674 -310.722823)
			(xy 231.312578 -310.675707) (xy 231.294295 -310.625553) (xy 231.283181 -310.57334) (xy 231.279453 -310.520088)
			(xy 226.758716 -310.520088) (xy 226.754988 -310.573336) (xy 226.743875 -310.625544) (xy 226.725593 -310.675694)
			(xy 226.700499 -310.722807) (xy 226.669084 -310.765961) (xy 226.63196 -310.804316) (xy 226.61118 -310.82107)
			(xy 226.602433 -310.828646) (xy 226.592242 -310.849394) (xy 226.591622 -310.860948) (xy 226.591622 -310.941212)
			(xy 226.592178 -310.952782) (xy 226.602382 -310.973553) (xy 226.61118 -310.98109) (xy 226.633655 -310.999292)
			(xy 226.673391 -311.041309) (xy 226.706332 -311.088841) (xy 226.731722 -311.1408) (xy 226.74898 -311.195996)
			(xy 226.75771 -311.253165) (xy 226.758246 -311.28208) (xy 226.757703 -311.309329) (xy 226.74995 -311.363273)
			(xy 226.7346 -311.415564) (xy 226.711964 -311.465139) (xy 226.682503 -311.510987) (xy 226.646818 -311.552177)
			(xy 226.605634 -311.587868) (xy 226.559789 -311.617336) (xy 226.510218 -311.63998) (xy 226.457929 -311.655338)
			(xy 226.403987 -311.663099) (xy 226.376738 -311.663588) (xy 226.347822 -311.663047) (xy 226.290652 -311.654323)
			(xy 226.235453 -311.63707) (xy 226.183491 -311.611683) (xy 226.135957 -311.578743) (xy 226.093939 -311.539006)
			(xy 226.075748 -311.516522) (xy 226.068174 -311.507773) (xy 226.047424 -311.497586) (xy 226.03587 -311.496964)
			(xy 225.955606 -311.496964) (xy 225.944035 -311.497516) (xy 225.923263 -311.507721) (xy 225.915728 -311.516522)
			(xy 225.897527 -311.538997) (xy 225.855508 -311.578731) (xy 225.807975 -311.611671) (xy 225.756016 -311.63706)
			(xy 225.700821 -311.654319) (xy 225.643653 -311.663051) (xy 225.614738 -311.663588) (xy 225.587485 -311.663109)
			(xy 225.533534 -311.655357) (xy 225.481235 -311.640005) (xy 225.431654 -311.617365) (xy 225.385799 -311.587899)
			(xy 225.344606 -311.552207) (xy 225.308911 -311.511015) (xy 225.279443 -311.465162) (xy 225.256802 -311.415582)
			(xy 225.241447 -311.363284) (xy 225.233692 -311.309333) (xy 225.23323 -311.28208) (xy 225.233795 -311.253165)
			(xy 225.242513 -311.195995) (xy 225.259761 -311.140797) (xy 225.285143 -311.088835) (xy 225.31808 -311.0413)
			(xy 225.357814 -310.999281) (xy 225.380296 -310.98109) (xy 225.389057 -310.973527) (xy 225.399241 -310.952769)
			(xy 225.399854 -310.941212) (xy 225.399854 -310.860948) (xy 225.399272 -310.849381) (xy 225.389087 -310.828609)
			(xy 225.380296 -310.82107) (xy 225.359492 -310.804341) (xy 225.322357 -310.765987) (xy 225.290933 -310.72283)
			(xy 225.265832 -310.675714) (xy 225.247545 -310.625558) (xy 225.236428 -310.573343) (xy 225.232699 -310.520088)
			(xy 221.5642 -310.520088) (xy 221.5642 -313.076827) (xy 222.352414 -313.076827) (xy 222.356139 -313.023581)
			(xy 222.36725 -312.971374) (xy 222.38553 -312.921226) (xy 222.410622 -312.874115) (xy 222.442035 -312.830962)
			(xy 222.479157 -312.792608) (xy 222.499936 -312.775854) (xy 222.50872 -312.768314) (xy 222.51889 -312.747538)
			(xy 222.519494 -312.735976) (xy 222.519494 -312.655712) (xy 222.518919 -312.644145) (xy 222.508728 -312.623374)
			(xy 222.499936 -312.615834) (xy 222.477476 -312.597615) (xy 222.437738 -312.555602) (xy 222.404795 -312.508073)
			(xy 222.379402 -312.456117) (xy 222.362141 -312.400924) (xy 222.353407 -312.343759) (xy 222.35287 -312.314844)
			(xy 222.353356 -312.287593) (xy 222.361112 -312.233645) (xy 222.376467 -312.18135) (xy 222.399109 -312.131773)
			(xy 222.428575 -312.085923) (xy 222.464266 -312.044732) (xy 222.505457 -312.009041) (xy 222.551307 -311.979575)
			(xy 222.600884 -311.956933) (xy 222.653179 -311.941578) (xy 222.707127 -311.933822) (xy 222.761629 -311.933822)
			(xy 222.815577 -311.941578) (xy 222.867872 -311.956933) (xy 222.917449 -311.979575) (xy 222.963299 -312.009041)
			(xy 223.00449 -312.044732) (xy 223.040181 -312.085923) (xy 223.069647 -312.131773) (xy 223.092289 -312.18135)
			(xy 223.107644 -312.233645) (xy 223.1154 -312.287593) (xy 223.115886 -312.314844) (xy 223.115333 -312.34376)
			(xy 223.106612 -312.40093) (xy 223.089361 -312.456128) (xy 223.063976 -312.50809) (xy 223.031038 -312.555625)
			(xy 222.991303 -312.597643) (xy 222.96882 -312.615834) (xy 222.960034 -312.623372) (xy 222.949867 -312.644149)
			(xy 222.949262 -312.655712) (xy 222.949262 -312.735976) (xy 222.949825 -312.747545) (xy 222.960023 -312.768318)
			(xy 222.96882 -312.775854) (xy 222.989647 -312.792555) (xy 223.02678 -312.830913) (xy 223.058203 -312.874074)
			(xy 223.083303 -312.921193) (xy 223.101588 -312.971352) (xy 223.112703 -313.02357) (xy 223.116429 -313.076827)
			(xy 223.113276 -313.121801) (xy 223.568279 -313.121801) (xy 223.572008 -313.068551) (xy 223.583124 -313.01634)
			(xy 223.601408 -312.966188) (xy 223.626505 -312.919075) (xy 223.657924 -312.87592) (xy 223.695052 -312.837566)
			(xy 223.715834 -312.820812) (xy 223.724592 -312.813246) (xy 223.734776 -312.79249) (xy 223.735392 -312.780934)
			(xy 223.735392 -312.70067) (xy 223.734784 -312.689107) (xy 223.724616 -312.668335) (xy 223.715834 -312.660792)
			(xy 223.693354 -312.642597) (xy 223.653617 -312.600579) (xy 223.620676 -312.553045) (xy 223.595287 -312.501085)
			(xy 223.578031 -312.445887) (xy 223.569302 -312.388718) (xy 223.568768 -312.359802) (xy 223.569254 -312.332551)
			(xy 223.57701 -312.278603) (xy 223.592365 -312.226308) (xy 223.615007 -312.176731) (xy 223.644473 -312.130881)
			(xy 223.680164 -312.08969) (xy 223.721355 -312.053999) (xy 223.767205 -312.024533) (xy 223.816782 -312.001891)
			(xy 223.869077 -311.986536) (xy 223.923025 -311.97878) (xy 223.977527 -311.97878) (xy 224.031475 -311.986536)
			(xy 224.08377 -312.001891) (xy 224.133347 -312.024533) (xy 224.179197 -312.053999) (xy 224.220388 -312.08969)
			(xy 224.256079 -312.130881) (xy 224.285545 -312.176731) (xy 224.308187 -312.226308) (xy 224.323542 -312.278603)
			(xy 224.331298 -312.332551) (xy 224.331784 -312.359802) (xy 224.331273 -312.388719) (xy 224.322543 -312.445891)
			(xy 224.305284 -312.50109) (xy 224.279891 -312.553052) (xy 224.246946 -312.600586) (xy 224.207204 -312.642602)
			(xy 224.184718 -312.660792) (xy 224.17595 -312.668347) (xy 224.165773 -312.689112) (xy 224.16516 -312.70067)
			(xy 224.16516 -312.780934) (xy 224.165747 -312.7925) (xy 224.175928 -312.813273) (xy 224.184718 -312.820812)
			(xy 224.205504 -312.837562) (xy 224.242637 -312.875915) (xy 224.27406 -312.919069) (xy 224.29916 -312.966183)
			(xy 224.317448 -313.016336) (xy 224.328565 -313.068549) (xy 224.332295 -313.121801) (xy 224.329501 -313.161688)
			(xy 224.841563 -313.161688) (xy 224.845294 -313.108435) (xy 224.856412 -313.056222) (xy 224.874699 -313.006069)
			(xy 224.899799 -312.958954) (xy 224.931222 -312.915799) (xy 224.968353 -312.877444) (xy 224.989136 -312.86069)
			(xy 224.997904 -312.853134) (xy 225.008083 -312.832371) (xy 225.008694 -312.820812) (xy 225.008694 -312.740548)
			(xy 225.008098 -312.728983) (xy 224.997922 -312.708212) (xy 224.989136 -312.70067) (xy 224.966646 -312.682487)
			(xy 224.926909 -312.640467) (xy 224.89397 -312.59293) (xy 224.868582 -312.540967) (xy 224.851328 -312.485768)
			(xy 224.842603 -312.428597) (xy 224.84207 -312.39968) (xy 224.842556 -312.372429) (xy 224.850312 -312.318481)
			(xy 224.865667 -312.266186) (xy 224.888309 -312.216609) (xy 224.917775 -312.170759) (xy 224.953466 -312.129568)
			(xy 224.994657 -312.093877) (xy 225.040507 -312.064411) (xy 225.090084 -312.041769) (xy 225.142379 -312.026414)
			(xy 225.196327 -312.018658) (xy 225.250829 -312.018658) (xy 225.304777 -312.026414) (xy 225.357072 -312.041769)
			(xy 225.406649 -312.064411) (xy 225.452499 -312.093877) (xy 225.49369 -312.129568) (xy 225.529381 -312.170759)
			(xy 225.558847 -312.216609) (xy 225.581489 -312.266186) (xy 225.596844 -312.318481) (xy 225.6046 -312.372429)
			(xy 225.605086 -312.39968) (xy 225.604559 -312.428597) (xy 225.595832 -312.485768) (xy 225.578576 -312.540966)
			(xy 225.553186 -312.592928) (xy 225.520244 -312.640462) (xy 225.480505 -312.68248) (xy 225.45802 -312.70067)
			(xy 225.449263 -312.708236) (xy 225.43908 -312.728992) (xy 225.438462 -312.740548) (xy 225.438462 -312.820812)
			(xy 225.439004 -312.832384) (xy 225.449217 -312.853156) (xy 225.45802 -312.86069) (xy 225.478784 -312.877467)
			(xy 225.515916 -312.915816) (xy 225.547339 -312.958968) (xy 225.57244 -313.006078) (xy 225.590728 -313.056228)
			(xy 225.601847 -313.108438) (xy 225.605578 -313.161688) (xy 225.60185 -313.214938) (xy 225.590735 -313.267148)
			(xy 225.57245 -313.317299) (xy 225.547352 -313.364412) (xy 225.515932 -313.407565) (xy 225.478802 -313.445917)
			(xy 225.45802 -313.46267) (xy 225.449263 -313.470236) (xy 225.43908 -313.490992) (xy 225.438462 -313.502548)
			(xy 225.438462 -313.582812) (xy 225.439004 -313.594384) (xy 225.449217 -313.615156) (xy 225.45802 -313.62269)
			(xy 225.480503 -313.640882) (xy 225.520237 -313.682902) (xy 225.553176 -313.730437) (xy 225.578564 -313.782398)
			(xy 225.595821 -313.837595) (xy 225.60455 -313.894764) (xy 225.605086 -313.92368) (xy 225.6046 -313.950931)
			(xy 225.596844 -314.004879) (xy 225.581489 -314.057174) (xy 225.558847 -314.106751) (xy 225.529381 -314.152601)
			(xy 225.49369 -314.193792) (xy 225.452499 -314.229483) (xy 225.406649 -314.258949) (xy 225.357072 -314.281591)
			(xy 225.304777 -314.296946) (xy 225.250829 -314.304702) (xy 225.196327 -314.304702) (xy 225.142379 -314.296946)
			(xy 225.090084 -314.281591) (xy 225.040507 -314.258949) (xy 224.994657 -314.229483) (xy 224.953466 -314.193792)
			(xy 224.917775 -314.152601) (xy 224.888309 -314.106751) (xy 224.865667 -314.057174) (xy 224.850312 -314.004879)
			(xy 224.842556 -313.950931) (xy 224.84207 -313.92368) (xy 224.842619 -313.894764) (xy 224.851338 -313.837593)
			(xy 224.868588 -313.782394) (xy 224.893974 -313.730431) (xy 224.926914 -313.682897) (xy 224.966652 -313.64088)
			(xy 224.989136 -313.62269) (xy 224.997904 -313.615134) (xy 225.008083 -313.594371) (xy 225.008694 -313.582812)
			(xy 225.008694 -313.502548) (xy 225.008098 -313.490983) (xy 224.997922 -313.470212) (xy 224.989136 -313.46267)
			(xy 224.968334 -313.44594) (xy 224.931206 -313.407583) (xy 224.899786 -313.364425) (xy 224.874689 -313.317309)
			(xy 224.856405 -313.267154) (xy 224.845291 -313.214941) (xy 224.841563 -313.161688) (xy 224.329501 -313.161688)
			(xy 224.328565 -313.175054) (xy 224.317447 -313.227266) (xy 224.299159 -313.277419) (xy 224.274059 -313.324533)
			(xy 224.242635 -313.367687) (xy 224.205502 -313.406039) (xy 224.184718 -313.422792) (xy 224.17595 -313.430347)
			(xy 224.165773 -313.451112) (xy 224.16516 -313.46267) (xy 224.16516 -313.542934) (xy 224.165747 -313.5545)
			(xy 224.175928 -313.575273) (xy 224.184718 -313.582812) (xy 224.207211 -313.600992) (xy 224.246945 -313.643014)
			(xy 224.279882 -313.690552) (xy 224.305269 -313.742515) (xy 224.322523 -313.797714) (xy 224.33125 -313.854885)
			(xy 224.331784 -313.883802) (xy 224.331355 -313.909545) (xy 224.324435 -313.960563) (xy 224.310722 -314.010189)
			(xy 224.290463 -314.057521) (xy 224.264028 -314.101701) (xy 224.231894 -314.141928) (xy 224.194646 -314.177471)
			(xy 224.17405 -314.19292) (xy 224.163636 -314.200286) (xy 224.15246 -314.222892) (xy 224.156524 -314.332874)
			(xy 224.169224 -314.354718) (xy 224.180146 -314.361576) (xy 224.203415 -314.376576) (xy 224.245749 -314.41225)
			(xy 224.282478 -314.453672) (xy 224.312831 -314.49997) (xy 224.336169 -314.550171) (xy 224.352002 -314.603219)
			(xy 224.359997 -314.658) (xy 224.360486 -314.68568) (xy 224.359959 -314.714597) (xy 224.351232 -314.771768)
			(xy 224.333976 -314.826966) (xy 224.308586 -314.878928) (xy 224.275644 -314.926462) (xy 224.235905 -314.96848)
			(xy 224.21342 -314.98667) (xy 224.204663 -314.994236) (xy 224.19448 -315.014992) (xy 224.193862 -315.026548)
			(xy 224.193862 -315.106812) (xy 224.194404 -315.118384) (xy 224.204617 -315.139156) (xy 224.21342 -315.14669)
			(xy 224.235903 -315.164882) (xy 224.275637 -315.206902) (xy 224.308576 -315.254437) (xy 224.333964 -315.306398)
			(xy 224.351221 -315.361595) (xy 224.35995 -315.418764) (xy 224.360486 -315.44768) (xy 227.43287 -315.44768)
			(xy 227.433419 -315.418764) (xy 227.442138 -315.361593) (xy 227.459388 -315.306394) (xy 227.484774 -315.254431)
			(xy 227.517714 -315.206897) (xy 227.557452 -315.16488) (xy 227.579936 -315.14669) (xy 227.588704 -315.139134)
			(xy 227.598883 -315.118371) (xy 227.599494 -315.106812) (xy 227.599494 -315.026548) (xy 227.598898 -315.014983)
			(xy 227.588722 -314.994212) (xy 227.579936 -314.98667) (xy 227.557446 -314.968487) (xy 227.517709 -314.926467)
			(xy 227.48477 -314.87893) (xy 227.459382 -314.826967) (xy 227.442128 -314.771768) (xy 227.433403 -314.714597)
			(xy 227.43287 -314.68568) (xy 227.433289 -314.659704) (xy 227.440335 -314.608231) (xy 227.454307 -314.558193)
			(xy 227.474946 -314.510516) (xy 227.501871 -314.466085) (xy 227.53458 -314.425723) (xy 227.572469 -314.390177)
			(xy 227.593398 -314.374784) (xy 227.603304 -314.367672) (xy 227.61448 -314.346336) (xy 227.616766 -314.240926)
			(xy 227.606606 -314.219082) (xy 227.596954 -314.211716) (xy 227.576197 -314.194932) (xy 227.539067 -314.156582)
			(xy 227.507646 -314.113431) (xy 227.482547 -314.066321) (xy 227.46426 -314.016173) (xy 227.453142 -313.963964)
			(xy 227.44941 -313.910716) (xy 227.453137 -313.857467) (xy 227.464251 -313.805258) (xy 227.482534 -313.755108)
			(xy 227.507629 -313.707996) (xy 227.539047 -313.664842) (xy 227.576173 -313.626489) (xy 227.596954 -313.609736)
			(xy 227.605704 -313.602164) (xy 227.615892 -313.581412) (xy 227.616512 -313.569858) (xy 227.616512 -313.489594)
			(xy 227.615941 -313.478026) (xy 227.605746 -313.457256) (xy 227.596954 -313.449716) (xy 227.576197 -313.432932)
			(xy 227.539067 -313.394582) (xy 227.507646 -313.351431) (xy 227.482547 -313.304321) (xy 227.46426 -313.254173)
			(xy 227.453142 -313.201964) (xy 227.44941 -313.148716) (xy 227.453137 -313.095467) (xy 227.464251 -313.043258)
			(xy 227.482534 -312.993108) (xy 227.507629 -312.945996) (xy 227.539047 -312.902842) (xy 227.576173 -312.864489)
			(xy 227.596954 -312.847736) (xy 227.605704 -312.840164) (xy 227.615892 -312.819412) (xy 227.616512 -312.807858)
			(xy 227.616512 -312.727594) (xy 227.615941 -312.716026) (xy 227.605746 -312.695256) (xy 227.596954 -312.687716)
			(xy 227.574469 -312.669528) (xy 227.534736 -312.627506) (xy 227.501798 -312.57997) (xy 227.476411 -312.528008)
			(xy 227.459154 -312.472811) (xy 227.450424 -312.415642) (xy 227.449888 -312.386726) (xy 227.450374 -312.359475)
			(xy 227.45813 -312.305527) (xy 227.473485 -312.253232) (xy 227.496127 -312.203655) (xy 227.525593 -312.157805)
			(xy 227.561284 -312.116614) (xy 227.602475 -312.080923) (xy 227.648325 -312.051457) (xy 227.697902 -312.028815)
			(xy 227.750197 -312.01346) (xy 227.804145 -312.005704) (xy 227.858647 -312.005704) (xy 227.912595 -312.01346)
			(xy 227.96489 -312.028815) (xy 228.014467 -312.051457) (xy 228.060317 -312.080923) (xy 228.101508 -312.116614)
			(xy 228.137199 -312.157805) (xy 228.166665 -312.203655) (xy 228.189307 -312.253232) (xy 228.204662 -312.305527)
			(xy 228.212418 -312.359475) (xy 228.212904 -312.386726) (xy 228.212369 -312.415643) (xy 228.203648 -312.472815)
			(xy 228.186396 -312.528015) (xy 228.161008 -312.579977) (xy 228.128065 -312.627511) (xy 228.088324 -312.669527)
			(xy 228.065838 -312.687716) (xy 228.057063 -312.695265) (xy 228.046889 -312.716034) (xy 228.04628 -312.727594)
			(xy 228.04628 -312.807858) (xy 228.046882 -312.819422) (xy 228.057055 -312.840192) (xy 228.065838 -312.847736)
			(xy 228.086647 -312.864459) (xy 228.123778 -312.902815) (xy 228.155199 -312.945974) (xy 228.180298 -312.993091)
			(xy 228.198583 -313.043246) (xy 228.209698 -313.095461) (xy 228.213426 -313.148716) (xy 228.21216 -313.166775)
			(xy 229.48998 -313.166775) (xy 229.493714 -313.113519) (xy 229.504836 -313.061303) (xy 229.523128 -313.011147)
			(xy 229.548235 -312.964031) (xy 229.579664 -312.920875) (xy 229.616803 -312.882522) (xy 229.63759 -312.86577)
			(xy 229.646359 -312.858215) (xy 229.656539 -312.837451) (xy 229.657148 -312.825892) (xy 229.657148 -312.745628)
			(xy 229.656579 -312.734059) (xy 229.646385 -312.713287) (xy 229.63759 -312.70575) (xy 229.615128 -312.687533)
			(xy 229.575392 -312.645519) (xy 229.542451 -312.597989) (xy 229.517059 -312.546033) (xy 229.499798 -312.49084)
			(xy 229.491063 -312.433674) (xy 229.490524 -312.40476) (xy 229.49101 -312.377509) (xy 229.498766 -312.323561)
			(xy 229.514121 -312.271266) (xy 229.536763 -312.221689) (xy 229.566229 -312.175839) (xy 229.60192 -312.134648)
			(xy 229.643111 -312.098957) (xy 229.688961 -312.069491) (xy 229.738538 -312.046849) (xy 229.790833 -312.031494)
			(xy 229.844781 -312.023738) (xy 229.899283 -312.023738) (xy 229.953231 -312.031494) (xy 230.005526 -312.046849)
			(xy 230.055103 -312.069491) (xy 230.100953 -312.098957) (xy 230.142144 -312.134648) (xy 230.177835 -312.175839)
			(xy 230.207301 -312.221689) (xy 230.229943 -312.271266) (xy 230.245298 -312.323561) (xy 230.253054 -312.377509)
			(xy 230.25354 -312.40476) (xy 230.253016 -312.433677) (xy 230.244291 -312.490849) (xy 230.227036 -312.546049)
			(xy 230.201646 -312.598011) (xy 230.168702 -312.645545) (xy 230.12896 -312.687561) (xy 230.106474 -312.70575)
			(xy 230.097735 -312.713333) (xy 230.08754 -312.734076) (xy 230.086916 -312.745628) (xy 230.086916 -312.825892)
			(xy 230.087486 -312.83746) (xy 230.09768 -312.858231) (xy 230.106474 -312.86577) (xy 230.127216 -312.882571)
			(xy 230.164343 -312.92092) (xy 230.195762 -312.96407) (xy 230.220859 -313.011178) (xy 230.239146 -313.061324)
			(xy 230.250264 -313.11353) (xy 230.253639 -313.161688) (xy 230.937563 -313.161688) (xy 230.941294 -313.108435)
			(xy 230.952412 -313.056222) (xy 230.970699 -313.006069) (xy 230.995799 -312.958954) (xy 231.027222 -312.915799)
			(xy 231.064353 -312.877444) (xy 231.085136 -312.86069) (xy 231.093904 -312.853134) (xy 231.104083 -312.832371)
			(xy 231.104694 -312.820812) (xy 231.104694 -312.740548) (xy 231.104098 -312.728983) (xy 231.093922 -312.708212)
			(xy 231.085136 -312.70067) (xy 231.062646 -312.682487) (xy 231.022909 -312.640467) (xy 230.98997 -312.59293)
			(xy 230.964582 -312.540967) (xy 230.947328 -312.485768) (xy 230.938603 -312.428597) (xy 230.93807 -312.39968)
			(xy 230.938556 -312.372429) (xy 230.946312 -312.318481) (xy 230.961667 -312.266186) (xy 230.984309 -312.216609)
			(xy 231.013775 -312.170759) (xy 231.049466 -312.129568) (xy 231.090657 -312.093877) (xy 231.136507 -312.064411)
			(xy 231.186084 -312.041769) (xy 231.238379 -312.026414) (xy 231.292327 -312.018658) (xy 231.346829 -312.018658)
			(xy 231.400777 -312.026414) (xy 231.453072 -312.041769) (xy 231.502649 -312.064411) (xy 231.548499 -312.093877)
			(xy 231.58969 -312.129568) (xy 231.625381 -312.170759) (xy 231.654847 -312.216609) (xy 231.677489 -312.266186)
			(xy 231.692844 -312.318481) (xy 231.7006 -312.372429) (xy 231.701086 -312.39968) (xy 231.700559 -312.428597)
			(xy 231.691832 -312.485768) (xy 231.674576 -312.540966) (xy 231.649186 -312.592928) (xy 231.616244 -312.640462)
			(xy 231.576505 -312.68248) (xy 231.55402 -312.70067) (xy 231.545263 -312.708236) (xy 231.53508 -312.728992)
			(xy 231.534462 -312.740548) (xy 231.534462 -312.820812) (xy 231.535004 -312.832384) (xy 231.545217 -312.853156)
			(xy 231.55402 -312.86069) (xy 231.574784 -312.877467) (xy 231.611916 -312.915816) (xy 231.643339 -312.958968)
			(xy 231.66844 -313.006078) (xy 231.686728 -313.056228) (xy 231.697847 -313.108438) (xy 231.701578 -313.161688)
			(xy 231.69785 -313.214938) (xy 231.686735 -313.267148) (xy 231.66845 -313.317299) (xy 231.643352 -313.364412)
			(xy 231.611932 -313.407565) (xy 231.574802 -313.445917) (xy 231.55402 -313.46267) (xy 231.545263 -313.470236)
			(xy 231.53508 -313.490992) (xy 231.534462 -313.502548) (xy 231.534462 -313.582812) (xy 231.535004 -313.594384)
			(xy 231.545217 -313.615156) (xy 231.55402 -313.62269) (xy 231.576503 -313.640882) (xy 231.616237 -313.682902)
			(xy 231.649176 -313.730437) (xy 231.674564 -313.782398) (xy 231.691821 -313.837595) (xy 231.70055 -313.894764)
			(xy 231.701086 -313.92368) (xy 231.7006 -313.950931) (xy 231.692844 -314.004879) (xy 231.677489 -314.057174)
			(xy 231.654847 -314.106751) (xy 231.625381 -314.152601) (xy 231.58969 -314.193792) (xy 231.548499 -314.229483)
			(xy 231.502649 -314.258949) (xy 231.453072 -314.281591) (xy 231.400777 -314.296946) (xy 231.346829 -314.304702)
			(xy 231.292327 -314.304702) (xy 231.238379 -314.296946) (xy 231.186084 -314.281591) (xy 231.136507 -314.258949)
			(xy 231.090657 -314.229483) (xy 231.049466 -314.193792) (xy 231.013775 -314.152601) (xy 230.984309 -314.106751)
			(xy 230.961667 -314.057174) (xy 230.946312 -314.004879) (xy 230.938556 -313.950931) (xy 230.93807 -313.92368)
			(xy 230.938619 -313.894764) (xy 230.947338 -313.837593) (xy 230.964588 -313.782394) (xy 230.989974 -313.730431)
			(xy 231.022914 -313.682897) (xy 231.062652 -313.64088) (xy 231.085136 -313.62269) (xy 231.093904 -313.615134)
			(xy 231.104083 -313.594371) (xy 231.104694 -313.582812) (xy 231.104694 -313.502548) (xy 231.104098 -313.490983)
			(xy 231.093922 -313.470212) (xy 231.085136 -313.46267) (xy 231.064334 -313.44594) (xy 231.027206 -313.407583)
			(xy 230.995786 -313.364425) (xy 230.970689 -313.317309) (xy 230.952405 -313.267154) (xy 230.941291 -313.214941)
			(xy 230.937563 -313.161688) (xy 230.253639 -313.161688) (xy 230.253996 -313.166775) (xy 230.250271 -313.220022)
			(xy 230.239159 -313.272229) (xy 230.220879 -313.322377) (xy 230.195788 -313.369488) (xy 230.164375 -313.412642)
			(xy 230.127253 -313.450996) (xy 230.106474 -313.46775) (xy 230.097735 -313.475333) (xy 230.08754 -313.496076)
			(xy 230.086916 -313.507628) (xy 230.086916 -313.587892) (xy 230.087486 -313.59946) (xy 230.09768 -313.620231)
			(xy 230.106474 -313.62777) (xy 230.128938 -313.645985) (xy 230.168675 -313.687999) (xy 230.201617 -313.735528)
			(xy 230.227009 -313.787485) (xy 230.24427 -313.842679) (xy 230.253003 -313.899845) (xy 230.25354 -313.92876)
			(xy 230.253041 -313.957405) (xy 230.244467 -314.014049) (xy 230.227521 -314.068776) (xy 230.202583 -314.120353)
			(xy 230.170215 -314.167623) (xy 230.131143 -314.209522) (xy 230.109014 -314.227718) (xy 230.09987 -314.235084)
			(xy 230.08971 -314.255658) (xy 230.08971 -314.359036) (xy 230.099616 -314.37961) (xy 230.109014 -314.386976)
			(xy 230.131125 -314.405145) (xy 230.170123 -314.44703) (xy 230.202428 -314.494269) (xy 230.227313 -314.545805)
			(xy 230.244221 -314.600479) (xy 230.252773 -314.657065) (xy 230.253286 -314.68568) (xy 230.253286 -314.685688)
			(xy 233.325163 -314.685688) (xy 233.328894 -314.632435) (xy 233.340012 -314.580222) (xy 233.358299 -314.530069)
			(xy 233.383399 -314.482954) (xy 233.414822 -314.439799) (xy 233.451953 -314.401444) (xy 233.472736 -314.38469)
			(xy 233.481504 -314.377134) (xy 233.491683 -314.356371) (xy 233.492294 -314.344812) (xy 233.492294 -314.264548)
			(xy 233.491698 -314.252983) (xy 233.481522 -314.232212) (xy 233.472736 -314.22467) (xy 233.451934 -314.20794)
			(xy 233.414806 -314.169583) (xy 233.383386 -314.126425) (xy 233.358289 -314.079309) (xy 233.340005 -314.029154)
			(xy 233.328891 -313.976941) (xy 233.325163 -313.923688) (xy 233.328894 -313.870435) (xy 233.340012 -313.818222)
			(xy 233.358299 -313.768069) (xy 233.383399 -313.720954) (xy 233.414822 -313.677799) (xy 233.451953 -313.639444)
			(xy 233.472736 -313.62269) (xy 233.481504 -313.615134) (xy 233.491683 -313.594371) (xy 233.492294 -313.582812)
			(xy 233.492294 -313.502548) (xy 233.491698 -313.490983) (xy 233.481522 -313.470212) (xy 233.472736 -313.46267)
			(xy 233.451934 -313.44594) (xy 233.414806 -313.407583) (xy 233.383386 -313.364425) (xy 233.358289 -313.317309)
			(xy 233.340005 -313.267154) (xy 233.328891 -313.214941) (xy 233.325163 -313.161688) (xy 233.328894 -313.108435)
			(xy 233.340012 -313.056222) (xy 233.358299 -313.006069) (xy 233.383399 -312.958954) (xy 233.414822 -312.915799)
			(xy 233.451953 -312.877444) (xy 233.472736 -312.86069) (xy 233.481504 -312.853134) (xy 233.491683 -312.832371)
			(xy 233.492294 -312.820812) (xy 233.492294 -312.740548) (xy 233.491698 -312.728983) (xy 233.481522 -312.708212)
			(xy 233.472736 -312.70067) (xy 233.450246 -312.682487) (xy 233.410509 -312.640467) (xy 233.37757 -312.59293)
			(xy 233.352182 -312.540967) (xy 233.334928 -312.485768) (xy 233.326203 -312.428597) (xy 233.32567 -312.39968)
			(xy 233.326156 -312.372429) (xy 233.333912 -312.318481) (xy 233.349267 -312.266186) (xy 233.371909 -312.216609)
			(xy 233.401375 -312.170759) (xy 233.437066 -312.129568) (xy 233.478257 -312.093877) (xy 233.524107 -312.064411)
			(xy 233.573684 -312.041769) (xy 233.625979 -312.026414) (xy 233.679927 -312.018658) (xy 233.734429 -312.018658)
			(xy 233.788377 -312.026414) (xy 233.840672 -312.041769) (xy 233.890249 -312.064411) (xy 233.936099 -312.093877)
			(xy 233.97729 -312.129568) (xy 234.012981 -312.170759) (xy 234.042447 -312.216609) (xy 234.065089 -312.266186)
			(xy 234.080444 -312.318481) (xy 234.0882 -312.372429) (xy 234.088686 -312.39968) (xy 234.088159 -312.428597)
			(xy 234.079432 -312.485768) (xy 234.062176 -312.540966) (xy 234.036786 -312.592928) (xy 234.003844 -312.640462)
			(xy 233.964105 -312.68248) (xy 233.94162 -312.70067) (xy 233.932863 -312.708236) (xy 233.92268 -312.728992)
			(xy 233.922062 -312.740548) (xy 233.922062 -312.820812) (xy 233.922604 -312.832384) (xy 233.932817 -312.853156)
			(xy 233.94162 -312.86069) (xy 233.962384 -312.877467) (xy 233.999516 -312.915816) (xy 234.030939 -312.958968)
			(xy 234.05604 -313.006078) (xy 234.074328 -313.056228) (xy 234.078715 -313.076827) (xy 237.334336 -313.076827)
			(xy 237.338061 -313.02358) (xy 237.349174 -312.971372) (xy 237.367456 -312.921223) (xy 237.39255 -312.874112)
			(xy 237.423966 -312.830959) (xy 237.461092 -312.792607) (xy 237.481872 -312.775854) (xy 237.490662 -312.76832)
			(xy 237.500827 -312.74754) (xy 237.50143 -312.735976) (xy 237.50143 -312.655712) (xy 237.500877 -312.644141)
			(xy 237.490672 -312.623369) (xy 237.481872 -312.615834) (xy 237.459399 -312.597631) (xy 237.419664 -312.555613)
			(xy 237.386725 -312.50808) (xy 237.361335 -312.456121) (xy 237.344076 -312.400926) (xy 237.335343 -312.343759)
			(xy 237.334806 -312.314844) (xy 237.335292 -312.287593) (xy 237.343048 -312.233645) (xy 237.358403 -312.18135)
			(xy 237.381045 -312.131773) (xy 237.410511 -312.085923) (xy 237.446202 -312.044732) (xy 237.487393 -312.009041)
			(xy 237.533243 -311.979575) (xy 237.58282 -311.956933) (xy 237.635115 -311.941578) (xy 237.689063 -311.933822)
			(xy 237.743565 -311.933822) (xy 237.797513 -311.941578) (xy 237.849808 -311.956933) (xy 237.899385 -311.979575)
			(xy 237.945235 -312.009041) (xy 237.986426 -312.044732) (xy 238.022117 -312.085923) (xy 238.051583 -312.131773)
			(xy 238.074225 -312.18135) (xy 238.08958 -312.233645) (xy 238.097336 -312.287593) (xy 238.097822 -312.314844)
			(xy 238.097293 -312.343761) (xy 238.08857 -312.400933) (xy 238.071316 -312.456133) (xy 238.045927 -312.508095)
			(xy 238.012984 -312.555629) (xy 237.973242 -312.597645) (xy 237.950756 -312.615834) (xy 237.941976 -312.623378)
			(xy 237.931804 -312.644151) (xy 237.931198 -312.655712) (xy 237.931198 -312.735976) (xy 237.931783 -312.747542)
			(xy 237.941967 -312.768313) (xy 237.950756 -312.775854) (xy 237.971582 -312.792556) (xy 238.008711 -312.830916)
			(xy 238.040131 -312.874077) (xy 238.065228 -312.921196) (xy 238.083512 -312.971354) (xy 238.094625 -313.023571)
			(xy 238.098351 -313.076827) (xy 238.095199 -313.121801) (xy 238.550201 -313.121801) (xy 238.553931 -313.06855)
			(xy 238.565047 -313.016338) (xy 238.583334 -312.966186) (xy 238.608433 -312.919072) (xy 238.639855 -312.875918)
			(xy 238.676987 -312.837565) (xy 238.69777 -312.820812) (xy 238.706534 -312.813253) (xy 238.716713 -312.792491)
			(xy 238.717328 -312.780934) (xy 238.717328 -312.70067) (xy 238.716743 -312.689103) (xy 238.706561 -312.66833)
			(xy 238.69777 -312.660792) (xy 238.675276 -312.642613) (xy 238.635543 -312.60059) (xy 238.602606 -312.553052)
			(xy 238.57722 -312.501089) (xy 238.559966 -312.445889) (xy 238.551238 -312.388719) (xy 238.550704 -312.359802)
			(xy 238.55119 -312.332551) (xy 238.558946 -312.278603) (xy 238.574301 -312.226308) (xy 238.596943 -312.176731)
			(xy 238.626409 -312.130881) (xy 238.6621 -312.08969) (xy 238.703291 -312.053999) (xy 238.749141 -312.024533)
			(xy 238.798718 -312.001891) (xy 238.851013 -311.986536) (xy 238.904961 -311.97878) (xy 238.959463 -311.97878)
			(xy 239.013411 -311.986536) (xy 239.065706 -312.001891) (xy 239.115283 -312.024533) (xy 239.161133 -312.053999)
			(xy 239.202324 -312.08969) (xy 239.238015 -312.130881) (xy 239.267481 -312.176731) (xy 239.290123 -312.226308)
			(xy 239.305478 -312.278603) (xy 239.313234 -312.332551) (xy 239.31372 -312.359802) (xy 239.313233 -312.38872)
			(xy 239.304502 -312.445895) (xy 239.28724 -312.501095) (xy 239.261842 -312.553058) (xy 239.228892 -312.60059)
			(xy 239.189143 -312.642604) (xy 239.166654 -312.660792) (xy 239.157893 -312.668354) (xy 239.147711 -312.689113)
			(xy 239.147096 -312.70067) (xy 239.147096 -312.780934) (xy 239.147706 -312.792497) (xy 239.157873 -312.813268)
			(xy 239.166654 -312.820812) (xy 239.187438 -312.837563) (xy 239.224568 -312.875917) (xy 239.255988 -312.919073)
			(xy 239.281086 -312.966186) (xy 239.299372 -313.016338) (xy 239.310488 -313.06855) (xy 239.314217 -313.121801)
			(xy 239.311423 -313.161688) (xy 239.823485 -313.161688) (xy 239.827216 -313.108434) (xy 239.838336 -313.05622)
			(xy 239.856625 -313.006066) (xy 239.881727 -312.958951) (xy 239.913153 -312.915796) (xy 239.950287 -312.877443)
			(xy 239.971072 -312.86069) (xy 239.979846 -312.85314) (xy 239.99002 -312.832372) (xy 239.99063 -312.820812)
			(xy 239.99063 -312.740548) (xy 239.990056 -312.72898) (xy 239.979866 -312.708207) (xy 239.971072 -312.70067)
			(xy 239.948568 -312.682503) (xy 239.908836 -312.640477) (xy 239.8759 -312.592937) (xy 239.850515 -312.540971)
			(xy 239.833263 -312.48577) (xy 239.824539 -312.428597) (xy 239.824006 -312.39968) (xy 239.824492 -312.372429)
			(xy 239.832248 -312.318481) (xy 239.847603 -312.266186) (xy 239.870245 -312.216609) (xy 239.899711 -312.170759)
			(xy 239.935402 -312.129568) (xy 239.976593 -312.093877) (xy 240.022443 -312.064411) (xy 240.07202 -312.041769)
			(xy 240.124315 -312.026414) (xy 240.178263 -312.018658) (xy 240.232765 -312.018658) (xy 240.286713 -312.026414)
			(xy 240.339008 -312.041769) (xy 240.388585 -312.064411) (xy 240.434435 -312.093877) (xy 240.475626 -312.129568)
			(xy 240.511317 -312.170759) (xy 240.540783 -312.216609) (xy 240.563425 -312.266186) (xy 240.57878 -312.318481)
			(xy 240.586536 -312.372429) (xy 240.587022 -312.39968) (xy 240.586519 -312.428598) (xy 240.577791 -312.485771)
			(xy 240.560532 -312.540972) (xy 240.535138 -312.592934) (xy 240.50219 -312.640467) (xy 240.462444 -312.682482)
			(xy 240.439956 -312.70067) (xy 240.431205 -312.708242) (xy 240.421017 -312.728993) (xy 240.420398 -312.740548)
			(xy 240.420398 -312.820812) (xy 240.420962 -312.832381) (xy 240.431161 -312.853151) (xy 240.439956 -312.86069)
			(xy 240.460719 -312.877467) (xy 240.497847 -312.915818) (xy 240.529268 -312.95897) (xy 240.554366 -313.006081)
			(xy 240.572652 -313.05623) (xy 240.58377 -313.108439) (xy 240.587501 -313.161688) (xy 240.583773 -313.214937)
			(xy 240.572659 -313.267146) (xy 240.554376 -313.317296) (xy 240.529281 -313.364409) (xy 240.497863 -313.407563)
			(xy 240.460737 -313.445916) (xy 240.439956 -313.46267) (xy 240.431205 -313.470242) (xy 240.421017 -313.490993)
			(xy 240.420398 -313.502548) (xy 240.420398 -313.582812) (xy 240.420962 -313.594381) (xy 240.431161 -313.615151)
			(xy 240.439956 -313.62269) (xy 240.462426 -313.640898) (xy 240.502164 -313.682913) (xy 240.535106 -313.730444)
			(xy 240.560497 -313.782402) (xy 240.577755 -313.837597) (xy 240.586486 -313.894765) (xy 240.587022 -313.92368)
			(xy 240.586536 -313.950931) (xy 240.57878 -314.004879) (xy 240.563425 -314.057174) (xy 240.540783 -314.106751)
			(xy 240.511317 -314.152601) (xy 240.475626 -314.193792) (xy 240.434435 -314.229483) (xy 240.388585 -314.258949)
			(xy 240.339008 -314.281591) (xy 240.286713 -314.296946) (xy 240.232765 -314.304702) (xy 240.178263 -314.304702)
			(xy 240.124315 -314.296946) (xy 240.07202 -314.281591) (xy 240.022443 -314.258949) (xy 239.976593 -314.229483)
			(xy 239.935402 -314.193792) (xy 239.899711 -314.152601) (xy 239.870245 -314.106751) (xy 239.847603 -314.057174)
			(xy 239.832248 -314.004879) (xy 239.824492 -313.950931) (xy 239.824006 -313.92368) (xy 239.824579 -313.894765)
			(xy 239.833297 -313.837596) (xy 239.850543 -313.782398) (xy 239.875925 -313.730436) (xy 239.908859 -313.682901)
			(xy 239.948591 -313.640882) (xy 239.971072 -313.62269) (xy 239.979846 -313.61514) (xy 239.99002 -313.594372)
			(xy 239.99063 -313.582812) (xy 239.99063 -313.502548) (xy 239.990056 -313.49098) (xy 239.979866 -313.470207)
			(xy 239.971072 -313.46267) (xy 239.950269 -313.445941) (xy 239.913137 -313.407585) (xy 239.881714 -313.364428)
			(xy 239.856615 -313.317312) (xy 239.838329 -313.267157) (xy 239.827213 -313.214942) (xy 239.823485 -313.161688)
			(xy 239.311423 -313.161688) (xy 239.310487 -313.175052) (xy 239.299371 -313.227264) (xy 239.281085 -313.277416)
			(xy 239.255987 -313.32453) (xy 239.224566 -313.367685) (xy 239.187437 -313.406038) (xy 239.166654 -313.422792)
			(xy 239.157893 -313.430354) (xy 239.147711 -313.451113) (xy 239.147096 -313.46267) (xy 239.147096 -313.542934)
			(xy 239.147706 -313.554497) (xy 239.157873 -313.575268) (xy 239.166654 -313.582812) (xy 239.189154 -313.600983)
			(xy 239.228886 -313.643008) (xy 239.261822 -313.690548) (xy 239.287207 -313.742513) (xy 239.30446 -313.797713)
			(xy 239.313186 -313.854885) (xy 239.31372 -313.883802) (xy 239.313317 -313.909546) (xy 239.306396 -313.960566)
			(xy 239.29268 -314.010194) (xy 239.272418 -314.057527) (xy 239.245978 -314.101707) (xy 239.213839 -314.141933)
			(xy 239.176585 -314.177473) (xy 239.155986 -314.19292) (xy 239.145572 -314.200286) (xy 239.134396 -314.222892)
			(xy 239.13846 -314.332874) (xy 239.15116 -314.354718) (xy 239.162082 -314.361576) (xy 239.185359 -314.376563)
			(xy 239.227691 -314.412241) (xy 239.264419 -314.453666) (xy 239.29477 -314.499966) (xy 239.318107 -314.550168)
			(xy 239.333939 -314.603218) (xy 239.341933 -314.657999) (xy 239.342422 -314.68568) (xy 239.341919 -314.714598)
			(xy 239.333191 -314.771771) (xy 239.315932 -314.826972) (xy 239.290538 -314.878934) (xy 239.25759 -314.926467)
			(xy 239.217844 -314.968482) (xy 239.195356 -314.98667) (xy 239.186605 -314.994242) (xy 239.176417 -315.014993)
			(xy 239.175798 -315.026548) (xy 239.175798 -315.106812) (xy 239.176362 -315.118381) (xy 239.186561 -315.139151)
			(xy 239.195356 -315.14669) (xy 239.217826 -315.164898) (xy 239.257564 -315.206913) (xy 239.290506 -315.254444)
			(xy 239.315897 -315.306402) (xy 239.333155 -315.361597) (xy 239.341886 -315.418765) (xy 239.342422 -315.44768)
			(xy 242.414806 -315.44768) (xy 242.415379 -315.418765) (xy 242.424097 -315.361596) (xy 242.441343 -315.306398)
			(xy 242.466725 -315.254436) (xy 242.499659 -315.206901) (xy 242.539391 -315.164882) (xy 242.561872 -315.14669)
			(xy 242.570646 -315.13914) (xy 242.58082 -315.118372) (xy 242.58143 -315.106812) (xy 242.58143 -315.026548)
			(xy 242.580856 -315.01498) (xy 242.570666 -314.994207) (xy 242.561872 -314.98667) (xy 242.539368 -314.968503)
			(xy 242.499636 -314.926477) (xy 242.4667 -314.878937) (xy 242.441315 -314.826971) (xy 242.424063 -314.77177)
			(xy 242.415339 -314.714597) (xy 242.414806 -314.68568) (xy 242.415252 -314.659705) (xy 242.422296 -314.608235)
			(xy 242.436266 -314.558198) (xy 242.456902 -314.510523) (xy 242.483821 -314.466091) (xy 242.516525 -314.425727)
			(xy 242.554408 -314.390179) (xy 242.575334 -314.374784) (xy 242.58524 -314.367672) (xy 242.596416 -314.346336)
			(xy 242.598702 -314.240926) (xy 242.588542 -314.219082) (xy 242.57889 -314.211716) (xy 242.556412 -314.193518)
			(xy 242.516677 -314.1515) (xy 242.483738 -314.103966) (xy 242.458348 -314.052006) (xy 242.441091 -313.99681)
			(xy 242.43236 -313.939642) (xy 242.431824 -313.910726) (xy 242.432287 -313.883626) (xy 242.439966 -313.829973)
			(xy 242.45516 -313.777946) (xy 242.477563 -313.728592) (xy 242.506724 -313.682905) (xy 242.542057 -313.641804)
			(xy 242.582849 -313.606116) (xy 242.605306 -313.59094) (xy 242.615554 -313.583455) (xy 242.627674 -313.561192)
			(xy 242.62842 -313.548522) (xy 242.62842 -313.51093) (xy 242.627704 -313.498252) (xy 242.615573 -313.475984)
			(xy 242.605306 -313.468512) (xy 242.58286 -313.45332) (xy 242.542065 -313.417637) (xy 242.506731 -313.37654)
			(xy 242.477569 -313.330856) (xy 242.455167 -313.281504) (xy 242.439976 -313.229478) (xy 242.432301 -313.175825)
			(xy 242.431824 -313.148726) (xy 242.432352 -313.119809) (xy 242.441078 -313.062638) (xy 242.458333 -313.007439)
			(xy 242.483723 -312.955477) (xy 242.516665 -312.907943) (xy 242.556405 -312.865926) (xy 242.57889 -312.847736)
			(xy 242.58763 -312.840152) (xy 242.597826 -312.81941) (xy 242.598448 -312.807858) (xy 242.598448 -312.727594)
			(xy 242.597899 -312.716023) (xy 242.587691 -312.695251) (xy 242.57889 -312.687716) (xy 242.556412 -312.669518)
			(xy 242.516677 -312.6275) (xy 242.483738 -312.579966) (xy 242.458348 -312.528006) (xy 242.441091 -312.47281)
			(xy 242.43236 -312.415642) (xy 242.431824 -312.386726) (xy 242.43231 -312.359475) (xy 242.440066 -312.305527)
			(xy 242.455421 -312.253232) (xy 242.478063 -312.203655) (xy 242.507529 -312.157805) (xy 242.54322 -312.116614)
			(xy 242.584411 -312.080923) (xy 242.630261 -312.051457) (xy 242.679838 -312.028815) (xy 242.732133 -312.01346)
			(xy 242.786081 -312.005704) (xy 242.840583 -312.005704) (xy 242.894531 -312.01346) (xy 242.946826 -312.028815)
			(xy 242.996403 -312.051457) (xy 243.042253 -312.080923) (xy 243.083444 -312.116614) (xy 243.119135 -312.157805)
			(xy 243.148601 -312.203655) (xy 243.171243 -312.253232) (xy 243.186598 -312.305527) (xy 243.194354 -312.359475)
			(xy 243.19484 -312.386726) (xy 243.194291 -312.415642) (xy 243.185572 -312.472813) (xy 243.168321 -312.528012)
			(xy 243.142935 -312.579974) (xy 243.109996 -312.627509) (xy 243.070258 -312.669526) (xy 243.047774 -312.687716)
			(xy 243.039005 -312.695271) (xy 243.028826 -312.716035) (xy 243.028216 -312.727594) (xy 243.028216 -312.807858)
			(xy 243.028805 -312.819424) (xy 243.038986 -312.840195) (xy 243.047774 -312.847736) (xy 243.070269 -312.865913)
			(xy 243.110005 -312.907935) (xy 243.142943 -312.955473) (xy 243.16833 -313.007437) (xy 243.185583 -313.062637)
			(xy 243.194308 -313.119809) (xy 243.19484 -313.148726) (xy 243.19484 -313.149996) (xy 243.19484 -313.160156)
			(xy 243.20246 -313.178952) (xy 243.260372 -313.237118) (xy 243.267786 -313.243941) (xy 243.286375 -313.25167)
			(xy 243.29644 -313.252104) (xy 244.371114 -313.252104) (xy 244.380928 -313.251615) (xy 244.399092 -313.244172)
			(xy 244.40642 -313.237626) (xy 244.464586 -313.181492) (xy 244.47246 -313.163966) (xy 244.472714 -313.153806)
			(xy 244.474163 -313.126005) (xy 244.484101 -313.071233) (xy 244.501898 -313.018487) (xy 244.527176 -312.968891)
			(xy 244.559397 -312.923497) (xy 244.597877 -312.883271) (xy 244.619526 -312.86577) (xy 244.628301 -312.858221)
			(xy 244.638476 -312.837452) (xy 244.639084 -312.825892) (xy 244.639084 -312.745628) (xy 244.638503 -312.734061)
			(xy 244.628317 -312.71329) (xy 244.619526 -312.70575) (xy 244.597072 -312.687524) (xy 244.557334 -312.645512)
			(xy 244.52439 -312.597985) (xy 244.498997 -312.54603) (xy 244.481734 -312.490839) (xy 244.472999 -312.433674)
			(xy 244.47246 -312.40476) (xy 244.472946 -312.377509) (xy 244.480702 -312.323561) (xy 244.496057 -312.271266)
			(xy 244.518699 -312.221689) (xy 244.548165 -312.175839) (xy 244.583856 -312.134648) (xy 244.625047 -312.098957)
			(xy 244.670897 -312.069491) (xy 244.720474 -312.046849) (xy 244.772769 -312.031494) (xy 244.826717 -312.023738)
			(xy 244.881219 -312.023738) (xy 244.935167 -312.031494) (xy 244.987462 -312.046849) (xy 245.037039 -312.069491)
			(xy 245.082889 -312.098957) (xy 245.12408 -312.134648) (xy 245.159771 -312.175839) (xy 245.189237 -312.221689)
			(xy 245.211879 -312.271266) (xy 245.227234 -312.323561) (xy 245.23499 -312.377509) (xy 245.235476 -312.40476)
			(xy 245.234938 -312.433676) (xy 245.226214 -312.490847) (xy 245.208961 -312.546046) (xy 245.183573 -312.598008)
			(xy 245.150633 -312.645542) (xy 245.110894 -312.68756) (xy 245.08841 -312.70575) (xy 245.079677 -312.71334)
			(xy 245.069477 -312.734077) (xy 245.068852 -312.745628) (xy 245.068852 -312.825892) (xy 245.069409 -312.837462)
			(xy 245.079611 -312.858234) (xy 245.08841 -312.86577) (xy 245.110881 -312.883975) (xy 245.150617 -312.925992)
			(xy 245.183557 -312.973524) (xy 245.208947 -313.025483) (xy 245.226206 -313.080678) (xy 245.234939 -313.137845)
			(xy 245.235382 -313.161688) (xy 245.919485 -313.161688) (xy 245.923216 -313.108434) (xy 245.934336 -313.05622)
			(xy 245.952625 -313.006066) (xy 245.977727 -312.958951) (xy 246.009153 -312.915796) (xy 246.046287 -312.877443)
			(xy 246.067072 -312.86069) (xy 246.075846 -312.85314) (xy 246.08602 -312.832372) (xy 246.08663 -312.820812)
			(xy 246.08663 -312.740548) (xy 246.086056 -312.72898) (xy 246.075866 -312.708207) (xy 246.067072 -312.70067)
			(xy 246.044568 -312.682503) (xy 246.004836 -312.640477) (xy 245.9719 -312.592937) (xy 245.946515 -312.540971)
			(xy 245.929263 -312.48577) (xy 245.920539 -312.428597) (xy 245.920006 -312.39968) (xy 245.920492 -312.372429)
			(xy 245.928248 -312.318481) (xy 245.943603 -312.266186) (xy 245.966245 -312.216609) (xy 245.995711 -312.170759)
			(xy 246.031402 -312.129568) (xy 246.072593 -312.093877) (xy 246.118443 -312.064411) (xy 246.16802 -312.041769)
			(xy 246.220315 -312.026414) (xy 246.274263 -312.018658) (xy 246.328765 -312.018658) (xy 246.382713 -312.026414)
			(xy 246.435008 -312.041769) (xy 246.484585 -312.064411) (xy 246.530435 -312.093877) (xy 246.571626 -312.129568)
			(xy 246.607317 -312.170759) (xy 246.636783 -312.216609) (xy 246.659425 -312.266186) (xy 246.67478 -312.318481)
			(xy 246.682536 -312.372429) (xy 246.683022 -312.39968) (xy 246.682519 -312.428598) (xy 246.673791 -312.485771)
			(xy 246.656532 -312.540972) (xy 246.631138 -312.592934) (xy 246.59819 -312.640467) (xy 246.558444 -312.682482)
			(xy 246.535956 -312.70067) (xy 246.527205 -312.708242) (xy 246.517017 -312.728993) (xy 246.516398 -312.740548)
			(xy 246.516398 -312.820812) (xy 246.516962 -312.832381) (xy 246.527161 -312.853151) (xy 246.535956 -312.86069)
			(xy 246.556719 -312.877467) (xy 246.593847 -312.915818) (xy 246.625268 -312.95897) (xy 246.650366 -313.006081)
			(xy 246.668652 -313.05623) (xy 246.67977 -313.108439) (xy 246.683501 -313.161688) (xy 246.679773 -313.214937)
			(xy 246.668659 -313.267146) (xy 246.650376 -313.317296) (xy 246.625281 -313.364409) (xy 246.593863 -313.407563)
			(xy 246.556737 -313.445916) (xy 246.535956 -313.46267) (xy 246.527205 -313.470242) (xy 246.517017 -313.490993)
			(xy 246.516398 -313.502548) (xy 246.516398 -313.582812) (xy 246.516962 -313.594381) (xy 246.527161 -313.615151)
			(xy 246.535956 -313.62269) (xy 246.558426 -313.640898) (xy 246.598164 -313.682913) (xy 246.631106 -313.730444)
			(xy 246.656497 -313.782402) (xy 246.673755 -313.837597) (xy 246.682486 -313.894765) (xy 246.683022 -313.92368)
			(xy 246.682536 -313.950931) (xy 246.67478 -314.004879) (xy 246.659425 -314.057174) (xy 246.636783 -314.106751)
			(xy 246.607317 -314.152601) (xy 246.571626 -314.193792) (xy 246.530435 -314.229483) (xy 246.484585 -314.258949)
			(xy 246.435008 -314.281591) (xy 246.382713 -314.296946) (xy 246.328765 -314.304702) (xy 246.274263 -314.304702)
			(xy 246.220315 -314.296946) (xy 246.16802 -314.281591) (xy 246.118443 -314.258949) (xy 246.072593 -314.229483)
			(xy 246.031402 -314.193792) (xy 245.995711 -314.152601) (xy 245.966245 -314.106751) (xy 245.943603 -314.057174)
			(xy 245.928248 -314.004879) (xy 245.920492 -313.950931) (xy 245.920006 -313.92368) (xy 245.920579 -313.894765)
			(xy 245.929297 -313.837596) (xy 245.946543 -313.782398) (xy 245.971925 -313.730436) (xy 246.004859 -313.682901)
			(xy 246.044591 -313.640882) (xy 246.067072 -313.62269) (xy 246.075846 -313.61514) (xy 246.08602 -313.594372)
			(xy 246.08663 -313.582812) (xy 246.08663 -313.502548) (xy 246.086056 -313.49098) (xy 246.075866 -313.470207)
			(xy 246.067072 -313.46267) (xy 246.046269 -313.445941) (xy 246.009137 -313.407585) (xy 245.977714 -313.364428)
			(xy 245.952615 -313.317312) (xy 245.934329 -313.267157) (xy 245.923213 -313.214942) (xy 245.919485 -313.161688)
			(xy 245.235382 -313.161688) (xy 245.235476 -313.16676) (xy 245.235026 -313.192789) (xy 245.227964 -313.244365)
			(xy 245.213951 -313.294501) (xy 245.193249 -313.342266) (xy 245.166242 -313.38677) (xy 245.133432 -313.427186)
			(xy 245.095429 -313.462764) (xy 245.07444 -313.478164) (xy 245.064944 -313.48579) (xy 245.053802 -313.507407)
			(xy 245.053104 -313.519566) (xy 245.053104 -313.575954) (xy 245.05377 -313.58812) (xy 245.064925 -313.609743)
			(xy 245.07444 -313.617356) (xy 245.095421 -313.632765) (xy 245.133413 -313.668351) (xy 245.166216 -313.708769)
			(xy 245.193221 -313.753271) (xy 245.213928 -313.801031) (xy 245.227952 -313.851161) (xy 245.235032 -313.902733)
			(xy 245.235476 -313.92876) (xy 245.234963 -313.957404) (xy 245.22639 -314.014048) (xy 245.209446 -314.068773)
			(xy 245.184511 -314.12035) (xy 245.152146 -314.16762) (xy 245.113077 -314.209521) (xy 245.09095 -314.227718)
			(xy 245.081806 -314.235084) (xy 245.071646 -314.255658) (xy 245.071646 -314.359036) (xy 245.081552 -314.37961)
			(xy 245.09095 -314.386976) (xy 245.113047 -314.405162) (xy 245.152049 -314.447041) (xy 245.184357 -314.494276)
			(xy 245.209245 -314.545809) (xy 245.226156 -314.600481) (xy 245.234708 -314.657066) (xy 245.235222 -314.68568)
			(xy 245.235222 -314.685688) (xy 248.307085 -314.685688) (xy 248.310816 -314.632434) (xy 248.321936 -314.58022)
			(xy 248.340225 -314.530066) (xy 248.365327 -314.482951) (xy 248.396753 -314.439796) (xy 248.433887 -314.401443)
			(xy 248.454672 -314.38469) (xy 248.463446 -314.37714) (xy 248.47362 -314.356372) (xy 248.47423 -314.344812)
			(xy 248.47423 -314.264548) (xy 248.473656 -314.25298) (xy 248.463466 -314.232207) (xy 248.454672 -314.22467)
			(xy 248.433869 -314.207941) (xy 248.396737 -314.169585) (xy 248.365314 -314.126428) (xy 248.340215 -314.079312)
			(xy 248.321929 -314.029157) (xy 248.310813 -313.976942) (xy 248.307085 -313.923688) (xy 248.310816 -313.870434)
			(xy 248.321936 -313.81822) (xy 248.340225 -313.768066) (xy 248.365327 -313.720951) (xy 248.396753 -313.677796)
			(xy 248.433887 -313.639443) (xy 248.454672 -313.62269) (xy 248.463446 -313.61514) (xy 248.47362 -313.594372)
			(xy 248.47423 -313.582812) (xy 248.47423 -313.502548) (xy 248.473656 -313.49098) (xy 248.463466 -313.470207)
			(xy 248.454672 -313.46267) (xy 248.433869 -313.445941) (xy 248.396737 -313.407585) (xy 248.365314 -313.364428)
			(xy 248.340215 -313.317312) (xy 248.321929 -313.267157) (xy 248.310813 -313.214942) (xy 248.307085 -313.161688)
			(xy 248.310816 -313.108434) (xy 248.321936 -313.05622) (xy 248.340225 -313.006066) (xy 248.365327 -312.958951)
			(xy 248.396753 -312.915796) (xy 248.433887 -312.877443) (xy 248.454672 -312.86069) (xy 248.463446 -312.85314)
			(xy 248.47362 -312.832372) (xy 248.47423 -312.820812) (xy 248.47423 -312.740548) (xy 248.473656 -312.72898)
			(xy 248.463466 -312.708207) (xy 248.454672 -312.70067) (xy 248.432168 -312.682503) (xy 248.392436 -312.640477)
			(xy 248.3595 -312.592937) (xy 248.334115 -312.540971) (xy 248.316863 -312.48577) (xy 248.308139 -312.428597)
			(xy 248.307606 -312.39968) (xy 248.308092 -312.372429) (xy 248.315848 -312.318481) (xy 248.331203 -312.266186)
			(xy 248.353845 -312.216609) (xy 248.383311 -312.170759) (xy 248.419002 -312.129568) (xy 248.460193 -312.093877)
			(xy 248.506043 -312.064411) (xy 248.55562 -312.041769) (xy 248.607915 -312.026414) (xy 248.661863 -312.018658)
			(xy 248.716365 -312.018658) (xy 248.770313 -312.026414) (xy 248.822608 -312.041769) (xy 248.872185 -312.064411)
			(xy 248.918035 -312.093877) (xy 248.959226 -312.129568) (xy 248.994917 -312.170759) (xy 249.024383 -312.216609)
			(xy 249.047025 -312.266186) (xy 249.06238 -312.318481) (xy 249.070136 -312.372429) (xy 249.070622 -312.39968)
			(xy 249.070119 -312.428598) (xy 249.061391 -312.485771) (xy 249.044132 -312.540972) (xy 249.018738 -312.592934)
			(xy 248.98579 -312.640467) (xy 248.946044 -312.682482) (xy 248.923556 -312.70067) (xy 248.914805 -312.708242)
			(xy 248.904617 -312.728993) (xy 248.903998 -312.740548) (xy 248.903998 -312.820812) (xy 248.904562 -312.832381)
			(xy 248.914761 -312.853151) (xy 248.923556 -312.86069) (xy 248.944319 -312.877467) (xy 248.981447 -312.915818)
			(xy 249.012868 -312.95897) (xy 249.037966 -313.006081) (xy 249.056252 -313.05623) (xy 249.06737 -313.108439)
			(xy 249.071101 -313.161688) (xy 249.067373 -313.214937) (xy 249.056259 -313.267146) (xy 249.037976 -313.317296)
			(xy 249.012881 -313.364409) (xy 248.981463 -313.407563) (xy 248.944337 -313.445916) (xy 248.923556 -313.46267)
			(xy 248.914805 -313.470242) (xy 248.904617 -313.490993) (xy 248.903998 -313.502548) (xy 248.903998 -313.582812)
			(xy 248.904562 -313.594381) (xy 248.914761 -313.615151) (xy 248.923556 -313.62269) (xy 248.944319 -313.639467)
			(xy 248.981447 -313.677818) (xy 249.012868 -313.72097) (xy 249.037966 -313.768081) (xy 249.056252 -313.81823)
			(xy 249.06737 -313.870439) (xy 249.071101 -313.923688) (xy 249.067373 -313.976937) (xy 249.056259 -314.029146)
			(xy 249.037976 -314.079296) (xy 249.012881 -314.126409) (xy 248.981463 -314.169563) (xy 248.944337 -314.207916)
			(xy 248.923556 -314.22467) (xy 248.914805 -314.232242) (xy 248.904617 -314.252993) (xy 248.903998 -314.264548)
			(xy 248.903998 -314.344812) (xy 248.904562 -314.356381) (xy 248.914761 -314.377151) (xy 248.923556 -314.38469)
			(xy 248.944319 -314.401467) (xy 248.981447 -314.439818) (xy 249.012868 -314.48297) (xy 249.037966 -314.530081)
			(xy 249.056252 -314.58023) (xy 249.06737 -314.632439) (xy 249.071101 -314.685688) (xy 249.067373 -314.738937)
			(xy 249.056259 -314.791146) (xy 249.037976 -314.841296) (xy 249.012881 -314.888409) (xy 248.981463 -314.931563)
			(xy 248.944337 -314.969916) (xy 248.923556 -314.98667) (xy 248.914805 -314.994242) (xy 248.904617 -315.014993)
			(xy 248.903998 -315.026548) (xy 248.903998 -315.106812) (xy 248.904562 -315.118381) (xy 248.914761 -315.139151)
			(xy 248.923556 -315.14669) (xy 248.946026 -315.164898) (xy 248.985764 -315.206913) (xy 249.018706 -315.254444)
			(xy 249.044097 -315.306402) (xy 249.061355 -315.361597) (xy 249.070086 -315.418765) (xy 249.070622 -315.44768)
			(xy 249.070136 -315.474931) (xy 249.06238 -315.528879) (xy 249.047025 -315.581174) (xy 249.024383 -315.630751)
			(xy 248.994917 -315.676601) (xy 248.959226 -315.717792) (xy 248.918035 -315.753483) (xy 248.872185 -315.782949)
			(xy 248.822608 -315.805591) (xy 248.770313 -315.820946) (xy 248.716365 -315.828702) (xy 248.661863 -315.828702)
			(xy 248.607915 -315.820946) (xy 248.55562 -315.805591) (xy 248.506043 -315.782949) (xy 248.460193 -315.753483)
			(xy 248.419002 -315.717792) (xy 248.383311 -315.676601) (xy 248.353845 -315.630751) (xy 248.331203 -315.581174)
			(xy 248.315848 -315.528879) (xy 248.308092 -315.474931) (xy 248.307606 -315.44768) (xy 248.308179 -315.418765)
			(xy 248.316897 -315.361596) (xy 248.334143 -315.306398) (xy 248.359525 -315.254436) (xy 248.392459 -315.206901)
			(xy 248.432191 -315.164882) (xy 248.454672 -315.14669) (xy 248.463446 -315.13914) (xy 248.47362 -315.118372)
			(xy 248.47423 -315.106812) (xy 248.47423 -315.026548) (xy 248.473656 -315.01498) (xy 248.463466 -314.994207)
			(xy 248.454672 -314.98667) (xy 248.433869 -314.969941) (xy 248.396737 -314.931585) (xy 248.365314 -314.888428)
			(xy 248.340215 -314.841312) (xy 248.321929 -314.791157) (xy 248.310813 -314.738942) (xy 248.307085 -314.685688)
			(xy 245.235222 -314.685688) (xy 245.234719 -314.714598) (xy 245.225991 -314.771771) (xy 245.208732 -314.826972)
			(xy 245.183338 -314.878934) (xy 245.15039 -314.926467) (xy 245.110644 -314.968482) (xy 245.088156 -314.98667)
			(xy 245.079405 -314.994242) (xy 245.069217 -315.014993) (xy 245.068598 -315.026548) (xy 245.068598 -315.106812)
			(xy 245.069162 -315.118381) (xy 245.079361 -315.139151) (xy 245.088156 -315.14669) (xy 245.110626 -315.164898)
			(xy 245.150364 -315.206913) (xy 245.183306 -315.254444) (xy 245.208697 -315.306402) (xy 245.225955 -315.361597)
			(xy 245.234686 -315.418765) (xy 245.235222 -315.44768) (xy 245.234736 -315.474931) (xy 245.22698 -315.528879)
			(xy 245.211625 -315.581174) (xy 245.188983 -315.630751) (xy 245.159517 -315.676601) (xy 245.123826 -315.717792)
			(xy 245.082635 -315.753483) (xy 245.036785 -315.782949) (xy 244.987208 -315.805591) (xy 244.934913 -315.820946)
			(xy 244.880965 -315.828702) (xy 244.826463 -315.828702) (xy 244.772515 -315.820946) (xy 244.72022 -315.805591)
			(xy 244.670643 -315.782949) (xy 244.624793 -315.753483) (xy 244.583602 -315.717792) (xy 244.547911 -315.676601)
			(xy 244.518445 -315.630751) (xy 244.495803 -315.581174) (xy 244.480448 -315.528879) (xy 244.472692 -315.474931)
			(xy 244.472206 -315.44768) (xy 244.472779 -315.418765) (xy 244.481497 -315.361596) (xy 244.498743 -315.306398)
			(xy 244.524125 -315.254436) (xy 244.557059 -315.206901) (xy 244.596791 -315.164882) (xy 244.619272 -315.14669)
			(xy 244.628046 -315.13914) (xy 244.63822 -315.118372) (xy 244.63883 -315.106812) (xy 244.63883 -315.026548)
			(xy 244.638256 -315.01498) (xy 244.628066 -314.994207) (xy 244.619272 -314.98667) (xy 244.596768 -314.968503)
			(xy 244.557036 -314.926477) (xy 244.5241 -314.878937) (xy 244.498715 -314.826971) (xy 244.481463 -314.77177)
			(xy 244.472739 -314.714597) (xy 244.472206 -314.68568) (xy 244.472754 -314.657037) (xy 244.48132 -314.600396)
			(xy 244.498258 -314.545671) (xy 244.523187 -314.494094) (xy 244.555546 -314.446823) (xy 244.594608 -314.40492)
			(xy 244.616732 -314.386722) (xy 244.625876 -314.379356) (xy 244.636036 -314.358782) (xy 244.636036 -314.255404)
			(xy 244.62613 -314.23483) (xy 244.616732 -314.227464) (xy 244.595393 -314.209885) (xy 244.557494 -314.169633)
			(xy 244.525811 -314.124327) (xy 244.501007 -314.074917) (xy 244.483605 -314.022442) (xy 244.478302 -313.995308)
			(xy 244.475 -313.976766) (xy 244.44706 -313.953144) (xy 243.217446 -313.953144) (xy 243.18976 -313.975496)
			(xy 243.18595 -313.993022) (xy 243.179438 -314.020338) (xy 243.159407 -314.0728) (xy 243.131889 -314.121752)
			(xy 243.097482 -314.166132) (xy 243.05693 -314.204978) (xy 243.034312 -314.221622) (xy 243.024406 -314.228734)
			(xy 243.01323 -314.25007) (xy 243.010944 -314.35548) (xy 243.021104 -314.377324) (xy 243.030756 -314.38469)
			(xy 243.051519 -314.401467) (xy 243.088647 -314.439818) (xy 243.120068 -314.48297) (xy 243.145166 -314.530081)
			(xy 243.163452 -314.58023) (xy 243.17457 -314.632439) (xy 243.178301 -314.685688) (xy 243.174573 -314.738937)
			(xy 243.163459 -314.791146) (xy 243.145176 -314.841296) (xy 243.120081 -314.888409) (xy 243.088663 -314.931563)
			(xy 243.051537 -314.969916) (xy 243.030756 -314.98667) (xy 243.022005 -314.994242) (xy 243.011817 -315.014993)
			(xy 243.011198 -315.026548) (xy 243.011198 -315.106812) (xy 243.011762 -315.118381) (xy 243.021961 -315.139151)
			(xy 243.030756 -315.14669) (xy 243.053226 -315.164898) (xy 243.092964 -315.206913) (xy 243.125906 -315.254444)
			(xy 243.151297 -315.306402) (xy 243.168555 -315.361597) (xy 243.177286 -315.418765) (xy 243.177822 -315.44768)
			(xy 243.177336 -315.474931) (xy 243.16958 -315.528879) (xy 243.154225 -315.581174) (xy 243.131583 -315.630751)
			(xy 243.102117 -315.676601) (xy 243.066426 -315.717792) (xy 243.025235 -315.753483) (xy 242.979385 -315.782949)
			(xy 242.929808 -315.805591) (xy 242.877513 -315.820946) (xy 242.823565 -315.828702) (xy 242.769063 -315.828702)
			(xy 242.715115 -315.820946) (xy 242.66282 -315.805591) (xy 242.613243 -315.782949) (xy 242.567393 -315.753483)
			(xy 242.526202 -315.717792) (xy 242.490511 -315.676601) (xy 242.461045 -315.630751) (xy 242.438403 -315.581174)
			(xy 242.423048 -315.528879) (xy 242.415292 -315.474931) (xy 242.414806 -315.44768) (xy 239.342422 -315.44768)
			(xy 239.341936 -315.474931) (xy 239.33418 -315.528879) (xy 239.318825 -315.581174) (xy 239.296183 -315.630751)
			(xy 239.266717 -315.676601) (xy 239.231026 -315.717792) (xy 239.189835 -315.753483) (xy 239.143985 -315.782949)
			(xy 239.094408 -315.805591) (xy 239.042113 -315.820946) (xy 238.988165 -315.828702) (xy 238.933663 -315.828702)
			(xy 238.879715 -315.820946) (xy 238.82742 -315.805591) (xy 238.777843 -315.782949) (xy 238.731993 -315.753483)
			(xy 238.690802 -315.717792) (xy 238.655111 -315.676601) (xy 238.625645 -315.630751) (xy 238.603003 -315.581174)
			(xy 238.587648 -315.528879) (xy 238.579892 -315.474931) (xy 238.579406 -315.44768) (xy 238.579979 -315.418765)
			(xy 238.588697 -315.361596) (xy 238.605943 -315.306398) (xy 238.631325 -315.254436) (xy 238.664259 -315.206901)
			(xy 238.703991 -315.164882) (xy 238.726472 -315.14669) (xy 238.735246 -315.13914) (xy 238.74542 -315.118372)
			(xy 238.74603 -315.106812) (xy 238.74603 -315.026548) (xy 238.745456 -315.01498) (xy 238.735266 -314.994207)
			(xy 238.726472 -314.98667) (xy 238.703968 -314.968503) (xy 238.664236 -314.926477) (xy 238.6313 -314.878937)
			(xy 238.605915 -314.826971) (xy 238.588663 -314.77177) (xy 238.579939 -314.714597) (xy 238.579406 -314.68568)
			(xy 238.579826 -314.659937) (xy 238.586748 -314.608918) (xy 238.600463 -314.559293) (xy 238.620723 -314.511961)
			(xy 238.64716 -314.467781) (xy 238.679295 -314.427554) (xy 238.716544 -314.392011) (xy 238.73714 -314.376562)
			(xy 238.747554 -314.369196) (xy 238.75873 -314.34659) (xy 238.754666 -314.236608) (xy 238.741966 -314.214764)
			(xy 238.731044 -314.207906) (xy 238.707765 -314.192922) (xy 238.665432 -314.157244) (xy 238.628703 -314.11582)
			(xy 238.598351 -314.069519) (xy 238.575015 -314.019316) (xy 238.559184 -313.966265) (xy 238.551192 -313.911483)
			(xy 238.550704 -313.883802) (xy 238.551222 -313.854885) (xy 238.559951 -313.797714) (xy 238.577209 -313.742515)
			(xy 238.602601 -313.690553) (xy 238.635544 -313.643019) (xy 238.675285 -313.601002) (xy 238.69777 -313.582812)
			(xy 238.706534 -313.575253) (xy 238.716713 -313.554491) (xy 238.717328 -313.542934) (xy 238.717328 -313.46267)
			(xy 238.716743 -313.451103) (xy 238.706561 -313.43033) (xy 238.69777 -313.422792) (xy 238.676988 -313.406037)
			(xy 238.639857 -313.367684) (xy 238.608435 -313.32453) (xy 238.583335 -313.277417) (xy 238.565048 -313.227265)
			(xy 238.553931 -313.175053) (xy 238.550201 -313.121801) (xy 238.095199 -313.121801) (xy 238.094618 -313.130083)
			(xy 238.083497 -313.182298) (xy 238.065206 -313.232453) (xy 238.040103 -313.279569) (xy 238.008676 -313.322725)
			(xy 237.971541 -313.36108) (xy 237.950756 -313.377834) (xy 237.941976 -313.385378) (xy 237.931804 -313.406151)
			(xy 237.931198 -313.417712) (xy 237.931198 -313.497976) (xy 237.931783 -313.509542) (xy 237.941967 -313.530313)
			(xy 237.950756 -313.537854) (xy 237.973208 -313.556082) (xy 238.012947 -313.598093) (xy 238.045891 -313.64562)
			(xy 238.071286 -313.697574) (xy 238.088548 -313.752765) (xy 238.097284 -313.80993) (xy 238.097822 -313.838844)
			(xy 238.097336 -313.866095) (xy 238.08958 -313.920043) (xy 238.074225 -313.972338) (xy 238.051583 -314.021915)
			(xy 238.022117 -314.067765) (xy 237.986426 -314.108956) (xy 237.945235 -314.144647) (xy 237.899385 -314.174113)
			(xy 237.849808 -314.196755) (xy 237.797513 -314.21211) (xy 237.743565 -314.219866) (xy 237.689063 -314.219866)
			(xy 237.635115 -314.21211) (xy 237.58282 -314.196755) (xy 237.533243 -314.174113) (xy 237.487393 -314.144647)
			(xy 237.446202 -314.108956) (xy 237.410511 -314.067765) (xy 237.381045 -314.021915) (xy 237.358403 -313.972338)
			(xy 237.343048 -313.920043) (xy 237.335292 -313.866095) (xy 237.334806 -313.838844) (xy 237.335354 -313.809928)
			(xy 237.344076 -313.752758) (xy 237.361328 -313.69756) (xy 237.386714 -313.645598) (xy 237.419653 -313.598063)
			(xy 237.459389 -313.556045) (xy 237.481872 -313.537854) (xy 237.490662 -313.53032) (xy 237.500827 -313.50954)
			(xy 237.50143 -313.497976) (xy 237.50143 -313.417712) (xy 237.500877 -313.406141) (xy 237.490672 -313.385369)
			(xy 237.481872 -313.377834) (xy 237.461132 -313.361029) (xy 237.424001 -313.322682) (xy 237.392578 -313.279534)
			(xy 237.367478 -313.232427) (xy 237.349189 -313.18228) (xy 237.338069 -313.130074) (xy 237.334336 -313.076827)
			(xy 234.078715 -313.076827) (xy 234.085447 -313.108438) (xy 234.089178 -313.161688) (xy 234.08545 -313.214938)
			(xy 234.074335 -313.267148) (xy 234.05605 -313.317299) (xy 234.030952 -313.364412) (xy 233.999532 -313.407565)
			(xy 233.962402 -313.445917) (xy 233.94162 -313.46267) (xy 233.932863 -313.470236) (xy 233.92268 -313.490992)
			(xy 233.922062 -313.502548) (xy 233.922062 -313.582812) (xy 233.922604 -313.594384) (xy 233.932817 -313.615156)
			(xy 233.94162 -313.62269) (xy 233.962384 -313.639467) (xy 233.999516 -313.677816) (xy 234.030939 -313.720968)
			(xy 234.05604 -313.768078) (xy 234.074328 -313.818228) (xy 234.085447 -313.870438) (xy 234.089178 -313.923688)
			(xy 234.08545 -313.976938) (xy 234.074335 -314.029148) (xy 234.05605 -314.079299) (xy 234.030952 -314.126412)
			(xy 233.999532 -314.169565) (xy 233.962402 -314.207917) (xy 233.94162 -314.22467) (xy 233.932863 -314.232236)
			(xy 233.92268 -314.252992) (xy 233.922062 -314.264548) (xy 233.922062 -314.344812) (xy 233.922604 -314.356384)
			(xy 233.932817 -314.377156) (xy 233.94162 -314.38469) (xy 233.962384 -314.401467) (xy 233.999516 -314.439816)
			(xy 234.030939 -314.482968) (xy 234.05604 -314.530078) (xy 234.074328 -314.580228) (xy 234.085447 -314.632438)
			(xy 234.089178 -314.685688) (xy 234.08545 -314.738938) (xy 234.074335 -314.791148) (xy 234.057224 -314.83808)
			(xy 237.33836 -314.83808) (xy 237.342431 -314.782458) (xy 237.354557 -314.728021) (xy 237.37448 -314.67593)
			(xy 237.401776 -314.627295) (xy 237.435862 -314.583152) (xy 237.476011 -314.544443) (xy 237.521369 -314.511992)
			(xy 237.570969 -314.486491) (xy 237.623753 -314.468484) (xy 237.678596 -314.458354) (xy 237.73433 -314.456317)
			(xy 237.789767 -314.462417) (xy 237.843724 -314.476523) (xy 237.895053 -314.498335) (xy 237.942659 -314.527389)
			(xy 237.985527 -314.563064) (xy 238.022744 -314.604601) (xy 238.053517 -314.651114) (xy 238.077189 -314.701611)
			(xy 238.093257 -314.755018) (xy 238.101377 -314.810194) (xy 238.101886 -314.83808) (xy 238.101377 -314.865966)
			(xy 238.093257 -314.921142) (xy 238.077189 -314.974549) (xy 238.053517 -315.025046) (xy 238.022744 -315.071559)
			(xy 237.985527 -315.113096) (xy 237.942659 -315.148771) (xy 237.895053 -315.177825) (xy 237.843724 -315.199637)
			(xy 237.789767 -315.213743) (xy 237.73433 -315.219843) (xy 237.678596 -315.217806) (xy 237.623753 -315.207676)
			(xy 237.570969 -315.189669) (xy 237.521369 -315.164168) (xy 237.476011 -315.131717) (xy 237.435862 -315.093008)
			(xy 237.401776 -315.048865) (xy 237.37448 -315.00023) (xy 237.354557 -314.948139) (xy 237.342431 -314.893702)
			(xy 237.33836 -314.83808) (xy 234.057224 -314.83808) (xy 234.05605 -314.841299) (xy 234.030952 -314.888412)
			(xy 233.999532 -314.931565) (xy 233.962402 -314.969917) (xy 233.94162 -314.98667) (xy 233.932863 -314.994236)
			(xy 233.92268 -315.014992) (xy 233.922062 -315.026548) (xy 233.922062 -315.106812) (xy 233.922604 -315.118384)
			(xy 233.932817 -315.139156) (xy 233.94162 -315.14669) (xy 233.964103 -315.164882) (xy 234.003837 -315.206902)
			(xy 234.036776 -315.254437) (xy 234.062164 -315.306398) (xy 234.079421 -315.361595) (xy 234.08815 -315.418764)
			(xy 234.088686 -315.44768) (xy 234.0882 -315.474931) (xy 234.080444 -315.528879) (xy 234.065089 -315.581174)
			(xy 234.042447 -315.630751) (xy 234.012981 -315.676601) (xy 233.97729 -315.717792) (xy 233.936099 -315.753483)
			(xy 233.890249 -315.782949) (xy 233.840672 -315.805591) (xy 233.788377 -315.820946) (xy 233.734429 -315.828702)
			(xy 233.679927 -315.828702) (xy 233.625979 -315.820946) (xy 233.573684 -315.805591) (xy 233.524107 -315.782949)
			(xy 233.478257 -315.753483) (xy 233.437066 -315.717792) (xy 233.401375 -315.676601) (xy 233.371909 -315.630751)
			(xy 233.349267 -315.581174) (xy 233.333912 -315.528879) (xy 233.326156 -315.474931) (xy 233.32567 -315.44768)
			(xy 233.326219 -315.418764) (xy 233.334938 -315.361593) (xy 233.352188 -315.306394) (xy 233.377574 -315.254431)
			(xy 233.410514 -315.206897) (xy 233.450252 -315.16488) (xy 233.472736 -315.14669) (xy 233.481504 -315.139134)
			(xy 233.491683 -315.118371) (xy 233.492294 -315.106812) (xy 233.492294 -315.026548) (xy 233.491698 -315.014983)
			(xy 233.481522 -314.994212) (xy 233.472736 -314.98667) (xy 233.451934 -314.96994) (xy 233.414806 -314.931583)
			(xy 233.383386 -314.888425) (xy 233.358289 -314.841309) (xy 233.340005 -314.791154) (xy 233.328891 -314.738941)
			(xy 233.325163 -314.685688) (xy 230.253286 -314.685688) (xy 230.252759 -314.714597) (xy 230.244032 -314.771768)
			(xy 230.226776 -314.826966) (xy 230.201386 -314.878928) (xy 230.168444 -314.926462) (xy 230.128705 -314.96848)
			(xy 230.10622 -314.98667) (xy 230.097463 -314.994236) (xy 230.08728 -315.014992) (xy 230.086662 -315.026548)
			(xy 230.086662 -315.106812) (xy 230.087204 -315.118384) (xy 230.097417 -315.139156) (xy 230.10622 -315.14669)
			(xy 230.128703 -315.164882) (xy 230.168437 -315.206902) (xy 230.201376 -315.254437) (xy 230.226764 -315.306398)
			(xy 230.244021 -315.361595) (xy 230.25275 -315.418764) (xy 230.253286 -315.44768) (xy 230.2528 -315.474931)
			(xy 230.245044 -315.528879) (xy 230.229689 -315.581174) (xy 230.207047 -315.630751) (xy 230.177581 -315.676601)
			(xy 230.14189 -315.717792) (xy 230.100699 -315.753483) (xy 230.054849 -315.782949) (xy 230.005272 -315.805591)
			(xy 229.952977 -315.820946) (xy 229.899029 -315.828702) (xy 229.844527 -315.828702) (xy 229.790579 -315.820946)
			(xy 229.738284 -315.805591) (xy 229.688707 -315.782949) (xy 229.642857 -315.753483) (xy 229.601666 -315.717792)
			(xy 229.565975 -315.676601) (xy 229.536509 -315.630751) (xy 229.513867 -315.581174) (xy 229.498512 -315.528879)
			(xy 229.490756 -315.474931) (xy 229.49027 -315.44768) (xy 229.490819 -315.418764) (xy 229.499538 -315.361593)
			(xy 229.516788 -315.306394) (xy 229.542174 -315.254431) (xy 229.575114 -315.206897) (xy 229.614852 -315.16488)
			(xy 229.637336 -315.14669) (xy 229.646104 -315.139134) (xy 229.656283 -315.118371) (xy 229.656894 -315.106812)
			(xy 229.656894 -315.026548) (xy 229.656298 -315.014983) (xy 229.646122 -314.994212) (xy 229.637336 -314.98667)
			(xy 229.614846 -314.968487) (xy 229.575109 -314.926467) (xy 229.54217 -314.87893) (xy 229.516782 -314.826967)
			(xy 229.499528 -314.771768) (xy 229.490803 -314.714597) (xy 229.49027 -314.68568) (xy 229.490794 -314.657036)
			(xy 229.499362 -314.600392) (xy 229.516303 -314.545666) (xy 229.541236 -314.494089) (xy 229.5736 -314.446818)
			(xy 229.612668 -314.404918) (xy 229.634796 -314.386722) (xy 229.64394 -314.379356) (xy 229.6541 -314.358782)
			(xy 229.6541 -314.255404) (xy 229.644194 -314.23483) (xy 229.634796 -314.227464) (xy 229.612706 -314.20927)
			(xy 229.573706 -314.167391) (xy 229.541399 -314.120157) (xy 229.51651 -314.068626) (xy 229.499597 -314.013956)
			(xy 229.49104 -313.957373) (xy 229.490524 -313.92876) (xy 229.491076 -313.899844) (xy 229.499797 -313.842674)
			(xy 229.517047 -313.787476) (xy 229.542433 -313.735514) (xy 229.575371 -313.687979) (xy 229.615107 -313.645961)
			(xy 229.63759 -313.62777) (xy 229.646359 -313.620215) (xy 229.656539 -313.599451) (xy 229.657148 -313.587892)
			(xy 229.657148 -313.507628) (xy 229.656579 -313.496059) (xy 229.646385 -313.475287) (xy 229.63759 -313.46775)
			(xy 229.616766 -313.451045) (xy 229.579632 -313.412687) (xy 229.548208 -313.369527) (xy 229.523108 -313.322408)
			(xy 229.504822 -313.27225) (xy 229.493707 -313.220033) (xy 229.48998 -313.166775) (xy 228.21216 -313.166775)
			(xy 228.209694 -313.20197) (xy 228.198574 -313.254184) (xy 228.180285 -313.304339) (xy 228.155182 -313.351454)
			(xy 228.123757 -313.394609) (xy 228.086623 -313.432963) (xy 228.065838 -313.449716) (xy 228.057063 -313.457265)
			(xy 228.046889 -313.478034) (xy 228.04628 -313.489594) (xy 228.04628 -313.569858) (xy 228.046882 -313.581422)
			(xy 228.057055 -313.602192) (xy 228.065838 -313.609736) (xy 228.088347 -313.627897) (xy 228.128079 -313.669924)
			(xy 228.161013 -313.717466) (xy 228.186397 -313.769433) (xy 228.203648 -313.824635) (xy 228.212372 -313.881808)
			(xy 228.212904 -313.910726) (xy 228.212459 -313.936701) (xy 228.205413 -313.988171) (xy 228.191444 -314.038207)
			(xy 228.170808 -314.085883) (xy 228.143888 -314.130314) (xy 228.111184 -314.170678) (xy 228.073301 -314.206227)
			(xy 228.052376 -314.221622) (xy 228.04247 -314.228734) (xy 228.031294 -314.25007) (xy 228.029008 -314.35548)
			(xy 228.039168 -314.377324) (xy 228.04882 -314.38469) (xy 228.069584 -314.401467) (xy 228.106716 -314.439816)
			(xy 228.138139 -314.482968) (xy 228.16324 -314.530078) (xy 228.181528 -314.580228) (xy 228.192647 -314.632438)
			(xy 228.196378 -314.685688) (xy 228.19265 -314.738938) (xy 228.181535 -314.791148) (xy 228.16325 -314.841299)
			(xy 228.138152 -314.888412) (xy 228.106732 -314.931565) (xy 228.069602 -314.969917) (xy 228.04882 -314.98667)
			(xy 228.040063 -314.994236) (xy 228.02988 -315.014992) (xy 228.029262 -315.026548) (xy 228.029262 -315.106812)
			(xy 228.029804 -315.118384) (xy 228.040017 -315.139156) (xy 228.04882 -315.14669) (xy 228.071303 -315.164882)
			(xy 228.111037 -315.206902) (xy 228.143976 -315.254437) (xy 228.169364 -315.306398) (xy 228.186621 -315.361595)
			(xy 228.19535 -315.418764) (xy 228.195886 -315.44768) (xy 228.1954 -315.474931) (xy 228.187644 -315.528879)
			(xy 228.172289 -315.581174) (xy 228.149647 -315.630751) (xy 228.120181 -315.676601) (xy 228.08449 -315.717792)
			(xy 228.043299 -315.753483) (xy 227.997449 -315.782949) (xy 227.947872 -315.805591) (xy 227.895577 -315.820946)
			(xy 227.841629 -315.828702) (xy 227.787127 -315.828702) (xy 227.733179 -315.820946) (xy 227.680884 -315.805591)
			(xy 227.631307 -315.782949) (xy 227.585457 -315.753483) (xy 227.544266 -315.717792) (xy 227.508575 -315.676601)
			(xy 227.479109 -315.630751) (xy 227.456467 -315.581174) (xy 227.441112 -315.528879) (xy 227.433356 -315.474931)
			(xy 227.43287 -315.44768) (xy 224.360486 -315.44768) (xy 224.36 -315.474931) (xy 224.352244 -315.528879)
			(xy 224.336889 -315.581174) (xy 224.314247 -315.630751) (xy 224.284781 -315.676601) (xy 224.24909 -315.717792)
			(xy 224.207899 -315.753483) (xy 224.162049 -315.782949) (xy 224.112472 -315.805591) (xy 224.060177 -315.820946)
			(xy 224.006229 -315.828702) (xy 223.951727 -315.828702) (xy 223.897779 -315.820946) (xy 223.845484 -315.805591)
			(xy 223.795907 -315.782949) (xy 223.750057 -315.753483) (xy 223.708866 -315.717792) (xy 223.673175 -315.676601)
			(xy 223.643709 -315.630751) (xy 223.621067 -315.581174) (xy 223.605712 -315.528879) (xy 223.597956 -315.474931)
			(xy 223.59747 -315.44768) (xy 223.598019 -315.418764) (xy 223.606738 -315.361593) (xy 223.623988 -315.306394)
			(xy 223.649374 -315.254431) (xy 223.682314 -315.206897) (xy 223.722052 -315.16488) (xy 223.744536 -315.14669)
			(xy 223.753304 -315.139134) (xy 223.763483 -315.118371) (xy 223.764094 -315.106812) (xy 223.764094 -315.026548)
			(xy 223.763498 -315.014983) (xy 223.753322 -314.994212) (xy 223.744536 -314.98667) (xy 223.722046 -314.968487)
			(xy 223.682309 -314.926467) (xy 223.64937 -314.87893) (xy 223.623982 -314.826967) (xy 223.606728 -314.771768)
			(xy 223.598003 -314.714597) (xy 223.59747 -314.68568) (xy 223.597864 -314.659936) (xy 223.604787 -314.608915)
			(xy 223.618505 -314.559288) (xy 223.638768 -314.511955) (xy 223.66521 -314.467775) (xy 223.69735 -314.427549)
			(xy 223.734605 -314.392009) (xy 223.755204 -314.376562) (xy 223.765618 -314.369196) (xy 223.776794 -314.34659)
			(xy 223.77273 -314.236608) (xy 223.76003 -314.214764) (xy 223.749108 -314.207906) (xy 223.725821 -314.192934)
			(xy 223.683489 -314.157253) (xy 223.646763 -314.115826) (xy 223.616413 -314.069523) (xy 223.593077 -314.019318)
			(xy 223.577247 -313.966267) (xy 223.569256 -313.911484) (xy 223.568768 -313.883802) (xy 223.569262 -313.854884)
			(xy 223.577992 -313.79771) (xy 223.595253 -313.74251) (xy 223.62065 -313.690548) (xy 223.653599 -313.643015)
			(xy 223.693346 -313.601) (xy 223.715834 -313.582812) (xy 223.724592 -313.575246) (xy 223.734776 -313.55449)
			(xy 223.735392 -313.542934) (xy 223.735392 -313.46267) (xy 223.734784 -313.451107) (xy 223.724616 -313.430335)
			(xy 223.715834 -313.422792) (xy 223.695054 -313.406036) (xy 223.657926 -313.367682) (xy 223.626507 -313.324527)
			(xy 223.601409 -313.277414) (xy 223.583124 -313.227262) (xy 223.572008 -313.175052) (xy 223.568279 -313.121801)
			(xy 223.113276 -313.121801) (xy 223.112695 -313.130084) (xy 223.101573 -313.1823) (xy 223.083281 -313.232456)
			(xy 223.058175 -313.279572) (xy 223.026745 -313.322728) (xy 222.989607 -313.361081) (xy 222.96882 -313.377834)
			(xy 222.960034 -313.385372) (xy 222.949867 -313.406149) (xy 222.949262 -313.417712) (xy 222.949262 -313.497976)
			(xy 222.949825 -313.509545) (xy 222.960023 -313.530318) (xy 222.96882 -313.537854) (xy 222.991286 -313.556066)
			(xy 223.031021 -313.598082) (xy 223.063962 -313.645613) (xy 223.089353 -313.69757) (xy 223.106613 -313.752763)
			(xy 223.115348 -313.809929) (xy 223.115886 -313.838844) (xy 223.1154 -313.866095) (xy 223.107644 -313.920043)
			(xy 223.092289 -313.972338) (xy 223.069647 -314.021915) (xy 223.040181 -314.067765) (xy 223.00449 -314.108956)
			(xy 222.963299 -314.144647) (xy 222.917449 -314.174113) (xy 222.867872 -314.196755) (xy 222.815577 -314.21211)
			(xy 222.761629 -314.219866) (xy 222.707127 -314.219866) (xy 222.653179 -314.21211) (xy 222.600884 -314.196755)
			(xy 222.551307 -314.174113) (xy 222.505457 -314.144647) (xy 222.464266 -314.108956) (xy 222.428575 -314.067765)
			(xy 222.399109 -314.021915) (xy 222.376467 -313.972338) (xy 222.361112 -313.920043) (xy 222.353356 -313.866095)
			(xy 222.35287 -313.838844) (xy 222.353393 -313.809927) (xy 222.362117 -313.752755) (xy 222.379373 -313.697555)
			(xy 222.404763 -313.645592) (xy 222.437707 -313.598059) (xy 222.47745 -313.556043) (xy 222.499936 -313.537854)
			(xy 222.50872 -313.530314) (xy 222.51889 -313.509538) (xy 222.519494 -313.497976) (xy 222.519494 -313.417712)
			(xy 222.518919 -313.406145) (xy 222.508728 -313.385374) (xy 222.499936 -313.377834) (xy 222.479198 -313.361028)
			(xy 222.44207 -313.32268) (xy 222.41065 -313.279531) (xy 222.385552 -313.232424) (xy 222.367265 -313.182278)
			(xy 222.356147 -313.130073) (xy 222.352414 -313.076827) (xy 221.5642 -313.076827) (xy 221.5642 -314.83808)
			(xy 222.356424 -314.83808) (xy 222.360495 -314.782458) (xy 222.372621 -314.728021) (xy 222.392544 -314.67593)
			(xy 222.41984 -314.627295) (xy 222.453926 -314.583152) (xy 222.494075 -314.544443) (xy 222.539433 -314.511992)
			(xy 222.589033 -314.486491) (xy 222.641817 -314.468484) (xy 222.69666 -314.458354) (xy 222.752394 -314.456317)
			(xy 222.807831 -314.462417) (xy 222.861788 -314.476523) (xy 222.913117 -314.498335) (xy 222.960723 -314.527389)
			(xy 223.003591 -314.563064) (xy 223.040808 -314.604601) (xy 223.071581 -314.651114) (xy 223.095253 -314.701611)
			(xy 223.111321 -314.755018) (xy 223.119441 -314.810194) (xy 223.11995 -314.83808) (xy 223.119441 -314.865966)
			(xy 223.111321 -314.921142) (xy 223.095253 -314.974549) (xy 223.071581 -315.025046) (xy 223.040808 -315.071559)
			(xy 223.003591 -315.113096) (xy 222.960723 -315.148771) (xy 222.913117 -315.177825) (xy 222.861788 -315.199637)
			(xy 222.807831 -315.213743) (xy 222.752394 -315.219843) (xy 222.69666 -315.217806) (xy 222.641817 -315.207676)
			(xy 222.589033 -315.189669) (xy 222.539433 -315.164168) (xy 222.494075 -315.131717) (xy 222.453926 -315.093008)
			(xy 222.41984 -315.048865) (xy 222.392544 -315.00023) (xy 222.372621 -314.948139) (xy 222.360495 -314.893702)
			(xy 222.356424 -314.83808) (xy 221.5642 -314.83808) (xy 221.5642 -318.17691) (xy 221.564625 -318.186979)
			(xy 221.572342 -318.205581) (xy 221.579186 -318.212978) (xy 223.230694 -319.864486) (xy 223.238091 -319.871335)
			(xy 223.25669 -319.879074) (xy 223.266762 -319.879472)
		)
		(stroke
			(width 0)
			(type solid)
		)
		(fill yes)
		(layer "In2.Cu")
		(net "GND")
	)
	(gr_poly
		(pts
			(xy 233.295698 -228.963728) (xy 233.307363 -228.963155) (xy 233.328279 -228.952826) (xy 233.33583 -228.943916)
			(xy 233.392472 -228.870256) (xy 233.39679 -228.84765) (xy 233.393742 -228.835966) (xy 233.387913 -228.812586)
			(xy 233.381665 -228.764808) (xy 233.381296 -228.740716) (xy 233.381812 -228.713116) (xy 233.390039 -228.658533)
			(xy 233.406309 -228.605786) (xy 233.430259 -228.556054) (xy 233.461354 -228.510446) (xy 233.498899 -228.469982)
			(xy 233.542056 -228.435565) (xy 233.58986 -228.407966) (xy 233.641244 -228.387799) (xy 233.695059 -228.375516)
			(xy 233.750104 -228.371391) (xy 233.805149 -228.375516) (xy 233.858964 -228.387799) (xy 233.910348 -228.407966)
			(xy 233.958152 -228.435565) (xy 234.001309 -228.469982) (xy 234.038854 -228.510446) (xy 234.069949 -228.556054)
			(xy 234.093899 -228.605786) (xy 234.110169 -228.658533) (xy 234.118396 -228.713116) (xy 234.118912 -228.740716)
			(xy 234.118539 -228.764809) (xy 234.112299 -228.812587) (xy 234.106466 -228.835966) (xy 234.103418 -228.84765)
			(xy 234.107736 -228.870256) (xy 234.164378 -228.943916) (xy 234.171966 -228.952772) (xy 234.192864 -228.963071)
			(xy 234.20451 -228.963728) (xy 235.289344 -228.963728) (xy 235.299411 -228.963298) (xy 235.318007 -228.955575)
			(xy 235.325412 -228.948742) (xy 237.246922 -227.027232) (xy 237.254803 -227.018442) (xy 237.262222 -226.996062)
			(xy 237.261146 -226.984306) (xy 237.248192 -226.892104) (xy 237.234984 -226.872546) (xy 237.224316 -226.866704)
			(xy 237.194703 -226.849642) (xy 237.139915 -226.808789) (xy 237.091082 -226.760975) (xy 237.06963 -226.73437)
			(xy 237.063534 -226.726242) (xy 237.04677 -226.71659) (xy 236.957108 -226.703636) (xy 236.938312 -226.708462)
			(xy 236.930184 -226.714304) (xy 236.906513 -226.730659) (xy 236.85516 -226.756597) (xy 236.800398 -226.774232)
			(xy 236.743558 -226.783133) (xy 236.714792 -226.783646) (xy 236.688447 -226.783176) (xy 236.636294 -226.775677)
			(xy 236.585739 -226.760832) (xy 236.537811 -226.738945) (xy 236.493485 -226.71046) (xy 236.453664 -226.675957)
			(xy 236.419158 -226.636139) (xy 236.390669 -226.591815) (xy 236.368778 -226.543889) (xy 236.35393 -226.493335)
			(xy 236.346427 -226.441183) (xy 236.345984 -226.414838) (xy 236.346587 -226.385034) (xy 236.356153 -226.3262)
			(xy 236.365034 -226.297744) (xy 236.369606 -226.283774) (xy 236.363256 -226.256088) (xy 236.278928 -226.170998)
			(xy 236.251242 -226.16414) (xy 236.237272 -226.168712) (xy 236.208539 -226.177497) (xy 236.149203 -226.186936)
			(xy 236.119162 -226.187508) (xy 236.091911 -226.18702) (xy 236.037966 -226.179258) (xy 235.985673 -226.163898)
			(xy 235.936099 -226.141253) (xy 235.890252 -226.111783) (xy 235.849066 -226.076089) (xy 235.813379 -226.034897)
			(xy 235.783916 -225.989045) (xy 235.76128 -225.939467) (xy 235.745929 -225.887173) (xy 235.738176 -225.833225)
			(xy 235.73818 -225.778724) (xy 235.745939 -225.724778) (xy 235.761297 -225.672485) (xy 235.783941 -225.62291)
			(xy 235.813409 -225.577062) (xy 235.849102 -225.535875) (xy 235.890293 -225.500186) (xy 235.936144 -225.470723)
			(xy 235.985721 -225.448084) (xy 236.038015 -225.432731) (xy 236.091962 -225.424977) (xy 236.146463 -225.424979)
			(xy 236.20041 -225.432737) (xy 236.252703 -225.448093) (xy 236.302279 -225.470735) (xy 236.348127 -225.500201)
			(xy 236.389316 -225.535893) (xy 236.425006 -225.577083) (xy 236.454471 -225.622933) (xy 236.477112 -225.672509)
			(xy 236.492466 -225.724803) (xy 236.500222 -225.778749) (xy 236.50067 -225.806) (xy 236.500029 -225.838117)
			(xy 236.489302 -225.901447) (xy 236.479334 -225.931984) (xy 236.474508 -225.9457) (xy 236.480604 -225.97364)
			(xy 236.563662 -226.06) (xy 236.591348 -226.066858) (xy 236.605318 -226.06254) (xy 236.632019 -226.054791)
			(xy 236.686993 -226.046505) (xy 236.714792 -226.04603) (xy 236.744423 -226.046598) (xy 236.802927 -226.056036)
			(xy 236.859166 -226.074719) (xy 236.911689 -226.102164) (xy 236.935772 -226.119436) (xy 236.9439 -226.125532)
			(xy 236.962442 -226.130612) (xy 237.052358 -226.119436) (xy 237.069376 -226.110038) (xy 237.075726 -226.102164)
			(xy 237.096463 -226.077325) (xy 237.143205 -226.032581) (xy 237.195247 -225.99413) (xy 237.251748 -225.962594)
			(xy 237.311794 -225.938484) (xy 237.374415 -225.922188) (xy 237.438597 -225.91397) (xy 237.47095 -225.913442)
			(xy 237.504794 -225.914002) (xy 237.571883 -225.922986) (xy 237.637188 -225.940789) (xy 237.699554 -225.967095)
			(xy 237.757881 -226.001441) (xy 237.811137 -226.043219) (xy 237.858382 -226.091691) (xy 237.898781 -226.146002)
			(xy 237.915704 -226.175316) (xy 237.921546 -226.185984) (xy 237.941104 -226.199192) (xy 238.033306 -226.212146)
			(xy 238.045058 -226.213195) (xy 238.067428 -226.205778) (xy 238.076232 -226.197922) (xy 239.566958 -224.707196)
			(xy 239.574232 -224.699166) (xy 239.581873 -224.678912) (xy 239.58169 -224.66808) (xy 239.576102 -224.580958)
			(xy 239.565942 -224.561654) (xy 239.557306 -224.55505) (xy 239.534641 -224.536866) (xy 239.494563 -224.494794)
			(xy 239.461332 -224.447128) (xy 239.435718 -224.394972) (xy 239.418313 -224.339534) (xy 239.409521 -224.282097)
			(xy 239.40897 -224.253044) (xy 239.40943 -224.225788) (xy 239.417182 -224.171832) (xy 239.432534 -224.119527)
			(xy 239.455173 -224.06994) (xy 239.48464 -224.02408) (xy 239.520333 -223.98288) (xy 239.561527 -223.947179)
			(xy 239.607382 -223.917705) (xy 239.656965 -223.895057) (xy 239.709267 -223.879696) (xy 239.763223 -223.871935)
			(xy 239.790478 -223.871536) (xy 239.819528 -223.872086) (xy 239.876955 -223.880904) (xy 239.932383 -223.898324)
			(xy 239.984529 -223.923943) (xy 240.032191 -223.95717) (xy 240.074265 -223.997237) (xy 240.092484 -224.019872)
			(xy 240.099088 -224.028508) (xy 240.118392 -224.038668) (xy 240.205514 -224.044256) (xy 240.216355 -224.044472)
			(xy 240.236631 -224.036843) (xy 240.24463 -224.029524) (xy 241.532918 -222.741236) (xy 241.540538 -222.718376)
			(xy 241.538506 -222.706438) (xy 241.536572 -222.692422) (xy 241.534541 -222.664199) (xy 241.534442 -222.65005)
			(xy 241.534902 -222.622796) (xy 241.542653 -222.568842) (xy 241.558006 -222.516541) (xy 241.580646 -222.466958)
			(xy 241.610113 -222.421102) (xy 241.645808 -222.379908) (xy 241.687002 -222.344213) (xy 241.732858 -222.314746)
			(xy 241.782441 -222.292106) (xy 241.834742 -222.276753) (xy 241.888696 -222.269002) (xy 241.91595 -222.268542)
			(xy 241.930098 -222.268648) (xy 241.95832 -222.270685) (xy 241.972338 -222.272606) (xy 241.984276 -222.274638)
			(xy 242.007136 -222.267018) (xy 246.551704 -217.72245) (xy 246.558542 -217.715049) (xy 246.566258 -217.696451)
			(xy 246.56669 -217.686382) (xy 246.56669 -203.437744) (xy 246.567123 -203.427678) (xy 246.57485 -203.409087)
			(xy 246.581676 -203.401676) (xy 253.588266 -196.395086) (xy 253.595664 -196.388241) (xy 253.614263 -196.380517)
			(xy 253.624334 -196.3801) (xy 255.3208 -196.3801) (xy 255.331551 -196.379625) (xy 255.35116 -196.370812)
			(xy 255.358646 -196.363082) (xy 255.416558 -196.298312) (xy 255.423162 -196.277992) (xy 255.421892 -196.26707)
			(xy 255.420359 -196.252832) (xy 255.418706 -196.22424) (xy 255.41859 -196.20992) (xy 255.419041 -196.179393)
			(xy 255.426349 -196.118779) (xy 255.440862 -196.059475) (xy 255.462372 -196.002336) (xy 255.490568 -195.948184)
			(xy 255.525046 -195.897798) (xy 255.56531 -195.851902) (xy 255.587754 -195.831206) (xy 255.596064 -195.822998)
			(xy 255.604844 -195.801379) (xy 255.603244 -195.7781) (xy 255.597914 -195.767706) (xy 255.585489 -195.745693)
			(xy 255.565918 -195.699086) (xy 255.55268 -195.650301) (xy 255.546008 -195.600195) (xy 255.54559 -195.57492)
			(xy 255.546067 -195.547552) (xy 255.553901 -195.493379) (xy 255.569397 -195.440882) (xy 255.592236 -195.391138)
			(xy 255.621949 -195.345169) (xy 255.63957 -195.324222) (xy 255.645666 -195.31711) (xy 255.652016 -195.300092)
			(xy 255.652016 -195.214748) (xy 255.645666 -195.19773) (xy 255.63957 -195.190618) (xy 255.621928 -195.169686)
			(xy 255.592202 -195.12372) (xy 255.569359 -195.073973) (xy 255.553867 -195.02147) (xy 255.546047 -194.967291)
			(xy 255.54559 -194.93992) (xy 255.546207 -194.908066) (xy 255.556755 -194.84524) (xy 255.577611 -194.785044)
			(xy 255.592326 -194.756786) (xy 255.596067 -194.74937) (xy 255.599055 -194.73304) (xy 255.598168 -194.724782)
			(xy 255.593596 -194.695572) (xy 255.592041 -194.687295) (xy 255.584261 -194.672367) (xy 255.578356 -194.666362)
			(xy 255.553608 -194.642243) (xy 255.510198 -194.588474) (xy 255.47447 -194.529322) (xy 255.447082 -194.465876)
			(xy 255.428539 -194.399305) (xy 255.419183 -194.330836) (xy 255.41859 -194.296284) (xy 255.41917 -194.261329)
			(xy 255.428741 -194.192078) (xy 255.447702 -194.124789) (xy 255.475694 -194.060728) (xy 255.512192 -194.001102)
			(xy 255.533906 -193.973704) (xy 255.539139 -193.966685) (xy 255.544986 -193.950194) (xy 255.545336 -193.941446)
			(xy 255.545336 -193.787522) (xy 255.545017 -193.778768) (xy 255.539162 -193.762273) (xy 255.533906 -193.755264)
			(xy 255.512192 -193.727866) (xy 255.475689 -193.668243) (xy 255.447697 -193.604182) (xy 255.428742 -193.536892)
			(xy 255.419183 -193.467639) (xy 255.41859 -193.432684) (xy 255.419071 -193.401387) (xy 255.426758 -193.339267)
			(xy 255.442012 -193.27856) (xy 255.464605 -193.220185) (xy 255.494192 -193.165026) (xy 255.530328 -193.113916)
			(xy 255.572465 -193.067629) (xy 255.595882 -193.046858) (xy 255.602028 -193.041123) (xy 255.610457 -193.02659)
			(xy 255.612392 -193.01841) (xy 255.618234 -192.989454) (xy 255.619576 -192.981261) (xy 255.617505 -192.964799)
			(xy 255.61417 -192.957196) (xy 255.601864 -192.93089) (xy 255.584459 -192.875484) (xy 255.575628 -192.818085)
			(xy 255.575054 -192.789048) (xy 255.57554 -192.761797) (xy 255.583296 -192.707849) (xy 255.598651 -192.655554)
			(xy 255.621293 -192.605977) (xy 255.650759 -192.560127) (xy 255.68645 -192.518936) (xy 255.727641 -192.483245)
			(xy 255.773491 -192.453779) (xy 255.823068 -192.431137) (xy 255.875363 -192.415782) (xy 255.929311 -192.408026)
			(xy 255.983813 -192.408026) (xy 256.037761 -192.415782) (xy 256.090056 -192.431137) (xy 256.139633 -192.453779)
			(xy 256.185483 -192.483245) (xy 256.226674 -192.518936) (xy 256.262365 -192.560127) (xy 256.291831 -192.605977)
			(xy 256.314473 -192.655554) (xy 256.329828 -192.707849) (xy 256.337584 -192.761797) (xy 256.33807 -192.789048)
			(xy 256.33762 -192.815175) (xy 256.330453 -192.866937) (xy 256.3163 -192.91724) (xy 256.295426 -192.965145)
			(xy 256.28219 -192.987676) (xy 256.278146 -192.994935) (xy 256.274501 -193.011137) (xy 256.275078 -193.019426)
			(xy 256.278126 -193.04889) (xy 256.27936 -193.057284) (xy 256.286616 -193.07261) (xy 256.29235 -193.078862)
			(xy 256.314688 -193.102641) (xy 256.353716 -193.154923) (xy 256.385734 -193.211769) (xy 256.410218 -193.272244)
			(xy 256.426763 -193.335354) (xy 256.435099 -193.400062) (xy 256.435606 -193.432684) (xy 256.435028 -193.467639)
			(xy 256.425461 -193.536893) (xy 256.406504 -193.604184) (xy 256.378514 -193.668248) (xy 256.342018 -193.727876)
			(xy 256.32029 -193.755264) (xy 256.315059 -193.762283) (xy 256.309223 -193.778775) (xy 256.30886 -193.787522)
			(xy 256.30886 -193.941446) (xy 256.309173 -193.950202) (xy 256.31502 -193.966704) (xy 256.32029 -193.973704)
			(xy 256.342006 -194.001102) (xy 256.378513 -194.060724) (xy 256.406509 -194.124784) (xy 256.425468 -194.192075)
			(xy 256.435032 -194.261328) (xy 256.435606 -194.296284) (xy 256.435027 -194.330837) (xy 256.42567 -194.399308)
			(xy 256.407126 -194.46588) (xy 256.395581 -194.492626) (xy 259.966714 -194.492626) (xy 259.967307 -194.457671)
			(xy 259.976866 -194.388418) (xy 259.99582 -194.321127) (xy 260.023812 -194.257067) (xy 260.060316 -194.197444)
			(xy 260.08203 -194.170046) (xy 260.087285 -194.163036) (xy 260.09314 -194.146542) (xy 260.09346 -194.137788)
			(xy 260.09346 -193.856864) (xy 260.09312 -193.848115) (xy 260.087268 -193.831623) (xy 260.08203 -193.824606)
			(xy 260.060324 -193.797201) (xy 260.023824 -193.737578) (xy 259.99583 -193.673519) (xy 259.976868 -193.606231)
			(xy 259.967295 -193.53698) (xy 259.966714 -193.502026) (xy 259.967192 -193.469875) (xy 259.975289 -193.406086)
			(xy 259.99137 -193.343828) (xy 260.015177 -193.284097) (xy 260.046331 -193.227847) (xy 260.084332 -193.175976)
			(xy 260.128575 -193.129316) (xy 260.15315 -193.10858) (xy 260.16077 -193.10223) (xy 260.170168 -193.085212)
			(xy 260.18109 -192.99555) (xy 260.17601 -192.977008) (xy 260.169914 -192.96888) (xy 260.152013 -192.94394)
			(xy 260.12355 -192.889553) (xy 260.104155 -192.831312) (xy 260.094329 -192.770719) (xy 260.093714 -192.740026)
			(xy 260.0942 -192.712775) (xy 260.101956 -192.658827) (xy 260.117311 -192.606532) (xy 260.139953 -192.556955)
			(xy 260.169419 -192.511105) (xy 260.20511 -192.469914) (xy 260.246301 -192.434223) (xy 260.292151 -192.404757)
			(xy 260.341728 -192.382115) (xy 260.394023 -192.36676) (xy 260.447971 -192.359004) (xy 260.502473 -192.359004)
			(xy 260.556421 -192.36676) (xy 260.608716 -192.382115) (xy 260.658293 -192.404757) (xy 260.704143 -192.434223)
			(xy 260.745334 -192.469914) (xy 260.781025 -192.511105) (xy 260.810491 -192.556955) (xy 260.833133 -192.606532)
			(xy 260.848488 -192.658827) (xy 260.856244 -192.712775) (xy 260.85673 -192.740026) (xy 260.856137 -192.77072)
			(xy 260.846309 -192.831316) (xy 260.826911 -192.889559) (xy 260.798442 -192.943947) (xy 260.78053 -192.96888)
			(xy 260.774434 -192.977008) (xy 260.769354 -192.99555) (xy 260.780276 -193.085212) (xy 260.789674 -193.10223)
			(xy 260.797294 -193.10858) (xy 260.82186 -193.129323) (xy 260.866085 -193.175995) (xy 260.904074 -193.227869)
			(xy 260.935221 -193.284118) (xy 260.959029 -193.343844) (xy 260.975119 -193.406095) (xy 260.983233 -193.469878)
			(xy 260.98373 -193.502026) (xy 260.983157 -193.536981) (xy 260.973592 -193.606235) (xy 260.954632 -193.673526)
			(xy 260.926636 -193.737586) (xy 260.890129 -193.797208) (xy 260.868414 -193.824606) (xy 260.863142 -193.831605)
			(xy 260.857296 -193.848108) (xy 260.856984 -193.856864) (xy 260.856984 -194.137788) (xy 260.857357 -194.146534)
			(xy 260.863188 -194.163025) (xy 260.868414 -194.170046) (xy 260.890104 -194.197462) (xy 260.926605 -194.257084)
			(xy 260.954602 -194.32114) (xy 260.973568 -194.388425) (xy 260.983146 -194.457673) (xy 260.98373 -194.492626)
			(xy 260.983238 -194.524776) (xy 260.975146 -194.588566) (xy 260.959069 -194.650824) (xy 260.935264 -194.710556)
			(xy 260.904113 -194.766807) (xy 260.866112 -194.818677) (xy 260.821869 -194.865337) (xy 260.797294 -194.886072)
			(xy 260.789674 -194.892422) (xy 260.780276 -194.90944) (xy 260.769354 -194.999102) (xy 260.774434 -195.017644)
			(xy 260.78053 -195.025772) (xy 260.798446 -195.050701) (xy 260.826908 -195.105091) (xy 260.846299 -195.163336)
			(xy 260.856119 -195.223932) (xy 260.85673 -195.254626) (xy 260.856244 -195.281877) (xy 260.848488 -195.335825)
			(xy 260.833133 -195.38812) (xy 260.810491 -195.437697) (xy 260.781025 -195.483547) (xy 260.745334 -195.524738)
			(xy 260.704143 -195.560429) (xy 260.658293 -195.589895) (xy 260.608716 -195.612537) (xy 260.556421 -195.627892)
			(xy 260.502473 -195.635648) (xy 260.447971 -195.635648) (xy 260.394023 -195.627892) (xy 260.341728 -195.612537)
			(xy 260.292151 -195.589895) (xy 260.246301 -195.560429) (xy 260.20511 -195.524738) (xy 260.169419 -195.483547)
			(xy 260.139953 -195.437697) (xy 260.117311 -195.38812) (xy 260.101956 -195.335825) (xy 260.0942 -195.281877)
			(xy 260.093714 -195.254626) (xy 260.094345 -195.223934) (xy 260.104163 -195.163339) (xy 260.123551 -195.105097)
			(xy 260.152008 -195.050707) (xy 260.169914 -195.025772) (xy 260.17601 -195.017644) (xy 260.18109 -194.999102)
			(xy 260.170168 -194.90944) (xy 260.16077 -194.892422) (xy 260.15315 -194.886072) (xy 260.12857 -194.865344)
			(xy 260.084344 -194.818671) (xy 260.046355 -194.766795) (xy 260.015209 -194.710544) (xy 259.991404 -194.650814)
			(xy 259.975318 -194.58856) (xy 259.967208 -194.524775) (xy 259.966714 -194.492626) (xy 256.395581 -194.492626)
			(xy 256.379738 -194.529328) (xy 256.344009 -194.588481) (xy 256.300598 -194.642251) (xy 256.27584 -194.666362)
			(xy 256.269994 -194.67241) (xy 256.262228 -194.687318) (xy 256.2606 -194.695572) (xy 256.256028 -194.724782)
			(xy 256.255156 -194.73304) (xy 256.258148 -194.749362) (xy 256.26187 -194.756786) (xy 256.276575 -194.785047)
			(xy 256.297409 -194.845247) (xy 256.30797 -194.908068) (xy 256.308606 -194.93992) (xy 256.308133 -194.96729)
			(xy 256.300307 -195.021466) (xy 256.284818 -195.073969) (xy 256.261984 -195.123718) (xy 256.232274 -195.169693)
			(xy 256.214626 -195.190618) (xy 256.20853 -195.19773) (xy 256.20218 -195.214748) (xy 256.20218 -195.300092)
			(xy 256.20853 -195.31711) (xy 256.214626 -195.324222) (xy 256.232266 -195.345154) (xy 256.261987 -195.391122)
			(xy 256.284826 -195.440869) (xy 256.300312 -195.493372) (xy 256.308127 -195.54755) (xy 256.308606 -195.57492)
			(xy 256.308194 -195.600194) (xy 256.301514 -195.6503) (xy 256.288274 -195.699084) (xy 256.268706 -195.745692)
			(xy 256.256282 -195.767706) (xy 256.250877 -195.778086) (xy 256.249214 -195.801402) (xy 256.258062 -195.823038)
			(xy 256.266442 -195.831206) (xy 256.288874 -195.851914) (xy 256.329136 -195.897808) (xy 256.363613 -195.948193)
			(xy 256.391809 -196.002343) (xy 256.413319 -196.05948) (xy 256.427832 -196.118782) (xy 256.43514 -196.179394)
			(xy 256.435606 -196.20992) (xy 256.435484 -196.22424) (xy 256.433832 -196.252832) (xy 256.432304 -196.26707)
			(xy 256.431034 -196.277992) (xy 256.437638 -196.298312) (xy 256.49555 -196.363082) (xy 256.503116 -196.370698)
			(xy 256.522677 -196.379484) (xy 256.533396 -196.3801) (xy 262.668004 -196.3801) (xy 262.693912 -196.362574)
			(xy 262.6995 -196.348096) (xy 262.710169 -196.322779) (xy 262.737717 -196.275247) (xy 262.77179 -196.232152)
			(xy 262.811687 -196.194383) (xy 262.833866 -196.17817) (xy 262.842502 -196.172074) (xy 262.85317 -196.154548)
			(xy 262.866632 -196.06006) (xy 262.861298 -196.040248) (xy 262.854694 -196.031866) (xy 262.833812 -196.004764)
			(xy 262.79874 -195.946018) (xy 262.771868 -195.883097) (xy 262.753682 -195.817139) (xy 262.744511 -195.749338)
			(xy 262.74395 -195.715128) (xy 262.744452 -195.683167) (xy 262.752463 -195.619749) (xy 262.76836 -195.557835)
			(xy 262.791892 -195.498402) (xy 262.822686 -195.442387) (xy 262.860259 -195.390672) (xy 262.904016 -195.344075)
			(xy 262.953269 -195.30333) (xy 263.00724 -195.269079) (xy 263.065079 -195.241862) (xy 263.125872 -195.222109)
			(xy 263.188662 -195.210131) (xy 263.252458 -195.206118) (xy 263.316254 -195.210131) (xy 263.379044 -195.222109)
			(xy 263.439837 -195.241862) (xy 263.497676 -195.269079) (xy 263.551647 -195.30333) (xy 263.6009 -195.344075)
			(xy 263.644657 -195.390672) (xy 263.68223 -195.442387) (xy 263.713024 -195.498402) (xy 263.736556 -195.557835)
			(xy 263.752453 -195.619749) (xy 263.760464 -195.683167) (xy 263.760966 -195.715128) (xy 263.760427 -195.748319)
			(xy 263.751788 -195.814138) (xy 263.73466 -195.878273) (xy 263.709334 -195.939635) (xy 263.676242 -195.997181)
			(xy 263.635944 -196.049934) (xy 263.589127 -196.096996) (xy 263.536585 -196.137567) (xy 263.479212 -196.170959)
			(xy 263.4488 -196.184266) (xy 263.438894 -196.18833) (xy 263.42467 -196.203062) (xy 263.390888 -196.29247)
			(xy 263.391904 -196.31279) (xy 263.39673 -196.322442) (xy 263.40816 -196.348096) (xy 263.413748 -196.362574)
			(xy 263.439656 -196.3801) (xy 263.65454 -196.3801) (xy 263.664446 -196.375782) (xy 263.69726 -196.361726)
			(xy 263.765844 -196.341922) (xy 263.836525 -196.331923) (xy 263.872218 -196.331332) (xy 263.907909 -196.331954)
			(xy 263.978585 -196.341962) (xy 264.047173 -196.361738) (xy 264.07999 -196.375782) (xy 264.089896 -196.3801)
			(xy 268.049248 -196.3801) (xy 268.059151 -196.379629) (xy 268.077487 -196.372136) (xy 268.091638 -196.358276)
			(xy 268.095984 -196.349366) (xy 268.13891 -196.249544) (xy 268.13383 -196.219826) (xy 268.123162 -196.20865)
			(xy 268.10144 -196.184978) (xy 268.06351 -196.133121) (xy 268.032411 -196.0769) (xy 268.008639 -196.017212)
			(xy 267.992571 -195.955005) (xy 267.984463 -195.89127) (xy 267.98397 -195.859146) (xy 267.984508 -195.825988)
			(xy 267.99313 -195.760236) (xy 268.010221 -195.696161) (xy 268.035492 -195.634849) (xy 268.068514 -195.57734)
			(xy 268.108727 -195.524608) (xy 268.15545 -195.477548) (xy 268.181328 -195.45681) (xy 268.190194 -195.449228)
			(xy 268.200507 -195.428328) (xy 268.20114 -195.416678) (xy 268.20114 -195.336414) (xy 268.20057 -195.324747)
			(xy 268.190246 -195.303825) (xy 268.181328 -195.296282) (xy 268.155434 -195.275564) (xy 268.108711 -195.228501)
			(xy 268.068499 -195.175767) (xy 268.035481 -195.118254) (xy 268.010217 -195.056939) (xy 267.993134 -194.99286)
			(xy 267.984524 -194.927104) (xy 267.98397 -194.893946) (xy 267.984519 -194.86017) (xy 267.993455 -194.793212)
			(xy 268.011176 -194.728026) (xy 268.037369 -194.66576) (xy 268.071574 -194.607508) (xy 268.113188 -194.554297)
			(xy 268.16148 -194.507062) (xy 268.2156 -194.466636) (xy 268.244828 -194.4497) (xy 268.256004 -194.443604)
			(xy 268.26972 -194.422522) (xy 268.279118 -194.313556) (xy 268.269466 -194.290188) (xy 268.25956 -194.282314)
			(xy 268.238708 -194.264704) (xy 268.201923 -194.224386) (xy 268.171485 -194.179084) (xy 268.148057 -194.129791)
			(xy 268.132153 -194.077582) (xy 268.12412 -194.023599) (xy 268.12367 -193.99631) (xy 268.124186 -193.96871)
			(xy 268.132413 -193.914127) (xy 268.148683 -193.86138) (xy 268.172633 -193.811648) (xy 268.203728 -193.76604)
			(xy 268.241273 -193.725576) (xy 268.28443 -193.691159) (xy 268.332234 -193.66356) (xy 268.383618 -193.643393)
			(xy 268.437433 -193.63111) (xy 268.492478 -193.626985) (xy 268.547523 -193.63111) (xy 268.601338 -193.643393)
			(xy 268.652722 -193.66356) (xy 268.700526 -193.691159) (xy 268.743683 -193.725576) (xy 268.781228 -193.76604)
			(xy 268.812323 -193.811648) (xy 268.836273 -193.86138) (xy 268.852543 -193.914127) (xy 268.86077 -193.96871)
			(xy 268.861286 -193.99631) (xy 268.860794 -194.023596) (xy 268.852754 -194.077574) (xy 268.836852 -194.129778)
			(xy 268.813435 -194.179071) (xy 268.783012 -194.224377) (xy 268.746248 -194.264708) (xy 268.725396 -194.282314)
			(xy 268.71549 -194.290188) (xy 268.705838 -194.313556) (xy 268.715236 -194.422522) (xy 268.728952 -194.443604)
			(xy 268.740128 -194.4497) (xy 268.769353 -194.46664) (xy 268.823466 -194.507072) (xy 268.871753 -194.554309)
			(xy 268.913365 -194.60752) (xy 268.94757 -194.66577) (xy 268.973766 -194.728034) (xy 268.991493 -194.793216)
			(xy 269.000438 -194.860171) (xy 269.000986 -194.893946) (xy 269.000449 -194.927103) (xy 268.991827 -194.992856)
			(xy 268.974735 -195.05693) (xy 268.949464 -195.118241) (xy 268.916441 -195.175749) (xy 268.876226 -195.228479)
			(xy 268.829501 -195.275537) (xy 268.803628 -195.296282) (xy 268.794766 -195.303867) (xy 268.78446 -195.324766)
			(xy 268.783816 -195.336414) (xy 268.783816 -195.416678) (xy 268.784383 -195.428347) (xy 268.794699 -195.449278)
			(xy 268.803628 -195.45681) (xy 268.829524 -195.477527) (xy 268.876252 -195.524588) (xy 268.916468 -195.577321)
			(xy 268.94949 -195.634834) (xy 268.949607 -195.635118) (xy 270.30807 -195.635118) (xy 270.308581 -195.602397)
			(xy 270.317183 -195.537524) (xy 270.334242 -195.474345) (xy 270.359459 -195.413958) (xy 270.392399 -195.357411)
			(xy 270.432487 -195.305687) (xy 270.45539 -195.282312) (xy 270.462756 -195.2752) (xy 270.47063 -195.256404)
			(xy 270.47063 -195.163694) (xy 270.462756 -195.144898) (xy 270.45539 -195.137786) (xy 270.432478 -195.114421)
			(xy 270.392395 -195.062692) (xy 270.359462 -195.006142) (xy 270.334249 -194.945753) (xy 270.317193 -194.882574)
			(xy 270.308593 -194.8177) (xy 270.30807 -194.78498) (xy 270.308559 -194.753817) (xy 270.316371 -194.691983)
			(xy 270.331871 -194.631615) (xy 270.354814 -194.573667) (xy 270.38484 -194.51905) (xy 270.421474 -194.468628)
			(xy 270.464139 -194.423194) (xy 270.512161 -194.383466) (xy 270.564785 -194.350071) (xy 270.621179 -194.323534)
			(xy 270.680454 -194.304274) (xy 270.741675 -194.292595) (xy 270.803878 -194.288682) (xy 270.866081 -194.292595)
			(xy 270.927302 -194.304274) (xy 270.986577 -194.323534) (xy 271.042971 -194.350071) (xy 271.095595 -194.383466)
			(xy 271.143617 -194.423194) (xy 271.186282 -194.468628) (xy 271.222916 -194.51905) (xy 271.252942 -194.573667)
			(xy 271.275885 -194.631615) (xy 271.291385 -194.691983) (xy 271.299197 -194.753817) (xy 271.299686 -194.78498)
			(xy 271.299187 -194.817701) (xy 271.290584 -194.882575) (xy 271.273524 -194.945755) (xy 271.248304 -195.006142)
			(xy 271.215362 -195.062689) (xy 271.17527 -195.114412) (xy 271.152366 -195.137786) (xy 271.145 -195.144898)
			(xy 271.137126 -195.163694) (xy 271.137126 -195.256404) (xy 271.145 -195.2752) (xy 271.152366 -195.282312)
			(xy 271.175288 -195.305667) (xy 271.215367 -195.3574) (xy 271.248299 -195.413952) (xy 271.27351 -195.474343)
			(xy 271.290564 -195.537523) (xy 271.299164 -195.602397) (xy 271.299686 -195.635118) (xy 271.299197 -195.666281)
			(xy 271.291385 -195.728115) (xy 271.275885 -195.788483) (xy 271.252942 -195.846431) (xy 271.222916 -195.901048)
			(xy 271.186282 -195.95147) (xy 271.143617 -195.996904) (xy 271.095595 -196.036632) (xy 271.042971 -196.070027)
			(xy 270.986577 -196.096564) (xy 270.927302 -196.115824) (xy 270.866081 -196.127503) (xy 270.803878 -196.131416)
			(xy 270.741675 -196.127503) (xy 270.680454 -196.115824) (xy 270.621179 -196.096564) (xy 270.564785 -196.070027)
			(xy 270.512161 -196.036632) (xy 270.464139 -195.996904) (xy 270.421474 -195.95147) (xy 270.38484 -195.901048)
			(xy 270.354814 -195.846431) (xy 270.331871 -195.788483) (xy 270.316371 -195.728115) (xy 270.308559 -195.666281)
			(xy 270.30807 -195.635118) (xy 268.949607 -195.635118) (xy 268.974757 -195.69615) (xy 268.991842 -195.76023)
			(xy 269.000455 -195.825987) (xy 269.000986 -195.859146) (xy 269.000497 -195.891272) (xy 268.992407 -195.955012)
			(xy 268.976348 -196.017224) (xy 268.952576 -196.076916) (xy 268.921472 -196.133137) (xy 268.88353 -196.184989)
			(xy 268.861794 -196.20865) (xy 268.851126 -196.219826) (xy 268.846046 -196.249544) (xy 268.888972 -196.349366)
			(xy 268.893306 -196.358291) (xy 268.907443 -196.372186) (xy 268.925796 -196.379673) (xy 268.935708 -196.3801)
			(xy 269.274036 -196.3801) (xy 269.299944 -196.362574) (xy 269.305786 -196.348096) (xy 269.316445 -196.322797)
			(xy 269.344159 -196.275409) (xy 269.378591 -196.232653) (xy 269.418982 -196.195474) (xy 269.464438 -196.164694)
			(xy 269.513956 -196.140994) (xy 269.566439 -196.124896) (xy 269.62073 -196.116757) (xy 269.675626 -196.116757)
			(xy 269.729917 -196.124896) (xy 269.7824 -196.140994) (xy 269.831918 -196.164694) (xy 269.877374 -196.195474)
			(xy 269.917765 -196.232653) (xy 269.952197 -196.275409) (xy 269.979911 -196.322797) (xy 269.99057 -196.348096)
			(xy 269.996412 -196.362574) (xy 270.02232 -196.3801) (xy 275.593302 -196.3801) (xy 275.603199 -196.37962)
			(xy 275.621518 -196.372115) (xy 275.635653 -196.358254) (xy 275.640038 -196.349366) (xy 275.682964 -196.249544)
			(xy 275.677884 -196.219826) (xy 275.667216 -196.20865) (xy 275.645492 -196.184979) (xy 275.607558 -196.133123)
			(xy 275.576456 -196.076903) (xy 275.552681 -196.017214) (xy 275.536611 -195.955007) (xy 275.528502 -195.891271)
			(xy 275.528024 -195.859146) (xy 275.528562 -195.825989) (xy 275.537185 -195.760237) (xy 275.554277 -195.696164)
			(xy 275.57955 -195.634854) (xy 275.612574 -195.577347) (xy 275.652789 -195.524618) (xy 275.699515 -195.477562)
			(xy 275.725382 -195.45681) (xy 275.734241 -195.449224) (xy 275.744542 -195.428325) (xy 275.745194 -195.416678)
			(xy 275.745194 -195.336414) (xy 275.744623 -195.324749) (xy 275.734292 -195.303834) (xy 275.725382 -195.296282)
			(xy 275.69949 -195.275562) (xy 275.652771 -195.228498) (xy 275.612563 -195.175763) (xy 275.579548 -195.11825)
			(xy 275.554286 -195.056935) (xy 275.537205 -194.992858) (xy 275.528595 -194.927104) (xy 275.528024 -194.893946)
			(xy 275.528573 -194.86017) (xy 275.537509 -194.79321) (xy 275.555228 -194.728023) (xy 275.58142 -194.665755)
			(xy 275.615623 -194.607501) (xy 275.657236 -194.554287) (xy 275.705526 -194.507049) (xy 275.759643 -194.466618)
			(xy 275.788882 -194.4497) (xy 275.800058 -194.443604) (xy 275.813774 -194.422522) (xy 275.823172 -194.313556)
			(xy 275.81352 -194.290188) (xy 275.803614 -194.282314) (xy 275.782764 -194.264703) (xy 275.745984 -194.224382)
			(xy 275.715549 -194.179081) (xy 275.692125 -194.129787) (xy 275.676223 -194.07758) (xy 275.668191 -194.023598)
			(xy 275.667724 -193.99631) (xy 275.66824 -193.96871) (xy 275.676467 -193.914127) (xy 275.692737 -193.86138)
			(xy 275.716687 -193.811648) (xy 275.747782 -193.76604) (xy 275.785327 -193.725576) (xy 275.828484 -193.691159)
			(xy 275.876288 -193.66356) (xy 275.927672 -193.643393) (xy 275.981487 -193.63111) (xy 276.036532 -193.626985)
			(xy 276.091577 -193.63111) (xy 276.145392 -193.643393) (xy 276.196776 -193.66356) (xy 276.24458 -193.691159)
			(xy 276.287737 -193.725576) (xy 276.325282 -193.76604) (xy 276.356377 -193.811648) (xy 276.380327 -193.86138)
			(xy 276.396597 -193.914127) (xy 276.404824 -193.96871) (xy 276.40534 -193.99631) (xy 276.404848 -194.023597)
			(xy 276.396809 -194.077575) (xy 276.380909 -194.129781) (xy 276.357494 -194.179077) (xy 276.327074 -194.224386)
			(xy 276.290313 -194.264721) (xy 276.26945 -194.282314) (xy 276.259544 -194.290188) (xy 276.249892 -194.313556)
			(xy 276.25929 -194.422522) (xy 276.273006 -194.443604) (xy 276.284182 -194.4497) (xy 276.313404 -194.466642)
			(xy 276.367512 -194.507077) (xy 276.415794 -194.554316) (xy 276.457402 -194.607528) (xy 276.491603 -194.665777)
			(xy 276.517796 -194.728039) (xy 276.53552 -194.79322) (xy 276.544465 -194.860172) (xy 276.54504 -194.893946)
			(xy 276.544503 -194.927104) (xy 276.535881 -194.992857) (xy 276.518791 -195.056933) (xy 276.493522 -195.118246)
			(xy 276.460501 -195.175756) (xy 276.420289 -195.228489) (xy 276.373566 -195.275552) (xy 276.347682 -195.296282)
			(xy 276.338813 -195.303863) (xy 276.328495 -195.324763) (xy 276.32787 -195.336414) (xy 276.32787 -195.416678)
			(xy 276.328439 -195.428345) (xy 276.338763 -195.449268) (xy 276.347682 -195.45681) (xy 276.373576 -195.477529)
			(xy 276.420299 -195.524591) (xy 276.460511 -195.577325) (xy 276.493529 -195.634838) (xy 276.493644 -195.635118)
			(xy 277.852124 -195.635118) (xy 277.852619 -195.602397) (xy 277.861222 -195.537522) (xy 277.878283 -195.474343)
			(xy 277.903503 -195.413955) (xy 277.936446 -195.357409) (xy 277.976539 -195.305686) (xy 277.999444 -195.282312)
			(xy 278.00681 -195.2752) (xy 278.014684 -195.256404) (xy 278.014684 -195.163694) (xy 278.00681 -195.144898)
			(xy 277.999444 -195.137786) (xy 277.976523 -195.11443) (xy 277.936443 -195.062698) (xy 277.903512 -195.006146)
			(xy 277.8783 -194.945755) (xy 277.861246 -194.882575) (xy 277.852646 -194.817701) (xy 277.852124 -194.78498)
			(xy 277.852613 -194.753817) (xy 277.860425 -194.691983) (xy 277.875925 -194.631615) (xy 277.898868 -194.573667)
			(xy 277.928894 -194.51905) (xy 277.965528 -194.468628) (xy 278.008193 -194.423194) (xy 278.056215 -194.383466)
			(xy 278.108839 -194.350071) (xy 278.165233 -194.323534) (xy 278.224508 -194.304274) (xy 278.285729 -194.292595)
			(xy 278.347932 -194.288682) (xy 278.410135 -194.292595) (xy 278.471356 -194.304274) (xy 278.530631 -194.323534)
			(xy 278.587025 -194.350071) (xy 278.639649 -194.383466) (xy 278.687671 -194.423194) (xy 278.730336 -194.468628)
			(xy 278.76697 -194.51905) (xy 278.796996 -194.573667) (xy 278.819939 -194.631615) (xy 278.835439 -194.691983)
			(xy 278.843251 -194.753817) (xy 278.84374 -194.78498) (xy 278.843255 -194.817702) (xy 278.834651 -194.882577)
			(xy 278.817589 -194.945757) (xy 278.792367 -195.006145) (xy 278.759422 -195.062691) (xy 278.719326 -195.114413)
			(xy 278.69642 -195.137786) (xy 278.689054 -195.144898) (xy 278.68118 -195.163694) (xy 278.68118 -195.256404)
			(xy 278.689054 -195.2752) (xy 278.69642 -195.282312) (xy 278.719333 -195.305676) (xy 278.759415 -195.357406)
			(xy 278.792348 -195.413956) (xy 278.817561 -195.474345) (xy 278.834616 -195.537524) (xy 278.843217 -195.602397)
			(xy 278.84374 -195.635118) (xy 278.843251 -195.666281) (xy 278.835439 -195.728115) (xy 278.819939 -195.788483)
			(xy 278.796996 -195.846431) (xy 278.76697 -195.901048) (xy 278.730336 -195.95147) (xy 278.687671 -195.996904)
			(xy 278.639649 -196.036632) (xy 278.587025 -196.070027) (xy 278.530631 -196.096564) (xy 278.471356 -196.115824)
			(xy 278.410135 -196.127503) (xy 278.347932 -196.131416) (xy 278.285729 -196.127503) (xy 278.224508 -196.115824)
			(xy 278.165233 -196.096564) (xy 278.108839 -196.070027) (xy 278.056215 -196.036632) (xy 278.008193 -195.996904)
			(xy 277.965528 -195.95147) (xy 277.928894 -195.901048) (xy 277.898868 -195.846431) (xy 277.875925 -195.788483)
			(xy 277.860425 -195.728115) (xy 277.852613 -195.666281) (xy 277.852124 -195.635118) (xy 276.493644 -195.635118)
			(xy 276.518794 -195.696154) (xy 276.535877 -195.760232) (xy 276.544488 -195.825988) (xy 276.54504 -195.859146)
			(xy 276.544551 -195.891271) (xy 276.53646 -195.955011) (xy 276.5204 -196.017222) (xy 276.496627 -196.076913)
			(xy 276.46552 -196.133132) (xy 276.427576 -196.184982) (xy 276.405848 -196.20865) (xy 276.39518 -196.219826)
			(xy 276.3901 -196.249544) (xy 276.433026 -196.349366) (xy 276.437363 -196.358285) (xy 276.451502 -196.372165)
			(xy 276.469854 -196.379633) (xy 276.479762 -196.3801) (xy 276.81809 -196.3801) (xy 276.843998 -196.362574)
			(xy 276.84984 -196.348096) (xy 276.860499 -196.322797) (xy 276.888213 -196.275409) (xy 276.922645 -196.232653)
			(xy 276.963036 -196.195474) (xy 277.008492 -196.164694) (xy 277.05801 -196.140994) (xy 277.110493 -196.124896)
			(xy 277.164784 -196.116757) (xy 277.21968 -196.116757) (xy 277.273971 -196.124896) (xy 277.326454 -196.140994)
			(xy 277.375972 -196.164694) (xy 277.421428 -196.195474) (xy 277.461819 -196.232653) (xy 277.496251 -196.275409)
			(xy 277.523965 -196.322797) (xy 277.534624 -196.348096) (xy 277.540466 -196.362574) (xy 277.566374 -196.3801)
			(xy 283.137356 -196.3801) (xy 283.147258 -196.379628) (xy 283.165591 -196.372133) (xy 283.17974 -196.358273)
			(xy 283.184092 -196.349366) (xy 283.227018 -196.249544) (xy 283.221938 -196.219826) (xy 283.21127 -196.20865)
			(xy 283.189547 -196.184978) (xy 283.151617 -196.133121) (xy 283.120518 -196.076901) (xy 283.096745 -196.017212)
			(xy 283.080677 -195.955005) (xy 283.072569 -195.89127) (xy 283.072078 -195.859146) (xy 283.072616 -195.825988)
			(xy 283.081238 -195.760236) (xy 283.09833 -195.696161) (xy 283.123601 -195.63485) (xy 283.156623 -195.577341)
			(xy 283.196836 -195.52461) (xy 283.243559 -195.47755) (xy 283.269436 -195.45681) (xy 283.278301 -195.449227)
			(xy 283.288612 -195.428327) (xy 283.289248 -195.416678) (xy 283.289248 -195.336414) (xy 283.288679 -195.324747)
			(xy 283.278355 -195.303824) (xy 283.269436 -195.296282) (xy 283.243542 -195.275564) (xy 283.196818 -195.228502)
			(xy 283.156605 -195.175768) (xy 283.123587 -195.118255) (xy 283.098322 -195.056939) (xy 283.081239 -194.99286)
			(xy 283.072629 -194.927105) (xy 283.072078 -194.893946) (xy 283.072627 -194.86017) (xy 283.081563 -194.793212)
			(xy 283.099284 -194.728027) (xy 283.125477 -194.66576) (xy 283.159682 -194.607509) (xy 283.201297 -194.554299)
			(xy 283.24959 -194.507065) (xy 283.30371 -194.466639) (xy 283.332936 -194.4497) (xy 283.344112 -194.443604)
			(xy 283.357828 -194.422522) (xy 283.367226 -194.313556) (xy 283.357574 -194.290188) (xy 283.347668 -194.282314)
			(xy 283.326815 -194.264704) (xy 283.29003 -194.224386) (xy 283.259591 -194.179085) (xy 283.236163 -194.129791)
			(xy 283.220259 -194.077582) (xy 283.212225 -194.023599) (xy 283.211778 -193.99631) (xy 283.212294 -193.96871)
			(xy 283.220521 -193.914127) (xy 283.236791 -193.86138) (xy 283.260741 -193.811648) (xy 283.291836 -193.76604)
			(xy 283.329381 -193.725576) (xy 283.372538 -193.691159) (xy 283.420342 -193.66356) (xy 283.471726 -193.643393)
			(xy 283.525541 -193.63111) (xy 283.580586 -193.626985) (xy 283.635631 -193.63111) (xy 283.689446 -193.643393)
			(xy 283.74083 -193.66356) (xy 283.788634 -193.691159) (xy 283.831791 -193.725576) (xy 283.869336 -193.76604)
			(xy 283.900431 -193.811648) (xy 283.924381 -193.86138) (xy 283.940651 -193.914127) (xy 283.948878 -193.96871)
			(xy 283.949394 -193.99631) (xy 283.948902 -194.023596) (xy 283.940863 -194.077574) (xy 283.924961 -194.129779)
			(xy 283.901544 -194.179072) (xy 283.871121 -194.224379) (xy 283.834358 -194.26471) (xy 283.813504 -194.282314)
			(xy 283.803598 -194.290188) (xy 283.793946 -194.313556) (xy 283.803344 -194.422522) (xy 283.81706 -194.443604)
			(xy 283.828236 -194.4497) (xy 283.857461 -194.46664) (xy 283.911573 -194.507073) (xy 283.959859 -194.55431)
			(xy 284.001471 -194.607521) (xy 284.035675 -194.665771) (xy 284.06187 -194.728034) (xy 284.079597 -194.793217)
			(xy 284.088542 -194.860171) (xy 284.089094 -194.893946) (xy 284.088557 -194.927104) (xy 284.079935 -194.992856)
			(xy 284.062843 -195.056931) (xy 284.037572 -195.118242) (xy 284.00455 -195.17575) (xy 283.964335 -195.228481)
			(xy 283.917611 -195.27554) (xy 283.891736 -195.296282) (xy 283.882873 -195.303867) (xy 283.872565 -195.324766)
			(xy 283.871924 -195.336414) (xy 283.871924 -195.416678) (xy 283.872491 -195.428347) (xy 283.882809 -195.449277)
			(xy 283.891736 -195.45681) (xy 283.917632 -195.477528) (xy 283.964359 -195.524588) (xy 284.004574 -195.577322)
			(xy 284.037595 -195.634834) (xy 284.037712 -195.635118) (xy 285.395924 -195.635118) (xy 285.396419 -195.602397)
			(xy 285.405022 -195.537522) (xy 285.422083 -195.474343) (xy 285.447303 -195.413955) (xy 285.480246 -195.357409)
			(xy 285.520339 -195.305686) (xy 285.543244 -195.282312) (xy 285.55061 -195.2752) (xy 285.558484 -195.256404)
			(xy 285.558484 -195.163694) (xy 285.55061 -195.144898) (xy 285.543244 -195.137786) (xy 285.520323 -195.11443)
			(xy 285.480243 -195.062698) (xy 285.447312 -195.006146) (xy 285.4221 -194.945755) (xy 285.405046 -194.882575)
			(xy 285.396446 -194.817701) (xy 285.395924 -194.78498) (xy 285.396413 -194.753817) (xy 285.404225 -194.691983)
			(xy 285.419725 -194.631615) (xy 285.442668 -194.573667) (xy 285.472694 -194.51905) (xy 285.509328 -194.468628)
			(xy 285.551993 -194.423194) (xy 285.600015 -194.383466) (xy 285.652639 -194.350071) (xy 285.709033 -194.323534)
			(xy 285.768308 -194.304274) (xy 285.829529 -194.292595) (xy 285.891732 -194.288682) (xy 285.953935 -194.292595)
			(xy 286.015156 -194.304274) (xy 286.074431 -194.323534) (xy 286.130825 -194.350071) (xy 286.183449 -194.383466)
			(xy 286.231471 -194.423194) (xy 286.274136 -194.468628) (xy 286.31077 -194.51905) (xy 286.340796 -194.573667)
			(xy 286.363739 -194.631615) (xy 286.379239 -194.691983) (xy 286.387051 -194.753817) (xy 286.38754 -194.78498)
			(xy 286.387055 -194.817702) (xy 286.378451 -194.882577) (xy 286.361389 -194.945757) (xy 286.336167 -195.006145)
			(xy 286.303222 -195.062691) (xy 286.263126 -195.114413) (xy 286.24022 -195.137786) (xy 286.232854 -195.144898)
			(xy 286.22498 -195.163694) (xy 286.22498 -195.256404) (xy 286.232854 -195.2752) (xy 286.24022 -195.282312)
			(xy 286.263133 -195.305676) (xy 286.303215 -195.357406) (xy 286.336148 -195.413956) (xy 286.361361 -195.474345)
			(xy 286.378416 -195.537524) (xy 286.387017 -195.602397) (xy 286.38754 -195.635118) (xy 286.387051 -195.666281)
			(xy 286.379239 -195.728115) (xy 286.363739 -195.788483) (xy 286.340796 -195.846431) (xy 286.31077 -195.901048)
			(xy 286.274136 -195.95147) (xy 286.231471 -195.996904) (xy 286.183449 -196.036632) (xy 286.130825 -196.070027)
			(xy 286.074431 -196.096564) (xy 286.015156 -196.115824) (xy 285.953935 -196.127503) (xy 285.891732 -196.131416)
			(xy 285.829529 -196.127503) (xy 285.768308 -196.115824) (xy 285.709033 -196.096564) (xy 285.652639 -196.070027)
			(xy 285.600015 -196.036632) (xy 285.551993 -195.996904) (xy 285.509328 -195.95147) (xy 285.472694 -195.901048)
			(xy 285.442668 -195.846431) (xy 285.419725 -195.788483) (xy 285.404225 -195.728115) (xy 285.396413 -195.666281)
			(xy 285.395924 -195.635118) (xy 284.037712 -195.635118) (xy 284.062863 -195.69615) (xy 284.079947 -195.76023)
			(xy 284.08856 -195.825987) (xy 284.089094 -195.859146) (xy 284.088605 -195.891272) (xy 284.080515 -195.955012)
			(xy 284.064456 -196.017224) (xy 284.040685 -196.076917) (xy 284.009581 -196.133138) (xy 283.971639 -196.18499)
			(xy 283.949902 -196.20865) (xy 283.939234 -196.219826) (xy 283.934154 -196.249544) (xy 283.97708 -196.349366)
			(xy 283.981415 -196.358291) (xy 283.995551 -196.372183) (xy 284.013905 -196.379667) (xy 284.023816 -196.3801)
			(xy 284.36189 -196.3801) (xy 284.387798 -196.362574) (xy 284.39364 -196.348096) (xy 284.404299 -196.322797)
			(xy 284.432013 -196.275409) (xy 284.466445 -196.232653) (xy 284.506836 -196.195474) (xy 284.552292 -196.164694)
			(xy 284.60181 -196.140994) (xy 284.654293 -196.124896) (xy 284.708584 -196.116757) (xy 284.76348 -196.116757)
			(xy 284.817771 -196.124896) (xy 284.870254 -196.140994) (xy 284.919772 -196.164694) (xy 284.965228 -196.195474)
			(xy 285.005619 -196.232653) (xy 285.040051 -196.275409) (xy 285.067765 -196.322797) (xy 285.078424 -196.348096)
			(xy 285.084266 -196.362574) (xy 285.110174 -196.3801) (xy 289.736784 -196.3801) (xy 289.745302 -196.379783)
			(xy 289.7614 -196.374209) (xy 289.76828 -196.369178) (xy 289.793864 -196.349725) (xy 289.848563 -196.315976)
			(xy 289.906656 -196.288475) (xy 289.967431 -196.267559) (xy 290.030145 -196.253486) (xy 290.094029 -196.246426)
			(xy 290.126166 -196.245988) (xy 290.356544 -196.245988) (xy 290.388682 -196.246405) (xy 290.452566 -196.253474)
			(xy 290.51528 -196.267552) (xy 290.576056 -196.288468) (xy 290.634152 -196.315967) (xy 290.688856 -196.349712)
			(xy 290.71443 -196.369178) (xy 290.721288 -196.374512) (xy 290.73729 -196.3801) (xy 290.821618 -196.3801)
			(xy 290.831623 -196.379609) (xy 290.850109 -196.371946) (xy 290.864256 -196.357794) (xy 290.871912 -196.339305)
			(xy 290.872418 -196.3293) (xy 290.872418 -196.316346) (xy 290.860226 -196.29374) (xy 290.849304 -196.286628)
			(xy 290.82288 -196.269026) (xy 290.774199 -196.228266) (xy 290.730971 -196.181764) (xy 290.693868 -196.130242)
			(xy 290.663466 -196.074502) (xy 290.64024 -196.015411) (xy 290.62455 -195.953889) (xy 290.616641 -195.890892)
			(xy 290.616132 -195.859146) (xy 290.61667 -195.825989) (xy 290.625293 -195.760238) (xy 290.642386 -195.696164)
			(xy 290.667658 -195.634854) (xy 290.700683 -195.577348) (xy 290.740899 -195.52462) (xy 290.787625 -195.477564)
			(xy 290.81349 -195.45681) (xy 290.822348 -195.449223) (xy 290.832647 -195.428324) (xy 290.833302 -195.416678)
			(xy 290.833302 -195.336414) (xy 290.832731 -195.324749) (xy 290.822401 -195.303832) (xy 290.81349 -195.296282)
			(xy 290.787598 -195.275562) (xy 290.740877 -195.228499) (xy 290.700669 -195.175764) (xy 290.667654 -195.118251)
			(xy 290.642391 -195.056936) (xy 290.62531 -194.992858) (xy 290.6167 -194.927104) (xy 290.616132 -194.893946)
			(xy 290.616681 -194.86017) (xy 290.625617 -194.793211) (xy 290.643336 -194.728024) (xy 290.669528 -194.665756)
			(xy 290.703732 -194.607502) (xy 290.745345 -194.554288) (xy 290.793635 -194.507051) (xy 290.847753 -194.466621)
			(xy 290.87699 -194.4497) (xy 290.888166 -194.443604) (xy 290.901882 -194.422522) (xy 290.91128 -194.313556)
			(xy 290.901628 -194.290188) (xy 290.891722 -194.282314) (xy 290.870872 -194.264703) (xy 290.834091 -194.224383)
			(xy 290.803655 -194.179081) (xy 290.78023 -194.129788) (xy 290.764328 -194.07758) (xy 290.756296 -194.023598)
			(xy 290.755832 -193.99631) (xy 290.756348 -193.96871) (xy 290.764575 -193.914127) (xy 290.780845 -193.86138)
			(xy 290.804795 -193.811648) (xy 290.83589 -193.76604) (xy 290.873435 -193.725576) (xy 290.916592 -193.691159)
			(xy 290.964396 -193.66356) (xy 291.01578 -193.643393) (xy 291.069595 -193.63111) (xy 291.12464 -193.626985)
			(xy 291.179685 -193.63111) (xy 291.2335 -193.643393) (xy 291.284884 -193.66356) (xy 291.332688 -193.691159)
			(xy 291.375845 -193.725576) (xy 291.41339 -193.76604) (xy 291.444485 -193.811648) (xy 291.468435 -193.86138)
			(xy 291.484705 -193.914127) (xy 291.492932 -193.96871) (xy 291.493448 -193.99631) (xy 291.492956 -194.023597)
			(xy 291.484918 -194.077576) (xy 291.469018 -194.129782) (xy 291.445603 -194.179077) (xy 291.415183 -194.224387)
			(xy 291.378423 -194.264723) (xy 291.357558 -194.282314) (xy 291.347652 -194.290188) (xy 291.338 -194.313556)
			(xy 291.347398 -194.422522) (xy 291.361114 -194.443604) (xy 291.37229 -194.4497) (xy 291.401512 -194.466642)
			(xy 291.455619 -194.507078) (xy 291.503901 -194.554317) (xy 291.545507 -194.607529) (xy 291.579707 -194.665778)
			(xy 291.6059 -194.72804) (xy 291.623624 -194.79322) (xy 291.632569 -194.860172) (xy 291.633148 -194.893946)
			(xy 291.632611 -194.927104) (xy 291.62399 -194.992857) (xy 291.6069 -195.056934) (xy 291.58163 -195.118247)
			(xy 291.54861 -195.175757) (xy 291.508398 -195.228491) (xy 291.461676 -195.275554) (xy 291.43579 -195.296282)
			(xy 291.426934 -195.30387) (xy 291.416635 -195.324768) (xy 291.415978 -195.336414) (xy 291.415978 -195.416678)
			(xy 291.416547 -195.428345) (xy 291.426872 -195.449267) (xy 291.43579 -195.45681) (xy 291.461684 -195.477529)
			(xy 291.508406 -195.524591) (xy 291.548617 -195.577326) (xy 291.581635 -195.634839) (xy 291.606899 -195.696154)
			(xy 291.623982 -195.760233) (xy 291.632593 -195.825988) (xy 291.633148 -195.859146) (xy 291.632659 -195.891272)
			(xy 291.624568 -195.955011) (xy 291.608508 -196.017222) (xy 291.584735 -196.076914) (xy 291.553629 -196.133133)
			(xy 291.515685 -196.184983) (xy 291.493956 -196.20865) (xy 291.483288 -196.219826) (xy 291.478208 -196.249544)
			(xy 291.521134 -196.349366) (xy 291.525471 -196.358285) (xy 291.539611 -196.372162) (xy 291.557962 -196.379627)
			(xy 291.56787 -196.3801) (xy 291.905944 -196.3801) (xy 291.931852 -196.362574) (xy 291.937694 -196.348096)
			(xy 291.948356 -196.322798) (xy 291.976074 -196.275411) (xy 292.010508 -196.232655) (xy 292.050898 -196.195475)
			(xy 292.096352 -196.164691) (xy 292.145867 -196.140983) (xy 292.198348 -196.124874) (xy 292.252637 -196.116722)
			(xy 292.280086 -196.116194) (xy 292.308117 -196.116724) (xy 292.363531 -196.125224) (xy 292.41702 -196.142015)
			(xy 292.46735 -196.166711) (xy 292.513361 -196.198741) (xy 292.553993 -196.237368) (xy 292.588309 -196.2817)
			(xy 292.602412 -196.305932) (xy 292.607585 -196.314339) (xy 292.62294 -196.326715) (xy 292.641833 -196.332372)
			(xy 292.651688 -196.33184) (xy 292.664992 -196.330664) (xy 292.691673 -196.329394) (xy 292.705028 -196.3293)
			(xy 293.159942 -196.3293) (xy 293.168532 -196.32901) (xy 293.184771 -196.32341) (xy 293.198244 -196.312755)
			(xy 293.203122 -196.305678) (xy 293.220905 -196.278059) (xy 293.261768 -196.226624) (xy 293.284656 -196.203062)
			(xy 293.298372 -196.189346) (xy 293.305062 -196.181934) (xy 293.31267 -196.163496) (xy 293.312679 -196.143549)
			(xy 293.305087 -196.125105) (xy 293.298372 -196.117718) (xy 293.28999 -196.109082) (xy 293.27856 -196.105272)
			(xy 293.249363 -196.095002) (xy 293.193568 -196.068212) (xy 293.14154 -196.034688) (xy 293.094089 -195.994949)
			(xy 293.051952 -195.949614) (xy 293.015784 -195.899387) (xy 292.986148 -195.84505) (xy 292.963504 -195.787448)
			(xy 292.948205 -195.727475) (xy 292.940488 -195.666065) (xy 292.939978 -195.635118) (xy 292.940497 -195.602185)
			(xy 292.949182 -195.536896) (xy 292.966443 -195.473333) (xy 292.991973 -195.412617) (xy 293.025323 -195.35582)
			(xy 293.065905 -195.303943) (xy 293.089076 -195.280534) (xy 293.096442 -195.273422) (xy 293.10457 -195.254372)
			(xy 293.104062 -195.1609) (xy 293.096188 -195.14185) (xy 293.088568 -195.134738) (xy 293.064431 -195.110699)
			(xy 293.022154 -195.057283) (xy 292.987391 -194.998699) (xy 292.960764 -194.935997) (xy 292.942752 -194.8703)
			(xy 292.933676 -194.802785) (xy 292.93312 -194.768724) (xy 292.933622 -194.736763) (xy 292.941633 -194.673345)
			(xy 292.95753 -194.611431) (xy 292.981062 -194.551998) (xy 293.011856 -194.495983) (xy 293.049429 -194.444268)
			(xy 293.093186 -194.397671) (xy 293.142439 -194.356926) (xy 293.19641 -194.322675) (xy 293.254249 -194.295458)
			(xy 293.315042 -194.275705) (xy 293.377832 -194.263727) (xy 293.441628 -194.259714) (xy 293.505424 -194.263727)
			(xy 293.568214 -194.275705) (xy 293.629007 -194.295458) (xy 293.686846 -194.322675) (xy 293.740817 -194.356926)
			(xy 293.79007 -194.397671) (xy 293.833827 -194.444268) (xy 293.8714 -194.495983) (xy 293.902194 -194.551998)
			(xy 293.925726 -194.611431) (xy 293.941623 -194.673345) (xy 293.949634 -194.736763) (xy 293.950136 -194.768724)
			(xy 293.949716 -194.798416) (xy 293.942799 -194.857396) (xy 293.929062 -194.91517) (xy 293.908693 -194.970951)
			(xy 293.881967 -195.023981) (xy 293.849249 -195.07354) (xy 293.810983 -195.118951) (xy 293.789608 -195.139564)
			(xy 293.781988 -195.146676) (xy 293.77386 -195.165472) (xy 293.772082 -195.258944) (xy 293.779956 -195.277994)
			(xy 293.787068 -195.28536) (xy 293.809541 -195.308662) (xy 293.848872 -195.360084) (xy 293.881174 -195.416189)
			(xy 293.905896 -195.476021) (xy 293.922619 -195.538562) (xy 293.931058 -195.602749) (xy 293.931594 -195.635118)
			(xy 293.931199 -195.662981) (xy 293.92496 -195.718356) (xy 293.919148 -195.745608) (xy 293.916608 -195.757292)
			(xy 293.921688 -195.77939) (xy 293.97833 -195.850764) (xy 293.985907 -195.859481) (xy 294.006671 -195.869544)
			(xy 294.018208 -195.870068) (xy 294.08882 -195.870068) (xy 294.121407 -195.870515) (xy 294.186173 -195.877792)
			(xy 294.249718 -195.892274) (xy 294.311241 -195.91378) (xy 294.369969 -195.942039) (xy 294.425165 -195.976696)
			(xy 294.476133 -196.017315) (xy 294.499538 -196.039994) (xy 294.662606 -196.203062) (xy 294.685488 -196.226629)
			(xy 294.726356 -196.27806) (xy 294.74414 -196.305678) (xy 294.749015 -196.31276) (xy 294.762487 -196.323427)
			(xy 294.778727 -196.329038) (xy 294.78732 -196.3293) (xy 296.190924 -196.3293) (xy 296.219118 -196.305424)
			(xy 296.222166 -196.286628) (xy 296.2285 -196.250864) (xy 296.248915 -196.181161) (xy 296.277868 -196.114549)
			(xy 296.314905 -196.05207) (xy 296.359447 -195.9947) (xy 296.384726 -195.96862) (xy 296.547794 -195.805552)
			(xy 296.571148 -195.782807) (xy 296.622108 -195.742148) (xy 296.677303 -195.707453) (xy 296.736037 -195.679161)
			(xy 296.797572 -195.657628) (xy 296.861131 -195.643124) (xy 296.925915 -195.635833) (xy 296.958512 -195.635372)
			(xy 297.18889 -195.635372) (xy 297.224729 -195.635922) (xy 297.295858 -195.644777) (xy 297.365356 -195.662318)
			(xy 297.432169 -195.688277) (xy 297.495279 -195.72226) (xy 297.553728 -195.763751) (xy 297.580558 -195.787518)
			(xy 297.587788 -195.793598) (xy 297.605407 -195.800369) (xy 297.614848 -195.800726) (xy 297.645582 -195.800726)
			(xy 297.655007 -195.800293) (xy 297.672601 -195.793529) (xy 297.679872 -195.787518) (xy 297.706684 -195.76373)
			(xy 297.765139 -195.722247) (xy 297.828254 -195.688271) (xy 297.89507 -195.662318) (xy 297.964571 -195.644783)
			(xy 298.035701 -195.635933) (xy 298.07154 -195.635372) (xy 298.181014 -195.635372) (xy 298.190008 -195.635054)
			(xy 298.206916 -195.628921) (xy 298.220676 -195.617339) (xy 298.225464 -195.609718) (xy 298.242533 -195.580438)
			(xy 298.283262 -195.526267) (xy 298.330838 -195.477998) (xy 298.35729 -195.45681) (xy 298.366148 -195.449223)
			(xy 298.376447 -195.428324) (xy 298.377102 -195.416678) (xy 298.377102 -195.336414) (xy 298.376531 -195.324749)
			(xy 298.366201 -195.303832) (xy 298.35729 -195.296282) (xy 298.331398 -195.275562) (xy 298.284677 -195.228499)
			(xy 298.244469 -195.175764) (xy 298.211454 -195.118251) (xy 298.186191 -195.056936) (xy 298.16911 -194.992858)
			(xy 298.1605 -194.927104) (xy 298.159932 -194.893946) (xy 298.160481 -194.86017) (xy 298.169417 -194.793211)
			(xy 298.187136 -194.728024) (xy 298.213328 -194.665756) (xy 298.247532 -194.607502) (xy 298.289145 -194.554288)
			(xy 298.337435 -194.507051) (xy 298.391553 -194.466621) (xy 298.42079 -194.4497) (xy 298.431966 -194.443604)
			(xy 298.445682 -194.422522) (xy 298.45508 -194.313556) (xy 298.445428 -194.290188) (xy 298.435522 -194.282314)
			(xy 298.414672 -194.264703) (xy 298.377891 -194.224383) (xy 298.347455 -194.179081) (xy 298.32403 -194.129788)
			(xy 298.308128 -194.07758) (xy 298.300096 -194.023598) (xy 298.299632 -193.99631) (xy 298.300148 -193.96871)
			(xy 298.308375 -193.914127) (xy 298.324645 -193.86138) (xy 298.348595 -193.811648) (xy 298.37969 -193.76604)
			(xy 298.417235 -193.725576) (xy 298.460392 -193.691159) (xy 298.508196 -193.66356) (xy 298.55958 -193.643393)
			(xy 298.613395 -193.63111) (xy 298.66844 -193.626985) (xy 298.723485 -193.63111) (xy 298.7773 -193.643393)
			(xy 298.828684 -193.66356) (xy 298.876488 -193.691159) (xy 298.919645 -193.725576) (xy 298.95719 -193.76604)
			(xy 298.988285 -193.811648) (xy 299.012235 -193.86138) (xy 299.028505 -193.914127) (xy 299.036732 -193.96871)
			(xy 299.037248 -193.99631) (xy 299.036756 -194.023597) (xy 299.028718 -194.077576) (xy 299.012818 -194.129782)
			(xy 298.989403 -194.179077) (xy 298.958983 -194.224387) (xy 298.922223 -194.264723) (xy 298.901358 -194.282314)
			(xy 298.891452 -194.290188) (xy 298.8818 -194.313556) (xy 298.891198 -194.422522) (xy 298.904914 -194.443604)
			(xy 298.91609 -194.4497) (xy 298.945312 -194.466642) (xy 298.999419 -194.507078) (xy 299.047701 -194.554317)
			(xy 299.089307 -194.607529) (xy 299.123507 -194.665778) (xy 299.1497 -194.72804) (xy 299.167424 -194.79322)
			(xy 299.176369 -194.860172) (xy 299.176948 -194.893946) (xy 299.176411 -194.927104) (xy 299.16779 -194.992857)
			(xy 299.1507 -195.056934) (xy 299.12543 -195.118247) (xy 299.09241 -195.175757) (xy 299.052198 -195.228491)
			(xy 299.005476 -195.275554) (xy 298.97959 -195.296282) (xy 298.970734 -195.30387) (xy 298.960435 -195.324768)
			(xy 298.959778 -195.336414) (xy 298.959778 -195.416678) (xy 298.960347 -195.428345) (xy 298.970672 -195.449267)
			(xy 298.97959 -195.45681) (xy 299.005484 -195.477529) (xy 299.052206 -195.524591) (xy 299.092417 -195.577326)
			(xy 299.125435 -195.634839) (xy 299.150699 -195.696154) (xy 299.167782 -195.760233) (xy 299.176393 -195.825988)
			(xy 299.176948 -195.859146) (xy 299.17648 -195.89063) (xy 299.168716 -195.953117) (xy 299.153299 -196.014169)
			(xy 299.130466 -196.072851) (xy 299.100565 -196.128267) (xy 299.064054 -196.179569) (xy 299.04309 -196.203062)
			(xy 299.035115 -196.212582) (xy 299.02873 -196.236553) (xy 299.030898 -196.248782) (xy 299.038264 -196.286628)
			(xy 299.041312 -196.305424) (xy 299.069506 -196.3293) (xy 299.458888 -196.3293) (xy 299.467837 -196.328942)
			(xy 299.484643 -196.322779) (xy 299.498319 -196.311231) (xy 299.503084 -196.303646) (xy 299.517211 -196.279639)
			(xy 299.551564 -196.235795) (xy 299.592124 -196.197618) (xy 299.637965 -196.165978) (xy 299.688045 -196.141596)
			(xy 299.741224 -196.125026) (xy 299.79629 -196.116645) (xy 299.85199 -196.116645) (xy 299.907056 -196.125026)
			(xy 299.960235 -196.141596) (xy 300.010315 -196.165978) (xy 300.056156 -196.197618) (xy 300.096716 -196.235795)
			(xy 300.131069 -196.279639) (xy 300.145196 -196.303646) (xy 300.149925 -196.311263) (xy 300.163603 -196.322837)
			(xy 300.180433 -196.328985) (xy 300.189392 -196.3293) (xy 303.640744 -196.3293) (xy 303.650777 -196.32892)
			(xy 303.66933 -196.321285) (xy 303.68351 -196.307093) (xy 303.691128 -196.288534) (xy 303.691544 -196.2785)
			(xy 303.691544 -196.232018) (xy 303.691983 -196.199421) (xy 303.699282 -196.134636) (xy 303.713791 -196.071076)
			(xy 303.735326 -196.009541) (xy 303.763618 -195.950804) (xy 303.798309 -195.895606) (xy 303.838963 -195.844639)
			(xy 303.861724 -195.8213) (xy 304.024792 -195.658232) (xy 304.048146 -195.635488) (xy 304.099107 -195.594829)
			(xy 304.154302 -195.560136) (xy 304.213036 -195.531845) (xy 304.274571 -195.510312) (xy 304.33813 -195.495809)
			(xy 304.402913 -195.488517) (xy 304.43551 -195.488052) (xy 304.665888 -195.488052) (xy 304.701727 -195.488601)
			(xy 304.772856 -195.497456) (xy 304.842355 -195.514996) (xy 304.909168 -195.540955) (xy 304.972279 -195.574937)
			(xy 305.030729 -195.616427) (xy 305.057556 -195.640198) (xy 305.064785 -195.64628) (xy 305.082405 -195.653055)
			(xy 305.091846 -195.653406) (xy 305.12258 -195.653406) (xy 305.132004 -195.652973) (xy 305.149598 -195.646207)
			(xy 305.15687 -195.640198) (xy 305.183682 -195.616411) (xy 305.242138 -195.574929) (xy 305.305253 -195.540954)
			(xy 305.372068 -195.515002) (xy 305.441569 -195.497467) (xy 305.512699 -195.488617) (xy 305.548538 -195.488052)
			(xy 305.66868 -195.488052) (xy 305.696366 -195.466208) (xy 305.700176 -195.448682) (xy 305.707089 -195.420023)
			(xy 305.726824 -195.364467) (xy 305.753019 -195.311649) (xy 305.785302 -195.262317) (xy 305.823217 -195.217168)
			(xy 305.844448 -195.196714) (xy 305.85156 -195.189856) (xy 305.859942 -195.171822) (xy 305.864006 -195.081144)
			(xy 305.857402 -195.062348) (xy 305.850544 -195.054982) (xy 305.830331 -195.031629) (xy 305.795111 -194.980891)
			(xy 305.766293 -194.926262) (xy 305.7443 -194.868546) (xy 305.729455 -194.808592) (xy 305.721978 -194.747282)
			(xy 305.721512 -194.7164) (xy 305.721968 -194.685796) (xy 305.729314 -194.625032) (xy 305.7439 -194.565588)
			(xy 305.765515 -194.508324) (xy 305.793846 -194.454069) (xy 305.828485 -194.403606) (xy 305.86893 -194.357665)
			(xy 305.891438 -194.336924) (xy 305.89855 -194.330828) (xy 305.906932 -194.314826) (xy 305.917346 -194.229482)
			(xy 305.913028 -194.211956) (xy 305.907694 -194.204082) (xy 305.892551 -194.181001) (xy 305.868609 -194.131261)
			(xy 305.852363 -194.078503) (xy 305.844178 -194.023912) (xy 305.843686 -193.99631) (xy 305.844202 -193.96871)
			(xy 305.852429 -193.914127) (xy 305.868699 -193.86138) (xy 305.892649 -193.811648) (xy 305.923744 -193.76604)
			(xy 305.961289 -193.725576) (xy 306.004446 -193.691159) (xy 306.05225 -193.66356) (xy 306.103634 -193.643393)
			(xy 306.157449 -193.63111) (xy 306.212494 -193.626985) (xy 306.267539 -193.63111) (xy 306.321354 -193.643393)
			(xy 306.372738 -193.66356) (xy 306.420542 -193.691159) (xy 306.463699 -193.725576) (xy 306.501244 -193.76604)
			(xy 306.532339 -193.811648) (xy 306.556289 -193.86138) (xy 306.572559 -193.914127) (xy 306.580786 -193.96871)
			(xy 306.581302 -193.99631) (xy 306.580863 -194.021645) (xy 306.573893 -194.071833) (xy 306.560128 -194.120597)
			(xy 306.539825 -194.167021) (xy 306.526946 -194.188842) (xy 306.52212 -194.19697) (xy 306.518564 -194.21475)
			(xy 306.533296 -194.299332) (xy 306.54244 -194.31508) (xy 306.549806 -194.320922) (xy 306.574648 -194.34168)
			(xy 306.619394 -194.388463) (xy 306.657844 -194.440544) (xy 306.689378 -194.497082) (xy 306.713485 -194.557163)
			(xy 306.729776 -194.619817) (xy 306.737988 -194.684031) (xy 306.738528 -194.7164) (xy 306.738097 -194.746866)
			(xy 306.733529 -194.78498) (xy 308.027576 -194.78498) (xy 308.03165 -194.721512) (xy 308.043808 -194.659087)
			(xy 308.063848 -194.598728) (xy 308.091442 -194.541428) (xy 308.126138 -194.488127) (xy 308.167364 -194.4397)
			(xy 308.214444 -194.396943) (xy 308.266606 -194.360557) (xy 308.322993 -194.33114) (xy 308.382678 -194.309175)
			(xy 308.444682 -194.295023) (xy 308.507986 -194.288917) (xy 308.571552 -194.290955) (xy 308.634335 -194.301105)
			(xy 308.695305 -194.319201) (xy 308.75346 -194.344944) (xy 308.807846 -194.377913) (xy 308.857569 -194.417566)
			(xy 308.901814 -194.463252) (xy 308.939853 -194.514221) (xy 308.971062 -194.569635) (xy 308.994928 -194.628586)
			(xy 309.01106 -194.690104) (xy 309.019193 -194.753181) (xy 309.019702 -194.78498) (xy 309.019193 -194.816779)
			(xy 309.01106 -194.879856) (xy 308.994928 -194.941374) (xy 308.971062 -195.000325) (xy 308.939853 -195.055739)
			(xy 308.901814 -195.106708) (xy 308.857569 -195.152394) (xy 308.807846 -195.192047) (xy 308.75346 -195.225016)
			(xy 308.695305 -195.250759) (xy 308.634335 -195.268855) (xy 308.571552 -195.279005) (xy 308.507986 -195.281043)
			(xy 308.444682 -195.274937) (xy 308.382678 -195.260785) (xy 308.322993 -195.23882) (xy 308.266606 -195.209403)
			(xy 308.214444 -195.173017) (xy 308.167364 -195.13026) (xy 308.126138 -195.081833) (xy 308.091442 -195.028532)
			(xy 308.063848 -194.971232) (xy 308.043808 -194.910873) (xy 308.03165 -194.848448) (xy 308.027576 -194.78498)
			(xy 306.733529 -194.78498) (xy 306.730846 -194.807366) (xy 306.716412 -194.866563) (xy 306.695002 -194.92361)
			(xy 306.666923 -194.977687) (xy 306.632578 -195.028018) (xy 306.592461 -195.073881) (xy 306.570126 -195.094606)
			(xy 306.562506 -195.10121) (xy 306.55387 -195.11899) (xy 306.548028 -195.209668) (xy 306.554124 -195.228464)
			(xy 306.560728 -195.236084) (xy 306.579387 -195.258578) (xy 306.611864 -195.307168) (xy 306.638404 -195.359238)
			(xy 306.658639 -195.414068) (xy 306.672289 -195.470895) (xy 306.679164 -195.528934) (xy 306.6796 -195.558156)
			(xy 306.67911 -195.590035) (xy 306.670946 -195.653268) (xy 306.654746 -195.714934) (xy 306.630778 -195.774015)
			(xy 306.599436 -195.829538) (xy 306.561238 -195.880587) (xy 306.516814 -195.92632) (xy 306.492148 -195.946522)
			(xy 306.483804 -195.953786) (xy 306.47381 -195.973495) (xy 306.473074 -195.995581) (xy 306.476908 -196.005958)
			(xy 306.491374 -196.041871) (xy 306.511745 -196.116567) (xy 306.522013 -196.193306) (xy 306.522628 -196.232018)
			(xy 306.522628 -196.2785) (xy 306.523048 -196.288519) (xy 306.530719 -196.307031) (xy 306.544892 -196.321197)
			(xy 306.563409 -196.328857) (xy 306.573428 -196.3293) (xy 307.002942 -196.3293) (xy 307.011895 -196.328949)
			(xy 307.028713 -196.322796) (xy 307.042402 -196.311252) (xy 307.047138 -196.303646) (xy 307.061265 -196.279639)
			(xy 307.095618 -196.235795) (xy 307.136178 -196.197618) (xy 307.182019 -196.165978) (xy 307.232099 -196.141596)
			(xy 307.285278 -196.125026) (xy 307.340344 -196.116645) (xy 307.396044 -196.116645) (xy 307.45111 -196.125026)
			(xy 307.504289 -196.141596) (xy 307.554369 -196.165978) (xy 307.60021 -196.197618) (xy 307.64077 -196.235795)
			(xy 307.675123 -196.279639) (xy 307.68925 -196.303646) (xy 307.693982 -196.311257) (xy 307.707662 -196.322816)
			(xy 307.72449 -196.328947) (xy 307.733446 -196.3293) (xy 307.97627 -196.3293) (xy 307.987023 -196.328831)
			(xy 308.006642 -196.320026) (xy 308.014116 -196.312282) (xy 308.072028 -196.247512) (xy 308.078378 -196.226938)
			(xy 308.077108 -196.216016) (xy 308.075545 -196.201653) (xy 308.073893 -196.172806) (xy 308.073806 -196.158358)
			(xy 308.074295 -196.127195) (xy 308.082107 -196.065361) (xy 308.097607 -196.004993) (xy 308.12055 -195.947045)
			(xy 308.150576 -195.892428) (xy 308.18721 -195.842006) (xy 308.229875 -195.796572) (xy 308.277897 -195.756844)
			(xy 308.330521 -195.723449) (xy 308.386915 -195.696912) (xy 308.44619 -195.677652) (xy 308.507411 -195.665973)
			(xy 308.569614 -195.66206) (xy 308.631817 -195.665973) (xy 308.693038 -195.677652) (xy 308.752313 -195.696912)
			(xy 308.808707 -195.723449) (xy 308.861331 -195.756844) (xy 308.909353 -195.796572) (xy 308.952018 -195.842006)
			(xy 308.988652 -195.892428) (xy 309.018678 -195.947045) (xy 309.041621 -196.004993) (xy 309.057121 -196.065361)
			(xy 309.064933 -196.127195) (xy 309.065422 -196.158358) (xy 309.065332 -196.172805) (xy 309.063677 -196.201652)
			(xy 309.06212 -196.216016) (xy 309.06085 -196.226938) (xy 309.0672 -196.247512) (xy 309.125112 -196.312282)
			(xy 309.132676 -196.319905) (xy 309.152236 -196.328705) (xy 309.162958 -196.3293) (xy 309.473092 -196.3293)
			(xy 309.48306 -196.328827) (xy 309.501504 -196.321258) (xy 309.508906 -196.314568) (xy 309.76697 -196.056504)
			(xy 309.77382 -196.049107) (xy 309.781561 -196.030509) (xy 309.781956 -196.020436) (xy 309.781956 -192.50787)
			(xy 309.781526 -192.497803) (xy 309.773799 -192.479211) (xy 309.76697 -192.471802) (xy 309.5244 -192.229232)
			(xy 309.518696 -192.223894) (xy 309.504858 -192.216661) (xy 309.497222 -192.215008) (xy 309.250842 -192.171574)
			(xy 309.240405 -192.170298) (xy 309.220005 -192.175302) (xy 309.203307 -192.188044) (xy 309.197756 -192.196974)
			(xy 309.143146 -192.295526) (xy 309.146956 -192.327784) (xy 309.158132 -192.339976) (xy 309.184886 -192.370187)
			(xy 309.23335 -192.434719) (xy 309.275679 -192.503432) (xy 309.311513 -192.575744) (xy 309.340551 -192.651043)
			(xy 309.362546 -192.728691) (xy 309.377312 -192.808033) (xy 309.384725 -192.888396) (xy 309.385208 -192.928748)
			(xy 309.384711 -192.970492) (xy 309.376775 -193.053602) (xy 309.360975 -193.13558) (xy 309.337454 -193.215686)
			(xy 309.306425 -193.293194) (xy 309.268168 -193.367401) (xy 309.223032 -193.437635) (xy 309.171423 -193.503261)
			(xy 309.11381 -193.563683) (xy 309.050714 -193.618356) (xy 308.982707 -193.666784) (xy 308.910404 -193.708528)
			(xy 308.834461 -193.74321) (xy 308.755565 -193.770516) (xy 308.674431 -193.790199) (xy 308.591793 -193.80208)
			(xy 308.5084 -193.806053) (xy 308.425007 -193.80208) (xy 308.342369 -193.790199) (xy 308.261235 -193.770516)
			(xy 308.182339 -193.74321) (xy 308.106396 -193.708528) (xy 308.034093 -193.666784) (xy 307.966086 -193.618356)
			(xy 307.90299 -193.563683) (xy 307.845377 -193.503261) (xy 307.793768 -193.437635) (xy 307.748632 -193.367401)
			(xy 307.710375 -193.293194) (xy 307.679346 -193.215686) (xy 307.655825 -193.13558) (xy 307.640025 -193.053602)
			(xy 307.632089 -192.970492) (xy 307.631592 -192.928748) (xy 307.632117 -192.885479) (xy 307.640649 -192.799362)
			(xy 307.657626 -192.714506) (xy 307.682882 -192.631735) (xy 307.71617 -192.551855) (xy 307.757168 -192.475645)
			(xy 307.805476 -192.403845) (xy 307.860624 -192.337155) (xy 307.922075 -192.276224) (xy 307.989231 -192.221644)
			(xy 308.061439 -192.173947) (xy 308.09946 -192.153286) (xy 308.113938 -192.145412) (xy 308.128416 -192.11671)
			(xy 308.11089 -192.005458) (xy 308.108714 -191.995123) (xy 308.097328 -191.977361) (xy 308.079784 -191.965642)
			(xy 308.069488 -191.963294) (xy 307.447442 -191.853566) (xy 307.438552 -191.852804) (xy 306.601876 -191.852804)
			(xy 306.592679 -191.853209) (xy 306.575465 -191.859699) (xy 306.561619 -191.871812) (xy 306.556918 -191.879728)
			(xy 306.50815 -191.971676) (xy 306.509674 -191.999616) (xy 306.517802 -192.0113) (xy 306.532814 -192.03433)
			(xy 306.556573 -192.083902) (xy 306.572697 -192.136456) (xy 306.580826 -192.190824) (xy 306.581302 -192.21831)
			(xy 306.580786 -192.24591) (xy 306.572559 -192.300493) (xy 306.556289 -192.35324) (xy 306.532339 -192.402973)
			(xy 306.501244 -192.44858) (xy 306.463699 -192.489044) (xy 306.420542 -192.523461) (xy 306.372738 -192.55106)
			(xy 306.321354 -192.571227) (xy 306.267539 -192.58351) (xy 306.212494 -192.587635) (xy 306.157449 -192.58351)
			(xy 306.103634 -192.571227) (xy 306.05225 -192.55106) (xy 306.004446 -192.523461) (xy 305.961289 -192.489044)
			(xy 305.923744 -192.44858) (xy 305.892649 -192.402973) (xy 305.868699 -192.35324) (xy 305.852429 -192.300493)
			(xy 305.844202 -192.24591) (xy 305.843686 -192.21831) (xy 305.844197 -192.190827) (xy 305.852352 -192.13647)
			(xy 305.86847 -192.083921) (xy 305.892194 -192.034339) (xy 305.907186 -192.0113) (xy 305.915314 -191.999616)
			(xy 305.916838 -191.971676) (xy 305.86807 -191.879728) (xy 305.863415 -191.871768) (xy 305.849583 -191.859598)
			(xy 305.832326 -191.853143) (xy 305.823112 -191.852804) (xy 304.813208 -191.852804) (xy 304.804008 -191.853203)
			(xy 304.786786 -191.859687) (xy 304.772931 -191.871798) (xy 304.76825 -191.879728) (xy 304.719482 -191.971676)
			(xy 304.721006 -191.999616) (xy 304.729134 -192.0113) (xy 304.744144 -192.034331) (xy 304.767902 -192.083903)
			(xy 304.784024 -192.136457) (xy 304.792153 -192.190824) (xy 304.792634 -192.21831) (xy 304.792118 -192.24591)
			(xy 304.783891 -192.300493) (xy 304.767621 -192.35324) (xy 304.743671 -192.402973) (xy 304.712576 -192.44858)
			(xy 304.675031 -192.489044) (xy 304.631874 -192.523461) (xy 304.58407 -192.55106) (xy 304.532686 -192.571227)
			(xy 304.478871 -192.58351) (xy 304.423826 -192.587635) (xy 304.368781 -192.58351) (xy 304.314966 -192.571227)
			(xy 304.263582 -192.55106) (xy 304.215778 -192.523461) (xy 304.172621 -192.489044) (xy 304.135076 -192.44858)
			(xy 304.103981 -192.402973) (xy 304.080031 -192.35324) (xy 304.063761 -192.300493) (xy 304.055534 -192.24591)
			(xy 304.055018 -192.21831) (xy 304.055529 -192.190827) (xy 304.063685 -192.136471) (xy 304.079804 -192.083922)
			(xy 304.103529 -192.034341) (xy 304.118518 -192.0113) (xy 304.126646 -191.999616) (xy 304.12817 -191.971676)
			(xy 304.079402 -191.879728) (xy 304.074748 -191.871765) (xy 304.060918 -191.859586) (xy 304.04366 -191.85312)
			(xy 304.034444 -191.852804) (xy 303.062386 -191.852804) (xy 303.050518 -191.853494) (xy 303.029337 -191.864227)
			(xy 303.021746 -191.873378) (xy 302.965866 -191.948308) (xy 302.961548 -191.97193) (xy 302.965104 -191.983614)
			(xy 302.976818 -192.024488) (xy 302.993208 -192.107925) (xy 303.001443 -192.192558) (xy 303.001934 -192.235074)
			(xy 303.001444 -192.276801) (xy 302.993493 -192.359874) (xy 302.97768 -192.441815) (xy 302.954147 -192.521882)
			(xy 302.923109 -192.599349) (xy 302.904398 -192.636648) (xy 302.89942 -192.647811) (xy 302.899427 -192.672217)
			(xy 302.904398 -192.683384) (xy 302.923076 -192.720698) (xy 302.954095 -192.798166) (xy 302.977619 -192.878231)
			(xy 302.993435 -192.960167) (xy 303.0014 -193.043234) (xy 303.001934 -193.084958) (xy 303.001419 -193.127344)
			(xy 302.993233 -193.21172) (xy 302.976943 -193.294912) (xy 302.952701 -193.376144) (xy 302.920734 -193.454657)
			(xy 302.881339 -193.529719) (xy 302.834884 -193.600629) (xy 302.781804 -193.666726) (xy 302.722593 -193.727392)
			(xy 302.657804 -193.78206) (xy 302.62322 -193.806572) (xy 302.615583 -193.81233) (xy 302.604919 -193.828191)
			(xy 302.600796 -193.846853) (xy 302.601884 -193.856356) (xy 302.604838 -193.875907) (xy 302.608019 -193.915324)
			(xy 302.608234 -193.935096) (xy 302.607774 -193.965786) (xy 302.603978 -193.996305) (xy 303.927495 -193.996305)
			(xy 303.931342 -193.934627) (xy 303.942824 -193.873905) (xy 303.961763 -193.815081) (xy 303.987865 -193.759067)
			(xy 304.020726 -193.706731) (xy 304.059837 -193.658884) (xy 304.10459 -193.616269) (xy 304.154293 -193.579545)
			(xy 304.181002 -193.564002) (xy 304.192178 -193.557906) (xy 304.20564 -193.53657) (xy 304.214276 -193.427096)
			(xy 304.20437 -193.403982) (xy 304.19421 -193.396108) (xy 304.172876 -193.378506) (xy 304.135213 -193.338004)
			(xy 304.104025 -193.292329) (xy 304.080012 -193.242507) (xy 304.063712 -193.189657) (xy 304.055491 -193.134964)
			(xy 304.055018 -193.10731) (xy 304.055534 -193.07971) (xy 304.063761 -193.025127) (xy 304.080031 -192.97238)
			(xy 304.103981 -192.922648) (xy 304.135076 -192.87704) (xy 304.172621 -192.836576) (xy 304.215778 -192.802159)
			(xy 304.263582 -192.77456) (xy 304.314966 -192.754393) (xy 304.368781 -192.74211) (xy 304.423826 -192.737985)
			(xy 304.478871 -192.74211) (xy 304.532686 -192.754393) (xy 304.58407 -192.77456) (xy 304.631874 -192.802159)
			(xy 304.675031 -192.836576) (xy 304.712576 -192.87704) (xy 304.743671 -192.922648) (xy 304.767621 -192.97238)
			(xy 304.783891 -193.025127) (xy 304.792118 -193.07971) (xy 304.792634 -193.10731) (xy 304.792139 -193.134961)
			(xy 304.7839 -193.189646) (xy 304.767594 -193.242489) (xy 304.743584 -193.292308) (xy 304.71241 -193.337986)
			(xy 304.674768 -193.3785) (xy 304.653442 -193.396108) (xy 304.643282 -193.403982) (xy 304.633376 -193.427096)
			(xy 304.642012 -193.53657) (xy 304.655474 -193.557906) (xy 304.66665 -193.564002) (xy 304.693366 -193.579532)
			(xy 304.743066 -193.61626) (xy 304.787816 -193.658878) (xy 304.826924 -193.706727) (xy 304.859783 -193.759065)
			(xy 304.885883 -193.815081) (xy 304.90482 -193.873905) (xy 304.916301 -193.934627) (xy 304.920148 -193.996305)
			(xy 304.9163 -194.057983) (xy 304.904818 -194.118704) (xy 304.885879 -194.177528) (xy 304.859778 -194.233543)
			(xy 304.826918 -194.28588) (xy 304.78781 -194.333729) (xy 304.743058 -194.376347) (xy 304.693358 -194.413073)
			(xy 304.66665 -194.428618) (xy 304.655474 -194.434714) (xy 304.642012 -194.45605) (xy 304.633376 -194.565524)
			(xy 304.643282 -194.588638) (xy 304.653442 -194.596512) (xy 304.674776 -194.614114) (xy 304.712441 -194.654615)
			(xy 304.74363 -194.700289) (xy 304.767644 -194.750111) (xy 304.783944 -194.802962) (xy 304.792162 -194.857656)
			(xy 304.792634 -194.88531) (xy 304.792118 -194.91291) (xy 304.783891 -194.967493) (xy 304.767621 -195.02024)
			(xy 304.743671 -195.069973) (xy 304.712576 -195.11558) (xy 304.675031 -195.156044) (xy 304.631874 -195.190461)
			(xy 304.58407 -195.21806) (xy 304.532686 -195.238227) (xy 304.478871 -195.25051) (xy 304.423826 -195.254635)
			(xy 304.368781 -195.25051) (xy 304.314966 -195.238227) (xy 304.263582 -195.21806) (xy 304.215778 -195.190461)
			(xy 304.172621 -195.156044) (xy 304.135076 -195.11558) (xy 304.103981 -195.069973) (xy 304.080031 -195.02024)
			(xy 304.063761 -194.967493) (xy 304.055534 -194.91291) (xy 304.055018 -194.88531) (xy 304.055508 -194.857658)
			(xy 304.063745 -194.802972) (xy 304.080051 -194.750128) (xy 304.104062 -194.700309) (xy 304.135238 -194.654632)
			(xy 304.172883 -194.614118) (xy 304.19421 -194.596512) (xy 304.20437 -194.588638) (xy 304.214276 -194.565524)
			(xy 304.20564 -194.45605) (xy 304.192178 -194.434714) (xy 304.181002 -194.428618) (xy 304.154301 -194.41306)
			(xy 304.104598 -194.376338) (xy 304.059844 -194.333723) (xy 304.020732 -194.285877) (xy 303.98787 -194.233542)
			(xy 303.961766 -194.177528) (xy 303.942826 -194.118704) (xy 303.931343 -194.057983) (xy 303.927495 -193.996305)
			(xy 302.603978 -193.996305) (xy 302.600198 -194.026698) (xy 302.585162 -194.086209) (xy 302.562894 -194.143408)
			(xy 302.533737 -194.197422) (xy 302.498135 -194.247423) (xy 302.456634 -194.292648) (xy 302.409868 -194.332404)
			(xy 302.38446 -194.349624) (xy 302.37557 -194.355466) (xy 302.364394 -194.372484) (xy 302.347376 -194.465448)
			(xy 302.351694 -194.485514) (xy 302.358044 -194.49415) (xy 302.375887 -194.519613) (xy 302.405774 -194.574135)
			(xy 302.428607 -194.631968) (xy 302.444028 -194.692202) (xy 302.451794 -194.753892) (xy 302.452278 -194.78498)
			(xy 302.451771 -194.817444) (xy 302.443299 -194.881816) (xy 302.426496 -194.944532) (xy 302.40165 -195.004518)
			(xy 302.369187 -195.060747) (xy 302.329661 -195.112257) (xy 302.28375 -195.158168) (xy 302.232238 -195.197692)
			(xy 302.176009 -195.230154) (xy 302.116022 -195.254999) (xy 302.053306 -195.271801) (xy 301.988934 -195.280272)
			(xy 301.95647 -195.280788) (xy 301.923364 -195.280236) (xy 301.85774 -195.271421) (xy 301.793874 -195.253951)
			(xy 301.7329 -195.228137) (xy 301.675904 -195.194439) (xy 301.6239 -195.153455) (xy 301.577812 -195.105915)
			(xy 301.55769 -195.07962) (xy 301.550324 -195.069714) (xy 301.528988 -195.059046) (xy 301.4218 -195.059808)
			(xy 301.400718 -195.07073) (xy 301.393352 -195.08089) (xy 301.380571 -195.098366) (xy 301.352467 -195.131306)
			(xy 301.337218 -195.146676) (xy 301.329852 -195.154042) (xy 301.322232 -195.172076) (xy 301.321216 -195.264024)
			(xy 301.328582 -195.282566) (xy 301.335694 -195.289932) (xy 301.357518 -195.313114) (xy 301.395651 -195.3641)
			(xy 301.426938 -195.419552) (xy 301.450862 -195.478555) (xy 301.467029 -195.540137) (xy 301.475171 -195.603283)
			(xy 301.475648 -195.635118) (xy 301.475159 -195.666281) (xy 301.467347 -195.728115) (xy 301.451847 -195.788483)
			(xy 301.428904 -195.846431) (xy 301.398878 -195.901048) (xy 301.362244 -195.95147) (xy 301.319579 -195.996904)
			(xy 301.271557 -196.036632) (xy 301.218933 -196.070027) (xy 301.162539 -196.096564) (xy 301.103264 -196.115824)
			(xy 301.042043 -196.127503) (xy 300.97984 -196.131416) (xy 300.917637 -196.127503) (xy 300.856416 -196.115824)
			(xy 300.797141 -196.096564) (xy 300.740747 -196.070027) (xy 300.688123 -196.036632) (xy 300.640101 -195.996904)
			(xy 300.597436 -195.95147) (xy 300.560802 -195.901048) (xy 300.530776 -195.846431) (xy 300.507833 -195.788483)
			(xy 300.492333 -195.728115) (xy 300.484521 -195.666281) (xy 300.484032 -195.635118) (xy 300.484527 -195.603286)
			(xy 300.492687 -195.540147) (xy 300.508863 -195.478573) (xy 300.532788 -195.419575) (xy 300.564069 -195.364126)
			(xy 300.60219 -195.313137) (xy 300.623986 -195.289932) (xy 300.631098 -195.282566) (xy 300.638464 -195.264024)
			(xy 300.637448 -195.172076) (xy 300.629828 -195.154042) (xy 300.622462 -195.146676) (xy 300.598974 -195.122715)
			(xy 300.557857 -195.069691) (xy 300.524068 -195.011722) (xy 300.498193 -194.949814) (xy 300.480681 -194.885041)
			(xy 300.471837 -194.818529) (xy 300.471332 -194.78498) (xy 300.471779 -194.75425) (xy 300.47919 -194.693237)
			(xy 300.493901 -194.633563) (xy 300.515698 -194.576097) (xy 300.544263 -194.521677) (xy 300.57918 -194.471098)
			(xy 300.619939 -194.425096) (xy 300.665945 -194.384343) (xy 300.716529 -194.349432) (xy 300.770952 -194.320873)
			(xy 300.82842 -194.299083) (xy 300.888096 -194.284379) (xy 300.949109 -194.276975) (xy 300.97984 -194.276472)
			(xy 301.010033 -194.2769) (xy 301.069995 -194.284046) (xy 301.128688 -194.298244) (xy 301.185286 -194.319295)
			(xy 301.238993 -194.346902) (xy 301.289051 -194.380676) (xy 301.334756 -194.420141) (xy 301.375464 -194.464743)
			(xy 301.393352 -194.48907) (xy 301.400718 -194.49923) (xy 301.4218 -194.510152) (xy 301.528988 -194.510914)
			(xy 301.550324 -194.500246) (xy 301.55769 -194.49034) (xy 301.57541 -194.46708) (xy 301.615455 -194.424468)
			(xy 301.660235 -194.386863) (xy 301.684436 -194.370452) (xy 301.693326 -194.36461) (xy 301.704502 -194.347592)
			(xy 301.72152 -194.254628) (xy 301.717202 -194.234562) (xy 301.710852 -194.225926) (xy 301.69301 -194.200463)
			(xy 301.663126 -194.14594) (xy 301.640296 -194.088107) (xy 301.624878 -194.027873) (xy 301.617115 -193.966184)
			(xy 301.616618 -193.935096) (xy 301.616906 -193.911647) (xy 301.621362 -193.86496) (xy 301.625508 -193.841878)
			(xy 301.626937 -193.832389) (xy 301.623412 -193.813543) (xy 301.613194 -193.797319) (xy 301.605696 -193.791332)
			(xy 301.573651 -193.767207) (xy 301.513638 -193.713978) (xy 301.458737 -193.655492) (xy 301.409405 -193.592237)
			(xy 301.366054 -193.524743) (xy 301.329048 -193.453572) (xy 301.298694 -193.379319) (xy 301.275247 -193.302605)
			(xy 301.258902 -193.224071) (xy 301.253906 -193.184272) (xy 301.252636 -193.17335) (xy 301.242222 -193.155316)
			(xy 301.164752 -193.09842) (xy 301.144178 -193.093848) (xy 301.133764 -193.09588) (xy 301.092515 -193.103364)
			(xy 301.009059 -193.111376) (xy 300.96714 -193.111882) (xy 300.924089 -193.111373) (xy 300.838403 -193.102937)
			(xy 300.753956 -193.086142) (xy 300.671561 -193.061151) (xy 300.592014 -193.028204) (xy 300.516078 -192.987618)
			(xy 300.444487 -192.939784) (xy 300.37793 -192.885163) (xy 300.317047 -192.824281) (xy 300.262424 -192.757724)
			(xy 300.214589 -192.686134) (xy 300.174002 -192.610199) (xy 300.141054 -192.530652) (xy 300.116061 -192.448258)
			(xy 300.099265 -192.363811) (xy 300.090828 -192.278124) (xy 300.090332 -192.235074) (xy 300.09076 -192.195734)
			(xy 300.097782 -192.117367) (xy 300.111795 -192.039944) (xy 300.121828 -192.001902) (xy 300.12513 -191.990218)
			(xy 300.120558 -191.967104) (xy 300.063662 -191.89319) (xy 300.055927 -191.884204) (xy 300.034614 -191.873879)
			(xy 300.022768 -191.873378) (xy 299.076364 -191.884554) (xy 299.067565 -191.885004) (xy 299.05106 -191.891128)
			(xy 299.037617 -191.902495) (xy 299.03293 -191.909954) (xy 298.982638 -191.997584) (xy 298.982638 -192.024508)
			(xy 298.989242 -192.036192) (xy 299.000661 -192.057094) (xy 299.018622 -192.101206) (xy 299.030764 -192.147261)
			(xy 299.036886 -192.194495) (xy 299.037248 -192.21831) (xy 299.036732 -192.24591) (xy 299.028505 -192.300493)
			(xy 299.012235 -192.35324) (xy 298.988285 -192.402973) (xy 298.95719 -192.44858) (xy 298.919645 -192.489044)
			(xy 298.876488 -192.523461) (xy 298.828684 -192.55106) (xy 298.7773 -192.571227) (xy 298.723485 -192.58351)
			(xy 298.66844 -192.587635) (xy 298.613395 -192.58351) (xy 298.55958 -192.571227) (xy 298.508196 -192.55106)
			(xy 298.460392 -192.523461) (xy 298.417235 -192.489044) (xy 298.37969 -192.44858) (xy 298.348595 -192.402973)
			(xy 298.324645 -192.35324) (xy 298.308375 -192.300493) (xy 298.300148 -192.24591) (xy 298.299632 -192.21831)
			(xy 298.300241 -192.187994) (xy 298.31016 -192.128179) (xy 298.329748 -192.070799) (xy 298.343574 -192.043812)
			(xy 298.349924 -192.032128) (xy 298.349162 -192.005204) (xy 298.296838 -191.918844) (xy 298.292006 -191.911408)
			(xy 298.278258 -191.900224) (xy 298.261508 -191.894432) (xy 298.252642 -191.894206) (xy 297.298872 -191.905636)
			(xy 297.290306 -191.906103) (xy 297.274211 -191.912007) (xy 297.260955 -191.92288) (xy 297.2562 -191.93002)
			(xy 297.204638 -192.014856) (xy 297.203368 -192.041018) (xy 297.209464 -192.052702) (xy 297.221819 -192.07854)
			(xy 297.23927 -192.133085) (xy 297.24807 -192.189675) (xy 297.24858 -192.21831) (xy 297.248064 -192.24591)
			(xy 297.239837 -192.300493) (xy 297.223567 -192.35324) (xy 297.199617 -192.402973) (xy 297.168522 -192.44858)
			(xy 297.130977 -192.489044) (xy 297.08782 -192.523461) (xy 297.040016 -192.55106) (xy 296.988632 -192.571227)
			(xy 296.934817 -192.58351) (xy 296.879772 -192.587635) (xy 296.824727 -192.58351) (xy 296.770912 -192.571227)
			(xy 296.719528 -192.55106) (xy 296.671724 -192.523461) (xy 296.628567 -192.489044) (xy 296.591022 -192.44858)
			(xy 296.559927 -192.402973) (xy 296.535977 -192.35324) (xy 296.519707 -192.300493) (xy 296.51148 -192.24591)
			(xy 296.510964 -192.21831) (xy 296.511432 -192.191137) (xy 296.519374 -192.137375) (xy 296.535116 -192.085359)
			(xy 296.54627 -192.060576) (xy 296.551858 -192.048892) (xy 296.550334 -192.02273) (xy 296.49674 -191.939164)
			(xy 296.491797 -191.932115) (xy 296.478219 -191.921547) (xy 296.461913 -191.916055) (xy 296.453306 -191.915796)
			(xy 295.536112 -191.926464) (xy 295.524802 -191.927246) (xy 295.504503 -191.937272) (xy 295.496996 -191.945768)
			(xy 295.440608 -192.01638) (xy 295.435528 -192.038224) (xy 295.438068 -192.049654) (xy 295.44736 -192.095444)
			(xy 295.457285 -192.188354) (xy 295.45788 -192.235074) (xy 295.45739 -192.2768) (xy 295.449439 -192.359874)
			(xy 295.433624 -192.441815) (xy 295.410091 -192.521881) (xy 295.37905 -192.599346) (xy 295.360344 -192.636648)
			(xy 295.35537 -192.647812) (xy 295.355377 -192.672216) (xy 295.360344 -192.683384) (xy 295.379023 -192.720697)
			(xy 295.410044 -192.798166) (xy 295.433569 -192.87823) (xy 295.449386 -192.960166) (xy 295.457352 -193.043234)
			(xy 295.45788 -193.084958) (xy 295.457365 -193.127344) (xy 295.449179 -193.211719) (xy 295.432888 -193.29491)
			(xy 295.408645 -193.37614) (xy 295.376676 -193.454652) (xy 295.33728 -193.529713) (xy 295.290824 -193.600621)
			(xy 295.237741 -193.666715) (xy 295.178528 -193.727378) (xy 295.113737 -193.782043) (xy 295.079166 -193.806572)
			(xy 295.071524 -193.812327) (xy 295.060849 -193.828187) (xy 295.056722 -193.846854) (xy 295.05783 -193.856356)
			(xy 295.060784 -193.875907) (xy 295.063964 -193.915324) (xy 295.06418 -193.935096) (xy 295.06369 -193.96693)
			(xy 295.059899 -193.996305) (xy 296.383469 -193.996305) (xy 296.387315 -193.934629) (xy 296.398795 -193.87391)
			(xy 296.417732 -193.815087) (xy 296.443831 -193.759074) (xy 296.476689 -193.706738) (xy 296.515795 -193.65889)
			(xy 296.560544 -193.616273) (xy 296.610241 -193.579547) (xy 296.636948 -193.564002) (xy 296.648124 -193.557906)
			(xy 296.661586 -193.53657) (xy 296.670222 -193.427096) (xy 296.660316 -193.403982) (xy 296.650156 -193.396108)
			(xy 296.628831 -193.378495) (xy 296.591166 -193.337997) (xy 296.559976 -193.292325) (xy 296.53596 -193.242505)
			(xy 296.519658 -193.189655) (xy 296.511437 -193.134964) (xy 296.510964 -193.10731) (xy 296.51148 -193.07971)
			(xy 296.519707 -193.025127) (xy 296.535977 -192.97238) (xy 296.559927 -192.922648) (xy 296.591022 -192.87704)
			(xy 296.628567 -192.836576) (xy 296.671724 -192.802159) (xy 296.719528 -192.77456) (xy 296.770912 -192.754393)
			(xy 296.824727 -192.74211) (xy 296.879772 -192.737985) (xy 296.934817 -192.74211) (xy 296.988632 -192.754393)
			(xy 297.040016 -192.77456) (xy 297.08782 -192.802159) (xy 297.130977 -192.836576) (xy 297.168522 -192.87704)
			(xy 297.199617 -192.922648) (xy 297.223567 -192.97238) (xy 297.239837 -193.025127) (xy 297.248064 -193.07971)
			(xy 297.24858 -193.10731) (xy 297.248105 -193.134962) (xy 297.239865 -193.189649) (xy 297.223556 -193.242494)
			(xy 297.199543 -193.292312) (xy 297.168363 -193.33799) (xy 297.130717 -193.378502) (xy 297.109388 -193.396108)
			(xy 297.099228 -193.403982) (xy 297.089322 -193.427096) (xy 297.097958 -193.53657) (xy 297.11142 -193.557906)
			(xy 297.122596 -193.564002) (xy 297.149315 -193.57953) (xy 297.199019 -193.616255) (xy 297.243774 -193.658872)
			(xy 297.282886 -193.70672) (xy 297.315749 -193.759059) (xy 297.341852 -193.815075) (xy 297.360792 -193.873901)
			(xy 297.372274 -193.934625) (xy 297.376121 -193.996305) (xy 297.372273 -194.057985) (xy 297.36079 -194.118708)
			(xy 297.341849 -194.177534) (xy 297.315744 -194.23355) (xy 297.282881 -194.285888) (xy 297.243768 -194.333735)
			(xy 297.199011 -194.376351) (xy 297.149306 -194.413075) (xy 297.122596 -194.428618) (xy 297.11142 -194.434714)
			(xy 297.097958 -194.45605) (xy 297.089322 -194.565524) (xy 297.099228 -194.588638) (xy 297.109388 -194.596512)
			(xy 297.130732 -194.614103) (xy 297.168393 -194.654607) (xy 297.19958 -194.700284) (xy 297.223592 -194.750108)
			(xy 297.23989 -194.802961) (xy 297.248108 -194.857655) (xy 297.24858 -194.88531) (xy 297.248064 -194.91291)
			(xy 297.239837 -194.967493) (xy 297.223567 -195.02024) (xy 297.199617 -195.069973) (xy 297.168522 -195.11558)
			(xy 297.130977 -195.156044) (xy 297.08782 -195.190461) (xy 297.040016 -195.21806) (xy 296.988632 -195.238227)
			(xy 296.934817 -195.25051) (xy 296.879772 -195.254635) (xy 296.824727 -195.25051) (xy 296.770912 -195.238227)
			(xy 296.719528 -195.21806) (xy 296.671724 -195.190461) (xy 296.628567 -195.156044) (xy 296.591022 -195.11558)
			(xy 296.559927 -195.069973) (xy 296.535977 -195.02024) (xy 296.519707 -194.967493) (xy 296.51148 -194.91291)
			(xy 296.510964 -194.88531) (xy 296.511474 -194.857659) (xy 296.51971 -194.802975) (xy 296.536013 -194.750132)
			(xy 296.56002 -194.700314) (xy 296.591192 -194.654635) (xy 296.628831 -194.61412) (xy 296.650156 -194.596512)
			(xy 296.660316 -194.588638) (xy 296.670222 -194.565524) (xy 296.661586 -194.45605) (xy 296.648124 -194.434714)
			(xy 296.636948 -194.428618) (xy 296.61025 -194.413058) (xy 296.560551 -194.376333) (xy 296.515802 -194.333717)
			(xy 296.476695 -194.28587) (xy 296.443836 -194.233535) (xy 296.417736 -194.177522) (xy 296.398798 -194.1187)
			(xy 296.387316 -194.05798) (xy 296.383469 -193.996305) (xy 295.059899 -193.996305) (xy 295.05554 -194.030074)
			(xy 295.039373 -194.091656) (xy 295.015456 -194.150661) (xy 294.984182 -194.206119) (xy 294.946065 -194.257116)
			(xy 294.924226 -194.280282) (xy 294.917114 -194.287648) (xy 294.909748 -194.305936) (xy 294.910764 -194.397884)
			(xy 294.918638 -194.416172) (xy 294.92575 -194.423284) (xy 294.949234 -194.447247) (xy 294.990344 -194.500272)
			(xy 295.024125 -194.558243) (xy 295.049992 -194.620151) (xy 295.067496 -194.684922) (xy 295.076332 -194.751433)
			(xy 295.07688 -194.78498) (xy 295.076378 -194.816941) (xy 295.068367 -194.880359) (xy 295.05247 -194.942273)
			(xy 295.028938 -195.001706) (xy 294.998144 -195.057721) (xy 294.960571 -195.109436) (xy 294.916814 -195.156033)
			(xy 294.867561 -195.196778) (xy 294.81359 -195.231029) (xy 294.755751 -195.258246) (xy 294.694958 -195.277999)
			(xy 294.632168 -195.289977) (xy 294.568372 -195.293991) (xy 294.504576 -195.289977) (xy 294.441786 -195.277999)
			(xy 294.380993 -195.258246) (xy 294.323154 -195.231029) (xy 294.269183 -195.196778) (xy 294.21993 -195.156033)
			(xy 294.176173 -195.109436) (xy 294.1386 -195.057721) (xy 294.107806 -195.001706) (xy 294.084274 -194.942273)
			(xy 294.068377 -194.880359) (xy 294.060366 -194.816941) (xy 294.059864 -194.78498) (xy 294.060398 -194.75143)
			(xy 294.069217 -194.684913) (xy 294.086712 -194.620135) (xy 294.112579 -194.558223) (xy 294.146368 -194.500252)
			(xy 294.187492 -194.447232) (xy 294.210994 -194.423284) (xy 294.218106 -194.416172) (xy 294.22598 -194.397884)
			(xy 294.226996 -194.305936) (xy 294.21963 -194.287648) (xy 294.212518 -194.280282) (xy 294.190693 -194.2571)
			(xy 294.152557 -194.206115) (xy 294.121268 -194.150664) (xy 294.097342 -194.091661) (xy 294.081173 -194.030078)
			(xy 294.073028 -193.966931) (xy 294.072564 -193.935096) (xy 294.072852 -193.911647) (xy 294.077308 -193.86496)
			(xy 294.081454 -193.841878) (xy 294.082883 -193.832389) (xy 294.07936 -193.813539) (xy 294.069148 -193.79731)
			(xy 294.061642 -193.791332) (xy 294.029598 -193.767206) (xy 293.969589 -193.713975) (xy 293.914691 -193.655488)
			(xy 293.865362 -193.592232) (xy 293.822014 -193.524737) (xy 293.78501 -193.453566) (xy 293.754658 -193.379314)
			(xy 293.731213 -193.302601) (xy 293.714869 -193.224068) (xy 293.709852 -193.184272) (xy 293.708582 -193.17335)
			(xy 293.698168 -193.155316) (xy 293.620698 -193.09842) (xy 293.600124 -193.093848) (xy 293.58971 -193.09588)
			(xy 293.548461 -193.103366) (xy 293.465006 -193.111383) (xy 293.423086 -193.111882) (xy 293.380037 -193.11137)
			(xy 293.294354 -193.10293) (xy 293.209911 -193.086131) (xy 293.127522 -193.061137) (xy 293.047978 -193.028187)
			(xy 292.972048 -192.9876) (xy 292.900461 -192.939765) (xy 292.833908 -192.885144) (xy 292.77303 -192.824262)
			(xy 292.718411 -192.757706) (xy 292.67058 -192.686118) (xy 292.629996 -192.610185) (xy 292.59705 -192.530641)
			(xy 292.572059 -192.44825) (xy 292.555265 -192.363806) (xy 292.546828 -192.278123) (xy 292.546278 -192.235074)
			(xy 292.546723 -192.196708) (xy 292.553464 -192.120272) (xy 292.55974 -192.08242) (xy 292.561772 -192.071244)
			(xy 292.555676 -192.0494) (xy 292.497764 -191.981074) (xy 292.490073 -191.972858) (xy 292.469639 -191.963497)
			(xy 292.458394 -191.96304) (xy 291.571172 -191.973708) (xy 291.559302 -191.974515) (xy 291.53824 -191.985516)
			(xy 291.530786 -191.99479) (xy 291.475922 -192.070736) (xy 291.472112 -192.094612) (xy 291.475668 -192.106042)
			(xy 291.483844 -192.133386) (xy 291.492643 -192.189775) (xy 291.493194 -192.21831) (xy 291.492678 -192.24591)
			(xy 291.484451 -192.300493) (xy 291.468181 -192.35324) (xy 291.444231 -192.402973) (xy 291.413136 -192.44858)
			(xy 291.375591 -192.489044) (xy 291.332434 -192.523461) (xy 291.28463 -192.55106) (xy 291.233246 -192.571227)
			(xy 291.179431 -192.58351) (xy 291.124386 -192.587635) (xy 291.069341 -192.58351) (xy 291.015526 -192.571227)
			(xy 290.964142 -192.55106) (xy 290.916338 -192.523461) (xy 290.873181 -192.489044) (xy 290.835636 -192.44858)
			(xy 290.804541 -192.402973) (xy 290.780591 -192.35324) (xy 290.764321 -192.300493) (xy 290.756094 -192.24591)
			(xy 290.755578 -192.21831) (xy 290.756064 -192.191969) (xy 290.763581 -192.139827) (xy 290.770564 -192.114424)
			(xy 290.773866 -192.10274) (xy 290.769548 -192.079118) (xy 290.712906 -192.004442) (xy 290.705158 -191.995345)
			(xy 290.683698 -191.984904) (xy 290.671758 -191.984376) (xy 289.788854 -191.99479) (xy 289.777231 -191.995473)
			(xy 289.756457 -192.005933) (xy 289.748976 -192.014856) (xy 289.69335 -192.088262) (xy 289.688778 -192.111122)
			(xy 289.691826 -192.122806) (xy 289.697749 -192.146237) (xy 289.704115 -192.194145) (xy 289.704526 -192.21831)
			(xy 289.70401 -192.24591) (xy 289.695783 -192.300493) (xy 289.679513 -192.35324) (xy 289.655563 -192.402973)
			(xy 289.624468 -192.44858) (xy 289.586923 -192.489044) (xy 289.543766 -192.523461) (xy 289.495962 -192.55106)
			(xy 289.444578 -192.571227) (xy 289.390763 -192.58351) (xy 289.335718 -192.587635) (xy 289.280673 -192.58351)
			(xy 289.226858 -192.571227) (xy 289.175474 -192.55106) (xy 289.12767 -192.523461) (xy 289.084513 -192.489044)
			(xy 289.046968 -192.44858) (xy 289.015873 -192.402973) (xy 288.991923 -192.35324) (xy 288.975653 -192.300493)
			(xy 288.967426 -192.24591) (xy 288.96691 -192.21831) (xy 288.96723 -192.196316) (xy 288.972451 -192.152638)
			(xy 288.977324 -192.131188) (xy 288.980118 -192.119504) (xy 288.975038 -192.096898) (xy 288.917888 -192.024762)
			(xy 288.910172 -192.016045) (xy 288.889136 -192.00613) (xy 288.877502 -192.005712) (xy 288.007044 -192.015872)
			(xy 287.996315 -192.016518) (xy 287.976855 -192.025603) (xy 287.969452 -192.033398) (xy 287.912556 -192.098422)
			(xy 287.906206 -192.118742) (xy 287.907476 -192.129664) (xy 287.910459 -192.155914) (xy 287.913634 -192.208656)
			(xy 287.913826 -192.235074) (xy 287.913336 -192.276801) (xy 287.905385 -192.359874) (xy 287.889572 -192.441815)
			(xy 287.866039 -192.521882) (xy 287.835 -192.599348) (xy 287.81629 -192.636648) (xy 287.811313 -192.647811)
			(xy 287.811319 -192.672217) (xy 287.81629 -192.683384) (xy 287.834968 -192.720697) (xy 287.865987 -192.798166)
			(xy 287.889512 -192.878231) (xy 287.905328 -192.960167) (xy 287.913293 -193.043234) (xy 287.913826 -193.084958)
			(xy 287.913311 -193.127344) (xy 287.905125 -193.21172) (xy 287.888835 -193.294911) (xy 287.864593 -193.376143)
			(xy 287.832625 -193.454656) (xy 287.79323 -193.529718) (xy 287.746775 -193.600628) (xy 287.693694 -193.666724)
			(xy 287.634483 -193.72739) (xy 287.569694 -193.782058) (xy 287.535112 -193.806572) (xy 287.527476 -193.812331)
			(xy 287.516813 -193.828191) (xy 287.512691 -193.846853) (xy 287.513776 -193.856356) (xy 287.51673 -193.875907)
			(xy 287.519911 -193.915324) (xy 287.520126 -193.935096) (xy 287.519636 -193.96693) (xy 287.515844 -193.996305)
			(xy 288.839391 -193.996305) (xy 288.843238 -193.934627) (xy 288.85472 -193.873906) (xy 288.873658 -193.815082)
			(xy 288.89976 -193.759068) (xy 288.932621 -193.706732) (xy 288.971731 -193.658885) (xy 289.016484 -193.616269)
			(xy 289.066185 -193.579545) (xy 289.092894 -193.564002) (xy 289.10407 -193.557906) (xy 289.117532 -193.53657)
			(xy 289.126168 -193.427096) (xy 289.116262 -193.403982) (xy 289.106102 -193.396108) (xy 289.084766 -193.378508)
			(xy 289.047104 -193.338006) (xy 289.015916 -193.29233) (xy 288.991903 -193.242508) (xy 288.975603 -193.189657)
			(xy 288.967383 -193.134964) (xy 288.96691 -193.10731) (xy 288.967426 -193.07971) (xy 288.975653 -193.025127)
			(xy 288.991923 -192.97238) (xy 289.015873 -192.922648) (xy 289.046968 -192.87704) (xy 289.084513 -192.836576)
			(xy 289.12767 -192.802159) (xy 289.175474 -192.77456) (xy 289.226858 -192.754393) (xy 289.280673 -192.74211)
			(xy 289.335718 -192.737985) (xy 289.390763 -192.74211) (xy 289.444578 -192.754393) (xy 289.495962 -192.77456)
			(xy 289.543766 -192.802159) (xy 289.586923 -192.836576) (xy 289.624468 -192.87704) (xy 289.655563 -192.922648)
			(xy 289.679513 -192.97238) (xy 289.695783 -193.025127) (xy 289.70401 -193.07971) (xy 289.704526 -193.10731)
			(xy 289.704034 -193.134961) (xy 289.695795 -193.189647) (xy 289.679488 -193.24249) (xy 289.655478 -193.292308)
			(xy 289.624303 -193.337986) (xy 289.58666 -193.378501) (xy 289.565334 -193.396108) (xy 289.555174 -193.403982)
			(xy 289.545268 -193.427096) (xy 289.553904 -193.53657) (xy 289.567366 -193.557906) (xy 289.578542 -193.564002)
			(xy 289.605258 -193.579532) (xy 289.654959 -193.616259) (xy 289.69971 -193.658877) (xy 289.738818 -193.706726)
			(xy 289.771678 -193.759064) (xy 289.797778 -193.81508) (xy 289.816716 -193.873905) (xy 289.828197 -193.934627)
			(xy 289.832044 -193.996305) (xy 289.828196 -194.057983) (xy 289.816714 -194.118705) (xy 289.797775 -194.177529)
			(xy 289.771673 -194.233544) (xy 289.738813 -194.285882) (xy 289.699703 -194.33373) (xy 289.654951 -194.376347)
			(xy 289.60525 -194.413073) (xy 289.578542 -194.428618) (xy 289.567366 -194.434714) (xy 289.553904 -194.45605)
			(xy 289.545268 -194.565524) (xy 289.555174 -194.588638) (xy 289.565334 -194.596512) (xy 289.586666 -194.614116)
			(xy 289.624331 -194.654616) (xy 289.655521 -194.70029) (xy 289.679536 -194.750112) (xy 289.695835 -194.802963)
			(xy 289.704054 -194.857656) (xy 289.704526 -194.88531) (xy 289.70401 -194.91291) (xy 289.695783 -194.967493)
			(xy 289.679513 -195.02024) (xy 289.655563 -195.069973) (xy 289.624468 -195.11558) (xy 289.586923 -195.156044)
			(xy 289.543766 -195.190461) (xy 289.495962 -195.21806) (xy 289.444578 -195.238227) (xy 289.390763 -195.25051)
			(xy 289.335718 -195.254635) (xy 289.280673 -195.25051) (xy 289.226858 -195.238227) (xy 289.175474 -195.21806)
			(xy 289.12767 -195.190461) (xy 289.084513 -195.156044) (xy 289.046968 -195.11558) (xy 289.015873 -195.069973)
			(xy 288.991923 -195.02024) (xy 288.975653 -194.967493) (xy 288.967426 -194.91291) (xy 288.96691 -194.88531)
			(xy 288.967403 -194.857659) (xy 288.97564 -194.802973) (xy 288.991946 -194.750129) (xy 289.015955 -194.70031)
			(xy 289.047131 -194.654632) (xy 289.084775 -194.614119) (xy 289.106102 -194.596512) (xy 289.116262 -194.588638)
			(xy 289.126168 -194.565524) (xy 289.117532 -194.45605) (xy 289.10407 -194.434714) (xy 289.092894 -194.428618)
			(xy 289.066194 -194.41306) (xy 289.016491 -194.376337) (xy 288.971737 -194.333722) (xy 288.932627 -194.285876)
			(xy 288.899765 -194.23354) (xy 288.873662 -194.177527) (xy 288.854722 -194.118703) (xy 288.843239 -194.057982)
			(xy 288.839391 -193.996305) (xy 287.515844 -193.996305) (xy 287.511485 -194.030073) (xy 287.495317 -194.091654)
			(xy 287.471398 -194.150657) (xy 287.440121 -194.206113) (xy 287.402002 -194.257107) (xy 287.380172 -194.280282)
			(xy 287.37306 -194.287648) (xy 287.365694 -194.305936) (xy 287.36671 -194.397884) (xy 287.374584 -194.416172)
			(xy 287.381696 -194.423284) (xy 287.405179 -194.447247) (xy 287.446285 -194.500274) (xy 287.480063 -194.558245)
			(xy 287.505928 -194.620153) (xy 287.52343 -194.684924) (xy 287.532265 -194.751433) (xy 287.532826 -194.78498)
			(xy 287.532324 -194.816941) (xy 287.524313 -194.880359) (xy 287.508416 -194.942273) (xy 287.484884 -195.001706)
			(xy 287.45409 -195.057721) (xy 287.416517 -195.109436) (xy 287.37276 -195.156033) (xy 287.323507 -195.196778)
			(xy 287.269536 -195.231029) (xy 287.211697 -195.258246) (xy 287.150904 -195.277999) (xy 287.088114 -195.289977)
			(xy 287.024318 -195.293991) (xy 286.960522 -195.289977) (xy 286.897732 -195.277999) (xy 286.836939 -195.258246)
			(xy 286.7791 -195.231029) (xy 286.725129 -195.196778) (xy 286.675876 -195.156033) (xy 286.632119 -195.109436)
			(xy 286.594546 -195.057721) (xy 286.563752 -195.001706) (xy 286.54022 -194.942273) (xy 286.524323 -194.880359)
			(xy 286.516312 -194.816941) (xy 286.51581 -194.78498) (xy 286.516343 -194.75143) (xy 286.525161 -194.684912)
			(xy 286.542655 -194.620133) (xy 286.56852 -194.558218) (xy 286.602307 -194.500246) (xy 286.643428 -194.447222)
			(xy 286.66694 -194.423284) (xy 286.674052 -194.416172) (xy 286.681926 -194.397884) (xy 286.682942 -194.305936)
			(xy 286.675576 -194.287648) (xy 286.668464 -194.280282) (xy 286.646641 -194.257099) (xy 286.608509 -194.206113)
			(xy 286.577224 -194.150661) (xy 286.5533 -194.091658) (xy 286.537133 -194.030076) (xy 286.528989 -193.96693)
			(xy 286.52851 -193.935096) (xy 286.528798 -193.911647) (xy 286.533253 -193.86496) (xy 286.5374 -193.841878)
			(xy 286.538829 -193.83239) (xy 286.535304 -193.813543) (xy 286.525085 -193.79732) (xy 286.517588 -193.791332)
			(xy 286.485543 -193.767207) (xy 286.425531 -193.713978) (xy 286.37063 -193.655491) (xy 286.321299 -193.592237)
			(xy 286.277949 -193.524742) (xy 286.240942 -193.453571) (xy 286.210589 -193.379318) (xy 286.187142 -193.302605)
			(xy 286.170797 -193.22407) (xy 286.165798 -193.184272) (xy 286.164528 -193.17335) (xy 286.154114 -193.155316)
			(xy 286.076644 -193.09842) (xy 286.05607 -193.093848) (xy 286.045656 -193.09588) (xy 286.004407 -193.103363)
			(xy 285.920951 -193.111375) (xy 285.879032 -193.111882) (xy 285.835982 -193.111372) (xy 285.750296 -193.102936)
			(xy 285.665849 -193.086141) (xy 285.583455 -193.061149) (xy 285.503908 -193.028201) (xy 285.427974 -192.987615)
			(xy 285.356383 -192.939781) (xy 285.289826 -192.88516) (xy 285.228944 -192.824278) (xy 285.174322 -192.757721)
			(xy 285.126488 -192.686131) (xy 285.085901 -192.610197) (xy 285.052953 -192.53065) (xy 285.027961 -192.448257)
			(xy 285.011165 -192.36381) (xy 285.002728 -192.278124) (xy 285.002224 -192.235074) (xy 285.002333 -192.216955)
			(xy 285.003856 -192.180748) (xy 285.005272 -192.162684) (xy 285.006034 -192.152016) (xy 284.999176 -192.13195)
			(xy 284.940502 -192.068958) (xy 284.932921 -192.061445) (xy 284.913325 -192.053035) (xy 284.902656 -192.052702)
			(xy 284.046422 -192.062862) (xy 284.035716 -192.063446) (xy 284.016254 -192.072397) (xy 284.00883 -192.080134)
			(xy 283.951934 -192.144904) (xy 283.945584 -192.165224) (xy 283.9466 -192.176146) (xy 283.94776 -192.186649)
			(xy 283.949028 -192.207744) (xy 283.94914 -192.21831) (xy 283.948624 -192.24591) (xy 283.940397 -192.300493)
			(xy 283.924127 -192.35324) (xy 283.900177 -192.402973) (xy 283.869082 -192.44858) (xy 283.831537 -192.489044)
			(xy 283.78838 -192.523461) (xy 283.740576 -192.55106) (xy 283.689192 -192.571227) (xy 283.635377 -192.58351)
			(xy 283.580332 -192.587635) (xy 283.525287 -192.58351) (xy 283.471472 -192.571227) (xy 283.420088 -192.55106)
			(xy 283.372284 -192.523461) (xy 283.329127 -192.489044) (xy 283.291582 -192.44858) (xy 283.260487 -192.402973)
			(xy 283.236537 -192.35324) (xy 283.220267 -192.300493) (xy 283.21204 -192.24591) (xy 283.211524 -192.21831)
			(xy 283.213048 -192.184782) (xy 283.214064 -192.174114) (xy 283.207206 -192.153794) (xy 283.148532 -192.090294)
			(xy 283.140955 -192.082771) (xy 283.121358 -192.074344) (xy 283.110686 -192.074038) (xy 282.259786 -192.084198)
			(xy 282.249406 -192.084803) (xy 282.230403 -192.093197) (xy 282.222956 -192.100454) (xy 282.165552 -192.162684)
			(xy 282.158948 -192.181988) (xy 282.15971 -192.19291) (xy 282.160472 -192.21831) (xy 282.159956 -192.24591)
			(xy 282.151729 -192.300493) (xy 282.135459 -192.35324) (xy 282.111509 -192.402973) (xy 282.080414 -192.44858)
			(xy 282.042869 -192.489044) (xy 281.999712 -192.523461) (xy 281.951908 -192.55106) (xy 281.900524 -192.571227)
			(xy 281.846709 -192.58351) (xy 281.791664 -192.587635) (xy 281.736619 -192.58351) (xy 281.682804 -192.571227)
			(xy 281.63142 -192.55106) (xy 281.583616 -192.523461) (xy 281.540459 -192.489044) (xy 281.502914 -192.44858)
			(xy 281.471819 -192.402973) (xy 281.447869 -192.35324) (xy 281.431599 -192.300493) (xy 281.423372 -192.24591)
			(xy 281.422856 -192.21831) (xy 281.423364 -192.201546) (xy 281.423618 -192.190878) (xy 281.416506 -192.171574)
			(xy 281.357578 -192.110868) (xy 281.350022 -192.103739) (xy 281.330876 -192.095731) (xy 281.320494 -192.095374)
			(xy 280.469848 -192.105534) (xy 280.459734 -192.106077) (xy 280.441142 -192.114071) (xy 280.43378 -192.121028)
			(xy 280.376376 -192.180718) (xy 280.36901 -192.199514) (xy 280.369518 -192.209928) (xy 280.369772 -192.235074)
			(xy 280.369282 -192.2768) (xy 280.361331 -192.359874) (xy 280.345516 -192.441815) (xy 280.321982 -192.521881)
			(xy 280.290942 -192.599346) (xy 280.272236 -192.636648) (xy 280.267255 -192.647811) (xy 280.267262 -192.672217)
			(xy 280.272236 -192.683384) (xy 280.290915 -192.720697) (xy 280.321936 -192.798166) (xy 280.345462 -192.87823)
			(xy 280.361279 -192.960166) (xy 280.369245 -193.043234) (xy 280.369772 -193.084958) (xy 280.369257 -193.127344)
			(xy 280.361071 -193.211718) (xy 280.34478 -193.294909) (xy 280.320537 -193.37614) (xy 280.288568 -193.454652)
			(xy 280.249171 -193.529712) (xy 280.202715 -193.60062) (xy 280.149632 -193.666713) (xy 280.090419 -193.727376)
			(xy 280.025627 -193.782041) (xy 279.991058 -193.806572) (xy 279.983417 -193.812328) (xy 279.972744 -193.828188)
			(xy 279.968618 -193.846853) (xy 279.969722 -193.856356) (xy 279.972676 -193.875907) (xy 279.975857 -193.915324)
			(xy 279.976072 -193.935096) (xy 279.975582 -193.96693) (xy 279.971791 -193.996305) (xy 281.295365 -193.996305)
			(xy 281.299211 -193.93463) (xy 281.310691 -193.87391) (xy 281.329628 -193.815088) (xy 281.355726 -193.759075)
			(xy 281.388583 -193.706739) (xy 281.427689 -193.658891) (xy 281.472437 -193.616274) (xy 281.522134 -193.579547)
			(xy 281.54884 -193.564002) (xy 281.560016 -193.557906) (xy 281.573478 -193.53657) (xy 281.582114 -193.427096)
			(xy 281.572208 -193.403982) (xy 281.562048 -193.396108) (xy 281.540721 -193.378497) (xy 281.503057 -193.337998)
			(xy 281.471867 -193.292325) (xy 281.447852 -193.242505) (xy 281.43155 -193.189656) (xy 281.423329 -193.134964)
			(xy 281.422856 -193.10731) (xy 281.423372 -193.07971) (xy 281.431599 -193.025127) (xy 281.447869 -192.97238)
			(xy 281.471819 -192.922648) (xy 281.502914 -192.87704) (xy 281.540459 -192.836576) (xy 281.583616 -192.802159)
			(xy 281.63142 -192.77456) (xy 281.682804 -192.754393) (xy 281.736619 -192.74211) (xy 281.791664 -192.737985)
			(xy 281.846709 -192.74211) (xy 281.900524 -192.754393) (xy 281.951908 -192.77456) (xy 281.999712 -192.802159)
			(xy 282.042869 -192.836576) (xy 282.080414 -192.87704) (xy 282.111509 -192.922648) (xy 282.135459 -192.97238)
			(xy 282.151729 -193.025127) (xy 282.159956 -193.07971) (xy 282.160472 -193.10731) (xy 282.16 -193.134962)
			(xy 282.15176 -193.189649) (xy 282.13545 -193.242494) (xy 282.111436 -193.292313) (xy 282.080257 -193.33799)
			(xy 282.042609 -193.378502) (xy 282.02128 -193.396108) (xy 282.01112 -193.403982) (xy 282.001214 -193.427096)
			(xy 282.00985 -193.53657) (xy 282.023312 -193.557906) (xy 282.034488 -193.564002) (xy 282.061207 -193.57953)
			(xy 282.110912 -193.616254) (xy 282.155668 -193.658871) (xy 282.194781 -193.706719) (xy 282.227644 -193.759058)
			(xy 282.253748 -193.815074) (xy 282.272688 -193.8739) (xy 282.28417 -193.934625) (xy 282.288017 -193.996305)
			(xy 282.284169 -194.057985) (xy 282.272685 -194.118709) (xy 282.253744 -194.177535) (xy 282.227639 -194.233551)
			(xy 282.194775 -194.285889) (xy 282.155661 -194.333736) (xy 282.110905 -194.376352) (xy 282.061199 -194.413075)
			(xy 282.034488 -194.428618) (xy 282.023312 -194.434714) (xy 282.00985 -194.45605) (xy 282.001214 -194.565524)
			(xy 282.01112 -194.588638) (xy 282.02128 -194.596512) (xy 282.042622 -194.614105) (xy 282.080284 -194.654609)
			(xy 282.111472 -194.700285) (xy 282.135484 -194.750109) (xy 282.151782 -194.802961) (xy 282.16 -194.857655)
			(xy 282.160472 -194.88531) (xy 282.159956 -194.91291) (xy 282.151729 -194.967493) (xy 282.135459 -195.02024)
			(xy 282.111509 -195.069973) (xy 282.080414 -195.11558) (xy 282.042869 -195.156044) (xy 281.999712 -195.190461)
			(xy 281.951908 -195.21806) (xy 281.900524 -195.238227) (xy 281.846709 -195.25051) (xy 281.791664 -195.254635)
			(xy 281.736619 -195.25051) (xy 281.682804 -195.238227) (xy 281.63142 -195.21806) (xy 281.583616 -195.190461)
			(xy 281.540459 -195.156044) (xy 281.502914 -195.11558) (xy 281.471819 -195.069973) (xy 281.447869 -195.02024)
			(xy 281.431599 -194.967493) (xy 281.423372 -194.91291) (xy 281.422856 -194.88531) (xy 281.423369 -194.85766)
			(xy 281.431604 -194.802976) (xy 281.447908 -194.750133) (xy 281.471914 -194.700314) (xy 281.503085 -194.654636)
			(xy 281.540724 -194.61412) (xy 281.562048 -194.596512) (xy 281.572208 -194.588638) (xy 281.582114 -194.565524)
			(xy 281.573478 -194.45605) (xy 281.560016 -194.434714) (xy 281.54884 -194.428618) (xy 281.522142 -194.413058)
			(xy 281.472444 -194.376332) (xy 281.427695 -194.333716) (xy 281.388589 -194.285869) (xy 281.355731 -194.233534)
			(xy 281.329631 -194.177521) (xy 281.310694 -194.118699) (xy 281.299212 -194.05798) (xy 281.295365 -193.996305)
			(xy 279.971791 -193.996305) (xy 279.967432 -194.030074) (xy 279.951265 -194.091655) (xy 279.927347 -194.15066)
			(xy 279.896073 -194.206118) (xy 279.857956 -194.257115) (xy 279.836118 -194.280282) (xy 279.829006 -194.287648)
			(xy 279.82164 -194.305936) (xy 279.822656 -194.397884) (xy 279.83053 -194.416172) (xy 279.837642 -194.423284)
			(xy 279.861127 -194.447246) (xy 279.902237 -194.500272) (xy 279.936019 -194.558242) (xy 279.961886 -194.62015)
			(xy 279.97939 -194.684922) (xy 279.988227 -194.751433) (xy 279.988772 -194.78498) (xy 279.98827 -194.816941)
			(xy 279.980259 -194.880359) (xy 279.964362 -194.942273) (xy 279.94083 -195.001706) (xy 279.910036 -195.057721)
			(xy 279.872463 -195.109436) (xy 279.828706 -195.156033) (xy 279.779453 -195.196778) (xy 279.725482 -195.231029)
			(xy 279.667643 -195.258246) (xy 279.60685 -195.277999) (xy 279.54406 -195.289977) (xy 279.480264 -195.293991)
			(xy 279.416468 -195.289977) (xy 279.353678 -195.277999) (xy 279.292885 -195.258246) (xy 279.235046 -195.231029)
			(xy 279.181075 -195.196778) (xy 279.131822 -195.156033) (xy 279.088065 -195.109436) (xy 279.050492 -195.057721)
			(xy 279.019698 -195.001706) (xy 278.996166 -194.942273) (xy 278.980269 -194.880359) (xy 278.972258 -194.816941)
			(xy 278.971756 -194.78498) (xy 278.972289 -194.75143) (xy 278.981108 -194.684913) (xy 278.998603 -194.620135)
			(xy 279.02447 -194.558222) (xy 279.058259 -194.500251) (xy 279.099382 -194.44723) (xy 279.122886 -194.423284)
			(xy 279.129998 -194.416172) (xy 279.137872 -194.397884) (xy 279.138888 -194.305936) (xy 279.131522 -194.287648)
			(xy 279.12441 -194.280282) (xy 279.102586 -194.2571) (xy 279.06445 -194.206115) (xy 279.033161 -194.150663)
			(xy 279.009236 -194.09166) (xy 278.993067 -194.030078) (xy 278.984923 -193.966931) (xy 278.984456 -193.935096)
			(xy 278.984744 -193.911647) (xy 278.9892 -193.86496) (xy 278.993346 -193.841878) (xy 278.994775 -193.832389)
			(xy 278.991252 -193.81354) (xy 278.981039 -193.797311) (xy 278.973534 -193.791332) (xy 278.941491 -193.767206)
			(xy 278.881482 -193.713975) (xy 278.826584 -193.655487) (xy 278.777256 -193.592231) (xy 278.733908 -193.524736)
			(xy 278.696904 -193.453566) (xy 278.666553 -193.379314) (xy 278.643108 -193.3026) (xy 278.626764 -193.224067)
			(xy 278.621744 -193.184272) (xy 278.620474 -193.173604) (xy 278.61006 -193.155316) (xy 278.53259 -193.09842)
			(xy 278.51227 -193.093848) (xy 278.501602 -193.09588) (xy 278.460414 -193.103339) (xy 278.377087 -193.111354)
			(xy 278.335232 -193.111882) (xy 278.29243 -193.111363) (xy 278.207234 -193.103014) (xy 278.123256 -193.086403)
			(xy 278.041298 -193.061688) (xy 277.962137 -193.029103) (xy 277.886529 -192.988959) (xy 277.815193 -192.941639)
			(xy 277.748807 -192.887592) (xy 277.688005 -192.827333) (xy 277.633363 -192.761436) (xy 277.585404 -192.690528)
			(xy 277.544582 -192.615283) (xy 277.511288 -192.536419) (xy 277.485837 -192.454686) (xy 277.468471 -192.370861)
			(xy 277.459358 -192.285743) (xy 277.458424 -192.242948) (xy 277.458424 -192.232788) (xy 277.45055 -192.214246)
			(xy 277.391876 -192.156842) (xy 277.384373 -192.150092) (xy 277.365643 -192.14262) (xy 277.355554 -192.142364)
			(xy 276.5044 -192.152524) (xy 276.494933 -192.153068) (xy 276.477345 -192.160109) (xy 276.47011 -192.16624)
			(xy 276.413214 -192.219834) (xy 276.405086 -192.236852) (xy 276.404324 -192.24625) (xy 276.401721 -192.273713)
			(xy 276.389393 -192.327482) (xy 276.369194 -192.378814) (xy 276.341574 -192.426565) (xy 276.30715 -192.46967)
			(xy 276.266688 -192.507165) (xy 276.221094 -192.538215) (xy 276.171382 -192.562128) (xy 276.118664 -192.578368)
			(xy 276.064114 -192.586575) (xy 276.036532 -192.587118) (xy 276.009397 -192.586632) (xy 275.955714 -192.578672)
			(xy 275.903777 -192.562932) (xy 275.854706 -192.539753) (xy 275.80956 -192.509636) (xy 275.769313 -192.473229)
			(xy 275.734834 -192.431319) (xy 275.706868 -192.38481) (xy 275.686017 -192.334706) (xy 275.672731 -192.282087)
			(xy 275.669502 -192.25514) (xy 275.668486 -192.245488) (xy 275.660104 -192.228724) (xy 275.601684 -192.176654)
			(xy 275.594382 -192.17072) (xy 275.576796 -192.164075) (xy 275.567394 -192.1637) (xy 274.646136 -192.174622)
			(xy 274.616926 -192.203578) (xy 274.616672 -192.224406) (xy 274.61579 -192.250462) (xy 274.607593 -192.301947)
			(xy 274.592225 -192.351765) (xy 274.569994 -192.398921) (xy 274.541342 -192.442475) (xy 274.50684 -192.48156)
			(xy 274.467177 -192.515395) (xy 274.423144 -192.543305) (xy 274.375618 -192.564735) (xy 274.325548 -192.579257)
			(xy 274.273931 -192.586582) (xy 274.247864 -192.587118) (xy 274.219619 -192.586577) (xy 274.163791 -192.57796)
			(xy 274.10993 -192.560933) (xy 274.059293 -192.535893) (xy 274.013066 -192.503427) (xy 273.972328 -192.464293)
			(xy 273.938033 -192.419406) (xy 273.910981 -192.369815) (xy 273.891806 -192.31668) (xy 273.880955 -192.261243)
			(xy 273.87931 -192.233042) (xy 273.878548 -192.212468) (xy 273.848576 -192.18402) (xy 272.855182 -192.195704)
			(xy 272.826226 -192.224914) (xy 272.825972 -192.245742) (xy 272.824991 -192.286392) (xy 272.816426 -192.367258)
			(xy 272.800412 -192.446985) (xy 272.777087 -192.524886) (xy 272.746651 -192.600294) (xy 272.728436 -192.636648)
			(xy 272.723455 -192.647811) (xy 272.723462 -192.672217) (xy 272.728436 -192.683384) (xy 272.747115 -192.720697)
			(xy 272.778136 -192.798166) (xy 272.801662 -192.87823) (xy 272.817479 -192.960166) (xy 272.825445 -193.043234)
			(xy 272.825972 -193.084958) (xy 272.825457 -193.127344) (xy 272.817271 -193.211718) (xy 272.80098 -193.294909)
			(xy 272.776737 -193.37614) (xy 272.744768 -193.454652) (xy 272.705371 -193.529712) (xy 272.658915 -193.60062)
			(xy 272.605832 -193.666713) (xy 272.546619 -193.727376) (xy 272.481827 -193.782041) (xy 272.447258 -193.806572)
			(xy 272.439617 -193.812328) (xy 272.428944 -193.828188) (xy 272.424818 -193.846853) (xy 272.425922 -193.856356)
			(xy 272.428876 -193.875907) (xy 272.432057 -193.915324) (xy 272.432272 -193.935096) (xy 272.431782 -193.96693)
			(xy 272.427991 -193.996305) (xy 273.751565 -193.996305) (xy 273.755411 -193.93463) (xy 273.766891 -193.87391)
			(xy 273.785828 -193.815088) (xy 273.811926 -193.759075) (xy 273.844783 -193.706739) (xy 273.883889 -193.658891)
			(xy 273.928637 -193.616274) (xy 273.978334 -193.579547) (xy 274.00504 -193.564002) (xy 274.016216 -193.557906)
			(xy 274.029678 -193.53657) (xy 274.038314 -193.427096) (xy 274.028408 -193.403982) (xy 274.018248 -193.396108)
			(xy 273.996921 -193.378497) (xy 273.959257 -193.337998) (xy 273.928067 -193.292325) (xy 273.904052 -193.242505)
			(xy 273.88775 -193.189656) (xy 273.879529 -193.134964) (xy 273.879056 -193.10731) (xy 273.879572 -193.07971)
			(xy 273.887799 -193.025127) (xy 273.904069 -192.97238) (xy 273.928019 -192.922648) (xy 273.959114 -192.87704)
			(xy 273.996659 -192.836576) (xy 274.039816 -192.802159) (xy 274.08762 -192.77456) (xy 274.139004 -192.754393)
			(xy 274.192819 -192.74211) (xy 274.247864 -192.737985) (xy 274.302909 -192.74211) (xy 274.356724 -192.754393)
			(xy 274.408108 -192.77456) (xy 274.455912 -192.802159) (xy 274.499069 -192.836576) (xy 274.536614 -192.87704)
			(xy 274.567709 -192.922648) (xy 274.591659 -192.97238) (xy 274.607929 -193.025127) (xy 274.616156 -193.07971)
			(xy 274.616672 -193.10731) (xy 274.6162 -193.134962) (xy 274.60796 -193.189649) (xy 274.59165 -193.242494)
			(xy 274.567636 -193.292313) (xy 274.536457 -193.33799) (xy 274.498809 -193.378502) (xy 274.47748 -193.396108)
			(xy 274.46732 -193.403982) (xy 274.457414 -193.427096) (xy 274.46605 -193.53657) (xy 274.479512 -193.557906)
			(xy 274.490688 -193.564002) (xy 274.517407 -193.57953) (xy 274.567112 -193.616254) (xy 274.611868 -193.658871)
			(xy 274.650981 -193.706719) (xy 274.683844 -193.759058) (xy 274.709948 -193.815074) (xy 274.728888 -193.8739)
			(xy 274.74037 -193.934625) (xy 274.744217 -193.996305) (xy 274.740369 -194.057985) (xy 274.728885 -194.118709)
			(xy 274.709944 -194.177535) (xy 274.683839 -194.233551) (xy 274.650975 -194.285889) (xy 274.611861 -194.333736)
			(xy 274.567105 -194.376352) (xy 274.517399 -194.413075) (xy 274.490688 -194.428618) (xy 274.479512 -194.434714)
			(xy 274.46605 -194.45605) (xy 274.457414 -194.565524) (xy 274.46732 -194.588638) (xy 274.47748 -194.596512)
			(xy 274.498822 -194.614105) (xy 274.536484 -194.654609) (xy 274.567672 -194.700285) (xy 274.591684 -194.750109)
			(xy 274.607982 -194.802961) (xy 274.6162 -194.857655) (xy 274.616672 -194.88531) (xy 274.616156 -194.91291)
			(xy 274.607929 -194.967493) (xy 274.591659 -195.02024) (xy 274.567709 -195.069973) (xy 274.536614 -195.11558)
			(xy 274.499069 -195.156044) (xy 274.455912 -195.190461) (xy 274.408108 -195.21806) (xy 274.356724 -195.238227)
			(xy 274.302909 -195.25051) (xy 274.247864 -195.254635) (xy 274.192819 -195.25051) (xy 274.139004 -195.238227)
			(xy 274.08762 -195.21806) (xy 274.039816 -195.190461) (xy 273.996659 -195.156044) (xy 273.959114 -195.11558)
			(xy 273.928019 -195.069973) (xy 273.904069 -195.02024) (xy 273.887799 -194.967493) (xy 273.879572 -194.91291)
			(xy 273.879056 -194.88531) (xy 273.879569 -194.85766) (xy 273.887804 -194.802976) (xy 273.904108 -194.750133)
			(xy 273.928114 -194.700314) (xy 273.959285 -194.654636) (xy 273.996924 -194.61412) (xy 274.018248 -194.596512)
			(xy 274.028408 -194.588638) (xy 274.038314 -194.565524) (xy 274.029678 -194.45605) (xy 274.016216 -194.434714)
			(xy 274.00504 -194.428618) (xy 273.978342 -194.413058) (xy 273.928644 -194.376332) (xy 273.883895 -194.333716)
			(xy 273.844789 -194.285869) (xy 273.811931 -194.233534) (xy 273.785831 -194.177521) (xy 273.766894 -194.118699)
			(xy 273.755412 -194.05798) (xy 273.751565 -193.996305) (xy 272.427991 -193.996305) (xy 272.423632 -194.030074)
			(xy 272.407465 -194.091655) (xy 272.383547 -194.15066) (xy 272.352273 -194.206118) (xy 272.314156 -194.257115)
			(xy 272.292318 -194.280282) (xy 272.285206 -194.287648) (xy 272.27784 -194.305936) (xy 272.278856 -194.397884)
			(xy 272.28673 -194.416172) (xy 272.293842 -194.423284) (xy 272.317327 -194.447246) (xy 272.358437 -194.500272)
			(xy 272.392219 -194.558242) (xy 272.418086 -194.62015) (xy 272.43559 -194.684922) (xy 272.444427 -194.751433)
			(xy 272.444972 -194.78498) (xy 272.44447 -194.816941) (xy 272.436459 -194.880359) (xy 272.420562 -194.942273)
			(xy 272.39703 -195.001706) (xy 272.366236 -195.057721) (xy 272.328663 -195.109436) (xy 272.284906 -195.156033)
			(xy 272.235653 -195.196778) (xy 272.181682 -195.231029) (xy 272.123843 -195.258246) (xy 272.06305 -195.277999)
			(xy 272.00026 -195.289977) (xy 271.936464 -195.293991) (xy 271.872668 -195.289977) (xy 271.809878 -195.277999)
			(xy 271.749085 -195.258246) (xy 271.691246 -195.231029) (xy 271.637275 -195.196778) (xy 271.588022 -195.156033)
			(xy 271.544265 -195.109436) (xy 271.506692 -195.057721) (xy 271.475898 -195.001706) (xy 271.452366 -194.942273)
			(xy 271.436469 -194.880359) (xy 271.428458 -194.816941) (xy 271.427956 -194.78498) (xy 271.428489 -194.75143)
			(xy 271.437308 -194.684913) (xy 271.454803 -194.620135) (xy 271.48067 -194.558222) (xy 271.514459 -194.500251)
			(xy 271.555582 -194.44723) (xy 271.579086 -194.423284) (xy 271.586198 -194.416172) (xy 271.594072 -194.397884)
			(xy 271.595088 -194.305936) (xy 271.587722 -194.287648) (xy 271.58061 -194.280282) (xy 271.558786 -194.2571)
			(xy 271.52065 -194.206115) (xy 271.489361 -194.150663) (xy 271.465436 -194.09166) (xy 271.449267 -194.030078)
			(xy 271.441123 -193.966931) (xy 271.440656 -193.935096) (xy 271.440944 -193.911647) (xy 271.4454 -193.86496)
			(xy 271.449546 -193.841878) (xy 271.450975 -193.832389) (xy 271.447452 -193.81354) (xy 271.437239 -193.797311)
			(xy 271.429734 -193.791332) (xy 271.397691 -193.767206) (xy 271.337682 -193.713975) (xy 271.282784 -193.655487)
			(xy 271.233456 -193.592231) (xy 271.190108 -193.524736) (xy 271.153104 -193.453566) (xy 271.122753 -193.379314)
			(xy 271.099308 -193.3026) (xy 271.082964 -193.224067) (xy 271.077944 -193.184272) (xy 271.076674 -193.17335)
			(xy 271.06626 -193.155316) (xy 270.98879 -193.09842) (xy 270.968216 -193.093848) (xy 270.957802 -193.09588)
			(xy 270.916553 -193.103365) (xy 270.833098 -193.111382) (xy 270.791178 -193.111882) (xy 270.74952 -193.111384)
			(xy 270.666581 -193.10347) (xy 270.584766 -193.087727) (xy 270.504814 -193.064294) (xy 270.427444 -193.033385)
			(xy 270.353354 -192.995277) (xy 270.283212 -192.950313) (xy 270.217651 -192.898901) (xy 270.157262 -192.841502)
			(xy 270.102589 -192.778634) (xy 270.054125 -192.710864) (xy 270.012306 -192.638803) (xy 269.977511 -192.563101)
			(xy 269.950052 -192.484441) (xy 269.930177 -192.40353) (xy 269.918065 -192.321099) (xy 269.915386 -192.279524)
			(xy 269.91437 -192.25895) (xy 269.884906 -192.23101) (xy 268.886432 -192.242948) (xy 268.858492 -192.26657)
			(xy 268.85519 -192.28435) (xy 268.849585 -192.312311) (xy 268.830903 -192.366188) (xy 268.804144 -192.416543)
			(xy 268.769947 -192.462175) (xy 268.729128 -192.501995) (xy 268.682663 -192.535051) (xy 268.631659 -192.560554)
			(xy 268.577336 -192.577895) (xy 268.52099 -192.586661) (xy 268.492478 -192.587118) (xy 268.464457 -192.586594)
			(xy 268.409061 -192.578113) (xy 268.355586 -192.561348) (xy 268.305263 -192.536686) (xy 268.25925 -192.504694)
			(xy 268.218607 -192.46611) (xy 268.184269 -192.421821) (xy 268.157026 -192.372846) (xy 268.137507 -192.320314)
			(xy 268.13129 -192.292986) (xy 268.127734 -192.275206) (xy 268.099286 -192.252346) (xy 267.093954 -192.264284)
			(xy 267.066776 -192.285874) (xy 267.062712 -192.303146) (xy 267.055909 -192.329735) (xy 267.035508 -192.380683)
			(xy 267.007782 -192.428046) (xy 266.973344 -192.470777) (xy 266.932953 -192.507933) (xy 266.887503 -192.538693)
			(xy 266.837996 -192.562378) (xy 266.785526 -192.578466) (xy 266.731251 -192.5866) (xy 266.70381 -192.587118)
			(xy 266.676846 -192.586627) (xy 266.623492 -192.578777) (xy 266.57185 -192.563242) (xy 266.523019 -192.540354)
			(xy 266.478042 -192.510601) (xy 266.437875 -192.474616) (xy 266.403376 -192.433166) (xy 266.37528 -192.387135)
			(xy 266.354184 -192.337504) (xy 266.34694 -192.311528) (xy 266.342622 -192.29451) (xy 266.314936 -192.273428)
			(xy 265.307318 -192.285366) (xy 265.27887 -192.311274) (xy 265.276838 -192.330578) (xy 265.271975 -192.370484)
			(xy 265.25587 -192.449251) (xy 265.232624 -192.526214) (xy 265.20243 -192.600726) (xy 265.184382 -192.636648)
			(xy 265.179405 -192.647812) (xy 265.179412 -192.672217) (xy 265.184382 -192.683384) (xy 265.20306 -192.720697)
			(xy 265.23408 -192.798166) (xy 265.257604 -192.87823) (xy 265.27342 -192.960166) (xy 265.281385 -193.043234)
			(xy 265.281918 -193.084958) (xy 265.281403 -193.127344) (xy 265.273217 -193.211719) (xy 265.256927 -193.294911)
			(xy 265.232685 -193.376143) (xy 265.200717 -193.454656) (xy 265.161321 -193.529717) (xy 265.114866 -193.600627)
			(xy 265.061785 -193.666723) (xy 265.002573 -193.727388) (xy 264.937784 -193.782055) (xy 264.903204 -193.806572)
			(xy 264.895569 -193.812331) (xy 264.884908 -193.828192) (xy 264.880787 -193.846853) (xy 264.881868 -193.856356)
			(xy 264.884822 -193.875907) (xy 264.888003 -193.915324) (xy 264.888218 -193.935096) (xy 264.887728 -193.96693)
			(xy 264.883936 -193.996305) (xy 266.207487 -193.996305) (xy 266.211334 -193.934628) (xy 266.222815 -193.873907)
			(xy 266.241754 -193.815083) (xy 266.267855 -193.759069) (xy 266.300715 -193.706733) (xy 266.339825 -193.658886)
			(xy 266.384577 -193.61627) (xy 266.434278 -193.579546) (xy 266.460986 -193.564002) (xy 266.472162 -193.557906)
			(xy 266.485624 -193.53657) (xy 266.49426 -193.427096) (xy 266.484354 -193.403982) (xy 266.474194 -193.396108)
			(xy 266.452877 -193.378485) (xy 266.41521 -193.33799) (xy 266.384018 -193.29232) (xy 266.36 -193.242502)
			(xy 266.343698 -193.189654) (xy 266.335476 -193.134963) (xy 266.335002 -193.10731) (xy 266.335518 -193.07971)
			(xy 266.343745 -193.025127) (xy 266.360015 -192.97238) (xy 266.383965 -192.922648) (xy 266.41506 -192.87704)
			(xy 266.452605 -192.836576) (xy 266.495762 -192.802159) (xy 266.543566 -192.77456) (xy 266.59495 -192.754393)
			(xy 266.648765 -192.74211) (xy 266.70381 -192.737985) (xy 266.758855 -192.74211) (xy 266.81267 -192.754393)
			(xy 266.864054 -192.77456) (xy 266.911858 -192.802159) (xy 266.955015 -192.836576) (xy 266.99256 -192.87704)
			(xy 267.023655 -192.922648) (xy 267.047605 -192.97238) (xy 267.063875 -193.025127) (xy 267.072102 -193.07971)
			(xy 267.072618 -193.10731) (xy 267.072129 -193.134961) (xy 267.06389 -193.189647) (xy 267.047582 -193.242491)
			(xy 267.023572 -193.292309) (xy 266.992396 -193.337987) (xy 266.954753 -193.378501) (xy 266.933426 -193.396108)
			(xy 266.923266 -193.403982) (xy 266.91336 -193.427096) (xy 266.921996 -193.53657) (xy 266.935458 -193.557906)
			(xy 266.946634 -193.564002) (xy 266.973351 -193.579532) (xy 267.023052 -193.616258) (xy 267.067804 -193.658876)
			(xy 267.106913 -193.706725) (xy 267.139773 -193.759063) (xy 267.165874 -193.815079) (xy 267.184812 -193.873904)
			(xy 267.196293 -193.934626) (xy 267.20014 -193.996305) (xy 267.196292 -194.057983) (xy 267.18481 -194.118706)
			(xy 267.16587 -194.17753) (xy 267.139768 -194.233545) (xy 267.106907 -194.285883) (xy 267.067797 -194.333731)
			(xy 267.023044 -194.376348) (xy 266.973343 -194.413074) (xy 266.946634 -194.428618) (xy 266.935458 -194.434714)
			(xy 266.921996 -194.45605) (xy 266.91336 -194.565524) (xy 266.923266 -194.588638) (xy 266.933426 -194.596512)
			(xy 266.954756 -194.614119) (xy 266.992422 -194.654618) (xy 267.023612 -194.700291) (xy 267.047627 -194.750112)
			(xy 267.063927 -194.802963) (xy 267.072146 -194.857656) (xy 267.072618 -194.88531) (xy 267.072102 -194.91291)
			(xy 267.063875 -194.967493) (xy 267.047605 -195.02024) (xy 267.023655 -195.069973) (xy 266.99256 -195.11558)
			(xy 266.955015 -195.156044) (xy 266.911858 -195.190461) (xy 266.864054 -195.21806) (xy 266.81267 -195.238227)
			(xy 266.758855 -195.25051) (xy 266.70381 -195.254635) (xy 266.648765 -195.25051) (xy 266.59495 -195.238227)
			(xy 266.543566 -195.21806) (xy 266.495762 -195.190461) (xy 266.452605 -195.156044) (xy 266.41506 -195.11558)
			(xy 266.383965 -195.069973) (xy 266.360015 -195.02024) (xy 266.343745 -194.967493) (xy 266.335518 -194.91291)
			(xy 266.335002 -194.88531) (xy 266.335498 -194.857659) (xy 266.343734 -194.802973) (xy 266.36004 -194.750129)
			(xy 266.384049 -194.700311) (xy 266.415224 -194.654633) (xy 266.452867 -194.614119) (xy 266.474194 -194.596512)
			(xy 266.484354 -194.588638) (xy 266.49426 -194.565524) (xy 266.485624 -194.45605) (xy 266.472162 -194.434714)
			(xy 266.460986 -194.428618) (xy 266.434286 -194.41306) (xy 266.384584 -194.376336) (xy 266.339831 -194.333721)
			(xy 266.300721 -194.285875) (xy 266.26786 -194.233539) (xy 266.241757 -194.177526) (xy 266.222818 -194.118703)
			(xy 266.211335 -194.057982) (xy 266.207487 -193.996305) (xy 264.883936 -193.996305) (xy 264.879577 -194.030073)
			(xy 264.863409 -194.091653) (xy 264.839489 -194.150657) (xy 264.808212 -194.206112) (xy 264.770093 -194.257106)
			(xy 264.748264 -194.280282) (xy 264.741152 -194.287648) (xy 264.733786 -194.305936) (xy 264.734802 -194.397884)
			(xy 264.742676 -194.416172) (xy 264.749788 -194.423284) (xy 264.773271 -194.447247) (xy 264.814378 -194.500274)
			(xy 264.848157 -194.558245) (xy 264.874022 -194.620153) (xy 264.891524 -194.684924) (xy 264.90036 -194.751433)
			(xy 264.900918 -194.78498) (xy 264.900416 -194.816941) (xy 264.892405 -194.880359) (xy 264.876508 -194.942273)
			(xy 264.852976 -195.001706) (xy 264.822182 -195.057721) (xy 264.784609 -195.109436) (xy 264.740852 -195.156033)
			(xy 264.691599 -195.196778) (xy 264.637628 -195.231029) (xy 264.579789 -195.258246) (xy 264.518996 -195.277999)
			(xy 264.456206 -195.289977) (xy 264.39241 -195.293991) (xy 264.328614 -195.289977) (xy 264.265824 -195.277999)
			(xy 264.205031 -195.258246) (xy 264.147192 -195.231029) (xy 264.093221 -195.196778) (xy 264.043968 -195.156033)
			(xy 264.000211 -195.109436) (xy 263.962638 -195.057721) (xy 263.931844 -195.001706) (xy 263.908312 -194.942273)
			(xy 263.892415 -194.880359) (xy 263.884404 -194.816941) (xy 263.883902 -194.78498) (xy 263.884435 -194.75143)
			(xy 263.893253 -194.684912) (xy 263.910747 -194.620132) (xy 263.936612 -194.558218) (xy 263.970398 -194.500245)
			(xy 264.011518 -194.447221) (xy 264.035032 -194.423284) (xy 264.042144 -194.416172) (xy 264.050018 -194.397884)
			(xy 264.051034 -194.305936) (xy 264.043668 -194.287648) (xy 264.036556 -194.280282) (xy 264.014734 -194.257099)
			(xy 263.976602 -194.206112) (xy 263.945317 -194.150661) (xy 263.921394 -194.091657) (xy 263.905227 -194.030076)
			(xy 263.897084 -193.96693) (xy 263.896602 -193.935096) (xy 263.89689 -193.911647) (xy 263.901345 -193.86496)
			(xy 263.905492 -193.841878) (xy 263.90692 -193.832388) (xy 263.9034 -193.813537) (xy 263.893193 -193.797302)
			(xy 263.88568 -193.791332) (xy 263.852875 -193.766611) (xy 263.791538 -193.711966) (xy 263.735581 -193.651825)
			(xy 263.685493 -193.586713) (xy 263.641715 -193.517202) (xy 263.60463 -193.443901) (xy 263.574563 -193.367454)
			(xy 263.551778 -193.288529) (xy 263.536474 -193.207819) (xy 263.528786 -193.126032) (xy 263.528302 -193.084958)
			(xy 263.52879 -193.043231) (xy 263.536739 -192.960157) (xy 263.55255 -192.878214) (xy 263.576081 -192.798147)
			(xy 263.607118 -192.720679) (xy 263.625838 -192.683384) (xy 263.630821 -192.67222) (xy 263.630828 -192.647808)
			(xy 263.625838 -192.636648) (xy 263.607158 -192.599335) (xy 263.576135 -192.521867) (xy 263.552607 -192.441803)
			(xy 263.536788 -192.359866) (xy 263.528819 -192.276798) (xy 263.528302 -192.235074) (xy 263.528568 -192.204299)
			(xy 263.532891 -192.142901) (xy 263.536938 -192.112392) (xy 263.539732 -192.092072) (xy 263.515602 -192.058798)
			(xy 263.459722 -192.049146) (xy 263.449782 -192.047928) (xy 263.430269 -192.052332) (xy 263.413924 -192.063866)
			(xy 263.403235 -192.080775) (xy 263.401048 -192.090548) (xy 263.400794 -192.091564) (xy 263.400794 -192.09258)
			(xy 263.395937 -192.125529) (xy 263.37871 -192.189865) (xy 263.353232 -192.251401) (xy 263.31994 -192.309085)
			(xy 263.279401 -192.361929) (xy 263.232312 -192.409029) (xy 263.179476 -192.449578) (xy 263.1218 -192.482884)
			(xy 263.060269 -192.508375) (xy 262.995937 -192.525615) (xy 262.929905 -192.53431) (xy 262.896604 -192.534794)
			(xy 262.865872 -192.534349) (xy 262.804856 -192.52694) (xy 262.745178 -192.512231) (xy 262.687709 -192.490436)
			(xy 262.633285 -192.461872) (xy 262.582701 -192.426956) (xy 262.536695 -192.386198) (xy 262.495938 -192.340191)
			(xy 262.461023 -192.289606) (xy 262.43246 -192.235182) (xy 262.410666 -192.177712) (xy 262.395958 -192.118034)
			(xy 262.388551 -192.057018) (xy 262.388096 -192.026286) (xy 262.388424 -191.999802) (xy 262.393896 -191.947116)
			(xy 262.399018 -191.92113) (xy 262.399272 -191.920368) (xy 262.399526 -191.919352) (xy 262.400819 -191.909382)
			(xy 262.396376 -191.889791) (xy 262.384741 -191.873414) (xy 262.367705 -191.862769) (xy 262.35787 -191.860678)
			(xy 262.31596 -191.853566) (xy 262.307578 -191.852804) (xy 259.198364 -191.852804) (xy 259.188297 -191.852374)
			(xy 259.169701 -191.844651) (xy 259.162296 -191.837818) (xy 258.542028 -191.21755) (xy 258.536278 -191.212169)
			(xy 258.522306 -191.204926) (xy 258.514596 -191.203326) (xy 257.414014 -191.015112) (xy 257.405632 -191.01435)
			(xy 253.227332 -191.01435) (xy 253.217268 -191.014787) (xy 253.198687 -191.022524) (xy 253.191264 -191.029336)
			(xy 241.894868 -202.325732) (xy 241.888019 -202.333129) (xy 241.880286 -202.351728) (xy 241.879882 -202.3618)
			(xy 241.879882 -203.820522) (xy 241.900456 -203.8477) (xy 241.916966 -203.852272) (xy 241.948558 -203.861715)
			(xy 242.009182 -203.887647) (xy 242.065945 -203.921198) (xy 242.117894 -203.961805) (xy 242.164159 -204.008787)
			(xy 242.203963 -204.061355) (xy 242.236637 -204.118627) (xy 242.261634 -204.179642) (xy 242.278534 -204.243377)
			(xy 242.287054 -204.308761) (xy 242.287552 -204.34173) (xy 242.287079 -204.373195) (xy 242.279309 -204.435644)
			(xy 242.263892 -204.496657) (xy 242.241062 -204.555301) (xy 242.211171 -204.610679) (xy 242.174673 -204.661945)
			(xy 242.132128 -204.708315) (xy 242.108482 -204.72908) (xy 242.099592 -204.736446) (xy 242.090448 -204.756766)
			(xy 242.090702 -204.856842) (xy 242.1001 -204.876908) (xy 242.108736 -204.884274) (xy 242.132654 -204.905025)
			(xy 242.175675 -204.95149) (xy 242.212592 -205.002938) (xy 242.242833 -205.058573) (xy 242.26593 -205.117534)
			(xy 242.281526 -205.178906) (xy 242.289378 -205.24174) (xy 242.289838 -205.273402) (xy 242.289308 -205.306472)
			(xy 242.280731 -205.372054) (xy 242.263722 -205.435971) (xy 242.238569 -205.497142) (xy 242.205696 -205.554535)
			(xy 242.165659 -205.60718) (xy 242.119133 -205.65419) (xy 242.066903 -205.694769) (xy 242.009853 -205.728233)
			(xy 241.948945 -205.754017) (xy 241.91722 -205.763368) (xy 241.900456 -205.76794) (xy 241.879882 -205.795118)
			(xy 241.879882 -206.048864) (xy 241.897154 -206.074264) (xy 241.911378 -206.08036) (xy 241.937314 -206.091488)
			(xy 241.985859 -206.12027) (xy 242.02963 -206.155893) (xy 242.067673 -206.19758) (xy 242.099154 -206.244419)
			(xy 242.123388 -206.295387) (xy 242.139843 -206.34937) (xy 242.148161 -206.40519) (xy 242.14816 -206.461625)
			(xy 242.13984 -206.517444) (xy 242.123382 -206.571427) (xy 242.099147 -206.622394) (xy 242.067663 -206.669232)
			(xy 242.029619 -206.710917) (xy 241.985846 -206.746539) (xy 241.937301 -206.775319) (xy 241.911378 -206.78648)
			(xy 241.897154 -206.792576) (xy 241.879882 -206.817976) (xy 241.879882 -206.869538) (xy 241.880269 -206.878806)
			(xy 241.886868 -206.896126) (xy 241.899245 -206.909921) (xy 241.907314 -206.914496) (xy 241.936022 -206.93003)
			(xy 241.989565 -206.967363) (xy 242.037893 -207.011239) (xy 242.080212 -207.060935) (xy 242.115828 -207.115636)
			(xy 242.144155 -207.174443) (xy 242.164727 -207.236391) (xy 242.177207 -207.30046) (xy 242.18139 -207.3656)
			(xy 242.177207 -207.43074) (xy 242.164727 -207.494809) (xy 242.144155 -207.556757) (xy 242.115828 -207.615564)
			(xy 242.080212 -207.670265) (xy 242.037893 -207.719961) (xy 241.989565 -207.763837) (xy 241.936022 -207.80117)
			(xy 241.907314 -207.816704) (xy 241.899299 -207.82134) (xy 241.886987 -207.835148) (xy 241.880341 -207.852414)
			(xy 241.879882 -207.861662) (xy 241.879882 -208.753159) (xy 243.736362 -208.753159) (xy 243.736362 -208.689237)
			(xy 243.744373 -208.625819) (xy 243.76027 -208.563905) (xy 243.783802 -208.504472) (xy 243.814596 -208.448457)
			(xy 243.852169 -208.396742) (xy 243.895926 -208.350145) (xy 243.945179 -208.3094) (xy 243.99915 -208.275149)
			(xy 244.056989 -208.247932) (xy 244.117782 -208.228179) (xy 244.180572 -208.216201) (xy 244.244368 -208.212188)
			(xy 244.308164 -208.216201) (xy 244.370954 -208.228179) (xy 244.431747 -208.247932) (xy 244.489586 -208.275149)
			(xy 244.543557 -208.3094) (xy 244.59281 -208.350145) (xy 244.636567 -208.396742) (xy 244.67414 -208.448457)
			(xy 244.704934 -208.504472) (xy 244.728466 -208.563905) (xy 244.744363 -208.625819) (xy 244.752374 -208.689237)
			(xy 244.752876 -208.721198) (xy 244.752374 -208.753159) (xy 244.744363 -208.816577) (xy 244.728466 -208.878491)
			(xy 244.704934 -208.937924) (xy 244.67414 -208.993939) (xy 244.636567 -209.045654) (xy 244.59281 -209.092251)
			(xy 244.543557 -209.132996) (xy 244.489586 -209.167247) (xy 244.431747 -209.194464) (xy 244.370954 -209.214217)
			(xy 244.308164 -209.226195) (xy 244.244368 -209.230209) (xy 244.180572 -209.226195) (xy 244.117782 -209.214217)
			(xy 244.056989 -209.194464) (xy 243.99915 -209.167247) (xy 243.945179 -209.132996) (xy 243.895926 -209.092251)
			(xy 243.852169 -209.045654) (xy 243.814596 -208.993939) (xy 243.783802 -208.937924) (xy 243.76027 -208.878491)
			(xy 243.744373 -208.816577) (xy 243.736362 -208.753159) (xy 241.879882 -208.753159) (xy 241.879882 -213.998302)
			(xy 241.879458 -214.008372) (xy 241.871741 -214.026974) (xy 241.864896 -214.03437) (xy 239.840305 -216.058961)
			(xy 240.537994 -216.058961) (xy 240.537994 -215.995039) (xy 240.546005 -215.931621) (xy 240.561902 -215.869707)
			(xy 240.585434 -215.810274) (xy 240.616228 -215.754259) (xy 240.653801 -215.702544) (xy 240.697558 -215.655947)
			(xy 240.746811 -215.615202) (xy 240.800782 -215.580951) (xy 240.858621 -215.553734) (xy 240.919414 -215.533981)
			(xy 240.982204 -215.522003) (xy 241.046 -215.51799) (xy 241.109796 -215.522003) (xy 241.172586 -215.533981)
			(xy 241.233379 -215.553734) (xy 241.291218 -215.580951) (xy 241.345189 -215.615202) (xy 241.394442 -215.655947)
			(xy 241.438199 -215.702544) (xy 241.475772 -215.754259) (xy 241.506566 -215.810274) (xy 241.530098 -215.869707)
			(xy 241.545995 -215.931621) (xy 241.554006 -215.995039) (xy 241.554508 -216.027) (xy 241.554006 -216.058961)
			(xy 241.545995 -216.122379) (xy 241.530098 -216.184293) (xy 241.506566 -216.243726) (xy 241.475772 -216.299741)
			(xy 241.438199 -216.351456) (xy 241.394442 -216.398053) (xy 241.345189 -216.438798) (xy 241.291218 -216.473049)
			(xy 241.233379 -216.500266) (xy 241.172586 -216.520019) (xy 241.109796 -216.531997) (xy 241.046 -216.536011)
			(xy 240.982204 -216.531997) (xy 240.919414 -216.520019) (xy 240.858621 -216.500266) (xy 240.800782 -216.473049)
			(xy 240.746811 -216.438798) (xy 240.697558 -216.398053) (xy 240.653801 -216.351456) (xy 240.616228 -216.299741)
			(xy 240.585434 -216.243726) (xy 240.561902 -216.184293) (xy 240.546005 -216.122379) (xy 240.537994 -216.058961)
			(xy 239.840305 -216.058961) (xy 238.589355 -217.309911) (xy 241.045994 -217.309911) (xy 241.045994 -217.245989)
			(xy 241.054005 -217.182571) (xy 241.069902 -217.120657) (xy 241.093434 -217.061224) (xy 241.124228 -217.005209)
			(xy 241.161801 -216.953494) (xy 241.205558 -216.906897) (xy 241.254811 -216.866152) (xy 241.308782 -216.831901)
			(xy 241.366621 -216.804684) (xy 241.427414 -216.784931) (xy 241.490204 -216.772953) (xy 241.554 -216.76894)
			(xy 241.617796 -216.772953) (xy 241.680586 -216.784931) (xy 241.741379 -216.804684) (xy 241.799218 -216.831901)
			(xy 241.853189 -216.866152) (xy 241.902442 -216.906897) (xy 241.946199 -216.953494) (xy 241.983772 -217.005209)
			(xy 242.014566 -217.061224) (xy 242.038098 -217.120657) (xy 242.053995 -217.182571) (xy 242.062006 -217.245989)
			(xy 242.062508 -217.27795) (xy 242.062006 -217.309911) (xy 242.053995 -217.373329) (xy 242.038098 -217.435243)
			(xy 242.014566 -217.494676) (xy 241.983772 -217.550691) (xy 241.946199 -217.602406) (xy 241.902442 -217.649003)
			(xy 241.853189 -217.689748) (xy 241.799218 -217.723999) (xy 241.741379 -217.751216) (xy 241.680586 -217.770969)
			(xy 241.617796 -217.782947) (xy 241.554 -217.786961) (xy 241.490204 -217.782947) (xy 241.427414 -217.770969)
			(xy 241.366621 -217.751216) (xy 241.308782 -217.723999) (xy 241.254811 -217.689748) (xy 241.205558 -217.649003)
			(xy 241.161801 -217.602406) (xy 241.124228 -217.550691) (xy 241.093434 -217.494676) (xy 241.069902 -217.435243)
			(xy 241.054005 -217.373329) (xy 241.045994 -217.309911) (xy 238.589355 -217.309911) (xy 236.804279 -219.094987)
			(xy 237.743078 -219.094987) (xy 237.748287 -219.032117) (xy 237.761232 -218.970374) (xy 237.781715 -218.910707)
			(xy 237.809421 -218.854032) (xy 237.843925 -218.801219) (xy 237.884697 -218.753079) (xy 237.93111 -218.710353)
			(xy 237.982451 -218.673695) (xy 238.037933 -218.64367) (xy 238.096702 -218.620738) (xy 238.157857 -218.605251)
			(xy 238.220457 -218.597448) (xy 238.252 -218.596972) (xy 238.282461 -218.597415) (xy 238.342949 -218.604674)
			(xy 238.37265 -218.61145) (xy 238.386877 -218.614472) (xy 238.415922 -218.613235) (xy 238.443441 -218.603861)
			(xy 238.467201 -218.58711) (xy 238.485277 -218.564341) (xy 238.496202 -218.537401) (xy 238.499089 -218.508473)
			(xy 238.496856 -218.494102) (xy 238.493898 -218.477367) (xy 238.490717 -218.443531) (xy 238.490506 -218.426538)
			(xy 238.490935 -218.399366) (xy 238.498904 -218.345608) (xy 238.514674 -218.293602) (xy 238.537905 -218.244472)
			(xy 238.568093 -218.199284) (xy 238.604585 -218.159013) (xy 238.646591 -218.124534) (xy 238.693201 -218.096591)
			(xy 238.743407 -218.075789) (xy 238.796123 -218.06258) (xy 238.850205 -218.057249) (xy 238.904485 -218.059911)
			(xy 238.957786 -218.070509) (xy 239.008956 -218.088813) (xy 239.056885 -218.114428) (xy 239.100538 -218.146798)
			(xy 239.138968 -218.185223) (xy 239.171344 -218.228871) (xy 239.196965 -218.276797) (xy 239.215277 -218.327964)
			(xy 239.225882 -218.381264) (xy 239.228552 -218.435543) (xy 239.223229 -218.489626) (xy 239.210027 -218.542343)
			(xy 239.189233 -218.592552) (xy 239.161296 -218.639167) (xy 239.126823 -218.681178) (xy 239.086558 -218.717675)
			(xy 239.041373 -218.74787) (xy 238.992247 -218.771107) (xy 238.940243 -218.786885) (xy 238.886486 -218.794861)
			(xy 238.859314 -218.795346) (xy 238.83239 -218.79433) (xy 238.817873 -218.793811) (xy 238.789489 -218.799904)
			(xy 238.763966 -218.813737) (xy 238.743367 -218.834193) (xy 238.729355 -218.859618) (xy 238.723063 -218.887959)
			(xy 238.724999 -218.916925) (xy 238.72952 -218.930728) (xy 238.739342 -218.958804) (xy 238.753137 -219.016664)
			(xy 238.760084 -219.075739) (xy 238.760508 -219.10548) (xy 238.760054 -219.137023) (xy 238.753576 -219.189003)
			(xy 239.013994 -219.189003) (xy 239.013994 -219.125081) (xy 239.022005 -219.061663) (xy 239.037902 -218.999749)
			(xy 239.061434 -218.940316) (xy 239.092228 -218.884301) (xy 239.129801 -218.832586) (xy 239.173558 -218.785989)
			(xy 239.222811 -218.745244) (xy 239.276782 -218.710993) (xy 239.334621 -218.683776) (xy 239.395414 -218.664023)
			(xy 239.458204 -218.652045) (xy 239.522 -218.648032) (xy 239.585796 -218.652045) (xy 239.648586 -218.664023)
			(xy 239.709379 -218.683776) (xy 239.767218 -218.710993) (xy 239.821189 -218.745244) (xy 239.870442 -218.785989)
			(xy 239.914199 -218.832586) (xy 239.951772 -218.884301) (xy 239.982566 -218.940316) (xy 240.006098 -218.999749)
			(xy 240.021995 -219.061663) (xy 240.030006 -219.125081) (xy 240.030508 -219.157042) (xy 240.030006 -219.189003)
			(xy 240.021995 -219.252421) (xy 240.006098 -219.314335) (xy 239.982566 -219.373768) (xy 239.951772 -219.429783)
			(xy 239.914199 -219.481498) (xy 239.870442 -219.528095) (xy 239.821189 -219.56884) (xy 239.767218 -219.603091)
			(xy 239.709379 -219.630308) (xy 239.648586 -219.650061) (xy 239.585796 -219.662039) (xy 239.522 -219.666053)
			(xy 239.458204 -219.662039) (xy 239.395414 -219.650061) (xy 239.334621 -219.630308) (xy 239.276782 -219.603091)
			(xy 239.222811 -219.56884) (xy 239.173558 -219.528095) (xy 239.129801 -219.481498) (xy 239.092228 -219.429783)
			(xy 239.061434 -219.373768) (xy 239.037902 -219.314335) (xy 239.022005 -219.252421) (xy 239.013994 -219.189003)
			(xy 238.753576 -219.189003) (xy 238.752253 -219.199623) (xy 238.736769 -219.260779) (xy 238.713839 -219.319549)
			(xy 238.683816 -219.375032) (xy 238.64716 -219.426375) (xy 238.604435 -219.472789) (xy 238.556297 -219.513563)
			(xy 238.503486 -219.548069) (xy 238.446811 -219.575777) (xy 238.387145 -219.596263) (xy 238.325403 -219.60921)
			(xy 238.262534 -219.614422) (xy 238.199502 -219.611816) (xy 238.137277 -219.601434) (xy 238.076814 -219.583435)
			(xy 238.019042 -219.558096) (xy 237.964848 -219.525804) (xy 237.915064 -219.487058) (xy 237.870455 -219.442451)
			(xy 237.831707 -219.392669) (xy 237.799414 -219.338476) (xy 237.774072 -219.280704) (xy 237.75607 -219.220242)
			(xy 237.745686 -219.158018) (xy 237.743078 -219.094987) (xy 236.804279 -219.094987) (xy 236.771942 -219.127324)
			(xy 236.768894 -219.164408) (xy 236.779816 -219.179394) (xy 236.797769 -219.205355) (xy 236.827815 -219.260866)
			(xy 236.850764 -219.319667) (xy 236.866264 -219.380855) (xy 236.874077 -219.44349) (xy 236.874558 -219.47505)
			(xy 236.874092 -219.50578) (xy 236.866678 -219.566792) (xy 236.851966 -219.626465) (xy 236.830169 -219.683931)
			(xy 236.801604 -219.73835) (xy 236.76669 -219.78893) (xy 236.725934 -219.834934) (xy 236.723602 -219.837)
			(xy 242.823492 -219.837) (xy 242.823926 -219.807334) (xy 242.830821 -219.748404) (xy 242.844529 -219.690677)
			(xy 242.864863 -219.634939) (xy 242.891547 -219.581946) (xy 242.924219 -219.53242) (xy 242.962434 -219.487034)
			(xy 242.983766 -219.466414) (xy 242.991386 -219.459302) (xy 242.999768 -219.439998) (xy 242.999768 -219.345002)
			(xy 242.991386 -219.325698) (xy 242.983766 -219.318586) (xy 242.962428 -219.297972) (xy 242.924218 -219.252581)
			(xy 242.891549 -219.203053) (xy 242.864864 -219.15006) (xy 242.844527 -219.094322) (xy 242.830813 -219.036596)
			(xy 242.82391 -218.977666) (xy 242.823492 -218.948) (xy 242.82399 -218.916198) (xy 242.831911 -218.85309)
			(xy 242.847643 -218.791463) (xy 242.870939 -218.732279) (xy 242.901435 -218.676464) (xy 242.938656 -218.624888)
			(xy 242.982019 -218.578358) (xy 243.006118 -218.557602) (xy 243.012732 -218.551577) (xy 243.021694 -218.536108)
			(xy 243.023644 -218.527376) (xy 243.028978 -218.497658) (xy 243.030154 -218.488978) (xy 243.027309 -218.471708)
			(xy 243.02339 -218.463876) (xy 243.008547 -218.43616) (xy 242.9875 -218.37692) (xy 242.976801 -218.314969)
			(xy 242.976146 -218.283536) (xy 242.976662 -218.255936) (xy 242.984889 -218.201353) (xy 243.001159 -218.148606)
			(xy 243.025109 -218.098874) (xy 243.056204 -218.053266) (xy 243.093749 -218.012802) (xy 243.136906 -217.978385)
			(xy 243.18471 -217.950786) (xy 243.236094 -217.930619) (xy 243.289909 -217.918336) (xy 243.344954 -217.914211)
			(xy 243.399999 -217.918336) (xy 243.453814 -217.930619) (xy 243.505198 -217.950786) (xy 243.553002 -217.978385)
			(xy 243.596159 -218.012802) (xy 243.633704 -218.053266) (xy 243.664799 -218.098874) (xy 243.688749 -218.148606)
			(xy 243.705019 -218.201353) (xy 243.713246 -218.255936) (xy 243.713762 -218.283536) (xy 243.713356 -218.308903)
			(xy 243.706402 -218.359159) (xy 243.69263 -218.407989) (xy 243.6723 -218.454472) (xy 243.659406 -218.476322)
			(xy 243.655115 -218.483973) (xy 243.651473 -218.501117) (xy 243.652294 -218.50985) (xy 243.656358 -218.539822)
			(xy 243.658046 -218.548591) (xy 243.666482 -218.564315) (xy 243.672868 -218.570556) (xy 243.695112 -218.591262)
			(xy 243.735026 -218.637089) (xy 243.769197 -218.687345) (xy 243.797136 -218.741314) (xy 243.818447 -218.798227)
			(xy 243.832825 -218.857274) (xy 243.840066 -218.917614) (xy 243.840508 -218.948) (xy 243.840074 -218.977666)
			(xy 243.833179 -219.036596) (xy 243.819471 -219.094323) (xy 243.799137 -219.150061) (xy 243.772453 -219.203054)
			(xy 243.739781 -219.25258) (xy 243.701566 -219.297966) (xy 243.680234 -219.318586) (xy 243.672614 -219.325698)
			(xy 243.664232 -219.345002) (xy 243.664232 -219.439998) (xy 243.672614 -219.459302) (xy 243.680234 -219.466414)
			(xy 243.701572 -219.487028) (xy 243.739782 -219.532419) (xy 243.772451 -219.581947) (xy 243.799136 -219.63494)
			(xy 243.819473 -219.690678) (xy 243.833187 -219.748404) (xy 243.84009 -219.807334) (xy 243.840508 -219.837)
			(xy 243.840006 -219.868961) (xy 243.831995 -219.932379) (xy 243.816098 -219.994293) (xy 243.792566 -220.053726)
			(xy 243.761772 -220.109741) (xy 243.724199 -220.161456) (xy 243.680442 -220.208053) (xy 243.631189 -220.248798)
			(xy 243.577218 -220.283049) (xy 243.519379 -220.310266) (xy 243.458586 -220.330019) (xy 243.395796 -220.341997)
			(xy 243.332 -220.346011) (xy 243.268204 -220.341997) (xy 243.205414 -220.330019) (xy 243.144621 -220.310266)
			(xy 243.086782 -220.283049) (xy 243.032811 -220.248798) (xy 242.983558 -220.208053) (xy 242.939801 -220.161456)
			(xy 242.902228 -220.109741) (xy 242.871434 -220.053726) (xy 242.847902 -219.994293) (xy 242.832005 -219.932379)
			(xy 242.823994 -219.868961) (xy 242.823492 -219.837) (xy 236.723602 -219.837) (xy 236.67993 -219.87569)
			(xy 236.62935 -219.910604) (xy 236.574931 -219.939169) (xy 236.517465 -219.960966) (xy 236.457792 -219.975678)
			(xy 236.39678 -219.983092) (xy 236.36605 -219.983558) (xy 236.334488 -219.983085) (xy 236.27185 -219.975281)
			(xy 236.210658 -219.959785) (xy 236.151854 -219.936838) (xy 236.096341 -219.90679) (xy 236.070394 -219.888816)
			(xy 236.055408 -219.877894) (xy 236.018324 -219.880942) (xy 230.462836 -225.43643) (xy 232.69397 -225.43643)
			(xy 232.698041 -225.380808) (xy 232.710167 -225.326371) (xy 232.73009 -225.27428) (xy 232.757386 -225.225645)
			(xy 232.791472 -225.181502) (xy 232.831621 -225.142793) (xy 232.876979 -225.110342) (xy 232.926579 -225.084841)
			(xy 232.979363 -225.066834) (xy 233.034206 -225.056704) (xy 233.08994 -225.054667) (xy 233.145377 -225.060767)
			(xy 233.199334 -225.074873) (xy 233.250663 -225.096685) (xy 233.298269 -225.125739) (xy 233.341137 -225.161414)
			(xy 233.378354 -225.202951) (xy 233.409127 -225.249464) (xy 233.432799 -225.299961) (xy 233.448867 -225.353368)
			(xy 233.456987 -225.408544) (xy 233.457496 -225.43643) (xy 233.456987 -225.464316) (xy 233.448867 -225.519492)
			(xy 233.432799 -225.572899) (xy 233.409127 -225.623396) (xy 233.378354 -225.669909) (xy 233.341137 -225.711446)
			(xy 233.298269 -225.747121) (xy 233.250663 -225.776175) (xy 233.199334 -225.797987) (xy 233.145377 -225.812093)
			(xy 233.08994 -225.818193) (xy 233.034206 -225.816156) (xy 232.979363 -225.806026) (xy 232.926579 -225.788019)
			(xy 232.876979 -225.762518) (xy 232.831621 -225.730067) (xy 232.791472 -225.691358) (xy 232.757386 -225.647215)
			(xy 232.73009 -225.59858) (xy 232.710167 -225.546489) (xy 232.698041 -225.492052) (xy 232.69397 -225.43643)
			(xy 230.462836 -225.43643) (xy 229.409244 -226.490022) (xy 229.402396 -226.497419) (xy 229.394663 -226.516018)
			(xy 229.394258 -226.52609) (xy 229.394258 -227.457) (xy 233.17099 -227.457) (xy 233.175003 -227.393204)
			(xy 233.186981 -227.330414) (xy 233.206734 -227.269621) (xy 233.233951 -227.211782) (xy 233.268202 -227.157811)
			(xy 233.308947 -227.108558) (xy 233.355544 -227.064801) (xy 233.407259 -227.027228) (xy 233.463274 -226.996434)
			(xy 233.522707 -226.972902) (xy 233.584621 -226.957005) (xy 233.648039 -226.948994) (xy 233.68 -226.948492)
			(xy 233.710215 -226.94893) (xy 233.770218 -226.956117) (xy 233.828945 -226.970367) (xy 233.885569 -226.991478)
			(xy 233.939291 -227.019152) (xy 233.989354 -227.053) (xy 234.012486 -227.072444) (xy 234.019623 -227.078069)
			(xy 234.036678 -227.084313) (xy 234.04576 -227.084636) (xy 234.07624 -227.084636) (xy 234.08532 -227.084302)
			(xy 234.102371 -227.078059) (xy 234.109514 -227.072444) (xy 234.132649 -227.053005) (xy 234.182716 -227.019167)
			(xy 234.236439 -226.991498) (xy 234.293061 -226.970389) (xy 234.351786 -226.956137) (xy 234.411786 -226.948942)
			(xy 234.442 -226.948492) (xy 234.473961 -226.948994) (xy 234.537379 -226.957005) (xy 234.599293 -226.972902)
			(xy 234.658726 -226.996434) (xy 234.714741 -227.027228) (xy 234.766456 -227.064801) (xy 234.813053 -227.108558)
			(xy 234.853798 -227.157811) (xy 234.888049 -227.211782) (xy 234.915266 -227.269621) (xy 234.935019 -227.330414)
			(xy 234.946997 -227.393204) (xy 234.951011 -227.457) (xy 234.946997 -227.520796) (xy 234.935019 -227.583586)
			(xy 234.915266 -227.644379) (xy 234.888049 -227.702218) (xy 234.853798 -227.756189) (xy 234.813053 -227.805442)
			(xy 234.766456 -227.849199) (xy 234.714741 -227.886772) (xy 234.658726 -227.917566) (xy 234.599293 -227.941098)
			(xy 234.537379 -227.956995) (xy 234.473961 -227.965006) (xy 234.442 -227.965508) (xy 234.411785 -227.96507)
			(xy 234.351782 -227.957883) (xy 234.293055 -227.943633) (xy 234.236431 -227.922522) (xy 234.182709 -227.894848)
			(xy 234.132646 -227.861) (xy 234.109514 -227.841556) (xy 234.102377 -227.835931) (xy 234.085322 -227.829687)
			(xy 234.07624 -227.829364) (xy 234.04576 -227.829364) (xy 234.03668 -227.829698) (xy 234.019629 -227.835941)
			(xy 234.012486 -227.841556) (xy 233.989351 -227.860995) (xy 233.939284 -227.894833) (xy 233.885561 -227.922502)
			(xy 233.828939 -227.943611) (xy 233.770214 -227.957863) (xy 233.710214 -227.965058) (xy 233.68 -227.965508)
			(xy 233.648039 -227.965006) (xy 233.584621 -227.956995) (xy 233.522707 -227.941098) (xy 233.463274 -227.917566)
			(xy 233.407259 -227.886772) (xy 233.355544 -227.849199) (xy 233.308947 -227.805442) (xy 233.268202 -227.756189)
			(xy 233.233951 -227.702218) (xy 233.206734 -227.644379) (xy 233.186981 -227.583586) (xy 233.175003 -227.520796)
			(xy 233.17099 -227.457) (xy 229.394258 -227.457) (xy 229.394258 -228.481636) (xy 229.394689 -228.491702)
			(xy 229.402419 -228.510291) (xy 229.409244 -228.517704) (xy 229.840282 -228.948742) (xy 229.847682 -228.955582)
			(xy 229.866281 -228.963295) (xy 229.87635 -228.963728)
		)
		(stroke
			(width 0)
			(type solid)
		)
		(fill yes)
		(layer "In2.Cu")
		(net "P3V3_AUX")
	)
	(gr_poly
		(pts
			(xy 369.248436 -403.038056) (xy 369.25697 -403.037788) (xy 369.273117 -403.03227) (xy 369.286536 -403.021729)
			(xy 369.291362 -403.014688) (xy 369.344448 -402.93163) (xy 369.346226 -402.905976) (xy 369.340638 -402.894038)
			(xy 369.329549 -402.868836) (xy 369.313924 -402.816041) (xy 369.306058 -402.761548) (xy 369.305586 -402.734018)
			(xy 369.306072 -402.706767) (xy 369.313828 -402.652819) (xy 369.329183 -402.600524) (xy 369.351825 -402.550947)
			(xy 369.381291 -402.505097) (xy 369.416982 -402.463906) (xy 369.458173 -402.428215) (xy 369.504023 -402.398749)
			(xy 369.5536 -402.376107) (xy 369.605895 -402.360752) (xy 369.659843 -402.352996) (xy 369.714345 -402.352996)
			(xy 369.768293 -402.360752) (xy 369.820588 -402.376107) (xy 369.870165 -402.398749) (xy 369.916015 -402.428215)
			(xy 369.957206 -402.463906) (xy 369.992897 -402.505097) (xy 370.022363 -402.550947) (xy 370.045005 -402.600524)
			(xy 370.06036 -402.652819) (xy 370.068116 -402.706767) (xy 370.068602 -402.734018) (xy 370.068133 -402.761547)
			(xy 370.060249 -402.816036) (xy 370.044618 -402.868827) (xy 370.03355 -402.894038) (xy 370.027962 -402.905976)
			(xy 370.02974 -402.93163) (xy 370.082826 -403.014688) (xy 370.087714 -403.021672) (xy 370.101125 -403.03218)
			(xy 370.117233 -403.037729) (xy 370.125752 -403.038056) (xy 386.771642 -403.038056) (xy 386.781605 -403.037573)
			(xy 386.800032 -403.029987) (xy 386.807456 -403.023324) (xy 387.304534 -402.526246) (xy 387.311379 -402.518848)
			(xy 387.319104 -402.500249) (xy 387.31952 -402.490178) (xy 387.31952 -398.917414) (xy 387.319105 -398.907805)
			(xy 387.312057 -398.889924) (xy 387.305804 -398.882616) (xy 387.284976 -398.860772) (xy 387.27868 -398.854564)
			(xy 387.26296 -398.846499) (xy 387.254242 -398.845024) (xy 387.229893 -398.841549) (xy 387.182665 -398.82783)
			(xy 387.138247 -398.806717) (xy 387.097788 -398.778756) (xy 387.062335 -398.74467) (xy 387.032805 -398.705342)
			(xy 387.009962 -398.661788) (xy 386.994397 -398.615135) (xy 386.986512 -398.566591) (xy 386.986512 -398.51741)
			(xy 386.994397 -398.468865) (xy 387.009962 -398.422213) (xy 387.032805 -398.378659) (xy 387.062334 -398.33933)
			(xy 387.097787 -398.305245) (xy 387.138246 -398.277284) (xy 387.182665 -398.25617) (xy 387.229893 -398.242451)
			(xy 387.254242 -398.23898) (xy 387.262956 -398.237495) (xy 387.278673 -398.229431) (xy 387.284976 -398.223232)
			(xy 387.305804 -398.201388) (xy 387.312082 -398.194095) (xy 387.319126 -398.176205) (xy 387.31952 -398.16659)
			(xy 387.31952 -397.018764) (xy 387.303518 -396.993872) (xy 387.290056 -396.987522) (xy 387.267777 -396.976644)
			(xy 387.226774 -396.948775) (xy 387.190811 -396.91465) (xy 387.160831 -396.875164) (xy 387.137622 -396.831355)
			(xy 387.121794 -396.784372) (xy 387.113761 -396.73545) (xy 387.113272 -396.710662) (xy 387.113771 -396.685264)
			(xy 387.12217 -396.635166) (xy 387.138747 -396.587151) (xy 387.163044 -396.542542) (xy 387.19439 -396.502571)
			(xy 387.21284 -396.48511) (xy 387.221222 -396.47749) (xy 387.229858 -396.457424) (xy 387.227064 -396.35811)
			(xy 387.217666 -396.338552) (xy 387.208776 -396.33144) (xy 387.190216 -396.315637) (xy 387.157492 -396.279509)
			(xy 387.130421 -396.238972) (xy 387.109589 -396.194902) (xy 387.095448 -396.148253) (xy 387.088303 -396.100035)
			(xy 387.087872 -396.075662) (xy 387.088311 -396.051546) (xy 387.095316 -396.003825) (xy 387.109172 -395.957626)
			(xy 387.129586 -395.913928) (xy 387.142482 -395.893544) (xy 387.148324 -395.884654) (xy 387.15188 -395.864588)
			(xy 387.130798 -395.772386) (xy 387.118606 -395.755622) (xy 387.109716 -395.750288) (xy 387.088911 -395.737435)
			(xy 387.050987 -395.70656) (xy 387.01803 -395.670431) (xy 386.99076 -395.629838) (xy 386.969774 -395.585667)
			(xy 386.95553 -395.538885) (xy 386.94834 -395.490514) (xy 386.947918 -395.466062) (xy 386.948068 -395.450733)
			(xy 386.950868 -395.420203) (xy 386.953506 -395.405102) (xy 386.956046 -395.392656) (xy 386.948426 -395.368526)
			(xy 386.535422 -394.955522) (xy 386.526401 -394.947513) (xy 386.503482 -394.940091) (xy 386.49148 -394.941298)
			(xy 386.398262 -394.95603) (xy 386.378704 -394.970254) (xy 386.373116 -394.981176) (xy 386.359289 -395.006935)
			(xy 386.32403 -395.053564) (xy 386.303012 -395.073886) (xy 386.295566 -395.081379) (xy 386.28703 -395.100674)
			(xy 386.286502 -395.111224) (xy 386.286502 -395.1859) (xy 386.287093 -395.196433) (xy 386.295627 -395.215703)
			(xy 386.303012 -395.223238) (xy 386.322668 -395.24217) (xy 386.356112 -395.28529) (xy 386.382021 -395.333317)
			(xy 386.399691 -395.384947) (xy 386.408642 -395.438777) (xy 386.409184 -395.466062) (xy 386.408751 -395.490179)
			(xy 386.401755 -395.537904) (xy 386.387906 -395.584108) (xy 386.367497 -395.627813) (xy 386.354574 -395.64818)
			(xy 386.348732 -395.65707) (xy 386.345176 -395.677136) (xy 386.366258 -395.769338) (xy 386.37845 -395.786102)
			(xy 386.38734 -395.791436) (xy 386.408141 -395.804292) (xy 386.446057 -395.83517) (xy 386.479006 -395.871301)
			(xy 386.506268 -395.911895) (xy 386.527247 -395.956065) (xy 386.541485 -396.002845) (xy 386.54867 -396.051212)
			(xy 386.549138 -396.075662) (xy 386.5487 -396.100033) (xy 386.541544 -396.148246) (xy 386.527396 -396.194888)
			(xy 386.506561 -396.238952) (xy 386.47949 -396.279484) (xy 386.446768 -396.315609) (xy 386.428234 -396.33144)
			(xy 386.419344 -396.338552) (xy 386.409946 -396.35811) (xy 386.407152 -396.457424) (xy 386.415788 -396.47749)
			(xy 386.42417 -396.48511) (xy 386.442593 -396.502597) (xy 386.473938 -396.542564) (xy 386.498237 -396.587166)
			(xy 386.514821 -396.635175) (xy 386.523232 -396.685266) (xy 386.523738 -396.710662) (xy 386.523647 -396.721944)
			(xy 386.521993 -396.744446) (xy 386.520436 -396.75562) (xy 386.519166 -396.76451) (xy 386.522722 -396.782036)
			(xy 386.566156 -396.852902) (xy 386.579872 -396.864078) (xy 386.588508 -396.866872) (xy 386.61075 -396.874812)
			(xy 386.652665 -396.896568) (xy 386.690733 -396.924516) (xy 386.724046 -396.957989) (xy 386.751809 -396.996192)
			(xy 386.763006 -397.016986) (xy 386.763514 -397.018002) (xy 387.155944 -397.696944) (xy 387.168751 -397.720277)
			(xy 387.186898 -397.770309) (xy 387.196081 -397.822733) (xy 387.196584 -397.849344) (xy 387.19611 -397.873332)
			(xy 387.188598 -397.920717) (xy 387.173767 -397.966344) (xy 387.15198 -398.009089) (xy 387.123776 -398.047899)
			(xy 387.089848 -398.08182) (xy 387.051031 -398.110016) (xy 387.008281 -398.131793) (xy 386.962651 -398.146614)
			(xy 386.915264 -398.154115) (xy 386.891276 -398.154652) (xy 386.867745 -398.154215) (xy 386.821242 -398.146989)
			(xy 386.776399 -398.13271) (xy 386.734278 -398.111719) (xy 386.695878 -398.084512) (xy 386.662109 -398.051733)
			(xy 386.633771 -398.01416) (xy 386.62229 -397.993616) (xy 386.622036 -397.993108) (xy 386.621528 -397.992346)
			(xy 386.223764 -397.304006) (xy 386.211831 -397.281345) (xy 386.194882 -397.233021) (xy 386.186241 -397.182544)
			(xy 386.185664 -397.15694) (xy 386.185664 -397.156432) (xy 386.185815 -397.145083) (xy 386.187596 -397.122453)
			(xy 386.18922 -397.11122) (xy 386.19049 -397.10233) (xy 386.186934 -397.085058) (xy 386.1435 -397.013938)
			(xy 386.12953 -397.003016) (xy 386.121148 -396.999968) (xy 386.098747 -396.991947) (xy 386.056555 -396.969958)
			(xy 386.018283 -396.941693) (xy 385.984856 -396.907835) (xy 385.957084 -396.869203) (xy 385.935639 -396.826732)
			(xy 385.921038 -396.78145) (xy 385.913635 -396.734451) (xy 385.913122 -396.710662) (xy 385.913622 -396.685264)
			(xy 385.922022 -396.635168) (xy 385.938601 -396.587154) (xy 385.9629 -396.542548) (xy 385.99425 -396.502581)
			(xy 386.01269 -396.48511) (xy 386.021072 -396.47749) (xy 386.029708 -396.457424) (xy 386.026914 -396.35811)
			(xy 386.017516 -396.338552) (xy 386.008626 -396.33144) (xy 385.990064 -396.315638) (xy 385.957334 -396.279513)
			(xy 385.93026 -396.238976) (xy 385.909425 -396.194906) (xy 385.895281 -396.148256) (xy 385.888135 -396.100036)
			(xy 385.887722 -396.075662) (xy 385.888161 -396.051546) (xy 385.895167 -396.003826) (xy 385.909025 -395.957628)
			(xy 385.929442 -395.913931) (xy 385.942332 -395.893544) (xy 385.948174 -395.884654) (xy 385.95173 -395.864588)
			(xy 385.930648 -395.772386) (xy 385.918456 -395.755622) (xy 385.909566 -395.750288) (xy 385.888763 -395.737433)
			(xy 385.850845 -395.706556) (xy 385.817893 -395.670425) (xy 385.790627 -395.629832) (xy 385.769645 -395.585662)
			(xy 385.755403 -395.538881) (xy 385.748214 -395.490512) (xy 385.747768 -395.466062) (xy 385.748329 -395.438779)
			(xy 385.757289 -395.384954) (xy 385.77496 -395.333329) (xy 385.800863 -395.285303) (xy 385.834295 -395.242179)
			(xy 385.85394 -395.223238) (xy 385.861384 -395.215744) (xy 385.869919 -395.196449) (xy 385.87045 -395.1859)
			(xy 385.87045 -395.111224) (xy 385.869862 -395.10069) (xy 385.861329 -395.081419) (xy 385.85394 -395.073886)
			(xy 385.834285 -395.054953) (xy 385.800843 -395.011832) (xy 385.774934 -394.963805) (xy 385.757263 -394.912177)
			(xy 385.748309 -394.858347) (xy 385.747768 -394.831062) (xy 385.748022 -394.81887) (xy 385.748276 -394.809218)
			(xy 385.74218 -394.791184) (xy 385.683506 -394.723874) (xy 385.666742 -394.715238) (xy 385.656836 -394.714222)
			(xy 385.629924 -394.710869) (xy 385.577627 -394.696522) (xy 385.528373 -394.673832) (xy 385.483482 -394.643407)
			(xy 385.444159 -394.606065) (xy 385.411457 -394.562805) (xy 385.386253 -394.514788) (xy 385.369224 -394.463302)
			(xy 385.364482 -394.4366) (xy 385.362958 -394.427202) (xy 385.089908 -393.954762) (xy 385.082796 -393.94892)
			(xy 385.062063 -393.931349) (xy 385.026072 -393.890632) (xy 384.997214 -393.844584) (xy 384.976264 -393.794441)
			(xy 384.963785 -393.741549) (xy 384.961384 -393.714478) (xy 384.960114 -393.694412) (xy 384.93065 -393.66698)
			(xy 384.516884 -393.66698) (xy 384.507989 -393.667307) (xy 384.491269 -393.673383) (xy 384.477648 -393.684826)
			(xy 384.472942 -393.69238) (xy 384.466084 -393.704318) (xy 384.466084 -393.731242) (xy 384.692144 -394.122402)
			(xy 384.69951 -394.128244) (xy 384.718288 -394.144048) (xy 384.75142 -394.180256) (xy 384.778839 -394.220961)
			(xy 384.799945 -394.26527) (xy 384.814273 -394.31221) (xy 384.82151 -394.360753) (xy 384.821938 -394.385292)
			(xy 384.821684 -394.397484) (xy 384.82143 -394.407136) (xy 384.827526 -394.42517) (xy 384.8862 -394.49248)
			(xy 384.902964 -394.501116) (xy 384.91287 -394.502132) (xy 384.93964 -394.505456) (xy 384.991672 -394.519677)
			(xy 385.040707 -394.542152) (xy 385.085445 -394.572285) (xy 385.1247 -394.609279) (xy 385.157433 -394.652153)
			(xy 385.182775 -394.69977) (xy 385.200054 -394.750868) (xy 385.208813 -394.804092) (xy 385.209288 -394.831062)
			(xy 385.208725 -394.858344) (xy 385.19976 -394.912166) (xy 385.182085 -394.963787) (xy 385.156178 -395.011807)
			(xy 385.122741 -395.054925) (xy 385.103116 -395.073886) (xy 385.095669 -395.081379) (xy 385.087133 -395.100674)
			(xy 385.086606 -395.111224) (xy 385.086606 -395.1859) (xy 385.087197 -395.196433) (xy 385.095731 -395.215702)
			(xy 385.103116 -395.223238) (xy 385.122772 -395.24217) (xy 385.156215 -395.28529) (xy 385.182124 -395.333317)
			(xy 385.199794 -395.384947) (xy 385.208745 -395.438777) (xy 385.209288 -395.466062) (xy 385.208855 -395.49018)
			(xy 385.201859 -395.537904) (xy 385.18801 -395.584108) (xy 385.167601 -395.627813) (xy 385.154678 -395.64818)
			(xy 385.148836 -395.65707) (xy 385.14528 -395.677136) (xy 385.166362 -395.769338) (xy 385.178554 -395.786102)
			(xy 385.187444 -395.791436) (xy 385.208245 -395.804292) (xy 385.24616 -395.835171) (xy 385.279109 -395.871302)
			(xy 385.30637 -395.911896) (xy 385.327349 -395.956065) (xy 385.341587 -396.002845) (xy 385.348772 -396.051213)
			(xy 385.349242 -396.075662) (xy 385.348804 -396.100033) (xy 385.341648 -396.148246) (xy 385.3275 -396.194888)
			(xy 385.306665 -396.238952) (xy 385.279595 -396.279485) (xy 385.246873 -396.31561) (xy 385.228338 -396.33144)
			(xy 385.219448 -396.338552) (xy 385.21005 -396.35811) (xy 385.207256 -396.457424) (xy 385.215892 -396.47749)
			(xy 385.224274 -396.48511) (xy 385.242697 -396.502597) (xy 385.274042 -396.542564) (xy 385.298341 -396.587167)
			(xy 385.314924 -396.635175) (xy 385.323335 -396.685266) (xy 385.323842 -396.710662) (xy 385.323751 -396.721944)
			(xy 385.322098 -396.744446) (xy 385.32054 -396.75562) (xy 385.31927 -396.764764) (xy 385.322572 -396.782036)
			(xy 385.36626 -396.853156) (xy 385.379976 -396.864078) (xy 385.388612 -396.866872) (xy 385.416741 -396.877147)
			(xy 385.468668 -396.906957) (xy 385.491736 -396.926054) (xy 385.513181 -396.945671) (xy 385.54898 -396.991448)
			(xy 385.562856 -397.016986) (xy 385.563618 -397.018256) (xy 385.955794 -397.696944) (xy 385.968579 -397.720294)
			(xy 385.986773 -397.770317) (xy 385.996058 -397.82273) (xy 385.996688 -397.849344) (xy 385.996238 -397.873347)
			(xy 385.988717 -397.92076) (xy 385.973869 -397.966413) (xy 385.952059 -398.009178) (xy 385.923824 -398.048003)
			(xy 385.889861 -398.081931) (xy 385.851007 -398.110125) (xy 385.808218 -398.131891) (xy 385.762551 -398.146692)
			(xy 385.71513 -398.154162) (xy 385.691126 -398.154652) (xy 385.667597 -398.154212) (xy 385.621099 -398.146979)
			(xy 385.576261 -398.132695) (xy 385.534146 -398.1117) (xy 385.495753 -398.08449) (xy 385.46199 -398.051711)
			(xy 385.433657 -398.014139) (xy 385.42214 -397.993616) (xy 385.421886 -397.993108) (xy 385.421378 -397.992346)
			(xy 385.02082 -397.298926) (xy 385.009752 -397.276825) (xy 384.994113 -397.229938) (xy 384.986221 -397.181146)
			(xy 384.985768 -397.156432) (xy 384.985852 -397.145087) (xy 384.987508 -397.122457) (xy 384.98907 -397.11122)
			(xy 384.99034 -397.10233) (xy 384.986784 -397.085058) (xy 384.94335 -397.013938) (xy 384.929634 -397.002762)
			(xy 384.920998 -396.999968) (xy 384.898608 -396.991942) (xy 384.856438 -396.969943) (xy 384.818191 -396.941671)
			(xy 384.784792 -396.907808) (xy 384.757049 -396.869175) (xy 384.735634 -396.826707) (xy 384.721064 -396.781431)
			(xy 384.713693 -396.734443) (xy 384.713226 -396.710662) (xy 384.713726 -396.685264) (xy 384.722126 -396.635168)
			(xy 384.738705 -396.587155) (xy 384.763005 -396.542549) (xy 384.794354 -396.502582) (xy 384.812794 -396.48511)
			(xy 384.821176 -396.47749) (xy 384.829812 -396.457424) (xy 384.827018 -396.35811) (xy 384.81762 -396.338552)
			(xy 384.80873 -396.33144) (xy 384.790167 -396.315638) (xy 384.757438 -396.279513) (xy 384.730363 -396.238976)
			(xy 384.709528 -396.194906) (xy 384.695384 -396.148256) (xy 384.688238 -396.100036) (xy 384.687826 -396.075662)
			(xy 384.688265 -396.051546) (xy 384.695271 -396.003826) (xy 384.709129 -395.957628) (xy 384.729546 -395.913931)
			(xy 384.742436 -395.893544) (xy 384.748278 -395.884654) (xy 384.751834 -395.864588) (xy 384.730752 -395.772386)
			(xy 384.71856 -395.755622) (xy 384.70967 -395.750288) (xy 384.688867 -395.737433) (xy 384.650948 -395.706556)
			(xy 384.617996 -395.670426) (xy 384.59073 -395.629832) (xy 384.569747 -395.585662) (xy 384.555505 -395.538882)
			(xy 384.548316 -395.490512) (xy 384.547872 -395.466062) (xy 384.548433 -395.438779) (xy 384.557393 -395.384954)
			(xy 384.575064 -395.333329) (xy 384.600967 -395.285304) (xy 384.6344 -395.24218) (xy 384.654044 -395.223238)
			(xy 384.661499 -395.215749) (xy 384.670052 -395.196453) (xy 384.670554 -395.1859) (xy 384.670554 -395.111224)
			(xy 384.669967 -395.10069) (xy 384.661433 -395.081418) (xy 384.654044 -395.073886) (xy 384.634389 -395.054953)
			(xy 384.600946 -395.011832) (xy 384.575037 -394.963806) (xy 384.557366 -394.912177) (xy 384.548412 -394.858347)
			(xy 384.547872 -394.831062) (xy 384.548126 -394.81887) (xy 384.54838 -394.809218) (xy 384.542284 -394.791184)
			(xy 384.48361 -394.723874) (xy 384.466846 -394.715238) (xy 384.45694 -394.714222) (xy 384.430028 -394.71087)
			(xy 384.37773 -394.696522) (xy 384.328476 -394.673833) (xy 384.283585 -394.643408) (xy 384.244261 -394.606066)
			(xy 384.211558 -394.562806) (xy 384.186354 -394.514789) (xy 384.169325 -394.463303) (xy 384.164586 -394.4366)
			(xy 384.163062 -394.427202) (xy 383.890266 -393.95527) (xy 383.8829 -393.949428) (xy 383.862096 -393.93184)
			(xy 383.825983 -393.891058) (xy 383.79704 -393.84491) (xy 383.776047 -393.794645) (xy 383.763572 -393.741619)
			(xy 383.761234 -393.714478) (xy 383.759964 -393.694412) (xy 383.7305 -393.66698) (xy 383.316988 -393.66698)
			(xy 383.308092 -393.667307) (xy 383.291372 -393.673381) (xy 383.27775 -393.684824) (xy 383.273046 -393.69238)
			(xy 383.266188 -393.704318) (xy 383.266188 -393.731242) (xy 383.492248 -394.122402) (xy 383.499614 -394.128244)
			(xy 383.518391 -394.144048) (xy 383.551523 -394.180256) (xy 383.578942 -394.220961) (xy 383.600048 -394.26527)
			(xy 383.614376 -394.31221) (xy 383.621612 -394.360753) (xy 383.622042 -394.385292) (xy 383.621788 -394.397484)
			(xy 383.621534 -394.407136) (xy 383.62763 -394.42517) (xy 383.686304 -394.49248) (xy 383.703068 -394.501116)
			(xy 383.71272 -394.502132) (xy 383.739487 -394.50546) (xy 383.791513 -394.519686) (xy 383.840541 -394.542165)
			(xy 383.885272 -394.5723) (xy 383.924521 -394.609295) (xy 383.957248 -394.652167) (xy 383.982585 -394.69978)
			(xy 383.999861 -394.750874) (xy 384.008618 -394.804094) (xy 384.009138 -394.831062) (xy 384.008628 -394.857049)
			(xy 384.000498 -394.908384) (xy 383.984437 -394.957814) (xy 383.960841 -395.004124) (xy 383.930291 -395.046172)
			(xy 383.89354 -395.082923) (xy 383.851492 -395.113473) (xy 383.805182 -395.137069) (xy 383.755752 -395.15313)
			(xy 383.704417 -395.16126) (xy 383.652443 -395.16126) (xy 383.601108 -395.15313) (xy 383.551678 -395.137069)
			(xy 383.505368 -395.113473) (xy 383.46332 -395.082923) (xy 383.426569 -395.046172) (xy 383.396019 -395.004124)
			(xy 383.372423 -394.957814) (xy 383.356362 -394.908384) (xy 383.348232 -394.857049) (xy 383.347722 -394.831062)
			(xy 383.347976 -394.81887) (xy 383.34823 -394.809218) (xy 383.342134 -394.791184) (xy 383.28346 -394.723874)
			(xy 383.266696 -394.715238) (xy 383.257044 -394.714222) (xy 383.230131 -394.71087) (xy 383.177834 -394.696523)
			(xy 383.128579 -394.673834) (xy 383.083687 -394.64341) (xy 383.044362 -394.606067) (xy 383.011659 -394.562807)
			(xy 382.986455 -394.51479) (xy 382.969425 -394.463304) (xy 382.96469 -394.4366) (xy 382.963166 -394.427202)
			(xy 382.69037 -393.95527) (xy 382.683004 -393.949428) (xy 382.6622 -393.93184) (xy 382.626087 -393.891058)
			(xy 382.597143 -393.844911) (xy 382.57615 -393.794645) (xy 382.563675 -393.741619) (xy 382.561338 -393.714478)
			(xy 382.560068 -393.694412) (xy 382.530604 -393.66698) (xy 382.116838 -393.66698) (xy 382.107947 -393.667315)
			(xy 382.091239 -393.6734) (xy 382.077631 -393.684847) (xy 382.072896 -393.69238) (xy 382.066038 -393.704318)
			(xy 382.066038 -393.731242) (xy 382.292098 -394.122402) (xy 382.299464 -394.128244) (xy 382.318244 -394.144047)
			(xy 382.35138 -394.180253) (xy 382.378804 -394.220957) (xy 382.399912 -394.265266) (xy 382.414243 -394.312208)
			(xy 382.421481 -394.360752) (xy 382.421892 -394.385292) (xy 382.421638 -394.397484) (xy 382.421384 -394.407136)
			(xy 382.42748 -394.42517) (xy 382.486154 -394.49248) (xy 382.502918 -394.501116) (xy 382.512824 -394.502132)
			(xy 382.539591 -394.50546) (xy 382.591616 -394.519687) (xy 382.640643 -394.542166) (xy 382.685374 -394.572302)
			(xy 382.724623 -394.609296) (xy 382.757349 -394.652168) (xy 382.782686 -394.699781) (xy 382.799961 -394.750875)
			(xy 382.808718 -394.804094) (xy 382.809242 -394.831062) (xy 382.808775 -394.85526) (xy 382.80168 -394.903133)
			(xy 382.787694 -394.949464) (xy 382.767114 -394.993267) (xy 382.754124 -395.013688) (xy 382.749371 -395.021658)
			(xy 382.745347 -395.039757) (xy 382.74625 -395.048994) (xy 382.750568 -395.079982) (xy 382.752371 -395.089236)
			(xy 382.761624 -395.105645) (xy 382.768602 -395.111986) (xy 382.790698 -395.13066) (xy 382.830474 -395.172669)
			(xy 382.864638 -395.219357) (xy 382.892646 -395.269978) (xy 382.91405 -395.323726) (xy 382.928509 -395.379743)
			(xy 382.935793 -395.437136) (xy 382.936242 -395.466062) (xy 382.935638 -395.499382) (xy 382.925968 -395.565316)
			(xy 382.906841 -395.629152) (xy 382.893316 -395.65961) (xy 382.889057 -395.67008) (xy 382.889132 -395.692655)
			(xy 382.898879 -395.713016) (xy 382.907286 -395.72057) (xy 382.929535 -395.739243) (xy 382.969603 -395.781297)
			(xy 383.004028 -395.828082) (xy 383.032257 -395.878847) (xy 383.053837 -395.932775) (xy 383.068421 -395.989001)
			(xy 383.075775 -396.046619) (xy 383.076196 -396.075662) (xy 383.075745 -396.104666) (xy 383.068414 -396.162209)
			(xy 383.053878 -396.218366) (xy 383.032368 -396.272238) (xy 383.004229 -396.322964) (xy 382.969911 -396.369731)
			(xy 382.929963 -396.411792) (xy 382.907794 -396.4305) (xy 382.900682 -396.436088) (xy 382.891538 -396.451328)
			(xy 382.876298 -396.534132) (xy 382.879092 -396.551404) (xy 382.883664 -396.559532) (xy 382.896259 -396.58271)
			(xy 382.914148 -396.63233) (xy 382.923231 -396.684289) (xy 382.923796 -396.710662) (xy 383.513076 -396.710662)
			(xy 383.513598 -396.685407) (xy 383.521911 -396.635585) (xy 383.538312 -396.587811) (xy 383.562353 -396.543388)
			(xy 383.593377 -396.503528) (xy 383.630539 -396.469318) (xy 383.672825 -396.441692) (xy 383.719081 -396.421402)
			(xy 383.768046 -396.409002) (xy 383.818384 -396.404831) (xy 383.868722 -396.409002) (xy 383.917687 -396.421402)
			(xy 383.963943 -396.441692) (xy 384.006229 -396.469318) (xy 384.043391 -396.503528) (xy 384.074415 -396.543388)
			(xy 384.098456 -396.587811) (xy 384.114857 -396.635585) (xy 384.12317 -396.685407) (xy 384.123692 -396.710662)
			(xy 384.123588 -396.721943) (xy 384.121937 -396.744445) (xy 384.12039 -396.75562) (xy 384.11912 -396.76451)
			(xy 384.122676 -396.782036) (xy 384.16611 -396.852902) (xy 384.179826 -396.864078) (xy 384.188462 -396.866872)
			(xy 384.210708 -396.874804) (xy 384.252629 -396.896556) (xy 384.290703 -396.924501) (xy 384.324021 -396.957974)
			(xy 384.351789 -396.996176) (xy 384.36296 -397.016986) (xy 384.363468 -397.018002) (xy 384.755898 -397.696944)
			(xy 384.768701 -397.720288) (xy 384.78693 -397.770305) (xy 384.796199 -397.822727) (xy 384.796792 -397.849344)
			(xy 384.796401 -397.873352) (xy 384.78888 -397.920775) (xy 384.774029 -397.966436) (xy 384.752214 -398.009211)
			(xy 384.723974 -398.048044) (xy 384.690005 -398.081979) (xy 384.651142 -398.110179) (xy 384.608346 -398.131949)
			(xy 384.562669 -398.146753) (xy 384.515238 -398.154226) (xy 384.49123 -398.154652) (xy 384.467698 -398.154225)
			(xy 384.421189 -398.147014) (xy 384.37634 -398.132743) (xy 384.334216 -398.111751) (xy 384.295818 -398.084536)
			(xy 384.262057 -398.051746) (xy 384.233734 -398.014157) (xy 384.222244 -397.993616) (xy 384.22199 -397.993108)
			(xy 384.221482 -397.992346) (xy 383.823718 -397.304006) (xy 383.811839 -397.281331) (xy 383.79499 -397.232997)
			(xy 383.786418 -397.182533) (xy 383.785872 -397.15694) (xy 383.785872 -397.156432) (xy 383.785964 -397.145087)
			(xy 383.787618 -397.122458) (xy 383.789174 -397.11122) (xy 383.790444 -397.10233) (xy 383.786888 -397.085058)
			(xy 383.743454 -397.013938) (xy 383.729484 -397.003016) (xy 383.721102 -396.999968) (xy 383.698691 -396.991959)
			(xy 383.656474 -396.969994) (xy 383.618178 -396.941742) (xy 383.584734 -396.907886) (xy 383.556951 -396.869249)
			(xy 383.535503 -396.826767) (xy 383.520911 -396.78147) (xy 383.513529 -396.734457) (xy 383.513076 -396.710662)
			(xy 382.923796 -396.710662) (xy 382.923705 -396.721944) (xy 382.922052 -396.744446) (xy 382.920494 -396.75562)
			(xy 382.919224 -396.76451) (xy 382.92278 -396.782036) (xy 382.966214 -396.852902) (xy 382.97993 -396.864078)
			(xy 382.988566 -396.866872) (xy 383.01081 -396.87481) (xy 383.05273 -396.896561) (xy 383.090802 -396.924506)
			(xy 383.124119 -396.957979) (xy 383.151887 -396.99618) (xy 383.163064 -397.016986) (xy 383.163572 -397.018002)
			(xy 383.556002 -397.696944) (xy 383.568786 -397.720294) (xy 383.58698 -397.770317) (xy 383.596264 -397.822731)
			(xy 383.596896 -397.849344) (xy 383.596446 -397.873347) (xy 383.588925 -397.920761) (xy 383.574077 -397.966414)
			(xy 383.552267 -398.00918) (xy 383.524033 -398.048006) (xy 383.49007 -398.081934) (xy 383.451215 -398.110129)
			(xy 383.408427 -398.131896) (xy 383.362759 -398.146698) (xy 383.315338 -398.15417) (xy 383.291334 -398.154652)
			(xy 383.267805 -398.154212) (xy 383.221306 -398.14698) (xy 383.176467 -398.132698) (xy 383.134351 -398.111703)
			(xy 383.095957 -398.084494) (xy 383.062193 -398.051715) (xy 383.033859 -398.014142) (xy 383.022348 -397.993616)
			(xy 383.022094 -397.993108) (xy 383.021586 -397.992346) (xy 382.623822 -397.304006) (xy 382.611925 -397.281337)
			(xy 382.595052 -397.233006) (xy 382.586491 -397.182536) (xy 382.585976 -397.15694) (xy 382.585976 -397.156432)
			(xy 382.58606 -397.145087) (xy 382.587716 -397.122457) (xy 382.589278 -397.11122) (xy 382.590548 -397.10233)
			(xy 382.586992 -397.085058) (xy 382.543558 -397.013938) (xy 382.529588 -397.003016) (xy 382.521206 -396.999968)
			(xy 382.498802 -396.99195) (xy 382.456603 -396.969966) (xy 382.418323 -396.941704) (xy 382.38489 -396.907847)
			(xy 382.357113 -396.869214) (xy 382.335662 -396.826741) (xy 382.321058 -396.781456) (xy 382.313654 -396.734453)
			(xy 382.31318 -396.710662) (xy 382.313762 -396.684292) (xy 382.322864 -396.632341) (xy 382.340741 -396.582721)
			(xy 382.353312 -396.559532) (xy 382.357884 -396.551404) (xy 382.360678 -396.534132) (xy 382.345438 -396.451328)
			(xy 382.336294 -396.436088) (xy 382.329182 -396.4305) (xy 382.306991 -396.411816) (xy 382.267038 -396.369757)
			(xy 382.232718 -396.322988) (xy 382.204582 -396.272257) (xy 382.18308 -396.218379) (xy 382.168557 -396.162216)
			(xy 382.161245 -396.104667) (xy 382.16078 -396.075662) (xy 382.161383 -396.042342) (xy 382.171048 -395.976405)
			(xy 382.190168 -395.912566) (xy 382.203706 -395.882114) (xy 382.207976 -395.871644) (xy 382.20791 -395.849064)
			(xy 382.198155 -395.828699) (xy 382.189736 -395.821154) (xy 382.167489 -395.80248) (xy 382.127427 -395.760425)
			(xy 382.093008 -395.713639) (xy 382.064786 -395.662873) (xy 382.043213 -395.608945) (xy 382.028638 -395.55272)
			(xy 382.021293 -395.495104) (xy 382.020826 -395.466062) (xy 382.021271 -395.437137) (xy 382.028565 -395.379747)
			(xy 382.043031 -395.323734) (xy 382.064439 -395.26999) (xy 382.092448 -395.219371) (xy 382.126611 -395.172685)
			(xy 382.166384 -395.130675) (xy 382.188466 -395.111986) (xy 382.195537 -395.10572) (xy 382.204818 -395.089278)
			(xy 382.2065 -395.079982) (xy 382.210818 -395.048994) (xy 382.211766 -395.039756) (xy 382.207733 -395.021644)
			(xy 382.202944 -395.013688) (xy 382.18991 -394.993291) (xy 382.169309 -394.949489) (xy 382.155321 -394.903149)
			(xy 382.148247 -394.855264) (xy 382.147826 -394.831062) (xy 382.14808 -394.81887) (xy 382.148334 -394.809218)
			(xy 382.142238 -394.791184) (xy 382.083564 -394.723874) (xy 382.0668 -394.715238) (xy 382.056894 -394.714222)
			(xy 382.029979 -394.710874) (xy 381.977675 -394.696533) (xy 381.928413 -394.673847) (xy 381.883515 -394.643425)
			(xy 381.844184 -394.606083) (xy 381.811475 -394.562822) (xy 381.786266 -394.514803) (xy 381.769233 -394.463313)
			(xy 381.76454 -394.4366) (xy 381.763016 -394.427202) (xy 381.49022 -393.95527) (xy 381.482854 -393.949428)
			(xy 381.462053 -393.931838) (xy 381.425945 -393.891054) (xy 381.397005 -393.844906) (xy 381.376015 -393.794641)
			(xy 381.363543 -393.741617) (xy 381.361188 -393.714478) (xy 381.359918 -393.694412) (xy 381.330454 -393.66698)
			(xy 380.916942 -393.66698) (xy 380.908051 -393.667314) (xy 380.891342 -393.673399) (xy 380.877733 -393.684845)
			(xy 380.873 -393.69238) (xy 380.866142 -393.704318) (xy 380.866142 -393.731242) (xy 381.092202 -394.122402)
			(xy 381.099568 -394.128244) (xy 381.118348 -394.144047) (xy 381.151484 -394.180253) (xy 381.178907 -394.220957)
			(xy 381.200015 -394.265267) (xy 381.214346 -394.312208) (xy 381.221583 -394.360752) (xy 381.221996 -394.385292)
			(xy 381.221742 -394.397484) (xy 381.221488 -394.407136) (xy 381.227584 -394.42517) (xy 381.286258 -394.49248)
			(xy 381.303022 -394.501116) (xy 381.312674 -394.502132) (xy 381.339444 -394.505456) (xy 381.391475 -394.519677)
			(xy 381.440509 -394.542153) (xy 381.485247 -394.572287) (xy 381.524502 -394.609281) (xy 381.557234 -394.652154)
			(xy 381.582575 -394.699771) (xy 381.599854 -394.750868) (xy 381.608613 -394.804092) (xy 381.609092 -394.831062)
			(xy 381.608529 -394.858344) (xy 381.599565 -394.912166) (xy 381.581889 -394.963787) (xy 381.555982 -395.011808)
			(xy 381.522546 -395.054926) (xy 381.50292 -395.073886) (xy 381.495473 -395.081378) (xy 381.486936 -395.100674)
			(xy 381.48641 -395.111224) (xy 381.48641 -395.1859) (xy 381.487001 -395.196433) (xy 381.495536 -395.215702)
			(xy 381.50292 -395.223238) (xy 381.522575 -395.24217) (xy 381.556019 -395.285291) (xy 381.581927 -395.333317)
			(xy 381.599597 -395.384947) (xy 381.608548 -395.438777) (xy 381.609092 -395.466062) (xy 381.608659 -395.49018)
			(xy 381.601663 -395.537904) (xy 381.587814 -395.584109) (xy 381.567405 -395.627813) (xy 381.554482 -395.64818)
			(xy 381.54864 -395.65707) (xy 381.545084 -395.677136) (xy 381.566166 -395.769338) (xy 381.578358 -395.786102)
			(xy 381.587248 -395.791436) (xy 381.608049 -395.804292) (xy 381.645964 -395.835171) (xy 381.678912 -395.871302)
			(xy 381.706173 -395.911896) (xy 381.727151 -395.956066) (xy 381.741389 -396.002845) (xy 381.748574 -396.051213)
			(xy 381.749046 -396.075662) (xy 381.748608 -396.100033) (xy 381.741452 -396.148246) (xy 381.727304 -396.194889)
			(xy 381.70647 -396.238953) (xy 381.679399 -396.279485) (xy 381.646678 -396.315611) (xy 381.628142 -396.33144)
			(xy 381.619252 -396.338552) (xy 381.609854 -396.35811) (xy 381.60706 -396.457424) (xy 381.615696 -396.47749)
			(xy 381.624078 -396.48511) (xy 381.642501 -396.502597) (xy 381.673845 -396.542564) (xy 381.698144 -396.587167)
			(xy 381.714727 -396.635175) (xy 381.723138 -396.685266) (xy 381.723646 -396.710662) (xy 381.723555 -396.721944)
			(xy 381.721902 -396.744446) (xy 381.720344 -396.75562) (xy 381.719074 -396.76451) (xy 381.72263 -396.782036)
			(xy 381.766064 -396.852902) (xy 381.77978 -396.864078) (xy 381.788416 -396.866872) (xy 381.810658 -396.874813)
			(xy 381.852572 -396.896569) (xy 381.890639 -396.924517) (xy 381.923951 -396.957991) (xy 381.951713 -396.996194)
			(xy 381.962914 -397.016986) (xy 381.963422 -397.018002) (xy 382.355852 -397.696944) (xy 382.368662 -397.720276)
			(xy 382.386814 -397.770308) (xy 382.396 -397.822732) (xy 382.396492 -397.849344) (xy 382.396018 -397.873333)
			(xy 382.388506 -397.920718) (xy 382.373675 -397.966345) (xy 382.351889 -398.00909) (xy 382.323684 -398.047902)
			(xy 382.289756 -398.081823) (xy 382.250939 -398.11002) (xy 382.20819 -398.131798) (xy 382.16256 -398.14662)
			(xy 382.115173 -398.154123) (xy 382.091184 -398.154652) (xy 382.067653 -398.154216) (xy 382.021149 -398.14699)
			(xy 381.976305 -398.132713) (xy 381.934183 -398.111722) (xy 381.895782 -398.084515) (xy 381.862012 -398.051737)
			(xy 381.833673 -398.014163) (xy 381.822198 -397.993616) (xy 381.821944 -397.993108) (xy 381.821436 -397.992346)
			(xy 381.423672 -397.304006) (xy 381.411739 -397.281345) (xy 381.394789 -397.233021) (xy 381.386148 -397.182544)
			(xy 381.385572 -397.15694) (xy 381.385572 -397.156432) (xy 381.385723 -397.145083) (xy 381.387504 -397.122453)
			(xy 381.389128 -397.11122) (xy 381.390398 -397.10233) (xy 381.386842 -397.085058) (xy 381.343408 -397.013938)
			(xy 381.329438 -397.003016) (xy 381.321056 -396.999968) (xy 381.298655 -396.991948) (xy 381.256462 -396.969959)
			(xy 381.218188 -396.941694) (xy 381.184761 -396.907836) (xy 381.156988 -396.869205) (xy 381.135542 -396.826734)
			(xy 381.120941 -396.781451) (xy 381.113538 -396.734451) (xy 381.11303 -396.710662) (xy 381.11353 -396.685264)
			(xy 381.12193 -396.635168) (xy 381.138509 -396.587155) (xy 381.162809 -396.542549) (xy 381.194159 -396.502582)
			(xy 381.212598 -396.48511) (xy 381.22098 -396.47749) (xy 381.229616 -396.457424) (xy 381.226822 -396.35811)
			(xy 381.217424 -396.338552) (xy 381.208534 -396.33144) (xy 381.189971 -396.315639) (xy 381.157241 -396.279513)
			(xy 381.130166 -396.238977) (xy 381.109331 -396.194906) (xy 381.095187 -396.148256) (xy 381.08804 -396.100036)
			(xy 381.08763 -396.075662) (xy 381.088069 -396.051546) (xy 381.095075 -396.003826) (xy 381.108933 -395.957628)
			(xy 381.129351 -395.913931) (xy 381.14224 -395.893544) (xy 381.148082 -395.884654) (xy 381.151638 -395.864588)
			(xy 381.130556 -395.772386) (xy 381.118364 -395.755622) (xy 381.109474 -395.750288) (xy 381.088671 -395.737433)
			(xy 381.050751 -395.706556) (xy 381.017799 -395.670426) (xy 380.990533 -395.629833) (xy 380.969549 -395.585663)
			(xy 380.955308 -395.538882) (xy 380.948118 -395.490513) (xy 380.947676 -395.466062) (xy 380.948237 -395.438779)
			(xy 380.957197 -395.384954) (xy 380.974869 -395.333329) (xy 381.000772 -395.285304) (xy 381.034205 -395.242181)
			(xy 381.053848 -395.223238) (xy 381.061303 -395.215749) (xy 381.069855 -395.196453) (xy 381.070358 -395.1859)
			(xy 381.070358 -395.111224) (xy 381.069771 -395.10069) (xy 381.061238 -395.081418) (xy 381.053848 -395.073886)
			(xy 381.034193 -395.054953) (xy 381.000749 -395.011833) (xy 380.97484 -394.963806) (xy 380.957169 -394.912177)
			(xy 380.948215 -394.858347) (xy 380.947676 -394.831062) (xy 380.94793 -394.81887) (xy 380.948184 -394.809218)
			(xy 380.942088 -394.791184) (xy 380.883414 -394.723874) (xy 380.86665 -394.715238) (xy 380.856998 -394.714222)
			(xy 380.830083 -394.710874) (xy 380.777778 -394.696534) (xy 380.728516 -394.673848) (xy 380.683617 -394.643427)
			(xy 380.644285 -394.606085) (xy 380.611576 -394.562823) (xy 380.586367 -394.514804) (xy 380.569333 -394.463313)
			(xy 380.564644 -394.4366) (xy 380.56312 -394.427202) (xy 380.290324 -393.95527) (xy 380.282958 -393.949428)
			(xy 380.262156 -393.931839) (xy 380.226048 -393.891055) (xy 380.197108 -393.844907) (xy 380.176118 -393.794642)
			(xy 380.163645 -393.741617) (xy 380.161292 -393.714478) (xy 380.160022 -393.694412) (xy 380.130558 -393.66698)
			(xy 379.716792 -393.66698) (xy 379.707896 -393.667306) (xy 379.691174 -393.67338) (xy 379.677551 -393.684822)
			(xy 379.67285 -393.69238) (xy 379.665992 -393.704318) (xy 379.665992 -393.731242) (xy 379.892052 -394.122402)
			(xy 379.899418 -394.128244) (xy 379.918195 -394.144049) (xy 379.951326 -394.180257) (xy 379.978745 -394.220962)
			(xy 379.99985 -394.26527) (xy 380.014178 -394.312211) (xy 380.021415 -394.360753) (xy 380.021846 -394.385292)
			(xy 380.021592 -394.397484) (xy 380.021338 -394.407136) (xy 380.027434 -394.42517) (xy 380.086108 -394.49248)
			(xy 380.102872 -394.501116) (xy 380.112778 -394.502132) (xy 380.139547 -394.505457) (xy 380.191578 -394.519678)
			(xy 380.240612 -394.542154) (xy 380.285349 -394.572288) (xy 380.324604 -394.609282) (xy 380.357335 -394.652155)
			(xy 380.382676 -394.699771) (xy 380.399955 -394.750869) (xy 380.408713 -394.804092) (xy 380.409196 -394.831062)
			(xy 380.408633 -394.858344) (xy 380.399669 -394.912166) (xy 380.381993 -394.963787) (xy 380.356087 -395.011808)
			(xy 380.32265 -395.054927) (xy 380.303024 -395.073886) (xy 380.295576 -395.081378) (xy 380.287038 -395.100674)
			(xy 380.286514 -395.111224) (xy 380.286514 -395.1859) (xy 380.287105 -395.196433) (xy 380.295641 -395.215701)
			(xy 380.303024 -395.223238) (xy 380.322679 -395.24217) (xy 380.356122 -395.285291) (xy 380.38203 -395.333318)
			(xy 380.399699 -395.384947) (xy 380.408651 -395.438777) (xy 380.409196 -395.466062) (xy 380.408763 -395.49018)
			(xy 380.401767 -395.537905) (xy 380.387918 -395.584109) (xy 380.36751 -395.627813) (xy 380.354586 -395.64818)
			(xy 380.348744 -395.65707) (xy 380.345188 -395.677136) (xy 380.36627 -395.769338) (xy 380.378462 -395.786102)
			(xy 380.387352 -395.791436) (xy 380.408153 -395.804292) (xy 380.446067 -395.835171) (xy 380.479015 -395.871303)
			(xy 380.506275 -395.911897) (xy 380.527254 -395.956066) (xy 380.541491 -396.002845) (xy 380.548676 -396.051213)
			(xy 380.54915 -396.075662) (xy 380.548712 -396.100033) (xy 380.541557 -396.148246) (xy 380.527408 -396.194889)
			(xy 380.506574 -396.238953) (xy 380.479504 -396.279486) (xy 380.446783 -396.315612) (xy 380.428246 -396.33144)
			(xy 380.419356 -396.338552) (xy 380.409958 -396.35811) (xy 380.407164 -396.457424) (xy 380.4158 -396.47749)
			(xy 380.424182 -396.48511) (xy 380.442605 -396.502597) (xy 380.473948 -396.542565) (xy 380.498247 -396.587167)
			(xy 380.51483 -396.635176) (xy 380.52324 -396.685266) (xy 380.52375 -396.710662) (xy 380.523659 -396.721944)
			(xy 380.522006 -396.744446) (xy 380.520448 -396.75562) (xy 380.519178 -396.76451) (xy 380.522734 -396.782036)
			(xy 380.566168 -396.852902) (xy 380.579884 -396.864078) (xy 380.58852 -396.866872) (xy 380.610761 -396.874813)
			(xy 380.652676 -396.89657) (xy 380.690742 -396.924518) (xy 380.724053 -396.957992) (xy 380.751816 -396.996195)
			(xy 380.763018 -397.016986) (xy 380.763526 -397.018002) (xy 381.155956 -397.696944) (xy 381.168766 -397.720276)
			(xy 381.186918 -397.770308) (xy 381.196104 -397.822732) (xy 381.196596 -397.849344) (xy 381.196122 -397.873333)
			(xy 381.18861 -397.920718) (xy 381.173779 -397.966346) (xy 381.151993 -398.009091) (xy 381.123789 -398.047903)
			(xy 381.08986 -398.081825) (xy 381.051044 -398.110022) (xy 381.008294 -398.1318) (xy 380.962664 -398.146624)
			(xy 380.915277 -398.154126) (xy 380.891288 -398.154652) (xy 380.867757 -398.154216) (xy 380.821252 -398.146991)
			(xy 380.776408 -398.132714) (xy 380.734286 -398.111724) (xy 380.695884 -398.084517) (xy 380.662114 -398.051738)
			(xy 380.633774 -398.014165) (xy 380.622302 -397.993616) (xy 380.622048 -397.993108) (xy 380.62154 -397.992346)
			(xy 380.223776 -397.304006) (xy 380.211843 -397.281345) (xy 380.194893 -397.233021) (xy 380.186251 -397.182544)
			(xy 380.185676 -397.15694) (xy 380.185676 -397.156432) (xy 380.185827 -397.145083) (xy 380.187608 -397.122453)
			(xy 380.189232 -397.11122) (xy 380.190502 -397.10233) (xy 380.186946 -397.085058) (xy 380.143512 -397.013938)
			(xy 380.129542 -397.003016) (xy 380.12116 -396.999968) (xy 380.098759 -396.991948) (xy 380.056565 -396.96996)
			(xy 380.018291 -396.941695) (xy 379.984863 -396.907837) (xy 379.95709 -396.869205) (xy 379.935643 -396.826734)
			(xy 379.921042 -396.781451) (xy 379.913639 -396.734451) (xy 379.913134 -396.710662) (xy 379.913634 -396.685264)
			(xy 379.922034 -396.635169) (xy 379.938613 -396.587155) (xy 379.962914 -396.54255) (xy 379.994264 -396.502583)
			(xy 380.012702 -396.48511) (xy 380.021084 -396.47749) (xy 380.02972 -396.457424) (xy 380.026926 -396.35811)
			(xy 380.017528 -396.338552) (xy 380.008638 -396.33144) (xy 379.990075 -396.315639) (xy 379.957345 -396.279513)
			(xy 379.930269 -396.238977) (xy 379.909433 -396.194907) (xy 379.895289 -396.148256) (xy 379.888143 -396.100036)
			(xy 379.887734 -396.075662) (xy 379.888173 -396.051546) (xy 379.895179 -396.003826) (xy 379.909038 -395.957629)
			(xy 379.929455 -395.913932) (xy 379.942344 -395.893544) (xy 379.948186 -395.884654) (xy 379.951742 -395.864588)
			(xy 379.93066 -395.772386) (xy 379.918468 -395.755622) (xy 379.909578 -395.750288) (xy 379.888775 -395.737434)
			(xy 379.850855 -395.706557) (xy 379.817902 -395.670427) (xy 379.790635 -395.629833) (xy 379.769652 -395.585663)
			(xy 379.75541 -395.538882) (xy 379.74822 -395.490513) (xy 379.74778 -395.466062) (xy 379.748341 -395.438779)
			(xy 379.757301 -395.384954) (xy 379.774973 -395.33333) (xy 379.800876 -395.285305) (xy 379.83431 -395.242181)
			(xy 379.853952 -395.223238) (xy 379.861406 -395.215749) (xy 379.869958 -395.196453) (xy 379.870462 -395.1859)
			(xy 379.870462 -395.111224) (xy 379.869875 -395.10069) (xy 379.861342 -395.081417) (xy 379.853952 -395.073886)
			(xy 379.834297 -395.054953) (xy 379.800853 -395.011833) (xy 379.774943 -394.963806) (xy 379.757272 -394.912177)
			(xy 379.748317 -394.858347) (xy 379.74778 -394.831062) (xy 379.748034 -394.81887) (xy 379.748288 -394.809218)
			(xy 379.742192 -394.791184) (xy 379.683518 -394.723874) (xy 379.666754 -394.715238) (xy 379.656848 -394.714222)
			(xy 379.629935 -394.71087) (xy 379.577637 -394.696524) (xy 379.528381 -394.673835) (xy 379.483489 -394.643411)
			(xy 379.444164 -394.606068) (xy 379.411461 -394.562809) (xy 379.386256 -394.514791) (xy 379.369226 -394.463304)
			(xy 379.364494 -394.4366) (xy 379.36297 -394.427202) (xy 379.08992 -393.954762) (xy 379.082808 -393.94892)
			(xy 379.062074 -393.93135) (xy 379.026082 -393.890633) (xy 378.997223 -393.844585) (xy 378.976272 -393.794442)
			(xy 378.963793 -393.74155) (xy 378.961396 -393.714478) (xy 378.960126 -393.694412) (xy 378.930662 -393.66698)
			(xy 378.516896 -393.66698) (xy 378.508 -393.667306) (xy 378.491277 -393.673378) (xy 378.477653 -393.684821)
			(xy 378.472954 -393.69238) (xy 378.466096 -393.704318) (xy 378.466096 -393.731242) (xy 378.692156 -394.122402)
			(xy 378.699522 -394.128244) (xy 378.718299 -394.144049) (xy 378.75143 -394.180257) (xy 378.778848 -394.220962)
			(xy 378.799953 -394.265271) (xy 378.814281 -394.312211) (xy 378.821517 -394.360753) (xy 378.82195 -394.385292)
			(xy 378.821696 -394.397484) (xy 378.821442 -394.407136) (xy 378.827538 -394.42517) (xy 378.886212 -394.49248)
			(xy 378.902976 -394.501116) (xy 378.912882 -394.502132) (xy 378.939651 -394.505457) (xy 378.991682 -394.519679)
			(xy 379.040715 -394.542155) (xy 379.085451 -394.572289) (xy 379.124705 -394.609283) (xy 379.157436 -394.652156)
			(xy 379.182777 -394.699772) (xy 379.200055 -394.750869) (xy 379.208814 -394.804092) (xy 379.2093 -394.831062)
			(xy 379.208737 -394.858344) (xy 379.199773 -394.912166) (xy 379.182098 -394.963788) (xy 379.156191 -395.011809)
			(xy 379.122755 -395.054928) (xy 379.103128 -395.073886) (xy 379.09568 -395.081378) (xy 379.087141 -395.100673)
			(xy 379.086618 -395.111224) (xy 379.086618 -395.1859) (xy 379.087209 -395.196433) (xy 379.095745 -395.215701)
			(xy 379.103128 -395.223238) (xy 379.122783 -395.24217) (xy 379.156226 -395.285291) (xy 379.182133 -395.333318)
			(xy 379.199802 -395.384947) (xy 379.208753 -395.438777) (xy 379.2093 -395.466062) (xy 379.208867 -395.49018)
			(xy 379.201871 -395.537905) (xy 379.188023 -395.584109) (xy 379.167614 -395.627814) (xy 379.15469 -395.64818)
			(xy 379.148848 -395.65707) (xy 379.145292 -395.677136) (xy 379.166374 -395.769338) (xy 379.178566 -395.786102)
			(xy 379.187456 -395.791436) (xy 379.208257 -395.804292) (xy 379.24617 -395.835172) (xy 379.279118 -395.871303)
			(xy 379.306378 -395.911897) (xy 379.327356 -395.956066) (xy 379.341593 -396.002846) (xy 379.348778 -396.051213)
			(xy 379.349254 -396.075662) (xy 379.348816 -396.100033) (xy 379.341661 -396.148246) (xy 379.327513 -396.194889)
			(xy 379.306678 -396.238953) (xy 379.279608 -396.279487) (xy 379.246888 -396.315613) (xy 379.22835 -396.33144)
			(xy 379.21946 -396.338552) (xy 379.210062 -396.35811) (xy 379.207268 -396.457424) (xy 379.215904 -396.47749)
			(xy 379.224286 -396.48511) (xy 379.242709 -396.502597) (xy 379.274052 -396.542565) (xy 379.29835 -396.587167)
			(xy 379.314933 -396.635176) (xy 379.323343 -396.685266) (xy 379.323854 -396.710662) (xy 379.323763 -396.721944)
			(xy 379.32211 -396.744446) (xy 379.320552 -396.75562) (xy 379.319282 -396.764764) (xy 379.322584 -396.782036)
			(xy 379.366272 -396.853156) (xy 379.379988 -396.864078) (xy 379.388624 -396.866872) (xy 379.416757 -396.87714)
			(xy 379.468694 -396.90694) (xy 379.491748 -396.926054) (xy 379.513193 -396.945672) (xy 379.54899 -396.991449)
			(xy 379.562868 -397.016986) (xy 379.56363 -397.018256) (xy 379.955806 -397.696944) (xy 379.96859 -397.720294)
			(xy 379.986784 -397.770317) (xy 379.996068 -397.822731) (xy 379.9967 -397.849344) (xy 379.99625 -397.873347)
			(xy 379.988729 -397.920761) (xy 379.973881 -397.966414) (xy 379.952071 -398.009181) (xy 379.923837 -398.048007)
			(xy 379.889874 -398.081936) (xy 379.85102 -398.110132) (xy 379.808231 -398.131899) (xy 379.762563 -398.146701)
			(xy 379.715142 -398.154173) (xy 379.691138 -398.154652) (xy 379.667609 -398.154212) (xy 379.621109 -398.146981)
			(xy 379.57627 -398.132699) (xy 379.534154 -398.111705) (xy 379.495759 -398.084496) (xy 379.461994 -398.051716)
			(xy 379.43366 -398.014144) (xy 379.422152 -397.993616) (xy 379.421898 -397.993108) (xy 379.42139 -397.992346)
			(xy 379.020832 -397.298926) (xy 379.009763 -397.276825) (xy 378.994124 -397.229938) (xy 378.986231 -397.181146)
			(xy 378.98578 -397.156432) (xy 378.985864 -397.145087) (xy 378.98752 -397.122457) (xy 378.989082 -397.11122)
			(xy 378.990352 -397.10233) (xy 378.986796 -397.085058) (xy 378.943362 -397.013938) (xy 378.929646 -397.002762)
			(xy 378.92101 -396.999968) (xy 378.898625 -396.991937) (xy 378.856466 -396.969931) (xy 378.818229 -396.941654)
			(xy 378.78484 -396.90779) (xy 378.757106 -396.869159) (xy 378.735698 -396.826693) (xy 378.721133 -396.781422)
			(xy 378.713765 -396.73444) (xy 378.713238 -396.710662) (xy 378.713738 -396.685264) (xy 378.722139 -396.635169)
			(xy 378.738718 -396.587155) (xy 378.763018 -396.54255) (xy 378.794369 -396.502584) (xy 378.812806 -396.48511)
			(xy 378.821188 -396.47749) (xy 378.829824 -396.457424) (xy 378.82703 -396.35811) (xy 378.817632 -396.338552)
			(xy 378.808742 -396.33144) (xy 378.790179 -396.315639) (xy 378.757448 -396.279514) (xy 378.730372 -396.238977)
			(xy 378.709536 -396.194907) (xy 378.695392 -396.148257) (xy 378.688245 -396.100036) (xy 378.687838 -396.075662)
			(xy 378.688277 -396.051546) (xy 378.695283 -396.003826) (xy 378.709142 -395.957629) (xy 378.72956 -395.913932)
			(xy 378.742448 -395.893544) (xy 378.74829 -395.884654) (xy 378.751846 -395.864588) (xy 378.730764 -395.772386)
			(xy 378.718572 -395.755622) (xy 378.709682 -395.750288) (xy 378.688878 -395.737434) (xy 378.650958 -395.706557)
			(xy 378.618005 -395.670427) (xy 378.590738 -395.629833) (xy 378.569754 -395.585663) (xy 378.555512 -395.538882)
			(xy 378.548322 -395.490513) (xy 378.547884 -395.466062) (xy 378.548445 -395.438779) (xy 378.557406 -395.384955)
			(xy 378.575077 -395.33333) (xy 378.600981 -395.285305) (xy 378.634414 -395.242182) (xy 378.654056 -395.223238)
			(xy 378.66151 -395.215748) (xy 378.67006 -395.196453) (xy 378.670566 -395.1859) (xy 378.670566 -395.111224)
			(xy 378.669979 -395.10069) (xy 378.661447 -395.081417) (xy 378.654056 -395.073886) (xy 378.6344 -395.054954)
			(xy 378.600956 -395.011833) (xy 378.575046 -394.963807) (xy 378.557375 -394.912177) (xy 378.54842 -394.858347)
			(xy 378.547884 -394.831062) (xy 378.548138 -394.81887) (xy 378.548392 -394.809218) (xy 378.542296 -394.791184)
			(xy 378.483622 -394.723874) (xy 378.466858 -394.715238) (xy 378.456952 -394.714222) (xy 378.430039 -394.710871)
			(xy 378.37774 -394.696525) (xy 378.328484 -394.673836) (xy 378.283591 -394.643412) (xy 378.244266 -394.60607)
			(xy 378.211562 -394.56281) (xy 378.186357 -394.514792) (xy 378.169327 -394.463305) (xy 378.164598 -394.4366)
			(xy 378.163074 -394.427202) (xy 377.890278 -393.95527) (xy 377.882912 -393.949428) (xy 377.862108 -393.93184)
			(xy 377.825994 -393.891059) (xy 377.797049 -393.844911) (xy 377.776055 -393.794646) (xy 377.76358 -393.74162)
			(xy 377.761246 -393.714478) (xy 377.759976 -393.694412) (xy 377.730512 -393.66698) (xy 377.317 -393.66698)
			(xy 377.308112 -393.667321) (xy 377.291414 -393.673415) (xy 377.277817 -393.684864) (xy 377.273058 -393.69238)
			(xy 377.2662 -393.704318) (xy 377.2662 -393.731242) (xy 377.49226 -394.122402) (xy 377.499626 -394.128244)
			(xy 377.518403 -394.144049) (xy 377.551533 -394.180257) (xy 377.578952 -394.220962) (xy 377.600056 -394.265271)
			(xy 377.614384 -394.312211) (xy 377.62162 -394.360753) (xy 377.622054 -394.385292) (xy 377.6218 -394.397484)
			(xy 377.621546 -394.407136) (xy 377.627642 -394.42517) (xy 377.686316 -394.49248) (xy 377.70308 -394.501116)
			(xy 377.712732 -394.502132) (xy 377.739498 -394.505461) (xy 377.791522 -394.519688) (xy 377.840549 -394.542168)
			(xy 377.885278 -394.572304) (xy 377.924526 -394.609298) (xy 377.957251 -394.65217) (xy 377.982587 -394.699783)
			(xy 377.999862 -394.750876) (xy 378.008619 -394.804095) (xy 378.00915 -394.831062) (xy 378.008587 -394.858344)
			(xy 377.999624 -394.912168) (xy 377.981951 -394.963791) (xy 377.956047 -395.011814) (xy 377.922614 -395.054937)
			(xy 377.902978 -395.073886) (xy 377.895536 -395.081381) (xy 377.887006 -395.100676) (xy 377.886468 -395.111224)
			(xy 377.886468 -395.1859) (xy 377.887058 -395.196434) (xy 377.895588 -395.215707) (xy 377.902978 -395.223238)
			(xy 377.92263 -395.242172) (xy 377.956068 -395.285294) (xy 377.981972 -395.333321) (xy 377.999638 -395.38495)
			(xy 378.008587 -395.438778) (xy 378.00915 -395.466062) (xy 378.008717 -395.490179) (xy 378.00172 -395.537904)
			(xy 377.98787 -395.584107) (xy 377.967459 -395.62781) (xy 377.95454 -395.64818) (xy 377.948698 -395.65707)
			(xy 377.945142 -395.677136) (xy 377.966224 -395.769338) (xy 377.978416 -395.786102) (xy 377.987306 -395.791436)
			(xy 378.008109 -395.80429) (xy 378.046028 -395.835167) (xy 378.07898 -395.871297) (xy 378.106245 -395.911891)
			(xy 378.127227 -395.956061) (xy 378.141466 -396.002842) (xy 378.148653 -396.051212) (xy 378.149104 -396.075662)
			(xy 378.148666 -396.100032) (xy 378.14151 -396.148245) (xy 378.12736 -396.194886) (xy 378.106524 -396.238948)
			(xy 378.079451 -396.279479) (xy 378.046728 -396.315601) (xy 378.0282 -396.33144) (xy 378.01931 -396.338552)
			(xy 378.009912 -396.35811) (xy 378.007118 -396.457424) (xy 378.015754 -396.47749) (xy 378.024136 -396.48511)
			(xy 378.042556 -396.502599) (xy 378.073894 -396.542568) (xy 378.098188 -396.587171) (xy 378.114768 -396.635178)
			(xy 378.123177 -396.685267) (xy 378.123704 -396.710662) (xy 378.123613 -396.721944) (xy 378.12196 -396.744446)
			(xy 378.120402 -396.75562) (xy 378.119132 -396.76451) (xy 378.122688 -396.782036) (xy 378.166122 -396.852902)
			(xy 378.179838 -396.864078) (xy 378.188474 -396.866872) (xy 378.210718 -396.87481) (xy 378.252637 -396.896563)
			(xy 378.290708 -396.924508) (xy 378.324024 -396.957981) (xy 378.351791 -396.996183) (xy 378.362972 -397.016986)
			(xy 378.36348 -397.018002) (xy 378.75591 -397.696944) (xy 378.768694 -397.720294) (xy 378.786887 -397.770317)
			(xy 378.796171 -397.822731) (xy 378.796804 -397.849344) (xy 378.796354 -397.873347) (xy 378.788833 -397.920762)
			(xy 378.773985 -397.966415) (xy 378.752176 -398.009182) (xy 378.723941 -398.048008) (xy 378.689978 -398.081938)
			(xy 378.651124 -398.110134) (xy 378.608336 -398.131901) (xy 378.562668 -398.146704) (xy 378.515246 -398.154177)
			(xy 378.491242 -398.154652) (xy 378.467713 -398.154213) (xy 378.421212 -398.146982) (xy 378.376373 -398.1327)
			(xy 378.334256 -398.111706) (xy 378.295861 -398.084497) (xy 378.262096 -398.051718) (xy 378.233761 -398.014145)
			(xy 378.222256 -397.993616) (xy 378.222002 -397.993108) (xy 378.221494 -397.992346) (xy 377.82373 -397.304006)
			(xy 377.811833 -397.281337) (xy 377.794959 -397.233007) (xy 377.786398 -397.182536) (xy 377.785884 -397.15694)
			(xy 377.785884 -397.156432) (xy 377.785968 -397.145087) (xy 377.787624 -397.122457) (xy 377.789186 -397.11122)
			(xy 377.790456 -397.10233) (xy 377.7869 -397.085058) (xy 377.743466 -397.013938) (xy 377.729496 -397.003016)
			(xy 377.721114 -396.999968) (xy 377.69871 -396.991951) (xy 377.656509 -396.969967) (xy 377.618229 -396.941705)
			(xy 377.584795 -396.907848) (xy 377.557017 -396.869216) (xy 377.535565 -396.826742) (xy 377.520961 -396.781456)
			(xy 377.513557 -396.734453) (xy 377.513088 -396.710662) (xy 377.513588 -396.685264) (xy 377.521987 -396.635167)
			(xy 377.538564 -396.587152) (xy 377.562862 -396.542544) (xy 377.594209 -396.502574) (xy 377.612656 -396.48511)
			(xy 377.621038 -396.47749) (xy 377.629674 -396.457424) (xy 377.62688 -396.35811) (xy 377.617482 -396.338552)
			(xy 377.608592 -396.33144) (xy 377.590031 -396.315637) (xy 377.557305 -396.27951) (xy 377.530233 -396.238973)
			(xy 377.509401 -396.194903) (xy 377.495259 -396.148254) (xy 377.488113 -396.100035) (xy 377.487688 -396.075662)
			(xy 377.488127 -396.051546) (xy 377.495132 -396.003826) (xy 377.508989 -395.957627) (xy 377.529404 -395.913929)
			(xy 377.542298 -395.893544) (xy 377.54814 -395.884654) (xy 377.551696 -395.864588) (xy 377.530614 -395.772386)
			(xy 377.518422 -395.755622) (xy 377.509532 -395.750288) (xy 377.488731 -395.737432) (xy 377.450816 -395.706552)
			(xy 377.417867 -395.670421) (xy 377.390605 -395.629827) (xy 377.369625 -395.585658) (xy 377.355385 -395.538879)
			(xy 377.348197 -395.490512) (xy 377.347734 -395.466062) (xy 377.348295 -395.438779) (xy 377.357254 -395.384953)
			(xy 377.374924 -395.333327) (xy 377.400825 -395.285299) (xy 377.434255 -395.242173) (xy 377.453906 -395.223238)
			(xy 377.461354 -395.215746) (xy 377.469896 -395.196451) (xy 377.470416 -395.1859) (xy 377.470416 -395.111224)
			(xy 377.46983 -395.100688) (xy 377.461304 -395.08141) (xy 377.453906 -395.073886) (xy 377.434253 -395.054952)
			(xy 377.400814 -395.01183) (xy 377.374908 -394.963803) (xy 377.357239 -394.912175) (xy 377.348286 -394.858346)
			(xy 377.347734 -394.831062) (xy 377.347988 -394.81887) (xy 377.348242 -394.809218) (xy 377.342146 -394.791184)
			(xy 377.283472 -394.723874) (xy 377.266708 -394.715238) (xy 377.257056 -394.714222) (xy 377.230143 -394.710871)
			(xy 377.177844 -394.696526) (xy 377.128587 -394.673837) (xy 377.083693 -394.643414) (xy 377.044367 -394.606071)
			(xy 377.011663 -394.562811) (xy 376.986458 -394.514793) (xy 376.969427 -394.463306) (xy 376.964702 -394.4366)
			(xy 376.963178 -394.427202) (xy 376.690382 -393.95527) (xy 376.683016 -393.949428) (xy 376.662211 -393.931841)
			(xy 376.626097 -393.891059) (xy 376.597152 -393.844912) (xy 376.576158 -393.794646) (xy 376.563683 -393.74162)
			(xy 376.56135 -393.714478) (xy 376.56008 -393.694412) (xy 376.530616 -393.66698) (xy 376.11685 -393.66698)
			(xy 376.107958 -393.667313) (xy 376.091247 -393.673396) (xy 376.077636 -393.684841) (xy 376.072908 -393.69238)
			(xy 376.06605 -393.704318) (xy 376.06605 -393.731242) (xy 376.29211 -394.122402) (xy 376.299476 -394.128244)
			(xy 376.318255 -394.144047) (xy 376.351391 -394.180254) (xy 376.378813 -394.220958) (xy 376.399921 -394.265267)
			(xy 376.414251 -394.312209) (xy 376.421488 -394.360752) (xy 376.421904 -394.385292) (xy 376.42165 -394.397484)
			(xy 376.421396 -394.407136) (xy 376.427492 -394.42517) (xy 376.486166 -394.49248) (xy 376.50293 -394.501116)
			(xy 376.512836 -394.502132) (xy 376.539602 -394.505461) (xy 376.591626 -394.519689) (xy 376.640652 -394.542169)
			(xy 376.685381 -394.572305) (xy 376.724628 -394.609299) (xy 376.757352 -394.652171) (xy 376.782688 -394.699784)
			(xy 376.799963 -394.750877) (xy 376.80872 -394.804095) (xy 376.809254 -394.831062) (xy 376.808786 -394.855259)
			(xy 376.80169 -394.903132) (xy 376.7877 -394.949461) (xy 376.767117 -394.993261) (xy 376.754136 -395.013688)
			(xy 376.749382 -395.021657) (xy 376.745357 -395.039757) (xy 376.746262 -395.048994) (xy 376.75058 -395.079982)
			(xy 376.752383 -395.089236) (xy 376.761638 -395.105643) (xy 376.768614 -395.111986) (xy 376.790709 -395.13066)
			(xy 376.830485 -395.17267) (xy 376.864648 -395.219358) (xy 376.892655 -395.269979) (xy 376.914058 -395.323727)
			(xy 376.928517 -395.379744) (xy 376.9358 -395.437136) (xy 376.936254 -395.466062) (xy 376.93565 -395.499382)
			(xy 376.92598 -395.565316) (xy 376.906854 -395.629153) (xy 376.893328 -395.65961) (xy 376.889068 -395.67008)
			(xy 376.889143 -395.692654) (xy 376.898892 -395.713015) (xy 376.907298 -395.72057) (xy 376.929546 -395.739243)
			(xy 376.969613 -395.781298) (xy 377.004037 -395.828083) (xy 377.032266 -395.878848) (xy 377.053846 -395.932776)
			(xy 377.068429 -395.989001) (xy 377.075783 -396.046619) (xy 377.076208 -396.075662) (xy 377.075757 -396.104666)
			(xy 377.068427 -396.162209) (xy 377.05389 -396.218366) (xy 377.03238 -396.272239) (xy 377.004242 -396.322965)
			(xy 376.969925 -396.369734) (xy 376.929978 -396.411795) (xy 376.907806 -396.4305) (xy 376.900694 -396.436088)
			(xy 376.89155 -396.451328) (xy 376.87631 -396.534132) (xy 376.879104 -396.551404) (xy 376.883676 -396.559532)
			(xy 376.89627 -396.58271) (xy 376.914158 -396.632331) (xy 376.923241 -396.684289) (xy 376.923808 -396.710662)
			(xy 376.923717 -396.721944) (xy 376.922064 -396.744446) (xy 376.920506 -396.75562) (xy 376.919236 -396.76451)
			(xy 376.922792 -396.782036) (xy 376.966226 -396.852902) (xy 376.979942 -396.864078) (xy 376.988578 -396.866872)
			(xy 377.010821 -396.87481) (xy 377.05274 -396.896563) (xy 377.090811 -396.924509) (xy 377.124127 -396.957982)
			(xy 377.151893 -396.996184) (xy 377.163076 -397.016986) (xy 377.163584 -397.018002) (xy 377.556014 -397.696944)
			(xy 377.568798 -397.720294) (xy 377.586991 -397.770318) (xy 377.596275 -397.822731) (xy 377.596908 -397.849344)
			(xy 377.596458 -397.873348) (xy 377.588937 -397.920762) (xy 377.57409 -397.966416) (xy 377.55228 -398.009183)
			(xy 377.524045 -398.04801) (xy 377.490083 -398.081939) (xy 377.451228 -398.110136) (xy 377.40844 -398.131904)
			(xy 377.362772 -398.146707) (xy 377.31535 -398.154181) (xy 377.291346 -398.154652) (xy 377.267816 -398.154213)
			(xy 377.221316 -398.146983) (xy 377.176476 -398.132701) (xy 377.134359 -398.111708) (xy 377.095963 -398.084499)
			(xy 377.062197 -398.05172) (xy 377.033863 -398.014147) (xy 377.02236 -397.993616) (xy 377.022106 -397.993108)
			(xy 377.021598 -397.992346) (xy 376.623834 -397.304006) (xy 376.611936 -397.281337) (xy 376.595062 -397.233007)
			(xy 376.586502 -397.182536) (xy 376.585988 -397.15694) (xy 376.585988 -397.156432) (xy 376.586072 -397.145087)
			(xy 376.587728 -397.122458) (xy 376.58929 -397.11122) (xy 376.59056 -397.10233) (xy 376.587004 -397.085058)
			(xy 376.54357 -397.013938) (xy 376.5296 -397.003016) (xy 376.521218 -396.999968) (xy 376.498813 -396.991951)
			(xy 376.456613 -396.969968) (xy 376.418332 -396.941706) (xy 376.384897 -396.907849) (xy 376.357118 -396.869216)
			(xy 376.335667 -396.826743) (xy 376.321062 -396.781457) (xy 376.313658 -396.734453) (xy 376.313192 -396.710662)
			(xy 376.313774 -396.684292) (xy 376.322877 -396.632341) (xy 376.340754 -396.582721) (xy 376.353324 -396.559532)
			(xy 376.357896 -396.551404) (xy 376.36069 -396.534132) (xy 376.34545 -396.451328) (xy 376.336306 -396.436088)
			(xy 376.329194 -396.4305) (xy 376.307003 -396.411816) (xy 376.267048 -396.369758) (xy 376.232728 -396.322989)
			(xy 376.20459 -396.272258) (xy 376.183088 -396.21838) (xy 376.168564 -396.162216) (xy 376.161253 -396.104668)
			(xy 376.160792 -396.075662) (xy 376.161395 -396.042342) (xy 376.17106 -395.976405) (xy 376.190181 -395.912567)
			(xy 376.203718 -395.882114) (xy 376.207987 -395.871644) (xy 376.207921 -395.849063) (xy 376.198168 -395.828697)
			(xy 376.189748 -395.821154) (xy 376.167505 -395.802478) (xy 376.12745 -395.76042) (xy 376.093038 -395.713632)
			(xy 376.064821 -395.662866) (xy 376.043253 -395.608939) (xy 376.02868 -395.552717) (xy 376.021337 -395.495102)
			(xy 376.020838 -395.466062) (xy 376.021283 -395.437137) (xy 376.028577 -395.379748) (xy 376.043043 -395.323735)
			(xy 376.064452 -395.269991) (xy 376.092461 -395.219373) (xy 376.126625 -395.172687) (xy 376.166399 -395.130678)
			(xy 376.188478 -395.111986) (xy 376.195548 -395.105719) (xy 376.204826 -395.089277) (xy 376.206512 -395.079982)
			(xy 376.21083 -395.048994) (xy 376.211778 -395.039756) (xy 376.207746 -395.021644) (xy 376.202956 -395.013688)
			(xy 376.189922 -394.993291) (xy 376.169319 -394.949489) (xy 376.155331 -394.90315) (xy 376.148257 -394.855264)
			(xy 376.147838 -394.831062) (xy 376.148092 -394.81887) (xy 376.148346 -394.809218) (xy 376.14225 -394.791184)
			(xy 376.083576 -394.723874) (xy 376.066812 -394.715238) (xy 376.056906 -394.714222) (xy 376.02999 -394.710874)
			(xy 375.977685 -394.696535) (xy 375.928421 -394.67385) (xy 375.883521 -394.643429) (xy 375.844189 -394.606087)
			(xy 375.811479 -394.562826) (xy 375.786269 -394.514806) (xy 375.769235 -394.463315) (xy 375.764552 -394.4366)
			(xy 375.763028 -394.427202) (xy 375.490232 -393.95527) (xy 375.482866 -393.949428) (xy 375.462064 -393.931839)
			(xy 375.425955 -393.891055) (xy 375.397014 -393.844907) (xy 375.376024 -393.794642) (xy 375.363551 -393.741618)
			(xy 375.3612 -393.714478) (xy 375.35993 -393.694412) (xy 375.330466 -393.66698) (xy 374.916954 -393.66698)
			(xy 374.908061 -393.667312) (xy 374.891349 -393.673394) (xy 374.877737 -393.68484) (xy 374.873012 -393.69238)
			(xy 374.866154 -393.704318) (xy 374.866154 -393.731242) (xy 375.092214 -394.122402) (xy 375.09958 -394.128244)
			(xy 375.118359 -394.144047) (xy 375.151494 -394.180254) (xy 375.178916 -394.220958) (xy 375.200024 -394.265267)
			(xy 375.214353 -394.312209) (xy 375.221591 -394.360752) (xy 375.222008 -394.385292) (xy 375.221754 -394.397484)
			(xy 375.2215 -394.407136) (xy 375.227596 -394.42517) (xy 375.28627 -394.49248) (xy 375.303034 -394.501116)
			(xy 375.312686 -394.502132) (xy 375.339455 -394.505457) (xy 375.391485 -394.51968) (xy 375.440518 -394.542156)
			(xy 375.485254 -394.57229) (xy 375.524507 -394.609284) (xy 375.557238 -394.652157) (xy 375.582578 -394.699773)
			(xy 375.599856 -394.75087) (xy 375.608614 -394.804093) (xy 375.609104 -394.831062) (xy 375.608594 -394.857049)
			(xy 375.600464 -394.908384) (xy 375.584403 -394.957814) (xy 375.560807 -395.004124) (xy 375.530257 -395.046172)
			(xy 375.493506 -395.082923) (xy 375.451458 -395.113473) (xy 375.405148 -395.137069) (xy 375.355718 -395.15313)
			(xy 375.304383 -395.16126) (xy 375.252409 -395.16126) (xy 375.201074 -395.15313) (xy 375.151644 -395.137069)
			(xy 375.105334 -395.113473) (xy 375.063286 -395.082923) (xy 375.026535 -395.046172) (xy 374.995985 -395.004124)
			(xy 374.972389 -394.957814) (xy 374.956328 -394.908384) (xy 374.948198 -394.857049) (xy 374.947688 -394.831062)
			(xy 374.947942 -394.81887) (xy 374.948196 -394.809218) (xy 374.9421 -394.791184) (xy 374.883426 -394.723874)
			(xy 374.866662 -394.715238) (xy 374.85701 -394.714222) (xy 374.830094 -394.710875) (xy 374.777788 -394.696536)
			(xy 374.728524 -394.673852) (xy 374.683623 -394.64343) (xy 374.64429 -394.606088) (xy 374.61158 -394.562827)
			(xy 374.586369 -394.514807) (xy 374.569335 -394.463316) (xy 374.564656 -394.4366) (xy 374.563132 -394.427202)
			(xy 374.290336 -393.95527) (xy 374.28297 -393.949428) (xy 374.262168 -393.931839) (xy 374.226058 -393.891055)
			(xy 374.197117 -393.844908) (xy 374.176126 -393.794643) (xy 374.163653 -393.741618) (xy 374.161304 -393.714478)
			(xy 374.160034 -393.694412) (xy 374.13057 -393.66698) (xy 373.716804 -393.66698) (xy 373.707916 -393.66732)
			(xy 373.691217 -393.673413) (xy 373.677618 -393.684862) (xy 373.672862 -393.69238) (xy 373.666004 -393.704318)
			(xy 373.666004 -393.731242) (xy 373.892064 -394.122402) (xy 373.89943 -394.128244) (xy 373.918207 -394.144049)
			(xy 373.951337 -394.180257) (xy 373.978755 -394.220962) (xy 373.999859 -394.265271) (xy 374.014186 -394.312211)
			(xy 374.021423 -394.360753) (xy 374.021858 -394.385292) (xy 374.021604 -394.397484) (xy 374.02135 -394.407136)
			(xy 374.027446 -394.42517) (xy 374.08612 -394.49248) (xy 374.102884 -394.501116) (xy 374.11279 -394.502132)
			(xy 374.139559 -394.505458) (xy 374.191588 -394.51968) (xy 374.24062 -394.542157) (xy 374.285356 -394.572291)
			(xy 374.324609 -394.609286) (xy 374.357339 -394.652158) (xy 374.382679 -394.699774) (xy 374.399957 -394.75087)
			(xy 374.408715 -394.804093) (xy 374.409208 -394.831062) (xy 374.408645 -394.858344) (xy 374.399681 -394.912166)
			(xy 374.382006 -394.963788) (xy 374.3561 -395.01181) (xy 374.322665 -395.054929) (xy 374.303036 -395.073886)
			(xy 374.295587 -395.081377) (xy 374.287047 -395.100673) (xy 374.286526 -395.111224) (xy 374.286526 -395.1859)
			(xy 374.287117 -395.196433) (xy 374.295654 -395.215699) (xy 374.303036 -395.223238) (xy 374.322691 -395.242171)
			(xy 374.356132 -395.285292) (xy 374.382039 -395.333318) (xy 374.399708 -395.384948) (xy 374.408659 -395.438777)
			(xy 374.409208 -395.466062) (xy 374.408775 -395.49018) (xy 374.401779 -395.537905) (xy 374.387931 -395.584109)
			(xy 374.367523 -395.627814) (xy 374.354598 -395.64818) (xy 374.348756 -395.65707) (xy 374.3452 -395.677136)
			(xy 374.366282 -395.769338) (xy 374.378474 -395.786102) (xy 374.387364 -395.791436) (xy 374.408164 -395.804293)
			(xy 374.446077 -395.835172) (xy 374.479024 -395.871304) (xy 374.506283 -395.911898) (xy 374.527261 -395.956067)
			(xy 374.541498 -396.002846) (xy 374.548682 -396.051213) (xy 374.549162 -396.075662) (xy 374.548724 -396.100033)
			(xy 374.541569 -396.148246) (xy 374.527421 -396.19489) (xy 374.506587 -396.238954) (xy 374.479518 -396.279488)
			(xy 374.446797 -396.315615) (xy 374.428258 -396.33144) (xy 374.419368 -396.338552) (xy 374.40997 -396.35811)
			(xy 374.407176 -396.457424) (xy 374.415812 -396.47749) (xy 374.424194 -396.48511) (xy 374.442616 -396.502598)
			(xy 374.473959 -396.542565) (xy 374.498256 -396.587168) (xy 374.514838 -396.635176) (xy 374.523248 -396.685266)
			(xy 374.523762 -396.710662) (xy 375.113042 -396.710662) (xy 375.113564 -396.685407) (xy 375.121877 -396.635585)
			(xy 375.138278 -396.587811) (xy 375.162319 -396.543388) (xy 375.193343 -396.503528) (xy 375.230505 -396.469318)
			(xy 375.272791 -396.441692) (xy 375.319047 -396.421402) (xy 375.368012 -396.409002) (xy 375.41835 -396.404831)
			(xy 375.468688 -396.409002) (xy 375.517653 -396.421402) (xy 375.563909 -396.441692) (xy 375.606195 -396.469318)
			(xy 375.643357 -396.503528) (xy 375.674381 -396.543388) (xy 375.698422 -396.587811) (xy 375.714823 -396.635585)
			(xy 375.723136 -396.685407) (xy 375.723658 -396.710662) (xy 375.723555 -396.721943) (xy 375.721903 -396.744445)
			(xy 375.720356 -396.75562) (xy 375.719086 -396.76451) (xy 375.722642 -396.782036) (xy 375.766076 -396.852902)
			(xy 375.779792 -396.864078) (xy 375.788428 -396.866872) (xy 375.810668 -396.87482) (xy 375.85259 -396.896567)
			(xy 375.890665 -396.924509) (xy 375.923984 -396.957978) (xy 375.951754 -396.996178) (xy 375.962926 -397.016986)
			(xy 375.963434 -397.018002) (xy 376.355864 -397.696944) (xy 376.368602 -397.720307) (xy 376.386714 -397.770336)
			(xy 376.395922 -397.822741) (xy 376.396504 -397.849344) (xy 376.396078 -397.873337) (xy 376.388565 -397.92073)
			(xy 376.373731 -397.966365) (xy 376.351942 -398.009118) (xy 376.323733 -398.047937) (xy 376.2898 -398.081865)
			(xy 376.250977 -398.110067) (xy 376.208221 -398.13185) (xy 376.162583 -398.146676) (xy 376.115189 -398.154182)
			(xy 376.091196 -398.154652) (xy 376.067665 -398.154172) (xy 376.021159 -398.146971) (xy 375.976312 -398.132709)
			(xy 375.934188 -398.111726) (xy 375.895789 -398.08452) (xy 375.862026 -398.051736) (xy 375.833702 -398.014154)
			(xy 375.82221 -397.993616) (xy 375.821956 -397.993108) (xy 375.821448 -397.992346) (xy 375.423684 -397.304006)
			(xy 375.411767 -397.281338) (xy 375.394831 -397.233013) (xy 375.386171 -397.182542) (xy 375.385584 -397.15694)
			(xy 375.385584 -397.156432) (xy 375.385742 -397.145083) (xy 375.387518 -397.122454) (xy 375.38914 -397.11122)
			(xy 375.39041 -397.10233) (xy 375.386854 -397.085058) (xy 375.34342 -397.013938) (xy 375.32945 -397.003016)
			(xy 375.321068 -396.999968) (xy 375.298671 -396.991921) (xy 375.256452 -396.969965) (xy 375.218155 -396.94172)
			(xy 375.184707 -396.90787) (xy 375.156922 -396.869238) (xy 375.135472 -396.82676) (xy 375.120879 -396.781466)
			(xy 375.113495 -396.734455) (xy 375.113042 -396.710662) (xy 374.523762 -396.710662) (xy 374.523671 -396.721944)
			(xy 374.522018 -396.744446) (xy 374.52046 -396.75562) (xy 374.51919 -396.76451) (xy 374.522746 -396.782036)
			(xy 374.56618 -396.852902) (xy 374.579896 -396.864078) (xy 374.588532 -396.866872) (xy 374.610773 -396.874813)
			(xy 374.652686 -396.896571) (xy 374.690751 -396.92452) (xy 374.724061 -396.957995) (xy 374.751822 -396.996198)
			(xy 374.76303 -397.016986) (xy 374.763538 -397.018002) (xy 375.155968 -397.696944) (xy 375.168777 -397.720276)
			(xy 375.186929 -397.770308) (xy 375.196114 -397.822732) (xy 375.196608 -397.849344) (xy 375.196134 -397.873333)
			(xy 375.188623 -397.920719) (xy 375.173791 -397.966347) (xy 375.152005 -398.009094) (xy 375.123801 -398.047907)
			(xy 375.089873 -398.08183) (xy 375.051056 -398.110028) (xy 375.008307 -398.131808) (xy 374.962676 -398.146633)
			(xy 374.915289 -398.154138) (xy 374.8913 -398.154652) (xy 374.867772 -398.15421) (xy 374.821276 -398.146973)
			(xy 374.776441 -398.132687) (xy 374.73433 -398.11169) (xy 374.695939 -398.084479) (xy 374.66218 -398.0517)
			(xy 374.63385 -398.014127) (xy 374.622314 -397.993616) (xy 374.62206 -397.993108) (xy 374.621552 -397.992346)
			(xy 374.223788 -397.304006) (xy 374.211854 -397.281345) (xy 374.194904 -397.233021) (xy 374.186262 -397.182545)
			(xy 374.185688 -397.15694) (xy 374.185688 -397.156432) (xy 374.185839 -397.145083) (xy 374.18762 -397.122453)
			(xy 374.189244 -397.11122) (xy 374.190514 -397.10233) (xy 374.186958 -397.085058) (xy 374.143524 -397.013938)
			(xy 374.129554 -397.003016) (xy 374.121172 -396.999968) (xy 374.09877 -396.991948) (xy 374.056575 -396.969962)
			(xy 374.0183 -396.941697) (xy 373.98487 -396.90784) (xy 373.957096 -396.869208) (xy 373.935648 -396.826736)
			(xy 373.921046 -396.781452) (xy 373.913643 -396.734452) (xy 373.913146 -396.710662) (xy 373.913645 -396.685263)
			(xy 373.922044 -396.635166) (xy 373.938619 -396.587149) (xy 373.962915 -396.542539) (xy 373.994259 -396.502566)
			(xy 374.012714 -396.48511) (xy 374.021096 -396.47749) (xy 374.029732 -396.457424) (xy 374.026938 -396.35811)
			(xy 374.01754 -396.338552) (xy 374.00865 -396.33144) (xy 373.990086 -396.315639) (xy 373.957355 -396.279514)
			(xy 373.930278 -396.238978) (xy 373.909442 -396.194908) (xy 373.895297 -396.148257) (xy 373.88815 -396.100036)
			(xy 373.887746 -396.075662) (xy 373.888185 -396.051546) (xy 373.895191 -396.003826) (xy 373.90905 -395.957629)
			(xy 373.929468 -395.913933) (xy 373.942356 -395.893544) (xy 373.948198 -395.884654) (xy 373.951754 -395.864588)
			(xy 373.930672 -395.772386) (xy 373.91848 -395.755622) (xy 373.90959 -395.750288) (xy 373.888786 -395.737434)
			(xy 373.850865 -395.706558) (xy 373.81791 -395.670428) (xy 373.790643 -395.629834) (xy 373.769659 -395.585664)
			(xy 373.755416 -395.538883) (xy 373.748226 -395.490513) (xy 373.747792 -395.466062) (xy 373.748353 -395.438779)
			(xy 373.757314 -395.384955) (xy 373.774986 -395.33333) (xy 373.80089 -395.285306) (xy 373.834324 -395.242184)
			(xy 373.853964 -395.223238) (xy 373.861417 -395.215748) (xy 373.869966 -395.196452) (xy 373.870474 -395.1859)
			(xy 373.870474 -395.111224) (xy 373.869887 -395.100689) (xy 373.861356 -395.081416) (xy 373.853964 -395.073886)
			(xy 373.834308 -395.054954) (xy 373.800863 -395.011834) (xy 373.774953 -394.963807) (xy 373.75728 -394.912178)
			(xy 373.748326 -394.858347) (xy 373.747792 -394.831062) (xy 373.748046 -394.81887) (xy 373.7483 -394.809218)
			(xy 373.742204 -394.791184) (xy 373.68353 -394.723874) (xy 373.666766 -394.715238) (xy 373.65686 -394.714222)
			(xy 373.629947 -394.710871) (xy 373.577647 -394.696526) (xy 373.52839 -394.673838) (xy 373.483496 -394.643415)
			(xy 373.444169 -394.606072) (xy 373.411464 -394.562812) (xy 373.386259 -394.514794) (xy 373.369228 -394.463307)
			(xy 373.364506 -394.4366) (xy 373.362982 -394.427202) (xy 373.089932 -393.954762) (xy 373.08282 -393.94892)
			(xy 373.062085 -393.93135) (xy 373.026092 -393.890634) (xy 372.997232 -393.844586) (xy 372.976281 -393.794443)
			(xy 372.963801 -393.74155) (xy 372.961408 -393.714478) (xy 372.960138 -393.694412) (xy 372.930674 -393.66698)
			(xy 372.516908 -393.66698) (xy 372.50802 -393.66732) (xy 372.491319 -393.673412) (xy 372.47772 -393.68486)
			(xy 372.472966 -393.69238) (xy 372.466108 -393.704318) (xy 372.466108 -393.731242) (xy 372.692168 -394.122402)
			(xy 372.699534 -394.128244) (xy 372.718315 -394.144046) (xy 372.751455 -394.180251) (xy 372.778881 -394.220955)
			(xy 372.799991 -394.265264) (xy 372.814323 -394.312206) (xy 372.821562 -394.360751) (xy 372.821962 -394.385292)
			(xy 372.821708 -394.397484) (xy 372.821454 -394.407136) (xy 372.82755 -394.42517) (xy 372.886224 -394.49248)
			(xy 372.902988 -394.501116) (xy 372.912894 -394.502132) (xy 372.939662 -394.505458) (xy 372.991691 -394.519681)
			(xy 373.040723 -394.542158) (xy 373.085458 -394.572293) (xy 373.12471 -394.609287) (xy 373.15744 -394.65216)
			(xy 373.182779 -394.699775) (xy 373.200057 -394.750871) (xy 373.208815 -394.804093) (xy 373.209312 -394.831062)
			(xy 373.208749 -394.858344) (xy 373.199785 -394.912166) (xy 373.18211 -394.963788) (xy 373.156204 -395.01181)
			(xy 373.122769 -395.05493) (xy 373.10314 -395.073886) (xy 373.09569 -395.081377) (xy 373.08715 -395.100673)
			(xy 373.08663 -395.111224) (xy 373.08663 -395.1859) (xy 373.087222 -395.196432) (xy 373.095759 -395.215699)
			(xy 373.10314 -395.223238) (xy 373.122794 -395.242171) (xy 373.156236 -395.285292) (xy 373.182142 -395.333319)
			(xy 373.199811 -395.384948) (xy 373.208761 -395.438778) (xy 373.209312 -395.466062) (xy 373.208879 -395.49018)
			(xy 373.201883 -395.537905) (xy 373.188035 -395.584109) (xy 373.167628 -395.627815) (xy 373.154702 -395.64818)
			(xy 373.14886 -395.65707) (xy 373.145304 -395.677136) (xy 373.166386 -395.769338) (xy 373.178578 -395.786102)
			(xy 373.187468 -395.791436) (xy 373.208268 -395.804293) (xy 373.246181 -395.835173) (xy 373.279127 -395.871305)
			(xy 373.306386 -395.911899) (xy 373.327363 -395.956068) (xy 373.3416 -396.002847) (xy 373.348784 -396.051213)
			(xy 373.349266 -396.075662) (xy 373.348828 -396.100033) (xy 373.341673 -396.148246) (xy 373.327525 -396.19489)
			(xy 373.306692 -396.238955) (xy 373.279622 -396.279489) (xy 373.246902 -396.315616) (xy 373.228362 -396.33144)
			(xy 373.219472 -396.338552) (xy 373.210074 -396.35811) (xy 373.20728 -396.457424) (xy 373.215916 -396.47749)
			(xy 373.224298 -396.48511) (xy 373.24272 -396.502598) (xy 373.274062 -396.542566) (xy 373.298359 -396.587168)
			(xy 373.314941 -396.635176) (xy 373.323351 -396.685266) (xy 373.323866 -396.710662) (xy 373.323775 -396.721944)
			(xy 373.322122 -396.744446) (xy 373.320564 -396.75562) (xy 373.319294 -396.764764) (xy 373.322596 -396.782036)
			(xy 373.366284 -396.853156) (xy 373.38 -396.864078) (xy 373.388636 -396.866872) (xy 373.416768 -396.877141)
			(xy 373.468704 -396.906942) (xy 373.49176 -396.926054) (xy 373.513204 -396.945672) (xy 373.549 -396.99145)
			(xy 373.56288 -397.016986) (xy 373.563642 -397.018256) (xy 373.955818 -397.696944) (xy 373.968602 -397.720294)
			(xy 373.986794 -397.770318) (xy 373.996078 -397.822731) (xy 373.996712 -397.849344) (xy 373.996262 -397.873348)
			(xy 373.988741 -397.920763) (xy 373.973894 -397.966416) (xy 373.952084 -398.009184) (xy 373.92385 -398.048011)
			(xy 373.889887 -398.081941) (xy 373.851033 -398.110138) (xy 373.808244 -398.131906) (xy 373.762576 -398.14671)
			(xy 373.715154 -398.154185) (xy 373.69115 -398.154652) (xy 373.66762 -398.154213) (xy 373.621119 -398.146983)
			(xy 373.576279 -398.132703) (xy 373.534162 -398.111709) (xy 373.495765 -398.084501) (xy 373.461999 -398.051722)
			(xy 373.433664 -398.014149) (xy 373.422164 -397.993616) (xy 373.42191 -397.993108) (xy 373.421402 -397.992346)
			(xy 373.020844 -397.298926) (xy 373.009775 -397.276825) (xy 372.994135 -397.229938) (xy 372.986242 -397.181146)
			(xy 372.985792 -397.156432) (xy 372.985876 -397.145087) (xy 372.987532 -397.122458) (xy 372.989094 -397.11122)
			(xy 372.990364 -397.10233) (xy 372.986808 -397.085058) (xy 372.943374 -397.013938) (xy 372.929658 -397.002762)
			(xy 372.921022 -396.999968) (xy 372.898636 -396.991937) (xy 372.856476 -396.969933) (xy 372.818238 -396.941656)
			(xy 372.784847 -396.907793) (xy 372.757112 -396.869161) (xy 372.735703 -396.826695) (xy 372.721137 -396.781423)
			(xy 372.713769 -396.734441) (xy 372.71325 -396.710662) (xy 372.713749 -396.685263) (xy 372.722148 -396.635166)
			(xy 372.738724 -396.587149) (xy 372.763019 -396.542539) (xy 372.794364 -396.502567) (xy 372.812818 -396.48511)
			(xy 372.8212 -396.47749) (xy 372.829836 -396.457424) (xy 372.827042 -396.35811) (xy 372.817644 -396.338552)
			(xy 372.808754 -396.33144) (xy 372.79019 -396.315639) (xy 372.757458 -396.279515) (xy 372.730381 -396.238978)
			(xy 372.709545 -396.194908) (xy 372.6954 -396.148257) (xy 372.688253 -396.100036) (xy 372.68785 -396.075662)
			(xy 372.688289 -396.051546) (xy 372.695295 -396.003826) (xy 372.709155 -395.957629) (xy 372.729573 -395.913933)
			(xy 372.74246 -395.893544) (xy 372.748302 -395.884654) (xy 372.751858 -395.864588) (xy 372.730776 -395.772386)
			(xy 372.718584 -395.755622) (xy 372.709694 -395.750288) (xy 372.68889 -395.737434) (xy 372.650968 -395.706558)
			(xy 372.618013 -395.670429) (xy 372.590746 -395.629835) (xy 372.569761 -395.585665) (xy 372.555518 -395.538883)
			(xy 372.548328 -395.490513) (xy 372.547896 -395.466062) (xy 372.548457 -395.438779) (xy 372.557418 -395.384955)
			(xy 372.57509 -395.333331) (xy 372.600994 -395.285306) (xy 372.634429 -395.242184) (xy 372.654068 -395.223238)
			(xy 372.66152 -395.215748) (xy 372.670069 -395.196452) (xy 372.670578 -395.1859) (xy 372.670578 -395.111224)
			(xy 372.669991 -395.100689) (xy 372.661461 -395.081415) (xy 372.654068 -395.073886) (xy 372.634412 -395.054954)
			(xy 372.600966 -395.011834) (xy 372.575056 -394.963807) (xy 372.557383 -394.912178) (xy 372.548428 -394.858347)
			(xy 372.547896 -394.831062) (xy 372.54815 -394.81887) (xy 372.548404 -394.809218) (xy 372.542308 -394.791184)
			(xy 372.483634 -394.723874) (xy 372.46687 -394.715238) (xy 372.456964 -394.714222) (xy 372.43005 -394.710871)
			(xy 372.37775 -394.696527) (xy 372.328492 -394.673839) (xy 372.283598 -394.643416) (xy 372.244271 -394.606074)
			(xy 372.211566 -394.562813) (xy 372.186359 -394.514795) (xy 372.169328 -394.463307) (xy 372.16461 -394.4366)
			(xy 372.163086 -394.427202) (xy 371.89029 -393.95527) (xy 371.882924 -393.949428) (xy 371.862119 -393.931841)
			(xy 371.826004 -393.891059) (xy 371.797058 -393.844912) (xy 371.776063 -393.794646) (xy 371.763588 -393.74162)
			(xy 371.761258 -393.714478) (xy 371.759988 -393.694412) (xy 371.730524 -393.66698) (xy 371.620542 -393.66698)
			(xy 371.610476 -393.667413) (xy 371.591885 -393.67514) (xy 371.584474 -393.681966) (xy 371.392196 -393.874244)
			(xy 371.384753 -393.882521) (xy 371.377199 -393.903433) (xy 371.379198 -393.925577) (xy 371.384322 -393.935458)
			(xy 371.492272 -394.122402) (xy 371.499638 -394.128244) (xy 371.518419 -394.144046) (xy 371.551558 -394.180251)
			(xy 371.578984 -394.220955) (xy 371.600094 -394.265264) (xy 371.614426 -394.312207) (xy 371.621664 -394.360751)
			(xy 371.622066 -394.385292) (xy 371.621812 -394.397484) (xy 371.621558 -394.407136) (xy 371.627654 -394.42517)
			(xy 371.686328 -394.49248) (xy 371.703092 -394.501116) (xy 371.712744 -394.502132) (xy 371.739515 -394.505454)
			(xy 371.791551 -394.519672) (xy 371.840589 -394.542145) (xy 371.885331 -394.572278) (xy 371.92459 -394.609272)
			(xy 371.957325 -394.652146) (xy 371.982669 -394.699764) (xy 371.99995 -394.750864) (xy 372.00871 -394.804091)
			(xy 372.009162 -394.831062) (xy 372.008599 -394.858344) (xy 371.999636 -394.912168) (xy 371.981964 -394.963791)
			(xy 371.95606 -395.011816) (xy 371.922629 -395.054939) (xy 371.90299 -395.073886) (xy 371.895547 -395.08138)
			(xy 371.887015 -395.100675) (xy 371.88648 -395.111224) (xy 371.88648 -395.1859) (xy 371.88707 -395.196434)
			(xy 371.895601 -395.215706) (xy 371.90299 -395.223238) (xy 371.922642 -395.242172) (xy 371.956078 -395.285295)
			(xy 371.981981 -395.333322) (xy 371.999646 -395.38495) (xy 372.008596 -395.438778) (xy 372.009162 -395.466062)
			(xy 372.008729 -395.490179) (xy 372.001732 -395.537904) (xy 371.987882 -395.584108) (xy 371.967472 -395.627811)
			(xy 371.954552 -395.64818) (xy 371.94871 -395.65707) (xy 371.945154 -395.677136) (xy 371.966236 -395.769338)
			(xy 371.978428 -395.786102) (xy 371.987318 -395.791436) (xy 372.008121 -395.804291) (xy 372.046038 -395.835168)
			(xy 372.078989 -395.871299) (xy 372.106253 -395.911892) (xy 372.127234 -395.956062) (xy 372.141473 -396.002843)
			(xy 372.148659 -396.051212) (xy 372.149116 -396.075662) (xy 372.148678 -396.100032) (xy 372.141522 -396.148245)
			(xy 372.127373 -396.194887) (xy 372.106537 -396.23895) (xy 372.079465 -396.279481) (xy 372.046742 -396.315604)
			(xy 372.028212 -396.33144) (xy 372.019322 -396.338552) (xy 372.009924 -396.35811) (xy 372.00713 -396.457424)
			(xy 372.015766 -396.47749) (xy 372.024148 -396.48511) (xy 372.042567 -396.502599) (xy 372.073904 -396.542569)
			(xy 372.098197 -396.587172) (xy 372.114776 -396.635179) (xy 372.123185 -396.685267) (xy 372.123716 -396.710662)
			(xy 372.123625 -396.721944) (xy 372.121972 -396.744446) (xy 372.120414 -396.75562) (xy 372.119144 -396.76451)
			(xy 372.1227 -396.782036) (xy 372.166134 -396.852902) (xy 372.17985 -396.864078) (xy 372.188486 -396.866872)
			(xy 372.210729 -396.874811) (xy 372.252647 -396.896564) (xy 372.290717 -396.924511) (xy 372.324032 -396.957984)
			(xy 372.351797 -396.996186) (xy 372.362984 -397.016986) (xy 372.363492 -397.018002) (xy 372.755922 -397.696944)
			(xy 372.768706 -397.720294) (xy 372.786898 -397.770318) (xy 372.796182 -397.822731) (xy 372.796816 -397.849344)
			(xy 372.796366 -397.873348) (xy 372.788845 -397.920763) (xy 372.773998 -397.966417) (xy 372.752188 -398.009185)
			(xy 372.723954 -398.048012) (xy 372.689991 -398.081943) (xy 372.651137 -398.11014) (xy 372.608348 -398.131909)
			(xy 372.56268 -398.146713) (xy 372.515258 -398.154188) (xy 372.491254 -398.154652) (xy 372.467724 -398.154214)
			(xy 372.421223 -398.146984) (xy 372.376382 -398.132704) (xy 372.334264 -398.111711) (xy 372.295867 -398.084502)
			(xy 372.2621 -398.051723) (xy 372.233765 -398.014151) (xy 372.222268 -397.993616) (xy 372.222014 -397.993108)
			(xy 372.221506 -397.992346) (xy 371.823742 -397.304006) (xy 371.811844 -397.281337) (xy 371.79497 -397.233007)
			(xy 371.786409 -397.182536) (xy 371.785896 -397.15694) (xy 371.785896 -397.156432) (xy 371.78598 -397.145087)
			(xy 371.787636 -397.122458) (xy 371.789198 -397.11122) (xy 371.790468 -397.10233) (xy 371.786912 -397.085058)
			(xy 371.743478 -397.013938) (xy 371.729508 -397.003016) (xy 371.721126 -396.999968) (xy 371.698721 -396.991951)
			(xy 371.656519 -396.969969) (xy 371.618238 -396.941707) (xy 371.584802 -396.907851) (xy 371.557022 -396.869218)
			(xy 371.53557 -396.826744) (xy 371.520965 -396.781458) (xy 371.51356 -396.734454) (xy 371.5131 -396.710662)
			(xy 371.5136 -396.685264) (xy 371.522 -396.635167) (xy 371.538577 -396.587153) (xy 371.562875 -396.542546)
			(xy 371.594224 -396.502577) (xy 371.612668 -396.48511) (xy 371.62105 -396.47749) (xy 371.629686 -396.457424)
			(xy 371.626892 -396.35811) (xy 371.617494 -396.338552) (xy 371.608604 -396.33144) (xy 371.590043 -396.315638)
			(xy 371.557316 -396.279511) (xy 371.530242 -396.238974) (xy 371.509409 -396.194904) (xy 371.495267 -396.148255)
			(xy 371.488121 -396.100035) (xy 371.4877 -396.075662) (xy 371.488139 -396.051546) (xy 371.495144 -396.003826)
			(xy 371.509002 -395.957627) (xy 371.529417 -395.913929) (xy 371.54231 -395.893544) (xy 371.548152 -395.884654)
			(xy 371.551708 -395.864588) (xy 371.530626 -395.772386) (xy 371.518434 -395.755622) (xy 371.509544 -395.750288)
			(xy 371.488742 -395.737432) (xy 371.450826 -395.706553) (xy 371.417876 -395.670423) (xy 371.390613 -395.629829)
			(xy 371.369632 -395.58566) (xy 371.355391 -395.53888) (xy 371.348203 -395.490512) (xy 371.347746 -395.466062)
			(xy 371.348307 -395.438779) (xy 371.357267 -395.384953) (xy 371.374937 -395.333328) (xy 371.400838 -395.285301)
			(xy 371.434269 -395.242175) (xy 371.453918 -395.223238) (xy 371.461364 -395.215745) (xy 371.469904 -395.19645)
			(xy 371.470428 -395.1859) (xy 371.470428 -395.111224) (xy 371.469843 -395.100688) (xy 371.461318 -395.081408)
			(xy 371.453918 -395.073886) (xy 371.434264 -395.054952) (xy 371.400824 -395.011831) (xy 371.374917 -394.963804)
			(xy 371.357247 -394.912175) (xy 371.348294 -394.858346) (xy 371.347746 -394.831062) (xy 371.348 -394.81887)
			(xy 371.348254 -394.809218) (xy 371.342158 -394.791184) (xy 371.283484 -394.723874) (xy 371.26672 -394.715238)
			(xy 371.257068 -394.714222) (xy 371.230154 -394.710872) (xy 371.177853 -394.696528) (xy 371.128595 -394.67384)
			(xy 371.0837 -394.643417) (xy 371.044372 -394.606075) (xy 371.011667 -394.562815) (xy 370.98646 -394.514796)
			(xy 370.969429 -394.463308) (xy 370.964714 -394.4366) (xy 370.96319 -394.427202) (xy 370.950744 -394.405866)
			(xy 370.94443 -394.395957) (xy 370.924961 -394.382853) (xy 370.913406 -394.38072) (xy 370.901722 -394.379196)
			(xy 370.879624 -394.386816) (xy 370.870226 -394.396214) (xy 370.863379 -394.403612) (xy 370.855646 -394.42221)
			(xy 370.85524 -394.432282) (xy 370.85524 -395.824964) (xy 370.855615 -395.834068) (xy 370.861998 -395.851119)
			(xy 370.867686 -395.858238) (xy 370.884644 -395.878451) (xy 370.912583 -395.923204) (xy 370.933063 -395.971825)
			(xy 370.945564 -396.023081) (xy 370.94977 -396.075671) (xy 370.945573 -396.128262) (xy 370.93308 -396.17952)
			(xy 370.912609 -396.228145) (xy 370.884678 -396.272903) (xy 370.867686 -396.293086) (xy 370.862 -396.300206)
			(xy 370.855608 -396.317256) (xy 370.85524 -396.32636) (xy 370.85524 -396.500604) (xy 370.855597 -396.508643)
			(xy 370.860631 -396.523917) (xy 370.865146 -396.530576) (xy 370.878989 -396.550294) (xy 370.900937 -396.593181)
			(xy 370.91586 -396.638988) (xy 370.923386 -396.686573) (xy 370.92382 -396.710662) (xy 370.923729 -396.721944)
			(xy 370.922076 -396.744446) (xy 370.920518 -396.75562) (xy 370.919248 -396.76451) (xy 370.922804 -396.782036)
			(xy 370.966238 -396.852902) (xy 370.979954 -396.864078) (xy 370.98859 -396.866872) (xy 371.010833 -396.874811)
			(xy 371.05275 -396.896565) (xy 371.09082 -396.924512) (xy 371.124134 -396.957985) (xy 371.151899 -396.996187)
			(xy 371.163088 -397.016986) (xy 371.163596 -397.018002) (xy 371.556026 -397.696944) (xy 371.56881 -397.720294)
			(xy 371.587002 -397.770318) (xy 371.596285 -397.822731) (xy 371.59692 -397.849344) (xy 371.59647 -397.873348)
			(xy 371.58895 -397.920763) (xy 371.574102 -397.966417) (xy 371.552292 -398.009185) (xy 371.524058 -398.048013)
			(xy 371.490095 -398.081944) (xy 371.451241 -398.110142) (xy 371.408453 -398.131911) (xy 371.362785 -398.146716)
			(xy 371.315362 -398.154192) (xy 371.291358 -398.154652) (xy 371.267828 -398.154214) (xy 371.221326 -398.146985)
			(xy 371.176485 -398.132705) (xy 371.134367 -398.111712) (xy 371.095969 -398.084504) (xy 371.062202 -398.051725)
			(xy 371.033866 -398.014152) (xy 371.022372 -397.993616) (xy 371.022118 -397.993108) (xy 371.02161 -397.992346)
			(xy 370.949982 -397.868394) (xy 370.94392 -397.859033) (xy 370.925668 -397.846263) (xy 370.903729 -397.842405)
			(xy 370.892832 -397.844772) (xy 370.876068 -397.849344) (xy 370.85524 -397.876522) (xy 370.85524 -398.542002)
			(xy 371.38535 -398.542002) (xy 371.38931 -398.492948) (xy 371.401087 -398.445164) (xy 371.420378 -398.399888)
			(xy 371.446681 -398.358292) (xy 371.479316 -398.321455) (xy 371.517437 -398.29033) (xy 371.560058 -398.265723)
			(xy 371.606074 -398.248271) (xy 371.654293 -398.238427) (xy 371.703468 -398.236446) (xy 371.752323 -398.242378)
			(xy 371.799594 -398.25607) (xy 371.844056 -398.277168) (xy 371.884559 -398.305124) (xy 371.920052 -398.339216)
			(xy 371.949617 -398.37856) (xy 371.972488 -398.422137) (xy 371.988072 -398.468818) (xy 371.995967 -398.517395)
			(xy 371.996462 -398.542002) (xy 372.5855 -398.542002) (xy 372.58946 -398.492948) (xy 372.601237 -398.445164)
			(xy 372.620528 -398.399888) (xy 372.646831 -398.358292) (xy 372.679466 -398.321455) (xy 372.717587 -398.29033)
			(xy 372.760208 -398.265723) (xy 372.806224 -398.248271) (xy 372.854443 -398.238427) (xy 372.903618 -398.236446)
			(xy 372.952473 -398.242378) (xy 372.999744 -398.25607) (xy 373.044206 -398.277168) (xy 373.084709 -398.305124)
			(xy 373.120202 -398.339216) (xy 373.149767 -398.37856) (xy 373.172638 -398.422137) (xy 373.188222 -398.468818)
			(xy 373.196117 -398.517395) (xy 373.196612 -398.542002) (xy 373.785396 -398.542002) (xy 373.789356 -398.492948)
			(xy 373.801133 -398.445164) (xy 373.820424 -398.399888) (xy 373.846727 -398.358292) (xy 373.879362 -398.321455)
			(xy 373.917483 -398.29033) (xy 373.960104 -398.265723) (xy 374.00612 -398.248271) (xy 374.054339 -398.238427)
			(xy 374.103514 -398.236446) (xy 374.152369 -398.242378) (xy 374.19964 -398.25607) (xy 374.244102 -398.277168)
			(xy 374.284605 -398.305124) (xy 374.320098 -398.339216) (xy 374.349663 -398.37856) (xy 374.372534 -398.422137)
			(xy 374.388118 -398.468818) (xy 374.396013 -398.517395) (xy 374.396508 -398.542002) (xy 374.985546 -398.542002)
			(xy 374.989506 -398.492948) (xy 375.001283 -398.445164) (xy 375.020574 -398.399888) (xy 375.046877 -398.358292)
			(xy 375.079512 -398.321455) (xy 375.117633 -398.29033) (xy 375.160254 -398.265723) (xy 375.20627 -398.248271)
			(xy 375.254489 -398.238427) (xy 375.303664 -398.236446) (xy 375.352519 -398.242378) (xy 375.39979 -398.25607)
			(xy 375.444252 -398.277168) (xy 375.484755 -398.305124) (xy 375.520248 -398.339216) (xy 375.549813 -398.37856)
			(xy 375.572684 -398.422137) (xy 375.588268 -398.468818) (xy 375.596163 -398.517395) (xy 375.596658 -398.542002)
			(xy 376.185442 -398.542002) (xy 376.189402 -398.492948) (xy 376.201179 -398.445164) (xy 376.22047 -398.399888)
			(xy 376.246773 -398.358292) (xy 376.279408 -398.321455) (xy 376.317529 -398.29033) (xy 376.36015 -398.265723)
			(xy 376.406166 -398.248271) (xy 376.454385 -398.238427) (xy 376.50356 -398.236446) (xy 376.552415 -398.242378)
			(xy 376.599686 -398.25607) (xy 376.644148 -398.277168) (xy 376.684651 -398.305124) (xy 376.720144 -398.339216)
			(xy 376.749709 -398.37856) (xy 376.77258 -398.422137) (xy 376.788164 -398.468818) (xy 376.796059 -398.517395)
			(xy 376.796554 -398.542002) (xy 377.385338 -398.542002) (xy 377.389298 -398.492948) (xy 377.401075 -398.445164)
			(xy 377.420366 -398.399888) (xy 377.446669 -398.358292) (xy 377.479304 -398.321455) (xy 377.517425 -398.29033)
			(xy 377.560046 -398.265723) (xy 377.606062 -398.248271) (xy 377.654281 -398.238427) (xy 377.703456 -398.236446)
			(xy 377.752311 -398.242378) (xy 377.799582 -398.25607) (xy 377.844044 -398.277168) (xy 377.884547 -398.305124)
			(xy 377.92004 -398.339216) (xy 377.949605 -398.37856) (xy 377.972476 -398.422137) (xy 377.98806 -398.468818)
			(xy 377.995955 -398.517395) (xy 377.99645 -398.542002) (xy 378.585488 -398.542002) (xy 378.589448 -398.492948)
			(xy 378.601225 -398.445164) (xy 378.620516 -398.399888) (xy 378.646819 -398.358292) (xy 378.679454 -398.321455)
			(xy 378.717575 -398.29033) (xy 378.760196 -398.265723) (xy 378.806212 -398.248271) (xy 378.854431 -398.238427)
			(xy 378.903606 -398.236446) (xy 378.952461 -398.242378) (xy 378.999732 -398.25607) (xy 379.044194 -398.277168)
			(xy 379.084697 -398.305124) (xy 379.12019 -398.339216) (xy 379.149755 -398.37856) (xy 379.172626 -398.422137)
			(xy 379.18821 -398.468818) (xy 379.196105 -398.517395) (xy 379.1966 -398.542002) (xy 379.785384 -398.542002)
			(xy 379.789344 -398.492948) (xy 379.801121 -398.445164) (xy 379.820412 -398.399888) (xy 379.846715 -398.358292)
			(xy 379.87935 -398.321455) (xy 379.917471 -398.29033) (xy 379.960092 -398.265723) (xy 380.006108 -398.248271)
			(xy 380.054327 -398.238427) (xy 380.103502 -398.236446) (xy 380.152357 -398.242378) (xy 380.199628 -398.25607)
			(xy 380.24409 -398.277168) (xy 380.284593 -398.305124) (xy 380.320086 -398.339216) (xy 380.349651 -398.37856)
			(xy 380.372522 -398.422137) (xy 380.388106 -398.468818) (xy 380.396001 -398.517395) (xy 380.396496 -398.542002)
			(xy 380.985534 -398.542002) (xy 380.989494 -398.492948) (xy 381.001271 -398.445164) (xy 381.020562 -398.399888)
			(xy 381.046865 -398.358292) (xy 381.0795 -398.321455) (xy 381.117621 -398.29033) (xy 381.160242 -398.265723)
			(xy 381.206258 -398.248271) (xy 381.254477 -398.238427) (xy 381.303652 -398.236446) (xy 381.352507 -398.242378)
			(xy 381.399778 -398.25607) (xy 381.44424 -398.277168) (xy 381.484743 -398.305124) (xy 381.520236 -398.339216)
			(xy 381.549801 -398.37856) (xy 381.572672 -398.422137) (xy 381.588256 -398.468818) (xy 381.596151 -398.517395)
			(xy 381.596646 -398.542002) (xy 382.18543 -398.542002) (xy 382.18939 -398.492948) (xy 382.201167 -398.445164)
			(xy 382.220458 -398.399888) (xy 382.246761 -398.358292) (xy 382.279396 -398.321455) (xy 382.317517 -398.29033)
			(xy 382.360138 -398.265723) (xy 382.406154 -398.248271) (xy 382.454373 -398.238427) (xy 382.503548 -398.236446)
			(xy 382.552403 -398.242378) (xy 382.599674 -398.25607) (xy 382.644136 -398.277168) (xy 382.684639 -398.305124)
			(xy 382.720132 -398.339216) (xy 382.749697 -398.37856) (xy 382.772568 -398.422137) (xy 382.788152 -398.468818)
			(xy 382.796047 -398.517395) (xy 382.796542 -398.542002) (xy 383.385326 -398.542002) (xy 383.389286 -398.492948)
			(xy 383.401063 -398.445164) (xy 383.420354 -398.399888) (xy 383.446657 -398.358292) (xy 383.479292 -398.321455)
			(xy 383.517413 -398.29033) (xy 383.560034 -398.265723) (xy 383.60605 -398.248271) (xy 383.654269 -398.238427)
			(xy 383.703444 -398.236446) (xy 383.752299 -398.242378) (xy 383.79957 -398.25607) (xy 383.844032 -398.277168)
			(xy 383.884535 -398.305124) (xy 383.920028 -398.339216) (xy 383.949593 -398.37856) (xy 383.972464 -398.422137)
			(xy 383.988048 -398.468818) (xy 383.995943 -398.517395) (xy 383.996438 -398.542002) (xy 384.585476 -398.542002)
			(xy 384.589436 -398.492948) (xy 384.601213 -398.445164) (xy 384.620504 -398.399888) (xy 384.646807 -398.358292)
			(xy 384.679442 -398.321455) (xy 384.717563 -398.29033) (xy 384.760184 -398.265723) (xy 384.8062 -398.248271)
			(xy 384.854419 -398.238427) (xy 384.903594 -398.236446) (xy 384.952449 -398.242378) (xy 384.99972 -398.25607)
			(xy 385.044182 -398.277168) (xy 385.084685 -398.305124) (xy 385.120178 -398.339216) (xy 385.149743 -398.37856)
			(xy 385.172614 -398.422137) (xy 385.188198 -398.468818) (xy 385.196093 -398.517395) (xy 385.196588 -398.542002)
			(xy 385.785372 -398.542002) (xy 385.789332 -398.492948) (xy 385.801109 -398.445164) (xy 385.8204 -398.399888)
			(xy 385.846703 -398.358292) (xy 385.879338 -398.321455) (xy 385.917459 -398.29033) (xy 385.96008 -398.265723)
			(xy 386.006096 -398.248271) (xy 386.054315 -398.238427) (xy 386.10349 -398.236446) (xy 386.152345 -398.242378)
			(xy 386.199616 -398.25607) (xy 386.244078 -398.277168) (xy 386.284581 -398.305124) (xy 386.320074 -398.339216)
			(xy 386.349639 -398.37856) (xy 386.37251 -398.422137) (xy 386.388094 -398.468818) (xy 386.395989 -398.517395)
			(xy 386.396484 -398.542002) (xy 386.395989 -398.566609) (xy 386.388094 -398.615186) (xy 386.37251 -398.661867)
			(xy 386.349639 -398.705444) (xy 386.320074 -398.744788) (xy 386.284581 -398.77888) (xy 386.244078 -398.806836)
			(xy 386.199616 -398.827934) (xy 386.152345 -398.841626) (xy 386.10349 -398.847558) (xy 386.054315 -398.845577)
			(xy 386.006096 -398.835733) (xy 385.96008 -398.818281) (xy 385.917459 -398.793674) (xy 385.879338 -398.762549)
			(xy 385.846703 -398.725712) (xy 385.8204 -398.684116) (xy 385.801109 -398.63884) (xy 385.789332 -398.591056)
			(xy 385.785372 -398.542002) (xy 385.196588 -398.542002) (xy 385.196093 -398.566609) (xy 385.188198 -398.615186)
			(xy 385.172614 -398.661867) (xy 385.149743 -398.705444) (xy 385.120178 -398.744788) (xy 385.084685 -398.77888)
			(xy 385.044182 -398.806836) (xy 384.99972 -398.827934) (xy 384.952449 -398.841626) (xy 384.903594 -398.847558)
			(xy 384.854419 -398.845577) (xy 384.8062 -398.835733) (xy 384.760184 -398.818281) (xy 384.717563 -398.793674)
			(xy 384.679442 -398.762549) (xy 384.646807 -398.725712) (xy 384.620504 -398.684116) (xy 384.601213 -398.63884)
			(xy 384.589436 -398.591056) (xy 384.585476 -398.542002) (xy 383.996438 -398.542002) (xy 383.995943 -398.566609)
			(xy 383.988048 -398.615186) (xy 383.972464 -398.661867) (xy 383.949593 -398.705444) (xy 383.920028 -398.744788)
			(xy 383.884535 -398.77888) (xy 383.844032 -398.806836) (xy 383.79957 -398.827934) (xy 383.752299 -398.841626)
			(xy 383.703444 -398.847558) (xy 383.654269 -398.845577) (xy 383.60605 -398.835733) (xy 383.560034 -398.818281)
			(xy 383.517413 -398.793674) (xy 383.479292 -398.762549) (xy 383.446657 -398.725712) (xy 383.420354 -398.684116)
			(xy 383.401063 -398.63884) (xy 383.389286 -398.591056) (xy 383.385326 -398.542002) (xy 382.796542 -398.542002)
			(xy 382.796047 -398.566609) (xy 382.788152 -398.615186) (xy 382.772568 -398.661867) (xy 382.749697 -398.705444)
			(xy 382.720132 -398.744788) (xy 382.684639 -398.77888) (xy 382.644136 -398.806836) (xy 382.599674 -398.827934)
			(xy 382.552403 -398.841626) (xy 382.503548 -398.847558) (xy 382.454373 -398.845577) (xy 382.406154 -398.835733)
			(xy 382.360138 -398.818281) (xy 382.317517 -398.793674) (xy 382.279396 -398.762549) (xy 382.246761 -398.725712)
			(xy 382.220458 -398.684116) (xy 382.201167 -398.63884) (xy 382.18939 -398.591056) (xy 382.18543 -398.542002)
			(xy 381.596646 -398.542002) (xy 381.596151 -398.566609) (xy 381.588256 -398.615186) (xy 381.572672 -398.661867)
			(xy 381.549801 -398.705444) (xy 381.520236 -398.744788) (xy 381.484743 -398.77888) (xy 381.44424 -398.806836)
			(xy 381.399778 -398.827934) (xy 381.352507 -398.841626) (xy 381.303652 -398.847558) (xy 381.254477 -398.845577)
			(xy 381.206258 -398.835733) (xy 381.160242 -398.818281) (xy 381.117621 -398.793674) (xy 381.0795 -398.762549)
			(xy 381.046865 -398.725712) (xy 381.020562 -398.684116) (xy 381.001271 -398.63884) (xy 380.989494 -398.591056)
			(xy 380.985534 -398.542002) (xy 380.396496 -398.542002) (xy 380.396001 -398.566609) (xy 380.388106 -398.615186)
			(xy 380.372522 -398.661867) (xy 380.349651 -398.705444) (xy 380.320086 -398.744788) (xy 380.284593 -398.77888)
			(xy 380.24409 -398.806836) (xy 380.199628 -398.827934) (xy 380.152357 -398.841626) (xy 380.103502 -398.847558)
			(xy 380.054327 -398.845577) (xy 380.006108 -398.835733) (xy 379.960092 -398.818281) (xy 379.917471 -398.793674)
			(xy 379.87935 -398.762549) (xy 379.846715 -398.725712) (xy 379.820412 -398.684116) (xy 379.801121 -398.63884)
			(xy 379.789344 -398.591056) (xy 379.785384 -398.542002) (xy 379.1966 -398.542002) (xy 379.196105 -398.566609)
			(xy 379.18821 -398.615186) (xy 379.172626 -398.661867) (xy 379.149755 -398.705444) (xy 379.12019 -398.744788)
			(xy 379.084697 -398.77888) (xy 379.044194 -398.806836) (xy 378.999732 -398.827934) (xy 378.952461 -398.841626)
			(xy 378.903606 -398.847558) (xy 378.854431 -398.845577) (xy 378.806212 -398.835733) (xy 378.760196 -398.818281)
			(xy 378.717575 -398.793674) (xy 378.679454 -398.762549) (xy 378.646819 -398.725712) (xy 378.620516 -398.684116)
			(xy 378.601225 -398.63884) (xy 378.589448 -398.591056) (xy 378.585488 -398.542002) (xy 377.99645 -398.542002)
			(xy 377.995955 -398.566609) (xy 377.98806 -398.615186) (xy 377.972476 -398.661867) (xy 377.949605 -398.705444)
			(xy 377.92004 -398.744788) (xy 377.884547 -398.77888) (xy 377.844044 -398.806836) (xy 377.799582 -398.827934)
			(xy 377.752311 -398.841626) (xy 377.703456 -398.847558) (xy 377.654281 -398.845577) (xy 377.606062 -398.835733)
			(xy 377.560046 -398.818281) (xy 377.517425 -398.793674) (xy 377.479304 -398.762549) (xy 377.446669 -398.725712)
			(xy 377.420366 -398.684116) (xy 377.401075 -398.63884) (xy 377.389298 -398.591056) (xy 377.385338 -398.542002)
			(xy 376.796554 -398.542002) (xy 376.796059 -398.566609) (xy 376.788164 -398.615186) (xy 376.77258 -398.661867)
			(xy 376.749709 -398.705444) (xy 376.720144 -398.744788) (xy 376.684651 -398.77888) (xy 376.644148 -398.806836)
			(xy 376.599686 -398.827934) (xy 376.552415 -398.841626) (xy 376.50356 -398.847558) (xy 376.454385 -398.845577)
			(xy 376.406166 -398.835733) (xy 376.36015 -398.818281) (xy 376.317529 -398.793674) (xy 376.279408 -398.762549)
			(xy 376.246773 -398.725712) (xy 376.22047 -398.684116) (xy 376.201179 -398.63884) (xy 376.189402 -398.591056)
			(xy 376.185442 -398.542002) (xy 375.596658 -398.542002) (xy 375.596163 -398.566609) (xy 375.588268 -398.615186)
			(xy 375.572684 -398.661867) (xy 375.549813 -398.705444) (xy 375.520248 -398.744788) (xy 375.484755 -398.77888)
			(xy 375.444252 -398.806836) (xy 375.39979 -398.827934) (xy 375.352519 -398.841626) (xy 375.303664 -398.847558)
			(xy 375.254489 -398.845577) (xy 375.20627 -398.835733) (xy 375.160254 -398.818281) (xy 375.117633 -398.793674)
			(xy 375.079512 -398.762549) (xy 375.046877 -398.725712) (xy 375.020574 -398.684116) (xy 375.001283 -398.63884)
			(xy 374.989506 -398.591056) (xy 374.985546 -398.542002) (xy 374.396508 -398.542002) (xy 374.396013 -398.566609)
			(xy 374.388118 -398.615186) (xy 374.372534 -398.661867) (xy 374.349663 -398.705444) (xy 374.320098 -398.744788)
			(xy 374.284605 -398.77888) (xy 374.244102 -398.806836) (xy 374.19964 -398.827934) (xy 374.152369 -398.841626)
			(xy 374.103514 -398.847558) (xy 374.054339 -398.845577) (xy 374.00612 -398.835733) (xy 373.960104 -398.818281)
			(xy 373.917483 -398.793674) (xy 373.879362 -398.762549) (xy 373.846727 -398.725712) (xy 373.820424 -398.684116)
			(xy 373.801133 -398.63884) (xy 373.789356 -398.591056) (xy 373.785396 -398.542002) (xy 373.196612 -398.542002)
			(xy 373.196117 -398.566609) (xy 373.188222 -398.615186) (xy 373.172638 -398.661867) (xy 373.149767 -398.705444)
			(xy 373.120202 -398.744788) (xy 373.084709 -398.77888) (xy 373.044206 -398.806836) (xy 372.999744 -398.827934)
			(xy 372.952473 -398.841626) (xy 372.903618 -398.847558) (xy 372.854443 -398.845577) (xy 372.806224 -398.835733)
			(xy 372.760208 -398.818281) (xy 372.717587 -398.793674) (xy 372.679466 -398.762549) (xy 372.646831 -398.725712)
			(xy 372.620528 -398.684116) (xy 372.601237 -398.63884) (xy 372.58946 -398.591056) (xy 372.5855 -398.542002)
			(xy 371.996462 -398.542002) (xy 371.995967 -398.566609) (xy 371.988072 -398.615186) (xy 371.972488 -398.661867)
			(xy 371.949617 -398.705444) (xy 371.920052 -398.744788) (xy 371.884559 -398.77888) (xy 371.844056 -398.806836)
			(xy 371.799594 -398.827934) (xy 371.752323 -398.841626) (xy 371.703468 -398.847558) (xy 371.654293 -398.845577)
			(xy 371.606074 -398.835733) (xy 371.560058 -398.818281) (xy 371.517437 -398.793674) (xy 371.479316 -398.762549)
			(xy 371.446681 -398.725712) (xy 371.420378 -398.684116) (xy 371.401087 -398.63884) (xy 371.38931 -398.591056)
			(xy 371.38535 -398.542002) (xy 370.85524 -398.542002) (xy 370.85524 -399.807938) (xy 370.855595 -399.817321)
			(xy 370.862369 -399.834819) (xy 370.868448 -399.841974) (xy 370.920518 -399.899632) (xy 370.937028 -399.908014)
			(xy 370.94668 -399.90903) (xy 370.971482 -399.912002) (xy 371.019715 -399.924977) (xy 371.065194 -399.945628)
			(xy 371.106706 -399.973406) (xy 371.143144 -400.007569) (xy 371.173537 -400.047206) (xy 371.197074 -400.091262)
			(xy 371.213128 -400.13856) (xy 371.22127 -400.18784) (xy 371.221762 -400.212814) (xy 371.221264 -400.237184)
			(xy 371.213484 -400.2853) (xy 371.198173 -400.331573) (xy 371.175716 -400.374833) (xy 371.161564 -400.394678)
			(xy 371.155976 -400.402552) (xy 371.150896 -400.420332) (xy 371.159278 -400.506946) (xy 371.167406 -400.52371)
			(xy 371.174518 -400.53006) (xy 371.193643 -400.548201) (xy 371.227218 -400.588837) (xy 371.254882 -400.633708)
			(xy 371.276106 -400.681959) (xy 371.290487 -400.732672) (xy 371.29775 -400.784882) (xy 371.298216 -400.811238)
			(xy 371.298216 -401.674838) (xy 371.734588 -401.674838) (xy 371.734588 -400.811238) (xy 371.735052 -400.784882)
			(xy 371.742316 -400.732672) (xy 371.756697 -400.681959) (xy 371.777921 -400.633708) (xy 371.805585 -400.588837)
			(xy 371.839161 -400.548201) (xy 371.858286 -400.53006) (xy 371.865398 -400.523456) (xy 371.87378 -400.506946)
			(xy 371.881908 -400.420078) (xy 371.877082 -400.402298) (xy 371.87124 -400.394678) (xy 371.857129 -400.374814)
			(xy 371.834709 -400.331557) (xy 371.819453 -400.285285) (xy 371.81175 -400.237175) (xy 371.811296 -400.212814)
			(xy 371.811818 -400.187559) (xy 371.820131 -400.137737) (xy 371.836532 -400.089963) (xy 371.860573 -400.04554)
			(xy 371.891597 -400.00568) (xy 371.928759 -399.97147) (xy 371.971045 -399.943844) (xy 372.017301 -399.923554)
			(xy 372.066266 -399.911154) (xy 372.116604 -399.906983) (xy 372.166942 -399.911154) (xy 372.215907 -399.923554)
			(xy 372.262163 -399.943844) (xy 372.304449 -399.97147) (xy 372.341611 -400.00568) (xy 372.372635 -400.04554)
			(xy 372.396676 -400.089963) (xy 372.413077 -400.137737) (xy 372.42139 -400.187559) (xy 372.421912 -400.212814)
			(xy 372.421455 -400.237217) (xy 372.413694 -400.285402) (xy 372.398372 -400.331741) (xy 372.375878 -400.375054)
			(xy 372.361714 -400.394932) (xy 372.356126 -400.402552) (xy 372.351046 -400.420332) (xy 372.359174 -400.5072)
			(xy 372.367556 -400.52371) (xy 372.374668 -400.530314) (xy 372.393727 -400.548477) (xy 372.42722 -400.589096)
			(xy 372.45482 -400.633928) (xy 372.476004 -400.682125) (xy 372.49037 -400.732774) (xy 372.497647 -400.784915)
			(xy 372.498112 -400.811238) (xy 372.498112 -401.674838) (xy 372.934992 -401.674838) (xy 372.934992 -400.811238)
			(xy 372.935443 -400.784893) (xy 372.942691 -400.732703) (xy 372.957041 -400.682004) (xy 372.978222 -400.633757)
			(xy 373.005831 -400.588879) (xy 373.039344 -400.54822) (xy 373.058436 -400.53006) (xy 373.065548 -400.52371)
			(xy 373.073676 -400.506946) (xy 373.082058 -400.420332) (xy 373.076978 -400.402552) (xy 373.07139 -400.394678)
			(xy 373.057245 -400.374828) (xy 373.034785 -400.331571) (xy 373.019471 -400.285299) (xy 373.011691 -400.237184)
			(xy 373.011192 -400.212814) (xy 373.011714 -400.187559) (xy 373.020027 -400.137737) (xy 373.036428 -400.089963)
			(xy 373.060469 -400.04554) (xy 373.091493 -400.00568) (xy 373.128655 -399.97147) (xy 373.170941 -399.943844)
			(xy 373.217197 -399.923554) (xy 373.266162 -399.911154) (xy 373.3165 -399.906983) (xy 373.366838 -399.911154)
			(xy 373.415803 -399.923554) (xy 373.462059 -399.943844) (xy 373.504345 -399.97147) (xy 373.541507 -400.00568)
			(xy 373.572531 -400.04554) (xy 373.596572 -400.089963) (xy 373.612973 -400.137737) (xy 373.621286 -400.187559)
			(xy 373.621808 -400.212814) (xy 373.621338 -400.237187) (xy 373.613578 -400.285311) (xy 373.598258 -400.331586)
			(xy 373.575769 -400.374834) (xy 373.56161 -400.394678) (xy 373.556022 -400.402552) (xy 373.550942 -400.420332)
			(xy 373.559324 -400.506946) (xy 373.567452 -400.52371) (xy 373.574564 -400.53006) (xy 373.59367 -400.548207)
			(xy 373.62719 -400.588864) (xy 373.654803 -400.633744) (xy 373.675983 -400.681994) (xy 373.690329 -400.732697)
			(xy 373.697568 -400.784891) (xy 373.698008 -400.811238) (xy 373.698008 -401.674838) (xy 374.134888 -401.674838)
			(xy 374.134888 -400.811238) (xy 374.13534 -400.784893) (xy 374.142588 -400.732703) (xy 374.156938 -400.682004)
			(xy 374.178119 -400.633758) (xy 374.205727 -400.588879) (xy 374.23924 -400.54822) (xy 374.258332 -400.53006)
			(xy 374.265444 -400.52371) (xy 374.273572 -400.506946) (xy 374.281954 -400.420332) (xy 374.276874 -400.402552)
			(xy 374.271286 -400.394678) (xy 374.25714 -400.374828) (xy 374.234681 -400.331571) (xy 374.219367 -400.285299)
			(xy 374.211587 -400.237184) (xy 374.211088 -400.212814) (xy 374.21161 -400.187559) (xy 374.219923 -400.137737)
			(xy 374.236324 -400.089963) (xy 374.260365 -400.04554) (xy 374.291389 -400.00568) (xy 374.328551 -399.97147)
			(xy 374.370837 -399.943844) (xy 374.417093 -399.923554) (xy 374.466058 -399.911154) (xy 374.516396 -399.906983)
			(xy 374.566734 -399.911154) (xy 374.615699 -399.923554) (xy 374.661955 -399.943844) (xy 374.704241 -399.97147)
			(xy 374.741403 -400.00568) (xy 374.772427 -400.04554) (xy 374.796468 -400.089963) (xy 374.812869 -400.137737)
			(xy 374.821182 -400.187559) (xy 374.821704 -400.212814) (xy 374.821235 -400.237187) (xy 374.813475 -400.285311)
			(xy 374.798155 -400.331586) (xy 374.775665 -400.374834) (xy 374.761506 -400.394678) (xy 374.755918 -400.402552)
			(xy 374.750838 -400.420332) (xy 374.75922 -400.506946) (xy 374.767348 -400.52371) (xy 374.77446 -400.53006)
			(xy 374.793565 -400.548208) (xy 374.827086 -400.588865) (xy 374.854698 -400.633744) (xy 374.875879 -400.681994)
			(xy 374.890225 -400.732697) (xy 374.897464 -400.784891) (xy 374.897904 -400.811238) (xy 374.897904 -401.674838)
			(xy 375.334784 -401.674838) (xy 375.334784 -400.811238) (xy 375.33525 -400.784882) (xy 375.342513 -400.732672)
			(xy 375.356894 -400.681959) (xy 375.378118 -400.633708) (xy 375.405782 -400.588837) (xy 375.439357 -400.548201)
			(xy 375.458482 -400.53006) (xy 375.465594 -400.52371) (xy 375.473722 -400.506946) (xy 375.482104 -400.420332)
			(xy 375.477024 -400.402552) (xy 375.471436 -400.394678) (xy 375.457284 -400.374833) (xy 375.434827 -400.331573)
			(xy 375.419516 -400.2853) (xy 375.411736 -400.237184) (xy 375.411238 -400.212814) (xy 375.41176 -400.187559)
			(xy 375.420073 -400.137737) (xy 375.436474 -400.089963) (xy 375.460515 -400.04554) (xy 375.491539 -400.00568)
			(xy 375.528701 -399.97147) (xy 375.570987 -399.943844) (xy 375.617243 -399.923554) (xy 375.666208 -399.911154)
			(xy 375.716546 -399.906983) (xy 375.766884 -399.911154) (xy 375.815849 -399.923554) (xy 375.862105 -399.943844)
			(xy 375.904391 -399.97147) (xy 375.941553 -400.00568) (xy 375.972577 -400.04554) (xy 375.996618 -400.089963)
			(xy 376.013019 -400.137737) (xy 376.021332 -400.187559) (xy 376.021854 -400.212814) (xy 376.021375 -400.237186)
			(xy 376.013616 -400.285309) (xy 375.998299 -400.331585) (xy 375.975813 -400.374833) (xy 375.961656 -400.394678)
			(xy 375.956068 -400.402552) (xy 375.950988 -400.420332) (xy 375.95937 -400.506946) (xy 375.967498 -400.52371)
			(xy 375.97461 -400.53006) (xy 375.993736 -400.548202) (xy 376.027326 -400.58883) (xy 376.055 -400.633698)
			(xy 376.076229 -400.68195) (xy 376.090609 -400.732666) (xy 376.097865 -400.78488) (xy 376.098308 -400.811238)
			(xy 376.098308 -401.674838) (xy 376.53468 -401.674838) (xy 376.53468 -400.811238) (xy 376.535147 -400.784882)
			(xy 376.542411 -400.732672) (xy 376.556791 -400.681959) (xy 376.578015 -400.633708) (xy 376.605678 -400.588837)
			(xy 376.639254 -400.548201) (xy 376.658378 -400.53006) (xy 376.66549 -400.52371) (xy 376.673618 -400.506946)
			(xy 376.682 -400.420332) (xy 376.67692 -400.402552) (xy 376.671332 -400.394678) (xy 376.657179 -400.374833)
			(xy 376.634723 -400.331573) (xy 376.619412 -400.2853) (xy 376.611632 -400.237184) (xy 376.611134 -400.212814)
			(xy 376.611656 -400.187559) (xy 376.619969 -400.137737) (xy 376.63637 -400.089963) (xy 376.660411 -400.04554)
			(xy 376.691435 -400.00568) (xy 376.728597 -399.97147) (xy 376.770883 -399.943844) (xy 376.817139 -399.923554)
			(xy 376.866104 -399.911154) (xy 376.916442 -399.906983) (xy 376.96678 -399.911154) (xy 377.015745 -399.923554)
			(xy 377.062001 -399.943844) (xy 377.104287 -399.97147) (xy 377.141449 -400.00568) (xy 377.172473 -400.04554)
			(xy 377.196514 -400.089963) (xy 377.212915 -400.137737) (xy 377.221228 -400.187559) (xy 377.22175 -400.212814)
			(xy 377.221272 -400.237186) (xy 377.213513 -400.28531) (xy 377.198195 -400.331585) (xy 377.175709 -400.374833)
			(xy 377.161552 -400.394678) (xy 377.155964 -400.402552) (xy 377.150884 -400.420332) (xy 377.159266 -400.506946)
			(xy 377.167394 -400.52371) (xy 377.174506 -400.53006) (xy 377.193632 -400.548203) (xy 377.227222 -400.58883)
			(xy 377.254896 -400.633698) (xy 377.276125 -400.68195) (xy 377.290505 -400.732666) (xy 377.297761 -400.78488)
			(xy 377.298204 -400.811238) (xy 377.298204 -401.674838) (xy 377.735084 -401.674838) (xy 377.735084 -400.811238)
			(xy 377.735537 -400.784893) (xy 377.742785 -400.732703) (xy 377.757135 -400.682004) (xy 377.778316 -400.633758)
			(xy 377.805924 -400.588879) (xy 377.839436 -400.54822) (xy 377.858528 -400.53006) (xy 377.86564 -400.52371)
			(xy 377.873768 -400.506946) (xy 377.88215 -400.420332) (xy 377.87707 -400.402552) (xy 377.871482 -400.394678)
			(xy 377.857336 -400.374829) (xy 377.834876 -400.331571) (xy 377.819563 -400.285299) (xy 377.811782 -400.237184)
			(xy 377.811284 -400.212814) (xy 377.811806 -400.187559) (xy 377.820119 -400.137737) (xy 377.83652 -400.089963)
			(xy 377.860561 -400.04554) (xy 377.891585 -400.00568) (xy 377.928747 -399.97147) (xy 377.971033 -399.943844)
			(xy 378.017289 -399.923554) (xy 378.066254 -399.911154) (xy 378.116592 -399.906983) (xy 378.16693 -399.911154)
			(xy 378.215895 -399.923554) (xy 378.262151 -399.943844) (xy 378.304437 -399.97147) (xy 378.341599 -400.00568)
			(xy 378.372623 -400.04554) (xy 378.396664 -400.089963) (xy 378.413065 -400.137737) (xy 378.421378 -400.187559)
			(xy 378.4219 -400.212814) (xy 378.421431 -400.237187) (xy 378.413671 -400.285311) (xy 378.398351 -400.331586)
			(xy 378.375861 -400.374834) (xy 378.361702 -400.394678) (xy 378.356114 -400.402552) (xy 378.351034 -400.420332)
			(xy 378.359416 -400.506946) (xy 378.367544 -400.52371) (xy 378.374656 -400.53006) (xy 378.39376 -400.548209)
			(xy 378.427281 -400.588865) (xy 378.454894 -400.633745) (xy 378.476075 -400.681994) (xy 378.490421 -400.732697)
			(xy 378.49766 -400.784891) (xy 378.4981 -400.811238) (xy 378.4981 -401.674838) (xy 378.93498 -401.674838)
			(xy 378.93498 -400.811238) (xy 378.935434 -400.784893) (xy 378.942682 -400.732703) (xy 378.957032 -400.682004)
			(xy 378.978212 -400.633758) (xy 379.00582 -400.58888) (xy 379.039332 -400.54822) (xy 379.058424 -400.53006)
			(xy 379.065536 -400.52371) (xy 379.073664 -400.506946) (xy 379.082046 -400.420332) (xy 379.076966 -400.402552)
			(xy 379.071378 -400.394678) (xy 379.057231 -400.374829) (xy 379.034772 -400.331571) (xy 379.019459 -400.285299)
			(xy 379.011678 -400.237184) (xy 379.01118 -400.212814) (xy 379.011702 -400.187559) (xy 379.020015 -400.137737)
			(xy 379.036416 -400.089963) (xy 379.060457 -400.04554) (xy 379.091481 -400.00568) (xy 379.128643 -399.97147)
			(xy 379.170929 -399.943844) (xy 379.217185 -399.923554) (xy 379.26615 -399.911154) (xy 379.316488 -399.906983)
			(xy 379.366826 -399.911154) (xy 379.415791 -399.923554) (xy 379.462047 -399.943844) (xy 379.504333 -399.97147)
			(xy 379.541495 -400.00568) (xy 379.572519 -400.04554) (xy 379.59656 -400.089963) (xy 379.612961 -400.137737)
			(xy 379.621274 -400.187559) (xy 379.621796 -400.212814) (xy 379.621328 -400.237187) (xy 379.613568 -400.285311)
			(xy 379.598247 -400.331587) (xy 379.575757 -400.374834) (xy 379.561598 -400.394678) (xy 379.55601 -400.402552)
			(xy 379.55093 -400.420332) (xy 379.559312 -400.506946) (xy 379.56744 -400.52371) (xy 379.574552 -400.53006)
			(xy 379.593655 -400.548209) (xy 379.627177 -400.588866) (xy 379.65479 -400.633745) (xy 379.675971 -400.681994)
			(xy 379.690317 -400.732697) (xy 379.697556 -400.784891) (xy 379.697996 -400.811238) (xy 379.697996 -401.674838)
			(xy 380.134876 -401.674838) (xy 380.134876 -400.811238) (xy 380.135294 -400.78491) (xy 380.142545 -400.732755)
			(xy 380.156901 -400.682094) (xy 380.178088 -400.633888) (xy 380.205705 -400.589055) (xy 380.239226 -400.548446)
			(xy 380.25832 -400.530314) (xy 380.265432 -400.52371) (xy 380.273814 -400.5072) (xy 380.281942 -400.420332)
			(xy 380.276862 -400.402552) (xy 380.271274 -400.394932) (xy 380.257115 -400.375052) (xy 380.234629 -400.331737)
			(xy 380.219312 -400.285399) (xy 380.211554 -400.237216) (xy 380.211076 -400.212814) (xy 380.211598 -400.187559)
			(xy 380.219911 -400.137737) (xy 380.236312 -400.089963) (xy 380.260353 -400.04554) (xy 380.291377 -400.00568)
			(xy 380.328539 -399.97147) (xy 380.370825 -399.943844) (xy 380.417081 -399.923554) (xy 380.466046 -399.911154)
			(xy 380.516384 -399.906983) (xy 380.566722 -399.911154) (xy 380.615687 -399.923554) (xy 380.661943 -399.943844)
			(xy 380.704229 -399.97147) (xy 380.741391 -400.00568) (xy 380.772415 -400.04554) (xy 380.796456 -400.089963)
			(xy 380.812857 -400.137737) (xy 380.82117 -400.187559) (xy 380.821692 -400.212814) (xy 380.821205 -400.237173)
			(xy 380.813491 -400.285276) (xy 380.798245 -400.331546) (xy 380.775853 -400.374813) (xy 380.761748 -400.394678)
			(xy 380.755906 -400.402298) (xy 380.75108 -400.420078) (xy 380.759208 -400.506946) (xy 380.76759 -400.523456)
			(xy 380.774702 -400.53006) (xy 380.793827 -400.548203) (xy 380.827417 -400.588831) (xy 380.855091 -400.633698)
			(xy 380.876321 -400.68195) (xy 380.890701 -400.732667) (xy 380.897957 -400.78488) (xy 380.8984 -400.811238)
			(xy 380.8984 -401.674838) (xy 381.334772 -401.674838) (xy 381.334772 -400.811238) (xy 381.335242 -400.784882)
			(xy 381.342505 -400.732672) (xy 381.356885 -400.68196) (xy 381.378109 -400.633709) (xy 381.405771 -400.588838)
			(xy 381.439346 -400.548202) (xy 381.45847 -400.53006) (xy 381.465582 -400.52371) (xy 381.47371 -400.506946)
			(xy 381.482092 -400.420332) (xy 381.477012 -400.402552) (xy 381.471424 -400.394678) (xy 381.45727 -400.374834)
			(xy 381.434815 -400.331574) (xy 381.419503 -400.2853) (xy 381.411724 -400.237184) (xy 381.411226 -400.212814)
			(xy 381.411748 -400.187559) (xy 381.420061 -400.137737) (xy 381.436462 -400.089963) (xy 381.460503 -400.04554)
			(xy 381.491527 -400.00568) (xy 381.528689 -399.97147) (xy 381.570975 -399.943844) (xy 381.617231 -399.923554)
			(xy 381.666196 -399.911154) (xy 381.716534 -399.906983) (xy 381.766872 -399.911154) (xy 381.815837 -399.923554)
			(xy 381.862093 -399.943844) (xy 381.904379 -399.97147) (xy 381.941541 -400.00568) (xy 381.972565 -400.04554)
			(xy 381.996606 -400.089963) (xy 382.013007 -400.137737) (xy 382.02132 -400.187559) (xy 382.021842 -400.212814)
			(xy 382.021365 -400.237186) (xy 382.013606 -400.28531) (xy 381.998288 -400.331585) (xy 381.975801 -400.374833)
			(xy 381.961644 -400.394678) (xy 381.956056 -400.402552) (xy 381.950976 -400.420332) (xy 381.959358 -400.506946)
			(xy 381.967486 -400.52371) (xy 381.974598 -400.53006) (xy 381.993722 -400.548204) (xy 382.027313 -400.588831)
			(xy 382.054987 -400.633699) (xy 382.076216 -400.68195) (xy 382.090597 -400.732667) (xy 382.097853 -400.78488)
			(xy 382.098296 -400.811238) (xy 382.098296 -401.674838) (xy 382.535176 -401.674838) (xy 382.535176 -400.811238)
			(xy 382.535616 -400.784922) (xy 382.54284 -400.732787) (xy 382.557156 -400.682139) (xy 382.578293 -400.633937)
			(xy 382.60585 -400.589096) (xy 382.639305 -400.548464) (xy 382.658366 -400.530314) (xy 382.665478 -400.52371)
			(xy 382.67386 -400.5072) (xy 382.681988 -400.420332) (xy 382.676908 -400.402552) (xy 382.67132 -400.394932)
			(xy 382.657167 -400.375048) (xy 382.634678 -400.331735) (xy 382.619359 -400.285398) (xy 382.6116 -400.237216)
			(xy 382.611122 -400.212814) (xy 382.611644 -400.187559) (xy 382.619957 -400.137737) (xy 382.636358 -400.089963)
			(xy 382.660399 -400.04554) (xy 382.691423 -400.00568) (xy 382.728585 -399.97147) (xy 382.770871 -399.943844)
			(xy 382.817127 -399.923554) (xy 382.866092 -399.911154) (xy 382.91643 -399.906983) (xy 382.966768 -399.911154)
			(xy 383.015733 -399.923554) (xy 383.061989 -399.943844) (xy 383.104275 -399.97147) (xy 383.141437 -400.00568)
			(xy 383.172461 -400.04554) (xy 383.196502 -400.089963) (xy 383.212903 -400.137737) (xy 383.221216 -400.187559)
			(xy 383.221738 -400.212814) (xy 383.221243 -400.237172) (xy 383.21353 -400.285275) (xy 383.198287 -400.331545)
			(xy 383.175898 -400.374812) (xy 383.161794 -400.394678) (xy 383.155952 -400.402298) (xy 383.151126 -400.420078)
			(xy 383.159254 -400.506946) (xy 383.167636 -400.523456) (xy 383.174748 -400.53006) (xy 383.193851 -400.54821)
			(xy 383.227372 -400.588866) (xy 383.254985 -400.633745) (xy 383.276167 -400.681994) (xy 383.290513 -400.732697)
			(xy 383.297752 -400.784891) (xy 383.298192 -400.811238) (xy 383.298192 -401.674838) (xy 383.735072 -401.674838)
			(xy 383.735072 -400.811238) (xy 383.735529 -400.784893) (xy 383.742777 -400.732704) (xy 383.757127 -400.682005)
			(xy 383.778306 -400.633759) (xy 383.805913 -400.58888) (xy 383.839425 -400.54822) (xy 383.858516 -400.53006)
			(xy 383.865628 -400.52371) (xy 383.873756 -400.506946) (xy 383.882138 -400.420332) (xy 383.877058 -400.402552)
			(xy 383.87147 -400.394678) (xy 383.857322 -400.37483) (xy 383.834864 -400.331572) (xy 383.819551 -400.285299)
			(xy 383.81177 -400.237184) (xy 383.811272 -400.212814) (xy 383.811794 -400.187559) (xy 383.820107 -400.137737)
			(xy 383.836508 -400.089963) (xy 383.860549 -400.04554) (xy 383.891573 -400.00568) (xy 383.928735 -399.97147)
			(xy 383.971021 -399.943844) (xy 384.017277 -399.923554) (xy 384.066242 -399.911154) (xy 384.11658 -399.906983)
			(xy 384.166918 -399.911154) (xy 384.215883 -399.923554) (xy 384.262139 -399.943844) (xy 384.304425 -399.97147)
			(xy 384.341587 -400.00568) (xy 384.372611 -400.04554) (xy 384.396652 -400.089963) (xy 384.413053 -400.137737)
			(xy 384.421366 -400.187559) (xy 384.421888 -400.212814) (xy 384.421422 -400.237187) (xy 384.413661 -400.285311)
			(xy 384.39834 -400.331587) (xy 384.37585 -400.374834) (xy 384.36169 -400.394678) (xy 384.356102 -400.402552)
			(xy 384.351022 -400.420332) (xy 384.359404 -400.506946) (xy 384.367532 -400.52371) (xy 384.374644 -400.53006)
			(xy 384.393746 -400.548211) (xy 384.427267 -400.588867) (xy 384.454881 -400.633746) (xy 384.476062 -400.681995)
			(xy 384.490409 -400.732697) (xy 384.497648 -400.784891) (xy 384.498088 -400.811238) (xy 384.498088 -401.674838)
			(xy 384.934968 -401.674838) (xy 384.934968 -400.811238) (xy 384.935426 -400.784893) (xy 384.942674 -400.732704)
			(xy 384.957024 -400.682005) (xy 384.978203 -400.633759) (xy 385.00581 -400.58888) (xy 385.039321 -400.54822)
			(xy 385.058412 -400.53006) (xy 385.065524 -400.52371) (xy 385.073652 -400.506946) (xy 385.082034 -400.420332)
			(xy 385.076954 -400.402552) (xy 385.071366 -400.394678) (xy 385.057218 -400.37483) (xy 385.034759 -400.331572)
			(xy 385.019446 -400.285299) (xy 385.011666 -400.237184) (xy 385.011168 -400.212814) (xy 385.01169 -400.187559)
			(xy 385.020003 -400.137737) (xy 385.036404 -400.089963) (xy 385.060445 -400.04554) (xy 385.091469 -400.00568)
			(xy 385.128631 -399.97147) (xy 385.170917 -399.943844) (xy 385.217173 -399.923554) (xy 385.266138 -399.911154)
			(xy 385.316476 -399.906983) (xy 385.366814 -399.911154) (xy 385.415779 -399.923554) (xy 385.462035 -399.943844)
			(xy 385.504321 -399.97147) (xy 385.541483 -400.00568) (xy 385.572507 -400.04554) (xy 385.596548 -400.089963)
			(xy 385.612949 -400.137737) (xy 385.621262 -400.187559) (xy 385.621784 -400.212814) (xy 385.621319 -400.237187)
			(xy 385.613558 -400.285311) (xy 385.598237 -400.331587) (xy 385.575746 -400.374834) (xy 385.561586 -400.394678)
			(xy 385.555998 -400.402552) (xy 385.550918 -400.420332) (xy 385.5593 -400.506946) (xy 385.567428 -400.52371)
			(xy 385.57454 -400.53006) (xy 385.593641 -400.548212) (xy 385.627163 -400.588867) (xy 385.654777 -400.633746)
			(xy 385.675958 -400.681995) (xy 385.690305 -400.732697) (xy 385.697544 -400.784891) (xy 385.697984 -400.811238)
			(xy 385.697984 -401.674838) (xy 386.134864 -401.674838) (xy 386.134864 -400.811238) (xy 386.135324 -400.784893)
			(xy 386.142571 -400.732704) (xy 386.156921 -400.682005) (xy 386.1781 -400.633759) (xy 386.205706 -400.588881)
			(xy 386.239217 -400.54822) (xy 386.258308 -400.53006) (xy 386.26542 -400.52371) (xy 386.273548 -400.506946)
			(xy 386.28193 -400.420332) (xy 386.27685 -400.402552) (xy 386.271262 -400.394678) (xy 386.257113 -400.37483)
			(xy 386.234655 -400.331572) (xy 386.219342 -400.285299) (xy 386.211562 -400.237184) (xy 386.211064 -400.212814)
			(xy 386.211586 -400.187559) (xy 386.219899 -400.137737) (xy 386.2363 -400.089963) (xy 386.260341 -400.04554)
			(xy 386.291365 -400.00568) (xy 386.328527 -399.97147) (xy 386.370813 -399.943844) (xy 386.417069 -399.923554)
			(xy 386.466034 -399.911154) (xy 386.516372 -399.906983) (xy 386.56671 -399.911154) (xy 386.615675 -399.923554)
			(xy 386.661931 -399.943844) (xy 386.704217 -399.97147) (xy 386.741379 -400.00568) (xy 386.772403 -400.04554)
			(xy 386.796444 -400.089963) (xy 386.812845 -400.137737) (xy 386.821158 -400.187559) (xy 386.82168 -400.212814)
			(xy 386.821215 -400.237187) (xy 386.813455 -400.285311) (xy 386.798133 -400.331587) (xy 386.775642 -400.374834)
			(xy 386.761482 -400.394678) (xy 386.755894 -400.402552) (xy 386.750814 -400.420332) (xy 386.759196 -400.506946)
			(xy 386.767324 -400.52371) (xy 386.774436 -400.53006) (xy 386.793536 -400.548213) (xy 386.827058 -400.588868)
			(xy 386.854672 -400.633746) (xy 386.875854 -400.681995) (xy 386.890201 -400.732698) (xy 386.89744 -400.784891)
			(xy 386.89788 -400.811238) (xy 386.89788 -401.674838) (xy 386.897414 -401.701001) (xy 386.890264 -401.752836)
			(xy 386.876103 -401.80321) (xy 386.855196 -401.851178) (xy 386.827935 -401.895842) (xy 386.794831 -401.936365)
			(xy 386.77596 -401.954492) (xy 386.768594 -401.96135) (xy 386.760466 -401.978876) (xy 386.755132 -402.069046)
			(xy 386.761228 -402.087334) (xy 386.767832 -402.094954) (xy 386.782737 -402.112994) (xy 386.807799 -402.152513)
			(xy 386.827046 -402.195169) (xy 386.840092 -402.240109) (xy 386.846678 -402.28644) (xy 386.84708 -402.309838)
			(xy 386.84657 -402.335825) (xy 386.83844 -402.38716) (xy 386.822379 -402.43659) (xy 386.798783 -402.4829)
			(xy 386.768233 -402.524948) (xy 386.731482 -402.561699) (xy 386.689434 -402.592249) (xy 386.643124 -402.615845)
			(xy 386.593694 -402.631906) (xy 386.542359 -402.640036) (xy 386.490385 -402.640036) (xy 386.43905 -402.631906)
			(xy 386.38962 -402.615845) (xy 386.34331 -402.592249) (xy 386.301262 -402.561699) (xy 386.264511 -402.524948)
			(xy 386.233961 -402.4829) (xy 386.210365 -402.43659) (xy 386.194304 -402.38716) (xy 386.186174 -402.335825)
			(xy 386.185664 -402.309838) (xy 386.186085 -402.286441) (xy 386.192672 -402.240114) (xy 386.205719 -402.195177)
			(xy 386.224966 -402.152526) (xy 386.25003 -402.113012) (xy 386.264912 -402.094954) (xy 386.271516 -402.087334)
			(xy 386.277612 -402.069046) (xy 386.272278 -401.978876) (xy 386.26415 -401.96135) (xy 386.256784 -401.954492)
			(xy 386.237887 -401.936389) (xy 386.20477 -401.895867) (xy 386.177502 -401.851201) (xy 386.156592 -401.803228)
			(xy 386.142433 -401.752847) (xy 386.135291 -401.701004) (xy 386.134864 -401.674838) (xy 385.697984 -401.674838)
			(xy 385.697464 -401.703743) (xy 385.688758 -401.760895) (xy 385.671534 -401.81608) (xy 385.646188 -401.868038)
			(xy 385.613298 -401.91558) (xy 385.593844 -401.936966) (xy 385.587748 -401.94357) (xy 385.580636 -401.959572)
			(xy 385.575048 -402.041868) (xy 385.579874 -402.058886) (xy 385.584954 -402.065998) (xy 385.599591 -402.087228)
			(xy 385.622844 -402.133249) (xy 385.63867 -402.182322) (xy 385.646685 -402.233257) (xy 385.647184 -402.259038)
			(xy 385.646674 -402.285025) (xy 385.638544 -402.33636) (xy 385.622483 -402.38579) (xy 385.598887 -402.4321)
			(xy 385.568337 -402.474148) (xy 385.531586 -402.510899) (xy 385.489538 -402.541449) (xy 385.443228 -402.565045)
			(xy 385.393798 -402.581106) (xy 385.342463 -402.589236) (xy 385.290489 -402.589236) (xy 385.239154 -402.581106)
			(xy 385.189724 -402.565045) (xy 385.143414 -402.541449) (xy 385.101366 -402.510899) (xy 385.064615 -402.474148)
			(xy 385.034065 -402.4321) (xy 385.010469 -402.38579) (xy 384.994408 -402.33636) (xy 384.986278 -402.285025)
			(xy 384.985768 -402.259038) (xy 384.986247 -402.233255) (xy 384.994253 -402.182314) (xy 385.010078 -402.133236)
			(xy 385.033337 -402.087213) (xy 385.047998 -402.065998) (xy 385.053078 -402.058886) (xy 385.057904 -402.041868)
			(xy 385.052316 -401.959572) (xy 385.045204 -401.94357) (xy 385.039108 -401.936966) (xy 385.019626 -401.915602)
			(xy 384.986718 -401.868065) (xy 384.961366 -401.816103) (xy 384.944154 -401.760908) (xy 384.935476 -401.703747)
			(xy 384.934968 -401.674838) (xy 384.498088 -401.674838) (xy 384.497619 -401.701001) (xy 384.490469 -401.752836)
			(xy 384.476308 -401.803209) (xy 384.455402 -401.851177) (xy 384.428142 -401.895841) (xy 384.395038 -401.936365)
			(xy 384.376168 -401.954492) (xy 384.368802 -401.96135) (xy 384.360674 -401.978876) (xy 384.35534 -402.069046)
			(xy 384.361436 -402.087334) (xy 384.36804 -402.094954) (xy 384.382946 -402.112993) (xy 384.408008 -402.152513)
			(xy 384.427254 -402.195168) (xy 384.4403 -402.240109) (xy 384.446886 -402.28644) (xy 384.447288 -402.309838)
			(xy 384.446778 -402.335825) (xy 384.438648 -402.38716) (xy 384.422587 -402.43659) (xy 384.398991 -402.4829)
			(xy 384.368441 -402.524948) (xy 384.33169 -402.561699) (xy 384.289642 -402.592249) (xy 384.243332 -402.615845)
			(xy 384.193902 -402.631906) (xy 384.142567 -402.640036) (xy 384.090593 -402.640036) (xy 384.039258 -402.631906)
			(xy 383.989828 -402.615845) (xy 383.943518 -402.592249) (xy 383.90147 -402.561699) (xy 383.864719 -402.524948)
			(xy 383.834169 -402.4829) (xy 383.810573 -402.43659) (xy 383.794512 -402.38716) (xy 383.786382 -402.335825)
			(xy 383.785872 -402.309838) (xy 383.786292 -402.286441) (xy 383.792878 -402.240114) (xy 383.805925 -402.195177)
			(xy 383.825173 -402.152526) (xy 383.850237 -402.113011) (xy 383.86512 -402.094954) (xy 383.871724 -402.087334)
			(xy 383.87782 -402.069046) (xy 383.872486 -401.978876) (xy 383.864358 -401.96135) (xy 383.856992 -401.954492)
			(xy 383.838096 -401.936387) (xy 383.804979 -401.895866) (xy 383.77771 -401.8512) (xy 383.7568 -401.803227)
			(xy 383.742641 -401.752847) (xy 383.735499 -401.701004) (xy 383.735072 -401.674838) (xy 383.298192 -401.674838)
			(xy 383.297722 -401.701001) (xy 383.290572 -401.752836) (xy 383.276411 -401.803209) (xy 383.255505 -401.851177)
			(xy 383.228245 -401.895841) (xy 383.195142 -401.936365) (xy 383.176272 -401.954492) (xy 383.168906 -401.96135)
			(xy 383.160778 -401.978876) (xy 383.155444 -402.069046) (xy 383.16154 -402.087334) (xy 383.168144 -402.094954)
			(xy 383.183051 -402.112993) (xy 383.208113 -402.152513) (xy 383.227358 -402.195168) (xy 383.240404 -402.240109)
			(xy 383.24699 -402.28644) (xy 383.247392 -402.309838) (xy 383.246882 -402.335825) (xy 383.238752 -402.38716)
			(xy 383.222691 -402.43659) (xy 383.199095 -402.4829) (xy 383.168545 -402.524948) (xy 383.131794 -402.561699)
			(xy 383.089746 -402.592249) (xy 383.043436 -402.615845) (xy 382.994006 -402.631906) (xy 382.942671 -402.640036)
			(xy 382.890697 -402.640036) (xy 382.839362 -402.631906) (xy 382.789932 -402.615845) (xy 382.743622 -402.592249)
			(xy 382.701574 -402.561699) (xy 382.664823 -402.524948) (xy 382.634273 -402.4829) (xy 382.610677 -402.43659)
			(xy 382.594616 -402.38716) (xy 382.586486 -402.335825) (xy 382.585976 -402.309838) (xy 382.586395 -402.286441)
			(xy 382.592981 -402.240114) (xy 382.606029 -402.195177) (xy 382.625277 -402.152526) (xy 382.650341 -402.113011)
			(xy 382.665224 -402.094954) (xy 382.671828 -402.087334) (xy 382.677924 -402.069046) (xy 382.67259 -401.978876)
			(xy 382.664462 -401.96135) (xy 382.657096 -401.954492) (xy 382.638201 -401.936387) (xy 382.605084 -401.895866)
			(xy 382.577815 -401.8512) (xy 382.556904 -401.803227) (xy 382.542745 -401.752847) (xy 382.535603 -401.701004)
			(xy 382.535176 -401.674838) (xy 382.098296 -401.674838) (xy 382.097882 -401.701013) (xy 382.090684 -401.752866)
			(xy 382.076471 -401.803249) (xy 382.055507 -401.851218) (xy 382.028187 -401.895874) (xy 381.995022 -401.936379)
			(xy 381.976122 -401.954492) (xy 381.968756 -401.96135) (xy 381.960628 -401.978876) (xy 381.955294 -402.069046)
			(xy 381.96139 -402.087334) (xy 381.967994 -402.094954) (xy 381.982893 -402.112999) (xy 382.007958 -402.152516)
			(xy 382.027206 -402.19517) (xy 382.040253 -402.24011) (xy 382.04684 -402.28644) (xy 382.047242 -402.309838)
			(xy 382.046732 -402.335825) (xy 382.038602 -402.38716) (xy 382.022541 -402.43659) (xy 381.998945 -402.4829)
			(xy 381.968395 -402.524948) (xy 381.931644 -402.561699) (xy 381.889596 -402.592249) (xy 381.843286 -402.615845)
			(xy 381.793856 -402.631906) (xy 381.742521 -402.640036) (xy 381.690547 -402.640036) (xy 381.639212 -402.631906)
			(xy 381.589782 -402.615845) (xy 381.543472 -402.592249) (xy 381.501424 -402.561699) (xy 381.464673 -402.524948)
			(xy 381.434123 -402.4829) (xy 381.410527 -402.43659) (xy 381.394466 -402.38716) (xy 381.386336 -402.335825)
			(xy 381.385826 -402.309838) (xy 381.386256 -402.286442) (xy 381.392842 -402.240116) (xy 381.405887 -402.195179)
			(xy 381.425132 -402.152528) (xy 381.450193 -402.113012) (xy 381.465074 -402.094954) (xy 381.471678 -402.087334)
			(xy 381.477774 -402.069046) (xy 381.47244 -401.978876) (xy 381.464312 -401.96135) (xy 381.456946 -401.954492)
			(xy 381.438039 -401.936386) (xy 381.404879 -401.89588) (xy 381.377565 -401.851222) (xy 381.356609 -401.80325)
			(xy 381.342405 -401.752865) (xy 381.33522 -401.701012) (xy 381.334772 -401.674838) (xy 380.8984 -401.674838)
			(xy 380.897985 -401.701013) (xy 380.890787 -401.752865) (xy 380.876574 -401.803249) (xy 380.85561 -401.851218)
			(xy 380.82829 -401.895874) (xy 380.795126 -401.936379) (xy 380.776226 -401.954492) (xy 380.76886 -401.96135)
			(xy 380.760732 -401.978876) (xy 380.755398 -402.069046) (xy 380.761494 -402.087334) (xy 380.768098 -402.094954)
			(xy 380.782998 -402.112999) (xy 380.808062 -402.152516) (xy 380.82731 -402.19517) (xy 380.840357 -402.24011)
			(xy 380.846944 -402.28644) (xy 380.847346 -402.309838) (xy 380.846836 -402.335825) (xy 380.838706 -402.38716)
			(xy 380.822645 -402.43659) (xy 380.799049 -402.4829) (xy 380.768499 -402.524948) (xy 380.731748 -402.561699)
			(xy 380.6897 -402.592249) (xy 380.64339 -402.615845) (xy 380.59396 -402.631906) (xy 380.542625 -402.640036)
			(xy 380.490651 -402.640036) (xy 380.439316 -402.631906) (xy 380.389886 -402.615845) (xy 380.343576 -402.592249)
			(xy 380.301528 -402.561699) (xy 380.264777 -402.524948) (xy 380.234227 -402.4829) (xy 380.210631 -402.43659)
			(xy 380.19457 -402.38716) (xy 380.18644 -402.335825) (xy 380.18593 -402.309838) (xy 380.18636 -402.286442)
			(xy 380.192945 -402.240115) (xy 380.205991 -402.195179) (xy 380.225236 -402.152527) (xy 380.250297 -402.113012)
			(xy 380.265178 -402.094954) (xy 380.271782 -402.087334) (xy 380.277878 -402.069046) (xy 380.272544 -401.978876)
			(xy 380.264416 -401.96135) (xy 380.25705 -401.954492) (xy 380.238144 -401.936385) (xy 380.204984 -401.895879)
			(xy 380.177669 -401.851221) (xy 380.156713 -401.80325) (xy 380.142509 -401.752865) (xy 380.135324 -401.701012)
			(xy 380.134876 -401.674838) (xy 379.697996 -401.674838) (xy 379.697454 -401.704988) (xy 379.687996 -401.76454)
			(xy 379.669291 -401.821865) (xy 379.641803 -401.875534) (xy 379.606217 -401.924213) (xy 379.58522 -401.945856)
			(xy 379.578616 -401.95246) (xy 379.570996 -401.969224) (xy 379.565662 -402.05533) (xy 379.570996 -402.07311)
			(xy 379.576838 -402.080476) (xy 379.593342 -402.102467) (xy 379.619618 -402.150759) (xy 379.63755 -402.202729)
			(xy 379.646647 -402.256949) (xy 379.647196 -402.284438) (xy 379.646686 -402.310425) (xy 379.638556 -402.36176)
			(xy 379.622495 -402.41119) (xy 379.598899 -402.4575) (xy 379.568349 -402.499548) (xy 379.531598 -402.536299)
			(xy 379.48955 -402.566849) (xy 379.44324 -402.590445) (xy 379.39381 -402.606506) (xy 379.342475 -402.614636)
			(xy 379.290501 -402.614636) (xy 379.239166 -402.606506) (xy 379.189736 -402.590445) (xy 379.143426 -402.566849)
			(xy 379.101378 -402.536299) (xy 379.064627 -402.499548) (xy 379.034077 -402.4575) (xy 379.010481 -402.41119)
			(xy 378.99442 -402.36176) (xy 378.98629 -402.310425) (xy 378.98578 -402.284438) (xy 378.986337 -402.256948)
			(xy 378.995412 -402.202722) (xy 379.013336 -402.150746) (xy 379.039614 -402.102452) (xy 379.056138 -402.080476)
			(xy 379.06198 -402.07311) (xy 379.067314 -402.05533) (xy 379.06198 -401.969224) (xy 379.05436 -401.95246)
			(xy 379.047756 -401.945856) (xy 379.026771 -401.924201) (xy 378.991175 -401.875531) (xy 378.963683 -401.821865)
			(xy 378.944979 -401.764541) (xy 378.935531 -401.704987) (xy 378.93498 -401.674838) (xy 378.4981 -401.674838)
			(xy 378.497576 -401.703743) (xy 378.48887 -401.760894) (xy 378.471647 -401.816079) (xy 378.446302 -401.868037)
			(xy 378.413413 -401.91558) (xy 378.39396 -401.936966) (xy 378.387864 -401.94357) (xy 378.380752 -401.959572)
			(xy 378.375164 -402.041868) (xy 378.37999 -402.058886) (xy 378.38507 -402.065998) (xy 378.399709 -402.087226)
			(xy 378.422961 -402.133248) (xy 378.438786 -402.182322) (xy 378.446801 -402.233257) (xy 378.4473 -402.259038)
			(xy 378.44679 -402.285025) (xy 378.43866 -402.33636) (xy 378.422599 -402.38579) (xy 378.399003 -402.4321)
			(xy 378.368453 -402.474148) (xy 378.331702 -402.510899) (xy 378.289654 -402.541449) (xy 378.243344 -402.565045)
			(xy 378.193914 -402.581106) (xy 378.142579 -402.589236) (xy 378.090605 -402.589236) (xy 378.03927 -402.581106)
			(xy 377.98984 -402.565045) (xy 377.94353 -402.541449) (xy 377.901482 -402.510899) (xy 377.864731 -402.474148)
			(xy 377.834181 -402.4321) (xy 377.810585 -402.38579) (xy 377.794524 -402.33636) (xy 377.786394 -402.285025)
			(xy 377.785884 -402.259038) (xy 377.78636 -402.233255) (xy 377.794367 -402.182313) (xy 377.810192 -402.133235)
			(xy 377.833452 -402.087212) (xy 377.848114 -402.065998) (xy 377.853194 -402.058886) (xy 377.85802 -402.041868)
			(xy 377.852432 -401.959572) (xy 377.84532 -401.94357) (xy 377.839224 -401.936966) (xy 377.819745 -401.9156)
			(xy 377.786835 -401.868064) (xy 377.761483 -401.816102) (xy 377.74427 -401.760908) (xy 377.735592 -401.703747)
			(xy 377.735084 -401.674838) (xy 377.298204 -401.674838) (xy 377.297788 -401.701013) (xy 377.29059 -401.752865)
			(xy 377.276377 -401.803248) (xy 377.255414 -401.851218) (xy 377.228094 -401.895874) (xy 377.19493 -401.936379)
			(xy 377.17603 -401.954492) (xy 377.168664 -401.96135) (xy 377.160536 -401.978876) (xy 377.155202 -402.069046)
			(xy 377.161298 -402.087334) (xy 377.167902 -402.094954) (xy 377.182802 -402.112998) (xy 377.207867 -402.152516)
			(xy 377.227114 -402.19517) (xy 377.240161 -402.24011) (xy 377.246748 -402.28644) (xy 377.24715 -402.309838)
			(xy 377.24664 -402.335825) (xy 377.23851 -402.38716) (xy 377.222449 -402.43659) (xy 377.198853 -402.4829)
			(xy 377.168303 -402.524948) (xy 377.131552 -402.561699) (xy 377.089504 -402.592249) (xy 377.043194 -402.615845)
			(xy 376.993764 -402.631906) (xy 376.942429 -402.640036) (xy 376.890455 -402.640036) (xy 376.83912 -402.631906)
			(xy 376.78969 -402.615845) (xy 376.74338 -402.592249) (xy 376.701332 -402.561699) (xy 376.664581 -402.524948)
			(xy 376.634031 -402.4829) (xy 376.610435 -402.43659) (xy 376.594374 -402.38716) (xy 376.586244 -402.335825)
			(xy 376.585734 -402.309838) (xy 376.586163 -402.286442) (xy 376.592748 -402.240115) (xy 376.605794 -402.195178)
			(xy 376.62504 -402.152527) (xy 376.650101 -402.113012) (xy 376.664982 -402.094954) (xy 376.671586 -402.087334)
			(xy 376.677682 -402.069046) (xy 376.672348 -401.978876) (xy 376.66422 -401.96135) (xy 376.656854 -401.954492)
			(xy 376.637949 -401.936385) (xy 376.604788 -401.895879) (xy 376.577473 -401.851221) (xy 376.556518 -401.80325)
			(xy 376.542313 -401.752865) (xy 376.535128 -401.701012) (xy 376.53468 -401.674838) (xy 376.098308 -401.674838)
			(xy 376.09789 -401.701012) (xy 376.090693 -401.752865) (xy 376.07648 -401.803248) (xy 376.055517 -401.851217)
			(xy 376.028197 -401.895873) (xy 375.995034 -401.936378) (xy 375.976134 -401.954492) (xy 375.968768 -401.96135)
			(xy 375.96064 -401.978876) (xy 375.955306 -402.069046) (xy 375.961402 -402.087334) (xy 375.968006 -402.094954)
			(xy 375.982907 -402.112998) (xy 376.007971 -402.152515) (xy 376.027218 -402.19517) (xy 376.040266 -402.24011)
			(xy 376.046852 -402.28644) (xy 376.047254 -402.309838) (xy 376.046744 -402.335825) (xy 376.038614 -402.38716)
			(xy 376.022553 -402.43659) (xy 375.998957 -402.4829) (xy 375.968407 -402.524948) (xy 375.931656 -402.561699)
			(xy 375.889608 -402.592249) (xy 375.843298 -402.615845) (xy 375.793868 -402.631906) (xy 375.742533 -402.640036)
			(xy 375.690559 -402.640036) (xy 375.639224 -402.631906) (xy 375.589794 -402.615845) (xy 375.543484 -402.592249)
			(xy 375.501436 -402.561699) (xy 375.464685 -402.524948) (xy 375.434135 -402.4829) (xy 375.410539 -402.43659)
			(xy 375.394478 -402.38716) (xy 375.386348 -402.335825) (xy 375.385838 -402.309838) (xy 375.386266 -402.286442)
			(xy 375.392852 -402.240115) (xy 375.405897 -402.195178) (xy 375.425143 -402.152527) (xy 375.450205 -402.113012)
			(xy 375.465086 -402.094954) (xy 375.47169 -402.087334) (xy 375.477786 -402.069046) (xy 375.472452 -401.978876)
			(xy 375.464324 -401.96135) (xy 375.456958 -401.954492) (xy 375.438054 -401.936384) (xy 375.404893 -401.895878)
			(xy 375.377578 -401.851221) (xy 375.356622 -401.80325) (xy 375.342418 -401.752865) (xy 375.335232 -401.701012)
			(xy 375.334784 -401.674838) (xy 374.897904 -401.674838) (xy 374.897379 -401.703743) (xy 374.888673 -401.760894)
			(xy 374.87145 -401.816079) (xy 374.846105 -401.868037) (xy 374.813217 -401.91558) (xy 374.793764 -401.936966)
			(xy 374.787668 -401.94357) (xy 374.780556 -401.959572) (xy 374.774968 -402.041868) (xy 374.779794 -402.058886)
			(xy 374.784874 -402.065998) (xy 374.799513 -402.087226) (xy 374.822765 -402.133248) (xy 374.83859 -402.182321)
			(xy 374.846605 -402.233257) (xy 374.847104 -402.259038) (xy 374.846594 -402.285025) (xy 374.838464 -402.33636)
			(xy 374.822403 -402.38579) (xy 374.798807 -402.4321) (xy 374.768257 -402.474148) (xy 374.731506 -402.510899)
			(xy 374.689458 -402.541449) (xy 374.643148 -402.565045) (xy 374.593718 -402.581106) (xy 374.542383 -402.589236)
			(xy 374.490409 -402.589236) (xy 374.439074 -402.581106) (xy 374.389644 -402.565045) (xy 374.343334 -402.541449)
			(xy 374.301286 -402.510899) (xy 374.264535 -402.474148) (xy 374.233985 -402.4321) (xy 374.210389 -402.38579)
			(xy 374.194328 -402.33636) (xy 374.186198 -402.285025) (xy 374.185688 -402.259038) (xy 374.186163 -402.233255)
			(xy 374.19417 -402.182313) (xy 374.209996 -402.133235) (xy 374.233256 -402.087212) (xy 374.247918 -402.065998)
			(xy 374.252998 -402.058886) (xy 374.257824 -402.041868) (xy 374.252236 -401.959572) (xy 374.245124 -401.94357)
			(xy 374.239028 -401.936966) (xy 374.21955 -401.915599) (xy 374.18664 -401.868063) (xy 374.161287 -401.816102)
			(xy 374.144074 -401.760908) (xy 374.135396 -401.703747) (xy 374.134888 -401.674838) (xy 373.698008 -401.674838)
			(xy 373.697533 -401.701001) (xy 373.690383 -401.752835) (xy 373.676223 -401.803208) (xy 373.655318 -401.851176)
			(xy 373.628059 -401.89584) (xy 373.594958 -401.936364) (xy 373.576088 -401.954492) (xy 373.568722 -401.96135)
			(xy 373.560594 -401.978876) (xy 373.55526 -402.069046) (xy 373.561356 -402.087334) (xy 373.56796 -402.094954)
			(xy 373.582854 -402.113003) (xy 373.607921 -402.152519) (xy 373.62717 -402.195172) (xy 373.640219 -402.240111)
			(xy 373.646806 -402.28644) (xy 373.647208 -402.309838) (xy 373.646698 -402.335825) (xy 373.638568 -402.38716)
			(xy 373.622507 -402.43659) (xy 373.598911 -402.4829) (xy 373.568361 -402.524948) (xy 373.53161 -402.561699)
			(xy 373.489562 -402.592249) (xy 373.443252 -402.615845) (xy 373.393822 -402.631906) (xy 373.342487 -402.640036)
			(xy 373.290513 -402.640036) (xy 373.239178 -402.631906) (xy 373.189748 -402.615845) (xy 373.143438 -402.592249)
			(xy 373.10139 -402.561699) (xy 373.064639 -402.524948) (xy 373.034089 -402.4829) (xy 373.010493 -402.43659)
			(xy 372.994432 -402.38716) (xy 372.986302 -402.335825) (xy 372.985792 -402.309838) (xy 372.986231 -402.286442)
			(xy 372.992815 -402.240117) (xy 373.005859 -402.19518) (xy 373.025102 -402.152529) (xy 373.050161 -402.113013)
			(xy 373.06504 -402.094954) (xy 373.071644 -402.087334) (xy 373.07774 -402.069046) (xy 373.072406 -401.978876)
			(xy 373.064278 -401.96135) (xy 373.056912 -401.954492) (xy 373.03802 -401.936384) (xy 373.004902 -401.895864)
			(xy 372.977632 -401.851199) (xy 372.956721 -401.803226) (xy 372.942561 -401.752846) (xy 372.935419 -401.701004)
			(xy 372.934992 -401.674838) (xy 372.498112 -401.674838) (xy 372.497511 -401.704996) (xy 372.488016 -401.764561)
			(xy 372.469269 -401.821891) (xy 372.441736 -401.875557) (xy 372.406103 -401.924223) (xy 372.385082 -401.945856)
			(xy 372.378478 -401.95246) (xy 372.370858 -401.969224) (xy 372.365524 -402.05533) (xy 372.370858 -402.07311)
			(xy 372.3767 -402.080476) (xy 372.393212 -402.10246) (xy 372.419484 -402.150755) (xy 372.437415 -402.202728)
			(xy 372.44651 -402.256949) (xy 372.447058 -402.284438) (xy 372.446548 -402.310425) (xy 372.438418 -402.36176)
			(xy 372.422357 -402.41119) (xy 372.398761 -402.4575) (xy 372.368211 -402.499548) (xy 372.33146 -402.536299)
			(xy 372.289412 -402.566849) (xy 372.243102 -402.590445) (xy 372.193672 -402.606506) (xy 372.142337 -402.614636)
			(xy 372.090363 -402.614636) (xy 372.039028 -402.606506) (xy 371.989598 -402.590445) (xy 371.943288 -402.566849)
			(xy 371.90124 -402.536299) (xy 371.864489 -402.499548) (xy 371.833939 -402.4575) (xy 371.810343 -402.41119)
			(xy 371.794282 -402.36176) (xy 371.786152 -402.310425) (xy 371.785642 -402.284438) (xy 371.786207 -402.256948)
			(xy 371.795281 -402.202723) (xy 371.813203 -402.150747) (xy 371.839478 -402.102453) (xy 371.856 -402.080476)
			(xy 371.861842 -402.07311) (xy 371.867176 -402.05533) (xy 371.861842 -401.969224) (xy 371.854222 -401.95246)
			(xy 371.847618 -401.945856) (xy 371.826582 -401.924234) (xy 371.790934 -401.875572) (xy 371.763392 -401.821905)
			(xy 371.744644 -401.76457) (xy 371.735156 -401.704999) (xy 371.734588 -401.674838) (xy 371.298216 -401.674838)
			(xy 371.297649 -401.704999) (xy 371.288161 -401.764571) (xy 371.269412 -401.821905) (xy 371.241871 -401.875573)
			(xy 371.206223 -401.924235) (xy 371.185186 -401.945856) (xy 371.178582 -401.95246) (xy 371.170962 -401.969224)
			(xy 371.165628 -402.05533) (xy 371.170962 -402.07311) (xy 371.176804 -402.080476) (xy 371.193326 -402.102453)
			(xy 371.219601 -402.150747) (xy 371.237522 -402.202723) (xy 371.246596 -402.256948) (xy 371.247162 -402.284438)
			(xy 371.246652 -402.310425) (xy 371.238522 -402.36176) (xy 371.222461 -402.41119) (xy 371.198865 -402.4575)
			(xy 371.168315 -402.499548) (xy 371.131564 -402.536299) (xy 371.089516 -402.566849) (xy 371.043206 -402.590445)
			(xy 370.993776 -402.606506) (xy 370.942441 -402.614636) (xy 370.890467 -402.614636) (xy 370.839132 -402.606506)
			(xy 370.789702 -402.590445) (xy 370.743392 -402.566849) (xy 370.701344 -402.536299) (xy 370.664593 -402.499548)
			(xy 370.634043 -402.4575) (xy 370.610447 -402.41119) (xy 370.594386 -402.36176) (xy 370.586256 -402.310425)
			(xy 370.585746 -402.284438) (xy 370.586294 -402.256949) (xy 370.59539 -402.202728) (xy 370.61332 -402.150756)
			(xy 370.639592 -402.102461) (xy 370.656104 -402.080476) (xy 370.661946 -402.07311) (xy 370.66728 -402.05533)
			(xy 370.661946 -401.969224) (xy 370.654326 -401.95246) (xy 370.647722 -401.945856) (xy 370.626701 -401.924223)
			(xy 370.591068 -401.875557) (xy 370.563534 -401.821891) (xy 370.544786 -401.764561) (xy 370.535291 -401.704996)
			(xy 370.534692 -401.674838) (xy 370.534692 -401.44446) (xy 370.534197 -401.434458) (xy 370.52653 -401.415982)
			(xy 370.512378 -401.401843) (xy 370.493894 -401.394194) (xy 370.483892 -401.39366) (xy 368.778282 -401.39366)
			(xy 368.768214 -401.393232) (xy 368.749618 -401.385509) (xy 368.742214 -401.378674) (xy 368.075718 -400.712178)
			(xy 368.069341 -400.706306) (xy 368.053701 -400.698859) (xy 368.036473 -400.697046) (xy 368.027966 -400.698716)
			(xy 367.930684 -400.72183) (xy 367.91138 -400.73961) (xy 367.907316 -400.75231) (xy 367.899442 -400.7739)
			(xy 367.895753 -400.785088) (xy 367.897853 -400.808525) (xy 367.903506 -400.818858) (xy 367.92027 -400.846544)
			(xy 367.926922 -400.856332) (xy 367.94692 -400.868935) (xy 367.958624 -400.870674) (xy 367.986482 -400.873992)
			(xy 368.040868 -400.887753) (xy 368.092653 -400.90933) (xy 368.140721 -400.938256) (xy 368.184035 -400.973909)
			(xy 368.221662 -401.01552) (xy 368.25279 -401.062192) (xy 368.276749 -401.112919) (xy 368.293022 -401.166608)
			(xy 368.301259 -401.2221) (xy 368.301778 -401.25015) (xy 368.301292 -401.277401) (xy 368.293536 -401.331349)
			(xy 368.278181 -401.383644) (xy 368.255539 -401.433221) (xy 368.226073 -401.479071) (xy 368.190382 -401.520262)
			(xy 368.149191 -401.555953) (xy 368.103341 -401.585419) (xy 368.053764 -401.608061) (xy 368.001469 -401.623416)
			(xy 367.947521 -401.631172) (xy 367.893019 -401.631172) (xy 367.839071 -401.623416) (xy 367.786776 -401.608061)
			(xy 367.737199 -401.585419) (xy 367.691349 -401.555953) (xy 367.650158 -401.520262) (xy 367.614467 -401.479071)
			(xy 367.585001 -401.433221) (xy 367.562359 -401.383644) (xy 367.547004 -401.331349) (xy 367.539248 -401.277401)
			(xy 367.538762 -401.25015) (xy 367.539254 -401.221916) (xy 367.547547 -401.16606) (xy 367.555272 -401.138898)
			(xy 367.558574 -401.12823) (xy 367.556034 -401.107148) (xy 367.504726 -401.023328) (xy 367.4872 -401.01139)
			(xy 367.476278 -401.009358) (xy 367.450243 -401.004159) (xy 367.399831 -400.987511) (xy 367.352216 -400.964032)
			(xy 367.308316 -400.934176) (xy 367.268982 -400.89852) (xy 367.234973 -400.857754) (xy 367.206946 -400.812664)
			(xy 367.185443 -400.764124) (xy 367.17088 -400.713071) (xy 367.163539 -400.660491) (xy 367.163096 -400.633946)
			(xy 367.1636 -400.606691) (xy 367.171393 -400.552741) (xy 367.186783 -400.500448) (xy 367.209458 -400.450878)
			(xy 367.223802 -400.427698) (xy 367.227516 -400.421393) (xy 367.231526 -400.407327) (xy 367.231676 -400.400012)
			(xy 367.231676 -398.624806) (xy 367.231202 -398.614838) (xy 367.22363 -398.596398) (xy 367.216944 -398.588992)
			(xy 366.211866 -397.583914) (xy 366.197392 -397.568941) (xy 366.172164 -397.535806) (xy 366.161574 -397.517874)
			(xy 366.154716 -397.505936) (xy 366.131094 -397.49222) (xy 365.046006 -397.49222) (xy 365.017558 -397.517112)
			(xy 365.014764 -397.536162) (xy 365.010641 -397.563271) (xy 364.995628 -397.616009) (xy 364.973217 -397.666054)
			(xy 364.943869 -397.712372) (xy 364.90819 -397.75401) (xy 364.866915 -397.790108) (xy 364.820896 -397.819923)
			(xy 364.77108 -397.842839) (xy 364.718497 -397.858384) (xy 364.664229 -397.866237) (xy 364.609395 -397.866237)
			(xy 364.555127 -397.858384) (xy 364.502544 -397.842839) (xy 364.452728 -397.819923) (xy 364.406709 -397.790108)
			(xy 364.365434 -397.75401) (xy 364.329755 -397.712372) (xy 364.300407 -397.666054) (xy 364.277996 -397.616009)
			(xy 364.262983 -397.563271) (xy 364.25886 -397.536162) (xy 364.256066 -397.517112) (xy 364.227618 -397.49222)
			(xy 363.510322 -397.49222) (xy 363.499654 -397.49476) (xy 363.49432 -397.4973) (xy 363.468455 -397.509087)
			(xy 363.414108 -397.525728) (xy 363.357893 -397.534125) (xy 363.329474 -397.534638) (xy 363.311201 -397.534439)
			(xy 363.274818 -397.531002) (xy 363.25683 -397.52778) (xy 363.244384 -397.52524) (xy 363.220254 -397.532606)
			(xy 362.424726 -398.328134) (xy 362.417882 -398.335533) (xy 362.410156 -398.354131) (xy 362.40974 -398.364202)
			(xy 362.40974 -398.39519) (xy 362.410018 -398.403717) (xy 362.415555 -398.419843) (xy 362.426111 -398.433232)
			(xy 362.433108 -398.438116) (xy 362.459016 -398.454626) (xy 362.46963 -398.460682) (xy 362.493912 -398.463081)
			(xy 362.505498 -398.459198) (xy 362.535653 -398.447654) (xy 362.598145 -398.431402) (xy 362.662189 -398.423171)
			(xy 362.694474 -398.422622) (xy 362.725168 -398.423105) (xy 362.786105 -398.430534) (xy 362.845706 -398.445238)
			(xy 362.903106 -398.467005) (xy 362.957471 -398.495517) (xy 362.983018 -398.512538) (xy 362.99177 -398.518009)
			(xy 363.011974 -398.522137) (xy 363.032178 -398.518009) (xy 363.04093 -398.512538) (xy 363.066457 -398.495484)
			(xy 363.12082 -398.466958) (xy 363.178224 -398.44519) (xy 363.237833 -398.430499) (xy 363.298778 -398.423097)
			(xy 363.329474 -398.422622) (xy 363.360206 -398.423066) (xy 363.421224 -398.430472) (xy 363.480903 -398.44518)
			(xy 363.538374 -398.466974) (xy 363.592799 -398.495537) (xy 363.643384 -398.530453) (xy 363.689391 -398.571212)
			(xy 363.73015 -398.617219) (xy 363.765065 -398.667804) (xy 363.793628 -398.72223) (xy 363.815421 -398.779701)
			(xy 363.830128 -398.83938) (xy 363.837534 -398.900398) (xy 363.837982 -398.93113) (xy 363.837427 -398.965315)
			(xy 363.82827 -399.033069) (xy 363.810126 -399.098988) (xy 363.78332 -399.161885) (xy 363.748336 -399.220627)
			(xy 363.705803 -399.274156) (xy 363.656487 -399.321511) (xy 363.629194 -399.342102) (xy 363.61751 -399.350484)
			(xy 363.606842 -399.376138) (xy 363.623352 -399.493232) (xy 363.641132 -399.514822) (xy 363.654594 -399.519648)
			(xy 363.683721 -399.530666) (xy 363.739272 -399.558811) (xy 363.79097 -399.59353) (xy 363.838042 -399.634303)
			(xy 363.879781 -399.680519) (xy 363.915563 -399.731487) (xy 363.944853 -399.786444) (xy 363.967213 -399.844566)
			(xy 363.982306 -399.904984) (xy 363.989908 -399.966793) (xy 363.990382 -399.99793) (xy 363.989902 -400.028625)
			(xy 363.982478 -400.089564) (xy 363.967778 -400.149168) (xy 363.946015 -400.206571) (xy 363.917506 -400.260939)
			(xy 363.900466 -400.286474) (xy 363.895003 -400.295226) (xy 363.890888 -400.315425) (xy 363.895022 -400.33562)
			(xy 363.900466 -400.344386) (xy 363.917522 -400.369913) (xy 363.946053 -400.424275) (xy 363.967825 -400.481678)
			(xy 363.982522 -400.541287) (xy 363.989928 -400.602233) (xy 363.990382 -400.63293) (xy 363.989916 -400.663659)
			(xy 363.982505 -400.724669) (xy 363.967793 -400.784341) (xy 363.945996 -400.841805) (xy 363.917432 -400.896222)
			(xy 363.882517 -400.946799) (xy 363.84176 -400.992799) (xy 363.795755 -401.033551) (xy 363.745174 -401.068461)
			(xy 363.690753 -401.097019) (xy 363.633288 -401.11881) (xy 363.573614 -401.133515) (xy 363.512603 -401.14092)
			(xy 363.481874 -401.141438) (xy 363.460792 -401.14093) (xy 363.44987 -401.140422) (xy 363.430312 -401.148042)
			(xy 363.361986 -401.216368) (xy 363.354366 -401.235926) (xy 363.354874 -401.246848) (xy 363.355382 -401.26793)
			(xy 363.354902 -401.298625) (xy 363.347478 -401.359564) (xy 363.332778 -401.419168) (xy 363.311015 -401.476571)
			(xy 363.282506 -401.530939) (xy 363.265466 -401.556474) (xy 363.260003 -401.565226) (xy 363.255888 -401.585425)
			(xy 363.260022 -401.60562) (xy 363.265466 -401.614386) (xy 363.282522 -401.639913) (xy 363.311053 -401.694275)
			(xy 363.332825 -401.751678) (xy 363.347522 -401.811287) (xy 363.354928 -401.872233) (xy 363.355382 -401.90293)
			(xy 364.210346 -401.90293) (xy 364.210818 -401.87556) (xy 364.218633 -401.821381) (xy 364.23412 -401.768877)
			(xy 364.256961 -401.71913) (xy 364.286685 -401.673163) (xy 364.304326 -401.652232) (xy 364.310422 -401.64512)
			(xy 364.316772 -401.628102) (xy 364.316772 -401.542758) (xy 364.310422 -401.52574) (xy 364.304326 -401.518628)
			(xy 364.286715 -401.497671) (xy 364.256989 -401.451708) (xy 364.234142 -401.401965) (xy 364.218643 -401.349467)
			(xy 364.210812 -401.295292) (xy 364.210809 -401.240553) (xy 364.218634 -401.186377) (xy 364.234126 -401.133877)
			(xy 364.256967 -401.084132) (xy 364.286687 -401.038165) (xy 364.304326 -401.017232) (xy 364.310422 -401.01012)
			(xy 364.316772 -400.993102) (xy 364.316772 -400.907758) (xy 364.310422 -400.89074) (xy 364.304326 -400.883628)
			(xy 364.286715 -400.862671) (xy 364.256989 -400.816708) (xy 364.234142 -400.766965) (xy 364.218643 -400.714467)
			(xy 364.210812 -400.660292) (xy 364.210809 -400.605553) (xy 364.218634 -400.551377) (xy 364.234126 -400.498877)
			(xy 364.256967 -400.449132) (xy 364.286687 -400.403165) (xy 364.304326 -400.382232) (xy 364.310422 -400.37512)
			(xy 364.316772 -400.358102) (xy 364.316772 -400.272758) (xy 364.310422 -400.25574) (xy 364.304326 -400.248628)
			(xy 364.286691 -400.227693) (xy 364.256977 -400.181721) (xy 364.23414 -400.131975) (xy 364.218648 -400.079474)
			(xy 364.21082 -400.025299) (xy 364.210346 -399.99793) (xy 364.210834 -399.97046) (xy 364.218718 -399.916089)
			(xy 364.234312 -399.863409) (xy 364.257296 -399.813508) (xy 364.287193 -399.767415) (xy 364.323388 -399.726084)
			(xy 364.34395 -399.707862) (xy 364.35157 -399.701258) (xy 364.360714 -399.683478) (xy 364.367826 -399.591276)
			(xy 364.361476 -399.571972) (xy 364.354618 -399.564352) (xy 364.337232 -399.54344) (xy 364.307922 -399.497634)
			(xy 364.2854 -399.448135) (xy 364.270122 -399.395944) (xy 364.262396 -399.342115) (xy 364.261908 -399.314924)
			(xy 364.262386 -399.287554) (xy 364.270201 -399.233376) (xy 364.285687 -399.180872) (xy 364.308526 -399.131125)
			(xy 364.338248 -399.085158) (xy 364.355888 -399.064226) (xy 364.361984 -399.057114) (xy 364.368334 -399.040096)
			(xy 364.368334 -398.954752) (xy 364.361984 -398.937734) (xy 364.355888 -398.930622) (xy 364.338244 -398.909694)
			(xy 364.308533 -398.86372) (xy 364.285698 -398.813971) (xy 364.270209 -398.76147) (xy 364.262381 -398.707293)
			(xy 364.261908 -398.679924) (xy 364.262394 -398.652673) (xy 364.27015 -398.598725) (xy 364.285505 -398.54643)
			(xy 364.308147 -398.496853) (xy 364.337613 -398.451003) (xy 364.373304 -398.409812) (xy 364.414495 -398.374121)
			(xy 364.460345 -398.344655) (xy 364.509922 -398.322013) (xy 364.562217 -398.306658) (xy 364.616165 -398.298902)
			(xy 364.670667 -398.298902) (xy 364.724615 -398.306658) (xy 364.77691 -398.322013) (xy 364.826487 -398.344655)
			(xy 364.872337 -398.374121) (xy 364.913528 -398.409812) (xy 364.949219 -398.451003) (xy 364.978685 -398.496853)
			(xy 365.001327 -398.54643) (xy 365.016682 -398.598725) (xy 365.024438 -398.652673) (xy 365.024924 -398.679924)
			(xy 365.024491 -398.707296) (xy 365.016668 -398.761477) (xy 365.001172 -398.813981) (xy 364.978323 -398.863727)
			(xy 364.94859 -398.909692) (xy 364.930944 -398.930622) (xy 364.924848 -398.937734) (xy 364.918498 -398.954752)
			(xy 364.918498 -399.040096) (xy 364.924848 -399.057114) (xy 364.930944 -399.064226) (xy 364.948569 -399.085169)
			(xy 364.978282 -399.13114) (xy 365.00112 -399.180884) (xy 365.016614 -399.233382) (xy 365.024447 -399.287556)
			(xy 365.024924 -399.314924) (xy 365.024342 -399.344534) (xy 365.015182 -399.403042) (xy 364.9971 -399.459435)
			(xy 364.97053 -399.512361) (xy 364.936108 -399.560551) (xy 364.894661 -399.60285) (xy 364.871254 -399.620994)
			(xy 364.862807 -399.627905) (xy 364.852273 -399.646993) (xy 364.850934 -399.657824) (xy 364.84687 -399.713958)
			(xy 364.858046 -399.724626) (xy 364.865368 -399.731177) (xy 364.883538 -399.738612) (xy 364.893352 -399.739104)
			(xy 364.925356 -399.739104) (xy 364.935172 -399.738636) (xy 364.953336 -399.731178) (xy 364.960662 -399.724626)
			(xy 364.982174 -399.704467) (xy 365.030231 -399.670321) (xy 365.082967 -399.643972) (xy 365.139128 -399.626048)
			(xy 365.197378 -399.616974) (xy 365.226854 -399.616422) (xy 365.254224 -399.61691) (xy 365.308402 -399.624721)
			(xy 365.360905 -399.640205) (xy 365.410652 -399.663042) (xy 365.45662 -399.692763) (xy 365.477552 -399.710402)
			(xy 365.484664 -399.716498) (xy 365.501682 -399.722848) (xy 365.587026 -399.722848) (xy 365.604044 -399.716498)
			(xy 365.611156 -399.710402) (xy 365.632089 -399.692761) (xy 365.678057 -399.663037) (xy 365.727803 -399.640191)
			(xy 365.780305 -399.624695) (xy 365.834483 -399.616866) (xy 365.889225 -399.616866) (xy 365.943403 -399.624695)
			(xy 365.995905 -399.640191) (xy 366.045651 -399.663037) (xy 366.091619 -399.692761) (xy 366.112552 -399.710402)
			(xy 366.119664 -399.716498) (xy 366.136682 -399.722848) (xy 366.222026 -399.722848) (xy 366.239044 -399.716498)
			(xy 366.246156 -399.710402) (xy 366.267094 -399.69277) (xy 366.313065 -399.663057) (xy 366.362811 -399.64022)
			(xy 366.415311 -399.624727) (xy 366.469485 -399.616897) (xy 366.496854 -399.616422) (xy 366.524107 -399.616898)
			(xy 366.578059 -399.62465) (xy 366.630359 -399.640001) (xy 366.679941 -399.662641) (xy 366.725795 -399.692107)
			(xy 366.766989 -399.727799) (xy 366.802684 -399.768992) (xy 366.832152 -399.814845) (xy 366.854793 -399.864426)
			(xy 366.870147 -399.916725) (xy 366.877901 -399.970677) (xy 366.878362 -399.99793) (xy 366.877923 -400.025301)
			(xy 366.8701 -400.079482) (xy 366.854605 -400.131986) (xy 366.831757 -400.181732) (xy 366.802026 -400.227697)
			(xy 366.784382 -400.248628) (xy 366.778286 -400.25574) (xy 366.771936 -400.272758) (xy 366.771936 -400.358102)
			(xy 366.778286 -400.37512) (xy 366.784382 -400.382232) (xy 366.802052 -400.403141) (xy 366.831775 -400.449113)
			(xy 366.854618 -400.498863) (xy 366.870111 -400.551369) (xy 366.877937 -400.605551) (xy 366.877934 -400.660294)
			(xy 366.870102 -400.714475) (xy 366.854602 -400.766979) (xy 366.831753 -400.816726) (xy 366.802024 -400.862695)
			(xy 366.784382 -400.883628) (xy 366.778286 -400.89074) (xy 366.771936 -400.907758) (xy 366.771936 -400.993102)
			(xy 366.778286 -401.01012) (xy 366.784382 -401.017232) (xy 366.802052 -401.038141) (xy 366.831775 -401.084113)
			(xy 366.854618 -401.133863) (xy 366.870111 -401.186369) (xy 366.877937 -401.240551) (xy 366.877934 -401.295294)
			(xy 366.870102 -401.349475) (xy 366.854602 -401.401979) (xy 366.831753 -401.451726) (xy 366.802024 -401.497695)
			(xy 366.784382 -401.518628) (xy 366.778286 -401.52574) (xy 366.771936 -401.542758) (xy 366.771936 -401.628102)
			(xy 366.778286 -401.64512) (xy 366.784382 -401.652232) (xy 366.802 -401.673181) (xy 366.831716 -401.719149)
			(xy 366.854556 -401.768892) (xy 366.870052 -401.821389) (xy 366.877885 -401.875562) (xy 366.878362 -401.90293)
			(xy 366.877973 -401.930186) (xy 366.870211 -401.984142) (xy 366.854848 -402.036444) (xy 366.832199 -402.086027)
			(xy 366.802724 -402.131882) (xy 366.767022 -402.173076) (xy 366.725822 -402.208769) (xy 366.67996 -402.238236)
			(xy 366.630373 -402.260875) (xy 366.578067 -402.276227) (xy 366.52411 -402.283978) (xy 366.496854 -402.284438)
			(xy 366.469484 -402.283955) (xy 366.415305 -402.276144) (xy 366.362802 -402.26066) (xy 366.313054 -402.237821)
			(xy 366.267088 -402.208099) (xy 366.246156 -402.190458) (xy 366.239044 -402.184362) (xy 366.222026 -402.178012)
			(xy 366.136682 -402.178012) (xy 366.119664 -402.184362) (xy 366.112552 -402.190458) (xy 366.091619 -402.208099)
			(xy 366.045651 -402.237823) (xy 365.995905 -402.260669) (xy 365.943403 -402.276165) (xy 365.889225 -402.283994)
			(xy 365.834483 -402.283994) (xy 365.780305 -402.276165) (xy 365.727803 -402.260669) (xy 365.678057 -402.237823)
			(xy 365.632089 -402.208099) (xy 365.611156 -402.190458) (xy 365.604044 -402.184362) (xy 365.587026 -402.178012)
			(xy 365.501682 -402.178012) (xy 365.484664 -402.184362) (xy 365.477552 -402.190458) (xy 365.456619 -402.208099)
			(xy 365.410651 -402.237823) (xy 365.360905 -402.260669) (xy 365.308403 -402.276165) (xy 365.254225 -402.283994)
			(xy 365.199483 -402.283994) (xy 365.145305 -402.276165) (xy 365.092803 -402.260669) (xy 365.043057 -402.237823)
			(xy 364.997089 -402.208099) (xy 364.976156 -402.190458) (xy 364.969044 -402.184362) (xy 364.952026 -402.178012)
			(xy 364.866682 -402.178012) (xy 364.849664 -402.184362) (xy 364.842552 -402.190458) (xy 364.821606 -402.20808)
			(xy 364.775638 -402.237796) (xy 364.725894 -402.260636) (xy 364.673396 -402.276131) (xy 364.619222 -402.283962)
			(xy 364.591854 -402.284438) (xy 364.564603 -402.283965) (xy 364.510656 -402.276203) (xy 364.458363 -402.260844)
			(xy 364.408788 -402.238199) (xy 364.362939 -402.208731) (xy 364.32175 -402.173038) (xy 364.286059 -402.131848)
			(xy 364.256593 -402.085998) (xy 364.233951 -402.036422) (xy 364.218594 -401.984128) (xy 364.210834 -401.930181)
			(xy 364.210346 -401.90293) (xy 363.355382 -401.90293) (xy 363.354916 -401.933659) (xy 363.347505 -401.994669)
			(xy 363.332793 -402.054341) (xy 363.310996 -402.111805) (xy 363.282432 -402.166222) (xy 363.247517 -402.216799)
			(xy 363.20676 -402.262799) (xy 363.160755 -402.303551) (xy 363.110174 -402.338461) (xy 363.055753 -402.367019)
			(xy 362.998288 -402.38881) (xy 362.938614 -402.403515) (xy 362.877603 -402.41092) (xy 362.846874 -402.411438)
			(xy 362.816179 -402.410958) (xy 362.75524 -402.403534) (xy 362.695637 -402.388833) (xy 362.638234 -402.36707)
			(xy 362.583867 -402.338559) (xy 362.55833 -402.321522) (xy 362.549578 -402.316051) (xy 362.529374 -402.311923)
			(xy 362.50917 -402.316051) (xy 362.500418 -402.321522) (xy 362.485387 -402.331697) (xy 362.454117 -402.350132)
			(xy 362.437934 -402.358352) (xy 362.429694 -402.362934) (xy 362.416995 -402.376845) (xy 362.41017 -402.394401)
			(xy 362.40974 -402.403818) (xy 362.40974 -402.675598) (xy 362.410164 -402.685667) (xy 362.417882 -402.704269)
			(xy 362.424726 -402.711666) (xy 362.736384 -403.023324) (xy 362.743794 -403.030008) (xy 362.76223 -403.037592)
			(xy 362.772198 -403.038056)
		)
		(stroke
			(width 0)
			(type solid)
		)
		(fill yes)
		(layer "In2.Cu")
		(net "P0V9_CPU0_RT3_2A_2D")
	)
	(gr_poly
		(pts
			(xy 143.896842 -394.504164) (xy 143.906841 -394.503668) (xy 143.925313 -394.496) (xy 143.939444 -394.481847)
			(xy 143.947084 -394.463364) (xy 143.947642 -394.453364) (xy 143.947642 -392.631676) (xy 143.931386 -392.606784)
			(xy 143.917416 -392.600688) (xy 143.892484 -392.58907) (xy 143.845959 -392.559729) (xy 143.804126 -392.524015)
			(xy 143.767852 -392.482667) (xy 143.737887 -392.436542) (xy 143.714853 -392.386593) (xy 143.699225 -392.333855)
			(xy 143.691329 -392.279421) (xy 143.691326 -392.224417) (xy 143.699217 -392.169981) (xy 143.71484 -392.117242)
			(xy 143.737869 -392.067291) (xy 143.767829 -392.021162) (xy 143.804099 -391.979811) (xy 143.845928 -391.944093)
			(xy 143.892451 -391.914748) (xy 143.917416 -391.903204) (xy 143.931386 -391.897108) (xy 143.947642 -391.872216)
			(xy 143.947642 -391.206482) (xy 143.94807 -391.196414) (xy 143.955793 -391.177819) (xy 143.962628 -391.170414)
			(xy 144.394682 -390.73836) (xy 144.401794 -390.713214) (xy 144.398746 -390.700514) (xy 144.39481 -390.682161)
			(xy 144.390611 -390.64486) (xy 144.390364 -390.626092) (xy 144.390758 -390.602858) (xy 144.397261 -390.556848)
			(xy 144.410139 -390.5122) (xy 144.429137 -390.469794) (xy 144.453883 -390.430463) (xy 144.468596 -390.412478)
			(xy 144.474692 -390.405366) (xy 144.480788 -390.388856) (xy 144.480788 -390.304528) (xy 144.474692 -390.288018)
			(xy 144.468596 -390.280906) (xy 144.453887 -390.262916) (xy 144.42913 -390.22359) (xy 144.410122 -390.181186)
			(xy 144.397239 -390.136538) (xy 144.390734 -390.090527) (xy 144.390364 -390.067292) (xy 144.390874 -390.041305)
			(xy 144.399004 -389.98997) (xy 144.415065 -389.94054) (xy 144.438661 -389.89423) (xy 144.469211 -389.852182)
			(xy 144.505962 -389.815431) (xy 144.54801 -389.784881) (xy 144.59432 -389.761285) (xy 144.64375 -389.745224)
			(xy 144.695085 -389.737094) (xy 144.747059 -389.737094) (xy 144.798394 -389.745224) (xy 144.847824 -389.761285)
			(xy 144.894134 -389.784881) (xy 144.936182 -389.815431) (xy 144.972933 -389.852182) (xy 145.003483 -389.89423)
			(xy 145.027079 -389.94054) (xy 145.04314 -389.98997) (xy 145.05127 -390.041305) (xy 145.05178 -390.067292)
			(xy 145.051387 -390.090526) (xy 145.044885 -390.136536) (xy 145.038117 -390.160002) (xy 146.712952 -390.160002)
			(xy 146.716912 -390.110948) (xy 146.728689 -390.063164) (xy 146.74798 -390.017888) (xy 146.774283 -389.976292)
			(xy 146.806918 -389.939455) (xy 146.845039 -389.90833) (xy 146.88766 -389.883723) (xy 146.933676 -389.866271)
			(xy 146.981895 -389.856427) (xy 147.03107 -389.854446) (xy 147.079925 -389.860378) (xy 147.127196 -389.87407)
			(xy 147.171658 -389.895168) (xy 147.212161 -389.923124) (xy 147.247654 -389.957216) (xy 147.277219 -389.99656)
			(xy 147.30009 -390.040137) (xy 147.315674 -390.086818) (xy 147.323569 -390.135395) (xy 147.324064 -390.160002)
			(xy 147.913102 -390.160002) (xy 147.917062 -390.110948) (xy 147.928839 -390.063164) (xy 147.94813 -390.017888)
			(xy 147.974433 -389.976292) (xy 148.007068 -389.939455) (xy 148.045189 -389.90833) (xy 148.08781 -389.883723)
			(xy 148.133826 -389.866271) (xy 148.182045 -389.856427) (xy 148.23122 -389.854446) (xy 148.280075 -389.860378)
			(xy 148.327346 -389.87407) (xy 148.371808 -389.895168) (xy 148.412311 -389.923124) (xy 148.447804 -389.957216)
			(xy 148.477369 -389.99656) (xy 148.50024 -390.040137) (xy 148.515824 -390.086818) (xy 148.523719 -390.135395)
			(xy 148.524214 -390.160002) (xy 149.113252 -390.160002) (xy 149.117212 -390.110948) (xy 149.128989 -390.063164)
			(xy 149.14828 -390.017888) (xy 149.174583 -389.976292) (xy 149.207218 -389.939455) (xy 149.245339 -389.90833)
			(xy 149.28796 -389.883723) (xy 149.333976 -389.866271) (xy 149.382195 -389.856427) (xy 149.43137 -389.854446)
			(xy 149.480225 -389.860378) (xy 149.527496 -389.87407) (xy 149.571958 -389.895168) (xy 149.612461 -389.923124)
			(xy 149.647954 -389.957216) (xy 149.677519 -389.99656) (xy 149.70039 -390.040137) (xy 149.715974 -390.086818)
			(xy 149.723869 -390.135395) (xy 149.724364 -390.160002) (xy 150.313148 -390.160002) (xy 150.317108 -390.110948)
			(xy 150.328885 -390.063164) (xy 150.348176 -390.017888) (xy 150.374479 -389.976292) (xy 150.407114 -389.939455)
			(xy 150.445235 -389.90833) (xy 150.487856 -389.883723) (xy 150.533872 -389.866271) (xy 150.582091 -389.856427)
			(xy 150.631266 -389.854446) (xy 150.680121 -389.860378) (xy 150.727392 -389.87407) (xy 150.771854 -389.895168)
			(xy 150.812357 -389.923124) (xy 150.84785 -389.957216) (xy 150.877415 -389.99656) (xy 150.900286 -390.040137)
			(xy 150.91587 -390.086818) (xy 150.923765 -390.135395) (xy 150.92426 -390.160002) (xy 151.513298 -390.160002)
			(xy 151.517258 -390.110948) (xy 151.529035 -390.063164) (xy 151.548326 -390.017888) (xy 151.574629 -389.976292)
			(xy 151.607264 -389.939455) (xy 151.645385 -389.90833) (xy 151.688006 -389.883723) (xy 151.734022 -389.866271)
			(xy 151.782241 -389.856427) (xy 151.831416 -389.854446) (xy 151.880271 -389.860378) (xy 151.927542 -389.87407)
			(xy 151.972004 -389.895168) (xy 152.012507 -389.923124) (xy 152.048 -389.957216) (xy 152.077565 -389.99656)
			(xy 152.100436 -390.040137) (xy 152.11602 -390.086818) (xy 152.123915 -390.135395) (xy 152.12441 -390.160002)
			(xy 152.713194 -390.160002) (xy 152.717154 -390.110948) (xy 152.728931 -390.063164) (xy 152.748222 -390.017888)
			(xy 152.774525 -389.976292) (xy 152.80716 -389.939455) (xy 152.845281 -389.90833) (xy 152.887902 -389.883723)
			(xy 152.933918 -389.866271) (xy 152.982137 -389.856427) (xy 153.031312 -389.854446) (xy 153.080167 -389.860378)
			(xy 153.127438 -389.87407) (xy 153.1719 -389.895168) (xy 153.212403 -389.923124) (xy 153.247896 -389.957216)
			(xy 153.277461 -389.99656) (xy 153.300332 -390.040137) (xy 153.315916 -390.086818) (xy 153.323811 -390.135395)
			(xy 153.324306 -390.160002) (xy 153.91309 -390.160002) (xy 153.91705 -390.110948) (xy 153.928827 -390.063164)
			(xy 153.948118 -390.017888) (xy 153.974421 -389.976292) (xy 154.007056 -389.939455) (xy 154.045177 -389.90833)
			(xy 154.087798 -389.883723) (xy 154.133814 -389.866271) (xy 154.182033 -389.856427) (xy 154.231208 -389.854446)
			(xy 154.280063 -389.860378) (xy 154.327334 -389.87407) (xy 154.371796 -389.895168) (xy 154.412299 -389.923124)
			(xy 154.447792 -389.957216) (xy 154.477357 -389.99656) (xy 154.500228 -390.040137) (xy 154.515812 -390.086818)
			(xy 154.523707 -390.135395) (xy 154.524202 -390.160002) (xy 155.11324 -390.160002) (xy 155.1172 -390.110948)
			(xy 155.128977 -390.063164) (xy 155.148268 -390.017888) (xy 155.174571 -389.976292) (xy 155.207206 -389.939455)
			(xy 155.245327 -389.90833) (xy 155.287948 -389.883723) (xy 155.333964 -389.866271) (xy 155.382183 -389.856427)
			(xy 155.431358 -389.854446) (xy 155.480213 -389.860378) (xy 155.527484 -389.87407) (xy 155.571946 -389.895168)
			(xy 155.612449 -389.923124) (xy 155.647942 -389.957216) (xy 155.677507 -389.99656) (xy 155.700378 -390.040137)
			(xy 155.715962 -390.086818) (xy 155.723857 -390.135395) (xy 155.724352 -390.160002) (xy 156.313136 -390.160002)
			(xy 156.317096 -390.110948) (xy 156.328873 -390.063164) (xy 156.348164 -390.017888) (xy 156.374467 -389.976292)
			(xy 156.407102 -389.939455) (xy 156.445223 -389.90833) (xy 156.487844 -389.883723) (xy 156.53386 -389.866271)
			(xy 156.582079 -389.856427) (xy 156.631254 -389.854446) (xy 156.680109 -389.860378) (xy 156.72738 -389.87407)
			(xy 156.771842 -389.895168) (xy 156.812345 -389.923124) (xy 156.847838 -389.957216) (xy 156.877403 -389.99656)
			(xy 156.900274 -390.040137) (xy 156.915858 -390.086818) (xy 156.923753 -390.135395) (xy 156.924248 -390.160002)
			(xy 157.513286 -390.160002) (xy 157.517246 -390.110948) (xy 157.529023 -390.063164) (xy 157.548314 -390.017888)
			(xy 157.574617 -389.976292) (xy 157.607252 -389.939455) (xy 157.645373 -389.90833) (xy 157.687994 -389.883723)
			(xy 157.73401 -389.866271) (xy 157.782229 -389.856427) (xy 157.831404 -389.854446) (xy 157.880259 -389.860378)
			(xy 157.92753 -389.87407) (xy 157.971992 -389.895168) (xy 158.012495 -389.923124) (xy 158.047988 -389.957216)
			(xy 158.077553 -389.99656) (xy 158.100424 -390.040137) (xy 158.116008 -390.086818) (xy 158.123903 -390.135395)
			(xy 158.124398 -390.160002) (xy 158.713182 -390.160002) (xy 158.717142 -390.110948) (xy 158.728919 -390.063164)
			(xy 158.74821 -390.017888) (xy 158.774513 -389.976292) (xy 158.807148 -389.939455) (xy 158.845269 -389.90833)
			(xy 158.88789 -389.883723) (xy 158.933906 -389.866271) (xy 158.982125 -389.856427) (xy 159.0313 -389.854446)
			(xy 159.080155 -389.860378) (xy 159.127426 -389.87407) (xy 159.171888 -389.895168) (xy 159.212391 -389.923124)
			(xy 159.247884 -389.957216) (xy 159.277449 -389.99656) (xy 159.30032 -390.040137) (xy 159.315904 -390.086818)
			(xy 159.323799 -390.135395) (xy 159.324294 -390.160002) (xy 159.913078 -390.160002) (xy 159.917038 -390.110948)
			(xy 159.928815 -390.063164) (xy 159.948106 -390.017888) (xy 159.974409 -389.976292) (xy 160.007044 -389.939455)
			(xy 160.045165 -389.90833) (xy 160.087786 -389.883723) (xy 160.133802 -389.866271) (xy 160.182021 -389.856427)
			(xy 160.231196 -389.854446) (xy 160.280051 -389.860378) (xy 160.327322 -389.87407) (xy 160.371784 -389.895168)
			(xy 160.412287 -389.923124) (xy 160.44778 -389.957216) (xy 160.477345 -389.99656) (xy 160.500216 -390.040137)
			(xy 160.5158 -390.086818) (xy 160.523695 -390.135395) (xy 160.52419 -390.160002) (xy 161.113228 -390.160002)
			(xy 161.117188 -390.110948) (xy 161.128965 -390.063164) (xy 161.148256 -390.017888) (xy 161.174559 -389.976292)
			(xy 161.207194 -389.939455) (xy 161.245315 -389.90833) (xy 161.287936 -389.883723) (xy 161.333952 -389.866271)
			(xy 161.382171 -389.856427) (xy 161.431346 -389.854446) (xy 161.480201 -389.860378) (xy 161.527472 -389.87407)
			(xy 161.571934 -389.895168) (xy 161.612437 -389.923124) (xy 161.64793 -389.957216) (xy 161.677495 -389.99656)
			(xy 161.700366 -390.040137) (xy 161.71595 -390.086818) (xy 161.723845 -390.135395) (xy 161.72434 -390.160002)
			(xy 162.313124 -390.160002) (xy 162.317084 -390.110948) (xy 162.328861 -390.063164) (xy 162.348152 -390.017888)
			(xy 162.374455 -389.976292) (xy 162.40709 -389.939455) (xy 162.445211 -389.90833) (xy 162.487832 -389.883723)
			(xy 162.533848 -389.866271) (xy 162.582067 -389.856427) (xy 162.631242 -389.854446) (xy 162.680097 -389.860378)
			(xy 162.727368 -389.87407) (xy 162.77183 -389.895168) (xy 162.812333 -389.923124) (xy 162.847826 -389.957216)
			(xy 162.877391 -389.99656) (xy 162.900262 -390.040137) (xy 162.915846 -390.086818) (xy 162.923741 -390.135395)
			(xy 162.924236 -390.160002) (xy 162.923741 -390.184609) (xy 162.915846 -390.233186) (xy 162.900262 -390.279867)
			(xy 162.877391 -390.323444) (xy 162.847826 -390.362788) (xy 162.812333 -390.39688) (xy 162.77183 -390.424836)
			(xy 162.727368 -390.445934) (xy 162.680097 -390.459626) (xy 162.631242 -390.465558) (xy 162.582067 -390.463577)
			(xy 162.533848 -390.453733) (xy 162.487832 -390.436281) (xy 162.445211 -390.411674) (xy 162.40709 -390.380549)
			(xy 162.374455 -390.343712) (xy 162.348152 -390.302116) (xy 162.328861 -390.25684) (xy 162.317084 -390.209056)
			(xy 162.313124 -390.160002) (xy 161.72434 -390.160002) (xy 161.723845 -390.184609) (xy 161.71595 -390.233186)
			(xy 161.700366 -390.279867) (xy 161.677495 -390.323444) (xy 161.64793 -390.362788) (xy 161.612437 -390.39688)
			(xy 161.571934 -390.424836) (xy 161.527472 -390.445934) (xy 161.480201 -390.459626) (xy 161.431346 -390.465558)
			(xy 161.382171 -390.463577) (xy 161.333952 -390.453733) (xy 161.287936 -390.436281) (xy 161.245315 -390.411674)
			(xy 161.207194 -390.380549) (xy 161.174559 -390.343712) (xy 161.148256 -390.302116) (xy 161.128965 -390.25684)
			(xy 161.117188 -390.209056) (xy 161.113228 -390.160002) (xy 160.52419 -390.160002) (xy 160.523695 -390.184609)
			(xy 160.5158 -390.233186) (xy 160.500216 -390.279867) (xy 160.477345 -390.323444) (xy 160.44778 -390.362788)
			(xy 160.412287 -390.39688) (xy 160.371784 -390.424836) (xy 160.327322 -390.445934) (xy 160.280051 -390.459626)
			(xy 160.231196 -390.465558) (xy 160.182021 -390.463577) (xy 160.133802 -390.453733) (xy 160.087786 -390.436281)
			(xy 160.045165 -390.411674) (xy 160.007044 -390.380549) (xy 159.974409 -390.343712) (xy 159.948106 -390.302116)
			(xy 159.928815 -390.25684) (xy 159.917038 -390.209056) (xy 159.913078 -390.160002) (xy 159.324294 -390.160002)
			(xy 159.323799 -390.184609) (xy 159.315904 -390.233186) (xy 159.30032 -390.279867) (xy 159.277449 -390.323444)
			(xy 159.247884 -390.362788) (xy 159.212391 -390.39688) (xy 159.171888 -390.424836) (xy 159.127426 -390.445934)
			(xy 159.080155 -390.459626) (xy 159.0313 -390.465558) (xy 158.982125 -390.463577) (xy 158.933906 -390.453733)
			(xy 158.88789 -390.436281) (xy 158.845269 -390.411674) (xy 158.807148 -390.380549) (xy 158.774513 -390.343712)
			(xy 158.74821 -390.302116) (xy 158.728919 -390.25684) (xy 158.717142 -390.209056) (xy 158.713182 -390.160002)
			(xy 158.124398 -390.160002) (xy 158.123903 -390.184609) (xy 158.116008 -390.233186) (xy 158.100424 -390.279867)
			(xy 158.077553 -390.323444) (xy 158.047988 -390.362788) (xy 158.012495 -390.39688) (xy 157.971992 -390.424836)
			(xy 157.92753 -390.445934) (xy 157.880259 -390.459626) (xy 157.831404 -390.465558) (xy 157.782229 -390.463577)
			(xy 157.73401 -390.453733) (xy 157.687994 -390.436281) (xy 157.645373 -390.411674) (xy 157.607252 -390.380549)
			(xy 157.574617 -390.343712) (xy 157.548314 -390.302116) (xy 157.529023 -390.25684) (xy 157.517246 -390.209056)
			(xy 157.513286 -390.160002) (xy 156.924248 -390.160002) (xy 156.923753 -390.184609) (xy 156.915858 -390.233186)
			(xy 156.900274 -390.279867) (xy 156.877403 -390.323444) (xy 156.847838 -390.362788) (xy 156.812345 -390.39688)
			(xy 156.771842 -390.424836) (xy 156.72738 -390.445934) (xy 156.680109 -390.459626) (xy 156.631254 -390.465558)
			(xy 156.582079 -390.463577) (xy 156.53386 -390.453733) (xy 156.487844 -390.436281) (xy 156.445223 -390.411674)
			(xy 156.407102 -390.380549) (xy 156.374467 -390.343712) (xy 156.348164 -390.302116) (xy 156.328873 -390.25684)
			(xy 156.317096 -390.209056) (xy 156.313136 -390.160002) (xy 155.724352 -390.160002) (xy 155.723857 -390.184609)
			(xy 155.715962 -390.233186) (xy 155.700378 -390.279867) (xy 155.677507 -390.323444) (xy 155.647942 -390.362788)
			(xy 155.612449 -390.39688) (xy 155.571946 -390.424836) (xy 155.527484 -390.445934) (xy 155.480213 -390.459626)
			(xy 155.431358 -390.465558) (xy 155.382183 -390.463577) (xy 155.333964 -390.453733) (xy 155.287948 -390.436281)
			(xy 155.245327 -390.411674) (xy 155.207206 -390.380549) (xy 155.174571 -390.343712) (xy 155.148268 -390.302116)
			(xy 155.128977 -390.25684) (xy 155.1172 -390.209056) (xy 155.11324 -390.160002) (xy 154.524202 -390.160002)
			(xy 154.523707 -390.184609) (xy 154.515812 -390.233186) (xy 154.500228 -390.279867) (xy 154.477357 -390.323444)
			(xy 154.447792 -390.362788) (xy 154.412299 -390.39688) (xy 154.371796 -390.424836) (xy 154.327334 -390.445934)
			(xy 154.280063 -390.459626) (xy 154.231208 -390.465558) (xy 154.182033 -390.463577) (xy 154.133814 -390.453733)
			(xy 154.087798 -390.436281) (xy 154.045177 -390.411674) (xy 154.007056 -390.380549) (xy 153.974421 -390.343712)
			(xy 153.948118 -390.302116) (xy 153.928827 -390.25684) (xy 153.91705 -390.209056) (xy 153.91309 -390.160002)
			(xy 153.324306 -390.160002) (xy 153.323811 -390.184609) (xy 153.315916 -390.233186) (xy 153.300332 -390.279867)
			(xy 153.277461 -390.323444) (xy 153.247896 -390.362788) (xy 153.212403 -390.39688) (xy 153.1719 -390.424836)
			(xy 153.127438 -390.445934) (xy 153.080167 -390.459626) (xy 153.031312 -390.465558) (xy 152.982137 -390.463577)
			(xy 152.933918 -390.453733) (xy 152.887902 -390.436281) (xy 152.845281 -390.411674) (xy 152.80716 -390.380549)
			(xy 152.774525 -390.343712) (xy 152.748222 -390.302116) (xy 152.728931 -390.25684) (xy 152.717154 -390.209056)
			(xy 152.713194 -390.160002) (xy 152.12441 -390.160002) (xy 152.123915 -390.184609) (xy 152.11602 -390.233186)
			(xy 152.100436 -390.279867) (xy 152.077565 -390.323444) (xy 152.048 -390.362788) (xy 152.012507 -390.39688)
			(xy 151.972004 -390.424836) (xy 151.927542 -390.445934) (xy 151.880271 -390.459626) (xy 151.831416 -390.465558)
			(xy 151.782241 -390.463577) (xy 151.734022 -390.453733) (xy 151.688006 -390.436281) (xy 151.645385 -390.411674)
			(xy 151.607264 -390.380549) (xy 151.574629 -390.343712) (xy 151.548326 -390.302116) (xy 151.529035 -390.25684)
			(xy 151.517258 -390.209056) (xy 151.513298 -390.160002) (xy 150.92426 -390.160002) (xy 150.923765 -390.184609)
			(xy 150.91587 -390.233186) (xy 150.900286 -390.279867) (xy 150.877415 -390.323444) (xy 150.84785 -390.362788)
			(xy 150.812357 -390.39688) (xy 150.771854 -390.424836) (xy 150.727392 -390.445934) (xy 150.680121 -390.459626)
			(xy 150.631266 -390.465558) (xy 150.582091 -390.463577) (xy 150.533872 -390.453733) (xy 150.487856 -390.436281)
			(xy 150.445235 -390.411674) (xy 150.407114 -390.380549) (xy 150.374479 -390.343712) (xy 150.348176 -390.302116)
			(xy 150.328885 -390.25684) (xy 150.317108 -390.209056) (xy 150.313148 -390.160002) (xy 149.724364 -390.160002)
			(xy 149.723869 -390.184609) (xy 149.715974 -390.233186) (xy 149.70039 -390.279867) (xy 149.677519 -390.323444)
			(xy 149.647954 -390.362788) (xy 149.612461 -390.39688) (xy 149.571958 -390.424836) (xy 149.527496 -390.445934)
			(xy 149.480225 -390.459626) (xy 149.43137 -390.465558) (xy 149.382195 -390.463577) (xy 149.333976 -390.453733)
			(xy 149.28796 -390.436281) (xy 149.245339 -390.411674) (xy 149.207218 -390.380549) (xy 149.174583 -390.343712)
			(xy 149.14828 -390.302116) (xy 149.128989 -390.25684) (xy 149.117212 -390.209056) (xy 149.113252 -390.160002)
			(xy 148.524214 -390.160002) (xy 148.523719 -390.184609) (xy 148.515824 -390.233186) (xy 148.50024 -390.279867)
			(xy 148.477369 -390.323444) (xy 148.447804 -390.362788) (xy 148.412311 -390.39688) (xy 148.371808 -390.424836)
			(xy 148.327346 -390.445934) (xy 148.280075 -390.459626) (xy 148.23122 -390.465558) (xy 148.182045 -390.463577)
			(xy 148.133826 -390.453733) (xy 148.08781 -390.436281) (xy 148.045189 -390.411674) (xy 148.007068 -390.380549)
			(xy 147.974433 -390.343712) (xy 147.94813 -390.302116) (xy 147.928839 -390.25684) (xy 147.917062 -390.209056)
			(xy 147.913102 -390.160002) (xy 147.324064 -390.160002) (xy 147.323569 -390.184609) (xy 147.315674 -390.233186)
			(xy 147.30009 -390.279867) (xy 147.277219 -390.323444) (xy 147.247654 -390.362788) (xy 147.212161 -390.39688)
			(xy 147.171658 -390.424836) (xy 147.127196 -390.445934) (xy 147.079925 -390.459626) (xy 147.03107 -390.465558)
			(xy 146.981895 -390.463577) (xy 146.933676 -390.453733) (xy 146.88766 -390.436281) (xy 146.845039 -390.411674)
			(xy 146.806918 -390.380549) (xy 146.774283 -390.343712) (xy 146.74798 -390.302116) (xy 146.728689 -390.25684)
			(xy 146.716912 -390.209056) (xy 146.712952 -390.160002) (xy 145.038117 -390.160002) (xy 145.032007 -390.181184)
			(xy 145.013008 -390.22359) (xy 144.98826 -390.26292) (xy 144.973548 -390.280906) (xy 144.967452 -390.288018)
			(xy 144.961356 -390.304528) (xy 144.961356 -390.388856) (xy 144.967452 -390.405366) (xy 144.973548 -390.412478)
			(xy 144.988254 -390.430469) (xy 145.013005 -390.469795) (xy 145.032005 -390.5122) (xy 145.044879 -390.556848)
			(xy 145.051374 -390.602858) (xy 145.05178 -390.626092) (xy 145.05178 -390.62914) (xy 145.052274 -390.639144)
			(xy 145.05994 -390.657625) (xy 145.074091 -390.671771) (xy 145.092576 -390.679429) (xy 145.10258 -390.67994)
			(xy 163.770818 -390.67994) (xy 163.780885 -390.679512) (xy 163.799479 -390.671786) (xy 163.806886 -390.664954)
			(xy 163.836604 -390.635236) (xy 163.843005 -390.628247) (xy 163.850694 -390.610944) (xy 163.851623 -390.592033)
			(xy 163.84905 -390.582912) (xy 163.815014 -390.482836) (xy 163.792916 -390.464548) (xy 163.778438 -390.462516)
			(xy 163.754336 -390.458788) (xy 163.707655 -390.444679) (xy 163.66381 -390.42333) (xy 163.623915 -390.395283)
			(xy 163.588985 -390.361252) (xy 163.559909 -390.322102) (xy 163.537424 -390.278827) (xy 163.522103 -390.23253)
			(xy 163.514336 -390.184385) (xy 163.51377 -390.160002) (xy 163.51424 -390.13601) (xy 163.521746 -390.088617)
			(xy 163.536573 -390.042981) (xy 163.558356 -390.000227) (xy 163.586559 -389.961406) (xy 163.620488 -389.927475)
			(xy 163.659306 -389.899269) (xy 163.702059 -389.877482) (xy 163.747693 -389.862652) (xy 163.795086 -389.855142)
			(xy 163.819078 -389.854694) (xy 163.841015 -389.855068) (xy 163.884437 -389.861345) (xy 163.926509 -389.873787)
			(xy 163.946586 -389.882634) (xy 163.958524 -389.887968) (xy 163.984178 -389.88619) (xy 164.067236 -389.833104)
			(xy 164.074229 -389.828222) (xy 164.084755 -389.814813) (xy 164.09032 -389.798701) (xy 164.090604 -389.790178)
			(xy 164.090604 -389.17626) (xy 164.090404 -389.169594) (xy 164.08692 -389.156726) (xy 164.083746 -389.15086)
			(xy 163.948618 -388.916926) (xy 163.937504 -388.894836) (xy 163.921779 -388.847956) (xy 163.913809 -388.799155)
			(xy 163.913312 -388.774432) (xy 163.913463 -388.763083) (xy 163.915244 -388.740453) (xy 163.916868 -388.72922)
			(xy 163.918138 -388.72033) (xy 163.914582 -388.703058) (xy 163.871148 -388.631938) (xy 163.857432 -388.620762)
			(xy 163.848796 -388.617968) (xy 163.826406 -388.609941) (xy 163.784237 -388.587943) (xy 163.74599 -388.55967)
			(xy 163.712591 -388.525808) (xy 163.684848 -388.487175) (xy 163.663433 -388.444707) (xy 163.648863 -388.399431)
			(xy 163.641492 -388.352443) (xy 163.641024 -388.328662) (xy 163.641524 -388.303264) (xy 163.649924 -388.253168)
			(xy 163.666503 -388.205154) (xy 163.690802 -388.160548) (xy 163.722152 -388.120581) (xy 163.740592 -388.10311)
			(xy 163.748974 -388.09549) (xy 163.75761 -388.075424) (xy 163.754816 -387.97611) (xy 163.745418 -387.956552)
			(xy 163.736528 -387.94944) (xy 163.717965 -387.933638) (xy 163.685236 -387.897513) (xy 163.658161 -387.856976)
			(xy 163.637326 -387.812906) (xy 163.623183 -387.766256) (xy 163.616036 -387.718036) (xy 163.615624 -387.693662)
			(xy 163.616063 -387.669546) (xy 163.623069 -387.621826) (xy 163.636927 -387.575628) (xy 163.657344 -387.531931)
			(xy 163.670234 -387.511544) (xy 163.676076 -387.502654) (xy 163.679632 -387.482588) (xy 163.65855 -387.390386)
			(xy 163.646358 -387.373622) (xy 163.637468 -387.368288) (xy 163.616665 -387.355433) (xy 163.578746 -387.324556)
			(xy 163.545794 -387.288425) (xy 163.518529 -387.247832) (xy 163.497546 -387.203662) (xy 163.483304 -387.156881)
			(xy 163.476115 -387.108512) (xy 163.47567 -387.084062) (xy 163.476231 -387.056779) (xy 163.485191 -387.002954)
			(xy 163.502862 -386.951329) (xy 163.528765 -386.903303) (xy 163.562198 -386.860179) (xy 163.581842 -386.841238)
			(xy 163.589298 -386.833749) (xy 163.597851 -386.814453) (xy 163.598352 -386.8039) (xy 163.598352 -386.729224)
			(xy 163.597765 -386.71869) (xy 163.589231 -386.699419) (xy 163.581842 -386.691886) (xy 163.562187 -386.672953)
			(xy 163.528744 -386.629832) (xy 163.502836 -386.581806) (xy 163.485165 -386.530177) (xy 163.476211 -386.476347)
			(xy 163.47567 -386.449062) (xy 163.475924 -386.43687) (xy 163.476178 -386.427218) (xy 163.470082 -386.409184)
			(xy 163.411408 -386.341874) (xy 163.394644 -386.333238) (xy 163.384738 -386.332222) (xy 163.357826 -386.32887)
			(xy 163.305529 -386.314522) (xy 163.256274 -386.291832) (xy 163.211383 -386.261408) (xy 163.17206 -386.224065)
			(xy 163.139358 -386.180806) (xy 163.114154 -386.132789) (xy 163.097124 -386.081303) (xy 163.092384 -386.0546)
			(xy 163.09086 -386.045202) (xy 162.818064 -385.57327) (xy 162.810698 -385.567428) (xy 162.791921 -385.551623)
			(xy 162.758792 -385.515415) (xy 162.731375 -385.47471) (xy 162.710273 -385.430401) (xy 162.695948 -385.383461)
			(xy 162.688715 -385.334919) (xy 162.68827 -385.31038) (xy 162.688781 -385.284393) (xy 162.696914 -385.23306)
			(xy 162.712976 -385.183631) (xy 162.736573 -385.137322) (xy 162.767123 -385.095275) (xy 162.803873 -385.058524)
			(xy 162.845921 -385.027974) (xy 162.892229 -385.004377) (xy 162.941658 -384.988314) (xy 162.992991 -384.980181)
			(xy 163.018978 -384.979672) (xy 163.04499 -384.980155) (xy 163.096372 -384.988299) (xy 163.145845 -385.004389)
			(xy 163.192188 -385.028029) (xy 163.234256 -385.058634) (xy 163.271013 -385.09545) (xy 163.30155 -385.137568)
			(xy 163.325115 -385.183949) (xy 163.341125 -385.233447) (xy 163.345622 -385.259072) (xy 163.347146 -385.26847)
			(xy 163.619942 -385.740402) (xy 163.627308 -385.746244) (xy 163.646086 -385.762048) (xy 163.679218 -385.798256)
			(xy 163.706638 -385.838961) (xy 163.727743 -385.88327) (xy 163.742072 -385.93021) (xy 163.749309 -385.978752)
			(xy 163.749736 -386.003292) (xy 163.749482 -386.015484) (xy 163.749228 -386.025136) (xy 163.755324 -386.04317)
			(xy 163.813998 -386.11048) (xy 163.830762 -386.119116) (xy 163.840668 -386.120132) (xy 163.867954 -386.123523)
			(xy 163.920937 -386.138209) (xy 163.946078 -386.149342) (xy 163.958016 -386.15493) (xy 163.98367 -386.153152)
			(xy 164.066982 -386.100066) (xy 164.074022 -386.095215) (xy 164.084633 -386.081823) (xy 164.090241 -386.065683)
			(xy 164.090604 -386.05714) (xy 164.090604 -385.712462) (xy 164.090404 -385.705796) (xy 164.086921 -385.692928)
			(xy 164.083746 -385.687062) (xy 164.017706 -385.572762) (xy 164.010594 -385.56692) (xy 163.99186 -385.551141)
			(xy 163.958803 -385.514998) (xy 163.931442 -385.474373) (xy 163.910377 -385.430155) (xy 163.896067 -385.383312)
			(xy 163.888827 -385.33487) (xy 163.88842 -385.31038) (xy 163.888891 -385.28482) (xy 163.896748 -385.234308)
			(xy 163.912287 -385.185608) (xy 163.935137 -385.13988) (xy 163.964754 -385.098215) (xy 164.000432 -385.061605)
			(xy 164.04132 -385.030924) (xy 164.06368 -385.018534) (xy 164.07638 -385.011676) (xy 164.090604 -384.9878)
			(xy 164.090604 -384.96875) (xy 164.090107 -384.958749) (xy 164.082439 -384.940273) (xy 164.068288 -384.926135)
			(xy 164.049806 -384.918484) (xy 164.039804 -384.91795) (xy 164.02939 -384.91795) (xy 164.019992 -384.922014)
			(xy 163.999392 -384.930392) (xy 163.956509 -384.942171) (xy 163.912434 -384.948093) (xy 163.890198 -384.94843)
			(xy 163.864209 -384.94792) (xy 163.812872 -384.939789) (xy 163.763438 -384.923727) (xy 163.717126 -384.900129)
			(xy 163.675075 -384.869577) (xy 163.638321 -384.832823) (xy 163.60777 -384.790773) (xy 163.584173 -384.74446)
			(xy 163.568111 -384.695027) (xy 163.55998 -384.643689) (xy 163.55998 -384.591711) (xy 163.568111 -384.540373)
			(xy 163.584173 -384.49094) (xy 163.60777 -384.444627) (xy 163.638321 -384.402577) (xy 163.675075 -384.365823)
			(xy 163.717126 -384.335271) (xy 163.763438 -384.311673) (xy 163.812872 -384.295611) (xy 163.864209 -384.28748)
			(xy 163.890198 -384.287014) (xy 163.909292 -384.287258) (xy 163.947232 -384.291588) (xy 163.96589 -384.29565)
			(xy 163.97732 -384.298444) (xy 163.999672 -384.293618) (xy 164.0713 -384.236722) (xy 164.080018 -384.229147)
			(xy 164.090075 -384.208381) (xy 164.090604 -384.196844) (xy 164.090604 -384.054858) (xy 164.090168 -384.044825)
			(xy 164.082597 -384.026246) (xy 164.075872 -384.01879) (xy 163.957762 -383.90068) (xy 163.950335 -383.89391)
			(xy 163.931738 -383.886334) (xy 163.921694 -383.885948) (xy 145.092928 -383.885948) (xy 145.082939 -383.885414)
			(xy 145.064505 -383.877702) (xy 145.057114 -383.870962) (xy 145.034 -383.870962) (xy 144.963896 -383.941066)
			(xy 144.957057 -383.948431) (xy 144.949316 -383.966963) (xy 144.949318 -383.987047) (xy 144.957062 -384.005577)
			(xy 144.963896 -384.012948) (xy 144.97177 -384.020822) (xy 144.992598 -384.028442) (xy 145.003774 -384.02768)
			(xy 145.02892 -384.026664) (xy 145.054908 -384.027175) (xy 145.106245 -384.035309) (xy 145.155677 -384.051373)
			(xy 145.201987 -384.074972) (xy 145.244036 -384.105525) (xy 145.280788 -384.142279) (xy 145.311339 -384.18433)
			(xy 145.334935 -384.230642) (xy 145.350996 -384.280075) (xy 145.359126 -384.331412) (xy 145.359126 -384.383388)
			(xy 145.350996 -384.434725) (xy 145.334935 -384.484158) (xy 145.311339 -384.53047) (xy 145.280788 -384.572521)
			(xy 145.244036 -384.609275) (xy 145.201987 -384.639828) (xy 145.194371 -384.643709) (xy 146.759932 -384.643709)
			(xy 146.759932 -384.591735) (xy 146.768062 -384.5404) (xy 146.784123 -384.49097) (xy 146.807719 -384.44466)
			(xy 146.838269 -384.402612) (xy 146.87502 -384.365861) (xy 146.917068 -384.335311) (xy 146.963378 -384.311715)
			(xy 147.012808 -384.295654) (xy 147.064143 -384.287524) (xy 147.116117 -384.287524) (xy 147.167452 -384.295654)
			(xy 147.216882 -384.311715) (xy 147.263192 -384.335311) (xy 147.30524 -384.365861) (xy 147.341991 -384.402612)
			(xy 147.372541 -384.44466) (xy 147.396137 -384.49097) (xy 147.412198 -384.5404) (xy 147.420328 -384.591735)
			(xy 147.420838 -384.617722) (xy 147.420328 -384.643709) (xy 147.959828 -384.643709) (xy 147.959828 -384.591735)
			(xy 147.967958 -384.5404) (xy 147.984019 -384.49097) (xy 148.007615 -384.44466) (xy 148.038165 -384.402612)
			(xy 148.074916 -384.365861) (xy 148.116964 -384.335311) (xy 148.163274 -384.311715) (xy 148.212704 -384.295654)
			(xy 148.264039 -384.287524) (xy 148.316013 -384.287524) (xy 148.367348 -384.295654) (xy 148.416778 -384.311715)
			(xy 148.463088 -384.335311) (xy 148.505136 -384.365861) (xy 148.541887 -384.402612) (xy 148.572437 -384.44466)
			(xy 148.596033 -384.49097) (xy 148.612094 -384.5404) (xy 148.620224 -384.591735) (xy 148.620734 -384.617722)
			(xy 148.620224 -384.643709) (xy 149.159978 -384.643709) (xy 149.159978 -384.591735) (xy 149.168108 -384.5404)
			(xy 149.184169 -384.49097) (xy 149.207765 -384.44466) (xy 149.238315 -384.402612) (xy 149.275066 -384.365861)
			(xy 149.317114 -384.335311) (xy 149.363424 -384.311715) (xy 149.412854 -384.295654) (xy 149.464189 -384.287524)
			(xy 149.516163 -384.287524) (xy 149.567498 -384.295654) (xy 149.616928 -384.311715) (xy 149.663238 -384.335311)
			(xy 149.705286 -384.365861) (xy 149.742037 -384.402612) (xy 149.772587 -384.44466) (xy 149.796183 -384.49097)
			(xy 149.812244 -384.5404) (xy 149.820374 -384.591735) (xy 149.820884 -384.617722) (xy 149.820374 -384.643709)
			(xy 150.359874 -384.643709) (xy 150.359874 -384.591735) (xy 150.368004 -384.5404) (xy 150.384065 -384.49097)
			(xy 150.407661 -384.44466) (xy 150.438211 -384.402612) (xy 150.474962 -384.365861) (xy 150.51701 -384.335311)
			(xy 150.56332 -384.311715) (xy 150.61275 -384.295654) (xy 150.664085 -384.287524) (xy 150.716059 -384.287524)
			(xy 150.767394 -384.295654) (xy 150.816824 -384.311715) (xy 150.863134 -384.335311) (xy 150.905182 -384.365861)
			(xy 150.941933 -384.402612) (xy 150.972483 -384.44466) (xy 150.996079 -384.49097) (xy 151.01214 -384.5404)
			(xy 151.02027 -384.591735) (xy 151.02078 -384.617722) (xy 151.02027 -384.643709) (xy 151.560024 -384.643709)
			(xy 151.560024 -384.591735) (xy 151.568154 -384.5404) (xy 151.584215 -384.49097) (xy 151.607811 -384.44466)
			(xy 151.638361 -384.402612) (xy 151.675112 -384.365861) (xy 151.71716 -384.335311) (xy 151.76347 -384.311715)
			(xy 151.8129 -384.295654) (xy 151.864235 -384.287524) (xy 151.916209 -384.287524) (xy 151.967544 -384.295654)
			(xy 152.016974 -384.311715) (xy 152.063284 -384.335311) (xy 152.105332 -384.365861) (xy 152.142083 -384.402612)
			(xy 152.172633 -384.44466) (xy 152.196229 -384.49097) (xy 152.21229 -384.5404) (xy 152.22042 -384.591735)
			(xy 152.22093 -384.617722) (xy 152.22042 -384.643709) (xy 152.75992 -384.643709) (xy 152.75992 -384.591735)
			(xy 152.76805 -384.5404) (xy 152.784111 -384.49097) (xy 152.807707 -384.44466) (xy 152.838257 -384.402612)
			(xy 152.875008 -384.365861) (xy 152.917056 -384.335311) (xy 152.963366 -384.311715) (xy 153.012796 -384.295654)
			(xy 153.064131 -384.287524) (xy 153.116105 -384.287524) (xy 153.16744 -384.295654) (xy 153.21687 -384.311715)
			(xy 153.26318 -384.335311) (xy 153.305228 -384.365861) (xy 153.341979 -384.402612) (xy 153.372529 -384.44466)
			(xy 153.396125 -384.49097) (xy 153.412186 -384.5404) (xy 153.420316 -384.591735) (xy 153.420826 -384.617722)
			(xy 153.420316 -384.643709) (xy 153.959816 -384.643709) (xy 153.959816 -384.591735) (xy 153.967946 -384.5404)
			(xy 153.984007 -384.49097) (xy 154.007603 -384.44466) (xy 154.038153 -384.402612) (xy 154.074904 -384.365861)
			(xy 154.116952 -384.335311) (xy 154.163262 -384.311715) (xy 154.212692 -384.295654) (xy 154.264027 -384.287524)
			(xy 154.316001 -384.287524) (xy 154.367336 -384.295654) (xy 154.416766 -384.311715) (xy 154.463076 -384.335311)
			(xy 154.505124 -384.365861) (xy 154.541875 -384.402612) (xy 154.572425 -384.44466) (xy 154.596021 -384.49097)
			(xy 154.612082 -384.5404) (xy 154.620212 -384.591735) (xy 154.620722 -384.617722) (xy 154.620212 -384.643709)
			(xy 155.159966 -384.643709) (xy 155.159966 -384.591735) (xy 155.168096 -384.5404) (xy 155.184157 -384.49097)
			(xy 155.207753 -384.44466) (xy 155.238303 -384.402612) (xy 155.275054 -384.365861) (xy 155.317102 -384.335311)
			(xy 155.363412 -384.311715) (xy 155.412842 -384.295654) (xy 155.464177 -384.287524) (xy 155.516151 -384.287524)
			(xy 155.567486 -384.295654) (xy 155.616916 -384.311715) (xy 155.663226 -384.335311) (xy 155.705274 -384.365861)
			(xy 155.742025 -384.402612) (xy 155.772575 -384.44466) (xy 155.796171 -384.49097) (xy 155.812232 -384.5404)
			(xy 155.820362 -384.591735) (xy 155.820872 -384.617722) (xy 155.820362 -384.643709) (xy 156.359862 -384.643709)
			(xy 156.359862 -384.591735) (xy 156.367992 -384.5404) (xy 156.384053 -384.49097) (xy 156.407649 -384.44466)
			(xy 156.438199 -384.402612) (xy 156.47495 -384.365861) (xy 156.516998 -384.335311) (xy 156.563308 -384.311715)
			(xy 156.612738 -384.295654) (xy 156.664073 -384.287524) (xy 156.716047 -384.287524) (xy 156.767382 -384.295654)
			(xy 156.816812 -384.311715) (xy 156.863122 -384.335311) (xy 156.90517 -384.365861) (xy 156.941921 -384.402612)
			(xy 156.972471 -384.44466) (xy 156.996067 -384.49097) (xy 157.012128 -384.5404) (xy 157.020258 -384.591735)
			(xy 157.020768 -384.617722) (xy 157.020258 -384.643709) (xy 157.560012 -384.643709) (xy 157.560012 -384.591735)
			(xy 157.568142 -384.5404) (xy 157.584203 -384.49097) (xy 157.607799 -384.44466) (xy 157.638349 -384.402612)
			(xy 157.6751 -384.365861) (xy 157.717148 -384.335311) (xy 157.763458 -384.311715) (xy 157.812888 -384.295654)
			(xy 157.864223 -384.287524) (xy 157.916197 -384.287524) (xy 157.967532 -384.295654) (xy 158.016962 -384.311715)
			(xy 158.063272 -384.335311) (xy 158.10532 -384.365861) (xy 158.142071 -384.402612) (xy 158.172621 -384.44466)
			(xy 158.196217 -384.49097) (xy 158.212278 -384.5404) (xy 158.220408 -384.591735) (xy 158.220918 -384.617722)
			(xy 158.220408 -384.643709) (xy 158.759908 -384.643709) (xy 158.759908 -384.591735) (xy 158.768038 -384.5404)
			(xy 158.784099 -384.49097) (xy 158.807695 -384.44466) (xy 158.838245 -384.402612) (xy 158.874996 -384.365861)
			(xy 158.917044 -384.335311) (xy 158.963354 -384.311715) (xy 159.012784 -384.295654) (xy 159.064119 -384.287524)
			(xy 159.116093 -384.287524) (xy 159.167428 -384.295654) (xy 159.216858 -384.311715) (xy 159.263168 -384.335311)
			(xy 159.305216 -384.365861) (xy 159.341967 -384.402612) (xy 159.372517 -384.44466) (xy 159.396113 -384.49097)
			(xy 159.412174 -384.5404) (xy 159.420304 -384.591735) (xy 159.420814 -384.617722) (xy 159.420304 -384.643709)
			(xy 159.959804 -384.643709) (xy 159.959804 -384.591735) (xy 159.967934 -384.5404) (xy 159.983995 -384.49097)
			(xy 160.007591 -384.44466) (xy 160.038141 -384.402612) (xy 160.074892 -384.365861) (xy 160.11694 -384.335311)
			(xy 160.16325 -384.311715) (xy 160.21268 -384.295654) (xy 160.264015 -384.287524) (xy 160.315989 -384.287524)
			(xy 160.367324 -384.295654) (xy 160.416754 -384.311715) (xy 160.463064 -384.335311) (xy 160.505112 -384.365861)
			(xy 160.541863 -384.402612) (xy 160.572413 -384.44466) (xy 160.596009 -384.49097) (xy 160.61207 -384.5404)
			(xy 160.6202 -384.591735) (xy 160.62071 -384.617722) (xy 160.6202 -384.643709) (xy 161.159954 -384.643709)
			(xy 161.159954 -384.591735) (xy 161.168084 -384.5404) (xy 161.184145 -384.49097) (xy 161.207741 -384.44466)
			(xy 161.238291 -384.402612) (xy 161.275042 -384.365861) (xy 161.31709 -384.335311) (xy 161.3634 -384.311715)
			(xy 161.41283 -384.295654) (xy 161.464165 -384.287524) (xy 161.516139 -384.287524) (xy 161.567474 -384.295654)
			(xy 161.616904 -384.311715) (xy 161.663214 -384.335311) (xy 161.705262 -384.365861) (xy 161.742013 -384.402612)
			(xy 161.772563 -384.44466) (xy 161.796159 -384.49097) (xy 161.81222 -384.5404) (xy 161.82035 -384.591735)
			(xy 161.82086 -384.617722) (xy 161.82035 -384.643709) (xy 162.35985 -384.643709) (xy 162.35985 -384.591735)
			(xy 162.36798 -384.5404) (xy 162.384041 -384.49097) (xy 162.407637 -384.44466) (xy 162.438187 -384.402612)
			(xy 162.474938 -384.365861) (xy 162.516986 -384.335311) (xy 162.563296 -384.311715) (xy 162.612726 -384.295654)
			(xy 162.664061 -384.287524) (xy 162.716035 -384.287524) (xy 162.76737 -384.295654) (xy 162.8168 -384.311715)
			(xy 162.86311 -384.335311) (xy 162.905158 -384.365861) (xy 162.941909 -384.402612) (xy 162.972459 -384.44466)
			(xy 162.996055 -384.49097) (xy 163.012116 -384.5404) (xy 163.020246 -384.591735) (xy 163.020756 -384.617722)
			(xy 163.020246 -384.643709) (xy 163.012116 -384.695044) (xy 162.996055 -384.744474) (xy 162.972459 -384.790784)
			(xy 162.941909 -384.832832) (xy 162.905158 -384.869583) (xy 162.86311 -384.900133) (xy 162.8168 -384.923729)
			(xy 162.76737 -384.93979) (xy 162.716035 -384.94792) (xy 162.664061 -384.94792) (xy 162.612726 -384.93979)
			(xy 162.563296 -384.923729) (xy 162.516986 -384.900133) (xy 162.474938 -384.869583) (xy 162.438187 -384.832832)
			(xy 162.407637 -384.790784) (xy 162.384041 -384.744474) (xy 162.36798 -384.695044) (xy 162.35985 -384.643709)
			(xy 161.82035 -384.643709) (xy 161.81222 -384.695044) (xy 161.796159 -384.744474) (xy 161.772563 -384.790784)
			(xy 161.742013 -384.832832) (xy 161.705262 -384.869583) (xy 161.663214 -384.900133) (xy 161.616904 -384.923729)
			(xy 161.567474 -384.93979) (xy 161.516139 -384.94792) (xy 161.464165 -384.94792) (xy 161.41283 -384.93979)
			(xy 161.3634 -384.923729) (xy 161.31709 -384.900133) (xy 161.275042 -384.869583) (xy 161.238291 -384.832832)
			(xy 161.207741 -384.790784) (xy 161.184145 -384.744474) (xy 161.168084 -384.695044) (xy 161.159954 -384.643709)
			(xy 160.6202 -384.643709) (xy 160.61207 -384.695044) (xy 160.596009 -384.744474) (xy 160.572413 -384.790784)
			(xy 160.541863 -384.832832) (xy 160.505112 -384.869583) (xy 160.463064 -384.900133) (xy 160.416754 -384.923729)
			(xy 160.367324 -384.93979) (xy 160.315989 -384.94792) (xy 160.264015 -384.94792) (xy 160.21268 -384.93979)
			(xy 160.16325 -384.923729) (xy 160.11694 -384.900133) (xy 160.074892 -384.869583) (xy 160.038141 -384.832832)
			(xy 160.007591 -384.790784) (xy 159.983995 -384.744474) (xy 159.967934 -384.695044) (xy 159.959804 -384.643709)
			(xy 159.420304 -384.643709) (xy 159.412174 -384.695044) (xy 159.396113 -384.744474) (xy 159.372517 -384.790784)
			(xy 159.341967 -384.832832) (xy 159.305216 -384.869583) (xy 159.263168 -384.900133) (xy 159.216858 -384.923729)
			(xy 159.167428 -384.93979) (xy 159.116093 -384.94792) (xy 159.064119 -384.94792) (xy 159.012784 -384.93979)
			(xy 158.963354 -384.923729) (xy 158.917044 -384.900133) (xy 158.874996 -384.869583) (xy 158.838245 -384.832832)
			(xy 158.807695 -384.790784) (xy 158.784099 -384.744474) (xy 158.768038 -384.695044) (xy 158.759908 -384.643709)
			(xy 158.220408 -384.643709) (xy 158.212278 -384.695044) (xy 158.196217 -384.744474) (xy 158.172621 -384.790784)
			(xy 158.142071 -384.832832) (xy 158.10532 -384.869583) (xy 158.063272 -384.900133) (xy 158.016962 -384.923729)
			(xy 157.967532 -384.93979) (xy 157.916197 -384.94792) (xy 157.864223 -384.94792) (xy 157.812888 -384.93979)
			(xy 157.763458 -384.923729) (xy 157.717148 -384.900133) (xy 157.6751 -384.869583) (xy 157.638349 -384.832832)
			(xy 157.607799 -384.790784) (xy 157.584203 -384.744474) (xy 157.568142 -384.695044) (xy 157.560012 -384.643709)
			(xy 157.020258 -384.643709) (xy 157.012128 -384.695044) (xy 156.996067 -384.744474) (xy 156.972471 -384.790784)
			(xy 156.941921 -384.832832) (xy 156.90517 -384.869583) (xy 156.863122 -384.900133) (xy 156.816812 -384.923729)
			(xy 156.767382 -384.93979) (xy 156.716047 -384.94792) (xy 156.664073 -384.94792) (xy 156.612738 -384.93979)
			(xy 156.563308 -384.923729) (xy 156.516998 -384.900133) (xy 156.47495 -384.869583) (xy 156.438199 -384.832832)
			(xy 156.407649 -384.790784) (xy 156.384053 -384.744474) (xy 156.367992 -384.695044) (xy 156.359862 -384.643709)
			(xy 155.820362 -384.643709) (xy 155.812232 -384.695044) (xy 155.796171 -384.744474) (xy 155.772575 -384.790784)
			(xy 155.742025 -384.832832) (xy 155.705274 -384.869583) (xy 155.663226 -384.900133) (xy 155.616916 -384.923729)
			(xy 155.567486 -384.93979) (xy 155.516151 -384.94792) (xy 155.464177 -384.94792) (xy 155.412842 -384.93979)
			(xy 155.363412 -384.923729) (xy 155.317102 -384.900133) (xy 155.275054 -384.869583) (xy 155.238303 -384.832832)
			(xy 155.207753 -384.790784) (xy 155.184157 -384.744474) (xy 155.168096 -384.695044) (xy 155.159966 -384.643709)
			(xy 154.620212 -384.643709) (xy 154.612082 -384.695044) (xy 154.596021 -384.744474) (xy 154.572425 -384.790784)
			(xy 154.541875 -384.832832) (xy 154.505124 -384.869583) (xy 154.463076 -384.900133) (xy 154.416766 -384.923729)
			(xy 154.367336 -384.93979) (xy 154.316001 -384.94792) (xy 154.264027 -384.94792) (xy 154.212692 -384.93979)
			(xy 154.163262 -384.923729) (xy 154.116952 -384.900133) (xy 154.074904 -384.869583) (xy 154.038153 -384.832832)
			(xy 154.007603 -384.790784) (xy 153.984007 -384.744474) (xy 153.967946 -384.695044) (xy 153.959816 -384.643709)
			(xy 153.420316 -384.643709) (xy 153.412186 -384.695044) (xy 153.396125 -384.744474) (xy 153.372529 -384.790784)
			(xy 153.341979 -384.832832) (xy 153.305228 -384.869583) (xy 153.26318 -384.900133) (xy 153.21687 -384.923729)
			(xy 153.16744 -384.93979) (xy 153.116105 -384.94792) (xy 153.064131 -384.94792) (xy 153.012796 -384.93979)
			(xy 152.963366 -384.923729) (xy 152.917056 -384.900133) (xy 152.875008 -384.869583) (xy 152.838257 -384.832832)
			(xy 152.807707 -384.790784) (xy 152.784111 -384.744474) (xy 152.76805 -384.695044) (xy 152.75992 -384.643709)
			(xy 152.22042 -384.643709) (xy 152.21229 -384.695044) (xy 152.196229 -384.744474) (xy 152.172633 -384.790784)
			(xy 152.142083 -384.832832) (xy 152.105332 -384.869583) (xy 152.063284 -384.900133) (xy 152.016974 -384.923729)
			(xy 151.967544 -384.93979) (xy 151.916209 -384.94792) (xy 151.864235 -384.94792) (xy 151.8129 -384.93979)
			(xy 151.76347 -384.923729) (xy 151.71716 -384.900133) (xy 151.675112 -384.869583) (xy 151.638361 -384.832832)
			(xy 151.607811 -384.790784) (xy 151.584215 -384.744474) (xy 151.568154 -384.695044) (xy 151.560024 -384.643709)
			(xy 151.02027 -384.643709) (xy 151.01214 -384.695044) (xy 150.996079 -384.744474) (xy 150.972483 -384.790784)
			(xy 150.941933 -384.832832) (xy 150.905182 -384.869583) (xy 150.863134 -384.900133) (xy 150.816824 -384.923729)
			(xy 150.767394 -384.93979) (xy 150.716059 -384.94792) (xy 150.664085 -384.94792) (xy 150.61275 -384.93979)
			(xy 150.56332 -384.923729) (xy 150.51701 -384.900133) (xy 150.474962 -384.869583) (xy 150.438211 -384.832832)
			(xy 150.407661 -384.790784) (xy 150.384065 -384.744474) (xy 150.368004 -384.695044) (xy 150.359874 -384.643709)
			(xy 149.820374 -384.643709) (xy 149.812244 -384.695044) (xy 149.796183 -384.744474) (xy 149.772587 -384.790784)
			(xy 149.742037 -384.832832) (xy 149.705286 -384.869583) (xy 149.663238 -384.900133) (xy 149.616928 -384.923729)
			(xy 149.567498 -384.93979) (xy 149.516163 -384.94792) (xy 149.464189 -384.94792) (xy 149.412854 -384.93979)
			(xy 149.363424 -384.923729) (xy 149.317114 -384.900133) (xy 149.275066 -384.869583) (xy 149.238315 -384.832832)
			(xy 149.207765 -384.790784) (xy 149.184169 -384.744474) (xy 149.168108 -384.695044) (xy 149.159978 -384.643709)
			(xy 148.620224 -384.643709) (xy 148.612094 -384.695044) (xy 148.596033 -384.744474) (xy 148.572437 -384.790784)
			(xy 148.541887 -384.832832) (xy 148.505136 -384.869583) (xy 148.463088 -384.900133) (xy 148.416778 -384.923729)
			(xy 148.367348 -384.93979) (xy 148.316013 -384.94792) (xy 148.264039 -384.94792) (xy 148.212704 -384.93979)
			(xy 148.163274 -384.923729) (xy 148.116964 -384.900133) (xy 148.074916 -384.869583) (xy 148.038165 -384.832832)
			(xy 148.007615 -384.790784) (xy 147.984019 -384.744474) (xy 147.967958 -384.695044) (xy 147.959828 -384.643709)
			(xy 147.420328 -384.643709) (xy 147.412198 -384.695044) (xy 147.396137 -384.744474) (xy 147.372541 -384.790784)
			(xy 147.341991 -384.832832) (xy 147.30524 -384.869583) (xy 147.263192 -384.900133) (xy 147.216882 -384.923729)
			(xy 147.167452 -384.93979) (xy 147.116117 -384.94792) (xy 147.064143 -384.94792) (xy 147.012808 -384.93979)
			(xy 146.963378 -384.923729) (xy 146.917068 -384.900133) (xy 146.87502 -384.869583) (xy 146.838269 -384.832832)
			(xy 146.807719 -384.790784) (xy 146.784123 -384.744474) (xy 146.768062 -384.695044) (xy 146.759932 -384.643709)
			(xy 145.194371 -384.643709) (xy 145.155677 -384.663427) (xy 145.106245 -384.679491) (xy 145.054908 -384.687625)
			(xy 145.02892 -384.68808) (xy 145.003727 -384.687608) (xy 144.953922 -384.679967) (xy 144.905854 -384.664859)
			(xy 144.860634 -384.642633) (xy 144.819309 -384.613804) (xy 144.782837 -384.57904) (xy 144.75206 -384.539144)
			(xy 144.727692 -384.495042) (xy 144.710297 -384.447753) (xy 144.704816 -384.423158) (xy 144.702022 -384.409442)
			(xy 144.683226 -384.388614) (xy 144.583912 -384.358896) (xy 144.575041 -384.356604) (xy 144.556773 -384.357807)
			(xy 144.54011 -384.365393) (xy 144.533366 -384.371596) (xy 144.531588 -384.373374) (xy 144.52419 -384.380221)
			(xy 144.505592 -384.387956) (xy 144.49552 -384.38836) (xy 144.144746 -384.38836) (xy 144.132325 -384.38897)
			(xy 144.110349 -384.400549) (xy 144.102836 -384.410458) (xy 144.048226 -384.489706) (xy 144.045432 -384.514344)
			(xy 144.050004 -384.526282) (xy 144.057975 -384.548128) (xy 144.069166 -384.593266) (xy 144.074799 -384.639428)
			(xy 144.07515 -384.66268) (xy 144.074664 -384.689931) (xy 144.066908 -384.743879) (xy 144.051553 -384.796174)
			(xy 144.028911 -384.845751) (xy 143.999445 -384.891601) (xy 143.963754 -384.932792) (xy 143.922563 -384.968483)
			(xy 143.876713 -384.997949) (xy 143.827136 -385.020591) (xy 143.774841 -385.035946) (xy 143.720893 -385.043702)
			(xy 143.666391 -385.043702) (xy 143.612443 -385.035946) (xy 143.560148 -385.020591) (xy 143.510571 -384.997949)
			(xy 143.464721 -384.968483) (xy 143.42353 -384.932792) (xy 143.387839 -384.891601) (xy 143.358373 -384.845751)
			(xy 143.335731 -384.796174) (xy 143.320376 -384.743879) (xy 143.31262 -384.689931) (xy 143.312134 -384.66268)
			(xy 143.312465 -384.639427) (xy 143.318095 -384.593263) (xy 143.329306 -384.548128) (xy 143.33728 -384.526282)
			(xy 143.341852 -384.514344) (xy 143.339058 -384.489706) (xy 143.284448 -384.410458) (xy 143.276922 -384.400562)
			(xy 143.254955 -384.388974) (xy 143.242538 -384.38836) (xy 143.123666 -384.38836) (xy 143.1136 -384.388791)
			(xy 143.09501 -384.396521) (xy 143.087598 -384.403346) (xy 141.90859 -385.58216) (xy 143.311624 -385.58216)
			(xy 143.315695 -385.526538) (xy 143.327821 -385.472101) (xy 143.347744 -385.42001) (xy 143.37504 -385.371375)
			(xy 143.409126 -385.327232) (xy 143.449275 -385.288523) (xy 143.494633 -385.256072) (xy 143.544233 -385.230571)
			(xy 143.597017 -385.212564) (xy 143.65186 -385.202434) (xy 143.707594 -385.200397) (xy 143.763031 -385.206497)
			(xy 143.816988 -385.220603) (xy 143.868317 -385.242415) (xy 143.915923 -385.271469) (xy 143.958791 -385.307144)
			(xy 143.996008 -385.348681) (xy 144.026781 -385.395194) (xy 144.050453 -385.445691) (xy 144.066521 -385.499098)
			(xy 144.074641 -385.554274) (xy 144.07515 -385.58216) (xy 144.074641 -385.610046) (xy 144.071893 -385.628721)
			(xy 144.277336 -385.628721) (xy 144.277336 -385.576747) (xy 144.285466 -385.525412) (xy 144.301527 -385.475982)
			(xy 144.325123 -385.429672) (xy 144.355673 -385.387624) (xy 144.392424 -385.350873) (xy 144.434472 -385.320323)
			(xy 144.480782 -385.296727) (xy 144.530212 -385.280666) (xy 144.581547 -385.272536) (xy 144.633521 -385.272536)
			(xy 144.684856 -385.280666) (xy 144.734286 -385.296727) (xy 144.761082 -385.31038) (xy 147.088352 -385.31038)
			(xy 147.088883 -385.284394) (xy 147.097015 -385.233063) (xy 147.113077 -385.183636) (xy 147.136671 -385.137329)
			(xy 147.167219 -385.095282) (xy 147.203967 -385.058532) (xy 147.246012 -385.027982) (xy 147.292317 -385.004384)
			(xy 147.341743 -384.98832) (xy 147.393074 -384.980185) (xy 147.41906 -384.979672) (xy 147.445072 -384.980087)
			(xy 147.496451 -384.988255) (xy 147.545918 -385.004364) (xy 147.592254 -385.028017) (xy 147.634317 -385.058632)
			(xy 147.671069 -385.095453) (xy 147.701605 -385.137573) (xy 147.725172 -385.183953) (xy 147.741189 -385.23345)
			(xy 147.745704 -385.259072) (xy 147.747228 -385.26847) (xy 147.771454 -385.31038) (xy 148.288248 -385.31038)
			(xy 148.288783 -385.284394) (xy 148.296915 -385.233064) (xy 148.312976 -385.183636) (xy 148.336571 -385.13733)
			(xy 148.367118 -385.095284) (xy 148.403866 -385.058533) (xy 148.445909 -385.027983) (xy 148.492214 -385.004385)
			(xy 148.54164 -384.988321) (xy 148.592971 -384.980185) (xy 148.618956 -384.979672) (xy 148.644968 -384.980091)
			(xy 148.696347 -384.988258) (xy 148.745814 -385.004366) (xy 148.79215 -385.028019) (xy 148.834213 -385.058633)
			(xy 148.870965 -385.095454) (xy 148.901501 -385.137573) (xy 148.925068 -385.183953) (xy 148.941085 -385.23345)
			(xy 148.9456 -385.259072) (xy 148.947124 -385.26847) (xy 148.97135 -385.31038) (xy 149.488398 -385.31038)
			(xy 149.488883 -385.284392) (xy 149.497017 -385.233056) (xy 149.513081 -385.183625) (xy 149.53668 -385.137315)
			(xy 149.567232 -385.095267) (xy 149.603987 -385.058516) (xy 149.646037 -385.027966) (xy 149.692349 -385.004371)
			(xy 149.741782 -384.988311) (xy 149.793118 -384.980181) (xy 149.819106 -384.979672) (xy 149.84515 -384.980128)
			(xy 149.896591 -384.988316) (xy 149.946115 -385.004459) (xy 149.9925 -385.028158) (xy 150.034602 -385.058828)
			(xy 150.071382 -385.095712) (xy 150.101933 -385.137901) (xy 150.1255 -385.184353) (xy 150.141503 -385.233923)
			(xy 150.146004 -385.25958) (xy 150.147274 -385.268978) (xy 150.17121 -385.31038) (xy 150.688294 -385.31038)
			(xy 150.688783 -385.284392) (xy 150.696917 -385.233057) (xy 150.712981 -385.183626) (xy 150.736579 -385.137316)
			(xy 150.767131 -385.095268) (xy 150.803885 -385.058517) (xy 150.845935 -385.027968) (xy 150.892246 -385.004372)
			(xy 150.941678 -384.988312) (xy 150.993014 -384.980181) (xy 151.019002 -384.979672) (xy 151.045012 -384.98014)
			(xy 151.096389 -384.988299) (xy 151.145855 -385.0044) (xy 151.192191 -385.028046) (xy 151.234254 -385.058654)
			(xy 151.271008 -385.095469) (xy 151.301545 -385.137583) (xy 151.325113 -385.183959) (xy 151.341131 -385.233452)
			(xy 151.345646 -385.259072) (xy 151.34717 -385.26847) (xy 151.371396 -385.31038) (xy 151.88819 -385.31038)
			(xy 151.888683 -385.284392) (xy 151.896817 -385.233057) (xy 151.91288 -385.183627) (xy 151.936478 -385.137317)
			(xy 151.96703 -385.095269) (xy 152.003783 -385.058518) (xy 152.045833 -385.027969) (xy 152.092143 -385.004373)
			(xy 152.141575 -384.988312) (xy 152.19291 -384.980182) (xy 152.218898 -384.979672) (xy 152.244908 -384.980143)
			(xy 152.296285 -384.988302) (xy 152.345751 -385.004402) (xy 152.392087 -385.028048) (xy 152.43415 -385.058655)
			(xy 152.470903 -385.09547) (xy 152.501441 -385.137584) (xy 152.525009 -385.183959) (xy 152.541027 -385.233452)
			(xy 152.545542 -385.259072) (xy 152.547066 -385.26847) (xy 152.571292 -385.31038) (xy 153.08834 -385.31038)
			(xy 153.088757 -385.284388) (xy 153.096893 -385.233044) (xy 153.11296 -385.183605) (xy 153.136565 -385.137289)
			(xy 153.167125 -385.095235) (xy 153.203887 -385.05848) (xy 153.245947 -385.027929) (xy 153.292268 -385.004334)
			(xy 153.34171 -384.988277) (xy 153.393056 -384.980152) (xy 153.419048 -384.979672) (xy 153.44506 -384.980098)
			(xy 153.496438 -384.988264) (xy 153.545905 -385.004371) (xy 153.592241 -385.028023) (xy 153.634304 -385.058636)
			(xy 153.671057 -385.095456) (xy 153.701593 -385.137575) (xy 153.72516 -385.183954) (xy 153.741177 -385.23345)
			(xy 153.745692 -385.259072) (xy 153.747216 -385.26847) (xy 153.771442 -385.31038) (xy 154.288236 -385.31038)
			(xy 154.288657 -385.284388) (xy 154.296792 -385.233044) (xy 154.31286 -385.183606) (xy 154.336464 -385.13729)
			(xy 154.367023 -385.095236) (xy 154.403785 -385.058482) (xy 154.445844 -385.027931) (xy 154.492165 -385.004336)
			(xy 154.541607 -384.988277) (xy 154.592952 -384.980152) (xy 154.618944 -384.979672) (xy 154.644955 -384.980102)
			(xy 154.696334 -384.988267) (xy 154.745801 -385.004374) (xy 154.792137 -385.028025) (xy 154.8342 -385.058638)
			(xy 154.870952 -385.095457) (xy 154.901489 -385.137576) (xy 154.925056 -385.183954) (xy 154.941073 -385.233451)
			(xy 154.945588 -385.259072) (xy 154.947112 -385.26847) (xy 154.971338 -385.31038) (xy 155.488386 -385.31038)
			(xy 155.488883 -385.284393) (xy 155.497016 -385.233058) (xy 155.51308 -385.183628) (xy 155.536678 -385.137319)
			(xy 155.567229 -385.095271) (xy 155.603981 -385.05852) (xy 155.64603 -385.02797) (xy 155.692341 -385.004374)
			(xy 155.741772 -384.988313) (xy 155.793107 -384.980182) (xy 155.819094 -384.979672) (xy 155.845138 -384.980139)
			(xy 155.896578 -384.988325) (xy 155.946102 -385.004467) (xy 155.992487 -385.028164) (xy 156.03459 -385.058832)
			(xy 156.07137 -385.095716) (xy 156.10192 -385.137903) (xy 156.125488 -385.184355) (xy 156.141491 -385.233923)
			(xy 156.145992 -385.25958) (xy 156.147262 -385.268978) (xy 156.171198 -385.31038) (xy 156.688282 -385.31038)
			(xy 156.688783 -385.284393) (xy 156.696916 -385.233059) (xy 156.712979 -385.183629) (xy 156.736577 -385.13732)
			(xy 156.767128 -385.095272) (xy 156.80388 -385.058521) (xy 156.845928 -385.027972) (xy 156.892238 -385.004376)
			(xy 156.941668 -384.988314) (xy 156.993003 -384.980182) (xy 157.01899 -384.979672) (xy 157.045 -384.980151)
			(xy 157.096376 -384.988308) (xy 157.145842 -385.004407) (xy 157.192178 -385.028052) (xy 157.234241 -385.058658)
			(xy 157.270995 -385.095472) (xy 157.301532 -385.137585) (xy 157.325101 -385.18396) (xy 157.341119 -385.233452)
			(xy 157.345634 -385.259072) (xy 157.347158 -385.26847) (xy 157.371384 -385.31038) (xy 157.888178 -385.31038)
			(xy 157.888683 -385.284393) (xy 157.896816 -385.233059) (xy 157.912879 -385.183629) (xy 157.936476 -385.137321)
			(xy 157.967027 -385.095274) (xy 158.003778 -385.058523) (xy 158.045826 -385.027973) (xy 158.092135 -385.004377)
			(xy 158.141565 -384.988315) (xy 158.192899 -384.980183) (xy 158.218886 -384.979672) (xy 158.244896 -384.980154)
			(xy 158.296272 -384.988311) (xy 158.345738 -385.00441) (xy 158.392074 -385.028054) (xy 158.434137 -385.05866)
			(xy 158.470891 -385.095473) (xy 158.501428 -385.137586) (xy 158.524996 -385.18396) (xy 158.541015 -385.233453)
			(xy 158.54553 -385.259072) (xy 158.547054 -385.26847) (xy 158.57128 -385.31038) (xy 159.088328 -385.31038)
			(xy 159.088757 -385.284388) (xy 159.096892 -385.233046) (xy 159.112959 -385.183608) (xy 159.136563 -385.137292)
			(xy 159.167121 -385.095239) (xy 159.203882 -385.058485) (xy 159.24594 -385.027933) (xy 159.29226 -385.004338)
			(xy 159.3417 -384.988279) (xy 159.393044 -384.980152) (xy 159.419036 -384.979672) (xy 159.445047 -384.980109)
			(xy 159.496425 -384.988273) (xy 159.545892 -385.004379) (xy 159.592228 -385.028029) (xy 159.634291 -385.058641)
			(xy 159.671044 -385.095459) (xy 159.70158 -385.137577) (xy 159.725148 -385.183955) (xy 159.741165 -385.233451)
			(xy 159.74568 -385.259072) (xy 159.747204 -385.26847) (xy 159.77143 -385.31038) (xy 160.288224 -385.31038)
			(xy 160.288657 -385.284389) (xy 160.296792 -385.233046) (xy 160.312859 -385.183609) (xy 160.336462 -385.137293)
			(xy 160.36702 -385.095241) (xy 160.40378 -385.058486) (xy 160.445838 -385.027935) (xy 160.492157 -385.004339)
			(xy 160.541597 -384.98828) (xy 160.592941 -384.980153) (xy 160.618932 -384.979672) (xy 160.644943 -384.980112)
			(xy 160.696321 -384.988276) (xy 160.745788 -385.004381) (xy 160.792124 -385.028031) (xy 160.834187 -385.058642)
			(xy 160.87094 -385.095461) (xy 160.901476 -385.137578) (xy 160.925044 -385.183956) (xy 160.941061 -385.233451)
			(xy 160.945576 -385.259072) (xy 160.9471 -385.26847) (xy 160.971326 -385.31038) (xy 161.488374 -385.31038)
			(xy 161.488883 -385.284393) (xy 161.497016 -385.23306) (xy 161.513079 -385.18363) (xy 161.536675 -385.137322)
			(xy 161.567225 -385.095275) (xy 161.603976 -385.058524) (xy 161.646024 -385.027974) (xy 161.692332 -385.004378)
			(xy 161.741762 -384.988316) (xy 161.793095 -384.980183) (xy 161.819082 -384.979672) (xy 161.845125 -384.980149)
			(xy 161.896565 -384.988335) (xy 161.946089 -385.004474) (xy 161.992474 -385.02817) (xy 162.034577 -385.058837)
			(xy 162.071357 -385.095719) (xy 162.101908 -385.137905) (xy 162.125476 -385.184356) (xy 162.141478 -385.233924)
			(xy 162.14598 -385.25958) (xy 162.14725 -385.268978) (xy 162.419792 -385.740402) (xy 162.427158 -385.746244)
			(xy 162.445951 -385.762028) (xy 162.479066 -385.79825) (xy 162.506472 -385.838962) (xy 162.527569 -385.883274)
			(xy 162.541897 -385.930213) (xy 162.549141 -385.978753) (xy 162.549586 -386.003292) (xy 162.549332 -386.015484)
			(xy 162.549078 -386.025136) (xy 162.555174 -386.04317) (xy 162.613848 -386.11048) (xy 162.630612 -386.119116)
			(xy 162.640518 -386.120132) (xy 162.667282 -386.123476) (xy 162.719305 -386.137702) (xy 162.768331 -386.160179)
			(xy 162.81306 -386.190313) (xy 162.852307 -386.227305) (xy 162.885033 -386.270175) (xy 162.910369 -386.317787)
			(xy 162.927644 -386.368878) (xy 162.936401 -386.422096) (xy 162.936936 -386.449062) (xy 162.936393 -386.476347)
			(xy 162.92744 -386.530176) (xy 162.909769 -386.581805) (xy 162.883861 -386.629832) (xy 162.850419 -386.672953)
			(xy 162.830764 -386.691886) (xy 162.823376 -386.699419) (xy 162.814842 -386.71869) (xy 162.814254 -386.729224)
			(xy 162.814254 -386.8039) (xy 162.814783 -386.814449) (xy 162.82332 -386.833744) (xy 162.830764 -386.841238)
			(xy 162.850409 -386.860178) (xy 162.883841 -386.903303) (xy 162.909744 -386.951329) (xy 162.927415 -387.002954)
			(xy 162.936375 -387.056779) (xy 162.936936 -387.084062) (xy 162.936488 -387.108178) (xy 162.929492 -387.155901)
			(xy 162.915642 -387.202102) (xy 162.895231 -387.245802) (xy 162.882326 -387.26618) (xy 162.876484 -387.27507)
			(xy 162.872928 -387.295136) (xy 162.89401 -387.387338) (xy 162.906202 -387.404102) (xy 162.915092 -387.409436)
			(xy 162.935883 -387.422306) (xy 162.973791 -387.453192) (xy 163.006736 -387.489324) (xy 163.033999 -387.529914)
			(xy 163.054986 -387.574078) (xy 163.069239 -387.620851) (xy 163.076447 -387.669214) (xy 163.07689 -387.693662)
			(xy 163.076473 -387.718035) (xy 163.069327 -387.766255) (xy 163.055184 -387.812905) (xy 163.03435 -387.856975)
			(xy 163.007276 -387.897512) (xy 162.974548 -387.933638) (xy 162.955986 -387.94944) (xy 162.947096 -387.956552)
			(xy 162.937698 -387.97611) (xy 162.934904 -388.075424) (xy 162.94354 -388.09549) (xy 162.951922 -388.10311)
			(xy 162.970365 -388.120579) (xy 163.001713 -388.160547) (xy 163.026012 -388.205154) (xy 163.04259 -388.253168)
			(xy 163.05099 -388.303264) (xy 163.05149 -388.328662) (xy 163.051386 -388.339943) (xy 163.049735 -388.362445)
			(xy 163.048188 -388.37362) (xy 163.046918 -388.38251) (xy 163.050474 -388.400036) (xy 163.093908 -388.470902)
			(xy 163.107624 -388.482078) (xy 163.11626 -388.484872) (xy 163.138506 -388.492805) (xy 163.180427 -388.514557)
			(xy 163.2185 -388.542502) (xy 163.251819 -388.575974) (xy 163.279587 -388.614177) (xy 163.290758 -388.634986)
			(xy 163.291266 -388.636002) (xy 163.683696 -389.314944) (xy 163.696428 -389.33831) (xy 163.714544 -389.388338)
			(xy 163.723754 -389.440741) (xy 163.724336 -389.467344) (xy 163.723878 -389.491335) (xy 163.716366 -389.538726)
			(xy 163.701535 -389.584358) (xy 163.679748 -389.627109) (xy 163.651543 -389.665926) (xy 163.617613 -389.699853)
			(xy 163.578795 -389.728056) (xy 163.536043 -389.749841) (xy 163.49041 -389.76467) (xy 163.443019 -389.772179)
			(xy 163.419028 -389.772652) (xy 163.395496 -389.772227) (xy 163.348987 -389.765015) (xy 163.304138 -389.750744)
			(xy 163.262014 -389.729752) (xy 163.223616 -389.702537) (xy 163.189855 -389.669746) (xy 163.161532 -389.632157)
			(xy 163.150042 -389.611616) (xy 163.149788 -389.611108) (xy 163.14928 -389.610346) (xy 162.751516 -388.922006)
			(xy 162.739602 -388.899337) (xy 162.722664 -388.851012) (xy 162.714004 -388.800542) (xy 162.713416 -388.77494)
			(xy 162.713416 -388.774432) (xy 162.713573 -388.763083) (xy 162.71535 -388.740453) (xy 162.716972 -388.72922)
			(xy 162.718242 -388.72033) (xy 162.714686 -388.703058) (xy 162.671252 -388.631938) (xy 162.657282 -388.621016)
			(xy 162.6489 -388.617968) (xy 162.626489 -388.60996) (xy 162.584271 -388.587995) (xy 162.545976 -388.559742)
			(xy 162.512532 -388.525887) (xy 162.484749 -388.487249) (xy 162.463301 -388.444767) (xy 162.448709 -388.39947)
			(xy 162.441327 -388.352457) (xy 162.440874 -388.328662) (xy 162.441408 -388.303268) (xy 162.449817 -388.253179)
			(xy 162.466395 -388.205172) (xy 162.490687 -388.160569) (xy 162.522023 -388.1206) (xy 162.540442 -388.10311)
			(xy 162.548824 -388.09549) (xy 162.55746 -388.075424) (xy 162.554666 -387.97611) (xy 162.545268 -387.956552)
			(xy 162.536378 -387.94944) (xy 162.517846 -387.933606) (xy 162.485124 -387.897482) (xy 162.458052 -387.856951)
			(xy 162.437217 -387.812887) (xy 162.423068 -387.766245) (xy 162.415912 -387.718032) (xy 162.415474 -387.693662)
			(xy 162.415884 -387.669544) (xy 162.422891 -387.621821) (xy 162.436753 -387.57562) (xy 162.457174 -387.53192)
			(xy 162.470084 -387.511544) (xy 162.475926 -387.502654) (xy 162.479482 -387.482588) (xy 162.4584 -387.390386)
			(xy 162.446208 -387.373622) (xy 162.437318 -387.368288) (xy 162.41654 -387.355398) (xy 162.378632 -387.324516)
			(xy 162.345686 -387.288387) (xy 162.318421 -387.2478) (xy 162.297432 -387.20364) (xy 162.283176 -387.156869)
			(xy 162.275965 -387.108509) (xy 162.27552 -387.084062) (xy 162.27606 -387.056777) (xy 162.285012 -387.002946)
			(xy 162.302682 -386.951317) (xy 162.328591 -386.90329) (xy 162.362036 -386.86017) (xy 162.381692 -386.841238)
			(xy 162.389078 -386.833703) (xy 162.397611 -386.814433) (xy 162.398202 -386.8039) (xy 162.398202 -386.729224)
			(xy 162.397673 -386.718674) (xy 162.389138 -386.699379) (xy 162.381692 -386.691886) (xy 162.362069 -386.672924)
			(xy 162.328631 -386.629806) (xy 162.302724 -386.581786) (xy 162.285048 -386.530165) (xy 162.276083 -386.476344)
			(xy 162.27552 -386.449062) (xy 162.275774 -386.43687) (xy 162.276028 -386.427218) (xy 162.269932 -386.409184)
			(xy 162.211258 -386.341874) (xy 162.194494 -386.333238) (xy 162.184588 -386.332222) (xy 162.157684 -386.328828)
			(xy 162.105399 -386.314469) (xy 162.056155 -386.291774) (xy 162.011272 -386.261352) (xy 161.971952 -386.224018)
			(xy 161.939246 -386.180771) (xy 161.914032 -386.132769) (xy 161.896984 -386.081297) (xy 161.892234 -386.0546)
			(xy 161.89071 -386.045202) (xy 161.61766 -385.572762) (xy 161.610548 -385.56692) (xy 161.591806 -385.551152)
			(xy 161.558754 -385.515006) (xy 161.5314 -385.474378) (xy 161.510342 -385.430157) (xy 161.496044 -385.383312)
			(xy 161.488816 -385.334869) (xy 161.488374 -385.31038) (xy 160.971326 -385.31038) (xy 161.219896 -385.740402)
			(xy 161.227262 -385.746244) (xy 161.246056 -385.762027) (xy 161.27917 -385.798249) (xy 161.306576 -385.838962)
			(xy 161.327674 -385.883273) (xy 161.342001 -385.930213) (xy 161.349245 -385.978753) (xy 161.34969 -386.003292)
			(xy 161.349436 -386.015484) (xy 161.349182 -386.025136) (xy 161.355278 -386.04317) (xy 161.413952 -386.11048)
			(xy 161.430716 -386.119116) (xy 161.440622 -386.120132) (xy 161.467386 -386.123473) (xy 161.51941 -386.137699)
			(xy 161.568435 -386.160177) (xy 161.613165 -386.190312) (xy 161.652412 -386.227304) (xy 161.685137 -386.270174)
			(xy 161.710473 -386.317786) (xy 161.727748 -386.368878) (xy 161.736505 -386.422095) (xy 161.73704 -386.449062)
			(xy 161.736496 -386.476347) (xy 161.727543 -386.530176) (xy 161.709872 -386.581805) (xy 161.683964 -386.629832)
			(xy 161.650522 -386.672953) (xy 161.630868 -386.691886) (xy 161.623481 -386.69942) (xy 161.614946 -386.71869)
			(xy 161.614358 -386.729224) (xy 161.614358 -386.8039) (xy 161.614886 -386.814449) (xy 161.623423 -386.833744)
			(xy 161.630868 -386.841238) (xy 161.650514 -386.860178) (xy 161.683946 -386.903302) (xy 161.709848 -386.951328)
			(xy 161.727519 -387.002954) (xy 161.736479 -387.056779) (xy 161.73704 -387.084062) (xy 161.736592 -387.108178)
			(xy 161.729595 -387.1559) (xy 161.715745 -387.202101) (xy 161.695335 -387.245802) (xy 161.68243 -387.26618)
			(xy 161.676588 -387.27507) (xy 161.673032 -387.295136) (xy 161.694114 -387.387338) (xy 161.706306 -387.404102)
			(xy 161.715196 -387.409436) (xy 161.735988 -387.422305) (xy 161.773896 -387.453191) (xy 161.80684 -387.489323)
			(xy 161.834103 -387.529914) (xy 161.85509 -387.574078) (xy 161.869343 -387.620851) (xy 161.876551 -387.669214)
			(xy 161.876994 -387.693662) (xy 161.876575 -387.718035) (xy 161.869429 -387.766255) (xy 161.855286 -387.812905)
			(xy 161.834453 -387.856975) (xy 161.807379 -387.897512) (xy 161.774652 -387.933638) (xy 161.75609 -387.94944)
			(xy 161.7472 -387.956552) (xy 161.737802 -387.97611) (xy 161.735008 -388.075424) (xy 161.743644 -388.09549)
			(xy 161.752026 -388.10311) (xy 161.770469 -388.120578) (xy 161.801818 -388.160546) (xy 161.826116 -388.205153)
			(xy 161.842694 -388.253168) (xy 161.851094 -388.303264) (xy 161.851594 -388.328662) (xy 161.85149 -388.339943)
			(xy 161.849839 -388.362445) (xy 161.848292 -388.37362) (xy 161.847022 -388.382764) (xy 161.850324 -388.400036)
			(xy 161.894012 -388.471156) (xy 161.907728 -388.482078) (xy 161.916364 -388.484872) (xy 161.944527 -388.495073)
			(xy 161.996474 -388.524882) (xy 162.019488 -388.544054) (xy 162.040971 -388.563636) (xy 162.076785 -388.609414)
			(xy 162.090608 -388.634986) (xy 162.09137 -388.636256) (xy 162.483546 -389.314944) (xy 162.496353 -389.338286)
			(xy 162.51458 -389.388304) (xy 162.523847 -389.440727) (xy 162.52444 -389.467344) (xy 162.524002 -389.491349)
			(xy 162.516481 -389.538768) (xy 162.501633 -389.584425) (xy 162.479823 -389.627196) (xy 162.451588 -389.666027)
			(xy 162.417625 -389.699961) (xy 162.378769 -389.728162) (xy 162.335979 -389.749935) (xy 162.290309 -389.764744)
			(xy 162.242884 -389.772222) (xy 162.218878 -389.772652) (xy 162.195347 -389.772186) (xy 162.14884 -389.764983)
			(xy 162.103992 -389.750718) (xy 162.061869 -389.729733) (xy 162.02347 -389.702524) (xy 161.989707 -389.669739)
			(xy 161.961383 -389.632155) (xy 161.949892 -389.611616) (xy 161.949638 -389.611108) (xy 161.94913 -389.610346)
			(xy 161.55162 -388.921752) (xy 161.541048 -388.901825) (xy 161.525245 -388.859576) (xy 161.515837 -388.815459)
			(xy 161.514028 -388.792974) (xy 161.51352 -388.781798) (xy 161.51352 -388.774432) (xy 161.513611 -388.763087)
			(xy 161.515266 -388.740458) (xy 161.516822 -388.72922) (xy 161.518092 -388.72033) (xy 161.514536 -388.703058)
			(xy 161.471102 -388.631938) (xy 161.457386 -388.620762) (xy 161.44875 -388.617968) (xy 161.426343 -388.609983)
			(xy 161.384173 -388.587978) (xy 161.345926 -388.559698) (xy 161.312527 -388.52583) (xy 161.284784 -388.487191)
			(xy 161.263369 -388.444718) (xy 161.2488 -388.399437) (xy 161.241429 -388.352445) (xy 161.240978 -388.328662)
			(xy 161.241511 -388.303267) (xy 161.249919 -388.253179) (xy 161.266498 -388.205172) (xy 161.290791 -388.160569)
			(xy 161.322127 -388.120599) (xy 161.340546 -388.10311) (xy 161.348928 -388.09549) (xy 161.357564 -388.075424)
			(xy 161.35477 -387.97611) (xy 161.345372 -387.956552) (xy 161.336482 -387.94944) (xy 161.317951 -387.933605)
			(xy 161.285228 -387.897482) (xy 161.258156 -387.85695) (xy 161.237321 -387.812887) (xy 161.223172 -387.766245)
			(xy 161.216016 -387.718032) (xy 161.215578 -387.693662) (xy 161.215987 -387.669544) (xy 161.222995 -387.62182)
			(xy 161.236856 -387.575619) (xy 161.257278 -387.53192) (xy 161.270188 -387.511544) (xy 161.27603 -387.502654)
			(xy 161.279586 -387.482588) (xy 161.258504 -387.390386) (xy 161.246312 -387.373622) (xy 161.237422 -387.368288)
			(xy 161.216645 -387.355396) (xy 161.178736 -387.324515) (xy 161.14579 -387.288387) (xy 161.118525 -387.2478)
			(xy 161.097536 -387.203639) (xy 161.08328 -387.156869) (xy 161.076069 -387.108509) (xy 161.075624 -387.084062)
			(xy 161.076163 -387.056777) (xy 161.085115 -387.002946) (xy 161.102785 -386.951316) (xy 161.128695 -386.90329)
			(xy 161.16214 -386.86017) (xy 161.181796 -386.841238) (xy 161.189182 -386.833704) (xy 161.197715 -386.814433)
			(xy 161.198306 -386.8039) (xy 161.198306 -386.729224) (xy 161.197776 -386.718675) (xy 161.189241 -386.699379)
			(xy 161.181796 -386.691886) (xy 161.162173 -386.672923) (xy 161.128736 -386.629806) (xy 161.102828 -386.581786)
			(xy 161.085152 -386.530165) (xy 161.076187 -386.476343) (xy 161.075624 -386.449062) (xy 161.075878 -386.43687)
			(xy 161.076132 -386.427218) (xy 161.070036 -386.409184) (xy 161.011362 -386.341874) (xy 160.994598 -386.333238)
			(xy 160.984692 -386.332222) (xy 160.957789 -386.328825) (xy 160.905503 -386.314466) (xy 160.85626 -386.291772)
			(xy 160.811377 -386.261351) (xy 160.772056 -386.224017) (xy 160.739351 -386.18077) (xy 160.714136 -386.132768)
			(xy 160.697088 -386.081297) (xy 160.692338 -386.0546) (xy 160.690814 -386.045202) (xy 160.418018 -385.57327)
			(xy 160.410652 -385.567428) (xy 160.391895 -385.551603) (xy 160.358778 -385.515389) (xy 160.331367 -385.474686)
			(xy 160.310263 -385.430383) (xy 160.295927 -385.38345) (xy 160.288674 -385.334916) (xy 160.288224 -385.31038)
			(xy 159.77143 -385.31038) (xy 160.02 -385.740402) (xy 160.027366 -385.746244) (xy 160.046161 -385.762026)
			(xy 160.079275 -385.798249) (xy 160.10668 -385.838962) (xy 160.127778 -385.883273) (xy 160.142105 -385.930213)
			(xy 160.149349 -385.978753) (xy 160.149794 -386.003292) (xy 160.14954 -386.015484) (xy 160.149286 -386.025136)
			(xy 160.155382 -386.04317) (xy 160.214056 -386.11048) (xy 160.23082 -386.119116) (xy 160.240472 -386.120132)
			(xy 160.267231 -386.123514) (xy 160.319253 -386.137732) (xy 160.368279 -386.160204) (xy 160.413009 -386.190332)
			(xy 160.452258 -386.22732) (xy 160.484984 -386.270185) (xy 160.510321 -386.317794) (xy 160.527597 -386.368882)
			(xy 160.536354 -386.422097) (xy 160.53689 -386.449062) (xy 160.53638 -386.475049) (xy 160.52825 -386.526384)
			(xy 160.512189 -386.575814) (xy 160.488593 -386.622124) (xy 160.458043 -386.664172) (xy 160.421292 -386.700923)
			(xy 160.379244 -386.731473) (xy 160.332934 -386.755069) (xy 160.283504 -386.77113) (xy 160.232169 -386.77926)
			(xy 160.180195 -386.77926) (xy 160.12886 -386.77113) (xy 160.07943 -386.755069) (xy 160.03312 -386.731473)
			(xy 159.991072 -386.700923) (xy 159.954321 -386.664172) (xy 159.923771 -386.622124) (xy 159.900175 -386.575814)
			(xy 159.884114 -386.526384) (xy 159.875984 -386.475049) (xy 159.875474 -386.449062) (xy 159.875728 -386.43687)
			(xy 159.875982 -386.427218) (xy 159.869886 -386.409184) (xy 159.811212 -386.341874) (xy 159.794448 -386.333238)
			(xy 159.784796 -386.332222) (xy 159.757893 -386.328822) (xy 159.705608 -386.314464) (xy 159.656364 -386.29177)
			(xy 159.611481 -386.261349) (xy 159.57216 -386.224016) (xy 159.539455 -386.180769) (xy 159.51424 -386.132768)
			(xy 159.497192 -386.081297) (xy 159.492442 -386.0546) (xy 159.490918 -386.045202) (xy 159.218122 -385.57327)
			(xy 159.210756 -385.567428) (xy 159.192 -385.551602) (xy 159.158883 -385.515389) (xy 159.131472 -385.474685)
			(xy 159.110367 -385.430382) (xy 159.096032 -385.38345) (xy 159.088778 -385.334916) (xy 159.088328 -385.31038)
			(xy 158.57128 -385.31038) (xy 158.81985 -385.740402) (xy 158.827216 -385.746244) (xy 158.846001 -385.762038)
			(xy 158.879117 -385.798257) (xy 158.906526 -385.838967) (xy 158.927625 -385.883276) (xy 158.941954 -385.930215)
			(xy 158.949199 -385.978754) (xy 158.949644 -386.003292) (xy 158.94939 -386.015484) (xy 158.949136 -386.025136)
			(xy 158.955232 -386.04317) (xy 159.013906 -386.11048) (xy 159.03067 -386.119116) (xy 159.040576 -386.120132)
			(xy 159.067335 -386.123511) (xy 159.119358 -386.13773) (xy 159.168384 -386.160201) (xy 159.213114 -386.190331)
			(xy 159.252362 -386.227318) (xy 159.285088 -386.270185) (xy 159.310425 -386.317793) (xy 159.327701 -386.368882)
			(xy 159.336458 -386.422097) (xy 159.336994 -386.449062) (xy 159.33657 -386.473264) (xy 159.329496 -386.521149)
			(xy 159.315509 -386.567488) (xy 159.294909 -386.61129) (xy 159.281876 -386.631688) (xy 159.277089 -386.639645)
			(xy 159.273054 -386.657756) (xy 159.274002 -386.666994) (xy 159.27832 -386.697982) (xy 159.279996 -386.70728)
			(xy 159.289281 -386.723721) (xy 159.296354 -386.729986) (xy 159.31844 -386.74867) (xy 159.358212 -386.790681)
			(xy 159.392375 -386.837369) (xy 159.420383 -386.887988) (xy 159.44179 -386.941733) (xy 159.456256 -386.997747)
			(xy 159.463549 -387.055136) (xy 159.463994 -387.084062) (xy 159.463399 -387.117383) (xy 159.453738 -387.183321)
			(xy 159.434614 -387.247161) (xy 159.421068 -387.27761) (xy 159.416823 -387.288076) (xy 159.416937 -387.310634)
			(xy 159.426669 -387.330985) (xy 159.435038 -387.33857) (xy 159.457276 -387.357254) (xy 159.497338 -387.399308)
			(xy 159.531759 -387.446093) (xy 159.559984 -387.496857) (xy 159.581561 -387.550783) (xy 159.596143 -387.607005)
			(xy 159.603495 -387.664621) (xy 159.603948 -387.693662) (xy 159.603473 -387.722667) (xy 159.596162 -387.780214)
			(xy 159.58164 -387.836377) (xy 159.560139 -387.890255) (xy 159.532004 -387.940986) (xy 159.497687 -387.987756)
			(xy 159.457735 -388.029815) (xy 159.435546 -388.0485) (xy 159.428434 -388.054088) (xy 159.41929 -388.069328)
			(xy 159.40405 -388.152132) (xy 159.406844 -388.169404) (xy 159.411416 -388.177532) (xy 159.423989 -388.20072)
			(xy 159.441864 -388.25034) (xy 159.450966 -388.302291) (xy 159.451548 -388.328662) (xy 160.040828 -388.328662)
			(xy 160.04135 -388.303407) (xy 160.049663 -388.253585) (xy 160.066064 -388.205811) (xy 160.090105 -388.161388)
			(xy 160.121129 -388.121528) (xy 160.158291 -388.087318) (xy 160.200577 -388.059692) (xy 160.246833 -388.039402)
			(xy 160.295798 -388.027002) (xy 160.346136 -388.022831) (xy 160.396474 -388.027002) (xy 160.445439 -388.039402)
			(xy 160.491695 -388.059692) (xy 160.533981 -388.087318) (xy 160.571143 -388.121528) (xy 160.602167 -388.161388)
			(xy 160.626208 -388.205811) (xy 160.642609 -388.253585) (xy 160.650922 -388.303407) (xy 160.651444 -388.328662)
			(xy 160.651341 -388.339943) (xy 160.649689 -388.362445) (xy 160.648142 -388.37362) (xy 160.646872 -388.38251)
			(xy 160.650428 -388.400036) (xy 160.693862 -388.470902) (xy 160.707578 -388.482078) (xy 160.716214 -388.484872)
			(xy 160.73847 -388.49278) (xy 160.780389 -388.514538) (xy 160.818461 -388.54249) (xy 160.851777 -388.575968)
			(xy 160.879543 -388.614174) (xy 160.890712 -388.634986) (xy 160.89122 -388.636002) (xy 161.28365 -389.314944)
			(xy 161.296457 -389.338285) (xy 161.314684 -389.388304) (xy 161.323951 -389.440726) (xy 161.324544 -389.467344)
			(xy 161.324102 -389.491349) (xy 161.316582 -389.538767) (xy 161.301734 -389.584424) (xy 161.279924 -389.627195)
			(xy 161.25169 -389.666026) (xy 161.217726 -389.69996) (xy 161.178871 -389.728161) (xy 161.136082 -389.749934)
			(xy 161.090412 -389.764743) (xy 161.042988 -389.772222) (xy 161.018982 -389.772652) (xy 160.995451 -389.772183)
			(xy 160.948944 -389.76498) (xy 160.904096 -389.750716) (xy 160.861973 -389.729731) (xy 160.823574 -389.702523)
			(xy 160.789811 -389.669738) (xy 160.761487 -389.632155) (xy 160.749996 -389.611616) (xy 160.749742 -389.611108)
			(xy 160.749234 -389.610346) (xy 160.35147 -388.922006) (xy 160.339595 -388.899329) (xy 160.322743 -388.850996)
			(xy 160.31417 -388.800533) (xy 160.313624 -388.77494) (xy 160.313624 -388.774432) (xy 160.313715 -388.763087)
			(xy 160.31537 -388.740458) (xy 160.316926 -388.72922) (xy 160.318196 -388.72033) (xy 160.31464 -388.703058)
			(xy 160.271206 -388.631938) (xy 160.257236 -388.621016) (xy 160.248854 -388.617968) (xy 160.226454 -388.609929)
			(xy 160.184236 -388.587971) (xy 160.145938 -388.559724) (xy 160.112492 -388.525874) (xy 160.084707 -388.48724)
			(xy 160.063258 -388.444761) (xy 160.048665 -388.399467) (xy 160.041281 -388.352456) (xy 160.040828 -388.328662)
			(xy 159.451548 -388.328662) (xy 159.451445 -388.339943) (xy 159.449793 -388.362445) (xy 159.448246 -388.37362)
			(xy 159.446976 -388.38251) (xy 159.450532 -388.400036) (xy 159.493966 -388.470902) (xy 159.507682 -388.482078)
			(xy 159.516318 -388.484872) (xy 159.538574 -388.492778) (xy 159.580494 -388.514537) (xy 159.618565 -388.542489)
			(xy 159.651881 -388.575967) (xy 159.679647 -388.614174) (xy 159.690816 -388.634986) (xy 159.691324 -388.636002)
			(xy 160.083754 -389.314944) (xy 160.096562 -389.338285) (xy 160.114788 -389.388304) (xy 160.124055 -389.440726)
			(xy 160.124648 -389.467344) (xy 160.124202 -389.491349) (xy 160.116682 -389.538767) (xy 160.101834 -389.584423)
			(xy 160.080025 -389.627194) (xy 160.051791 -389.666025) (xy 160.017828 -389.699959) (xy 159.978973 -389.72816)
			(xy 159.936184 -389.749933) (xy 159.890515 -389.764742) (xy 159.843091 -389.772222) (xy 159.819086 -389.772652)
			(xy 159.795555 -389.77218) (xy 159.749049 -389.764977) (xy 159.704201 -389.750714) (xy 159.662077 -389.72973)
			(xy 159.623678 -389.702522) (xy 159.589916 -389.669737) (xy 159.561591 -389.632154) (xy 159.5501 -389.611616)
			(xy 159.549846 -389.611108) (xy 159.549338 -389.610346) (xy 159.151574 -388.922006) (xy 159.139699 -388.899329)
			(xy 159.122848 -388.850996) (xy 159.114274 -388.800533) (xy 159.113728 -388.77494) (xy 159.113728 -388.774432)
			(xy 159.113819 -388.763087) (xy 159.115474 -388.740458) (xy 159.11703 -388.72922) (xy 159.1183 -388.72033)
			(xy 159.114744 -388.703058) (xy 159.07131 -388.631938) (xy 159.05734 -388.621016) (xy 159.048958 -388.617968)
			(xy 159.026559 -388.609926) (xy 158.98434 -388.587969) (xy 158.946043 -388.559723) (xy 158.912596 -388.525873)
			(xy 158.884811 -388.48724) (xy 158.863362 -388.444761) (xy 158.848769 -388.399466) (xy 158.841385 -388.352456)
			(xy 158.840932 -388.328662) (xy 158.841494 -388.302289) (xy 158.850578 -388.25033) (xy 158.868468 -388.20071)
			(xy 158.881064 -388.177532) (xy 158.885636 -388.169404) (xy 158.88843 -388.152132) (xy 158.87319 -388.069328)
			(xy 158.864046 -388.054088) (xy 158.856934 -388.0485) (xy 158.83477 -388.029786) (xy 158.794822 -387.987727)
			(xy 158.760503 -387.940961) (xy 158.732362 -387.890236) (xy 158.710851 -387.836364) (xy 158.696314 -387.780208)
			(xy 158.688983 -387.722666) (xy 158.688532 -387.693662) (xy 158.689133 -387.660341) (xy 158.698791 -387.594403)
			(xy 158.717913 -387.530563) (xy 158.731458 -387.500114) (xy 158.735704 -387.489647) (xy 158.7356 -387.467087)
			(xy 158.725862 -387.446735) (xy 158.717488 -387.439154) (xy 158.695218 -387.420506) (xy 158.655157 -387.378446)
			(xy 158.620739 -387.331655) (xy 158.592517 -387.280885) (xy 158.570945 -387.226953) (xy 158.55637 -387.170725)
			(xy 158.549026 -387.113105) (xy 158.548578 -387.084062) (xy 158.54902 -387.055135) (xy 158.556304 -386.997742)
			(xy 158.570764 -386.941725) (xy 158.592169 -386.887977) (xy 158.620178 -386.837355) (xy 158.654343 -386.790668)
			(xy 158.694121 -386.748659) (xy 158.716218 -386.729986) (xy 158.723183 -386.723632) (xy 158.732446 -386.707233)
			(xy 158.734252 -386.697982) (xy 158.73857 -386.666994) (xy 158.739471 -386.657757) (xy 158.735448 -386.639658)
			(xy 158.730696 -386.631688) (xy 158.717708 -386.611266) (xy 158.697128 -386.567464) (xy 158.683141 -386.521133)
			(xy 158.676045 -386.47326) (xy 158.675578 -386.449062) (xy 158.675832 -386.43687) (xy 158.676086 -386.427218)
			(xy 158.66999 -386.409184) (xy 158.611316 -386.341874) (xy 158.594552 -386.333238) (xy 158.584646 -386.332222)
			(xy 158.557738 -386.328862) (xy 158.505452 -386.314496) (xy 158.456208 -386.291795) (xy 158.411326 -386.261368)
			(xy 158.372006 -386.224029) (xy 158.339302 -386.180778) (xy 158.314089 -386.132773) (xy 158.297042 -386.081298)
			(xy 158.292292 -386.0546) (xy 158.290768 -386.045202) (xy 158.017972 -385.57327) (xy 158.010606 -385.567428)
			(xy 157.991861 -385.55159) (xy 157.95874 -385.51538) (xy 157.931327 -385.47468) (xy 157.91022 -385.430379)
			(xy 157.895883 -385.383448) (xy 157.888629 -385.334916) (xy 157.888178 -385.31038) (xy 157.371384 -385.31038)
			(xy 157.619954 -385.740402) (xy 157.62732 -385.746244) (xy 157.646106 -385.762037) (xy 157.679222 -385.798256)
			(xy 157.70663 -385.838966) (xy 157.72773 -385.883276) (xy 157.742058 -385.930214) (xy 157.749303 -385.978754)
			(xy 157.749748 -386.003292) (xy 157.749494 -386.015484) (xy 157.74924 -386.025136) (xy 157.755336 -386.04317)
			(xy 157.81401 -386.11048) (xy 157.830774 -386.119116) (xy 157.840426 -386.120132) (xy 157.867191 -386.12347)
			(xy 157.919214 -386.137696) (xy 157.96824 -386.160175) (xy 158.012969 -386.19031) (xy 158.052216 -386.227303)
			(xy 158.084941 -386.270174) (xy 158.110277 -386.317786) (xy 158.127552 -386.368878) (xy 158.136309 -386.422095)
			(xy 158.136844 -386.449062) (xy 158.136299 -386.476347) (xy 158.127345 -386.530176) (xy 158.109675 -386.581805)
			(xy 158.083768 -386.629832) (xy 158.050326 -386.672953) (xy 158.030672 -386.691886) (xy 158.023285 -386.69942)
			(xy 158.01475 -386.71869) (xy 158.014162 -386.729224) (xy 158.014162 -386.8039) (xy 158.014689 -386.81445)
			(xy 158.023227 -386.833744) (xy 158.030672 -386.841238) (xy 158.050319 -386.860177) (xy 158.08375 -386.903302)
			(xy 158.109653 -386.951328) (xy 158.127323 -387.002954) (xy 158.136283 -387.056779) (xy 158.136844 -387.084062)
			(xy 158.136395 -387.108178) (xy 158.129399 -387.1559) (xy 158.115549 -387.202101) (xy 158.095139 -387.245802)
			(xy 158.082234 -387.26618) (xy 158.076392 -387.27507) (xy 158.072836 -387.295136) (xy 158.093918 -387.387338)
			(xy 158.10611 -387.404102) (xy 158.115 -387.409436) (xy 158.135793 -387.422303) (xy 158.1737 -387.453189)
			(xy 158.206645 -387.489322) (xy 158.233908 -387.529913) (xy 158.254894 -387.574077) (xy 158.269147 -387.620851)
			(xy 158.276355 -387.669214) (xy 158.276798 -387.693662) (xy 158.276378 -387.718035) (xy 158.269232 -387.766255)
			(xy 158.255089 -387.812904) (xy 158.234256 -387.856974) (xy 158.207183 -387.897511) (xy 158.174455 -387.933638)
			(xy 158.155894 -387.94944) (xy 158.147004 -387.956552) (xy 158.137606 -387.97611) (xy 158.134812 -388.075424)
			(xy 158.143448 -388.09549) (xy 158.15183 -388.10311) (xy 158.170274 -388.120577) (xy 158.201622 -388.160546)
			(xy 158.225921 -388.205153) (xy 158.242498 -388.253168) (xy 158.250898 -388.303264) (xy 158.251398 -388.328662)
			(xy 158.251294 -388.339943) (xy 158.249643 -388.362445) (xy 158.248096 -388.37362) (xy 158.246826 -388.38251)
			(xy 158.250382 -388.400036) (xy 158.293816 -388.470902) (xy 158.307532 -388.482078) (xy 158.316168 -388.484872)
			(xy 158.338415 -388.492802) (xy 158.380336 -388.514554) (xy 158.418409 -388.5425) (xy 158.451727 -388.575973)
			(xy 158.479495 -388.614176) (xy 158.490666 -388.634986) (xy 158.491174 -388.636002) (xy 158.883604 -389.314944)
			(xy 158.896337 -389.33831) (xy 158.914452 -389.388337) (xy 158.923662 -389.440741) (xy 158.924244 -389.467344)
			(xy 158.923778 -389.491335) (xy 158.916267 -389.538724) (xy 158.901435 -389.584356) (xy 158.879649 -389.627106)
			(xy 158.851445 -389.665923) (xy 158.817517 -389.69985) (xy 158.778699 -389.728054) (xy 158.735949 -389.749838)
			(xy 158.690317 -389.764668) (xy 158.642927 -389.772179) (xy 158.618936 -389.772652) (xy 158.595404 -389.77222)
			(xy 158.548895 -389.76501) (xy 158.504047 -389.75074) (xy 158.461923 -389.729749) (xy 158.423525 -389.702535)
			(xy 158.389763 -389.669745) (xy 158.36144 -389.632157) (xy 158.34995 -389.611616) (xy 158.349696 -389.611108)
			(xy 158.349188 -389.610346) (xy 157.951424 -388.922006) (xy 157.939511 -388.899337) (xy 157.922572 -388.851012)
			(xy 157.913912 -388.800542) (xy 157.913324 -388.77494) (xy 157.913324 -388.774432) (xy 157.913481 -388.763083)
			(xy 157.915258 -388.740453) (xy 157.91688 -388.72922) (xy 157.91815 -388.72033) (xy 157.914594 -388.703058)
			(xy 157.87116 -388.631938) (xy 157.85719 -388.621016) (xy 157.848808 -388.617968) (xy 157.826399 -388.609955)
			(xy 157.784181 -388.587991) (xy 157.745886 -388.559739) (xy 157.712441 -388.525885) (xy 157.684658 -388.487248)
			(xy 157.66321 -388.444766) (xy 157.648618 -388.399469) (xy 157.641235 -388.352457) (xy 157.640782 -388.328662)
			(xy 157.641314 -388.303267) (xy 157.649722 -388.253179) (xy 157.666301 -388.205172) (xy 157.690594 -388.160569)
			(xy 157.721931 -388.120599) (xy 157.74035 -388.10311) (xy 157.748732 -388.09549) (xy 157.757368 -388.075424)
			(xy 157.754574 -387.97611) (xy 157.745176 -387.956552) (xy 157.736286 -387.94944) (xy 157.717756 -387.933604)
			(xy 157.685033 -387.897481) (xy 157.657961 -387.85695) (xy 157.637125 -387.812887) (xy 157.622976 -387.766245)
			(xy 157.61582 -387.718032) (xy 157.615382 -387.693662) (xy 157.615791 -387.669544) (xy 157.622798 -387.62182)
			(xy 157.63666 -387.575619) (xy 157.657082 -387.53192) (xy 157.669992 -387.511544) (xy 157.675834 -387.502654)
			(xy 157.67939 -387.482588) (xy 157.658308 -387.390386) (xy 157.646116 -387.373622) (xy 157.637226 -387.368288)
			(xy 157.616427 -387.355431) (xy 157.578523 -387.32454) (xy 157.545582 -387.288404) (xy 157.518321 -387.247811)
			(xy 157.497336 -387.203647) (xy 157.483083 -387.156873) (xy 157.475873 -387.10851) (xy 157.475428 -387.084062)
			(xy 157.475966 -387.056777) (xy 157.484918 -387.002946) (xy 157.502588 -386.951316) (xy 157.528498 -386.903289)
			(xy 157.561943 -386.86017) (xy 157.5816 -386.841238) (xy 157.588987 -386.833704) (xy 157.59752 -386.814433)
			(xy 157.59811 -386.8039) (xy 157.59811 -386.729224) (xy 157.597578 -386.718675) (xy 157.589045 -386.69938)
			(xy 157.5816 -386.691886) (xy 157.561978 -386.672922) (xy 157.52854 -386.629806) (xy 157.502632 -386.581786)
			(xy 157.484956 -386.530165) (xy 157.475991 -386.476343) (xy 157.475428 -386.449062) (xy 157.475682 -386.43687)
			(xy 157.475936 -386.427218) (xy 157.46984 -386.409184) (xy 157.411166 -386.341874) (xy 157.394402 -386.333238)
			(xy 157.38475 -386.332222) (xy 157.357842 -386.328859) (xy 157.305556 -386.314493) (xy 157.256313 -386.291793)
			(xy 157.21143 -386.261367) (xy 157.172111 -386.224028) (xy 157.139406 -386.180777) (xy 157.114193 -386.132772)
			(xy 157.097146 -386.081298) (xy 157.092396 -386.0546) (xy 157.090872 -386.045202) (xy 156.818076 -385.57327)
			(xy 156.81071 -385.567428) (xy 156.791965 -385.551589) (xy 156.758845 -385.51538) (xy 156.731431 -385.474679)
			(xy 156.710324 -385.430379) (xy 156.695987 -385.383448) (xy 156.688733 -385.334916) (xy 156.688282 -385.31038)
			(xy 156.171198 -385.31038) (xy 156.419804 -385.740402) (xy 156.42717 -385.746244) (xy 156.445966 -385.762025)
			(xy 156.479079 -385.798248) (xy 156.506485 -385.838961) (xy 156.527582 -385.883273) (xy 156.541909 -385.930213)
			(xy 156.549153 -385.978753) (xy 156.549598 -386.003292) (xy 156.549344 -386.015484) (xy 156.54909 -386.025136)
			(xy 156.555186 -386.04317) (xy 156.61386 -386.11048) (xy 156.630624 -386.119116) (xy 156.64053 -386.120132)
			(xy 156.667295 -386.123467) (xy 156.719319 -386.137694) (xy 156.768344 -386.160173) (xy 156.813073 -386.190308)
			(xy 156.85232 -386.227302) (xy 156.885045 -386.270173) (xy 156.910381 -386.317785) (xy 156.927656 -386.368877)
			(xy 156.936413 -386.422095) (xy 156.936948 -386.449062) (xy 156.936402 -386.476346) (xy 156.927448 -386.530176)
			(xy 156.909778 -386.581804) (xy 156.883871 -386.629831) (xy 156.85043 -386.672953) (xy 156.830776 -386.691886)
			(xy 156.82339 -386.699421) (xy 156.814854 -386.71869) (xy 156.814266 -386.729224) (xy 156.814266 -386.8039)
			(xy 156.814792 -386.81445) (xy 156.82333 -386.833744) (xy 156.830776 -386.841238) (xy 156.850424 -386.860176)
			(xy 156.883855 -386.903301) (xy 156.909757 -386.951328) (xy 156.927427 -387.002954) (xy 156.936387 -387.056779)
			(xy 156.936948 -387.084062) (xy 156.936498 -387.108178) (xy 156.929502 -387.1559) (xy 156.915652 -387.202101)
			(xy 156.895243 -387.245802) (xy 156.882338 -387.26618) (xy 156.876496 -387.27507) (xy 156.87294 -387.295136)
			(xy 156.894022 -387.387338) (xy 156.906214 -387.404102) (xy 156.915104 -387.409436) (xy 156.935898 -387.422302)
			(xy 156.973805 -387.453188) (xy 157.006749 -387.489321) (xy 157.034012 -387.529913) (xy 157.054998 -387.574077)
			(xy 157.069251 -387.620851) (xy 157.076459 -387.669214) (xy 157.076902 -387.693662) (xy 157.07648 -387.718035)
			(xy 157.069335 -387.766255) (xy 157.055192 -387.812904) (xy 157.034359 -387.856974) (xy 157.007286 -387.897511)
			(xy 156.974559 -387.933638) (xy 156.955998 -387.94944) (xy 156.947108 -387.956552) (xy 156.93771 -387.97611)
			(xy 156.934916 -388.075424) (xy 156.943552 -388.09549) (xy 156.951934 -388.10311) (xy 156.970379 -388.120576)
			(xy 157.001727 -388.160545) (xy 157.026025 -388.205153) (xy 157.042602 -388.253167) (xy 157.051002 -388.303264)
			(xy 157.051502 -388.328662) (xy 157.051398 -388.339943) (xy 157.049747 -388.362445) (xy 157.0482 -388.37362)
			(xy 157.04693 -388.38251) (xy 157.050486 -388.400036) (xy 157.09392 -388.470902) (xy 157.107636 -388.482078)
			(xy 157.116272 -388.484872) (xy 157.13852 -388.4928) (xy 157.180441 -388.514553) (xy 157.218514 -388.542499)
			(xy 157.251831 -388.575973) (xy 157.279599 -388.614176) (xy 157.29077 -388.634986) (xy 157.291278 -388.636002)
			(xy 157.683708 -389.314944) (xy 157.696441 -389.33831) (xy 157.714556 -389.388337) (xy 157.723766 -389.440741)
			(xy 157.724348 -389.467344) (xy 157.723878 -389.491334) (xy 157.716367 -389.538724) (xy 157.701536 -389.584355)
			(xy 157.67975 -389.627105) (xy 157.651546 -389.665922) (xy 157.617618 -389.699849) (xy 157.578802 -389.728052)
			(xy 157.536051 -389.749837) (xy 157.49042 -389.764668) (xy 157.44303 -389.772178) (xy 157.41904 -389.772652)
			(xy 157.395508 -389.772217) (xy 157.348999 -389.765007) (xy 157.304151 -389.750738) (xy 157.262027 -389.729747)
			(xy 157.223629 -389.702534) (xy 157.189867 -389.669744) (xy 157.161545 -389.632156) (xy 157.150054 -389.611616)
			(xy 157.1498 -389.611108) (xy 157.149292 -389.610346) (xy 156.751528 -388.922006) (xy 156.739615 -388.899337)
			(xy 156.722676 -388.851012) (xy 156.714016 -388.800542) (xy 156.713428 -388.77494) (xy 156.713428 -388.774432)
			(xy 156.713585 -388.763083) (xy 156.715362 -388.740453) (xy 156.716984 -388.72922) (xy 156.718254 -388.72033)
			(xy 156.714698 -388.703058) (xy 156.671264 -388.631938) (xy 156.657294 -388.621016) (xy 156.648912 -388.617968)
			(xy 156.626503 -388.609953) (xy 156.584286 -388.58799) (xy 156.54599 -388.559738) (xy 156.512545 -388.525884)
			(xy 156.484762 -388.487247) (xy 156.463314 -388.444766) (xy 156.448722 -388.399469) (xy 156.441339 -388.352456)
			(xy 156.440886 -388.328662) (xy 156.441416 -388.303267) (xy 156.449825 -388.253179) (xy 156.466404 -388.205171)
			(xy 156.490697 -388.160569) (xy 156.522035 -388.120599) (xy 156.540454 -388.10311) (xy 156.548836 -388.09549)
			(xy 156.557472 -388.075424) (xy 156.554678 -387.97611) (xy 156.54528 -387.956552) (xy 156.53639 -387.94944)
			(xy 156.51786 -387.933603) (xy 156.485137 -387.89748) (xy 156.458065 -387.856949) (xy 156.437229 -387.812887)
			(xy 156.42308 -387.766245) (xy 156.415924 -387.718032) (xy 156.415486 -387.693662) (xy 156.415894 -387.669544)
			(xy 156.422902 -387.62182) (xy 156.436764 -387.575619) (xy 156.457186 -387.53192) (xy 156.470096 -387.511544)
			(xy 156.475938 -387.502654) (xy 156.479494 -387.482588) (xy 156.458412 -387.390386) (xy 156.44622 -387.373622)
			(xy 156.43733 -387.368288) (xy 156.416532 -387.355429) (xy 156.378628 -387.324539) (xy 156.345686 -387.288403)
			(xy 156.318426 -387.247811) (xy 156.29744 -387.203646) (xy 156.283187 -387.156873) (xy 156.275977 -387.10851)
			(xy 156.275532 -387.084062) (xy 156.276069 -387.056777) (xy 156.28502 -387.002946) (xy 156.302691 -386.951316)
			(xy 156.328602 -386.903289) (xy 156.362047 -386.86017) (xy 156.381704 -386.841238) (xy 156.389091 -386.833705)
			(xy 156.397624 -386.814433) (xy 156.398214 -386.8039) (xy 156.398214 -386.729224) (xy 156.397681 -386.718675)
			(xy 156.389148 -386.69938) (xy 156.381704 -386.691886) (xy 156.362064 -386.67294) (xy 156.328633 -386.629816)
			(xy 156.30273 -386.581792) (xy 156.285058 -386.530168) (xy 156.276095 -386.476344) (xy 156.275532 -386.449062)
			(xy 156.275786 -386.43687) (xy 156.27604 -386.427218) (xy 156.269944 -386.409184) (xy 156.21127 -386.341874)
			(xy 156.194506 -386.333238) (xy 156.1846 -386.332222) (xy 156.157698 -386.328819) (xy 156.105412 -386.314461)
			(xy 156.056169 -386.291768) (xy 156.011286 -386.261348) (xy 155.971965 -386.224015) (xy 155.939259 -386.180769)
			(xy 155.914045 -386.132767) (xy 155.896996 -386.081297) (xy 155.892246 -386.0546) (xy 155.890722 -386.045202)
			(xy 155.617672 -385.572762) (xy 155.61056 -385.56692) (xy 155.59182 -385.551149) (xy 155.558768 -385.515004)
			(xy 155.531413 -385.474377) (xy 155.510355 -385.430156) (xy 155.496056 -385.383311) (xy 155.488829 -385.334869)
			(xy 155.488386 -385.31038) (xy 154.971338 -385.31038) (xy 155.219908 -385.740402) (xy 155.227274 -385.746244)
			(xy 155.246071 -385.762024) (xy 155.279184 -385.798247) (xy 155.306589 -385.838961) (xy 155.327686 -385.883273)
			(xy 155.342013 -385.930213) (xy 155.349257 -385.978753) (xy 155.349702 -386.003292) (xy 155.349448 -386.015484)
			(xy 155.349194 -386.025136) (xy 155.35529 -386.04317) (xy 155.413964 -386.11048) (xy 155.430728 -386.119116)
			(xy 155.440634 -386.120132) (xy 155.4674 -386.123464) (xy 155.519423 -386.137691) (xy 155.568449 -386.160171)
			(xy 155.613178 -386.190307) (xy 155.652425 -386.227301) (xy 155.685149 -386.270172) (xy 155.710485 -386.317785)
			(xy 155.72776 -386.368877) (xy 155.736517 -386.422095) (xy 155.737052 -386.449062) (xy 155.736504 -386.476346)
			(xy 155.727551 -386.530176) (xy 155.709881 -386.581804) (xy 155.683974 -386.629831) (xy 155.650534 -386.672953)
			(xy 155.63088 -386.691886) (xy 155.62348 -386.699408) (xy 155.614955 -386.718688) (xy 155.61437 -386.729224)
			(xy 155.61437 -386.8039) (xy 155.614894 -386.81445) (xy 155.623434 -386.833745) (xy 155.63088 -386.841238)
			(xy 155.650528 -386.860175) (xy 155.683959 -386.903301) (xy 155.709861 -386.951328) (xy 155.727531 -387.002953)
			(xy 155.736491 -387.056779) (xy 155.737052 -387.084062) (xy 155.736602 -387.108178) (xy 155.729606 -387.1559)
			(xy 155.715756 -387.202101) (xy 155.695346 -387.245802) (xy 155.682442 -387.26618) (xy 155.6766 -387.27507)
			(xy 155.673044 -387.295136) (xy 155.694126 -387.387338) (xy 155.706318 -387.404102) (xy 155.715208 -387.409436)
			(xy 155.736003 -387.4223) (xy 155.77391 -387.453187) (xy 155.806854 -387.489321) (xy 155.834116 -387.529912)
			(xy 155.855103 -387.574077) (xy 155.869355 -387.620851) (xy 155.876563 -387.669214) (xy 155.877006 -387.693662)
			(xy 155.876583 -387.718035) (xy 155.869437 -387.766254) (xy 155.855295 -387.812904) (xy 155.834462 -387.856974)
			(xy 155.80739 -387.897511) (xy 155.774663 -387.933638) (xy 155.756102 -387.94944) (xy 155.747212 -387.956552)
			(xy 155.737814 -387.97611) (xy 155.73502 -388.075424) (xy 155.743656 -388.09549) (xy 155.752038 -388.10311)
			(xy 155.770484 -388.120575) (xy 155.801831 -388.160545) (xy 155.826129 -388.205153) (xy 155.842707 -388.253167)
			(xy 155.851106 -388.303264) (xy 155.851606 -388.328662) (xy 155.851502 -388.339943) (xy 155.849851 -388.362445)
			(xy 155.848304 -388.37362) (xy 155.847034 -388.382764) (xy 155.850336 -388.400036) (xy 155.894024 -388.471156)
			(xy 155.90774 -388.482078) (xy 155.916376 -388.484872) (xy 155.94454 -388.49507) (xy 155.996487 -388.524881)
			(xy 156.0195 -388.544054) (xy 156.040985 -388.563635) (xy 156.076798 -388.609414) (xy 156.09062 -388.634986)
			(xy 156.091382 -388.636256) (xy 156.483558 -389.314944) (xy 156.496366 -389.338285) (xy 156.514592 -389.388304)
			(xy 156.523859 -389.440726) (xy 156.524452 -389.467344) (xy 156.524002 -389.491349) (xy 156.516482 -389.538766)
			(xy 156.501634 -389.584422) (xy 156.479825 -389.627193) (xy 156.451592 -389.666023) (xy 156.41763 -389.699957)
			(xy 156.378776 -389.728158) (xy 156.335987 -389.749932) (xy 156.290319 -389.764741) (xy 156.242895 -389.772222)
			(xy 156.21889 -389.772652) (xy 156.195359 -389.772177) (xy 156.148853 -389.764975) (xy 156.104005 -389.750712)
			(xy 156.061882 -389.729728) (xy 156.023482 -389.702521) (xy 155.98972 -389.669737) (xy 155.961395 -389.632154)
			(xy 155.949904 -389.611616) (xy 155.94965 -389.611108) (xy 155.949142 -389.610346) (xy 155.551632 -388.921752)
			(xy 155.541061 -388.901824) (xy 155.525257 -388.859575) (xy 155.515849 -388.815459) (xy 155.51404 -388.792974)
			(xy 155.513532 -388.781798) (xy 155.513532 -388.774432) (xy 155.513623 -388.763087) (xy 155.515278 -388.740458)
			(xy 155.516834 -388.72922) (xy 155.518104 -388.72033) (xy 155.514548 -388.703058) (xy 155.471114 -388.631938)
			(xy 155.457398 -388.620762) (xy 155.448762 -388.617968) (xy 155.426358 -388.609977) (xy 155.384187 -388.587972)
			(xy 155.34594 -388.559694) (xy 155.31254 -388.525827) (xy 155.284797 -388.487189) (xy 155.263382 -388.444717)
			(xy 155.248812 -388.399437) (xy 155.241441 -388.352445) (xy 155.24099 -388.328662) (xy 155.241519 -388.303267)
			(xy 155.249928 -388.253179) (xy 155.266507 -388.205171) (xy 155.290801 -388.160568) (xy 155.322138 -388.120599)
			(xy 155.340558 -388.10311) (xy 155.34894 -388.09549) (xy 155.357576 -388.075424) (xy 155.354782 -387.97611)
			(xy 155.345384 -387.956552) (xy 155.336494 -387.94944) (xy 155.317965 -387.933602) (xy 155.285242 -387.89748)
			(xy 155.25817 -387.856949) (xy 155.237334 -387.812886) (xy 155.223184 -387.766245) (xy 155.216028 -387.718032)
			(xy 155.21559 -387.693662) (xy 155.215997 -387.669544) (xy 155.223005 -387.62182) (xy 155.236867 -387.575619)
			(xy 155.257289 -387.53192) (xy 155.2702 -387.511544) (xy 155.276042 -387.502654) (xy 155.279598 -387.482588)
			(xy 155.258516 -387.390386) (xy 155.246324 -387.373622) (xy 155.237434 -387.368288) (xy 155.216636 -387.355428)
			(xy 155.178733 -387.324538) (xy 155.145791 -387.288403) (xy 155.11853 -387.24781) (xy 155.097544 -387.203646)
			(xy 155.083291 -387.156873) (xy 155.076081 -387.10851) (xy 155.075636 -387.084062) (xy 155.076203 -387.056778)
			(xy 155.085152 -387.00295) (xy 155.102818 -386.951322) (xy 155.12872 -386.903295) (xy 155.162156 -386.860172)
			(xy 155.181808 -386.841238) (xy 155.189196 -386.833705) (xy 155.197728 -386.814434) (xy 155.198318 -386.8039)
			(xy 155.198318 -386.729224) (xy 155.197784 -386.718675) (xy 155.189252 -386.69938) (xy 155.181808 -386.691886)
			(xy 155.162169 -386.67294) (xy 155.128737 -386.629816) (xy 155.102834 -386.581792) (xy 155.085162 -386.530168)
			(xy 155.076199 -386.476344) (xy 155.075636 -386.449062) (xy 155.07589 -386.43687) (xy 155.076144 -386.427218)
			(xy 155.070048 -386.409184) (xy 155.011374 -386.341874) (xy 154.99461 -386.333238) (xy 154.984704 -386.332222)
			(xy 154.957802 -386.328816) (xy 154.905517 -386.314458) (xy 154.856273 -386.291766) (xy 154.81139 -386.261346)
			(xy 154.772069 -386.224014) (xy 154.739363 -386.180768) (xy 154.714149 -386.132767) (xy 154.6971 -386.081296)
			(xy 154.69235 -386.0546) (xy 154.690826 -386.045202) (xy 154.41803 -385.57327) (xy 154.410664 -385.567428)
			(xy 154.39191 -385.5516) (xy 154.358792 -385.515388) (xy 154.33138 -385.474684) (xy 154.310276 -385.430382)
			(xy 154.29594 -385.38345) (xy 154.288686 -385.334916) (xy 154.288236 -385.31038) (xy 153.771442 -385.31038)
			(xy 154.020012 -385.740402) (xy 154.027378 -385.746244) (xy 154.046155 -385.762047) (xy 154.079273 -385.798263)
			(xy 154.106684 -385.838971) (xy 154.127785 -385.883279) (xy 154.142115 -385.930216) (xy 154.14936 -385.978754)
			(xy 154.149806 -386.003292) (xy 154.149552 -386.015484) (xy 154.149298 -386.025136) (xy 154.155394 -386.04317)
			(xy 154.214068 -386.11048) (xy 154.230832 -386.119116) (xy 154.240484 -386.120132) (xy 154.267244 -386.123504)
			(xy 154.319267 -386.137724) (xy 154.368293 -386.160197) (xy 154.413022 -386.190327) (xy 154.45227 -386.227316)
			(xy 154.484996 -386.270183) (xy 154.510333 -386.317792) (xy 154.527609 -386.368881) (xy 154.536366 -386.422097)
			(xy 154.536902 -386.449062) (xy 154.53637 -386.476347) (xy 154.527415 -386.530178) (xy 154.509743 -386.581807)
			(xy 154.483832 -386.629834) (xy 154.450386 -386.672954) (xy 154.43073 -386.691886) (xy 154.423337 -386.699415)
			(xy 154.414807 -386.718689) (xy 154.41422 -386.729224) (xy 154.41422 -386.8039) (xy 154.41473 -386.814452)
			(xy 154.423278 -386.833748) (xy 154.43073 -386.841238) (xy 154.450369 -386.860185) (xy 154.483803 -386.903307)
			(xy 154.509708 -386.951331) (xy 154.52738 -387.002955) (xy 154.536341 -387.056779) (xy 154.536902 -387.084062)
			(xy 154.53646 -387.108179) (xy 154.529463 -387.155901) (xy 154.515611 -387.202102) (xy 154.495198 -387.245803)
			(xy 154.482292 -387.26618) (xy 154.47645 -387.27507) (xy 154.472894 -387.295136) (xy 154.493976 -387.387338)
			(xy 154.506168 -387.404102) (xy 154.515058 -387.409436) (xy 154.535864 -387.422282) (xy 154.573769 -387.453174)
			(xy 154.60671 -387.489312) (xy 154.63397 -387.529906) (xy 154.654955 -387.574073) (xy 154.669206 -387.620849)
			(xy 154.676413 -387.669213) (xy 154.676856 -387.693662) (xy 154.676451 -387.718036) (xy 154.669304 -387.766257)
			(xy 154.65516 -387.812907) (xy 154.634323 -387.856978) (xy 154.607247 -387.897514) (xy 154.574515 -387.933639)
			(xy 154.555952 -387.94944) (xy 154.547062 -387.956552) (xy 154.537664 -387.97611) (xy 154.53487 -388.075424)
			(xy 154.543506 -388.09549) (xy 154.551888 -388.10311) (xy 154.570343 -388.120566) (xy 154.601688 -388.160539)
			(xy 154.625983 -388.205149) (xy 154.642558 -388.253166) (xy 154.650957 -388.303263) (xy 154.651456 -388.328662)
			(xy 154.651353 -388.339943) (xy 154.649701 -388.362445) (xy 154.648154 -388.37362) (xy 154.646884 -388.38251)
			(xy 154.65044 -388.400036) (xy 154.693874 -388.470902) (xy 154.70759 -388.482078) (xy 154.716226 -388.484872)
			(xy 154.738466 -388.492821) (xy 154.780388 -388.514568) (xy 154.818463 -388.542509) (xy 154.851782 -388.575978)
			(xy 154.879552 -388.614178) (xy 154.890724 -388.634986) (xy 154.891232 -388.636002) (xy 155.283662 -389.314944)
			(xy 155.29647 -389.338285) (xy 155.314696 -389.388304) (xy 155.323963 -389.440726) (xy 155.324556 -389.467344)
			(xy 155.324102 -389.491349) (xy 155.316582 -389.538765) (xy 155.301735 -389.584421) (xy 155.279926 -389.627191)
			(xy 155.251693 -389.666022) (xy 155.217731 -389.699956) (xy 155.178878 -389.728157) (xy 155.13609 -389.749931)
			(xy 155.090422 -389.76474) (xy 155.042999 -389.772221) (xy 155.018994 -389.772652) (xy 154.995463 -389.772173)
			(xy 154.948957 -389.764972) (xy 154.904109 -389.75071) (xy 154.861986 -389.729727) (xy 154.823587 -389.70252)
			(xy 154.789824 -389.669736) (xy 154.761499 -389.632154) (xy 154.750008 -389.611616) (xy 154.749754 -389.611108)
			(xy 154.749246 -389.610346) (xy 154.351482 -388.922006) (xy 154.339608 -388.899328) (xy 154.322756 -388.850996)
			(xy 154.314182 -388.800533) (xy 154.313636 -388.77494) (xy 154.313636 -388.774432) (xy 154.313727 -388.763087)
			(xy 154.315382 -388.740458) (xy 154.316938 -388.72922) (xy 154.318208 -388.72033) (xy 154.314652 -388.703058)
			(xy 154.271218 -388.631938) (xy 154.257248 -388.621016) (xy 154.248866 -388.617968) (xy 154.226469 -388.609922)
			(xy 154.18425 -388.587966) (xy 154.145952 -388.55972) (xy 154.112505 -388.525871) (xy 154.08472 -388.487238)
			(xy 154.06327 -388.44476) (xy 154.048677 -388.399466) (xy 154.041293 -388.352455) (xy 154.04084 -388.328662)
			(xy 154.041353 -388.303266) (xy 154.049763 -388.253176) (xy 154.066346 -388.205168) (xy 154.090643 -388.160565)
			(xy 154.121986 -388.120598) (xy 154.140408 -388.10311) (xy 154.14879 -388.09549) (xy 154.157426 -388.075424)
			(xy 154.154632 -387.97611) (xy 154.145234 -387.956552) (xy 154.136344 -387.94944) (xy 154.117805 -387.933614)
			(xy 154.085085 -387.897488) (xy 154.058015 -387.856954) (xy 154.037181 -387.812889) (xy 154.023033 -387.766246)
			(xy 154.015878 -387.718033) (xy 154.01544 -387.693662) (xy 154.015855 -387.669545) (xy 154.022862 -387.621821)
			(xy 154.036722 -387.57562) (xy 154.057141 -387.531921) (xy 154.07005 -387.511544) (xy 154.075892 -387.502654)
			(xy 154.079448 -387.482588) (xy 154.058366 -387.390386) (xy 154.046174 -387.373622) (xy 154.037284 -387.368288)
			(xy 154.016498 -387.35541) (xy 153.978592 -387.324525) (xy 153.945647 -387.288394) (xy 153.918384 -387.247804)
			(xy 153.897396 -387.203642) (xy 153.883142 -387.156871) (xy 153.875931 -387.10851) (xy 153.875486 -387.084062)
			(xy 153.876037 -387.056778) (xy 153.884988 -387.002948) (xy 153.902656 -386.951319) (xy 153.928562 -386.903292)
			(xy 153.962004 -386.860171) (xy 153.981658 -386.841238) (xy 153.989039 -386.833698) (xy 153.997576 -386.814432)
			(xy 153.998168 -386.8039) (xy 153.998168 -386.729224) (xy 153.997649 -386.718673) (xy 153.989108 -386.699377)
			(xy 153.981658 -386.691886) (xy 153.962028 -386.67293) (xy 153.928593 -386.62981) (xy 153.902687 -386.581788)
			(xy 153.885013 -386.530166) (xy 153.876049 -386.476344) (xy 153.875486 -386.449062) (xy 153.87574 -386.43687)
			(xy 153.875994 -386.427218) (xy 153.869898 -386.409184) (xy 153.811224 -386.341874) (xy 153.79446 -386.333238)
			(xy 153.784808 -386.332222) (xy 153.757907 -386.328812) (xy 153.705621 -386.314456) (xy 153.656378 -386.291764)
			(xy 153.611495 -386.261345) (xy 153.572173 -386.224013) (xy 153.539468 -386.180767) (xy 153.514253 -386.132767)
			(xy 153.497204 -386.081296) (xy 153.492454 -386.0546) (xy 153.49093 -386.045202) (xy 153.218134 -385.57327)
			(xy 153.210768 -385.567428) (xy 153.192015 -385.551599) (xy 153.158896 -385.515387) (xy 153.131485 -385.474684)
			(xy 153.11038 -385.430382) (xy 153.096044 -385.38345) (xy 153.08879 -385.334916) (xy 153.08834 -385.31038)
			(xy 152.571292 -385.31038) (xy 152.819862 -385.740402) (xy 152.827228 -385.746244) (xy 152.846015 -385.762035)
			(xy 152.879131 -385.798255) (xy 152.906539 -385.838966) (xy 152.927638 -385.883276) (xy 152.941967 -385.930214)
			(xy 152.949211 -385.978754) (xy 152.949656 -386.003292) (xy 152.949402 -386.015484) (xy 152.949148 -386.025136)
			(xy 152.955244 -386.04317) (xy 153.013918 -386.11048) (xy 153.030682 -386.119116) (xy 153.040588 -386.120132)
			(xy 153.067349 -386.123501) (xy 153.119371 -386.137722) (xy 153.168397 -386.160195) (xy 153.213127 -386.190326)
			(xy 153.252375 -386.227315) (xy 153.285101 -386.270182) (xy 153.310437 -386.317791) (xy 153.327713 -386.368881)
			(xy 153.33647 -386.422096) (xy 153.337006 -386.449062) (xy 153.33658 -386.473264) (xy 153.329506 -386.521149)
			(xy 153.31552 -386.567488) (xy 153.294921 -386.61129) (xy 153.281888 -386.631688) (xy 153.277101 -386.639645)
			(xy 153.273066 -386.657756) (xy 153.274014 -386.666994) (xy 153.278332 -386.697982) (xy 153.280004 -386.707281)
			(xy 153.289291 -386.723722) (xy 153.296366 -386.729986) (xy 153.318455 -386.748667) (xy 153.358226 -386.790679)
			(xy 153.392388 -386.837367) (xy 153.420396 -386.887987) (xy 153.441803 -386.941732) (xy 153.456268 -386.997746)
			(xy 153.463561 -387.055136) (xy 153.464006 -387.084062) (xy 153.463419 -387.117384) (xy 153.453756 -387.183322)
			(xy 153.434629 -387.247161) (xy 153.42108 -387.27761) (xy 153.416831 -387.288075) (xy 153.416945 -387.310634)
			(xy 153.42668 -387.330985) (xy 153.43505 -387.33857) (xy 153.45727 -387.357275) (xy 153.497337 -387.399324)
			(xy 153.531761 -387.446104) (xy 153.55999 -387.496864) (xy 153.58157 -387.550787) (xy 153.596154 -387.607008)
			(xy 153.603507 -387.664621) (xy 153.60396 -387.693662) (xy 153.60348 -387.722667) (xy 153.59617 -387.780214)
			(xy 153.581648 -387.836376) (xy 153.560148 -387.890254) (xy 153.532014 -387.940985) (xy 153.497697 -387.987755)
			(xy 153.457747 -388.029815) (xy 153.435558 -388.0485) (xy 153.428446 -388.054088) (xy 153.419302 -388.069328)
			(xy 153.404062 -388.152132) (xy 153.406856 -388.169404) (xy 153.411428 -388.177532) (xy 153.424002 -388.200719)
			(xy 153.441877 -388.25034) (xy 153.450978 -388.302291) (xy 153.45156 -388.328662) (xy 153.451457 -388.339943)
			(xy 153.449805 -388.362445) (xy 153.448258 -388.37362) (xy 153.446988 -388.38251) (xy 153.450544 -388.400036)
			(xy 153.493978 -388.470902) (xy 153.507694 -388.482078) (xy 153.51633 -388.484872) (xy 153.538571 -388.492819)
			(xy 153.580493 -388.514567) (xy 153.618567 -388.542508) (xy 153.651886 -388.575978) (xy 153.679656 -388.614178)
			(xy 153.690828 -388.634986) (xy 153.691336 -388.636002) (xy 154.083766 -389.314944) (xy 154.096575 -389.338285)
			(xy 154.1148 -389.388303) (xy 154.124067 -389.440726) (xy 154.12466 -389.467344) (xy 154.124301 -389.491353)
			(xy 154.116779 -389.53878) (xy 154.101926 -389.584444) (xy 154.080109 -389.62722) (xy 154.051865 -389.666055)
			(xy 154.017891 -389.69999) (xy 153.979025 -389.72819) (xy 153.936223 -389.749958) (xy 153.890542 -389.764759)
			(xy 153.843108 -389.772228) (xy 153.819098 -389.772652) (xy 153.795567 -389.77217) (xy 153.749061 -389.764969)
			(xy 153.704214 -389.750708) (xy 153.66209 -389.729725) (xy 153.623691 -389.702519) (xy 153.589928 -389.669736)
			(xy 153.561604 -389.632154) (xy 153.550112 -389.611616) (xy 153.549858 -389.611108) (xy 153.54935 -389.610346)
			(xy 153.151586 -388.922006) (xy 153.139712 -388.899328) (xy 153.12286 -388.850996) (xy 153.114286 -388.800533)
			(xy 153.11374 -388.77494) (xy 153.11374 -388.774432) (xy 153.113831 -388.763087) (xy 153.115486 -388.740458)
			(xy 153.117042 -388.72922) (xy 153.118312 -388.72033) (xy 153.114756 -388.703058) (xy 153.071322 -388.631938)
			(xy 153.057352 -388.621016) (xy 153.04897 -388.617968) (xy 153.026574 -388.609919) (xy 152.984355 -388.587964)
			(xy 152.946057 -388.559719) (xy 152.91261 -388.52587) (xy 152.884824 -388.487238) (xy 152.863374 -388.444759)
			(xy 152.848781 -388.399466) (xy 152.841397 -388.352455) (xy 152.840944 -388.328662) (xy 152.841504 -388.302289)
			(xy 152.850588 -388.25033) (xy 152.86848 -388.20071) (xy 152.881076 -388.177532) (xy 152.885648 -388.169404)
			(xy 152.888442 -388.152132) (xy 152.873202 -388.069328) (xy 152.864058 -388.054088) (xy 152.856946 -388.0485)
			(xy 152.834764 -388.029807) (xy 152.79482 -387.987742) (xy 152.760505 -387.940971) (xy 152.732368 -387.890243)
			(xy 152.71086 -387.836369) (xy 152.696325 -387.78021) (xy 152.688994 -387.722666) (xy 152.688544 -387.693662)
			(xy 152.689144 -387.660341) (xy 152.698802 -387.594403) (xy 152.717924 -387.530563) (xy 152.73147 -387.500114)
			(xy 152.735712 -387.489646) (xy 152.735608 -387.467087) (xy 152.725873 -387.446736) (xy 152.7175 -387.439154)
			(xy 152.695233 -387.420503) (xy 152.655171 -387.378444) (xy 152.620752 -387.331653) (xy 152.59253 -387.280884)
			(xy 152.570958 -387.226953) (xy 152.556382 -387.170725) (xy 152.549038 -387.113105) (xy 152.54859 -387.084062)
			(xy 152.549028 -387.055135) (xy 152.556312 -386.997742) (xy 152.570772 -386.941724) (xy 152.592178 -386.887976)
			(xy 152.620187 -386.837355) (xy 152.654354 -386.790667) (xy 152.694133 -386.748659) (xy 152.71623 -386.729986)
			(xy 152.723197 -386.723634) (xy 152.732458 -386.707234) (xy 152.734264 -386.697982) (xy 152.738582 -386.666994)
			(xy 152.739481 -386.657757) (xy 152.735459 -386.639658) (xy 152.730708 -386.631688) (xy 152.717721 -386.611265)
			(xy 152.69714 -386.567463) (xy 152.683153 -386.521133) (xy 152.676057 -386.47326) (xy 152.67559 -386.449062)
			(xy 152.675844 -386.43687) (xy 152.676098 -386.427218) (xy 152.670002 -386.409184) (xy 152.611328 -386.341874)
			(xy 152.594564 -386.333238) (xy 152.584658 -386.332222) (xy 152.557751 -386.328852) (xy 152.505465 -386.314488)
			(xy 152.456222 -386.291789) (xy 152.411339 -386.261364) (xy 152.372019 -386.224026) (xy 152.339315 -386.180776)
			(xy 152.314101 -386.132771) (xy 152.297054 -386.081298) (xy 152.292304 -386.0546) (xy 152.29078 -386.045202)
			(xy 152.017984 -385.57327) (xy 152.010618 -385.567428) (xy 151.991875 -385.551587) (xy 151.958754 -385.515379)
			(xy 151.93134 -385.474679) (xy 151.910233 -385.430378) (xy 151.895895 -385.383448) (xy 151.888641 -385.334916)
			(xy 151.88819 -385.31038) (xy 151.371396 -385.31038) (xy 151.619966 -385.740402) (xy 151.627332 -385.746244)
			(xy 151.64612 -385.762034) (xy 151.679236 -385.798254) (xy 151.706643 -385.838965) (xy 151.727742 -385.883275)
			(xy 151.742071 -385.930214) (xy 151.749315 -385.978753) (xy 151.74976 -386.003292) (xy 151.749506 -386.015484)
			(xy 151.749252 -386.025136) (xy 151.755348 -386.04317) (xy 151.814022 -386.11048) (xy 151.830786 -386.119116)
			(xy 151.840438 -386.120132) (xy 151.867204 -386.12346) (xy 151.919228 -386.137689) (xy 151.968253 -386.160169)
			(xy 152.012982 -386.190305) (xy 152.052229 -386.227299) (xy 152.084954 -386.270171) (xy 152.110289 -386.317784)
			(xy 152.127564 -386.368877) (xy 152.136321 -386.422095) (xy 152.136856 -386.449062) (xy 152.136346 -386.475049)
			(xy 152.128216 -386.526384) (xy 152.112155 -386.575814) (xy 152.088559 -386.622124) (xy 152.058009 -386.664172)
			(xy 152.021258 -386.700923) (xy 151.97921 -386.731473) (xy 151.9329 -386.755069) (xy 151.88347 -386.77113)
			(xy 151.832135 -386.77926) (xy 151.780161 -386.77926) (xy 151.728826 -386.77113) (xy 151.679396 -386.755069)
			(xy 151.633086 -386.731473) (xy 151.591038 -386.700923) (xy 151.554287 -386.664172) (xy 151.523737 -386.622124)
			(xy 151.500141 -386.575814) (xy 151.48408 -386.526384) (xy 151.47595 -386.475049) (xy 151.47544 -386.449062)
			(xy 151.475694 -386.43687) (xy 151.475948 -386.427218) (xy 151.469852 -386.409184) (xy 151.411178 -386.341874)
			(xy 151.394414 -386.333238) (xy 151.384762 -386.332222) (xy 151.357855 -386.328849) (xy 151.30557 -386.314485)
			(xy 151.256326 -386.291787) (xy 151.211444 -386.261362) (xy 151.172124 -386.224025) (xy 151.139419 -386.180775)
			(xy 151.114205 -386.132771) (xy 151.097158 -386.081298) (xy 151.092408 -386.0546) (xy 151.090884 -386.045202)
			(xy 150.818088 -385.57327) (xy 150.810722 -385.567428) (xy 150.79198 -385.551586) (xy 150.758859 -385.515378)
			(xy 150.731444 -385.474678) (xy 150.710337 -385.430378) (xy 150.695999 -385.383448) (xy 150.688745 -385.334916)
			(xy 150.688294 -385.31038) (xy 150.17121 -385.31038) (xy 150.419816 -385.740402) (xy 150.427182 -385.746244)
			(xy 150.44596 -385.762046) (xy 150.479078 -385.798262) (xy 150.506488 -385.83897) (xy 150.527589 -385.883278)
			(xy 150.541919 -385.930216) (xy 150.549164 -385.978754) (xy 150.54961 -386.003292) (xy 150.549356 -386.015484)
			(xy 150.549102 -386.025136) (xy 150.555198 -386.04317) (xy 150.613872 -386.11048) (xy 150.630636 -386.119116)
			(xy 150.640542 -386.120132) (xy 150.667309 -386.123457) (xy 150.719332 -386.137686) (xy 150.768358 -386.160167)
			(xy 150.813087 -386.190304) (xy 150.852333 -386.227298) (xy 150.885058 -386.27017) (xy 150.910393 -386.317783)
			(xy 150.927668 -386.368876) (xy 150.936425 -386.422095) (xy 150.93696 -386.449062) (xy 150.93641 -386.476346)
			(xy 150.927457 -386.530175) (xy 150.909787 -386.581804) (xy 150.883881 -386.629831) (xy 150.850441 -386.672952)
			(xy 150.830788 -386.691886) (xy 150.823389 -386.699409) (xy 150.814863 -386.718688) (xy 150.814278 -386.729224)
			(xy 150.814278 -386.8039) (xy 150.8148 -386.81445) (xy 150.823341 -386.833745) (xy 150.830788 -386.841238)
			(xy 150.850438 -386.860174) (xy 150.883868 -386.9033) (xy 150.90977 -386.951327) (xy 150.927439 -387.002953)
			(xy 150.936399 -387.056779) (xy 150.93696 -387.084062) (xy 150.936508 -387.108178) (xy 150.929512 -387.1559)
			(xy 150.915663 -387.202101) (xy 150.895254 -387.245802) (xy 150.88235 -387.26618) (xy 150.876508 -387.27507)
			(xy 150.872952 -387.295136) (xy 150.894034 -387.387338) (xy 150.906226 -387.404102) (xy 150.915116 -387.409436)
			(xy 150.935913 -387.422298) (xy 150.973819 -387.453185) (xy 151.006763 -387.489319) (xy 151.034025 -387.529911)
			(xy 151.055011 -387.574076) (xy 151.069263 -387.62085) (xy 151.076471 -387.669213) (xy 151.076914 -387.693662)
			(xy 151.076488 -387.718035) (xy 151.069342 -387.766254) (xy 151.055201 -387.812903) (xy 151.034368 -387.856973)
			(xy 151.007296 -387.89751) (xy 150.974571 -387.933637) (xy 150.95601 -387.94944) (xy 150.94712 -387.956552)
			(xy 150.937722 -387.97611) (xy 150.934928 -388.075424) (xy 150.943564 -388.09549) (xy 150.951946 -388.10311)
			(xy 150.970393 -388.120574) (xy 151.001741 -388.160544) (xy 151.026038 -388.205152) (xy 151.042615 -388.253167)
			(xy 151.051015 -388.303264) (xy 151.051514 -388.328662) (xy 151.640794 -388.328662) (xy 151.641316 -388.303407)
			(xy 151.649629 -388.253585) (xy 151.66603 -388.205811) (xy 151.690071 -388.161388) (xy 151.721095 -388.121528)
			(xy 151.758257 -388.087318) (xy 151.800543 -388.059692) (xy 151.846799 -388.039402) (xy 151.895764 -388.027002)
			(xy 151.946102 -388.022831) (xy 151.99644 -388.027002) (xy 152.045405 -388.039402) (xy 152.091661 -388.059692)
			(xy 152.133947 -388.087318) (xy 152.171109 -388.121528) (xy 152.202133 -388.161388) (xy 152.226174 -388.205811)
			(xy 152.242575 -388.253585) (xy 152.250888 -388.303407) (xy 152.25141 -388.328662) (xy 152.251306 -388.339943)
			(xy 152.249655 -388.362445) (xy 152.248108 -388.37362) (xy 152.246838 -388.38251) (xy 152.250394 -388.400036)
			(xy 152.293828 -388.470902) (xy 152.307544 -388.482078) (xy 152.31618 -388.484872) (xy 152.33843 -388.492796)
			(xy 152.38035 -388.51455) (xy 152.418423 -388.542497) (xy 152.45174 -388.575972) (xy 152.479508 -388.614176)
			(xy 152.490678 -388.634986) (xy 152.491186 -388.636002) (xy 152.883616 -389.314944) (xy 152.89635 -389.338309)
			(xy 152.914465 -389.388337) (xy 152.923674 -389.440741) (xy 152.924256 -389.467344) (xy 152.923778 -389.491334)
			(xy 152.916267 -389.538723) (xy 152.901436 -389.584353) (xy 152.879652 -389.627103) (xy 152.851449 -389.665919)
			(xy 152.817522 -389.699846) (xy 152.778706 -389.72805) (xy 152.735957 -389.749835) (xy 152.690327 -389.764666)
			(xy 152.642938 -389.772178) (xy 152.618948 -389.772652) (xy 152.595416 -389.772211) (xy 152.548908 -389.765002)
			(xy 152.50406 -389.750734) (xy 152.461936 -389.729744) (xy 152.423537 -389.702532) (xy 152.389776 -389.669743)
			(xy 152.361453 -389.632156) (xy 152.349962 -389.611616) (xy 152.349708 -389.611108) (xy 152.3492 -389.610346)
			(xy 151.951436 -388.922006) (xy 151.939523 -388.899336) (xy 151.922584 -388.851012) (xy 151.913924 -388.800542)
			(xy 151.913336 -388.77494) (xy 151.913336 -388.774432) (xy 151.913493 -388.763083) (xy 151.91527 -388.740453)
			(xy 151.916892 -388.72922) (xy 151.918162 -388.72033) (xy 151.914606 -388.703058) (xy 151.871172 -388.631938)
			(xy 151.857202 -388.621016) (xy 151.84882 -388.617968) (xy 151.826413 -388.609948) (xy 151.784195 -388.587986)
			(xy 151.745899 -388.559735) (xy 151.712454 -388.525882) (xy 151.684671 -388.487246) (xy 151.663222 -388.444765)
			(xy 151.64863 -388.399469) (xy 151.641247 -388.352456) (xy 151.640794 -388.328662) (xy 151.051514 -388.328662)
			(xy 151.05141 -388.339943) (xy 151.049759 -388.362445) (xy 151.048212 -388.37362) (xy 151.046942 -388.38251)
			(xy 151.050498 -388.400036) (xy 151.093932 -388.470902) (xy 151.107648 -388.482078) (xy 151.116284 -388.484872)
			(xy 151.138534 -388.492794) (xy 151.180455 -388.514548) (xy 151.218527 -388.542496) (xy 151.251845 -388.575971)
			(xy 151.279612 -388.614175) (xy 151.290782 -388.634986) (xy 151.29129 -388.636002) (xy 151.68372 -389.314944)
			(xy 151.696454 -389.338309) (xy 151.714569 -389.388337) (xy 151.723778 -389.440741) (xy 151.72436 -389.467344)
			(xy 151.724002 -389.491341) (xy 151.716487 -389.538742) (xy 151.70165 -389.584385) (xy 151.679855 -389.627144)
			(xy 151.651639 -389.665968) (xy 151.617698 -389.699899) (xy 151.578866 -389.728103) (xy 151.5361 -389.749885)
			(xy 151.490453 -389.764709) (xy 151.443049 -389.772209) (xy 151.419052 -389.772652) (xy 151.39552 -389.772207)
			(xy 151.349012 -389.765) (xy 151.304164 -389.750732) (xy 151.26204 -389.729743) (xy 151.223642 -389.702531)
			(xy 151.18988 -389.669742) (xy 151.161557 -389.632156) (xy 151.150066 -389.611616) (xy 151.149812 -389.611108)
			(xy 151.149304 -389.610346) (xy 150.75154 -388.922006) (xy 150.739628 -388.899336) (xy 150.722688 -388.851012)
			(xy 150.714028 -388.800542) (xy 150.71344 -388.77494) (xy 150.71344 -388.774432) (xy 150.713597 -388.763083)
			(xy 150.715374 -388.740453) (xy 150.716996 -388.72922) (xy 150.718266 -388.72033) (xy 150.71471 -388.703058)
			(xy 150.671276 -388.631938) (xy 150.657306 -388.621016) (xy 150.648924 -388.617968) (xy 150.626518 -388.609946)
			(xy 150.5843 -388.587984) (xy 150.546004 -388.559734) (xy 150.512559 -388.525881) (xy 150.484775 -388.487245)
			(xy 150.463327 -388.444764) (xy 150.448734 -388.399468) (xy 150.441351 -388.352456) (xy 150.440898 -388.328662)
			(xy 150.441424 -388.303267) (xy 150.449834 -388.253178) (xy 150.466414 -388.205171) (xy 150.490708 -388.160568)
			(xy 150.522046 -388.120599) (xy 150.540466 -388.10311) (xy 150.548848 -388.09549) (xy 150.557484 -388.075424)
			(xy 150.55469 -387.97611) (xy 150.545292 -387.956552) (xy 150.536402 -387.94944) (xy 150.517875 -387.933601)
			(xy 150.485151 -387.897479) (xy 150.458078 -387.856948) (xy 150.437242 -387.812886) (xy 150.423092 -387.766244)
			(xy 150.415936 -387.718032) (xy 150.415498 -387.693662) (xy 150.415904 -387.669544) (xy 150.422912 -387.62182)
			(xy 150.436774 -387.575619) (xy 150.457197 -387.53192) (xy 150.470108 -387.511544) (xy 150.47595 -387.502654)
			(xy 150.479506 -387.482588) (xy 150.458424 -387.390386) (xy 150.446232 -387.373622) (xy 150.437342 -387.368288)
			(xy 150.416546 -387.355425) (xy 150.378642 -387.324536) (xy 150.3457 -387.288401) (xy 150.318439 -387.247809)
			(xy 150.297452 -387.203645) (xy 150.283199 -387.156872) (xy 150.275989 -387.10851) (xy 150.275544 -387.084062)
			(xy 150.276109 -387.056778) (xy 150.285058 -387.00295) (xy 150.302724 -386.951322) (xy 150.328627 -386.903294)
			(xy 150.362064 -386.860172) (xy 150.381716 -386.841238) (xy 150.389105 -386.833706) (xy 150.397636 -386.814434)
			(xy 150.398226 -386.8039) (xy 150.398226 -386.729224) (xy 150.39769 -386.718675) (xy 150.389159 -386.69938)
			(xy 150.381716 -386.691886) (xy 150.362079 -386.672938) (xy 150.328646 -386.629815) (xy 150.302743 -386.581791)
			(xy 150.28507 -386.530168) (xy 150.276107 -386.476344) (xy 150.275544 -386.449062) (xy 150.275798 -386.43687)
			(xy 150.276052 -386.427218) (xy 150.269956 -386.409184) (xy 150.211282 -386.341874) (xy 150.194518 -386.333238)
			(xy 150.184612 -386.332222) (xy 150.157711 -386.328809) (xy 150.105426 -386.314453) (xy 150.056182 -386.291762)
			(xy 150.011299 -386.261343) (xy 149.971978 -386.224012) (xy 149.939272 -386.180766) (xy 149.914057 -386.132766)
			(xy 149.897008 -386.081296) (xy 149.892258 -386.0546) (xy 149.890734 -386.045202) (xy 149.617684 -385.572762)
			(xy 149.610572 -385.56692) (xy 149.591835 -385.551146) (xy 149.558782 -385.515002) (xy 149.531426 -385.474375)
			(xy 149.510368 -385.430155) (xy 149.496069 -385.383311) (xy 149.488841 -385.334869) (xy 149.488398 -385.31038)
			(xy 148.97135 -385.31038) (xy 149.21992 -385.740402) (xy 149.227286 -385.746244) (xy 149.246064 -385.762045)
			(xy 149.279183 -385.798262) (xy 149.306592 -385.83897) (xy 149.327693 -385.883278) (xy 149.342023 -385.930216)
			(xy 149.349268 -385.978754) (xy 149.349714 -386.003292) (xy 149.34946 -386.015484) (xy 149.349206 -386.025136)
			(xy 149.355302 -386.04317) (xy 149.413976 -386.11048) (xy 149.43074 -386.119116) (xy 149.440646 -386.120132)
			(xy 149.467413 -386.123454) (xy 149.519437 -386.137683) (xy 149.568462 -386.160165) (xy 149.613191 -386.190302)
			(xy 149.652438 -386.227297) (xy 149.685162 -386.270169) (xy 149.710497 -386.317783) (xy 149.727772 -386.368876)
			(xy 149.736529 -386.422095) (xy 149.737064 -386.449062) (xy 149.736513 -386.476346) (xy 149.72756 -386.530175)
			(xy 149.70989 -386.581803) (xy 149.683985 -386.62983) (xy 149.650545 -386.672952) (xy 149.630892 -386.691886)
			(xy 149.623494 -386.69941) (xy 149.614968 -386.718688) (xy 149.614382 -386.729224) (xy 149.614382 -386.8039)
			(xy 149.614903 -386.814451) (xy 149.623444 -386.833745) (xy 149.630892 -386.841238) (xy 149.650542 -386.860173)
			(xy 149.683973 -386.9033) (xy 149.709874 -386.951327) (xy 149.727544 -387.002953) (xy 149.736503 -387.056779)
			(xy 149.737064 -387.084062) (xy 149.736612 -387.108178) (xy 149.729616 -387.1559) (xy 149.715767 -387.202101)
			(xy 149.695358 -387.245802) (xy 149.682454 -387.26618) (xy 149.676612 -387.27507) (xy 149.673056 -387.295136)
			(xy 149.694138 -387.387338) (xy 149.70633 -387.404102) (xy 149.71522 -387.409436) (xy 149.736018 -387.422296)
			(xy 149.773924 -387.453184) (xy 149.806867 -387.489319) (xy 149.834129 -387.529911) (xy 149.855115 -387.574076)
			(xy 149.869367 -387.62085) (xy 149.876575 -387.669213) (xy 149.877018 -387.693662) (xy 149.87659 -387.718035)
			(xy 149.869445 -387.766254) (xy 149.855303 -387.812903) (xy 149.834471 -387.856973) (xy 149.8074 -387.89751)
			(xy 149.774674 -387.933637) (xy 149.756114 -387.94944) (xy 149.747224 -387.956552) (xy 149.737826 -387.97611)
			(xy 149.735032 -388.075424) (xy 149.743668 -388.09549) (xy 149.75205 -388.10311) (xy 149.770498 -388.120573)
			(xy 149.801845 -388.160543) (xy 149.826142 -388.205152) (xy 149.842719 -388.253167) (xy 149.851119 -388.303264)
			(xy 149.851618 -388.328662) (xy 149.851514 -388.339943) (xy 149.849863 -388.362445) (xy 149.848316 -388.37362)
			(xy 149.847046 -388.382764) (xy 149.850348 -388.400036) (xy 149.894036 -388.471156) (xy 149.907752 -388.482078)
			(xy 149.916388 -388.484872) (xy 149.944553 -388.495068) (xy 149.996499 -388.52488) (xy 150.019512 -388.544054)
			(xy 150.040998 -388.563633) (xy 150.07681 -388.609413) (xy 150.090632 -388.634986) (xy 150.091394 -388.636256)
			(xy 150.48357 -389.314944) (xy 150.496379 -389.338285) (xy 150.514604 -389.388303) (xy 150.523871 -389.440726)
			(xy 150.524464 -389.467344) (xy 150.524101 -389.491353) (xy 150.516579 -389.538779) (xy 150.501726 -389.584443)
			(xy 150.479909 -389.627219) (xy 150.451666 -389.666053) (xy 150.417693 -389.699989) (xy 150.378827 -389.728188)
			(xy 150.336026 -389.749957) (xy 150.290346 -389.764759) (xy 150.242912 -389.772228) (xy 150.218902 -389.772652)
			(xy 150.195372 -389.772167) (xy 150.148866 -389.764967) (xy 150.104018 -389.750706) (xy 150.061895 -389.729724)
			(xy 150.023495 -389.702518) (xy 149.989732 -389.669735) (xy 149.961408 -389.632154) (xy 149.949916 -389.611616)
			(xy 149.949662 -389.611108) (xy 149.949154 -389.610346) (xy 149.551644 -388.921752) (xy 149.541074 -388.901824)
			(xy 149.525269 -388.859575) (xy 149.515861 -388.815459) (xy 149.514052 -388.792974) (xy 149.513544 -388.781798)
			(xy 149.513544 -388.774432) (xy 149.513635 -388.763087) (xy 149.51529 -388.740458) (xy 149.516846 -388.72922)
			(xy 149.518116 -388.72033) (xy 149.51456 -388.703058) (xy 149.471126 -388.631938) (xy 149.45741 -388.620762)
			(xy 149.448774 -388.617968) (xy 149.426372 -388.60997) (xy 149.384202 -388.587967) (xy 149.345953 -388.55969)
			(xy 149.312553 -388.525824) (xy 149.28481 -388.487187) (xy 149.263394 -388.444715) (xy 149.248824 -388.399436)
			(xy 149.241453 -388.352445) (xy 149.241002 -388.328662) (xy 149.241527 -388.303267) (xy 149.249936 -388.253178)
			(xy 149.266517 -388.20517) (xy 149.290811 -388.160568) (xy 149.32215 -388.120599) (xy 149.34057 -388.10311)
			(xy 149.348952 -388.09549) (xy 149.357588 -388.075424) (xy 149.354794 -387.97611) (xy 149.345396 -387.956552)
			(xy 149.336506 -387.94944) (xy 149.317959 -387.933623) (xy 149.285241 -387.897494) (xy 149.258173 -387.856958)
			(xy 149.237341 -387.812892) (xy 149.223195 -387.766247) (xy 149.216039 -387.718033) (xy 149.215602 -387.693662)
			(xy 149.216007 -387.669544) (xy 149.223016 -387.62182) (xy 149.236878 -387.575619) (xy 149.257301 -387.53192)
			(xy 149.270212 -387.511544) (xy 149.276054 -387.502654) (xy 149.27961 -387.482588) (xy 149.258528 -387.390386)
			(xy 149.246336 -387.373622) (xy 149.237446 -387.368288) (xy 149.216651 -387.355424) (xy 149.178747 -387.324535)
			(xy 149.145805 -387.288401) (xy 149.118543 -387.247809) (xy 149.097557 -387.203645) (xy 149.083303 -387.156872)
			(xy 149.076093 -387.10851) (xy 149.075648 -387.084062) (xy 149.076211 -387.056778) (xy 149.085161 -387.00295)
			(xy 149.102827 -386.951321) (xy 149.12873 -386.903294) (xy 149.162168 -386.860172) (xy 149.18182 -386.841238)
			(xy 149.18921 -386.833707) (xy 149.19774 -386.814434) (xy 149.19833 -386.8039) (xy 149.19833 -386.729224)
			(xy 149.197793 -386.718675) (xy 149.189262 -386.699381) (xy 149.18182 -386.691886) (xy 149.162183 -386.672937)
			(xy 149.128751 -386.629815) (xy 149.102847 -386.581791) (xy 149.085174 -386.530168) (xy 149.076211 -386.476344)
			(xy 149.075648 -386.449062) (xy 149.075902 -386.43687) (xy 149.076156 -386.427218) (xy 149.07006 -386.409184)
			(xy 149.011386 -386.341874) (xy 148.994622 -386.333238) (xy 148.984716 -386.332222) (xy 148.957815 -386.328806)
			(xy 148.90553 -386.314451) (xy 148.856287 -386.29176) (xy 148.811403 -386.261342) (xy 148.772082 -386.22401)
			(xy 148.739376 -386.180766) (xy 148.714161 -386.132766) (xy 148.697112 -386.081296) (xy 148.692362 -386.0546)
			(xy 148.690838 -386.045202) (xy 148.418042 -385.57327) (xy 148.410676 -385.567428) (xy 148.391924 -385.551597)
			(xy 148.358806 -385.515386) (xy 148.331394 -385.474683) (xy 148.310288 -385.430381) (xy 148.295952 -385.38345)
			(xy 148.288698 -385.334916) (xy 148.288248 -385.31038) (xy 147.771454 -385.31038) (xy 148.020024 -385.740402)
			(xy 148.02739 -385.746244) (xy 148.046169 -385.762044) (xy 148.079287 -385.798261) (xy 148.106697 -385.83897)
			(xy 148.127798 -385.883278) (xy 148.142127 -385.930215) (xy 148.149372 -385.978754) (xy 148.149818 -386.003292)
			(xy 148.149564 -386.015484) (xy 148.14931 -386.025136) (xy 148.155406 -386.04317) (xy 148.21408 -386.11048)
			(xy 148.230844 -386.119116) (xy 148.240496 -386.120132) (xy 148.267257 -386.123495) (xy 148.31928 -386.137717)
			(xy 148.368306 -386.160191) (xy 148.413036 -386.190322) (xy 148.452283 -386.227312) (xy 148.485009 -386.27018)
			(xy 148.510346 -386.31779) (xy 148.527621 -386.36888) (xy 148.536378 -386.422096) (xy 148.536914 -386.449062)
			(xy 148.536378 -386.476347) (xy 148.527424 -386.530177) (xy 148.509752 -386.581807) (xy 148.483842 -386.629833)
			(xy 148.450398 -386.672954) (xy 148.430742 -386.691886) (xy 148.423351 -386.699417) (xy 148.414819 -386.71869)
			(xy 148.414232 -386.729224) (xy 148.414232 -386.8039) (xy 148.414738 -386.814453) (xy 148.423288 -386.833748)
			(xy 148.430742 -386.841238) (xy 148.450383 -386.860182) (xy 148.483817 -386.903305) (xy 148.509721 -386.95133)
			(xy 148.527392 -387.002955) (xy 148.536353 -387.056779) (xy 148.536914 -387.084062) (xy 148.53647 -387.108178)
			(xy 148.529473 -387.155901) (xy 148.515622 -387.202102) (xy 148.49521 -387.245803) (xy 148.482304 -387.26618)
			(xy 148.476462 -387.27507) (xy 148.472906 -387.295136) (xy 148.493988 -387.387338) (xy 148.50618 -387.404102)
			(xy 148.51507 -387.409436) (xy 148.535879 -387.422278) (xy 148.573783 -387.453171) (xy 148.606724 -387.489309)
			(xy 148.633983 -387.529905) (xy 148.654967 -387.574072) (xy 148.669218 -387.620848) (xy 148.676425 -387.669213)
			(xy 148.676868 -387.693662) (xy 148.676459 -387.718036) (xy 148.669312 -387.766256) (xy 148.655168 -387.812907)
			(xy 148.634333 -387.856977) (xy 148.607257 -387.897513) (xy 148.574527 -387.933639) (xy 148.555964 -387.94944)
			(xy 148.547074 -387.956552) (xy 148.537676 -387.97611) (xy 148.534882 -388.075424) (xy 148.543518 -388.09549)
			(xy 148.5519 -388.10311) (xy 148.570339 -388.120583) (xy 148.601689 -388.160549) (xy 148.625989 -388.205155)
			(xy 148.642568 -388.253168) (xy 148.650968 -388.303264) (xy 148.651468 -388.328662) (xy 148.651364 -388.339943)
			(xy 148.649713 -388.362445) (xy 148.648166 -388.37362) (xy 148.646896 -388.38251) (xy 148.650452 -388.400036)
			(xy 148.693886 -388.470902) (xy 148.707602 -388.482078) (xy 148.716238 -388.484872) (xy 148.73848 -388.492816)
			(xy 148.780402 -388.514564) (xy 148.818476 -388.542506) (xy 148.851795 -388.575977) (xy 148.879565 -388.614177)
			(xy 148.890736 -388.634986) (xy 148.891244 -388.636002) (xy 149.283674 -389.314944) (xy 149.296483 -389.338284)
			(xy 149.314708 -389.388303) (xy 149.323975 -389.440726) (xy 149.324568 -389.467344) (xy 149.324201 -389.491353)
			(xy 149.316679 -389.538778) (xy 149.301826 -389.584442) (xy 149.28001 -389.627218) (xy 149.251767 -389.666052)
			(xy 149.217795 -389.699987) (xy 149.178929 -389.728187) (xy 149.136129 -389.749956) (xy 149.090449 -389.764758)
			(xy 149.043016 -389.772228) (xy 149.019006 -389.772652) (xy 148.995476 -389.772164) (xy 148.94897 -389.764964)
			(xy 148.904123 -389.750704) (xy 148.861999 -389.729722) (xy 148.8236 -389.702517) (xy 148.789837 -389.669735)
			(xy 148.761512 -389.632154) (xy 148.75002 -389.611616) (xy 148.749766 -389.611108) (xy 148.749258 -389.610346)
			(xy 148.351494 -388.922006) (xy 148.339621 -388.899328) (xy 148.322768 -388.850995) (xy 148.314194 -388.800532)
			(xy 148.313648 -388.77494) (xy 148.313648 -388.774432) (xy 148.31374 -388.763087) (xy 148.315394 -388.740458)
			(xy 148.31695 -388.72922) (xy 148.31822 -388.72033) (xy 148.314664 -388.703058) (xy 148.27123 -388.631938)
			(xy 148.25726 -388.621016) (xy 148.248878 -388.617968) (xy 148.226483 -388.609915) (xy 148.184264 -388.58796)
			(xy 148.145966 -388.559716) (xy 148.112518 -388.525868) (xy 148.084733 -388.487236) (xy 148.063283 -388.444759)
			(xy 148.048689 -388.399465) (xy 148.041305 -388.352455) (xy 148.040852 -388.328662) (xy 148.041361 -388.303266)
			(xy 148.049772 -388.253176) (xy 148.066355 -388.205167) (xy 148.090653 -388.160564) (xy 148.121997 -388.120597)
			(xy 148.14042 -388.10311) (xy 148.148802 -388.09549) (xy 148.157438 -388.075424) (xy 148.154644 -387.97611)
			(xy 148.145246 -387.956552) (xy 148.136356 -387.94944) (xy 148.11782 -387.933611) (xy 148.085098 -387.897486)
			(xy 148.058028 -387.856953) (xy 148.037194 -387.812889) (xy 148.023046 -387.766246) (xy 148.01589 -387.718033)
			(xy 148.015452 -387.693662) (xy 148.015865 -387.669544) (xy 148.022873 -387.621821) (xy 148.036733 -387.57562)
			(xy 148.057153 -387.53192) (xy 148.070062 -387.511544) (xy 148.075904 -387.502654) (xy 148.07946 -387.482588)
			(xy 148.058378 -387.390386) (xy 148.046186 -387.373622) (xy 148.037296 -387.368288) (xy 148.016513 -387.355406)
			(xy 147.978606 -387.324522) (xy 147.945661 -387.288391) (xy 147.918397 -387.247803) (xy 147.897409 -387.203641)
			(xy 147.883154 -387.15687) (xy 147.875943 -387.10851) (xy 147.875498 -387.084062) (xy 147.876045 -387.056777)
			(xy 147.884996 -387.002947) (xy 147.902665 -386.951318) (xy 147.928573 -386.903291) (xy 147.962015 -386.860171)
			(xy 147.98167 -386.841238) (xy 147.989053 -386.8337) (xy 147.997589 -386.814433) (xy 147.99818 -386.8039)
			(xy 147.99818 -386.729224) (xy 147.997657 -386.718673) (xy 147.989118 -386.699378) (xy 147.98167 -386.691886)
			(xy 147.962043 -386.672928) (xy 147.928607 -386.629809) (xy 147.9027 -386.581788) (xy 147.885025 -386.530166)
			(xy 147.876061 -386.476344) (xy 147.875498 -386.449062) (xy 147.875752 -386.43687) (xy 147.876006 -386.427218)
			(xy 147.86991 -386.409184) (xy 147.811236 -386.341874) (xy 147.794472 -386.333238) (xy 147.78482 -386.332222)
			(xy 147.757909 -386.328882) (xy 147.705622 -386.314512) (xy 147.656379 -386.291808) (xy 147.611497 -386.261378)
			(xy 147.572178 -386.224036) (xy 147.539474 -386.180783) (xy 147.514262 -386.132775) (xy 147.497215 -386.081299)
			(xy 147.492466 -386.0546) (xy 147.490942 -386.045202) (xy 147.218146 -385.57327) (xy 147.21078 -385.567428)
			(xy 147.192029 -385.551596) (xy 147.15891 -385.515385) (xy 147.131498 -385.474683) (xy 147.110393 -385.430381)
			(xy 147.096056 -385.383449) (xy 147.088802 -385.334916) (xy 147.088352 -385.31038) (xy 144.761082 -385.31038)
			(xy 144.780596 -385.320323) (xy 144.822644 -385.350873) (xy 144.859395 -385.387624) (xy 144.889945 -385.429672)
			(xy 144.913541 -385.475982) (xy 144.929602 -385.525412) (xy 144.937732 -385.576747) (xy 144.938242 -385.602734)
			(xy 144.937732 -385.628721) (xy 144.929602 -385.680056) (xy 144.913541 -385.729486) (xy 144.889945 -385.775796)
			(xy 144.859395 -385.817844) (xy 144.822644 -385.854595) (xy 144.79383 -385.87553) (xy 146.461734 -385.87553)
			(xy 146.462244 -385.849543) (xy 146.470374 -385.798208) (xy 146.486435 -385.748778) (xy 146.510031 -385.702468)
			(xy 146.540581 -385.66042) (xy 146.577332 -385.623669) (xy 146.61938 -385.593119) (xy 146.66569 -385.569523)
			(xy 146.71512 -385.553462) (xy 146.766455 -385.545332) (xy 146.818429 -385.545332) (xy 146.869764 -385.553462)
			(xy 146.919194 -385.569523) (xy 146.965504 -385.593119) (xy 147.007552 -385.623669) (xy 147.044303 -385.66042)
			(xy 147.074853 -385.702468) (xy 147.098449 -385.748778) (xy 147.11451 -385.798208) (xy 147.12264 -385.849543)
			(xy 147.12315 -385.87553) (xy 147.122767 -385.899206) (xy 147.116034 -385.946077) (xy 147.102668 -385.991504)
			(xy 147.093178 -386.013198) (xy 147.08886 -386.022596) (xy 147.088098 -386.042662) (xy 147.120356 -386.129022)
			(xy 147.134072 -386.143754) (xy 147.14347 -386.148072) (xy 147.167843 -386.159753) (xy 147.212712 -386.189883)
			(xy 147.252089 -386.226903) (xy 147.284927 -386.269829) (xy 147.310352 -386.317522) (xy 147.32769 -386.368712)
			(xy 147.336479 -386.422039) (xy 147.337018 -386.449062) (xy 147.336481 -386.476347) (xy 147.327527 -386.530177)
			(xy 147.309855 -386.581806) (xy 147.283946 -386.629833) (xy 147.250502 -386.672954) (xy 147.230846 -386.691886)
			(xy 147.223455 -386.699417) (xy 147.214923 -386.71869) (xy 147.214336 -386.729224) (xy 147.214336 -386.8039)
			(xy 147.214841 -386.814453) (xy 147.223392 -386.833749) (xy 147.230846 -386.841238) (xy 147.250488 -386.860182)
			(xy 147.283921 -386.903305) (xy 147.309825 -386.95133) (xy 147.327496 -387.002955) (xy 147.336457 -387.056779)
			(xy 147.337018 -387.084062) (xy 147.336573 -387.108178) (xy 147.329576 -387.155901) (xy 147.315725 -387.202102)
			(xy 147.295314 -387.245803) (xy 147.282408 -387.26618) (xy 147.276566 -387.27507) (xy 147.27301 -387.295136)
			(xy 147.294092 -387.387338) (xy 147.306284 -387.404102) (xy 147.315174 -387.409436) (xy 147.335984 -387.422277)
			(xy 147.373888 -387.45317) (xy 147.406828 -387.489309) (xy 147.434088 -387.529904) (xy 147.455071 -387.574072)
			(xy 147.469322 -387.620848) (xy 147.476529 -387.669213) (xy 147.476972 -387.693662) (xy 147.476561 -387.718036)
			(xy 147.469415 -387.766256) (xy 147.455271 -387.812906) (xy 147.434436 -387.856977) (xy 147.40736 -387.897513)
			(xy 147.374631 -387.933639) (xy 147.356068 -387.94944) (xy 147.347178 -387.956552) (xy 147.33778 -387.97611)
			(xy 147.334986 -388.075424) (xy 147.343622 -388.09549) (xy 147.352004 -388.10311) (xy 147.370443 -388.120582)
			(xy 147.401793 -388.160549) (xy 147.426093 -388.205155) (xy 147.442672 -388.253168) (xy 147.451072 -388.303264)
			(xy 147.451572 -388.328662) (xy 147.451468 -388.339943) (xy 147.449817 -388.362445) (xy 147.44827 -388.37362)
			(xy 147.447 -388.38251) (xy 147.450556 -388.400036) (xy 147.49399 -388.470902) (xy 147.507706 -388.482078)
			(xy 147.516342 -388.484872) (xy 147.538585 -388.492814) (xy 147.580506 -388.514563) (xy 147.61858 -388.542506)
			(xy 147.651899 -388.575976) (xy 147.679669 -388.614177) (xy 147.69084 -388.634986) (xy 147.691348 -388.636002)
			(xy 148.083778 -389.314944) (xy 148.096588 -389.338284) (xy 148.114813 -389.388303) (xy 148.124079 -389.440726)
			(xy 148.124672 -389.467344) (xy 148.124301 -389.491353) (xy 148.116779 -389.538778) (xy 148.101927 -389.584441)
			(xy 148.080111 -389.627217) (xy 148.051868 -389.666051) (xy 148.017896 -389.699986) (xy 147.979031 -389.728185)
			(xy 147.936232 -389.749955) (xy 147.890552 -389.764757) (xy 147.843119 -389.772228) (xy 147.81911 -389.772652)
			(xy 147.795577 -389.772241) (xy 147.749067 -389.765027) (xy 147.704218 -389.750753) (xy 147.662095 -389.729759)
			(xy 147.623697 -389.702541) (xy 147.589936 -389.669748) (xy 147.561614 -389.632158) (xy 147.550124 -389.611616)
			(xy 147.54987 -389.611108) (xy 147.549362 -389.610346) (xy 147.151598 -388.922006) (xy 147.139725 -388.899328)
			(xy 147.122872 -388.850995) (xy 147.114298 -388.800532) (xy 147.113752 -388.77494) (xy 147.113752 -388.774432)
			(xy 147.113844 -388.763087) (xy 147.115498 -388.740458) (xy 147.117054 -388.72922) (xy 147.118324 -388.72033)
			(xy 147.114768 -388.703058) (xy 147.071334 -388.631938) (xy 147.057364 -388.621016) (xy 147.048982 -388.617968)
			(xy 147.026588 -388.609913) (xy 146.984369 -388.587959) (xy 146.946071 -388.559715) (xy 146.912623 -388.525867)
			(xy 146.884837 -388.487236) (xy 146.863387 -388.444758) (xy 146.848793 -388.399465) (xy 146.841409 -388.352455)
			(xy 146.840956 -388.328662) (xy 146.841464 -388.303266) (xy 146.849875 -388.253175) (xy 146.866458 -388.205167)
			(xy 146.890757 -388.160564) (xy 146.922101 -388.120597) (xy 146.940524 -388.10311) (xy 146.948906 -388.09549)
			(xy 146.957542 -388.075424) (xy 146.954748 -387.97611) (xy 146.94535 -387.956552) (xy 146.93646 -387.94944)
			(xy 146.917924 -387.93361) (xy 146.885203 -387.897485) (xy 146.858132 -387.856952) (xy 146.837298 -387.812888)
			(xy 146.82315 -387.766246) (xy 146.815994 -387.718033) (xy 146.815556 -387.693662) (xy 146.815969 -387.669544)
			(xy 146.822976 -387.621821) (xy 146.836836 -387.57562) (xy 146.857257 -387.53192) (xy 146.870166 -387.511544)
			(xy 146.876008 -387.502654) (xy 146.879564 -387.482588) (xy 146.858482 -387.390386) (xy 146.84629 -387.373622)
			(xy 146.8374 -387.368288) (xy 146.816618 -387.355404) (xy 146.77871 -387.324521) (xy 146.745765 -387.288391)
			(xy 146.718501 -387.247802) (xy 146.697513 -387.203641) (xy 146.683258 -387.15687) (xy 146.676047 -387.10851)
			(xy 146.675602 -387.084062) (xy 146.676148 -387.056777) (xy 146.685099 -387.002947) (xy 146.702768 -386.951318)
			(xy 146.728676 -386.903291) (xy 146.762119 -386.86017) (xy 146.781774 -386.841238) (xy 146.789157 -386.833701)
			(xy 146.797693 -386.814433) (xy 146.798284 -386.8039) (xy 146.798284 -386.729224) (xy 146.79776 -386.718674)
			(xy 146.789222 -386.699378) (xy 146.781774 -386.691886) (xy 146.762147 -386.672927) (xy 146.728711 -386.629808)
			(xy 146.702804 -386.581787) (xy 146.685129 -386.530166) (xy 146.676165 -386.476344) (xy 146.675602 -386.449062)
			(xy 146.675987 -386.425386) (xy 146.68272 -386.378515) (xy 146.696084 -386.333089) (xy 146.705574 -386.311394)
			(xy 146.709892 -386.301996) (xy 146.710654 -386.28193) (xy 146.678396 -386.19557) (xy 146.66468 -386.180838)
			(xy 146.655282 -386.17652) (xy 146.630917 -386.164821) (xy 146.586046 -386.134697) (xy 146.546666 -386.097681)
			(xy 146.513827 -386.054758) (xy 146.4884 -386.007067) (xy 146.471061 -385.955879) (xy 146.462273 -385.902553)
			(xy 146.461734 -385.87553) (xy 144.79383 -385.87553) (xy 144.780596 -385.885145) (xy 144.734286 -385.908741)
			(xy 144.684856 -385.924802) (xy 144.633521 -385.932932) (xy 144.581547 -385.932932) (xy 144.530212 -385.924802)
			(xy 144.480782 -385.908741) (xy 144.434472 -385.885145) (xy 144.392424 -385.854595) (xy 144.355673 -385.817844)
			(xy 144.325123 -385.775796) (xy 144.301527 -385.729486) (xy 144.285466 -385.680056) (xy 144.277336 -385.628721)
			(xy 144.071893 -385.628721) (xy 144.066521 -385.665222) (xy 144.050453 -385.718629) (xy 144.026781 -385.769126)
			(xy 143.996008 -385.815639) (xy 143.958791 -385.857176) (xy 143.915923 -385.892851) (xy 143.868317 -385.921905)
			(xy 143.816988 -385.943717) (xy 143.763031 -385.957823) (xy 143.707594 -385.963923) (xy 143.65186 -385.961886)
			(xy 143.597017 -385.951756) (xy 143.544233 -385.933749) (xy 143.494633 -385.908248) (xy 143.449275 -385.875797)
			(xy 143.409126 -385.837088) (xy 143.37504 -385.792945) (xy 143.347744 -385.74431) (xy 143.327821 -385.692219)
			(xy 143.315695 -385.637782) (xy 143.311624 -385.58216) (xy 141.90859 -385.58216) (xy 141.545818 -385.944872)
			(xy 141.539907 -385.951277) (xy 141.532426 -385.967004) (xy 141.530653 -385.98433) (xy 141.532356 -385.992878)
			(xy 141.555978 -386.09016) (xy 141.573758 -386.109464) (xy 141.586458 -386.113528) (xy 141.6117 -386.122162)
			(xy 141.659676 -386.145492) (xy 141.703935 -386.175277) (xy 141.743614 -386.210937) (xy 141.77794 -386.251776)
			(xy 141.806243 -386.296997) (xy 141.827971 -386.34572) (xy 141.842702 -386.396994) (xy 141.850147 -386.44982)
			(xy 141.850618 -386.476494) (xy 141.850387 -386.489448) (xy 144.37868 -386.489448) (xy 144.37919 -386.463461)
			(xy 144.38732 -386.412126) (xy 144.403381 -386.362696) (xy 144.426977 -386.316386) (xy 144.457527 -386.274338)
			(xy 144.494278 -386.237587) (xy 144.536326 -386.207037) (xy 144.582636 -386.183441) (xy 144.632066 -386.16738)
			(xy 144.683401 -386.15925) (xy 144.735375 -386.15925) (xy 144.78671 -386.16738) (xy 144.83614 -386.183441)
			(xy 144.88245 -386.207037) (xy 144.924498 -386.237587) (xy 144.961249 -386.274338) (xy 144.991799 -386.316386)
			(xy 145.015395 -386.362696) (xy 145.031456 -386.412126) (xy 145.039586 -386.463461) (xy 145.040096 -386.489448)
			(xy 145.039559 -386.516777) (xy 145.030564 -386.570691) (xy 145.012827 -386.622392) (xy 144.98683 -386.670473)
			(xy 144.9705 -386.692394) (xy 144.964912 -386.69976) (xy 144.959324 -386.716524) (xy 144.96288 -386.800598)
			(xy 144.969738 -386.816854) (xy 144.975834 -386.823712) (xy 144.992219 -386.84211) (xy 145.019869 -386.882883)
			(xy 145.04117 -386.927305) (xy 145.055651 -386.974393) (xy 145.062992 -387.023108) (xy 145.063464 -387.04774)
			(xy 145.062954 -387.073727) (xy 145.054824 -387.125062) (xy 145.038763 -387.174492) (xy 145.015167 -387.220802)
			(xy 144.984617 -387.26285) (xy 144.947866 -387.299601) (xy 144.905818 -387.330151) (xy 144.859508 -387.353747)
			(xy 144.810078 -387.369808) (xy 144.758743 -387.377938) (xy 144.706769 -387.377938) (xy 144.655434 -387.369808)
			(xy 144.606004 -387.353747) (xy 144.559694 -387.330151) (xy 144.517646 -387.299601) (xy 144.480895 -387.26285)
			(xy 144.450345 -387.220802) (xy 144.426749 -387.174492) (xy 144.410688 -387.125062) (xy 144.402558 -387.073727)
			(xy 144.402048 -387.04774) (xy 144.402643 -387.020413) (xy 144.411622 -386.966503) (xy 144.429343 -386.914802)
			(xy 144.455322 -386.866718) (xy 144.471644 -386.844794) (xy 144.477232 -386.837428) (xy 144.48282 -386.820664)
			(xy 144.479264 -386.73659) (xy 144.472406 -386.720334) (xy 144.46631 -386.713476) (xy 144.449974 -386.695037)
			(xy 144.422315 -386.654275) (xy 144.401004 -386.609864) (xy 144.386512 -386.562785) (xy 144.379158 -386.514077)
			(xy 144.37868 -386.489448) (xy 141.850387 -386.489448) (xy 141.850133 -386.503746) (xy 141.842377 -386.557695)
			(xy 141.827022 -386.609991) (xy 141.804382 -386.659569) (xy 141.774916 -386.705421) (xy 141.739224 -386.746613)
			(xy 141.698034 -386.782306) (xy 141.652183 -386.811774) (xy 141.602606 -386.834417) (xy 141.55031 -386.849773)
			(xy 141.496362 -386.857531) (xy 141.46911 -386.858002) (xy 141.446604 -386.857642) (xy 141.401911 -386.852293)
			(xy 141.379956 -386.847334) (xy 141.368472 -386.845222) (xy 141.345726 -386.850391) (xy 141.336268 -386.85724)
			(xy 141.311122 -386.87756) (xy 141.302362 -386.885326) (xy 141.292432 -386.906499) (xy 141.292072 -386.9182)
			(xy 141.292072 -387.789674) (xy 141.291656 -387.815857) (xy 141.28453 -387.867734) (xy 141.27038 -387.918151)
			(xy 141.260322 -387.942328) (xy 141.254988 -387.95452) (xy 141.257782 -387.980936) (xy 141.323314 -388.073646)
			(xy 141.34719 -388.085076) (xy 141.360652 -388.084314) (xy 141.387068 -388.083298) (xy 141.41484 -388.083796)
			(xy 141.469796 -388.091846) (xy 141.523005 -388.10778) (xy 141.57334 -388.131262) (xy 141.619738 -388.161794)
			(xy 141.661219 -388.198732) (xy 141.696904 -388.241295) (xy 141.711934 -388.264654) (xy 141.71676 -388.272528)
			(xy 141.730984 -388.283704) (xy 141.812264 -388.309358) (xy 141.830298 -388.308342) (xy 141.83868 -388.304786)
			(xy 141.870683 -388.291553) (xy 141.937376 -388.272894) (xy 142.005984 -388.263465) (xy 142.04061 -388.262876)
			(xy 142.072572 -388.263379) (xy 142.135991 -388.271391) (xy 142.197905 -388.28729) (xy 142.224132 -388.297674)
			(xy 143.436592 -388.297674) (xy 143.440663 -388.242052) (xy 143.452789 -388.187615) (xy 143.472712 -388.135524)
			(xy 143.500008 -388.086889) (xy 143.534094 -388.042746) (xy 143.574243 -388.004037) (xy 143.619601 -387.971586)
			(xy 143.669201 -387.946085) (xy 143.721985 -387.928078) (xy 143.776828 -387.917948) (xy 143.832562 -387.915911)
			(xy 143.887999 -387.922011) (xy 143.941956 -387.936117) (xy 143.993285 -387.957929) (xy 144.040891 -387.986983)
			(xy 144.083759 -388.022658) (xy 144.120976 -388.064195) (xy 144.151749 -388.110708) (xy 144.175421 -388.161205)
			(xy 144.191489 -388.214612) (xy 144.199609 -388.269788) (xy 144.200118 -388.297674) (xy 144.199671 -388.322137)
			(xy 144.402558 -388.322137) (xy 144.402558 -388.270163) (xy 144.410688 -388.218828) (xy 144.426749 -388.169398)
			(xy 144.450345 -388.123088) (xy 144.480895 -388.08104) (xy 144.517646 -388.044289) (xy 144.559694 -388.013739)
			(xy 144.606004 -387.990143) (xy 144.655434 -387.974082) (xy 144.706769 -387.965952) (xy 144.758743 -387.965952)
			(xy 144.810078 -387.974082) (xy 144.859508 -387.990143) (xy 144.905818 -388.013739) (xy 144.947866 -388.044289)
			(xy 144.984617 -388.08104) (xy 145.015167 -388.123088) (xy 145.038763 -388.169398) (xy 145.054824 -388.218828)
			(xy 145.062954 -388.270163) (xy 145.063464 -388.29615) (xy 145.062954 -388.322137) (xy 145.054824 -388.373472)
			(xy 145.038763 -388.422902) (xy 145.015167 -388.469212) (xy 144.984617 -388.51126) (xy 144.947866 -388.548011)
			(xy 144.905818 -388.578561) (xy 144.859508 -388.602157) (xy 144.810078 -388.618218) (xy 144.758743 -388.626348)
			(xy 144.706769 -388.626348) (xy 144.655434 -388.618218) (xy 144.606004 -388.602157) (xy 144.559694 -388.578561)
			(xy 144.517646 -388.548011) (xy 144.480895 -388.51126) (xy 144.450345 -388.469212) (xy 144.426749 -388.422902)
			(xy 144.410688 -388.373472) (xy 144.402558 -388.322137) (xy 144.199671 -388.322137) (xy 144.199609 -388.32556)
			(xy 144.191489 -388.380736) (xy 144.175421 -388.434143) (xy 144.151749 -388.48464) (xy 144.120976 -388.531153)
			(xy 144.083759 -388.57269) (xy 144.040891 -388.608365) (xy 143.993285 -388.637419) (xy 143.941956 -388.659231)
			(xy 143.887999 -388.673337) (xy 143.832562 -388.679437) (xy 143.776828 -388.6774) (xy 143.721985 -388.66727)
			(xy 143.669201 -388.649263) (xy 143.619601 -388.623762) (xy 143.574243 -388.591311) (xy 143.534094 -388.552602)
			(xy 143.500008 -388.508459) (xy 143.472712 -388.459824) (xy 143.452789 -388.407733) (xy 143.440663 -388.353296)
			(xy 143.436592 -388.297674) (xy 142.224132 -388.297674) (xy 142.257339 -388.310822) (xy 142.313355 -388.341618)
			(xy 142.36507 -388.379192) (xy 142.411668 -388.422951) (xy 142.452413 -388.472205) (xy 142.486665 -388.526177)
			(xy 142.513882 -388.584017) (xy 142.533635 -388.644812) (xy 142.545613 -388.707603) (xy 142.549627 -388.7714)
			(xy 142.545613 -388.835197) (xy 142.533635 -388.897988) (xy 142.513882 -388.958783) (xy 142.486665 -389.016623)
			(xy 142.452413 -389.070595) (xy 142.411668 -389.119849) (xy 142.36507 -389.163608) (xy 142.313355 -389.201182)
			(xy 142.257339 -389.231978) (xy 142.197905 -389.25551) (xy 142.135991 -389.271409) (xy 142.072572 -389.279421)
			(xy 142.04061 -389.279892) (xy 142.007909 -389.279387) (xy 141.943048 -389.271001) (xy 141.879798 -389.254367)
			(xy 141.819203 -389.229758) (xy 141.762264 -389.197583) (xy 141.709922 -389.158371) (xy 141.66304 -389.112771)
			(xy 141.622393 -389.061535) (xy 141.588652 -389.005509) (xy 141.562374 -388.94562) (xy 141.552676 -388.914386)
			(xy 141.550136 -388.905496) (xy 141.539214 -388.891018) (xy 141.467586 -388.845044) (xy 141.45006 -388.841234)
			(xy 141.440916 -388.842504) (xy 141.427526 -388.844293) (xy 141.400576 -388.846197) (xy 141.387068 -388.846314)
			(xy 141.378178 -388.846314) (xy 141.366748 -388.84606) (xy 141.346428 -388.854696) (xy 141.27988 -388.92988)
			(xy 141.27353 -388.951216) (xy 141.275054 -388.962392) (xy 141.276943 -388.97603) (xy 141.278979 -389.003489)
			(xy 141.279118 -389.017256) (xy 141.278658 -389.04451) (xy 141.270907 -389.098465) (xy 141.255555 -389.150768)
			(xy 141.232917 -389.200353) (xy 141.203452 -389.246212) (xy 141.16776 -389.28741) (xy 141.126568 -389.32311)
			(xy 141.080715 -389.352583) (xy 141.031134 -389.375231) (xy 140.978834 -389.390592) (xy 140.92488 -389.398353)
			(xy 140.870372 -389.398357) (xy 140.816417 -389.390603) (xy 140.764115 -389.375249) (xy 140.714531 -389.352608)
			(xy 140.668674 -389.323141) (xy 140.627477 -389.287447) (xy 140.59178 -389.246253) (xy 140.562308 -389.200399)
			(xy 140.539663 -389.150817) (xy 140.524304 -389.098516) (xy 140.516545 -389.044562) (xy 140.516544 -388.990054)
			(xy 140.524301 -388.936099) (xy 140.539657 -388.883798) (xy 140.562301 -388.834215) (xy 140.59177 -388.788359)
			(xy 140.627466 -388.747164) (xy 140.668661 -388.711469) (xy 140.714517 -388.682) (xy 140.7641 -388.659356)
			(xy 140.816401 -388.644) (xy 140.870356 -388.636244) (xy 140.89761 -388.635748) (xy 140.9065 -388.635748)
			(xy 140.91793 -388.636002) (xy 140.93825 -388.627366) (xy 141.004798 -388.552182) (xy 141.011148 -388.530846)
			(xy 141.009624 -388.51967) (xy 141.007736 -388.506032) (xy 141.005703 -388.478573) (xy 141.00556 -388.464806)
			(xy 141.005989 -388.438666) (xy 141.013122 -388.386874) (xy 141.027257 -388.33654) (xy 141.03731 -388.312406)
			(xy 141.042644 -388.29996) (xy 141.040104 -388.273544) (xy 140.974572 -388.180834) (xy 140.950442 -388.169404)
			(xy 140.937234 -388.17042) (xy 140.910564 -388.171436) (xy 140.883301 -388.17097) (xy 140.82933 -388.163202)
			(xy 140.777014 -388.147831) (xy 140.72742 -388.125168) (xy 140.681557 -388.095676) (xy 140.64036 -388.059955)
			(xy 140.604667 -388.018733) (xy 140.575206 -387.97285) (xy 140.552578 -387.92324) (xy 140.537242 -387.870914)
			(xy 140.529511 -387.816938) (xy 140.529056 -387.789674) (xy 140.529056 -386.926074) (xy 140.529543 -386.898818)
			(xy 140.537302 -386.84486) (xy 140.552657 -386.792555) (xy 140.575296 -386.742966) (xy 140.604759 -386.697102)
			(xy 140.640447 -386.655896) (xy 140.681634 -386.620185) (xy 140.727482 -386.590697) (xy 140.777058 -386.56803)
			(xy 140.829355 -386.552646) (xy 140.883308 -386.544858) (xy 140.910564 -386.544312) (xy 140.92568 -386.544468)
			(xy 140.955815 -386.546882) (xy 140.970762 -386.549138) (xy 140.98143 -386.550916) (xy 141.002258 -386.545328)
			(xy 141.07795 -386.484622) (xy 141.087602 -386.465572) (xy 141.08811 -386.45465) (xy 141.090396 -386.430774)
			(xy 141.045438 -386.393436) (xy 141.035588 -386.386161) (xy 141.011695 -386.380982) (xy 140.999718 -386.38353)
			(xy 140.963806 -386.392471) (xy 140.890418 -386.402027) (xy 140.853414 -386.40258) (xy 140.37818 -386.40258)
			(xy 140.368194 -386.40312) (xy 140.349765 -386.410837) (xy 140.342366 -386.417566) (xy 138.924792 -387.83514)
			(xy 139.455142 -387.83514) (xy 139.459213 -387.779518) (xy 139.471339 -387.725081) (xy 139.491262 -387.67299)
			(xy 139.518558 -387.624355) (xy 139.552644 -387.580212) (xy 139.592793 -387.541503) (xy 139.638151 -387.509052)
			(xy 139.687751 -387.483551) (xy 139.740535 -387.465544) (xy 139.795378 -387.455414) (xy 139.851112 -387.453377)
			(xy 139.906549 -387.459477) (xy 139.960506 -387.473583) (xy 140.011835 -387.495395) (xy 140.059441 -387.524449)
			(xy 140.102309 -387.560124) (xy 140.139526 -387.601661) (xy 140.170299 -387.648174) (xy 140.193971 -387.698671)
			(xy 140.210039 -387.752078) (xy 140.218159 -387.807254) (xy 140.218668 -387.83514) (xy 140.218159 -387.863026)
			(xy 140.210039 -387.918202) (xy 140.193971 -387.971609) (xy 140.170299 -388.022106) (xy 140.139526 -388.068619)
			(xy 140.102309 -388.110156) (xy 140.059441 -388.145831) (xy 140.011835 -388.174885) (xy 139.960506 -388.196697)
			(xy 139.906549 -388.210803) (xy 139.851112 -388.216903) (xy 139.795378 -388.214866) (xy 139.740535 -388.204736)
			(xy 139.687751 -388.186729) (xy 139.638151 -388.161228) (xy 139.592793 -388.128777) (xy 139.552644 -388.090068)
			(xy 139.518558 -388.045925) (xy 139.491262 -387.99729) (xy 139.471339 -387.945199) (xy 139.459213 -387.890762)
			(xy 139.455142 -387.83514) (xy 138.924792 -387.83514) (xy 138.339068 -388.420864) (xy 138.316276 -388.44306)
			(xy 138.266543 -388.482739) (xy 138.212679 -388.5166) (xy 138.155363 -388.544215) (xy 138.095314 -388.565239)
			(xy 138.033289 -388.579405) (xy 137.970067 -388.586536) (xy 137.938256 -388.58698) (xy 137.646918 -388.58698)
			(xy 137.638389 -388.587256) (xy 137.622256 -388.592787) (xy 137.608855 -388.603336) (xy 137.603992 -388.610348)
			(xy 137.550906 -388.69366) (xy 137.549382 -388.719568) (xy 137.554716 -388.731252) (xy 137.565999 -388.756629)
			(xy 137.578498 -388.798352) (xy 138.841185 -388.798352) (xy 138.841185 -388.743848) (xy 138.848942 -388.689899)
			(xy 138.864299 -388.637603) (xy 138.886941 -388.588025) (xy 138.916409 -388.542175) (xy 138.952103 -388.500984)
			(xy 138.993295 -388.465294) (xy 139.039148 -388.435829) (xy 139.088728 -388.413189) (xy 139.141025 -388.397837)
			(xy 139.194974 -388.390083) (xy 139.222226 -388.389622) (xy 139.249597 -388.390067) (xy 139.303777 -388.397889)
			(xy 139.356281 -388.413383) (xy 139.406027 -388.436229) (xy 139.451993 -388.465959) (xy 139.472924 -388.483602)
			(xy 139.480036 -388.489698) (xy 139.497054 -388.496048) (xy 139.582398 -388.496048) (xy 139.599416 -388.489698)
			(xy 139.606528 -388.483602) (xy 139.627477 -388.465984) (xy 139.673445 -388.436269) (xy 139.723188 -388.413429)
			(xy 139.775685 -388.397933) (xy 139.829858 -388.390099) (xy 139.857226 -388.389622) (xy 139.884478 -388.39005)
			(xy 139.938427 -388.39781) (xy 139.990723 -388.413168) (xy 140.040301 -388.435813) (xy 140.086152 -388.465282)
			(xy 140.127342 -388.500976) (xy 140.163034 -388.542169) (xy 140.1925 -388.588022) (xy 140.215141 -388.637601)
			(xy 140.230496 -388.689898) (xy 140.238252 -388.743848) (xy 140.238252 -388.798352) (xy 140.230496 -388.852302)
			(xy 140.215141 -388.904599) (xy 140.1925 -388.954178) (xy 140.163034 -389.000031) (xy 140.127342 -389.041224)
			(xy 140.086152 -389.076918) (xy 140.040301 -389.106387) (xy 139.990723 -389.129032) (xy 139.938427 -389.14439)
			(xy 139.884478 -389.15215) (xy 139.857226 -389.152638) (xy 139.829856 -389.152172) (xy 139.775676 -389.144356)
			(xy 139.723172 -389.128868) (xy 139.673425 -389.106026) (xy 139.627459 -389.0763) (xy 139.606528 -389.058658)
			(xy 139.599416 -389.052562) (xy 139.582398 -389.046212) (xy 139.497054 -389.046212) (xy 139.480036 -389.052562)
			(xy 139.472924 -389.058658) (xy 139.451988 -389.076293) (xy 139.406017 -389.106007) (xy 139.356271 -389.128844)
			(xy 139.303771 -389.144336) (xy 139.249595 -389.152164) (xy 139.222226 -389.152638) (xy 139.194974 -389.152117)
			(xy 139.141025 -389.144363) (xy 139.088728 -389.129011) (xy 139.039148 -389.106371) (xy 138.993295 -389.076906)
			(xy 138.952103 -389.041216) (xy 138.916409 -389.000025) (xy 138.886941 -388.954175) (xy 138.864299 -388.904597)
			(xy 138.848942 -388.852301) (xy 138.841185 -388.798352) (xy 137.578498 -388.798352) (xy 137.581936 -388.809829)
			(xy 137.590008 -388.864775) (xy 137.59053 -388.892542) (xy 137.590041 -388.919792) (xy 137.58228 -388.973736)
			(xy 137.566922 -389.026027) (xy 137.544278 -389.075601) (xy 137.514811 -389.121447) (xy 137.47912 -389.162634)
			(xy 137.437931 -389.198323) (xy 137.392083 -389.227788) (xy 137.342508 -389.250429) (xy 137.290217 -389.265784)
			(xy 137.236272 -389.273543) (xy 137.209022 -389.27405) (xy 137.181654 -389.273573) (xy 137.127482 -389.265738)
			(xy 137.074986 -389.250241) (xy 137.025244 -389.227399) (xy 136.979278 -389.197682) (xy 136.958324 -389.18007)
			(xy 136.951212 -389.173974) (xy 136.934194 -389.167624) (xy 136.84885 -389.167624) (xy 136.831832 -389.173974)
			(xy 136.82472 -389.18007) (xy 136.803787 -389.197711) (xy 136.757819 -389.227435) (xy 136.708073 -389.250281)
			(xy 136.655571 -389.265777) (xy 136.601393 -389.273606) (xy 136.546651 -389.273606) (xy 136.492473 -389.265777)
			(xy 136.439971 -389.250281) (xy 136.390225 -389.227435) (xy 136.344257 -389.197711) (xy 136.323324 -389.18007)
			(xy 136.316212 -389.173974) (xy 136.299194 -389.167624) (xy 136.21385 -389.167624) (xy 136.196832 -389.173974)
			(xy 136.18972 -389.18007) (xy 136.16879 -389.197714) (xy 136.122824 -389.227445) (xy 136.073078 -389.250293)
			(xy 136.020574 -389.265787) (xy 135.966393 -389.273609) (xy 135.939022 -389.27405) (xy 135.914079 -389.273622)
			(xy 135.864623 -389.267083) (xy 135.816437 -389.254166) (xy 135.770341 -389.23509) (xy 135.748522 -389.222996)
			(xy 135.736584 -389.216138) (xy 135.70966 -389.216138) (xy 135.621522 -389.267192) (xy 135.61402 -389.271966)
			(xy 135.602586 -389.285567) (xy 135.596473 -389.302251) (xy 135.596122 -389.311134) (xy 135.596122 -390.395249)
			(xy 137.098806 -390.395249) (xy 137.098806 -390.340751) (xy 137.106562 -390.286809) (xy 137.121915 -390.234519)
			(xy 137.144553 -390.184947) (xy 137.174016 -390.1391) (xy 137.209704 -390.097914) (xy 137.250889 -390.062225)
			(xy 137.296734 -390.03276) (xy 137.346306 -390.01012) (xy 137.398595 -389.994765) (xy 137.452537 -389.987007)
			(xy 137.479786 -389.98652) (xy 137.507156 -389.986989) (xy 137.561335 -389.994806) (xy 137.613839 -390.010294)
			(xy 137.663586 -390.033135) (xy 137.709552 -390.062859) (xy 137.730484 -390.0805) (xy 137.737596 -390.086596)
			(xy 137.754614 -390.092946) (xy 137.839958 -390.092946) (xy 137.856976 -390.086596) (xy 137.864088 -390.0805)
			(xy 137.885014 -390.062853) (xy 137.930988 -390.033142) (xy 137.980737 -390.010308) (xy 138.033239 -389.994819)
			(xy 138.087416 -389.986993) (xy 138.114786 -389.98652) (xy 138.142042 -389.986926) (xy 138.195998 -389.994682)
			(xy 138.248301 -390.010038) (xy 138.297887 -390.032681) (xy 138.343745 -390.062151) (xy 138.384943 -390.097847)
			(xy 138.420641 -390.139043) (xy 138.450112 -390.184901) (xy 138.472757 -390.234485) (xy 138.488115 -390.286788)
			(xy 138.495873 -390.340744) (xy 138.495873 -390.395256) (xy 138.488115 -390.449212) (xy 138.472757 -390.501515)
			(xy 138.450112 -390.551099) (xy 138.420641 -390.596957) (xy 138.384943 -390.638153) (xy 138.343745 -390.673849)
			(xy 138.297887 -390.703319) (xy 138.248301 -390.725962) (xy 138.195998 -390.741318) (xy 138.142042 -390.749074)
			(xy 138.114786 -390.749536) (xy 138.087415 -390.749094) (xy 138.033234 -390.741273) (xy 137.98073 -390.725779)
			(xy 137.930983 -390.702931) (xy 137.885018 -390.6732) (xy 137.864088 -390.655556) (xy 137.856976 -390.64946)
			(xy 137.839958 -390.64311) (xy 137.754614 -390.64311) (xy 137.737596 -390.64946) (xy 137.730484 -390.655556)
			(xy 137.709525 -390.673162) (xy 137.663561 -390.702881) (xy 137.61382 -390.725724) (xy 137.561325 -390.741222)
			(xy 137.507153 -390.749058) (xy 137.479786 -390.749536) (xy 137.452537 -390.748993) (xy 137.398595 -390.741235)
			(xy 137.346306 -390.72588) (xy 137.296734 -390.70324) (xy 137.250889 -390.673775) (xy 137.209704 -390.638087)
			(xy 137.174016 -390.5969) (xy 137.144553 -390.551053) (xy 137.121915 -390.501481) (xy 137.106562 -390.449191)
			(xy 137.098806 -390.395249) (xy 135.596122 -390.395249) (xy 135.596122 -393.52093) (xy 136.326118 -393.52093)
			(xy 136.326572 -393.490233) (xy 136.333978 -393.429287) (xy 136.348675 -393.369678) (xy 136.370447 -393.312275)
			(xy 136.398978 -393.257913) (xy 136.416034 -393.232386) (xy 136.421478 -393.22362) (xy 136.425612 -393.203425)
			(xy 136.421497 -393.183226) (xy 136.416034 -393.174474) (xy 136.398994 -393.148939) (xy 136.370485 -393.094571)
			(xy 136.348722 -393.037168) (xy 136.334022 -392.977564) (xy 136.326598 -392.916625) (xy 136.326118 -392.88593)
			(xy 136.326566 -392.855198) (xy 136.333972 -392.79418) (xy 136.348679 -392.734501) (xy 136.370472 -392.67703)
			(xy 136.399035 -392.622604) (xy 136.43395 -392.572019) (xy 136.474709 -392.526012) (xy 136.520716 -392.485253)
			(xy 136.571301 -392.450337) (xy 136.625726 -392.421774) (xy 136.683197 -392.39998) (xy 136.742876 -392.385272)
			(xy 136.803894 -392.377866) (xy 136.834626 -392.377422) (xy 136.865322 -392.377897) (xy 136.926267 -392.385299)
			(xy 136.985876 -392.39999) (xy 137.04328 -392.421758) (xy 137.097643 -392.450284) (xy 137.12317 -392.467338)
			(xy 137.131922 -392.472809) (xy 137.152126 -392.476937) (xy 137.17233 -392.472809) (xy 137.181082 -392.467338)
			(xy 137.206629 -392.450317) (xy 137.260994 -392.421805) (xy 137.318394 -392.400038) (xy 137.377995 -392.385334)
			(xy 137.438932 -392.377905) (xy 137.469626 -392.377422) (xy 137.500322 -392.377897) (xy 137.561267 -392.385299)
			(xy 137.620876 -392.39999) (xy 137.67828 -392.421758) (xy 137.732643 -392.450284) (xy 137.75817 -392.467338)
			(xy 137.766922 -392.472809) (xy 137.787126 -392.476937) (xy 137.80733 -392.472809) (xy 137.816082 -392.467338)
			(xy 137.841629 -392.450317) (xy 137.895994 -392.421805) (xy 137.953394 -392.400038) (xy 138.012995 -392.385334)
			(xy 138.073932 -392.377905) (xy 138.104626 -392.377422) (xy 138.125708 -392.37793) (xy 138.13663 -392.378438)
			(xy 138.156188 -392.370818) (xy 138.224514 -392.302492) (xy 138.232134 -392.282934) (xy 138.231626 -392.272012)
			(xy 138.231118 -392.25093) (xy 138.231572 -392.220233) (xy 138.238978 -392.159287) (xy 138.253675 -392.099678)
			(xy 138.275447 -392.042275) (xy 138.303978 -391.987913) (xy 138.321034 -391.962386) (xy 138.326478 -391.95362)
			(xy 138.330612 -391.933425) (xy 138.326497 -391.913226) (xy 138.321034 -391.904474) (xy 138.303994 -391.878939)
			(xy 138.275485 -391.824571) (xy 138.253722 -391.767168) (xy 138.239022 -391.707564) (xy 138.231598 -391.646625)
			(xy 138.231118 -391.61593) (xy 138.231566 -391.585198) (xy 138.238972 -391.52418) (xy 138.253679 -391.464501)
			(xy 138.275472 -391.40703) (xy 138.304035 -391.352604) (xy 138.33895 -391.302019) (xy 138.379709 -391.256012)
			(xy 138.425716 -391.215253) (xy 138.476301 -391.180337) (xy 138.530726 -391.151774) (xy 138.588197 -391.12998)
			(xy 138.647876 -391.115272) (xy 138.708894 -391.107866) (xy 138.739626 -391.107422) (xy 138.770322 -391.107897)
			(xy 138.831267 -391.115299) (xy 138.890876 -391.12999) (xy 138.94828 -391.151758) (xy 139.002643 -391.180284)
			(xy 139.02817 -391.197338) (xy 139.036922 -391.202809) (xy 139.057126 -391.206937) (xy 139.07733 -391.202809)
			(xy 139.086082 -391.197338) (xy 139.120626 -391.175494) (xy 139.128483 -391.170484) (xy 139.140207 -391.156022)
			(xy 139.143486 -391.1473) (xy 139.153138 -391.11809) (xy 139.155604 -391.109158) (xy 139.154694 -391.090667)
			(xy 139.15136 -391.082022) (xy 139.137851 -391.049737) (xy 139.118854 -390.982379) (xy 139.109267 -390.913053)
			(xy 139.108688 -390.87806) (xy 139.109199 -390.845898) (xy 139.117319 -390.782089) (xy 139.133425 -390.719814)
			(xy 139.15726 -390.660068) (xy 139.188441 -390.603808) (xy 139.226472 -390.55193) (xy 139.270744 -390.505266)
			(xy 139.320549 -390.464559) (xy 139.375092 -390.430462) (xy 139.40409 -390.416542) (xy 139.413464 -390.411543)
			(xy 139.427438 -390.395582) (xy 139.433735 -390.375325) (xy 139.433046 -390.364726) (xy 139.431591 -390.350611)
			(xy 139.430067 -390.322273) (xy 139.429998 -390.308084) (xy 139.4305 -390.276123) (xy 139.438511 -390.212705)
			(xy 139.454408 -390.150791) (xy 139.47794 -390.091358) (xy 139.508734 -390.035343) (xy 139.546307 -389.983628)
			(xy 139.590064 -389.937031) (xy 139.639317 -389.896286) (xy 139.693288 -389.862035) (xy 139.751127 -389.834818)
			(xy 139.81192 -389.815065) (xy 139.87471 -389.803087) (xy 139.938506 -389.799074) (xy 140.002302 -389.803087)
			(xy 140.065092 -389.815065) (xy 140.125885 -389.834818) (xy 140.183724 -389.862035) (xy 140.237695 -389.896286)
			(xy 140.286948 -389.937031) (xy 140.330705 -389.983628) (xy 140.368278 -390.035343) (xy 140.399072 -390.091358)
			(xy 140.422604 -390.150791) (xy 140.438501 -390.212705) (xy 140.446512 -390.276123) (xy 140.447014 -390.308084)
			(xy 140.446539 -390.340247) (xy 140.438413 -390.404058) (xy 140.422302 -390.466334) (xy 140.398463 -390.526079)
			(xy 140.367277 -390.58234) (xy 140.329242 -390.634217) (xy 140.284966 -390.680881) (xy 140.235157 -390.721586)
			(xy 140.180611 -390.755682) (xy 140.151612 -390.769602) (xy 140.142197 -390.774531) (xy 140.128237 -390.790529)
			(xy 140.121958 -390.810811) (xy 140.122656 -390.821418) (xy 140.124107 -390.835533) (xy 140.125633 -390.863871)
			(xy 140.125704 -390.87806) (xy 140.125174 -390.911868) (xy 140.116255 -390.978894) (xy 140.107924 -391.011664)
			(xy 140.105384 -391.021062) (xy 140.107416 -391.040112) (xy 140.149326 -391.118852) (xy 140.164058 -391.131298)
			(xy 140.173202 -391.134346) (xy 140.202975 -391.145024) (xy 140.259878 -391.17264) (xy 140.312917 -391.2071)
			(xy 140.361272 -391.247872) (xy 140.404199 -391.294326) (xy 140.441033 -391.345744) (xy 140.471205 -391.401334)
			(xy 140.494251 -391.460236) (xy 140.509815 -391.521542) (xy 140.517655 -391.584305) (xy 140.518134 -391.61593)
			(xy 140.517651 -391.646626) (xy 140.51025 -391.70757) (xy 140.49556 -391.767179) (xy 140.473794 -391.824583)
			(xy 140.44527 -391.878946) (xy 140.428218 -391.904474) (xy 140.422719 -391.913211) (xy 140.418597 -391.933425)
			(xy 140.422738 -391.953634) (xy 140.428218 -391.962386) (xy 140.445235 -391.987936) (xy 140.47375 -392.042299)
			(xy 140.495517 -392.099699) (xy 140.510222 -392.159299) (xy 140.517651 -392.220236) (xy 140.518134 -392.25093)
			(xy 140.517672 -392.281661) (xy 140.510261 -392.342673) (xy 140.49555 -392.402348) (xy 140.473753 -392.459815)
			(xy 140.445189 -392.514235) (xy 140.410274 -392.564816) (xy 140.369518 -392.610821) (xy 140.323513 -392.651577)
			(xy 140.272932 -392.686491) (xy 140.218511 -392.715055) (xy 140.161044 -392.736851) (xy 140.10137 -392.751561)
			(xy 140.040357 -392.758972) (xy 140.009626 -392.759438) (xy 139.988544 -392.75893) (xy 139.977622 -392.758422)
			(xy 139.958064 -392.766042) (xy 139.889738 -392.834368) (xy 139.882118 -392.853926) (xy 139.882626 -392.864848)
			(xy 139.883134 -392.88593) (xy 139.882651 -392.916626) (xy 139.87525 -392.97757) (xy 139.86056 -393.037179)
			(xy 139.838794 -393.094583) (xy 139.81027 -393.148946) (xy 139.793218 -393.174474) (xy 139.787719 -393.183211)
			(xy 139.783597 -393.203425) (xy 139.787738 -393.223634) (xy 139.793218 -393.232386) (xy 139.810235 -393.257936)
			(xy 139.83875 -393.312299) (xy 139.860517 -393.369699) (xy 139.875222 -393.429299) (xy 139.882651 -393.490236)
			(xy 139.883134 -393.52093) (xy 140.738098 -393.52093) (xy 140.738582 -393.49356) (xy 140.746396 -393.439382)
			(xy 140.761881 -393.386879) (xy 140.784718 -393.337132) (xy 140.814439 -393.291164) (xy 140.832078 -393.270232)
			(xy 140.838174 -393.26312) (xy 140.844524 -393.246102) (xy 140.844524 -393.160758) (xy 140.838174 -393.14374)
			(xy 140.832078 -393.136628) (xy 140.814469 -393.11567) (xy 140.784746 -393.069706) (xy 140.761902 -393.019963)
			(xy 140.746406 -392.967465) (xy 140.738576 -392.913291) (xy 140.738572 -392.858554) (xy 140.746396 -392.804379)
			(xy 140.761886 -392.751879) (xy 140.784725 -392.702134) (xy 140.814441 -392.656166) (xy 140.832078 -392.635232)
			(xy 140.838174 -392.62812) (xy 140.844524 -392.611102) (xy 140.844524 -392.525758) (xy 140.838174 -392.50874)
			(xy 140.832078 -392.501628) (xy 140.814469 -392.48067) (xy 140.784746 -392.434706) (xy 140.761902 -392.384963)
			(xy 140.746406 -392.332465) (xy 140.738576 -392.278291) (xy 140.738572 -392.223554) (xy 140.746396 -392.169379)
			(xy 140.761886 -392.116879) (xy 140.784725 -392.067134) (xy 140.814441 -392.021166) (xy 140.832078 -392.000232)
			(xy 140.838174 -391.99312) (xy 140.844524 -391.976102) (xy 140.844524 -391.890758) (xy 140.838174 -391.87374)
			(xy 140.832078 -391.866628) (xy 140.814435 -391.845699) (xy 140.784725 -391.799725) (xy 140.76189 -391.749977)
			(xy 140.7464 -391.697475) (xy 140.738572 -391.643299) (xy 140.738098 -391.61593) (xy 140.738601 -391.588394)
			(xy 140.746503 -391.533894) (xy 140.762163 -391.481096) (xy 140.785253 -391.4311) (xy 140.815294 -391.384945)
			(xy 140.851662 -391.34359) (xy 140.8936 -391.307897) (xy 140.91666 -391.292842) (xy 140.925296 -391.287508)
			(xy 140.936726 -391.271252) (xy 140.957808 -391.181844) (xy 140.954506 -391.162286) (xy 140.949172 -391.15365)
			(xy 140.935741 -391.130982) (xy 140.91457 -391.082732) (xy 140.900225 -391.032032) (xy 140.892977 -390.979843)
			(xy 140.89253 -390.953498) (xy 140.892988 -390.926127) (xy 140.900806 -390.871948) (xy 140.916297 -390.819444)
			(xy 140.939141 -390.769697) (xy 140.968868 -390.723731) (xy 140.98651 -390.7028) (xy 140.992606 -390.695688)
			(xy 140.998956 -390.67867) (xy 140.998956 -390.593326) (xy 140.992606 -390.576308) (xy 140.98651 -390.569196)
			(xy 140.968857 -390.548275) (xy 140.939147 -390.502299) (xy 140.916314 -390.452549) (xy 140.900826 -390.400046)
			(xy 140.893002 -390.345868) (xy 140.89253 -390.318498) (xy 140.893016 -390.291247) (xy 140.900772 -390.237299)
			(xy 140.916127 -390.185004) (xy 140.938769 -390.135427) (xy 140.968235 -390.089577) (xy 141.003926 -390.048386)
			(xy 141.045117 -390.012695) (xy 141.090967 -389.983229) (xy 141.140544 -389.960587) (xy 141.192839 -389.945232)
			(xy 141.246787 -389.937476) (xy 141.301289 -389.937476) (xy 141.355237 -389.945232) (xy 141.407532 -389.960587)
			(xy 141.457109 -389.983229) (xy 141.502959 -390.012695) (xy 141.54415 -390.048386) (xy 141.579841 -390.089577)
			(xy 141.609307 -390.135427) (xy 141.631949 -390.185004) (xy 141.647304 -390.237299) (xy 141.65506 -390.291247)
			(xy 141.655546 -390.318498) (xy 141.655092 -390.345869) (xy 141.647273 -390.400049) (xy 141.631782 -390.452553)
			(xy 141.608937 -390.502299) (xy 141.579209 -390.548265) (xy 141.561566 -390.569196) (xy 141.55547 -390.576308)
			(xy 141.54912 -390.593326) (xy 141.54912 -390.67867) (xy 141.55547 -390.695688) (xy 141.561566 -390.7028)
			(xy 141.579213 -390.723726) (xy 141.608925 -390.7697) (xy 141.63176 -390.819449) (xy 141.647249 -390.871951)
			(xy 141.655074 -390.926128) (xy 141.655546 -390.953498) (xy 141.655167 -390.977849) (xy 141.648946 -391.026152)
			(xy 141.636619 -391.073267) (xy 141.62786 -391.095992) (xy 141.623034 -391.108438) (xy 141.626082 -391.133838)
			(xy 141.692376 -391.225278) (xy 141.715744 -391.2362) (xy 141.728952 -391.235184) (xy 141.754606 -391.234422)
			(xy 141.781977 -391.234879) (xy 141.836156 -391.242698) (xy 141.88866 -391.258189) (xy 141.938406 -391.281033)
			(xy 141.984373 -391.31076) (xy 142.005304 -391.328402) (xy 142.012416 -391.334498) (xy 142.029434 -391.340848)
			(xy 142.114778 -391.340848) (xy 142.131796 -391.334498) (xy 142.138908 -391.328402) (xy 142.159841 -391.310761)
			(xy 142.205809 -391.281037) (xy 142.255555 -391.258191) (xy 142.308057 -391.242695) (xy 142.362235 -391.234866)
			(xy 142.416977 -391.234866) (xy 142.471155 -391.242695) (xy 142.523657 -391.258191) (xy 142.573403 -391.281037)
			(xy 142.619371 -391.310761) (xy 142.640304 -391.328402) (xy 142.647416 -391.334498) (xy 142.664434 -391.340848)
			(xy 142.749778 -391.340848) (xy 142.766796 -391.334498) (xy 142.773908 -391.328402) (xy 142.794826 -391.310746)
			(xy 142.840803 -391.281037) (xy 142.890554 -391.258204) (xy 142.943058 -391.242717) (xy 142.997236 -391.234893)
			(xy 143.024606 -391.234422) (xy 143.05186 -391.23485) (xy 143.105814 -391.242608) (xy 143.158114 -391.257967)
			(xy 143.207697 -391.280612) (xy 143.253551 -391.310084) (xy 143.294745 -391.345781) (xy 143.330438 -391.386978)
			(xy 143.359905 -391.432835) (xy 143.382546 -391.482419) (xy 143.397899 -391.534721) (xy 143.405653 -391.588676)
			(xy 143.406114 -391.61593) (xy 143.405662 -391.643301) (xy 143.39784 -391.69748) (xy 143.382348 -391.749983)
			(xy 143.359503 -391.79973) (xy 143.329776 -391.845696) (xy 143.312134 -391.866628) (xy 143.306038 -391.87374)
			(xy 143.299688 -391.890758) (xy 143.299688 -391.976102) (xy 143.306038 -391.99312) (xy 143.312134 -392.000232)
			(xy 143.329806 -392.02114) (xy 143.359532 -392.067111) (xy 143.382378 -392.116861) (xy 143.397874 -392.169367)
			(xy 143.405701 -392.22355) (xy 143.405697 -392.278295) (xy 143.397864 -392.332477) (xy 143.382362 -392.384981)
			(xy 143.35951 -392.434728) (xy 143.329778 -392.480696) (xy 143.312134 -392.501628) (xy 143.306038 -392.50874)
			(xy 143.299688 -392.525758) (xy 143.299688 -392.611102) (xy 143.306038 -392.62812) (xy 143.312134 -392.635232)
			(xy 143.329806 -392.65614) (xy 143.359532 -392.702111) (xy 143.382378 -392.751861) (xy 143.397874 -392.804367)
			(xy 143.405701 -392.85855) (xy 143.405697 -392.913295) (xy 143.397864 -392.967477) (xy 143.382362 -393.019981)
			(xy 143.35951 -393.069728) (xy 143.329778 -393.115696) (xy 143.312134 -393.136628) (xy 143.306038 -393.14374)
			(xy 143.299688 -393.160758) (xy 143.299688 -393.246102) (xy 143.306038 -393.26312) (xy 143.312134 -393.270232)
			(xy 143.32976 -393.291175) (xy 143.359473 -393.337145) (xy 143.382311 -393.38689) (xy 143.397805 -393.439388)
			(xy 143.405637 -393.493562) (xy 143.406114 -393.52093) (xy 143.40565 -393.548182) (xy 143.39789 -393.60213)
			(xy 143.382531 -393.654425) (xy 143.359887 -393.704002) (xy 143.330418 -393.749852) (xy 143.294724 -393.791041)
			(xy 143.253532 -393.826732) (xy 143.207681 -393.856198) (xy 143.158102 -393.878839) (xy 143.105806 -393.894195)
			(xy 143.051858 -393.901952) (xy 143.024606 -393.902438) (xy 142.997235 -393.901984) (xy 142.943055 -393.894165)
			(xy 142.890551 -393.878674) (xy 142.840804 -393.85583) (xy 142.794839 -393.826101) (xy 142.773908 -393.808458)
			(xy 142.766796 -393.802362) (xy 142.749778 -393.796012) (xy 142.664434 -393.796012) (xy 142.647416 -393.802362)
			(xy 142.640304 -393.808458) (xy 142.619371 -393.826099) (xy 142.573403 -393.855823) (xy 142.523657 -393.878669)
			(xy 142.471155 -393.894165) (xy 142.416977 -393.901994) (xy 142.362235 -393.901994) (xy 142.308057 -393.894165)
			(xy 142.255555 -393.878669) (xy 142.205809 -393.855823) (xy 142.159841 -393.826099) (xy 142.138908 -393.808458)
			(xy 142.131796 -393.802362) (xy 142.114778 -393.796012) (xy 142.029434 -393.796012) (xy 142.012416 -393.802362)
			(xy 142.005304 -393.808458) (xy 141.984371 -393.826099) (xy 141.938403 -393.855823) (xy 141.888657 -393.878669)
			(xy 141.836155 -393.894165) (xy 141.781977 -393.901994) (xy 141.727235 -393.901994) (xy 141.673057 -393.894165)
			(xy 141.620555 -393.878669) (xy 141.570809 -393.855823) (xy 141.524841 -393.826099) (xy 141.503908 -393.808458)
			(xy 141.496796 -393.802362) (xy 141.479778 -393.796012) (xy 141.394434 -393.796012) (xy 141.377416 -393.802362)
			(xy 141.370304 -393.808458) (xy 141.349376 -393.826102) (xy 141.303403 -393.855815) (xy 141.253654 -393.87865)
			(xy 141.201152 -393.89414) (xy 141.146976 -393.901966) (xy 141.119606 -393.902438) (xy 141.092356 -393.901917)
			(xy 141.038411 -393.894162) (xy 140.986119 -393.878809) (xy 140.936544 -393.856171) (xy 140.890695 -393.826708)
			(xy 140.849505 -393.79102) (xy 140.813814 -393.749834) (xy 140.784347 -393.703988) (xy 140.761704 -393.654415)
			(xy 140.746346 -393.602124) (xy 140.738586 -393.54818) (xy 140.738098 -393.52093) (xy 139.883134 -393.52093)
			(xy 139.882672 -393.551661) (xy 139.875261 -393.612673) (xy 139.86055 -393.672348) (xy 139.838753 -393.729815)
			(xy 139.810189 -393.784235) (xy 139.775274 -393.834816) (xy 139.734518 -393.880821) (xy 139.688513 -393.921577)
			(xy 139.637932 -393.956491) (xy 139.583511 -393.985055) (xy 139.526044 -394.006851) (xy 139.46637 -394.021561)
			(xy 139.405357 -394.028972) (xy 139.374626 -394.029438) (xy 139.343929 -394.028977) (xy 139.282984 -394.02157)
			(xy 139.223376 -394.006875) (xy 139.165972 -393.985105) (xy 139.111609 -393.956576) (xy 139.086082 -393.939522)
			(xy 139.07733 -393.934051) (xy 139.057126 -393.929923) (xy 139.036922 -393.934051) (xy 139.02817 -393.939522)
			(xy 139.002633 -393.956559) (xy 138.948266 -393.98507) (xy 138.890863 -394.006833) (xy 138.83126 -394.021534)
			(xy 138.770321 -394.028958) (xy 138.739626 -394.029438) (xy 138.708929 -394.028977) (xy 138.647984 -394.02157)
			(xy 138.588376 -394.006875) (xy 138.530972 -393.985105) (xy 138.476609 -393.956576) (xy 138.451082 -393.939522)
			(xy 138.44233 -393.934051) (xy 138.422126 -393.929923) (xy 138.401922 -393.934051) (xy 138.39317 -393.939522)
			(xy 138.367633 -393.956559) (xy 138.313266 -393.98507) (xy 138.255863 -394.006833) (xy 138.19626 -394.021534)
			(xy 138.135321 -394.028958) (xy 138.104626 -394.029438) (xy 138.073929 -394.028977) (xy 138.012984 -394.02157)
			(xy 137.953376 -394.006875) (xy 137.895972 -393.985105) (xy 137.841609 -393.956576) (xy 137.816082 -393.939522)
			(xy 137.80733 -393.934051) (xy 137.787126 -393.929923) (xy 137.766922 -393.934051) (xy 137.75817 -393.939522)
			(xy 137.732633 -393.956559) (xy 137.678266 -393.98507) (xy 137.620863 -394.006833) (xy 137.56126 -394.021534)
			(xy 137.500321 -394.028958) (xy 137.469626 -394.029438) (xy 137.438929 -394.028977) (xy 137.377984 -394.02157)
			(xy 137.318376 -394.006875) (xy 137.260972 -393.985105) (xy 137.206609 -393.956576) (xy 137.181082 -393.939522)
			(xy 137.17233 -393.934051) (xy 137.152126 -393.929923) (xy 137.131922 -393.934051) (xy 137.12317 -393.939522)
			(xy 137.097633 -393.956559) (xy 137.043266 -393.98507) (xy 136.985863 -394.006833) (xy 136.92626 -394.021534)
			(xy 136.865321 -394.028958) (xy 136.834626 -394.029438) (xy 136.803897 -394.02892) (xy 136.742886 -394.021515)
			(xy 136.683212 -394.00681) (xy 136.625747 -393.985019) (xy 136.571326 -393.956461) (xy 136.520745 -393.921551)
			(xy 136.47474 -393.880799) (xy 136.433983 -393.834799) (xy 136.399068 -393.784222) (xy 136.370504 -393.729805)
			(xy 136.348707 -393.672341) (xy 136.333995 -393.612669) (xy 136.326584 -393.551659) (xy 136.326118 -393.52093)
			(xy 135.596122 -393.52093) (xy 135.596122 -393.922758) (xy 135.596556 -393.932823) (xy 135.604288 -393.95141)
			(xy 135.611108 -393.958826) (xy 136.14146 -394.489178) (xy 136.148808 -394.495981) (xy 136.16727 -394.503696)
			(xy 136.177274 -394.504164)
		)
		(stroke
			(width 0)
			(type solid)
		)
		(fill yes)
		(layer "In2.Cu")
		(net "P0V9_CPU1_RT2_2A_2D")
	)
	(gr_poly
		(pts
			(xy 399.251678 -403.14118) (xy 399.261639 -403.140691) (xy 399.280058 -403.133098) (xy 399.287492 -403.126448)
			(xy 399.387314 -403.026626) (xy 399.394158 -403.019228) (xy 399.401879 -403.000628) (xy 399.4023 -402.990558)
			(xy 399.4023 -402.92782) (xy 399.399506 -402.91639) (xy 399.396712 -402.910802) (xy 399.385674 -402.888417)
			(xy 399.370054 -402.841016) (xy 399.362145 -402.791738) (xy 399.36166 -402.766784) (xy 399.36166 -402.324824)
			(xy 399.36123 -402.316022) (xy 399.35517 -402.299487) (xy 399.34389 -402.285964) (xy 399.336514 -402.281136)
			(xy 399.249138 -402.229828) (xy 399.222214 -402.229574) (xy 399.21053 -402.236178) (xy 399.189134 -402.247663)
			(xy 399.144057 -402.265727) (xy 399.097054 -402.27793) (xy 399.048883 -402.284074) (xy 399.024602 -402.284438)
			(xy 398.997232 -402.283966) (xy 398.943055 -402.276142) (xy 398.890552 -402.260653) (xy 398.840803 -402.237818)
			(xy 398.794829 -402.208106) (xy 398.773904 -402.190458) (xy 398.766792 -402.184362) (xy 398.749774 -402.178012)
			(xy 398.66443 -402.178012) (xy 398.647412 -402.184362) (xy 398.6403 -402.190458) (xy 398.619367 -402.208099)
			(xy 398.573399 -402.237823) (xy 398.523653 -402.260669) (xy 398.471151 -402.276165) (xy 398.416973 -402.283994)
			(xy 398.362231 -402.283994) (xy 398.308053 -402.276165) (xy 398.255551 -402.260669) (xy 398.205805 -402.237823)
			(xy 398.159837 -402.208099) (xy 398.138904 -402.190458) (xy 398.131792 -402.184362) (xy 398.114774 -402.178012)
			(xy 398.02943 -402.178012) (xy 398.012412 -402.184362) (xy 398.0053 -402.190458) (xy 397.984367 -402.208099)
			(xy 397.938399 -402.237823) (xy 397.888653 -402.260669) (xy 397.836151 -402.276165) (xy 397.781973 -402.283994)
			(xy 397.727231 -402.283994) (xy 397.673053 -402.276165) (xy 397.620551 -402.260669) (xy 397.570805 -402.237823)
			(xy 397.524837 -402.208099) (xy 397.503904 -402.190458) (xy 397.496792 -402.184362) (xy 397.479774 -402.178012)
			(xy 397.39443 -402.178012) (xy 397.377412 -402.184362) (xy 397.3703 -402.190458) (xy 397.349369 -402.208102)
			(xy 397.303404 -402.237831) (xy 397.253657 -402.260677) (xy 397.201153 -402.276169) (xy 397.146973 -402.283988)
			(xy 397.119602 -402.284438) (xy 397.09235 -402.283952) (xy 397.0384 -402.276196) (xy 396.986104 -402.260842)
			(xy 396.936524 -402.238201) (xy 396.890671 -402.208735) (xy 396.849479 -402.173044) (xy 396.813784 -402.131854)
			(xy 396.784314 -402.086004) (xy 396.76167 -402.036426) (xy 396.746311 -401.984131) (xy 396.73855 -401.930182)
			(xy 396.738094 -401.90293) (xy 396.738571 -401.875562) (xy 396.746403 -401.821388) (xy 396.761898 -401.76889)
			(xy 396.784736 -401.719146) (xy 396.814449 -401.673176) (xy 396.832074 -401.652232) (xy 396.83817 -401.64512)
			(xy 396.84452 -401.628102) (xy 396.84452 -401.542758) (xy 396.83817 -401.52574) (xy 396.832074 -401.518628)
			(xy 396.814429 -401.497696) (xy 396.784697 -401.451729) (xy 396.761844 -401.401981) (xy 396.746342 -401.349477)
			(xy 396.738509 -401.295295) (xy 396.738506 -401.24055) (xy 396.746332 -401.186367) (xy 396.761828 -401.133861)
			(xy 396.784675 -401.084111) (xy 396.814402 -401.03814) (xy 396.832074 -401.017232) (xy 396.83817 -401.01012)
			(xy 396.84452 -400.993102) (xy 396.84452 -400.907758) (xy 396.83817 -400.89074) (xy 396.832074 -400.883628)
			(xy 396.814429 -400.862696) (xy 396.784697 -400.816729) (xy 396.761844 -400.766981) (xy 396.746342 -400.714477)
			(xy 396.738509 -400.660295) (xy 396.738506 -400.60555) (xy 396.746332 -400.551367) (xy 396.761828 -400.498861)
			(xy 396.784675 -400.449111) (xy 396.814402 -400.40314) (xy 396.832074 -400.382232) (xy 396.83817 -400.37512)
			(xy 396.84452 -400.358102) (xy 396.84452 -400.272758) (xy 396.83817 -400.25574) (xy 396.832074 -400.248628)
			(xy 396.814432 -400.227697) (xy 396.784704 -400.18173) (xy 396.761859 -400.131984) (xy 396.746366 -400.079481)
			(xy 396.738544 -400.025301) (xy 396.738094 -399.99793) (xy 396.738582 -399.969973) (xy 396.746744 -399.914657)
			(xy 396.762896 -399.861126) (xy 396.786693 -399.810529) (xy 396.817624 -399.763948) (xy 396.855026 -399.722385)
			(xy 396.898097 -399.686729) (xy 396.921736 -399.671794) (xy 396.930372 -399.66646) (xy 396.942056 -399.650712)
			(xy 396.964916 -399.562828) (xy 396.962122 -399.543016) (xy 396.957296 -399.53438) (xy 396.945361 -399.512683)
			(xy 396.92657 -399.466868) (xy 396.913854 -399.419009) (xy 396.907426 -399.369909) (xy 396.907004 -399.34515)
			(xy 396.907591 -399.31525) (xy 396.916911 -399.25618) (xy 396.925546 -399.227548) (xy 396.929102 -399.21688)
			(xy 396.926308 -399.195036) (xy 396.874492 -399.109946) (xy 396.856204 -399.097754) (xy 396.845028 -399.095976)
			(xy 396.818516 -399.091235) (xy 396.767079 -399.075274) (xy 396.718398 -399.052237) (xy 396.673442 -399.022581)
			(xy 396.633104 -398.986895) (xy 396.598187 -398.945891) (xy 396.569385 -398.900383) (xy 396.547271 -398.851276)
			(xy 396.532285 -398.799546) (xy 396.524724 -398.746223) (xy 396.524226 -398.719294) (xy 396.524712 -398.692043)
			(xy 396.532468 -398.638095) (xy 396.547823 -398.5858) (xy 396.570465 -398.536223) (xy 396.599931 -398.490373)
			(xy 396.635622 -398.449182) (xy 396.676813 -398.413491) (xy 396.722663 -398.384025) (xy 396.77224 -398.361383)
			(xy 396.824535 -398.346028) (xy 396.878483 -398.338272) (xy 396.932985 -398.338272) (xy 396.986933 -398.346028)
			(xy 397.039228 -398.361383) (xy 397.088805 -398.384025) (xy 397.134655 -398.413491) (xy 397.175846 -398.449182)
			(xy 397.211537 -398.490373) (xy 397.241003 -398.536223) (xy 397.263645 -398.5858) (xy 397.279 -398.638095)
			(xy 397.286756 -398.692043) (xy 397.287242 -398.719294) (xy 397.286659 -398.749195) (xy 397.277346 -398.808267)
			(xy 397.2687 -398.836896) (xy 397.265144 -398.847564) (xy 397.267938 -398.869408) (xy 397.319754 -398.954498)
			(xy 397.338042 -398.96669) (xy 397.349218 -398.968468) (xy 397.375729 -398.973211) (xy 397.427165 -398.989176)
			(xy 397.475844 -399.012215) (xy 397.5208 -399.041872) (xy 397.561137 -399.077557) (xy 397.596055 -399.11856)
			(xy 397.624859 -399.164067) (xy 397.646976 -399.213172) (xy 397.661968 -399.2649) (xy 397.669535 -399.318222)
			(xy 397.67002 -399.34515) (xy 397.669295 -399.379439) (xy 397.657021 -399.44691) (xy 397.645636 -399.479262)
			(xy 397.641064 -399.491454) (xy 397.644366 -399.516346) (xy 397.708374 -399.605754) (xy 397.730726 -399.61693)
			(xy 397.74368 -399.616676) (xy 397.754602 -399.616422) (xy 397.781972 -399.616894) (xy 397.83615 -399.624718)
			(xy 397.888653 -399.640206) (xy 397.938403 -399.66304) (xy 397.984379 -399.69275) (xy 398.0053 -399.710402)
			(xy 398.012412 -399.716498) (xy 398.02943 -399.722848) (xy 398.114774 -399.722848) (xy 398.131792 -399.716498)
			(xy 398.138904 -399.710402) (xy 398.159837 -399.692761) (xy 398.205805 -399.663037) (xy 398.255551 -399.640191)
			(xy 398.308053 -399.624695) (xy 398.362231 -399.616866) (xy 398.416973 -399.616866) (xy 398.471151 -399.624695)
			(xy 398.523653 -399.640191) (xy 398.573399 -399.663037) (xy 398.619367 -399.692761) (xy 398.6403 -399.710402)
			(xy 398.647412 -399.716498) (xy 398.66443 -399.722848) (xy 398.749774 -399.722848) (xy 398.766792 -399.716498)
			(xy 398.773904 -399.710402) (xy 398.794835 -399.69276) (xy 398.840802 -399.663034) (xy 398.890549 -399.640192)
			(xy 398.943052 -399.624702) (xy 398.997232 -399.616884) (xy 399.024602 -399.616422) (xy 399.050944 -399.616858)
			(xy 399.10313 -399.624093) (xy 399.153824 -399.638438) (xy 399.202062 -399.659621) (xy 399.246928 -399.687239)
			(xy 399.287567 -399.720766) (xy 399.323208 -399.759566) (xy 399.353171 -399.8029) (xy 399.376889 -399.849944)
			(xy 399.38579 -399.87474) (xy 399.389854 -399.88744) (xy 399.409412 -399.904966) (xy 399.506186 -399.927318)
			(xy 399.514653 -399.928978) (xy 399.5318 -399.927153) (xy 399.547363 -399.919728) (xy 399.553684 -399.913856)
			(xy 400.207734 -399.259806) (xy 400.215134 -399.252964) (xy 400.233732 -399.245241) (xy 400.243802 -399.24482)
			(xy 400.31035 -399.24482) (xy 400.322421 -399.244151) (xy 400.343908 -399.233147) (xy 400.351498 -399.223738)
			(xy 400.407124 -399.147284) (xy 400.41068 -399.123154) (xy 400.40687 -399.11147) (xy 400.399155 -399.086325)
			(xy 400.390866 -399.034389) (xy 400.39036 -399.008092) (xy 400.390754 -398.984858) (xy 400.397257 -398.938848)
			(xy 400.410135 -398.8942) (xy 400.429133 -398.851794) (xy 400.453878 -398.812463) (xy 400.468592 -398.794478)
			(xy 400.474688 -398.787366) (xy 400.480784 -398.770856) (xy 400.480784 -398.686528) (xy 400.474688 -398.670018)
			(xy 400.468592 -398.662906) (xy 400.453883 -398.644916) (xy 400.429126 -398.60559) (xy 400.410119 -398.563186)
			(xy 400.397236 -398.518538) (xy 400.390731 -398.472527) (xy 400.39036 -398.449292) (xy 400.39087 -398.423305)
			(xy 400.399 -398.37197) (xy 400.415061 -398.32254) (xy 400.438657 -398.27623) (xy 400.469207 -398.234182)
			(xy 400.505958 -398.197431) (xy 400.548006 -398.166881) (xy 400.594316 -398.143285) (xy 400.643746 -398.127224)
			(xy 400.695081 -398.119094) (xy 400.747055 -398.119094) (xy 400.79839 -398.127224) (xy 400.84782 -398.143285)
			(xy 400.89413 -398.166881) (xy 400.936178 -398.197431) (xy 400.972929 -398.234182) (xy 401.003479 -398.27623)
			(xy 401.027075 -398.32254) (xy 401.043136 -398.37197) (xy 401.051266 -398.423305) (xy 401.051776 -398.449292)
			(xy 401.051383 -398.472526) (xy 401.044881 -398.518536) (xy 401.038113 -398.542002) (xy 402.712948 -398.542002)
			(xy 402.716908 -398.492948) (xy 402.728685 -398.445164) (xy 402.747976 -398.399888) (xy 402.774279 -398.358292)
			(xy 402.806914 -398.321455) (xy 402.845035 -398.29033) (xy 402.887656 -398.265723) (xy 402.933672 -398.248271)
			(xy 402.981891 -398.238427) (xy 403.031066 -398.236446) (xy 403.079921 -398.242378) (xy 403.127192 -398.25607)
			(xy 403.171654 -398.277168) (xy 403.212157 -398.305124) (xy 403.24765 -398.339216) (xy 403.277215 -398.37856)
			(xy 403.300086 -398.422137) (xy 403.31567 -398.468818) (xy 403.323565 -398.517395) (xy 403.32406 -398.542002)
			(xy 403.913098 -398.542002) (xy 403.917058 -398.492948) (xy 403.928835 -398.445164) (xy 403.948126 -398.399888)
			(xy 403.974429 -398.358292) (xy 404.007064 -398.321455) (xy 404.045185 -398.29033) (xy 404.087806 -398.265723)
			(xy 404.133822 -398.248271) (xy 404.182041 -398.238427) (xy 404.231216 -398.236446) (xy 404.280071 -398.242378)
			(xy 404.327342 -398.25607) (xy 404.371804 -398.277168) (xy 404.412307 -398.305124) (xy 404.4478 -398.339216)
			(xy 404.477365 -398.37856) (xy 404.500236 -398.422137) (xy 404.51582 -398.468818) (xy 404.523715 -398.517395)
			(xy 404.52421 -398.542002) (xy 405.113248 -398.542002) (xy 405.117208 -398.492948) (xy 405.128985 -398.445164)
			(xy 405.148276 -398.399888) (xy 405.174579 -398.358292) (xy 405.207214 -398.321455) (xy 405.245335 -398.29033)
			(xy 405.287956 -398.265723) (xy 405.333972 -398.248271) (xy 405.382191 -398.238427) (xy 405.431366 -398.236446)
			(xy 405.480221 -398.242378) (xy 405.527492 -398.25607) (xy 405.571954 -398.277168) (xy 405.612457 -398.305124)
			(xy 405.64795 -398.339216) (xy 405.677515 -398.37856) (xy 405.700386 -398.422137) (xy 405.71597 -398.468818)
			(xy 405.723865 -398.517395) (xy 405.72436 -398.542002) (xy 406.313144 -398.542002) (xy 406.317104 -398.492948)
			(xy 406.328881 -398.445164) (xy 406.348172 -398.399888) (xy 406.374475 -398.358292) (xy 406.40711 -398.321455)
			(xy 406.445231 -398.29033) (xy 406.487852 -398.265723) (xy 406.533868 -398.248271) (xy 406.582087 -398.238427)
			(xy 406.631262 -398.236446) (xy 406.680117 -398.242378) (xy 406.727388 -398.25607) (xy 406.77185 -398.277168)
			(xy 406.812353 -398.305124) (xy 406.847846 -398.339216) (xy 406.877411 -398.37856) (xy 406.900282 -398.422137)
			(xy 406.915866 -398.468818) (xy 406.923761 -398.517395) (xy 406.924256 -398.542002) (xy 407.513294 -398.542002)
			(xy 407.517254 -398.492948) (xy 407.529031 -398.445164) (xy 407.548322 -398.399888) (xy 407.574625 -398.358292)
			(xy 407.60726 -398.321455) (xy 407.645381 -398.29033) (xy 407.688002 -398.265723) (xy 407.734018 -398.248271)
			(xy 407.782237 -398.238427) (xy 407.831412 -398.236446) (xy 407.880267 -398.242378) (xy 407.927538 -398.25607)
			(xy 407.972 -398.277168) (xy 408.012503 -398.305124) (xy 408.047996 -398.339216) (xy 408.077561 -398.37856)
			(xy 408.100432 -398.422137) (xy 408.116016 -398.468818) (xy 408.123911 -398.517395) (xy 408.124406 -398.542002)
			(xy 408.71319 -398.542002) (xy 408.71715 -398.492948) (xy 408.728927 -398.445164) (xy 408.748218 -398.399888)
			(xy 408.774521 -398.358292) (xy 408.807156 -398.321455) (xy 408.845277 -398.29033) (xy 408.887898 -398.265723)
			(xy 408.933914 -398.248271) (xy 408.982133 -398.238427) (xy 409.031308 -398.236446) (xy 409.080163 -398.242378)
			(xy 409.127434 -398.25607) (xy 409.171896 -398.277168) (xy 409.212399 -398.305124) (xy 409.247892 -398.339216)
			(xy 409.277457 -398.37856) (xy 409.300328 -398.422137) (xy 409.315912 -398.468818) (xy 409.323807 -398.517395)
			(xy 409.324302 -398.542002) (xy 409.913086 -398.542002) (xy 409.917046 -398.492948) (xy 409.928823 -398.445164)
			(xy 409.948114 -398.399888) (xy 409.974417 -398.358292) (xy 410.007052 -398.321455) (xy 410.045173 -398.29033)
			(xy 410.087794 -398.265723) (xy 410.13381 -398.248271) (xy 410.182029 -398.238427) (xy 410.231204 -398.236446)
			(xy 410.280059 -398.242378) (xy 410.32733 -398.25607) (xy 410.371792 -398.277168) (xy 410.412295 -398.305124)
			(xy 410.447788 -398.339216) (xy 410.477353 -398.37856) (xy 410.500224 -398.422137) (xy 410.515808 -398.468818)
			(xy 410.523703 -398.517395) (xy 410.524198 -398.542002) (xy 411.113236 -398.542002) (xy 411.117196 -398.492948)
			(xy 411.128973 -398.445164) (xy 411.148264 -398.399888) (xy 411.174567 -398.358292) (xy 411.207202 -398.321455)
			(xy 411.245323 -398.29033) (xy 411.287944 -398.265723) (xy 411.33396 -398.248271) (xy 411.382179 -398.238427)
			(xy 411.431354 -398.236446) (xy 411.480209 -398.242378) (xy 411.52748 -398.25607) (xy 411.571942 -398.277168)
			(xy 411.612445 -398.305124) (xy 411.647938 -398.339216) (xy 411.677503 -398.37856) (xy 411.700374 -398.422137)
			(xy 411.715958 -398.468818) (xy 411.723853 -398.517395) (xy 411.724348 -398.542002) (xy 412.313132 -398.542002)
			(xy 412.317092 -398.492948) (xy 412.328869 -398.445164) (xy 412.34816 -398.399888) (xy 412.374463 -398.358292)
			(xy 412.407098 -398.321455) (xy 412.445219 -398.29033) (xy 412.48784 -398.265723) (xy 412.533856 -398.248271)
			(xy 412.582075 -398.238427) (xy 412.63125 -398.236446) (xy 412.680105 -398.242378) (xy 412.727376 -398.25607)
			(xy 412.771838 -398.277168) (xy 412.812341 -398.305124) (xy 412.847834 -398.339216) (xy 412.877399 -398.37856)
			(xy 412.90027 -398.422137) (xy 412.915854 -398.468818) (xy 412.923749 -398.517395) (xy 412.924244 -398.542002)
			(xy 413.513282 -398.542002) (xy 413.517242 -398.492948) (xy 413.529019 -398.445164) (xy 413.54831 -398.399888)
			(xy 413.574613 -398.358292) (xy 413.607248 -398.321455) (xy 413.645369 -398.29033) (xy 413.68799 -398.265723)
			(xy 413.734006 -398.248271) (xy 413.782225 -398.238427) (xy 413.8314 -398.236446) (xy 413.880255 -398.242378)
			(xy 413.927526 -398.25607) (xy 413.971988 -398.277168) (xy 414.012491 -398.305124) (xy 414.047984 -398.339216)
			(xy 414.077549 -398.37856) (xy 414.10042 -398.422137) (xy 414.116004 -398.468818) (xy 414.123899 -398.517395)
			(xy 414.124394 -398.542002) (xy 414.713178 -398.542002) (xy 414.717138 -398.492948) (xy 414.728915 -398.445164)
			(xy 414.748206 -398.399888) (xy 414.774509 -398.358292) (xy 414.807144 -398.321455) (xy 414.845265 -398.29033)
			(xy 414.887886 -398.265723) (xy 414.933902 -398.248271) (xy 414.982121 -398.238427) (xy 415.031296 -398.236446)
			(xy 415.080151 -398.242378) (xy 415.127422 -398.25607) (xy 415.171884 -398.277168) (xy 415.212387 -398.305124)
			(xy 415.24788 -398.339216) (xy 415.277445 -398.37856) (xy 415.300316 -398.422137) (xy 415.3159 -398.468818)
			(xy 415.323795 -398.517395) (xy 415.32429 -398.542002) (xy 415.913074 -398.542002) (xy 415.917034 -398.492948)
			(xy 415.928811 -398.445164) (xy 415.948102 -398.399888) (xy 415.974405 -398.358292) (xy 416.00704 -398.321455)
			(xy 416.045161 -398.29033) (xy 416.087782 -398.265723) (xy 416.133798 -398.248271) (xy 416.182017 -398.238427)
			(xy 416.231192 -398.236446) (xy 416.280047 -398.242378) (xy 416.327318 -398.25607) (xy 416.37178 -398.277168)
			(xy 416.412283 -398.305124) (xy 416.447776 -398.339216) (xy 416.477341 -398.37856) (xy 416.500212 -398.422137)
			(xy 416.515796 -398.468818) (xy 416.523691 -398.517395) (xy 416.524186 -398.542002) (xy 417.113224 -398.542002)
			(xy 417.117184 -398.492948) (xy 417.128961 -398.445164) (xy 417.148252 -398.399888) (xy 417.174555 -398.358292)
			(xy 417.20719 -398.321455) (xy 417.245311 -398.29033) (xy 417.287932 -398.265723) (xy 417.333948 -398.248271)
			(xy 417.382167 -398.238427) (xy 417.431342 -398.236446) (xy 417.480197 -398.242378) (xy 417.527468 -398.25607)
			(xy 417.57193 -398.277168) (xy 417.612433 -398.305124) (xy 417.647926 -398.339216) (xy 417.677491 -398.37856)
			(xy 417.700362 -398.422137) (xy 417.715946 -398.468818) (xy 417.723841 -398.517395) (xy 417.724336 -398.542002)
			(xy 418.31312 -398.542002) (xy 418.31708 -398.492948) (xy 418.328857 -398.445164) (xy 418.348148 -398.399888)
			(xy 418.374451 -398.358292) (xy 418.407086 -398.321455) (xy 418.445207 -398.29033) (xy 418.487828 -398.265723)
			(xy 418.533844 -398.248271) (xy 418.582063 -398.238427) (xy 418.631238 -398.236446) (xy 418.680093 -398.242378)
			(xy 418.727364 -398.25607) (xy 418.771826 -398.277168) (xy 418.812329 -398.305124) (xy 418.847822 -398.339216)
			(xy 418.877387 -398.37856) (xy 418.900258 -398.422137) (xy 418.915842 -398.468818) (xy 418.923737 -398.517395)
			(xy 418.924232 -398.542002) (xy 419.51327 -398.542002) (xy 419.51723 -398.492948) (xy 419.529007 -398.445164)
			(xy 419.548298 -398.399888) (xy 419.574601 -398.358292) (xy 419.607236 -398.321455) (xy 419.645357 -398.29033)
			(xy 419.687978 -398.265723) (xy 419.733994 -398.248271) (xy 419.782213 -398.238427) (xy 419.831388 -398.236446)
			(xy 419.880243 -398.242378) (xy 419.927514 -398.25607) (xy 419.971976 -398.277168) (xy 420.012479 -398.305124)
			(xy 420.047972 -398.339216) (xy 420.077537 -398.37856) (xy 420.100408 -398.422137) (xy 420.115992 -398.468818)
			(xy 420.123887 -398.517395) (xy 420.124382 -398.542002) (xy 420.123887 -398.566609) (xy 420.115992 -398.615186)
			(xy 420.100408 -398.661867) (xy 420.077537 -398.705444) (xy 420.047972 -398.744788) (xy 420.012479 -398.77888)
			(xy 419.971976 -398.806836) (xy 419.927514 -398.827934) (xy 419.880243 -398.841626) (xy 419.831388 -398.847558)
			(xy 419.782213 -398.845577) (xy 419.733994 -398.835733) (xy 419.687978 -398.818281) (xy 419.645357 -398.793674)
			(xy 419.607236 -398.762549) (xy 419.574601 -398.725712) (xy 419.548298 -398.684116) (xy 419.529007 -398.63884)
			(xy 419.51723 -398.591056) (xy 419.51327 -398.542002) (xy 418.924232 -398.542002) (xy 418.923737 -398.566609)
			(xy 418.915842 -398.615186) (xy 418.900258 -398.661867) (xy 418.877387 -398.705444) (xy 418.847822 -398.744788)
			(xy 418.812329 -398.77888) (xy 418.771826 -398.806836) (xy 418.727364 -398.827934) (xy 418.680093 -398.841626)
			(xy 418.631238 -398.847558) (xy 418.582063 -398.845577) (xy 418.533844 -398.835733) (xy 418.487828 -398.818281)
			(xy 418.445207 -398.793674) (xy 418.407086 -398.762549) (xy 418.374451 -398.725712) (xy 418.348148 -398.684116)
			(xy 418.328857 -398.63884) (xy 418.31708 -398.591056) (xy 418.31312 -398.542002) (xy 417.724336 -398.542002)
			(xy 417.723841 -398.566609) (xy 417.715946 -398.615186) (xy 417.700362 -398.661867) (xy 417.677491 -398.705444)
			(xy 417.647926 -398.744788) (xy 417.612433 -398.77888) (xy 417.57193 -398.806836) (xy 417.527468 -398.827934)
			(xy 417.480197 -398.841626) (xy 417.431342 -398.847558) (xy 417.382167 -398.845577) (xy 417.333948 -398.835733)
			(xy 417.287932 -398.818281) (xy 417.245311 -398.793674) (xy 417.20719 -398.762549) (xy 417.174555 -398.725712)
			(xy 417.148252 -398.684116) (xy 417.128961 -398.63884) (xy 417.117184 -398.591056) (xy 417.113224 -398.542002)
			(xy 416.524186 -398.542002) (xy 416.523691 -398.566609) (xy 416.515796 -398.615186) (xy 416.500212 -398.661867)
			(xy 416.477341 -398.705444) (xy 416.447776 -398.744788) (xy 416.412283 -398.77888) (xy 416.37178 -398.806836)
			(xy 416.327318 -398.827934) (xy 416.280047 -398.841626) (xy 416.231192 -398.847558) (xy 416.182017 -398.845577)
			(xy 416.133798 -398.835733) (xy 416.087782 -398.818281) (xy 416.045161 -398.793674) (xy 416.00704 -398.762549)
			(xy 415.974405 -398.725712) (xy 415.948102 -398.684116) (xy 415.928811 -398.63884) (xy 415.917034 -398.591056)
			(xy 415.913074 -398.542002) (xy 415.32429 -398.542002) (xy 415.323795 -398.566609) (xy 415.3159 -398.615186)
			(xy 415.300316 -398.661867) (xy 415.277445 -398.705444) (xy 415.24788 -398.744788) (xy 415.212387 -398.77888)
			(xy 415.171884 -398.806836) (xy 415.127422 -398.827934) (xy 415.080151 -398.841626) (xy 415.031296 -398.847558)
			(xy 414.982121 -398.845577) (xy 414.933902 -398.835733) (xy 414.887886 -398.818281) (xy 414.845265 -398.793674)
			(xy 414.807144 -398.762549) (xy 414.774509 -398.725712) (xy 414.748206 -398.684116) (xy 414.728915 -398.63884)
			(xy 414.717138 -398.591056) (xy 414.713178 -398.542002) (xy 414.124394 -398.542002) (xy 414.123899 -398.566609)
			(xy 414.116004 -398.615186) (xy 414.10042 -398.661867) (xy 414.077549 -398.705444) (xy 414.047984 -398.744788)
			(xy 414.012491 -398.77888) (xy 413.971988 -398.806836) (xy 413.927526 -398.827934) (xy 413.880255 -398.841626)
			(xy 413.8314 -398.847558) (xy 413.782225 -398.845577) (xy 413.734006 -398.835733) (xy 413.68799 -398.818281)
			(xy 413.645369 -398.793674) (xy 413.607248 -398.762549) (xy 413.574613 -398.725712) (xy 413.54831 -398.684116)
			(xy 413.529019 -398.63884) (xy 413.517242 -398.591056) (xy 413.513282 -398.542002) (xy 412.924244 -398.542002)
			(xy 412.923749 -398.566609) (xy 412.915854 -398.615186) (xy 412.90027 -398.661867) (xy 412.877399 -398.705444)
			(xy 412.847834 -398.744788) (xy 412.812341 -398.77888) (xy 412.771838 -398.806836) (xy 412.727376 -398.827934)
			(xy 412.680105 -398.841626) (xy 412.63125 -398.847558) (xy 412.582075 -398.845577) (xy 412.533856 -398.835733)
			(xy 412.48784 -398.818281) (xy 412.445219 -398.793674) (xy 412.407098 -398.762549) (xy 412.374463 -398.725712)
			(xy 412.34816 -398.684116) (xy 412.328869 -398.63884) (xy 412.317092 -398.591056) (xy 412.313132 -398.542002)
			(xy 411.724348 -398.542002) (xy 411.723853 -398.566609) (xy 411.715958 -398.615186) (xy 411.700374 -398.661867)
			(xy 411.677503 -398.705444) (xy 411.647938 -398.744788) (xy 411.612445 -398.77888) (xy 411.571942 -398.806836)
			(xy 411.52748 -398.827934) (xy 411.480209 -398.841626) (xy 411.431354 -398.847558) (xy 411.382179 -398.845577)
			(xy 411.33396 -398.835733) (xy 411.287944 -398.818281) (xy 411.245323 -398.793674) (xy 411.207202 -398.762549)
			(xy 411.174567 -398.725712) (xy 411.148264 -398.684116) (xy 411.128973 -398.63884) (xy 411.117196 -398.591056)
			(xy 411.113236 -398.542002) (xy 410.524198 -398.542002) (xy 410.523703 -398.566609) (xy 410.515808 -398.615186)
			(xy 410.500224 -398.661867) (xy 410.477353 -398.705444) (xy 410.447788 -398.744788) (xy 410.412295 -398.77888)
			(xy 410.371792 -398.806836) (xy 410.32733 -398.827934) (xy 410.280059 -398.841626) (xy 410.231204 -398.847558)
			(xy 410.182029 -398.845577) (xy 410.13381 -398.835733) (xy 410.087794 -398.818281) (xy 410.045173 -398.793674)
			(xy 410.007052 -398.762549) (xy 409.974417 -398.725712) (xy 409.948114 -398.684116) (xy 409.928823 -398.63884)
			(xy 409.917046 -398.591056) (xy 409.913086 -398.542002) (xy 409.324302 -398.542002) (xy 409.323807 -398.566609)
			(xy 409.315912 -398.615186) (xy 409.300328 -398.661867) (xy 409.277457 -398.705444) (xy 409.247892 -398.744788)
			(xy 409.212399 -398.77888) (xy 409.171896 -398.806836) (xy 409.127434 -398.827934) (xy 409.080163 -398.841626)
			(xy 409.031308 -398.847558) (xy 408.982133 -398.845577) (xy 408.933914 -398.835733) (xy 408.887898 -398.818281)
			(xy 408.845277 -398.793674) (xy 408.807156 -398.762549) (xy 408.774521 -398.725712) (xy 408.748218 -398.684116)
			(xy 408.728927 -398.63884) (xy 408.71715 -398.591056) (xy 408.71319 -398.542002) (xy 408.124406 -398.542002)
			(xy 408.123911 -398.566609) (xy 408.116016 -398.615186) (xy 408.100432 -398.661867) (xy 408.077561 -398.705444)
			(xy 408.047996 -398.744788) (xy 408.012503 -398.77888) (xy 407.972 -398.806836) (xy 407.927538 -398.827934)
			(xy 407.880267 -398.841626) (xy 407.831412 -398.847558) (xy 407.782237 -398.845577) (xy 407.734018 -398.835733)
			(xy 407.688002 -398.818281) (xy 407.645381 -398.793674) (xy 407.60726 -398.762549) (xy 407.574625 -398.725712)
			(xy 407.548322 -398.684116) (xy 407.529031 -398.63884) (xy 407.517254 -398.591056) (xy 407.513294 -398.542002)
			(xy 406.924256 -398.542002) (xy 406.923761 -398.566609) (xy 406.915866 -398.615186) (xy 406.900282 -398.661867)
			(xy 406.877411 -398.705444) (xy 406.847846 -398.744788) (xy 406.812353 -398.77888) (xy 406.77185 -398.806836)
			(xy 406.727388 -398.827934) (xy 406.680117 -398.841626) (xy 406.631262 -398.847558) (xy 406.582087 -398.845577)
			(xy 406.533868 -398.835733) (xy 406.487852 -398.818281) (xy 406.445231 -398.793674) (xy 406.40711 -398.762549)
			(xy 406.374475 -398.725712) (xy 406.348172 -398.684116) (xy 406.328881 -398.63884) (xy 406.317104 -398.591056)
			(xy 406.313144 -398.542002) (xy 405.72436 -398.542002) (xy 405.723865 -398.566609) (xy 405.71597 -398.615186)
			(xy 405.700386 -398.661867) (xy 405.677515 -398.705444) (xy 405.64795 -398.744788) (xy 405.612457 -398.77888)
			(xy 405.571954 -398.806836) (xy 405.527492 -398.827934) (xy 405.480221 -398.841626) (xy 405.431366 -398.847558)
			(xy 405.382191 -398.845577) (xy 405.333972 -398.835733) (xy 405.287956 -398.818281) (xy 405.245335 -398.793674)
			(xy 405.207214 -398.762549) (xy 405.174579 -398.725712) (xy 405.148276 -398.684116) (xy 405.128985 -398.63884)
			(xy 405.117208 -398.591056) (xy 405.113248 -398.542002) (xy 404.52421 -398.542002) (xy 404.523715 -398.566609)
			(xy 404.51582 -398.615186) (xy 404.500236 -398.661867) (xy 404.477365 -398.705444) (xy 404.4478 -398.744788)
			(xy 404.412307 -398.77888) (xy 404.371804 -398.806836) (xy 404.327342 -398.827934) (xy 404.280071 -398.841626)
			(xy 404.231216 -398.847558) (xy 404.182041 -398.845577) (xy 404.133822 -398.835733) (xy 404.087806 -398.818281)
			(xy 404.045185 -398.793674) (xy 404.007064 -398.762549) (xy 403.974429 -398.725712) (xy 403.948126 -398.684116)
			(xy 403.928835 -398.63884) (xy 403.917058 -398.591056) (xy 403.913098 -398.542002) (xy 403.32406 -398.542002)
			(xy 403.323565 -398.566609) (xy 403.31567 -398.615186) (xy 403.300086 -398.661867) (xy 403.277215 -398.705444)
			(xy 403.24765 -398.744788) (xy 403.212157 -398.77888) (xy 403.171654 -398.806836) (xy 403.127192 -398.827934)
			(xy 403.079921 -398.841626) (xy 403.031066 -398.847558) (xy 402.981891 -398.845577) (xy 402.933672 -398.835733)
			(xy 402.887656 -398.818281) (xy 402.845035 -398.793674) (xy 402.806914 -398.762549) (xy 402.774279 -398.725712)
			(xy 402.747976 -398.684116) (xy 402.728685 -398.63884) (xy 402.716908 -398.591056) (xy 402.712948 -398.542002)
			(xy 401.038113 -398.542002) (xy 401.032003 -398.563184) (xy 401.013003 -398.60559) (xy 400.988256 -398.644919)
			(xy 400.973544 -398.662906) (xy 400.967448 -398.670018) (xy 400.961352 -398.686528) (xy 400.961352 -398.770856)
			(xy 400.967448 -398.787366) (xy 400.973544 -398.794478) (xy 400.988247 -398.81247) (xy 401.012991 -398.851799)
			(xy 401.031985 -398.894204) (xy 401.044855 -398.938851) (xy 401.051348 -398.984859) (xy 401.051776 -399.008092)
			(xy 401.051289 -399.03439) (xy 401.042994 -399.086328) (xy 401.035266 -399.11147) (xy 401.031456 -399.123154)
			(xy 401.035012 -399.147284) (xy 401.090638 -399.223738) (xy 401.098247 -399.233124) (xy 401.119723 -399.244127)
			(xy 401.131786 -399.24482) (xy 420.940738 -399.24482) (xy 420.950806 -399.244391) (xy 420.969402 -399.236669)
			(xy 420.976806 -399.229834) (xy 421.401494 -398.805146) (xy 421.408333 -398.797745) (xy 421.416048 -398.779147)
			(xy 421.41648 -398.769078) (xy 421.41648 -398.623282) (xy 421.416057 -398.613265) (xy 421.408383 -398.594757)
			(xy 421.394211 -398.580596) (xy 421.375698 -398.572936) (xy 421.36568 -398.572482) (xy 421.347646 -398.572482)
			(xy 421.320214 -398.594326) (xy 421.31615 -398.611598) (xy 421.309802 -398.636398) (xy 421.289975 -398.683591)
			(xy 421.262558 -398.726818) (xy 421.228317 -398.764868) (xy 421.188212 -398.796678) (xy 421.143365 -398.821356)
			(xy 421.095031 -398.838212) (xy 421.044564 -398.846775) (xy 421.01897 -398.84731) (xy 420.993716 -398.846786)
			(xy 420.943898 -398.838468) (xy 420.896128 -398.822065) (xy 420.851709 -398.798023) (xy 420.811853 -398.766998)
			(xy 420.777647 -398.729837) (xy 420.750023 -398.687552) (xy 420.729736 -398.641298) (xy 420.717338 -398.592335)
			(xy 420.713167 -398.542) (xy 420.717338 -398.491665) (xy 420.729736 -398.442702) (xy 420.750023 -398.396448)
			(xy 420.777647 -398.354163) (xy 420.811853 -398.317002) (xy 420.851709 -398.285977) (xy 420.896128 -398.261935)
			(xy 420.943898 -398.245532) (xy 420.993716 -398.237214) (xy 421.01897 -398.236694) (xy 421.043843 -398.237182)
			(xy 421.092932 -398.245248) (xy 421.140062 -398.26117) (xy 421.183984 -398.284527) (xy 421.223536 -398.3147)
			(xy 421.240966 -398.332452) (xy 421.251888 -398.343882) (xy 421.282114 -398.350486) (xy 421.384476 -398.309846)
			(xy 421.393748 -398.305691) (xy 421.40824 -398.291477) (xy 421.416082 -398.272753) (xy 421.41648 -398.262602)
			(xy 421.41648 -397.776192) (xy 421.416285 -397.769524) (xy 421.412813 -397.75665) (xy 421.409622 -397.750792)
			(xy 421.151558 -397.304006) (xy 421.13966 -397.281338) (xy 421.122784 -397.233007) (xy 421.114223 -397.182536)
			(xy 421.113712 -397.15694) (xy 421.113712 -397.156432) (xy 421.113796 -397.145087) (xy 421.115452 -397.122457)
			(xy 421.117014 -397.11122) (xy 421.118284 -397.10233) (xy 421.114728 -397.085058) (xy 421.071294 -397.013938)
			(xy 421.057324 -397.003016) (xy 421.048942 -396.999968) (xy 421.026542 -396.991947) (xy 420.98435 -396.969957)
			(xy 420.946079 -396.941692) (xy 420.912653 -396.907834) (xy 420.884881 -396.869202) (xy 420.863436 -396.826731)
			(xy 420.848836 -396.781449) (xy 420.841433 -396.734451) (xy 420.840916 -396.710662) (xy 420.841416 -396.685264)
			(xy 420.849816 -396.635168) (xy 420.866394 -396.587154) (xy 420.890693 -396.542547) (xy 420.922043 -396.50258)
			(xy 420.940484 -396.48511) (xy 420.948866 -396.47749) (xy 420.957502 -396.457424) (xy 420.954708 -396.35811)
			(xy 420.94531 -396.338552) (xy 420.93642 -396.33144) (xy 420.917858 -396.315638) (xy 420.885129 -396.279512)
			(xy 420.858055 -396.238976) (xy 420.837221 -396.194905) (xy 420.823077 -396.148256) (xy 420.815931 -396.100035)
			(xy 420.815516 -396.075662) (xy 420.815955 -396.051546) (xy 420.822961 -396.003826) (xy 420.836819 -395.957628)
			(xy 420.857235 -395.91393) (xy 420.870126 -395.893544) (xy 420.875968 -395.884654) (xy 420.879524 -395.864588)
			(xy 420.858442 -395.772386) (xy 420.84625 -395.755622) (xy 420.83736 -395.750288) (xy 420.816558 -395.737433)
			(xy 420.77864 -395.706555) (xy 420.745688 -395.670424) (xy 420.718423 -395.629831) (xy 420.697441 -395.585661)
			(xy 420.6832 -395.538881) (xy 420.676011 -395.490512) (xy 420.675562 -395.466062) (xy 420.676123 -395.438779)
			(xy 420.685083 -395.384954) (xy 420.702754 -395.333329) (xy 420.728656 -395.285303) (xy 420.762088 -395.242178)
			(xy 420.781734 -395.223238) (xy 420.789178 -395.215744) (xy 420.797715 -395.196449) (xy 420.798244 -395.1859)
			(xy 420.798244 -395.111224) (xy 420.797656 -395.10069) (xy 420.789122 -395.08142) (xy 420.781734 -395.073886)
			(xy 420.762079 -395.054953) (xy 420.728637 -395.011832) (xy 420.70273 -394.963805) (xy 420.685059 -394.912176)
			(xy 420.676105 -394.858347) (xy 420.675562 -394.831062) (xy 420.675816 -394.81887) (xy 420.67607 -394.809218)
			(xy 420.669974 -394.791184) (xy 420.6113 -394.723874) (xy 420.594536 -394.715238) (xy 420.58463 -394.714222)
			(xy 420.557718 -394.710869) (xy 420.505422 -394.696521) (xy 420.456169 -394.67383) (xy 420.411279 -394.643405)
			(xy 420.371956 -394.606063) (xy 420.339255 -394.562803) (xy 420.314052 -394.514787) (xy 420.297023 -394.463301)
			(xy 420.292276 -394.4366) (xy 420.290752 -394.427202) (xy 420.017702 -393.954762) (xy 420.01059 -393.94892)
			(xy 419.991856 -393.933141) (xy 419.9588 -393.896998) (xy 419.931439 -393.856373) (xy 419.910374 -393.812154)
			(xy 419.896064 -393.765311) (xy 419.888825 -393.71687) (xy 419.888416 -393.69238) (xy 419.888901 -393.666392)
			(xy 419.897035 -393.615058) (xy 419.913099 -393.565627) (xy 419.936698 -393.519319) (xy 419.967251 -393.477272)
			(xy 420.004005 -393.440522) (xy 420.046056 -393.409975) (xy 420.092368 -393.386382) (xy 420.141801 -393.370324)
			(xy 420.193136 -393.362197) (xy 420.219124 -393.361672) (xy 420.245171 -393.362154) (xy 420.296622 -393.370308)
			(xy 420.346159 -393.386428) (xy 420.392556 -393.410115) (xy 420.434666 -393.440782) (xy 420.471448 -393.477671)
			(xy 420.501991 -393.519871) (xy 420.525542 -393.566337) (xy 420.541517 -393.615921) (xy 420.546022 -393.64158)
			(xy 420.547292 -393.650978) (xy 420.819834 -394.122402) (xy 420.8272 -394.128244) (xy 420.845978 -394.144048)
			(xy 420.879111 -394.180255) (xy 420.906532 -394.22096) (xy 420.927638 -394.265269) (xy 420.941967 -394.31221)
			(xy 420.949204 -394.360752) (xy 420.949628 -394.385292) (xy 420.949374 -394.397484) (xy 420.94912 -394.407136)
			(xy 420.955216 -394.42517) (xy 421.01389 -394.49248) (xy 421.030654 -394.501116) (xy 421.04056 -394.502132)
			(xy 421.068919 -394.505688) (xy 421.123897 -394.521288) (xy 421.175372 -394.546114) (xy 421.22181 -394.579424)
			(xy 421.242236 -394.599414) (xy 421.253158 -394.61059) (xy 421.283384 -394.61694) (xy 421.384984 -394.575284)
			(xy 421.394117 -394.571076) (xy 421.408356 -394.556898) (xy 421.416064 -394.538341) (xy 421.41648 -394.528294)
			(xy 421.41648 -394.31214) (xy 421.416279 -394.305474) (xy 421.412795 -394.292606) (xy 421.409622 -394.28674)
			(xy 421.218106 -393.95527) (xy 421.21074 -393.949428) (xy 421.191961 -393.933625) (xy 421.158828 -393.897418)
			(xy 421.131407 -393.856713) (xy 421.110302 -393.812404) (xy 421.095975 -393.765463) (xy 421.088741 -393.71692)
			(xy 421.088312 -393.69238) (xy 421.088814 -393.666081) (xy 421.09713 -393.614146) (xy 421.113564 -393.564182)
			(xy 421.137703 -393.517451) (xy 421.168936 -393.475132) (xy 421.206476 -393.438292) (xy 421.249376 -393.407861)
			(xy 421.296553 -393.384606) (xy 421.346817 -393.369116) (xy 421.372792 -393.364974) (xy 421.391588 -393.36218)
			(xy 421.41648 -393.333478) (xy 421.41648 -393.263628) (xy 421.416065 -393.253605) (xy 421.408399 -393.235082)
			(xy 421.394225 -393.220905) (xy 421.375703 -393.213237) (xy 421.36568 -393.212828) (xy 421.355266 -393.212828)
			(xy 421.336216 -393.220702) (xy 421.329104 -393.228322) (xy 421.310261 -393.247286) (xy 421.267581 -393.279476)
			(xy 421.220277 -393.304377) (xy 421.169583 -393.321342) (xy 421.116819 -393.329927) (xy 421.09009 -393.33043)
			(xy 421.064103 -393.32992) (xy 421.012768 -393.321788) (xy 420.963338 -393.305726) (xy 420.917028 -393.28213)
			(xy 420.874979 -393.251581) (xy 420.838227 -393.21483) (xy 420.807676 -393.172782) (xy 420.784078 -393.126474)
			(xy 420.768015 -393.077044) (xy 420.759881 -393.025709) (xy 420.759382 -392.999722) (xy 420.759834 -392.975181)
			(xy 420.767095 -392.926639) (xy 420.781447 -392.879702) (xy 420.802574 -392.835399) (xy 420.830013 -392.794703)
			(xy 420.863162 -392.758507) (xy 420.901295 -392.727603) (xy 420.922196 -392.714734) (xy 420.93261 -392.708638)
			(xy 420.94531 -392.689334) (xy 420.956994 -392.59764) (xy 420.957901 -392.586042) (xy 420.950368 -392.564058)
			(xy 420.942516 -392.555476) (xy 420.689786 -392.302746) (xy 420.682389 -392.295897) (xy 420.66379 -392.28816)
			(xy 420.653718 -392.28776) (xy 400.069558 -392.28776) (xy 400.060606 -392.288112) (xy 400.043795 -392.294269)
			(xy 400.030116 -392.305821) (xy 400.025362 -392.313414) (xy 400.011735 -392.336537) (xy 399.978989 -392.379061)
			(xy 399.940603 -392.416572) (xy 399.897335 -392.44833) (xy 399.850042 -392.473706) (xy 399.799657 -392.492198)
			(xy 399.747177 -392.503442) (xy 399.693638 -392.507215) (xy 399.640099 -392.503442) (xy 399.587619 -392.492198)
			(xy 399.537234 -392.473706) (xy 399.489941 -392.44833) (xy 399.446673 -392.416572) (xy 399.408287 -392.379061)
			(xy 399.375541 -392.336537) (xy 399.361914 -392.313414) (xy 399.35719 -392.305789) (xy 399.343516 -392.294199)
			(xy 399.326681 -392.28804) (xy 399.317718 -392.28776) (xy 398.757902 -392.28776) (xy 398.747833 -392.288184)
			(xy 398.729234 -392.295905) (xy 398.721834 -392.302746) (xy 397.9799 -393.04468) (xy 399.31162 -393.04468)
			(xy 399.315691 -392.989058) (xy 399.327817 -392.934621) (xy 399.34774 -392.88253) (xy 399.375036 -392.833895)
			(xy 399.409122 -392.789752) (xy 399.449271 -392.751043) (xy 399.494629 -392.718592) (xy 399.544229 -392.693091)
			(xy 399.597013 -392.675084) (xy 399.651856 -392.664954) (xy 399.70759 -392.662917) (xy 399.763027 -392.669017)
			(xy 399.816984 -392.683123) (xy 399.868313 -392.704935) (xy 399.915919 -392.733989) (xy 399.953614 -392.765359)
			(xy 400.698718 -392.765359) (xy 400.698718 -392.713385) (xy 400.706848 -392.66205) (xy 400.722909 -392.61262)
			(xy 400.746505 -392.56631) (xy 400.777055 -392.524262) (xy 400.813806 -392.487511) (xy 400.855854 -392.456961)
			(xy 400.902164 -392.433365) (xy 400.951594 -392.417304) (xy 401.002929 -392.409174) (xy 401.054903 -392.409174)
			(xy 401.106238 -392.417304) (xy 401.155668 -392.433365) (xy 401.201978 -392.456961) (xy 401.244026 -392.487511)
			(xy 401.280777 -392.524262) (xy 401.311327 -392.56631) (xy 401.334923 -392.61262) (xy 401.350984 -392.66205)
			(xy 401.359114 -392.713385) (xy 401.359624 -392.739372) (xy 401.359114 -392.765359) (xy 401.350984 -392.816694)
			(xy 401.334923 -392.866124) (xy 401.311327 -392.912434) (xy 401.280777 -392.954482) (xy 401.244026 -392.991233)
			(xy 401.201978 -393.021783) (xy 401.194273 -393.025709) (xy 402.759928 -393.025709) (xy 402.759928 -392.973735)
			(xy 402.768058 -392.9224) (xy 402.784119 -392.87297) (xy 402.807715 -392.82666) (xy 402.838265 -392.784612)
			(xy 402.875016 -392.747861) (xy 402.917064 -392.717311) (xy 402.963374 -392.693715) (xy 403.012804 -392.677654)
			(xy 403.064139 -392.669524) (xy 403.116113 -392.669524) (xy 403.167448 -392.677654) (xy 403.216878 -392.693715)
			(xy 403.263188 -392.717311) (xy 403.305236 -392.747861) (xy 403.341987 -392.784612) (xy 403.372537 -392.82666)
			(xy 403.396133 -392.87297) (xy 403.412194 -392.9224) (xy 403.420324 -392.973735) (xy 403.420834 -392.999722)
			(xy 403.420324 -393.025709) (xy 403.959824 -393.025709) (xy 403.959824 -392.973735) (xy 403.967954 -392.9224)
			(xy 403.984015 -392.87297) (xy 404.007611 -392.82666) (xy 404.038161 -392.784612) (xy 404.074912 -392.747861)
			(xy 404.11696 -392.717311) (xy 404.16327 -392.693715) (xy 404.2127 -392.677654) (xy 404.264035 -392.669524)
			(xy 404.316009 -392.669524) (xy 404.367344 -392.677654) (xy 404.416774 -392.693715) (xy 404.463084 -392.717311)
			(xy 404.505132 -392.747861) (xy 404.541883 -392.784612) (xy 404.572433 -392.82666) (xy 404.596029 -392.87297)
			(xy 404.61209 -392.9224) (xy 404.62022 -392.973735) (xy 404.62073 -392.999722) (xy 404.62022 -393.025709)
			(xy 405.159974 -393.025709) (xy 405.159974 -392.973735) (xy 405.168104 -392.9224) (xy 405.184165 -392.87297)
			(xy 405.207761 -392.82666) (xy 405.238311 -392.784612) (xy 405.275062 -392.747861) (xy 405.31711 -392.717311)
			(xy 405.36342 -392.693715) (xy 405.41285 -392.677654) (xy 405.464185 -392.669524) (xy 405.516159 -392.669524)
			(xy 405.567494 -392.677654) (xy 405.616924 -392.693715) (xy 405.663234 -392.717311) (xy 405.705282 -392.747861)
			(xy 405.742033 -392.784612) (xy 405.772583 -392.82666) (xy 405.796179 -392.87297) (xy 405.81224 -392.9224)
			(xy 405.82037 -392.973735) (xy 405.82088 -392.999722) (xy 405.82037 -393.025709) (xy 406.35987 -393.025709)
			(xy 406.35987 -392.973735) (xy 406.368 -392.9224) (xy 406.384061 -392.87297) (xy 406.407657 -392.82666)
			(xy 406.438207 -392.784612) (xy 406.474958 -392.747861) (xy 406.517006 -392.717311) (xy 406.563316 -392.693715)
			(xy 406.612746 -392.677654) (xy 406.664081 -392.669524) (xy 406.716055 -392.669524) (xy 406.76739 -392.677654)
			(xy 406.81682 -392.693715) (xy 406.86313 -392.717311) (xy 406.905178 -392.747861) (xy 406.941929 -392.784612)
			(xy 406.972479 -392.82666) (xy 406.996075 -392.87297) (xy 407.012136 -392.9224) (xy 407.020266 -392.973735)
			(xy 407.020776 -392.999722) (xy 407.020266 -393.025709) (xy 407.56002 -393.025709) (xy 407.56002 -392.973735)
			(xy 407.56815 -392.9224) (xy 407.584211 -392.87297) (xy 407.607807 -392.82666) (xy 407.638357 -392.784612)
			(xy 407.675108 -392.747861) (xy 407.717156 -392.717311) (xy 407.763466 -392.693715) (xy 407.812896 -392.677654)
			(xy 407.864231 -392.669524) (xy 407.916205 -392.669524) (xy 407.96754 -392.677654) (xy 408.01697 -392.693715)
			(xy 408.06328 -392.717311) (xy 408.105328 -392.747861) (xy 408.142079 -392.784612) (xy 408.172629 -392.82666)
			(xy 408.196225 -392.87297) (xy 408.212286 -392.9224) (xy 408.220416 -392.973735) (xy 408.220926 -392.999722)
			(xy 408.220416 -393.025709) (xy 408.759916 -393.025709) (xy 408.759916 -392.973735) (xy 408.768046 -392.9224)
			(xy 408.784107 -392.87297) (xy 408.807703 -392.82666) (xy 408.838253 -392.784612) (xy 408.875004 -392.747861)
			(xy 408.917052 -392.717311) (xy 408.963362 -392.693715) (xy 409.012792 -392.677654) (xy 409.064127 -392.669524)
			(xy 409.116101 -392.669524) (xy 409.167436 -392.677654) (xy 409.216866 -392.693715) (xy 409.263176 -392.717311)
			(xy 409.305224 -392.747861) (xy 409.341975 -392.784612) (xy 409.372525 -392.82666) (xy 409.396121 -392.87297)
			(xy 409.412182 -392.9224) (xy 409.420312 -392.973735) (xy 409.420822 -392.999722) (xy 409.420312 -393.025709)
			(xy 409.959812 -393.025709) (xy 409.959812 -392.973735) (xy 409.967942 -392.9224) (xy 409.984003 -392.87297)
			(xy 410.007599 -392.82666) (xy 410.038149 -392.784612) (xy 410.0749 -392.747861) (xy 410.116948 -392.717311)
			(xy 410.163258 -392.693715) (xy 410.212688 -392.677654) (xy 410.264023 -392.669524) (xy 410.315997 -392.669524)
			(xy 410.367332 -392.677654) (xy 410.416762 -392.693715) (xy 410.463072 -392.717311) (xy 410.50512 -392.747861)
			(xy 410.541871 -392.784612) (xy 410.572421 -392.82666) (xy 410.596017 -392.87297) (xy 410.612078 -392.9224)
			(xy 410.620208 -392.973735) (xy 410.620718 -392.999722) (xy 410.620208 -393.025709) (xy 411.159962 -393.025709)
			(xy 411.159962 -392.973735) (xy 411.168092 -392.9224) (xy 411.184153 -392.87297) (xy 411.207749 -392.82666)
			(xy 411.238299 -392.784612) (xy 411.27505 -392.747861) (xy 411.317098 -392.717311) (xy 411.363408 -392.693715)
			(xy 411.412838 -392.677654) (xy 411.464173 -392.669524) (xy 411.516147 -392.669524) (xy 411.567482 -392.677654)
			(xy 411.616912 -392.693715) (xy 411.663222 -392.717311) (xy 411.70527 -392.747861) (xy 411.742021 -392.784612)
			(xy 411.772571 -392.82666) (xy 411.796167 -392.87297) (xy 411.812228 -392.9224) (xy 411.820358 -392.973735)
			(xy 411.820868 -392.999722) (xy 411.820358 -393.025709) (xy 412.359858 -393.025709) (xy 412.359858 -392.973735)
			(xy 412.367988 -392.9224) (xy 412.384049 -392.87297) (xy 412.407645 -392.82666) (xy 412.438195 -392.784612)
			(xy 412.474946 -392.747861) (xy 412.516994 -392.717311) (xy 412.563304 -392.693715) (xy 412.612734 -392.677654)
			(xy 412.664069 -392.669524) (xy 412.716043 -392.669524) (xy 412.767378 -392.677654) (xy 412.816808 -392.693715)
			(xy 412.863118 -392.717311) (xy 412.905166 -392.747861) (xy 412.941917 -392.784612) (xy 412.972467 -392.82666)
			(xy 412.996063 -392.87297) (xy 413.012124 -392.9224) (xy 413.020254 -392.973735) (xy 413.020764 -392.999722)
			(xy 413.020254 -393.025709) (xy 413.560008 -393.025709) (xy 413.560008 -392.973735) (xy 413.568138 -392.9224)
			(xy 413.584199 -392.87297) (xy 413.607795 -392.82666) (xy 413.638345 -392.784612) (xy 413.675096 -392.747861)
			(xy 413.717144 -392.717311) (xy 413.763454 -392.693715) (xy 413.812884 -392.677654) (xy 413.864219 -392.669524)
			(xy 413.916193 -392.669524) (xy 413.967528 -392.677654) (xy 414.016958 -392.693715) (xy 414.063268 -392.717311)
			(xy 414.105316 -392.747861) (xy 414.142067 -392.784612) (xy 414.172617 -392.82666) (xy 414.196213 -392.87297)
			(xy 414.212274 -392.9224) (xy 414.220404 -392.973735) (xy 414.220914 -392.999722) (xy 414.220404 -393.025709)
			(xy 414.759904 -393.025709) (xy 414.759904 -392.973735) (xy 414.768034 -392.9224) (xy 414.784095 -392.87297)
			(xy 414.807691 -392.82666) (xy 414.838241 -392.784612) (xy 414.874992 -392.747861) (xy 414.91704 -392.717311)
			(xy 414.96335 -392.693715) (xy 415.01278 -392.677654) (xy 415.064115 -392.669524) (xy 415.116089 -392.669524)
			(xy 415.167424 -392.677654) (xy 415.216854 -392.693715) (xy 415.263164 -392.717311) (xy 415.305212 -392.747861)
			(xy 415.341963 -392.784612) (xy 415.372513 -392.82666) (xy 415.396109 -392.87297) (xy 415.41217 -392.9224)
			(xy 415.4203 -392.973735) (xy 415.42081 -392.999722) (xy 415.4203 -393.025709) (xy 415.9598 -393.025709)
			(xy 415.9598 -392.973735) (xy 415.96793 -392.9224) (xy 415.983991 -392.87297) (xy 416.007587 -392.82666)
			(xy 416.038137 -392.784612) (xy 416.074888 -392.747861) (xy 416.116936 -392.717311) (xy 416.163246 -392.693715)
			(xy 416.212676 -392.677654) (xy 416.264011 -392.669524) (xy 416.315985 -392.669524) (xy 416.36732 -392.677654)
			(xy 416.41675 -392.693715) (xy 416.46306 -392.717311) (xy 416.505108 -392.747861) (xy 416.541859 -392.784612)
			(xy 416.572409 -392.82666) (xy 416.596005 -392.87297) (xy 416.612066 -392.9224) (xy 416.620196 -392.973735)
			(xy 416.620706 -392.999722) (xy 416.620196 -393.025709) (xy 417.15995 -393.025709) (xy 417.15995 -392.973735)
			(xy 417.16808 -392.9224) (xy 417.184141 -392.87297) (xy 417.207737 -392.82666) (xy 417.238287 -392.784612)
			(xy 417.275038 -392.747861) (xy 417.317086 -392.717311) (xy 417.363396 -392.693715) (xy 417.412826 -392.677654)
			(xy 417.464161 -392.669524) (xy 417.516135 -392.669524) (xy 417.56747 -392.677654) (xy 417.6169 -392.693715)
			(xy 417.66321 -392.717311) (xy 417.705258 -392.747861) (xy 417.742009 -392.784612) (xy 417.772559 -392.82666)
			(xy 417.796155 -392.87297) (xy 417.812216 -392.9224) (xy 417.820346 -392.973735) (xy 417.820856 -392.999722)
			(xy 417.820346 -393.025709) (xy 418.359846 -393.025709) (xy 418.359846 -392.973735) (xy 418.367976 -392.9224)
			(xy 418.384037 -392.87297) (xy 418.407633 -392.82666) (xy 418.438183 -392.784612) (xy 418.474934 -392.747861)
			(xy 418.516982 -392.717311) (xy 418.563292 -392.693715) (xy 418.612722 -392.677654) (xy 418.664057 -392.669524)
			(xy 418.716031 -392.669524) (xy 418.767366 -392.677654) (xy 418.816796 -392.693715) (xy 418.863106 -392.717311)
			(xy 418.905154 -392.747861) (xy 418.941905 -392.784612) (xy 418.972455 -392.82666) (xy 418.996051 -392.87297)
			(xy 419.012112 -392.9224) (xy 419.020242 -392.973735) (xy 419.020752 -392.999722) (xy 419.020242 -393.025709)
			(xy 419.559996 -393.025709) (xy 419.559996 -392.973735) (xy 419.568126 -392.9224) (xy 419.584187 -392.87297)
			(xy 419.607783 -392.82666) (xy 419.638333 -392.784612) (xy 419.675084 -392.747861) (xy 419.717132 -392.717311)
			(xy 419.763442 -392.693715) (xy 419.812872 -392.677654) (xy 419.864207 -392.669524) (xy 419.916181 -392.669524)
			(xy 419.967516 -392.677654) (xy 420.016946 -392.693715) (xy 420.063256 -392.717311) (xy 420.105304 -392.747861)
			(xy 420.142055 -392.784612) (xy 420.172605 -392.82666) (xy 420.196201 -392.87297) (xy 420.212262 -392.9224)
			(xy 420.220392 -392.973735) (xy 420.220902 -392.999722) (xy 420.220392 -393.025709) (xy 420.212262 -393.077044)
			(xy 420.196201 -393.126474) (xy 420.172605 -393.172784) (xy 420.142055 -393.214832) (xy 420.105304 -393.251583)
			(xy 420.063256 -393.282133) (xy 420.016946 -393.305729) (xy 419.967516 -393.32179) (xy 419.916181 -393.32992)
			(xy 419.864207 -393.32992) (xy 419.812872 -393.32179) (xy 419.763442 -393.305729) (xy 419.717132 -393.282133)
			(xy 419.675084 -393.251583) (xy 419.638333 -393.214832) (xy 419.607783 -393.172784) (xy 419.584187 -393.126474)
			(xy 419.568126 -393.077044) (xy 419.559996 -393.025709) (xy 419.020242 -393.025709) (xy 419.012112 -393.077044)
			(xy 418.996051 -393.126474) (xy 418.972455 -393.172784) (xy 418.941905 -393.214832) (xy 418.905154 -393.251583)
			(xy 418.863106 -393.282133) (xy 418.816796 -393.305729) (xy 418.767366 -393.32179) (xy 418.716031 -393.32992)
			(xy 418.664057 -393.32992) (xy 418.612722 -393.32179) (xy 418.563292 -393.305729) (xy 418.516982 -393.282133)
			(xy 418.474934 -393.251583) (xy 418.438183 -393.214832) (xy 418.407633 -393.172784) (xy 418.384037 -393.126474)
			(xy 418.367976 -393.077044) (xy 418.359846 -393.025709) (xy 417.820346 -393.025709) (xy 417.812216 -393.077044)
			(xy 417.796155 -393.126474) (xy 417.772559 -393.172784) (xy 417.742009 -393.214832) (xy 417.705258 -393.251583)
			(xy 417.66321 -393.282133) (xy 417.6169 -393.305729) (xy 417.56747 -393.32179) (xy 417.516135 -393.32992)
			(xy 417.464161 -393.32992) (xy 417.412826 -393.32179) (xy 417.363396 -393.305729) (xy 417.317086 -393.282133)
			(xy 417.275038 -393.251583) (xy 417.238287 -393.214832) (xy 417.207737 -393.172784) (xy 417.184141 -393.126474)
			(xy 417.16808 -393.077044) (xy 417.15995 -393.025709) (xy 416.620196 -393.025709) (xy 416.612066 -393.077044)
			(xy 416.596005 -393.126474) (xy 416.572409 -393.172784) (xy 416.541859 -393.214832) (xy 416.505108 -393.251583)
			(xy 416.46306 -393.282133) (xy 416.41675 -393.305729) (xy 416.36732 -393.32179) (xy 416.315985 -393.32992)
			(xy 416.264011 -393.32992) (xy 416.212676 -393.32179) (xy 416.163246 -393.305729) (xy 416.116936 -393.282133)
			(xy 416.074888 -393.251583) (xy 416.038137 -393.214832) (xy 416.007587 -393.172784) (xy 415.983991 -393.126474)
			(xy 415.96793 -393.077044) (xy 415.9598 -393.025709) (xy 415.4203 -393.025709) (xy 415.41217 -393.077044)
			(xy 415.396109 -393.126474) (xy 415.372513 -393.172784) (xy 415.341963 -393.214832) (xy 415.305212 -393.251583)
			(xy 415.263164 -393.282133) (xy 415.216854 -393.305729) (xy 415.167424 -393.32179) (xy 415.116089 -393.32992)
			(xy 415.064115 -393.32992) (xy 415.01278 -393.32179) (xy 414.96335 -393.305729) (xy 414.91704 -393.282133)
			(xy 414.874992 -393.251583) (xy 414.838241 -393.214832) (xy 414.807691 -393.172784) (xy 414.784095 -393.126474)
			(xy 414.768034 -393.077044) (xy 414.759904 -393.025709) (xy 414.220404 -393.025709) (xy 414.212274 -393.077044)
			(xy 414.196213 -393.126474) (xy 414.172617 -393.172784) (xy 414.142067 -393.214832) (xy 414.105316 -393.251583)
			(xy 414.063268 -393.282133) (xy 414.016958 -393.305729) (xy 413.967528 -393.32179) (xy 413.916193 -393.32992)
			(xy 413.864219 -393.32992) (xy 413.812884 -393.32179) (xy 413.763454 -393.305729) (xy 413.717144 -393.282133)
			(xy 413.675096 -393.251583) (xy 413.638345 -393.214832) (xy 413.607795 -393.172784) (xy 413.584199 -393.126474)
			(xy 413.568138 -393.077044) (xy 413.560008 -393.025709) (xy 413.020254 -393.025709) (xy 413.012124 -393.077044)
			(xy 412.996063 -393.126474) (xy 412.972467 -393.172784) (xy 412.941917 -393.214832) (xy 412.905166 -393.251583)
			(xy 412.863118 -393.282133) (xy 412.816808 -393.305729) (xy 412.767378 -393.32179) (xy 412.716043 -393.32992)
			(xy 412.664069 -393.32992) (xy 412.612734 -393.32179) (xy 412.563304 -393.305729) (xy 412.516994 -393.282133)
			(xy 412.474946 -393.251583) (xy 412.438195 -393.214832) (xy 412.407645 -393.172784) (xy 412.384049 -393.126474)
			(xy 412.367988 -393.077044) (xy 412.359858 -393.025709) (xy 411.820358 -393.025709) (xy 411.812228 -393.077044)
			(xy 411.796167 -393.126474) (xy 411.772571 -393.172784) (xy 411.742021 -393.214832) (xy 411.70527 -393.251583)
			(xy 411.663222 -393.282133) (xy 411.616912 -393.305729) (xy 411.567482 -393.32179) (xy 411.516147 -393.32992)
			(xy 411.464173 -393.32992) (xy 411.412838 -393.32179) (xy 411.363408 -393.305729) (xy 411.317098 -393.282133)
			(xy 411.27505 -393.251583) (xy 411.238299 -393.214832) (xy 411.207749 -393.172784) (xy 411.184153 -393.126474)
			(xy 411.168092 -393.077044) (xy 411.159962 -393.025709) (xy 410.620208 -393.025709) (xy 410.612078 -393.077044)
			(xy 410.596017 -393.126474) (xy 410.572421 -393.172784) (xy 410.541871 -393.214832) (xy 410.50512 -393.251583)
			(xy 410.463072 -393.282133) (xy 410.416762 -393.305729) (xy 410.367332 -393.32179) (xy 410.315997 -393.32992)
			(xy 410.264023 -393.32992) (xy 410.212688 -393.32179) (xy 410.163258 -393.305729) (xy 410.116948 -393.282133)
			(xy 410.0749 -393.251583) (xy 410.038149 -393.214832) (xy 410.007599 -393.172784) (xy 409.984003 -393.126474)
			(xy 409.967942 -393.077044) (xy 409.959812 -393.025709) (xy 409.420312 -393.025709) (xy 409.412182 -393.077044)
			(xy 409.396121 -393.126474) (xy 409.372525 -393.172784) (xy 409.341975 -393.214832) (xy 409.305224 -393.251583)
			(xy 409.263176 -393.282133) (xy 409.216866 -393.305729) (xy 409.167436 -393.32179) (xy 409.116101 -393.32992)
			(xy 409.064127 -393.32992) (xy 409.012792 -393.32179) (xy 408.963362 -393.305729) (xy 408.917052 -393.282133)
			(xy 408.875004 -393.251583) (xy 408.838253 -393.214832) (xy 408.807703 -393.172784) (xy 408.784107 -393.126474)
			(xy 408.768046 -393.077044) (xy 408.759916 -393.025709) (xy 408.220416 -393.025709) (xy 408.212286 -393.077044)
			(xy 408.196225 -393.126474) (xy 408.172629 -393.172784) (xy 408.142079 -393.214832) (xy 408.105328 -393.251583)
			(xy 408.06328 -393.282133) (xy 408.01697 -393.305729) (xy 407.96754 -393.32179) (xy 407.916205 -393.32992)
			(xy 407.864231 -393.32992) (xy 407.812896 -393.32179) (xy 407.763466 -393.305729) (xy 407.717156 -393.282133)
			(xy 407.675108 -393.251583) (xy 407.638357 -393.214832) (xy 407.607807 -393.172784) (xy 407.584211 -393.126474)
			(xy 407.56815 -393.077044) (xy 407.56002 -393.025709) (xy 407.020266 -393.025709) (xy 407.012136 -393.077044)
			(xy 406.996075 -393.126474) (xy 406.972479 -393.172784) (xy 406.941929 -393.214832) (xy 406.905178 -393.251583)
			(xy 406.86313 -393.282133) (xy 406.81682 -393.305729) (xy 406.76739 -393.32179) (xy 406.716055 -393.32992)
			(xy 406.664081 -393.32992) (xy 406.612746 -393.32179) (xy 406.563316 -393.305729) (xy 406.517006 -393.282133)
			(xy 406.474958 -393.251583) (xy 406.438207 -393.214832) (xy 406.407657 -393.172784) (xy 406.384061 -393.126474)
			(xy 406.368 -393.077044) (xy 406.35987 -393.025709) (xy 405.82037 -393.025709) (xy 405.81224 -393.077044)
			(xy 405.796179 -393.126474) (xy 405.772583 -393.172784) (xy 405.742033 -393.214832) (xy 405.705282 -393.251583)
			(xy 405.663234 -393.282133) (xy 405.616924 -393.305729) (xy 405.567494 -393.32179) (xy 405.516159 -393.32992)
			(xy 405.464185 -393.32992) (xy 405.41285 -393.32179) (xy 405.36342 -393.305729) (xy 405.31711 -393.282133)
			(xy 405.275062 -393.251583) (xy 405.238311 -393.214832) (xy 405.207761 -393.172784) (xy 405.184165 -393.126474)
			(xy 405.168104 -393.077044) (xy 405.159974 -393.025709) (xy 404.62022 -393.025709) (xy 404.61209 -393.077044)
			(xy 404.596029 -393.126474) (xy 404.572433 -393.172784) (xy 404.541883 -393.214832) (xy 404.505132 -393.251583)
			(xy 404.463084 -393.282133) (xy 404.416774 -393.305729) (xy 404.367344 -393.32179) (xy 404.316009 -393.32992)
			(xy 404.264035 -393.32992) (xy 404.2127 -393.32179) (xy 404.16327 -393.305729) (xy 404.11696 -393.282133)
			(xy 404.074912 -393.251583) (xy 404.038161 -393.214832) (xy 404.007611 -393.172784) (xy 403.984015 -393.126474)
			(xy 403.967954 -393.077044) (xy 403.959824 -393.025709) (xy 403.420324 -393.025709) (xy 403.412194 -393.077044)
			(xy 403.396133 -393.126474) (xy 403.372537 -393.172784) (xy 403.341987 -393.214832) (xy 403.305236 -393.251583)
			(xy 403.263188 -393.282133) (xy 403.216878 -393.305729) (xy 403.167448 -393.32179) (xy 403.116113 -393.32992)
			(xy 403.064139 -393.32992) (xy 403.012804 -393.32179) (xy 402.963374 -393.305729) (xy 402.917064 -393.282133)
			(xy 402.875016 -393.251583) (xy 402.838265 -393.214832) (xy 402.807715 -393.172784) (xy 402.784119 -393.126474)
			(xy 402.768058 -393.077044) (xy 402.759928 -393.025709) (xy 401.194273 -393.025709) (xy 401.155668 -393.045379)
			(xy 401.106238 -393.06144) (xy 401.054903 -393.06957) (xy 401.002929 -393.06957) (xy 400.951594 -393.06144)
			(xy 400.902164 -393.045379) (xy 400.855854 -393.021783) (xy 400.813806 -392.991233) (xy 400.777055 -392.954482)
			(xy 400.746505 -392.912434) (xy 400.722909 -392.866124) (xy 400.706848 -392.816694) (xy 400.698718 -392.765359)
			(xy 399.953614 -392.765359) (xy 399.958787 -392.769664) (xy 399.996004 -392.811201) (xy 400.026777 -392.857714)
			(xy 400.050449 -392.908211) (xy 400.066517 -392.961618) (xy 400.074637 -393.016794) (xy 400.075146 -393.04468)
			(xy 400.074637 -393.072566) (xy 400.066517 -393.127742) (xy 400.050449 -393.181149) (xy 400.026777 -393.231646)
			(xy 399.996004 -393.278159) (xy 399.958787 -393.319696) (xy 399.915919 -393.355371) (xy 399.868313 -393.384425)
			(xy 399.816984 -393.406237) (xy 399.763027 -393.420343) (xy 399.70759 -393.426443) (xy 399.651856 -393.424406)
			(xy 399.597013 -393.414276) (xy 399.544229 -393.396269) (xy 399.494629 -393.370768) (xy 399.449271 -393.338317)
			(xy 399.409122 -393.299608) (xy 399.375036 -393.255465) (xy 399.34774 -393.20683) (xy 399.327817 -393.154739)
			(xy 399.315691 -393.100302) (xy 399.31162 -393.04468) (xy 397.9799 -393.04468) (xy 397.743426 -393.281154)
			(xy 397.736585 -393.288554) (xy 397.728867 -393.307153) (xy 397.72844 -393.317222) (xy 397.72844 -393.96416)
			(xy 399.31162 -393.96416) (xy 399.315691 -393.908538) (xy 399.327817 -393.854101) (xy 399.34774 -393.80201)
			(xy 399.375036 -393.753375) (xy 399.409122 -393.709232) (xy 399.449271 -393.670523) (xy 399.494629 -393.638072)
			(xy 399.544229 -393.612571) (xy 399.597013 -393.594564) (xy 399.651856 -393.584434) (xy 399.70759 -393.582397)
			(xy 399.763027 -393.588497) (xy 399.816984 -393.602603) (xy 399.868313 -393.624415) (xy 399.915919 -393.653469)
			(xy 399.958787 -393.689144) (xy 399.996004 -393.730681) (xy 400.026777 -393.777194) (xy 400.050449 -393.827691)
			(xy 400.066517 -393.881098) (xy 400.074637 -393.936274) (xy 400.075146 -393.96416) (xy 400.074637 -393.992046)
			(xy 400.071889 -394.010721) (xy 400.277332 -394.010721) (xy 400.277332 -393.958747) (xy 400.285462 -393.907412)
			(xy 400.301523 -393.857982) (xy 400.325119 -393.811672) (xy 400.355669 -393.769624) (xy 400.39242 -393.732873)
			(xy 400.434468 -393.702323) (xy 400.480778 -393.678727) (xy 400.530208 -393.662666) (xy 400.581543 -393.654536)
			(xy 400.633517 -393.654536) (xy 400.684852 -393.662666) (xy 400.734282 -393.678727) (xy 400.761078 -393.69238)
			(xy 403.088348 -393.69238) (xy 403.088883 -393.666394) (xy 403.097015 -393.615064) (xy 403.113076 -393.565636)
			(xy 403.136671 -393.51933) (xy 403.167218 -393.477284) (xy 403.203966 -393.440533) (xy 403.246009 -393.409983)
			(xy 403.292314 -393.386385) (xy 403.34174 -393.370321) (xy 403.393071 -393.362185) (xy 403.419056 -393.361672)
			(xy 403.445068 -393.362091) (xy 403.496447 -393.370258) (xy 403.545914 -393.386366) (xy 403.59225 -393.410019)
			(xy 403.634313 -393.440633) (xy 403.671065 -393.477454) (xy 403.701601 -393.519573) (xy 403.725168 -393.565953)
			(xy 403.741185 -393.61545) (xy 403.7457 -393.641072) (xy 403.747224 -393.65047) (xy 403.77145 -393.69238)
			(xy 404.288244 -393.69238) (xy 404.288783 -393.666395) (xy 404.296915 -393.615064) (xy 404.312976 -393.565637)
			(xy 404.33657 -393.519331) (xy 404.367117 -393.477285) (xy 404.403864 -393.440535) (xy 404.445907 -393.409985)
			(xy 404.492211 -393.386386) (xy 404.541637 -393.370322) (xy 404.592967 -393.362185) (xy 404.618952 -393.361672)
			(xy 404.644964 -393.362094) (xy 404.696342 -393.370261) (xy 404.74581 -393.386369) (xy 404.792146 -393.410021)
			(xy 404.834208 -393.440635) (xy 404.870961 -393.477455) (xy 404.901497 -393.519574) (xy 404.925064 -393.565954)
			(xy 404.941081 -393.61545) (xy 404.945596 -393.641072) (xy 404.94712 -393.65047) (xy 404.971346 -393.69238)
			(xy 405.488394 -393.69238) (xy 405.488883 -393.666392) (xy 405.497017 -393.615057) (xy 405.513081 -393.565626)
			(xy 405.536679 -393.519316) (xy 405.567231 -393.477268) (xy 405.603985 -393.440517) (xy 405.646035 -393.409968)
			(xy 405.692346 -393.386372) (xy 405.741778 -393.370312) (xy 405.793114 -393.362181) (xy 405.819102 -393.361672)
			(xy 405.845146 -393.362131) (xy 405.896587 -393.370319) (xy 405.946111 -393.386462) (xy 405.992496 -393.41016)
			(xy 406.034598 -393.440829) (xy 406.071378 -393.477713) (xy 406.101929 -393.519902) (xy 406.125496 -393.566354)
			(xy 406.141499 -393.615923) (xy 406.146 -393.64158) (xy 406.14727 -393.650978) (xy 406.171206 -393.69238)
			(xy 406.68829 -393.69238) (xy 406.688783 -393.666392) (xy 406.696917 -393.615057) (xy 406.71298 -393.565627)
			(xy 406.736578 -393.519317) (xy 406.76713 -393.477269) (xy 406.803883 -393.440518) (xy 406.845933 -393.409969)
			(xy 406.892243 -393.386373) (xy 406.941675 -393.370312) (xy 406.99301 -393.362182) (xy 407.018998 -393.361672)
			(xy 407.045008 -393.362143) (xy 407.096385 -393.370302) (xy 407.145851 -393.386402) (xy 407.192187 -393.410048)
			(xy 407.23425 -393.440655) (xy 407.271003 -393.47747) (xy 407.301541 -393.519584) (xy 407.325109 -393.565959)
			(xy 407.341127 -393.615452) (xy 407.345642 -393.641072) (xy 407.347166 -393.65047) (xy 407.371392 -393.69238)
			(xy 407.888186 -393.69238) (xy 407.888683 -393.666393) (xy 407.896816 -393.615058) (xy 407.91288 -393.565628)
			(xy 407.936478 -393.519319) (xy 407.967029 -393.477271) (xy 408.003781 -393.44052) (xy 408.04583 -393.40997)
			(xy 408.092141 -393.386374) (xy 408.141572 -393.370313) (xy 408.192907 -393.362182) (xy 408.218894 -393.361672)
			(xy 408.244904 -393.362147) (xy 408.29628 -393.370305) (xy 408.345747 -393.386405) (xy 408.392082 -393.41005)
			(xy 408.434146 -393.440657) (xy 408.470899 -393.477471) (xy 408.501436 -393.519585) (xy 408.525005 -393.56596)
			(xy 408.541023 -393.615452) (xy 408.545538 -393.641072) (xy 408.547062 -393.65047) (xy 408.571288 -393.69238)
			(xy 409.088336 -393.69238) (xy 409.088757 -393.666388) (xy 409.096892 -393.615044) (xy 409.11296 -393.565606)
			(xy 409.136564 -393.51929) (xy 409.167123 -393.477236) (xy 409.203885 -393.440482) (xy 409.245944 -393.409931)
			(xy 409.292265 -393.386336) (xy 409.341707 -393.370277) (xy 409.393052 -393.362152) (xy 409.419044 -393.361672)
			(xy 409.445055 -393.362102) (xy 409.496434 -393.370267) (xy 409.545901 -393.386374) (xy 409.592237 -393.410025)
			(xy 409.6343 -393.440638) (xy 409.671052 -393.477457) (xy 409.701589 -393.519576) (xy 409.725156 -393.565954)
			(xy 409.741173 -393.615451) (xy 409.745688 -393.641072) (xy 409.747212 -393.65047) (xy 409.771438 -393.69238)
			(xy 410.288232 -393.69238) (xy 410.288657 -393.666388) (xy 410.296792 -393.615045) (xy 410.31286 -393.565607)
			(xy 410.336463 -393.519291) (xy 410.367022 -393.477238) (xy 410.403784 -393.440483) (xy 410.445842 -393.409932)
			(xy 410.492162 -393.386337) (xy 410.541604 -393.370278) (xy 410.592948 -393.362152) (xy 410.61894 -393.361672)
			(xy 410.644951 -393.362105) (xy 410.69633 -393.37027) (xy 410.745797 -393.386376) (xy 410.792133 -393.410027)
			(xy 410.834195 -393.440639) (xy 410.870948 -393.477458) (xy 410.901485 -393.519576) (xy 410.925052 -393.565955)
			(xy 410.941069 -393.615451) (xy 410.945584 -393.641072) (xy 410.947108 -393.65047) (xy 410.971334 -393.69238)
			(xy 411.488382 -393.69238) (xy 411.488883 -393.666393) (xy 411.497016 -393.615059) (xy 411.513079 -393.565629)
			(xy 411.536677 -393.51932) (xy 411.567228 -393.477272) (xy 411.60398 -393.440521) (xy 411.646028 -393.409972)
			(xy 411.692338 -393.386376) (xy 411.741768 -393.370314) (xy 411.793103 -393.362182) (xy 411.81909 -393.361672)
			(xy 411.845134 -393.362142) (xy 411.896574 -393.370328) (xy 411.946098 -393.386469) (xy 411.992483 -393.410166)
			(xy 412.034585 -393.440834) (xy 412.071365 -393.477717) (xy 412.101916 -393.519904) (xy 412.125484 -393.566355)
			(xy 412.141486 -393.615924) (xy 412.145988 -393.64158) (xy 412.147258 -393.650978) (xy 412.171194 -393.69238)
			(xy 412.688278 -393.69238) (xy 412.688783 -393.666393) (xy 412.696916 -393.615059) (xy 412.712979 -393.565629)
			(xy 412.736576 -393.519321) (xy 412.767127 -393.477274) (xy 412.803878 -393.440523) (xy 412.845926 -393.409973)
			(xy 412.892235 -393.386377) (xy 412.941665 -393.370315) (xy 412.992999 -393.362183) (xy 413.018986 -393.361672)
			(xy 413.044996 -393.362154) (xy 413.096372 -393.370311) (xy 413.145838 -393.38641) (xy 413.192174 -393.410054)
			(xy 413.234237 -393.44066) (xy 413.270991 -393.477473) (xy 413.301528 -393.519586) (xy 413.325096 -393.56596)
			(xy 413.341115 -393.615453) (xy 413.34563 -393.641072) (xy 413.347154 -393.65047) (xy 413.37138 -393.69238)
			(xy 413.888174 -393.69238) (xy 413.888683 -393.666393) (xy 413.896816 -393.61506) (xy 413.912879 -393.56563)
			(xy 413.936475 -393.519322) (xy 413.967025 -393.477275) (xy 414.003776 -393.440524) (xy 414.045824 -393.409974)
			(xy 414.092132 -393.386378) (xy 414.141562 -393.370316) (xy 414.192895 -393.362183) (xy 414.218882 -393.361672)
			(xy 414.244892 -393.362158) (xy 414.296268 -393.370314) (xy 414.345733 -393.386412) (xy 414.392069 -393.410056)
			(xy 414.434133 -393.440661) (xy 414.470886 -393.477474) (xy 414.501424 -393.519587) (xy 414.524992 -393.565961)
			(xy 414.541011 -393.615453) (xy 414.545526 -393.641072) (xy 414.54705 -393.65047) (xy 414.571276 -393.69238)
			(xy 415.088324 -393.69238) (xy 415.088757 -393.666389) (xy 415.096892 -393.615046) (xy 415.112959 -393.565609)
			(xy 415.136562 -393.519293) (xy 415.16712 -393.477241) (xy 415.20388 -393.440486) (xy 415.245938 -393.409935)
			(xy 415.292257 -393.386339) (xy 415.341697 -393.37028) (xy 415.393041 -393.362153) (xy 415.419032 -393.361672)
			(xy 415.445043 -393.362112) (xy 415.496421 -393.370276) (xy 415.545888 -393.386381) (xy 415.592224 -393.410031)
			(xy 415.634287 -393.440642) (xy 415.67104 -393.477461) (xy 415.701576 -393.519578) (xy 415.725144 -393.565956)
			(xy 415.741161 -393.615451) (xy 415.745676 -393.641072) (xy 415.7472 -393.65047) (xy 415.771426 -393.69238)
			(xy 416.28822 -393.69238) (xy 416.288657 -393.666389) (xy 416.296792 -393.615047) (xy 416.312859 -393.56561)
			(xy 416.336461 -393.519295) (xy 416.367019 -393.477242) (xy 416.403779 -393.440487) (xy 416.445836 -393.409936)
			(xy 416.492154 -393.38634) (xy 416.541594 -393.370281) (xy 416.592937 -393.362153) (xy 416.618928 -393.361672)
			(xy 416.644939 -393.362116) (xy 416.696317 -393.370279) (xy 416.745783 -393.386384) (xy 416.792119 -393.410033)
			(xy 416.834182 -393.440644) (xy 416.870935 -393.477462) (xy 416.901472 -393.519578) (xy 416.92504 -393.565956)
			(xy 416.941057 -393.615451) (xy 416.945572 -393.641072) (xy 416.947096 -393.65047) (xy 416.971322 -393.69238)
			(xy 417.48837 -393.69238) (xy 417.488883 -393.666393) (xy 417.497016 -393.61506) (xy 417.513078 -393.565631)
			(xy 417.536675 -393.519323) (xy 417.567224 -393.477276) (xy 417.603975 -393.440526) (xy 417.646022 -393.409976)
			(xy 417.692329 -393.386379) (xy 417.741758 -393.370316) (xy 417.793091 -393.362183) (xy 417.819078 -393.361672)
			(xy 417.845121 -393.362153) (xy 417.896561 -393.370338) (xy 417.946085 -393.386476) (xy 417.99247 -393.410172)
			(xy 418.034572 -393.440838) (xy 418.071353 -393.47772) (xy 418.101904 -393.519906) (xy 418.125471 -393.566356)
			(xy 418.141474 -393.615924) (xy 418.145976 -393.64158) (xy 418.147246 -393.650978) (xy 418.171182 -393.69238)
			(xy 418.688266 -393.69238) (xy 418.688783 -393.666394) (xy 418.696916 -393.615061) (xy 418.712978 -393.565632)
			(xy 418.736574 -393.519325) (xy 418.767123 -393.477278) (xy 418.803873 -393.440527) (xy 418.845919 -393.409977)
			(xy 418.892227 -393.38638) (xy 418.941655 -393.370317) (xy 418.992988 -393.362183) (xy 419.018974 -393.361672)
			(xy 419.044983 -393.362165) (xy 419.096359 -393.37032) (xy 419.145825 -393.386417) (xy 419.192161 -393.41006)
			(xy 419.234224 -393.440664) (xy 419.270978 -393.477476) (xy 419.301515 -393.519588) (xy 419.325084 -393.565962)
			(xy 419.341103 -393.615453) (xy 419.345618 -393.641072) (xy 419.347142 -393.65047) (xy 419.619938 -394.122402)
			(xy 419.627304 -394.128244) (xy 419.646086 -394.14404) (xy 419.679204 -394.180259) (xy 419.706613 -394.220968)
			(xy 419.727713 -394.265277) (xy 419.742042 -394.312215) (xy 419.749287 -394.360754) (xy 419.749732 -394.385292)
			(xy 419.749478 -394.397484) (xy 419.749224 -394.407136) (xy 419.75532 -394.42517) (xy 419.813994 -394.49248)
			(xy 419.830758 -394.501116) (xy 419.840664 -394.502132) (xy 419.867422 -394.505521) (xy 419.919444 -394.519738)
			(xy 419.96847 -394.542208) (xy 420.0132 -394.572335) (xy 420.052449 -394.609322) (xy 420.085175 -394.652187)
			(xy 420.110513 -394.699795) (xy 420.127789 -394.750883) (xy 420.136546 -394.804097) (xy 420.137082 -394.831062)
			(xy 420.136557 -394.858348) (xy 420.127601 -394.912179) (xy 420.109927 -394.963809) (xy 420.084015 -395.011835)
			(xy 420.050567 -395.054955) (xy 420.03091 -395.073886) (xy 420.023514 -395.081412) (xy 420.014986 -395.100689)
			(xy 420.0144 -395.111224) (xy 420.0144 -395.1859) (xy 420.014915 -395.196451) (xy 420.02346 -395.215747)
			(xy 420.03091 -395.223238) (xy 420.050545 -395.242188) (xy 420.083981 -395.285309) (xy 420.109887 -395.333332)
			(xy 420.12756 -395.384956) (xy 420.136521 -395.43878) (xy 420.137082 -395.466062) (xy 420.136627 -395.490178)
			(xy 420.129631 -395.5379) (xy 420.115783 -395.5841) (xy 420.095375 -395.627802) (xy 420.082472 -395.64818)
			(xy 420.07663 -395.65707) (xy 420.073074 -395.677136) (xy 420.094156 -395.769338) (xy 420.106348 -395.786102)
			(xy 420.115238 -395.791436) (xy 420.13604 -395.80429) (xy 420.173945 -395.83518) (xy 420.206888 -395.871315)
			(xy 420.234149 -395.911909) (xy 420.255134 -395.956075) (xy 420.269386 -396.002849) (xy 420.276593 -396.051213)
			(xy 420.277036 -396.075662) (xy 420.276602 -396.100035) (xy 420.269457 -396.148253) (xy 420.255316 -396.194902)
			(xy 420.234485 -396.238971) (xy 420.207415 -396.279509) (xy 420.174692 -396.315637) (xy 420.156132 -396.33144)
			(xy 420.147242 -396.338552) (xy 420.137844 -396.35811) (xy 420.13505 -396.457424) (xy 420.143686 -396.47749)
			(xy 420.152068 -396.48511) (xy 420.17052 -396.502569) (xy 420.201865 -396.542541) (xy 420.226161 -396.58715)
			(xy 420.242738 -396.635166) (xy 420.251137 -396.685264) (xy 420.251636 -396.710662) (xy 420.251533 -396.721943)
			(xy 420.249881 -396.744445) (xy 420.248334 -396.75562) (xy 420.247064 -396.764764) (xy 420.250366 -396.782036)
			(xy 420.294054 -396.853156) (xy 420.30777 -396.864078) (xy 420.316406 -396.866872) (xy 420.344573 -396.877064)
			(xy 420.396518 -396.906879) (xy 420.41953 -396.926054) (xy 420.441018 -396.945631) (xy 420.476829 -396.991413)
			(xy 420.49065 -397.016986) (xy 420.491412 -397.018256) (xy 420.883588 -397.696944) (xy 420.896319 -397.72031)
			(xy 420.914436 -397.770338) (xy 420.923646 -397.822741) (xy 420.924228 -397.849344) (xy 420.923778 -397.873335)
			(xy 420.916266 -397.920727) (xy 420.901434 -397.96636) (xy 420.879647 -398.009111) (xy 420.851441 -398.047928)
			(xy 420.81751 -398.081856) (xy 420.778691 -398.110059) (xy 420.735937 -398.131843) (xy 420.690303 -398.146672)
			(xy 420.642911 -398.15418) (xy 420.61892 -398.154652) (xy 420.595387 -398.154233) (xy 420.548878 -398.14702)
			(xy 420.504029 -398.132748) (xy 420.461906 -398.111755) (xy 420.423507 -398.084539) (xy 420.389746 -398.051747)
			(xy 420.361424 -398.014157) (xy 420.349934 -397.993616) (xy 420.34968 -397.993108) (xy 420.349172 -397.992346)
			(xy 419.951662 -397.303752) (xy 419.941085 -397.283827) (xy 419.925285 -397.241577) (xy 419.915879 -397.197459)
			(xy 419.91407 -397.174974) (xy 419.913562 -397.163798) (xy 419.913308 -397.156432) (xy 419.913465 -397.145083)
			(xy 419.915242 -397.122454) (xy 419.916864 -397.11122) (xy 419.918134 -397.10233) (xy 419.914578 -397.085058)
			(xy 419.871144 -397.013938) (xy 419.857428 -397.002762) (xy 419.848792 -396.999968) (xy 419.826394 -396.991959)
			(xy 419.784223 -396.969959) (xy 419.745974 -396.941684) (xy 419.712573 -396.90782) (xy 419.684829 -396.869184)
			(xy 419.663413 -396.826713) (xy 419.648843 -396.781435) (xy 419.641471 -396.734445) (xy 419.64102 -396.710662)
			(xy 419.641539 -396.685267) (xy 419.649949 -396.635177) (xy 419.66653 -396.587169) (xy 419.690826 -396.542566)
			(xy 419.722167 -396.502598) (xy 419.740588 -396.48511) (xy 419.74897 -396.47749) (xy 419.757606 -396.457424)
			(xy 419.754812 -396.35811) (xy 419.745414 -396.338552) (xy 419.736524 -396.33144) (xy 419.717981 -396.315619)
			(xy 419.685262 -396.279491) (xy 419.658193 -396.238956) (xy 419.63736 -396.194891) (xy 419.623213 -396.148247)
			(xy 419.616058 -396.100033) (xy 419.61562 -396.075662) (xy 419.616039 -396.051545) (xy 419.623045 -396.003822)
			(xy 419.636904 -395.957621) (xy 419.657322 -395.913921) (xy 419.67023 -395.893544) (xy 419.676072 -395.884654)
			(xy 419.679628 -395.864588) (xy 419.658546 -395.772386) (xy 419.646354 -395.755622) (xy 419.637464 -395.750288)
			(xy 419.616673 -395.737417) (xy 419.578768 -395.70653) (xy 419.545825 -395.670397) (xy 419.518562 -395.629807)
			(xy 419.497575 -395.585644) (xy 419.483321 -395.538872) (xy 419.476111 -395.49051) (xy 419.475666 -395.466062)
			(xy 419.476224 -395.438778) (xy 419.485173 -395.384949) (xy 419.502841 -395.33332) (xy 419.528745 -395.285293)
			(xy 419.562185 -395.242171) (xy 419.581838 -395.223238) (xy 419.589216 -395.215696) (xy 419.597756 -395.196432)
			(xy 419.598348 -395.1859) (xy 419.598348 -395.111224) (xy 419.597805 -395.100676) (xy 419.589278 -395.081382)
			(xy 419.581838 -395.073886) (xy 419.562205 -395.054934) (xy 419.528771 -395.011813) (xy 419.502866 -394.96379)
			(xy 419.485192 -394.912167) (xy 419.476229 -394.858344) (xy 419.475666 -394.831062) (xy 419.47592 -394.81887)
			(xy 419.476174 -394.809218) (xy 419.470078 -394.791184) (xy 419.411404 -394.723874) (xy 419.39464 -394.715238)
			(xy 419.384734 -394.714222) (xy 419.357824 -394.710871) (xy 419.305538 -394.696503) (xy 419.256295 -394.673801)
			(xy 419.211412 -394.643373) (xy 419.172093 -394.606032) (xy 419.139389 -394.56278) (xy 419.114176 -394.514774)
			(xy 419.09713 -394.463299) (xy 419.09238 -394.4366) (xy 419.090856 -394.427202) (xy 418.81806 -393.95527)
			(xy 418.810694 -393.949428) (xy 418.791946 -393.933593) (xy 418.758826 -393.897383) (xy 418.731413 -393.856681)
			(xy 418.710307 -393.81238) (xy 418.69597 -393.765449) (xy 418.688716 -393.716916) (xy 418.688266 -393.69238)
			(xy 418.171182 -393.69238) (xy 418.419788 -394.122402) (xy 418.427154 -394.128244) (xy 418.445947 -394.144029)
			(xy 418.479061 -394.180251) (xy 418.506467 -394.220963) (xy 418.527565 -394.265274) (xy 418.541893 -394.312213)
			(xy 418.549137 -394.360753) (xy 418.549582 -394.385292) (xy 418.549328 -394.397484) (xy 418.549074 -394.407136)
			(xy 418.55517 -394.42517) (xy 418.613844 -394.49248) (xy 418.630608 -394.501116) (xy 418.640514 -394.502132)
			(xy 418.667277 -394.50548) (xy 418.7193 -394.519705) (xy 418.768326 -394.542182) (xy 418.813055 -394.572315)
			(xy 418.852303 -394.609307) (xy 418.885028 -394.652176) (xy 418.910364 -394.699788) (xy 418.927639 -394.750879)
			(xy 418.936396 -394.804096) (xy 418.936932 -394.831062) (xy 418.936391 -394.858347) (xy 418.927437 -394.912177)
			(xy 418.909766 -394.963805) (xy 418.883857 -395.011832) (xy 418.850415 -395.054953) (xy 418.83076 -395.073886)
			(xy 418.823371 -395.081419) (xy 418.814838 -395.10069) (xy 418.81425 -395.111224) (xy 418.81425 -395.1859)
			(xy 418.814781 -395.196449) (xy 418.823316 -395.215744) (xy 418.83076 -395.223238) (xy 418.850405 -395.242179)
			(xy 418.883837 -395.285303) (xy 418.90974 -395.333329) (xy 418.927411 -395.384954) (xy 418.936371 -395.438779)
			(xy 418.936932 -395.466062) (xy 418.936485 -395.490178) (xy 418.929488 -395.537901) (xy 418.915638 -395.584102)
			(xy 418.895227 -395.627803) (xy 418.882322 -395.64818) (xy 418.87648 -395.65707) (xy 418.872924 -395.677136)
			(xy 418.894006 -395.769338) (xy 418.906198 -395.786102) (xy 418.915088 -395.791436) (xy 418.935878 -395.804308)
			(xy 418.973786 -395.835193) (xy 419.006731 -395.871324) (xy 419.033995 -395.911915) (xy 419.054982 -395.956078)
			(xy 419.069235 -396.002851) (xy 419.076443 -396.051214) (xy 419.076886 -396.075662) (xy 419.07647 -396.100035)
			(xy 419.069324 -396.148255) (xy 419.055181 -396.194905) (xy 419.034347 -396.238975) (xy 419.007272 -396.279512)
			(xy 418.974544 -396.315638) (xy 418.955982 -396.33144) (xy 418.947092 -396.338552) (xy 418.937694 -396.35811)
			(xy 418.9349 -396.457424) (xy 418.943536 -396.47749) (xy 418.951918 -396.48511) (xy 418.97036 -396.502579)
			(xy 419.001709 -396.542547) (xy 419.026008 -396.587154) (xy 419.042586 -396.635168) (xy 419.050986 -396.685264)
			(xy 419.051486 -396.710662) (xy 419.051382 -396.721943) (xy 419.049731 -396.744445) (xy 419.048184 -396.75562)
			(xy 419.046914 -396.76451) (xy 419.05047 -396.782036) (xy 419.093904 -396.852902) (xy 419.10762 -396.864078)
			(xy 419.116256 -396.866872) (xy 419.138501 -396.874807) (xy 419.180422 -396.896558) (xy 419.218496 -396.924503)
			(xy 419.251814 -396.957975) (xy 419.279583 -396.996177) (xy 419.290754 -397.016986) (xy 419.291262 -397.018002)
			(xy 419.683692 -397.696944) (xy 419.696424 -397.72031) (xy 419.71454 -397.770338) (xy 419.72375 -397.822741)
			(xy 419.724332 -397.849344) (xy 419.723878 -397.873335) (xy 419.716366 -397.920726) (xy 419.701534 -397.966359)
			(xy 419.679747 -398.00911) (xy 419.651542 -398.047927) (xy 419.617612 -398.081855) (xy 419.578793 -398.110058)
			(xy 419.53604 -398.131842) (xy 419.490407 -398.146671) (xy 419.443015 -398.15418) (xy 419.419024 -398.154652)
			(xy 419.395491 -398.15423) (xy 419.348982 -398.147018) (xy 419.304134 -398.132746) (xy 419.26201 -398.111753)
			(xy 419.223612 -398.084538) (xy 419.189851 -398.051746) (xy 419.161528 -398.014157) (xy 419.150038 -397.993616)
			(xy 419.149784 -397.993108) (xy 419.149276 -397.992346) (xy 418.751512 -397.304006) (xy 418.739598 -397.281337)
			(xy 418.72266 -397.233012) (xy 418.714 -397.182542) (xy 418.713412 -397.15694) (xy 418.713412 -397.156432)
			(xy 418.713569 -397.145083) (xy 418.715346 -397.122454) (xy 418.716968 -397.11122) (xy 418.718238 -397.10233)
			(xy 418.714682 -397.085058) (xy 418.671248 -397.013938) (xy 418.657278 -397.003016) (xy 418.648896 -396.999968)
			(xy 418.626484 -396.991962) (xy 418.584267 -396.969997) (xy 418.545972 -396.941744) (xy 418.512527 -396.907888)
			(xy 418.484744 -396.86925) (xy 418.463297 -396.826767) (xy 418.448705 -396.78147) (xy 418.441323 -396.734457)
			(xy 418.44087 -396.710662) (xy 418.441405 -396.685268) (xy 418.449814 -396.63518) (xy 418.466392 -396.587173)
			(xy 418.490684 -396.54257) (xy 418.522019 -396.5026) (xy 418.540438 -396.48511) (xy 418.54882 -396.47749)
			(xy 418.557456 -396.457424) (xy 418.554662 -396.35811) (xy 418.545264 -396.338552) (xy 418.536374 -396.33144)
			(xy 418.517841 -396.315607) (xy 418.485119 -396.279483) (xy 418.458048 -396.238951) (xy 418.437213 -396.194888)
			(xy 418.423064 -396.148245) (xy 418.415908 -396.100032) (xy 418.41547 -396.075662) (xy 418.41588 -396.051544)
			(xy 418.422888 -396.003821) (xy 418.436749 -395.95762) (xy 418.45717 -395.91392) (xy 418.47008 -395.893544)
			(xy 418.475922 -395.884654) (xy 418.479478 -395.864588) (xy 418.458396 -395.772386) (xy 418.446204 -395.755622)
			(xy 418.437314 -395.750288) (xy 418.416535 -395.737399) (xy 418.378627 -395.706517) (xy 418.345681 -395.670388)
			(xy 418.318417 -395.629801) (xy 418.297428 -395.58564) (xy 418.283172 -395.53887) (xy 418.275961 -395.490509)
			(xy 418.275516 -395.466062) (xy 418.276058 -395.438777) (xy 418.285009 -395.384947) (xy 418.302679 -395.333317)
			(xy 418.328588 -395.28529) (xy 418.362032 -395.24217) (xy 418.381688 -395.223238) (xy 418.389073 -395.215703)
			(xy 418.397607 -395.196433) (xy 418.398198 -395.1859) (xy 418.398198 -395.111224) (xy 418.39767 -395.100674)
			(xy 418.389134 -395.081379) (xy 418.381688 -395.073886) (xy 418.362064 -395.054924) (xy 418.328627 -395.011807)
			(xy 418.302719 -394.963786) (xy 418.285044 -394.912165) (xy 418.276079 -394.858344) (xy 418.275516 -394.831062)
			(xy 418.27577 -394.81887) (xy 418.276024 -394.809218) (xy 418.269928 -394.791184) (xy 418.211254 -394.723874)
			(xy 418.19449 -394.715238) (xy 418.184584 -394.714222) (xy 418.15768 -394.710831) (xy 418.105394 -394.696471)
			(xy 418.056151 -394.673776) (xy 418.011268 -394.643354) (xy 417.971947 -394.606019) (xy 417.939242 -394.562771)
			(xy 417.914028 -394.514769) (xy 417.89698 -394.463297) (xy 417.89223 -394.4366) (xy 417.890706 -394.427202)
			(xy 417.617656 -393.954762) (xy 417.610544 -393.94892) (xy 417.591801 -393.933153) (xy 417.558749 -393.897007)
			(xy 417.531395 -393.856379) (xy 417.510338 -393.812157) (xy 417.49604 -393.765312) (xy 417.488812 -393.716869)
			(xy 417.48837 -393.69238) (xy 416.971322 -393.69238) (xy 417.219892 -394.122402) (xy 417.227258 -394.128244)
			(xy 417.246051 -394.144028) (xy 417.279166 -394.18025) (xy 417.306572 -394.220962) (xy 417.327669 -394.265274)
			(xy 417.341997 -394.312213) (xy 417.349241 -394.360753) (xy 417.349686 -394.385292) (xy 417.349432 -394.397484)
			(xy 417.349178 -394.407136) (xy 417.355274 -394.42517) (xy 417.413948 -394.49248) (xy 417.430712 -394.501116)
			(xy 417.440618 -394.502132) (xy 417.467382 -394.505476) (xy 417.519405 -394.519702) (xy 417.568431 -394.542179)
			(xy 417.61316 -394.572313) (xy 417.652407 -394.609305) (xy 417.685133 -394.652175) (xy 417.710469 -394.699787)
			(xy 417.727744 -394.750878) (xy 417.736501 -394.804096) (xy 417.737036 -394.831062) (xy 417.736493 -394.858347)
			(xy 417.72754 -394.912176) (xy 417.709869 -394.963805) (xy 417.683961 -395.011832) (xy 417.650519 -395.054953)
			(xy 417.630864 -395.073886) (xy 417.623476 -395.081419) (xy 417.614942 -395.10069) (xy 417.614354 -395.111224)
			(xy 417.614354 -395.1859) (xy 417.614883 -395.196449) (xy 417.62342 -395.215744) (xy 417.630864 -395.223238)
			(xy 417.650509 -395.242178) (xy 417.683941 -395.285303) (xy 417.709844 -395.333329) (xy 417.727515 -395.384954)
			(xy 417.736475 -395.438779) (xy 417.737036 -395.466062) (xy 417.736588 -395.490178) (xy 417.729592 -395.537901)
			(xy 417.715742 -395.584102) (xy 417.695331 -395.627802) (xy 417.682426 -395.64818) (xy 417.676584 -395.65707)
			(xy 417.673028 -395.677136) (xy 417.69411 -395.769338) (xy 417.706302 -395.786102) (xy 417.715192 -395.791436)
			(xy 417.735983 -395.804306) (xy 417.773891 -395.835192) (xy 417.806836 -395.871324) (xy 417.834099 -395.911914)
			(xy 417.855086 -395.956078) (xy 417.869339 -396.002851) (xy 417.876547 -396.051214) (xy 417.87699 -396.075662)
			(xy 417.876573 -396.100035) (xy 417.869427 -396.148255) (xy 417.855284 -396.194905) (xy 417.83445 -396.238975)
			(xy 417.807376 -396.279512) (xy 417.774648 -396.315638) (xy 417.756086 -396.33144) (xy 417.747196 -396.338552)
			(xy 417.737798 -396.35811) (xy 417.735004 -396.457424) (xy 417.74364 -396.47749) (xy 417.752022 -396.48511)
			(xy 417.770465 -396.502579) (xy 417.801813 -396.542547) (xy 417.826112 -396.587154) (xy 417.84269 -396.635168)
			(xy 417.85109 -396.685264) (xy 417.85159 -396.710662) (xy 417.851486 -396.721943) (xy 417.849835 -396.744445)
			(xy 417.848288 -396.75562) (xy 417.847018 -396.764764) (xy 417.85032 -396.782036) (xy 417.894008 -396.853156)
			(xy 417.907724 -396.864078) (xy 417.91636 -396.866872) (xy 417.944523 -396.877074) (xy 417.99647 -396.906882)
			(xy 418.019484 -396.926054) (xy 418.040967 -396.945637) (xy 418.076781 -396.991414) (xy 418.090604 -397.016986)
			(xy 418.091366 -397.018256) (xy 418.483542 -397.696944) (xy 418.496349 -397.720286) (xy 418.514576 -397.770304)
			(xy 418.523843 -397.822727) (xy 418.524436 -397.849344) (xy 418.524002 -397.87335) (xy 418.516481 -397.920768)
			(xy 418.501633 -397.966426) (xy 418.479822 -398.009197) (xy 418.451587 -398.048029) (xy 418.417623 -398.081963)
			(xy 418.378767 -398.110164) (xy 418.335976 -398.131936) (xy 418.290305 -398.146744) (xy 418.24288 -398.154223)
			(xy 418.218874 -398.154652) (xy 418.195343 -398.15419) (xy 418.148836 -398.146985) (xy 418.103988 -398.13272)
			(xy 418.061864 -398.111734) (xy 418.023465 -398.084525) (xy 417.989703 -398.051739) (xy 417.961379 -398.014155)
			(xy 417.949888 -397.993616) (xy 417.949634 -397.993108) (xy 417.949126 -397.992346) (xy 417.551616 -397.303752)
			(xy 417.541044 -397.283825) (xy 417.52524 -397.241576) (xy 417.515833 -397.197459) (xy 417.514024 -397.174974)
			(xy 417.513516 -397.163798) (xy 417.513516 -397.156432) (xy 417.513607 -397.145087) (xy 417.515262 -397.122458)
			(xy 417.516818 -397.11122) (xy 417.518088 -397.10233) (xy 417.514532 -397.085058) (xy 417.471098 -397.013938)
			(xy 417.457382 -397.002762) (xy 417.448746 -396.999968) (xy 417.426339 -396.991986) (xy 417.384168 -396.969979)
			(xy 417.345921 -396.9417) (xy 417.312522 -396.907831) (xy 417.28478 -396.869192) (xy 417.263365 -396.826718)
			(xy 417.248796 -396.781438) (xy 417.241425 -396.734445) (xy 417.240974 -396.710662) (xy 417.241508 -396.685268)
			(xy 417.249917 -396.635179) (xy 417.266495 -396.587172) (xy 417.290787 -396.542569) (xy 417.322123 -396.5026)
			(xy 417.340542 -396.48511) (xy 417.348924 -396.47749) (xy 417.35756 -396.457424) (xy 417.354766 -396.35811)
			(xy 417.345368 -396.338552) (xy 417.336478 -396.33144) (xy 417.317946 -396.315606) (xy 417.285224 -396.279482)
			(xy 417.258152 -396.238951) (xy 417.237317 -396.194887) (xy 417.223168 -396.148245) (xy 417.216012 -396.100032)
			(xy 417.215574 -396.075662) (xy 417.215984 -396.051544) (xy 417.222991 -396.003821) (xy 417.236853 -395.95762)
			(xy 417.257274 -395.91392) (xy 417.270184 -395.893544) (xy 417.276026 -395.884654) (xy 417.279582 -395.864588)
			(xy 417.2585 -395.772386) (xy 417.246308 -395.755622) (xy 417.237418 -395.750288) (xy 417.21664 -395.737398)
			(xy 417.178732 -395.706516) (xy 417.145786 -395.670387) (xy 417.118521 -395.6298) (xy 417.097532 -395.58564)
			(xy 417.083276 -395.538869) (xy 417.076065 -395.490509) (xy 417.07562 -395.466062) (xy 417.07616 -395.438777)
			(xy 417.085112 -395.384946) (xy 417.102782 -395.333317) (xy 417.128691 -395.28529) (xy 417.162136 -395.24217)
			(xy 417.181792 -395.223238) (xy 417.189178 -395.215703) (xy 417.197711 -395.196433) (xy 417.198302 -395.1859)
			(xy 417.198302 -395.111224) (xy 417.197773 -395.100674) (xy 417.189238 -395.081379) (xy 417.181792 -395.073886)
			(xy 417.162169 -395.054924) (xy 417.128731 -395.011806) (xy 417.102824 -394.963786) (xy 417.085148 -394.912165)
			(xy 417.076183 -394.858344) (xy 417.07562 -394.831062) (xy 417.075874 -394.81887) (xy 417.076128 -394.809218)
			(xy 417.070032 -394.791184) (xy 417.011358 -394.723874) (xy 416.994594 -394.715238) (xy 416.984688 -394.714222)
			(xy 416.957784 -394.710828) (xy 416.905499 -394.696469) (xy 416.856255 -394.673774) (xy 416.811372 -394.643352)
			(xy 416.772052 -394.606018) (xy 416.739346 -394.562771) (xy 416.714132 -394.514769) (xy 416.697084 -394.463297)
			(xy 416.692334 -394.4366) (xy 416.69081 -394.427202) (xy 416.418014 -393.95527) (xy 416.410648 -393.949428)
			(xy 416.39189 -393.933604) (xy 416.358774 -393.89739) (xy 416.331363 -393.856686) (xy 416.310259 -393.812383)
			(xy 416.295923 -393.76545) (xy 416.28867 -393.716916) (xy 416.28822 -393.69238) (xy 415.771426 -393.69238)
			(xy 416.019996 -394.122402) (xy 416.027362 -394.128244) (xy 416.046156 -394.144027) (xy 416.07927 -394.180249)
			(xy 416.106676 -394.220962) (xy 416.127774 -394.265273) (xy 416.142101 -394.312213) (xy 416.149345 -394.360753)
			(xy 416.14979 -394.385292) (xy 416.149536 -394.397484) (xy 416.149282 -394.407136) (xy 416.155378 -394.42517)
			(xy 416.214052 -394.49248) (xy 416.230816 -394.501116) (xy 416.240468 -394.502132) (xy 416.267226 -394.505517)
			(xy 416.319249 -394.519735) (xy 416.368275 -394.542206) (xy 416.413005 -394.572334) (xy 416.452253 -394.609321)
			(xy 416.48498 -394.652186) (xy 416.510317 -394.699794) (xy 416.527593 -394.750882) (xy 416.53635 -394.804097)
			(xy 416.536886 -394.831062) (xy 416.536376 -394.857049) (xy 416.528246 -394.908384) (xy 416.512185 -394.957814)
			(xy 416.488589 -395.004124) (xy 416.458039 -395.046172) (xy 416.421288 -395.082923) (xy 416.37924 -395.113473)
			(xy 416.33293 -395.137069) (xy 416.2835 -395.15313) (xy 416.232165 -395.16126) (xy 416.180191 -395.16126)
			(xy 416.128856 -395.15313) (xy 416.079426 -395.137069) (xy 416.033116 -395.113473) (xy 415.991068 -395.082923)
			(xy 415.954317 -395.046172) (xy 415.923767 -395.004124) (xy 415.900171 -394.957814) (xy 415.88411 -394.908384)
			(xy 415.87598 -394.857049) (xy 415.87547 -394.831062) (xy 415.875724 -394.81887) (xy 415.875978 -394.809218)
			(xy 415.869882 -394.791184) (xy 415.811208 -394.723874) (xy 415.794444 -394.715238) (xy 415.784792 -394.714222)
			(xy 415.757889 -394.710825) (xy 415.705603 -394.696466) (xy 415.65636 -394.673772) (xy 415.611477 -394.643351)
			(xy 415.572156 -394.606017) (xy 415.539451 -394.56277) (xy 415.514236 -394.514768) (xy 415.497188 -394.463297)
			(xy 415.492438 -394.4366) (xy 415.490914 -394.427202) (xy 415.218118 -393.95527) (xy 415.210752 -393.949428)
			(xy 415.191995 -393.933603) (xy 415.158878 -393.897389) (xy 415.131467 -393.856686) (xy 415.110363 -393.812383)
			(xy 415.096027 -393.76545) (xy 415.088774 -393.716916) (xy 415.088324 -393.69238) (xy 414.571276 -393.69238)
			(xy 414.819846 -394.122402) (xy 414.827212 -394.128244) (xy 414.845996 -394.144039) (xy 414.879113 -394.180257)
			(xy 414.906521 -394.220967) (xy 414.927621 -394.265276) (xy 414.94195 -394.312215) (xy 414.949195 -394.360754)
			(xy 414.94964 -394.385292) (xy 414.949386 -394.397484) (xy 414.949132 -394.407136) (xy 414.955228 -394.42517)
			(xy 415.013902 -394.49248) (xy 415.030666 -394.501116) (xy 415.040572 -394.502132) (xy 415.067331 -394.505514)
			(xy 415.119353 -394.519732) (xy 415.168379 -394.542204) (xy 415.213109 -394.572332) (xy 415.252358 -394.60932)
			(xy 415.285084 -394.652185) (xy 415.310421 -394.699794) (xy 415.327697 -394.750882) (xy 415.336454 -394.804097)
			(xy 415.33699 -394.831062) (xy 415.336566 -394.855264) (xy 415.329493 -394.903149) (xy 415.315506 -394.949489)
			(xy 415.294905 -394.993291) (xy 415.281872 -395.013688) (xy 415.277084 -395.021645) (xy 415.27305 -395.039756)
			(xy 415.273998 -395.048994) (xy 415.278316 -395.079982) (xy 415.279993 -395.089279) (xy 415.289277 -395.105721)
			(xy 415.29635 -395.111986) (xy 415.318436 -395.130671) (xy 415.358208 -395.172682) (xy 415.39237 -395.219369)
			(xy 415.420379 -395.269989) (xy 415.441786 -395.323733) (xy 415.456252 -395.379747) (xy 415.463545 -395.437136)
			(xy 415.46399 -395.466062) (xy 415.463396 -395.499383) (xy 415.453734 -395.565321) (xy 415.43461 -395.629161)
			(xy 415.421064 -395.65961) (xy 415.416821 -395.670076) (xy 415.416935 -395.692633) (xy 415.426666 -395.712984)
			(xy 415.435034 -395.72057) (xy 415.457271 -395.739254) (xy 415.497334 -395.781309) (xy 415.531754 -395.828094)
			(xy 415.55998 -395.878857) (xy 415.581557 -395.932783) (xy 415.596139 -395.989005) (xy 415.603491 -396.046621)
			(xy 415.603944 -396.075662) (xy 415.60347 -396.104667) (xy 415.596159 -396.162214) (xy 415.581637 -396.218377)
			(xy 415.560136 -396.272255) (xy 415.532001 -396.322986) (xy 415.497683 -396.369756) (xy 415.457732 -396.411816)
			(xy 415.435542 -396.4305) (xy 415.42843 -396.436088) (xy 415.419286 -396.451328) (xy 415.404046 -396.534132)
			(xy 415.40684 -396.551404) (xy 415.411412 -396.559532) (xy 415.423985 -396.58272) (xy 415.44186 -396.632341)
			(xy 415.450962 -396.684291) (xy 415.451544 -396.710662) (xy 416.040824 -396.710662) (xy 416.041346 -396.685407)
			(xy 416.049659 -396.635585) (xy 416.06606 -396.587811) (xy 416.090101 -396.543388) (xy 416.121125 -396.503528)
			(xy 416.158287 -396.469318) (xy 416.200573 -396.441692) (xy 416.246829 -396.421402) (xy 416.295794 -396.409002)
			(xy 416.346132 -396.404831) (xy 416.39647 -396.409002) (xy 416.445435 -396.421402) (xy 416.491691 -396.441692)
			(xy 416.533977 -396.469318) (xy 416.571139 -396.503528) (xy 416.602163 -396.543388) (xy 416.626204 -396.587811)
			(xy 416.642605 -396.635585) (xy 416.650918 -396.685407) (xy 416.65144 -396.710662) (xy 416.651337 -396.721943)
			(xy 416.649685 -396.744445) (xy 416.648138 -396.75562) (xy 416.646868 -396.76451) (xy 416.650424 -396.782036)
			(xy 416.693858 -396.852902) (xy 416.707574 -396.864078) (xy 416.71621 -396.866872) (xy 416.738465 -396.874781)
			(xy 416.780385 -396.89654) (xy 416.818456 -396.924491) (xy 416.851772 -396.957968) (xy 416.879539 -396.996175)
			(xy 416.890708 -397.016986) (xy 416.891216 -397.018002) (xy 417.283646 -397.696944) (xy 417.296453 -397.720286)
			(xy 417.31468 -397.770304) (xy 417.323947 -397.822727) (xy 417.32454 -397.849344) (xy 417.324102 -397.873349)
			(xy 417.316581 -397.920768) (xy 417.301733 -397.966425) (xy 417.279923 -398.009196) (xy 417.251688 -398.048027)
			(xy 417.217725 -398.081961) (xy 417.178869 -398.110162) (xy 417.136079 -398.131935) (xy 417.090409 -398.146744)
			(xy 417.042984 -398.154222) (xy 417.018978 -398.154652) (xy 416.995447 -398.154186) (xy 416.94894 -398.146983)
			(xy 416.904092 -398.132718) (xy 416.861969 -398.111733) (xy 416.82357 -398.084524) (xy 416.789807 -398.051739)
			(xy 416.761483 -398.014155) (xy 416.749992 -397.993616) (xy 416.749738 -397.993108) (xy 416.74923 -397.992346)
			(xy 416.351466 -397.304006) (xy 416.339591 -397.281329) (xy 416.322739 -397.232996) (xy 416.314166 -397.182533)
			(xy 416.31362 -397.15694) (xy 416.31362 -397.156432) (xy 416.313711 -397.145087) (xy 416.315366 -397.122458)
			(xy 416.316922 -397.11122) (xy 416.318192 -397.10233) (xy 416.314636 -397.085058) (xy 416.271202 -397.013938)
			(xy 416.257232 -397.003016) (xy 416.24885 -396.999968) (xy 416.226449 -396.991931) (xy 416.184231 -396.969973)
			(xy 416.145934 -396.941726) (xy 416.112487 -396.907875) (xy 416.084703 -396.869241) (xy 416.063254 -396.826762)
			(xy 416.04866 -396.781467) (xy 416.041277 -396.734456) (xy 416.040824 -396.710662) (xy 415.451544 -396.710662)
			(xy 415.451441 -396.721943) (xy 415.449789 -396.744445) (xy 415.448242 -396.75562) (xy 415.446972 -396.76451)
			(xy 415.450528 -396.782036) (xy 415.493962 -396.852902) (xy 415.507678 -396.864078) (xy 415.516314 -396.866872)
			(xy 415.53857 -396.87478) (xy 415.580489 -396.896538) (xy 415.618561 -396.92449) (xy 415.651877 -396.957968)
			(xy 415.679643 -396.996174) (xy 415.690812 -397.016986) (xy 415.69132 -397.018002) (xy 416.08375 -397.696944)
			(xy 416.096557 -397.720285) (xy 416.114784 -397.770304) (xy 416.124051 -397.822726) (xy 416.124644 -397.849344)
			(xy 416.124202 -397.873349) (xy 416.116682 -397.920767) (xy 416.101834 -397.966424) (xy 416.080024 -398.009195)
			(xy 416.05179 -398.048026) (xy 416.017826 -398.08196) (xy 415.978971 -398.110161) (xy 415.936182 -398.131934)
			(xy 415.890512 -398.146743) (xy 415.843088 -398.154222) (xy 415.819082 -398.154652) (xy 415.795551 -398.154183)
			(xy 415.749044 -398.14698) (xy 415.704196 -398.132716) (xy 415.662073 -398.111731) (xy 415.623674 -398.084523)
			(xy 415.589911 -398.051738) (xy 415.561587 -398.014155) (xy 415.550096 -397.993616) (xy 415.549842 -397.993108)
			(xy 415.549334 -397.992346) (xy 415.15157 -397.304006) (xy 415.139695 -397.281329) (xy 415.122843 -397.232996)
			(xy 415.11427 -397.182533) (xy 415.113724 -397.15694) (xy 415.113724 -397.156432) (xy 415.113815 -397.145087)
			(xy 415.11547 -397.122458) (xy 415.117026 -397.11122) (xy 415.118296 -397.10233) (xy 415.11474 -397.085058)
			(xy 415.071306 -397.013938) (xy 415.057336 -397.003016) (xy 415.048954 -396.999968) (xy 415.026554 -396.991929)
			(xy 414.984336 -396.969971) (xy 414.946038 -396.941724) (xy 414.912592 -396.907874) (xy 414.884807 -396.86924)
			(xy 414.863358 -396.826761) (xy 414.848765 -396.781467) (xy 414.841381 -396.734456) (xy 414.840928 -396.710662)
			(xy 414.84149 -396.684289) (xy 414.850574 -396.63233) (xy 414.868464 -396.58271) (xy 414.88106 -396.559532)
			(xy 414.885632 -396.551404) (xy 414.888426 -396.534132) (xy 414.873186 -396.451328) (xy 414.864042 -396.436088)
			(xy 414.85693 -396.4305) (xy 414.834766 -396.411787) (xy 414.794817 -396.369727) (xy 414.760498 -396.322961)
			(xy 414.732358 -396.272236) (xy 414.710847 -396.218364) (xy 414.69631 -396.162208) (xy 414.688979 -396.104666)
			(xy 414.688528 -396.075662) (xy 414.689129 -396.042341) (xy 414.698787 -395.976403) (xy 414.717909 -395.912563)
			(xy 414.731454 -395.882114) (xy 414.735702 -395.871647) (xy 414.735597 -395.849086) (xy 414.725859 -395.828735)
			(xy 414.717484 -395.821154) (xy 414.695214 -395.802507) (xy 414.655152 -395.760446) (xy 414.620734 -395.713655)
			(xy 414.592513 -395.662886) (xy 414.570941 -395.608953) (xy 414.556366 -395.552725) (xy 414.549022 -395.495105)
			(xy 414.548574 -395.466062) (xy 414.549017 -395.437135) (xy 414.556301 -395.379742) (xy 414.570761 -395.323725)
			(xy 414.592166 -395.269977) (xy 414.620174 -395.219356) (xy 414.65434 -395.172668) (xy 414.694117 -395.130659)
			(xy 414.716214 -395.111986) (xy 414.723178 -395.105631) (xy 414.732442 -395.089233) (xy 414.734248 -395.079982)
			(xy 414.738566 -395.048994) (xy 414.739467 -395.039757) (xy 414.735444 -395.021658) (xy 414.730692 -395.013688)
			(xy 414.717704 -394.993266) (xy 414.697123 -394.949464) (xy 414.683137 -394.903133) (xy 414.676041 -394.85526)
			(xy 414.675574 -394.831062) (xy 414.675828 -394.81887) (xy 414.676082 -394.809218) (xy 414.669986 -394.791184)
			(xy 414.611312 -394.723874) (xy 414.594548 -394.715238) (xy 414.584642 -394.714222) (xy 414.557733 -394.710865)
			(xy 414.505447 -394.696498) (xy 414.456204 -394.673797) (xy 414.411321 -394.64337) (xy 414.372002 -394.60603)
			(xy 414.339298 -394.562779) (xy 414.314085 -394.514773) (xy 414.297038 -394.463298) (xy 414.292288 -394.4366)
			(xy 414.290764 -394.427202) (xy 414.017968 -393.95527) (xy 414.010602 -393.949428) (xy 413.991856 -393.93359)
			(xy 413.958736 -393.897381) (xy 413.931322 -393.85668) (xy 413.910216 -393.812379) (xy 413.895879 -393.765449)
			(xy 413.888625 -393.716916) (xy 413.888174 -393.69238) (xy 413.37138 -393.69238) (xy 413.61995 -394.122402)
			(xy 413.627316 -394.128244) (xy 413.646101 -394.144038) (xy 413.679217 -394.180257) (xy 413.706626 -394.220967)
			(xy 413.727725 -394.265276) (xy 413.742054 -394.312215) (xy 413.749299 -394.360754) (xy 413.749744 -394.385292)
			(xy 413.74949 -394.397484) (xy 413.749236 -394.407136) (xy 413.755332 -394.42517) (xy 413.814006 -394.49248)
			(xy 413.83077 -394.501116) (xy 413.840422 -394.502132) (xy 413.867186 -394.505473) (xy 413.91921 -394.519699)
			(xy 413.968235 -394.542177) (xy 414.012965 -394.572312) (xy 414.052212 -394.609304) (xy 414.084937 -394.652174)
			(xy 414.110273 -394.699786) (xy 414.127548 -394.750878) (xy 414.136305 -394.804095) (xy 414.13684 -394.831062)
			(xy 414.136296 -394.858347) (xy 414.127343 -394.912176) (xy 414.109672 -394.963805) (xy 414.083764 -395.011832)
			(xy 414.050322 -395.054953) (xy 414.030668 -395.073886) (xy 414.023281 -395.08142) (xy 414.014746 -395.10069)
			(xy 414.014158 -395.111224) (xy 414.014158 -395.1859) (xy 414.014686 -395.196449) (xy 414.023223 -395.215744)
			(xy 414.030668 -395.223238) (xy 414.050314 -395.242178) (xy 414.083746 -395.285302) (xy 414.109648 -395.333328)
			(xy 414.127319 -395.384954) (xy 414.136279 -395.438779) (xy 414.13684 -395.466062) (xy 414.136392 -395.490178)
			(xy 414.129395 -395.5379) (xy 414.115545 -395.584101) (xy 414.095135 -395.627802) (xy 414.08223 -395.64818)
			(xy 414.076388 -395.65707) (xy 414.072832 -395.677136) (xy 414.093914 -395.769338) (xy 414.106106 -395.786102)
			(xy 414.114996 -395.791436) (xy 414.135788 -395.804305) (xy 414.173696 -395.835191) (xy 414.20664 -395.871323)
			(xy 414.233903 -395.911914) (xy 414.25489 -395.956078) (xy 414.269143 -396.002851) (xy 414.276351 -396.051214)
			(xy 414.276794 -396.075662) (xy 414.276375 -396.100035) (xy 414.269229 -396.148255) (xy 414.255086 -396.194905)
			(xy 414.234253 -396.238975) (xy 414.207179 -396.279512) (xy 414.174452 -396.315638) (xy 414.15589 -396.33144)
			(xy 414.147 -396.338552) (xy 414.137602 -396.35811) (xy 414.134808 -396.457424) (xy 414.143444 -396.47749)
			(xy 414.151826 -396.48511) (xy 414.170269 -396.502578) (xy 414.201618 -396.542546) (xy 414.225916 -396.587153)
			(xy 414.242494 -396.635168) (xy 414.250894 -396.685264) (xy 414.251394 -396.710662) (xy 414.25129 -396.721943)
			(xy 414.249639 -396.744445) (xy 414.248092 -396.75562) (xy 414.246822 -396.76451) (xy 414.250378 -396.782036)
			(xy 414.293812 -396.852902) (xy 414.307528 -396.864078) (xy 414.316164 -396.866872) (xy 414.338411 -396.874803)
			(xy 414.380332 -396.896555) (xy 414.418405 -396.924501) (xy 414.451723 -396.957974) (xy 414.479491 -396.996176)
			(xy 414.490662 -397.016986) (xy 414.49117 -397.018002) (xy 414.8836 -397.696944) (xy 414.896332 -397.72031)
			(xy 414.914448 -397.770338) (xy 414.923658 -397.822741) (xy 414.92424 -397.849344) (xy 414.923778 -397.873335)
			(xy 414.916266 -397.920725) (xy 414.901435 -397.966357) (xy 414.879649 -398.009107) (xy 414.851444 -398.047924)
			(xy 414.817515 -398.081852) (xy 414.778697 -398.110055) (xy 414.735946 -398.13184) (xy 414.690313 -398.146669)
			(xy 414.642923 -398.154179) (xy 414.618932 -398.154652) (xy 414.5954 -398.154223) (xy 414.548891 -398.147013)
			(xy 414.504042 -398.132742) (xy 414.461919 -398.11175) (xy 414.42352 -398.084536) (xy 414.389759 -398.051745)
			(xy 414.361436 -398.014157) (xy 414.349946 -397.993616) (xy 414.349692 -397.993108) (xy 414.349184 -397.992346)
			(xy 413.95142 -397.304006) (xy 413.939506 -397.281337) (xy 413.922568 -397.233012) (xy 413.913908 -397.182542)
			(xy 413.91332 -397.15694) (xy 413.91332 -397.156432) (xy 413.913477 -397.145083) (xy 413.915254 -397.122453)
			(xy 413.916876 -397.11122) (xy 413.918146 -397.10233) (xy 413.91459 -397.085058) (xy 413.871156 -397.013938)
			(xy 413.857186 -397.003016) (xy 413.848804 -396.999968) (xy 413.826394 -396.991957) (xy 413.784176 -396.969993)
			(xy 413.745881 -396.941741) (xy 413.712436 -396.907886) (xy 413.684653 -396.869248) (xy 413.663206 -396.826766)
			(xy 413.648614 -396.78147) (xy 413.641231 -396.734457) (xy 413.640778 -396.710662) (xy 413.641311 -396.685267)
			(xy 413.649719 -396.635179) (xy 413.666298 -396.587172) (xy 413.690591 -396.542569) (xy 413.721927 -396.502599)
			(xy 413.740346 -396.48511) (xy 413.748728 -396.47749) (xy 413.757364 -396.457424) (xy 413.75457 -396.35811)
			(xy 413.745172 -396.338552) (xy 413.736282 -396.33144) (xy 413.717751 -396.315605) (xy 413.685028 -396.279482)
			(xy 413.657956 -396.23895) (xy 413.637121 -396.194887) (xy 413.622972 -396.148245) (xy 413.615816 -396.100032)
			(xy 413.615378 -396.075662) (xy 413.615787 -396.051544) (xy 413.622795 -396.00382) (xy 413.636656 -395.957619)
			(xy 413.657078 -395.91392) (xy 413.669988 -395.893544) (xy 413.67583 -395.884654) (xy 413.679386 -395.864588)
			(xy 413.658304 -395.772386) (xy 413.646112 -395.755622) (xy 413.637222 -395.750288) (xy 413.616445 -395.737396)
			(xy 413.578536 -395.706515) (xy 413.54559 -395.670387) (xy 413.518325 -395.6298) (xy 413.497336 -395.585639)
			(xy 413.48308 -395.538869) (xy 413.475869 -395.490509) (xy 413.475424 -395.466062) (xy 413.475963 -395.438777)
			(xy 413.484915 -395.384946) (xy 413.502585 -395.333316) (xy 413.528495 -395.28529) (xy 413.56194 -395.24217)
			(xy 413.581596 -395.223238) (xy 413.588982 -395.215704) (xy 413.597515 -395.196433) (xy 413.598106 -395.1859)
			(xy 413.598106 -395.111224) (xy 413.597576 -395.100675) (xy 413.589041 -395.081379) (xy 413.581596 -395.073886)
			(xy 413.561973 -395.054923) (xy 413.528536 -395.011806) (xy 413.502628 -394.963786) (xy 413.484952 -394.912165)
			(xy 413.475987 -394.858343) (xy 413.475424 -394.831062) (xy 413.475678 -394.81887) (xy 413.475932 -394.809218)
			(xy 413.469836 -394.791184) (xy 413.411162 -394.723874) (xy 413.394398 -394.715238) (xy 413.384746 -394.714222)
			(xy 413.357838 -394.710862) (xy 413.305552 -394.696496) (xy 413.256308 -394.673795) (xy 413.211426 -394.643368)
			(xy 413.172106 -394.606029) (xy 413.139402 -394.562778) (xy 413.114189 -394.514773) (xy 413.097142 -394.463298)
			(xy 413.092392 -394.4366) (xy 413.090868 -394.427202) (xy 412.818072 -393.95527) (xy 412.810706 -393.949428)
			(xy 412.791961 -393.93359) (xy 412.75884 -393.89738) (xy 412.731427 -393.85668) (xy 412.71032 -393.812379)
			(xy 412.695983 -393.765448) (xy 412.688729 -393.716916) (xy 412.688278 -393.69238) (xy 412.171194 -393.69238)
			(xy 412.4198 -394.122402) (xy 412.427166 -394.128244) (xy 412.445961 -394.144026) (xy 412.479075 -394.180249)
			(xy 412.50648 -394.220962) (xy 412.527578 -394.265273) (xy 412.541905 -394.312213) (xy 412.549149 -394.360753)
			(xy 412.549594 -394.385292) (xy 412.54934 -394.397484) (xy 412.549086 -394.407136) (xy 412.555182 -394.42517)
			(xy 412.613856 -394.49248) (xy 412.63062 -394.501116) (xy 412.640526 -394.502132) (xy 412.667291 -394.50547)
			(xy 412.719314 -394.519696) (xy 412.76834 -394.542175) (xy 412.813069 -394.57231) (xy 412.852316 -394.609303)
			(xy 412.885041 -394.652174) (xy 412.910377 -394.699786) (xy 412.927652 -394.750878) (xy 412.936409 -394.804095)
			(xy 412.936944 -394.831062) (xy 412.936399 -394.858347) (xy 412.927445 -394.912176) (xy 412.909775 -394.963805)
			(xy 412.883868 -395.011832) (xy 412.850426 -395.054953) (xy 412.830772 -395.073886) (xy 412.823385 -395.08142)
			(xy 412.81485 -395.10069) (xy 412.814262 -395.111224) (xy 412.814262 -395.1859) (xy 412.814789 -395.19645)
			(xy 412.823327 -395.215744) (xy 412.830772 -395.223238) (xy 412.850419 -395.242177) (xy 412.88385 -395.285302)
			(xy 412.909753 -395.333328) (xy 412.927423 -395.384954) (xy 412.936383 -395.438779) (xy 412.936944 -395.466062)
			(xy 412.936495 -395.490178) (xy 412.929499 -395.5379) (xy 412.915649 -395.584101) (xy 412.895239 -395.627802)
			(xy 412.882334 -395.64818) (xy 412.876492 -395.65707) (xy 412.872936 -395.677136) (xy 412.894018 -395.769338)
			(xy 412.90621 -395.786102) (xy 412.9151 -395.791436) (xy 412.935893 -395.804303) (xy 412.9738 -395.835189)
			(xy 413.006745 -395.871322) (xy 413.034008 -395.911913) (xy 413.054994 -395.956077) (xy 413.069247 -396.002851)
			(xy 413.076455 -396.051214) (xy 413.076898 -396.075662) (xy 413.076478 -396.100035) (xy 413.069332 -396.148255)
			(xy 413.055189 -396.194904) (xy 413.034356 -396.238974) (xy 413.007283 -396.279511) (xy 412.974555 -396.315638)
			(xy 412.955994 -396.33144) (xy 412.947104 -396.338552) (xy 412.937706 -396.35811) (xy 412.934912 -396.457424)
			(xy 412.943548 -396.47749) (xy 412.95193 -396.48511) (xy 412.970374 -396.502577) (xy 413.001722 -396.542546)
			(xy 413.026021 -396.587153) (xy 413.042598 -396.635168) (xy 413.050998 -396.685264) (xy 413.051498 -396.710662)
			(xy 413.051394 -396.721943) (xy 413.049743 -396.744445) (xy 413.048196 -396.75562) (xy 413.046926 -396.76451)
			(xy 413.050482 -396.782036) (xy 413.093916 -396.852902) (xy 413.107632 -396.864078) (xy 413.116268 -396.866872)
			(xy 413.138515 -396.874802) (xy 413.180436 -396.896554) (xy 413.218509 -396.9245) (xy 413.251827 -396.957973)
			(xy 413.279595 -396.996176) (xy 413.290766 -397.016986) (xy 413.291274 -397.018002) (xy 413.683704 -397.696944)
			(xy 413.696437 -397.72031) (xy 413.714552 -397.770337) (xy 413.723762 -397.822741) (xy 413.724344 -397.849344)
			(xy 413.723878 -397.873335) (xy 413.716367 -397.920724) (xy 413.701535 -397.966356) (xy 413.679749 -398.009106)
			(xy 413.651545 -398.047923) (xy 413.617617 -398.08185) (xy 413.578799 -398.110054) (xy 413.536049 -398.131838)
			(xy 413.490417 -398.146668) (xy 413.443027 -398.154179) (xy 413.419036 -398.154652) (xy 413.395504 -398.15422)
			(xy 413.348995 -398.14701) (xy 413.304147 -398.13274) (xy 413.262023 -398.111749) (xy 413.223625 -398.084535)
			(xy 413.189863 -398.051745) (xy 413.16154 -398.014157) (xy 413.15005 -397.993616) (xy 413.149796 -397.993108)
			(xy 413.149288 -397.992346) (xy 412.751524 -397.304006) (xy 412.739611 -397.281337) (xy 412.722672 -397.233012)
			(xy 412.714012 -397.182542) (xy 412.713424 -397.15694) (xy 412.713424 -397.156432) (xy 412.713581 -397.145083)
			(xy 412.715358 -397.122453) (xy 412.71698 -397.11122) (xy 412.71825 -397.10233) (xy 412.714694 -397.085058)
			(xy 412.67126 -397.013938) (xy 412.65729 -397.003016) (xy 412.648908 -396.999968) (xy 412.626499 -396.991955)
			(xy 412.584281 -396.969991) (xy 412.545986 -396.941739) (xy 412.512541 -396.907885) (xy 412.484758 -396.869248)
			(xy 412.46331 -396.826766) (xy 412.448718 -396.781469) (xy 412.441335 -396.734457) (xy 412.440882 -396.710662)
			(xy 412.441414 -396.685267) (xy 412.449822 -396.635179) (xy 412.466401 -396.587172) (xy 412.490694 -396.542569)
			(xy 412.522031 -396.502599) (xy 412.54045 -396.48511) (xy 412.548832 -396.47749) (xy 412.557468 -396.457424)
			(xy 412.554674 -396.35811) (xy 412.545276 -396.338552) (xy 412.536386 -396.33144) (xy 412.517856 -396.315604)
			(xy 412.485133 -396.279481) (xy 412.458061 -396.23895) (xy 412.437225 -396.194887) (xy 412.423076 -396.148245)
			(xy 412.41592 -396.100032) (xy 412.415482 -396.075662) (xy 412.415891 -396.051544) (xy 412.422898 -396.00382)
			(xy 412.43676 -395.957619) (xy 412.457182 -395.91392) (xy 412.470092 -395.893544) (xy 412.475934 -395.884654)
			(xy 412.47949 -395.864588) (xy 412.458408 -395.772386) (xy 412.446216 -395.755622) (xy 412.437326 -395.750288)
			(xy 412.416527 -395.737431) (xy 412.378623 -395.70654) (xy 412.345682 -395.670404) (xy 412.318421 -395.629811)
			(xy 412.297436 -395.585647) (xy 412.283183 -395.538873) (xy 412.275973 -395.49051) (xy 412.275528 -395.466062)
			(xy 412.276066 -395.438777) (xy 412.285018 -395.384946) (xy 412.302688 -395.333316) (xy 412.328598 -395.285289)
			(xy 412.362043 -395.24217) (xy 412.3817 -395.223238) (xy 412.389087 -395.215704) (xy 412.39762 -395.196433)
			(xy 412.39821 -395.1859) (xy 412.39821 -395.111224) (xy 412.397678 -395.100675) (xy 412.389145 -395.08138)
			(xy 412.3817 -395.073886) (xy 412.362078 -395.054922) (xy 412.32864 -395.011806) (xy 412.302732 -394.963786)
			(xy 412.285056 -394.912165) (xy 412.276091 -394.858343) (xy 412.275528 -394.831062) (xy 412.275782 -394.81887)
			(xy 412.276036 -394.809218) (xy 412.26994 -394.791184) (xy 412.211266 -394.723874) (xy 412.194502 -394.715238)
			(xy 412.184596 -394.714222) (xy 412.157693 -394.710822) (xy 412.105408 -394.696464) (xy 412.056164 -394.67377)
			(xy 412.011281 -394.643349) (xy 411.97196 -394.606016) (xy 411.939255 -394.562769) (xy 411.91404 -394.514768)
			(xy 411.896992 -394.463297) (xy 411.892242 -394.4366) (xy 411.890718 -394.427202) (xy 411.617668 -393.954762)
			(xy 411.610556 -393.94892) (xy 411.591815 -393.93315) (xy 411.558763 -393.897005) (xy 411.531408 -393.856377)
			(xy 411.510351 -393.812157) (xy 411.496052 -393.765312) (xy 411.488825 -393.716869) (xy 411.488382 -393.69238)
			(xy 410.971334 -393.69238) (xy 411.219904 -394.122402) (xy 411.22727 -394.128244) (xy 411.246066 -394.144025)
			(xy 411.279179 -394.180248) (xy 411.306585 -394.220961) (xy 411.327682 -394.265273) (xy 411.342009 -394.312213)
			(xy 411.349253 -394.360753) (xy 411.349698 -394.385292) (xy 411.349444 -394.397484) (xy 411.34919 -394.407136)
			(xy 411.355286 -394.42517) (xy 411.41396 -394.49248) (xy 411.430724 -394.501116) (xy 411.44063 -394.502132)
			(xy 411.467395 -394.505467) (xy 411.519419 -394.519694) (xy 411.568444 -394.542173) (xy 411.613173 -394.572308)
			(xy 411.65242 -394.609302) (xy 411.685145 -394.652173) (xy 411.710481 -394.699785) (xy 411.727756 -394.750877)
			(xy 411.736513 -394.804095) (xy 411.737048 -394.831062) (xy 411.736502 -394.858346) (xy 411.727548 -394.912176)
			(xy 411.709878 -394.963804) (xy 411.683971 -395.011831) (xy 411.65053 -395.054953) (xy 411.630876 -395.073886)
			(xy 411.62349 -395.081421) (xy 411.614954 -395.10069) (xy 411.614366 -395.111224) (xy 411.614366 -395.1859)
			(xy 411.614892 -395.19645) (xy 411.62343 -395.215744) (xy 411.630876 -395.223238) (xy 411.650524 -395.242176)
			(xy 411.683955 -395.285301) (xy 411.709857 -395.333328) (xy 411.727527 -395.384954) (xy 411.736487 -395.438779)
			(xy 411.737048 -395.466062) (xy 411.736598 -395.490178) (xy 411.729602 -395.5379) (xy 411.715752 -395.584101)
			(xy 411.695343 -395.627802) (xy 411.682438 -395.64818) (xy 411.676596 -395.65707) (xy 411.67304 -395.677136)
			(xy 411.694122 -395.769338) (xy 411.706314 -395.786102) (xy 411.715204 -395.791436) (xy 411.735998 -395.804302)
			(xy 411.773905 -395.835188) (xy 411.806849 -395.871321) (xy 411.834112 -395.911913) (xy 411.855098 -395.956077)
			(xy 411.869351 -396.002851) (xy 411.876559 -396.051214) (xy 411.877002 -396.075662) (xy 411.87658 -396.100035)
			(xy 411.869435 -396.148255) (xy 411.855292 -396.194904) (xy 411.834459 -396.238974) (xy 411.807386 -396.279511)
			(xy 411.774659 -396.315638) (xy 411.756098 -396.33144) (xy 411.747208 -396.338552) (xy 411.73781 -396.35811)
			(xy 411.735016 -396.457424) (xy 411.743652 -396.47749) (xy 411.752034 -396.48511) (xy 411.770479 -396.502576)
			(xy 411.801827 -396.542545) (xy 411.826125 -396.587153) (xy 411.842702 -396.635167) (xy 411.851102 -396.685264)
			(xy 411.851602 -396.710662) (xy 411.851498 -396.721943) (xy 411.849847 -396.744445) (xy 411.8483 -396.75562)
			(xy 411.84703 -396.764764) (xy 411.850332 -396.782036) (xy 411.89402 -396.853156) (xy 411.907736 -396.864078)
			(xy 411.916372 -396.866872) (xy 411.944536 -396.877071) (xy 411.996482 -396.906881) (xy 412.019496 -396.926054)
			(xy 412.04098 -396.945635) (xy 412.076794 -396.991414) (xy 412.090616 -397.016986) (xy 412.091378 -397.018256)
			(xy 412.483554 -397.696944) (xy 412.496362 -397.720285) (xy 412.514588 -397.770304) (xy 412.523855 -397.822726)
			(xy 412.524448 -397.849344) (xy 412.524002 -397.873349) (xy 412.516482 -397.920767) (xy 412.501634 -397.966423)
			(xy 412.479825 -398.009194) (xy 412.451591 -398.048025) (xy 412.417628 -398.081959) (xy 412.378773 -398.11016)
			(xy 412.335984 -398.131933) (xy 412.290315 -398.146742) (xy 412.242891 -398.154222) (xy 412.218886 -398.154652)
			(xy 412.195355 -398.15418) (xy 412.148849 -398.146977) (xy 412.104001 -398.132714) (xy 412.061877 -398.11173)
			(xy 412.023478 -398.084522) (xy 411.989716 -398.051737) (xy 411.961391 -398.014154) (xy 411.9499 -397.993616)
			(xy 411.949646 -397.993108) (xy 411.949138 -397.992346) (xy 411.551628 -397.303752) (xy 411.541057 -397.283825)
			(xy 411.525253 -397.241575) (xy 411.515845 -397.197459) (xy 411.514036 -397.174974) (xy 411.513528 -397.163798)
			(xy 411.513528 -397.156432) (xy 411.513619 -397.145087) (xy 411.515274 -397.122458) (xy 411.51683 -397.11122)
			(xy 411.5181 -397.10233) (xy 411.514544 -397.085058) (xy 411.47111 -397.013938) (xy 411.457394 -397.002762)
			(xy 411.448758 -396.999968) (xy 411.426353 -396.991979) (xy 411.384183 -396.969974) (xy 411.345935 -396.941696)
			(xy 411.312536 -396.907828) (xy 411.284793 -396.86919) (xy 411.263378 -396.826717) (xy 411.248808 -396.781437)
			(xy 411.241437 -396.734445) (xy 411.240986 -396.710662) (xy 411.241516 -396.685267) (xy 411.249925 -396.635179)
			(xy 411.266504 -396.587171) (xy 411.290797 -396.542569) (xy 411.322135 -396.502599) (xy 411.340554 -396.48511)
			(xy 411.348936 -396.47749) (xy 411.357572 -396.457424) (xy 411.354778 -396.35811) (xy 411.34538 -396.338552)
			(xy 411.33649 -396.33144) (xy 411.31796 -396.315603) (xy 411.285237 -396.27948) (xy 411.258165 -396.238949)
			(xy 411.237329 -396.194887) (xy 411.22318 -396.148245) (xy 411.216024 -396.100032) (xy 411.215586 -396.075662)
			(xy 411.215994 -396.051544) (xy 411.223002 -396.00382) (xy 411.236864 -395.957619) (xy 411.257286 -395.91392)
			(xy 411.270196 -395.893544) (xy 411.276038 -395.884654) (xy 411.279594 -395.864588) (xy 411.258512 -395.772386)
			(xy 411.24632 -395.755622) (xy 411.23743 -395.750288) (xy 411.216632 -395.737429) (xy 411.178728 -395.706539)
			(xy 411.145786 -395.670403) (xy 411.118526 -395.629811) (xy 411.09754 -395.585646) (xy 411.083287 -395.538873)
			(xy 411.076077 -395.49051) (xy 411.075632 -395.466062) (xy 411.076169 -395.438777) (xy 411.08512 -395.384946)
			(xy 411.102791 -395.333316) (xy 411.128702 -395.285289) (xy 411.162147 -395.24217) (xy 411.181804 -395.223238)
			(xy 411.189191 -395.215705) (xy 411.197724 -395.196433) (xy 411.198314 -395.1859) (xy 411.198314 -395.111224)
			(xy 411.197781 -395.100675) (xy 411.189248 -395.08138) (xy 411.181804 -395.073886) (xy 411.162164 -395.05494)
			(xy 411.128733 -395.011816) (xy 411.10283 -394.963792) (xy 411.085158 -394.912168) (xy 411.076195 -394.858344)
			(xy 411.075632 -394.831062) (xy 411.075886 -394.81887) (xy 411.07614 -394.809218) (xy 411.070044 -394.791184)
			(xy 411.01137 -394.723874) (xy 410.994606 -394.715238) (xy 410.9847 -394.714222) (xy 410.957798 -394.710819)
			(xy 410.905512 -394.696461) (xy 410.856269 -394.673768) (xy 410.811386 -394.643348) (xy 410.772065 -394.606015)
			(xy 410.739359 -394.562769) (xy 410.714145 -394.514767) (xy 410.697096 -394.463297) (xy 410.692346 -394.4366)
			(xy 410.690822 -394.427202) (xy 410.418026 -393.95527) (xy 410.41066 -393.949428) (xy 410.391905 -393.933601)
			(xy 410.358787 -393.897388) (xy 410.331376 -393.856685) (xy 410.310272 -393.812382) (xy 410.295936 -393.76545)
			(xy 410.288682 -393.716916) (xy 410.288232 -393.69238) (xy 409.771438 -393.69238) (xy 410.020008 -394.122402)
			(xy 410.027374 -394.128244) (xy 410.046171 -394.144024) (xy 410.079284 -394.180247) (xy 410.106689 -394.220961)
			(xy 410.127786 -394.265273) (xy 410.142113 -394.312213) (xy 410.149357 -394.360753) (xy 410.149802 -394.385292)
			(xy 410.149548 -394.397484) (xy 410.149294 -394.407136) (xy 410.15539 -394.42517) (xy 410.214064 -394.49248)
			(xy 410.230828 -394.501116) (xy 410.24048 -394.502132) (xy 410.26724 -394.505508) (xy 410.319262 -394.519727)
			(xy 410.368288 -394.542199) (xy 410.413018 -394.572329) (xy 410.452266 -394.609317) (xy 410.484992 -394.652184)
			(xy 410.510329 -394.699792) (xy 410.527605 -394.750881) (xy 410.536362 -394.804097) (xy 410.536898 -394.831062)
			(xy 410.536368 -394.858347) (xy 410.527413 -394.912178) (xy 410.50974 -394.963808) (xy 410.483829 -395.011834)
			(xy 410.450383 -395.054954) (xy 410.430726 -395.073886) (xy 410.423332 -395.081414) (xy 410.414802 -395.100689)
			(xy 410.414216 -395.111224) (xy 410.414216 -395.1859) (xy 410.414727 -395.196452) (xy 410.423275 -395.215747)
			(xy 410.430726 -395.223238) (xy 410.450364 -395.242185) (xy 410.483799 -395.285307) (xy 410.509704 -395.333331)
			(xy 410.527376 -395.384955) (xy 410.536337 -395.438779) (xy 410.536898 -395.466062) (xy 410.536456 -395.490179)
			(xy 410.529459 -395.537901) (xy 410.515607 -395.584102) (xy 410.495194 -395.627803) (xy 410.482288 -395.64818)
			(xy 410.476446 -395.65707) (xy 410.47289 -395.677136) (xy 410.493972 -395.769338) (xy 410.506164 -395.786102)
			(xy 410.515054 -395.791436) (xy 410.53586 -395.804284) (xy 410.573764 -395.835175) (xy 410.606706 -395.871312)
			(xy 410.633966 -395.911907) (xy 410.654951 -395.956073) (xy 410.669202 -396.002849) (xy 410.676409 -396.051213)
			(xy 410.676852 -396.075662) (xy 410.676448 -396.100036) (xy 410.669301 -396.148257) (xy 410.655157 -396.194908)
			(xy 410.63432 -396.238978) (xy 410.607243 -396.279514) (xy 410.574512 -396.315639) (xy 410.555948 -396.33144)
			(xy 410.547058 -396.338552) (xy 410.53766 -396.35811) (xy 410.534866 -396.457424) (xy 410.543502 -396.47749)
			(xy 410.551884 -396.48511) (xy 410.570339 -396.502566) (xy 410.601683 -396.542539) (xy 410.625979 -396.587149)
			(xy 410.642554 -396.635166) (xy 410.650953 -396.685263) (xy 410.651452 -396.710662) (xy 410.651349 -396.721943)
			(xy 410.649697 -396.744445) (xy 410.64815 -396.75562) (xy 410.64688 -396.76451) (xy 410.650436 -396.782036)
			(xy 410.69387 -396.852902) (xy 410.707586 -396.864078) (xy 410.716222 -396.866872) (xy 410.738479 -396.874776)
			(xy 410.780399 -396.896536) (xy 410.81847 -396.924488) (xy 410.851785 -396.957967) (xy 410.879551 -396.996174)
			(xy 410.89072 -397.016986) (xy 410.891228 -397.018002) (xy 411.283658 -397.696944) (xy 411.296466 -397.720285)
			(xy 411.314692 -397.770304) (xy 411.323959 -397.822726) (xy 411.324552 -397.849344) (xy 411.324102 -397.873349)
			(xy 411.316582 -397.920766) (xy 411.301734 -397.966422) (xy 411.279925 -398.009193) (xy 411.251692 -398.048023)
			(xy 411.21773 -398.081957) (xy 411.178876 -398.110158) (xy 411.136087 -398.131932) (xy 411.090419 -398.146741)
			(xy 411.042995 -398.154222) (xy 411.01899 -398.154652) (xy 410.995459 -398.154177) (xy 410.948953 -398.146975)
			(xy 410.904105 -398.132712) (xy 410.861982 -398.111728) (xy 410.823582 -398.084521) (xy 410.78982 -398.051737)
			(xy 410.761495 -398.014154) (xy 410.750004 -397.993616) (xy 410.74975 -397.993108) (xy 410.749242 -397.992346)
			(xy 410.351478 -397.304006) (xy 410.339603 -397.281328) (xy 410.322752 -397.232996) (xy 410.314178 -397.182533)
			(xy 410.313632 -397.15694) (xy 410.313632 -397.156432) (xy 410.313723 -397.145087) (xy 410.315378 -397.122458)
			(xy 410.316934 -397.11122) (xy 410.318204 -397.10233) (xy 410.314648 -397.085058) (xy 410.271214 -397.013938)
			(xy 410.257244 -397.003016) (xy 410.248862 -396.999968) (xy 410.226464 -396.991924) (xy 410.184245 -396.969967)
			(xy 410.145948 -396.941722) (xy 410.112501 -396.907872) (xy 410.084715 -396.869239) (xy 410.063266 -396.82676)
			(xy 410.048673 -396.781466) (xy 410.041289 -396.734456) (xy 410.040836 -396.710662) (xy 410.04135 -396.685266)
			(xy 410.04976 -396.635176) (xy 410.066343 -396.587168) (xy 410.09064 -396.542565) (xy 410.121982 -396.502598)
			(xy 410.140404 -396.48511) (xy 410.148786 -396.47749) (xy 410.157422 -396.457424) (xy 410.154628 -396.35811)
			(xy 410.14523 -396.338552) (xy 410.13634 -396.33144) (xy 410.1178 -396.315615) (xy 410.08508 -396.279488)
			(xy 410.058011 -396.238954) (xy 410.037177 -396.19489) (xy 410.023029 -396.148246) (xy 410.015874 -396.100033)
			(xy 410.015436 -396.075662) (xy 410.015852 -396.051545) (xy 410.022859 -396.003821) (xy 410.036718 -395.95762)
			(xy 410.057137 -395.913921) (xy 410.070046 -395.893544) (xy 410.075888 -395.884654) (xy 410.079444 -395.864588)
			(xy 410.058362 -395.772386) (xy 410.04617 -395.755622) (xy 410.03728 -395.750288) (xy 410.016493 -395.737411)
			(xy 409.978587 -395.706526) (xy 409.945643 -395.670394) (xy 409.91838 -395.629805) (xy 409.897392 -395.585643)
			(xy 409.883137 -395.538871) (xy 409.875927 -395.49051) (xy 409.875482 -395.466062) (xy 409.876034 -395.438778)
			(xy 409.884985 -395.384948) (xy 409.902653 -395.333319) (xy 409.928559 -395.285292) (xy 409.962 -395.242171)
			(xy 409.981654 -395.223238) (xy 409.989034 -395.215698) (xy 409.997572 -395.196432) (xy 409.998164 -395.1859)
			(xy 409.998164 -395.111224) (xy 409.997646 -395.100673) (xy 409.989104 -395.081377) (xy 409.981654 -395.073886)
			(xy 409.962024 -395.054931) (xy 409.928589 -395.011811) (xy 409.902683 -394.963789) (xy 409.885009 -394.912167)
			(xy 409.876045 -394.858344) (xy 409.875482 -394.831062) (xy 409.875736 -394.81887) (xy 409.87599 -394.809218)
			(xy 409.869894 -394.791184) (xy 409.81122 -394.723874) (xy 409.794456 -394.715238) (xy 409.784804 -394.714222)
			(xy 409.757902 -394.710816) (xy 409.705617 -394.696458) (xy 409.656373 -394.673766) (xy 409.61149 -394.643346)
			(xy 409.572169 -394.606014) (xy 409.539463 -394.562768) (xy 409.514249 -394.514767) (xy 409.4972 -394.463296)
			(xy 409.49245 -394.4366) (xy 409.490926 -394.427202) (xy 409.21813 -393.95527) (xy 409.210764 -393.949428)
			(xy 409.19201 -393.9336) (xy 409.158892 -393.897388) (xy 409.13148 -393.856684) (xy 409.110376 -393.812382)
			(xy 409.09604 -393.76545) (xy 409.088786 -393.716916) (xy 409.088336 -393.69238) (xy 408.571288 -393.69238)
			(xy 408.819858 -394.122402) (xy 408.827224 -394.128244) (xy 408.84601 -394.144036) (xy 408.879127 -394.180255)
			(xy 408.906534 -394.220966) (xy 408.927634 -394.265276) (xy 408.941962 -394.312214) (xy 408.949207 -394.360754)
			(xy 408.949652 -394.385292) (xy 408.949398 -394.397484) (xy 408.949144 -394.407136) (xy 408.95524 -394.42517)
			(xy 409.013914 -394.49248) (xy 409.030678 -394.501116) (xy 409.040584 -394.502132) (xy 409.067344 -394.505504)
			(xy 409.119367 -394.519724) (xy 409.168393 -394.542197) (xy 409.213122 -394.572327) (xy 409.25237 -394.609316)
			(xy 409.285096 -394.652183) (xy 409.310433 -394.699792) (xy 409.327709 -394.750881) (xy 409.336466 -394.804097)
			(xy 409.337002 -394.831062) (xy 409.336576 -394.855264) (xy 409.329503 -394.903149) (xy 409.315517 -394.949488)
			(xy 409.294917 -394.99329) (xy 409.281884 -395.013688) (xy 409.277097 -395.021645) (xy 409.273062 -395.039756)
			(xy 409.27401 -395.048994) (xy 409.278328 -395.079982) (xy 409.280001 -395.08928) (xy 409.289288 -395.105722)
			(xy 409.296362 -395.111986) (xy 409.31845 -395.130668) (xy 409.358222 -395.17268) (xy 409.392384 -395.219368)
			(xy 409.420391 -395.269988) (xy 409.441799 -395.323733) (xy 409.456264 -395.379746) (xy 409.463557 -395.437136)
			(xy 409.464002 -395.466062) (xy 409.463416 -395.499384) (xy 409.453752 -395.565322) (xy 409.434625 -395.629161)
			(xy 409.421076 -395.65961) (xy 409.416829 -395.670075) (xy 409.416943 -395.692634) (xy 409.426676 -395.712985)
			(xy 409.435046 -395.72057) (xy 409.457265 -395.739276) (xy 409.497332 -395.781324) (xy 409.531757 -395.828104)
			(xy 409.559986 -395.878864) (xy 409.581566 -395.932787) (xy 409.59615 -395.989008) (xy 409.603503 -396.046621)
			(xy 409.603956 -396.075662) (xy 409.603478 -396.104667) (xy 409.596167 -396.162214) (xy 409.581645 -396.218376)
			(xy 409.560145 -396.272255) (xy 409.532011 -396.322985) (xy 409.497694 -396.369755) (xy 409.457743 -396.411815)
			(xy 409.435554 -396.4305) (xy 409.428442 -396.436088) (xy 409.419298 -396.451328) (xy 409.404058 -396.534132)
			(xy 409.406852 -396.551404) (xy 409.411424 -396.559532) (xy 409.423998 -396.582719) (xy 409.441873 -396.63234)
			(xy 409.450974 -396.684291) (xy 409.451556 -396.710662) (xy 409.451453 -396.721943) (xy 409.449801 -396.744445)
			(xy 409.448254 -396.75562) (xy 409.446984 -396.76451) (xy 409.45054 -396.782036) (xy 409.493974 -396.852902)
			(xy 409.50769 -396.864078) (xy 409.516326 -396.866872) (xy 409.538566 -396.874821) (xy 409.580488 -396.896568)
			(xy 409.618563 -396.924509) (xy 409.651882 -396.957978) (xy 409.679652 -396.996178) (xy 409.690824 -397.016986)
			(xy 409.691332 -397.018002) (xy 410.083762 -397.696944) (xy 410.09657 -397.720285) (xy 410.114796 -397.770304)
			(xy 410.124063 -397.822726) (xy 410.124656 -397.849344) (xy 410.124202 -397.873349) (xy 410.116682 -397.920765)
			(xy 410.101835 -397.966421) (xy 410.080026 -398.009191) (xy 410.051793 -398.048022) (xy 410.017831 -398.081956)
			(xy 409.978978 -398.110157) (xy 409.93619 -398.131931) (xy 409.890522 -398.14674) (xy 409.843099 -398.154221)
			(xy 409.819094 -398.154652) (xy 409.795563 -398.154173) (xy 409.749057 -398.146972) (xy 409.704209 -398.13271)
			(xy 409.662086 -398.111727) (xy 409.623687 -398.08452) (xy 409.589924 -398.051736) (xy 409.561599 -398.014154)
			(xy 409.550108 -397.993616) (xy 409.549854 -397.993108) (xy 409.549346 -397.992346) (xy 409.151582 -397.304006)
			(xy 409.139708 -397.281328) (xy 409.122856 -397.232996) (xy 409.114282 -397.182533) (xy 409.113736 -397.15694)
			(xy 409.113736 -397.156432) (xy 409.113827 -397.145087) (xy 409.115482 -397.122458) (xy 409.117038 -397.11122)
			(xy 409.118308 -397.10233) (xy 409.114752 -397.085058) (xy 409.071318 -397.013938) (xy 409.057348 -397.003016)
			(xy 409.048966 -396.999968) (xy 409.026569 -396.991922) (xy 408.98435 -396.969966) (xy 408.946052 -396.94172)
			(xy 408.912605 -396.907871) (xy 408.88482 -396.869238) (xy 408.86337 -396.82676) (xy 408.848777 -396.781466)
			(xy 408.841393 -396.734455) (xy 408.84094 -396.710662) (xy 408.841501 -396.684289) (xy 408.850585 -396.63233)
			(xy 408.868476 -396.58271) (xy 408.881072 -396.559532) (xy 408.885644 -396.551404) (xy 408.888438 -396.534132)
			(xy 408.873198 -396.451328) (xy 408.864054 -396.436088) (xy 408.856942 -396.4305) (xy 408.83478 -396.411784)
			(xy 408.794831 -396.369725) (xy 408.760511 -396.32296) (xy 408.732371 -396.272235) (xy 408.71086 -396.218364)
			(xy 408.696322 -396.162208) (xy 408.688991 -396.104666) (xy 408.68854 -396.075662) (xy 408.68914 -396.042341)
			(xy 408.698799 -395.976403) (xy 408.717921 -395.912563) (xy 408.731466 -395.882114) (xy 408.73571 -395.871646)
			(xy 408.735605 -395.849087) (xy 408.725869 -395.828736) (xy 408.717496 -395.821154) (xy 408.695228 -395.802504)
			(xy 408.655166 -395.760444) (xy 408.620748 -395.713654) (xy 408.592526 -395.662885) (xy 408.570953 -395.608953)
			(xy 408.556378 -395.552725) (xy 408.549034 -395.495105) (xy 408.548586 -395.466062) (xy 408.549025 -395.437135)
			(xy 408.556309 -395.379742) (xy 408.570769 -395.323724) (xy 408.592175 -395.269976) (xy 408.620184 -395.219355)
			(xy 408.65435 -395.172667) (xy 408.694129 -395.130659) (xy 408.716226 -395.111986) (xy 408.723192 -395.105633)
			(xy 408.732454 -395.089234) (xy 408.73426 -395.079982) (xy 408.738578 -395.048994) (xy 408.739477 -395.039757)
			(xy 408.735455 -395.021658) (xy 408.730704 -395.013688) (xy 408.717717 -394.993265) (xy 408.697136 -394.949463)
			(xy 408.683149 -394.903133) (xy 408.676053 -394.85526) (xy 408.675586 -394.831062) (xy 408.67584 -394.81887)
			(xy 408.676094 -394.809218) (xy 408.669998 -394.791184) (xy 408.611324 -394.723874) (xy 408.59456 -394.715238)
			(xy 408.584654 -394.714222) (xy 408.557747 -394.710855) (xy 408.505461 -394.69649) (xy 408.456217 -394.673791)
			(xy 408.411335 -394.643365) (xy 408.372015 -394.606027) (xy 408.33931 -394.562777) (xy 408.314097 -394.514772)
			(xy 408.29705 -394.463298) (xy 408.2923 -394.4366) (xy 408.290776 -394.427202) (xy 408.01798 -393.95527)
			(xy 408.010614 -393.949428) (xy 407.99187 -393.933588) (xy 407.95875 -393.897379) (xy 407.931336 -393.856679)
			(xy 407.910229 -393.812379) (xy 407.895891 -393.765448) (xy 407.888637 -393.716916) (xy 407.888186 -393.69238)
			(xy 407.371392 -393.69238) (xy 407.619962 -394.122402) (xy 407.627328 -394.128244) (xy 407.646115 -394.144035)
			(xy 407.679231 -394.180255) (xy 407.706639 -394.220966) (xy 407.727738 -394.265276) (xy 407.742067 -394.312214)
			(xy 407.749311 -394.360754) (xy 407.749756 -394.385292) (xy 407.749502 -394.397484) (xy 407.749248 -394.407136)
			(xy 407.755344 -394.42517) (xy 407.814018 -394.49248) (xy 407.830782 -394.501116) (xy 407.840434 -394.502132)
			(xy 407.8672 -394.505464) (xy 407.919223 -394.519691) (xy 407.968249 -394.542171) (xy 408.012978 -394.572307)
			(xy 408.052225 -394.609301) (xy 408.084949 -394.652172) (xy 408.110285 -394.699785) (xy 408.12756 -394.750877)
			(xy 408.136317 -394.804095) (xy 408.136852 -394.831062) (xy 408.136342 -394.857049) (xy 408.128212 -394.908384)
			(xy 408.112151 -394.957814) (xy 408.088555 -395.004124) (xy 408.058005 -395.046172) (xy 408.021254 -395.082923)
			(xy 407.979206 -395.113473) (xy 407.932896 -395.137069) (xy 407.883466 -395.15313) (xy 407.832131 -395.16126)
			(xy 407.780157 -395.16126) (xy 407.728822 -395.15313) (xy 407.679392 -395.137069) (xy 407.633082 -395.113473)
			(xy 407.591034 -395.082923) (xy 407.554283 -395.046172) (xy 407.523733 -395.004124) (xy 407.500137 -394.957814)
			(xy 407.484076 -394.908384) (xy 407.475946 -394.857049) (xy 407.475436 -394.831062) (xy 407.47569 -394.81887)
			(xy 407.475944 -394.809218) (xy 407.469848 -394.791184) (xy 407.411174 -394.723874) (xy 407.39441 -394.715238)
			(xy 407.384758 -394.714222) (xy 407.357851 -394.710852) (xy 407.305565 -394.696488) (xy 407.256322 -394.673789)
			(xy 407.211439 -394.643364) (xy 407.172119 -394.606026) (xy 407.139415 -394.562776) (xy 407.114201 -394.514771)
			(xy 407.097154 -394.463298) (xy 407.092404 -394.4366) (xy 407.09088 -394.427202) (xy 406.818084 -393.95527)
			(xy 406.810718 -393.949428) (xy 406.791975 -393.933587) (xy 406.758854 -393.897379) (xy 406.73144 -393.856679)
			(xy 406.710333 -393.812378) (xy 406.695995 -393.765448) (xy 406.688741 -393.716916) (xy 406.68829 -393.69238)
			(xy 406.171206 -393.69238) (xy 406.419812 -394.122402) (xy 406.427178 -394.128244) (xy 406.445955 -394.144047)
			(xy 406.479073 -394.180263) (xy 406.506484 -394.220971) (xy 406.527585 -394.265279) (xy 406.541915 -394.312216)
			(xy 406.54916 -394.360754) (xy 406.549606 -394.385292) (xy 406.549352 -394.397484) (xy 406.549098 -394.407136)
			(xy 406.555194 -394.42517) (xy 406.613868 -394.49248) (xy 406.630632 -394.501116) (xy 406.640538 -394.502132)
			(xy 406.667304 -394.50546) (xy 406.719328 -394.519689) (xy 406.768353 -394.542169) (xy 406.813082 -394.572305)
			(xy 406.852329 -394.609299) (xy 406.885054 -394.652171) (xy 406.910389 -394.699784) (xy 406.927664 -394.750877)
			(xy 406.936421 -394.804095) (xy 406.936956 -394.831062) (xy 406.936407 -394.858346) (xy 406.927454 -394.912175)
			(xy 406.909784 -394.963804) (xy 406.883878 -395.011831) (xy 406.850438 -395.054952) (xy 406.830784 -395.073886)
			(xy 406.823384 -395.081409) (xy 406.814859 -395.100688) (xy 406.814274 -395.111224) (xy 406.814274 -395.1859)
			(xy 406.814797 -395.19645) (xy 406.823337 -395.215745) (xy 406.830784 -395.223238) (xy 406.850433 -395.242175)
			(xy 406.883864 -395.285301) (xy 406.909765 -395.333327) (xy 406.927435 -395.384953) (xy 406.936395 -395.438779)
			(xy 406.936956 -395.466062) (xy 406.936505 -395.490178) (xy 406.929509 -395.5379) (xy 406.91566 -395.584101)
			(xy 406.89525 -395.627802) (xy 406.882346 -395.64818) (xy 406.876504 -395.65707) (xy 406.872948 -395.677136)
			(xy 406.89403 -395.769338) (xy 406.906222 -395.786102) (xy 406.915112 -395.791436) (xy 406.935908 -395.804299)
			(xy 406.973814 -395.835186) (xy 407.006758 -395.87132) (xy 407.034021 -395.911912) (xy 407.055007 -395.956076)
			(xy 407.069259 -396.00285) (xy 407.076467 -396.051213) (xy 407.07691 -396.075662) (xy 407.076485 -396.100035)
			(xy 407.06934 -396.148254) (xy 407.055198 -396.194904) (xy 407.034365 -396.238974) (xy 407.007293 -396.279511)
			(xy 406.974567 -396.315637) (xy 406.956006 -396.33144) (xy 406.947116 -396.338552) (xy 406.937718 -396.35811)
			(xy 406.934924 -396.457424) (xy 406.94356 -396.47749) (xy 406.951942 -396.48511) (xy 406.970388 -396.502575)
			(xy 407.001736 -396.542544) (xy 407.026033 -396.587152) (xy 407.042611 -396.635167) (xy 407.05101 -396.685264)
			(xy 407.05151 -396.710662) (xy 407.64079 -396.710662) (xy 407.641312 -396.685407) (xy 407.649625 -396.635585)
			(xy 407.666026 -396.587811) (xy 407.690067 -396.543388) (xy 407.721091 -396.503528) (xy 407.758253 -396.469318)
			(xy 407.800539 -396.441692) (xy 407.846795 -396.421402) (xy 407.89576 -396.409002) (xy 407.946098 -396.404831)
			(xy 407.996436 -396.409002) (xy 408.045401 -396.421402) (xy 408.091657 -396.441692) (xy 408.133943 -396.469318)
			(xy 408.171105 -396.503528) (xy 408.202129 -396.543388) (xy 408.22617 -396.587811) (xy 408.242571 -396.635585)
			(xy 408.250884 -396.685407) (xy 408.251406 -396.710662) (xy 408.251302 -396.721943) (xy 408.249651 -396.744445)
			(xy 408.248104 -396.75562) (xy 408.246834 -396.76451) (xy 408.25039 -396.782036) (xy 408.293824 -396.852902)
			(xy 408.30754 -396.864078) (xy 408.316176 -396.866872) (xy 408.338425 -396.874798) (xy 408.380345 -396.896551)
			(xy 408.418418 -396.924498) (xy 408.451736 -396.957972) (xy 408.479504 -396.996176) (xy 408.490674 -397.016986)
			(xy 408.491182 -397.018002) (xy 408.883612 -397.696944) (xy 408.896345 -397.720309) (xy 408.91446 -397.770337)
			(xy 408.92367 -397.822741) (xy 408.924252 -397.849344) (xy 408.923778 -397.873334) (xy 408.916267 -397.920723)
			(xy 408.901436 -397.966354) (xy 408.879651 -398.009104) (xy 408.851448 -398.04792) (xy 408.81752 -398.081848)
			(xy 408.778704 -398.110051) (xy 408.735954 -398.131836) (xy 408.690323 -398.146667) (xy 408.642934 -398.154178)
			(xy 408.618944 -398.154652) (xy 408.595412 -398.154214) (xy 408.548904 -398.147005) (xy 408.504055 -398.132736)
			(xy 408.461932 -398.111746) (xy 408.423533 -398.084533) (xy 408.389772 -398.051743) (xy 408.361449 -398.014156)
			(xy 408.349958 -397.993616) (xy 408.349704 -397.993108) (xy 408.349196 -397.992346) (xy 407.951432 -397.304006)
			(xy 407.939519 -397.281336) (xy 407.92258 -397.233012) (xy 407.91392 -397.182542) (xy 407.913332 -397.15694)
			(xy 407.913332 -397.156432) (xy 407.913489 -397.145083) (xy 407.915266 -397.122453) (xy 407.916888 -397.11122)
			(xy 407.918158 -397.10233) (xy 407.914602 -397.085058) (xy 407.871168 -397.013938) (xy 407.857198 -397.003016)
			(xy 407.848816 -396.999968) (xy 407.826408 -396.99195) (xy 407.784191 -396.969988) (xy 407.745895 -396.941737)
			(xy 407.71245 -396.907883) (xy 407.684666 -396.869246) (xy 407.663218 -396.826765) (xy 407.648626 -396.781469)
			(xy 407.641243 -396.734456) (xy 407.64079 -396.710662) (xy 407.05151 -396.710662) (xy 407.051406 -396.721943)
			(xy 407.049755 -396.744445) (xy 407.048208 -396.75562) (xy 407.046938 -396.76451) (xy 407.050494 -396.782036)
			(xy 407.093928 -396.852902) (xy 407.107644 -396.864078) (xy 407.11628 -396.866872) (xy 407.13853 -396.874796)
			(xy 407.18045 -396.89655) (xy 407.218523 -396.924497) (xy 407.25184 -396.957972) (xy 407.279608 -396.996176)
			(xy 407.290778 -397.016986) (xy 407.291286 -397.018002) (xy 407.683716 -397.696944) (xy 407.69645 -397.720309)
			(xy 407.714565 -397.770337) (xy 407.723774 -397.822741) (xy 407.724356 -397.849344) (xy 407.723878 -397.873334)
			(xy 407.716367 -397.920723) (xy 407.701536 -397.966353) (xy 407.679752 -398.009103) (xy 407.651549 -398.047919)
			(xy 407.617622 -398.081846) (xy 407.578806 -398.11005) (xy 407.536057 -398.131835) (xy 407.490427 -398.146666)
			(xy 407.443038 -398.154178) (xy 407.419048 -398.154652) (xy 407.395516 -398.154211) (xy 407.349008 -398.147002)
			(xy 407.30416 -398.132734) (xy 407.262036 -398.111744) (xy 407.223637 -398.084532) (xy 407.189876 -398.051743)
			(xy 407.161553 -398.014156) (xy 407.150062 -397.993616) (xy 407.149808 -397.993108) (xy 407.1493 -397.992346)
			(xy 406.751536 -397.304006) (xy 406.739623 -397.281336) (xy 406.722684 -397.233012) (xy 406.714024 -397.182542)
			(xy 406.713436 -397.15694) (xy 406.713436 -397.156432) (xy 406.713593 -397.145083) (xy 406.71537 -397.122453)
			(xy 406.716992 -397.11122) (xy 406.718262 -397.10233) (xy 406.714706 -397.085058) (xy 406.671272 -397.013938)
			(xy 406.657302 -397.003016) (xy 406.64892 -396.999968) (xy 406.626513 -396.991948) (xy 406.584295 -396.969986)
			(xy 406.545999 -396.941735) (xy 406.512554 -396.907882) (xy 406.484771 -396.869246) (xy 406.463322 -396.826765)
			(xy 406.44873 -396.781469) (xy 406.441347 -396.734456) (xy 406.440894 -396.710662) (xy 406.441422 -396.685267)
			(xy 406.449831 -396.635178) (xy 406.46641 -396.587171) (xy 406.490704 -396.542568) (xy 406.522042 -396.502599)
			(xy 406.540462 -396.48511) (xy 406.548844 -396.47749) (xy 406.55748 -396.457424) (xy 406.554686 -396.35811)
			(xy 406.545288 -396.338552) (xy 406.536398 -396.33144) (xy 406.51787 -396.315601) (xy 406.485147 -396.279479)
			(xy 406.458074 -396.238949) (xy 406.437238 -396.194886) (xy 406.423088 -396.148245) (xy 406.415932 -396.100032)
			(xy 406.415494 -396.075662) (xy 406.415901 -396.051544) (xy 406.422909 -396.00382) (xy 406.436771 -395.957619)
			(xy 406.457193 -395.91392) (xy 406.470104 -395.893544) (xy 406.475946 -395.884654) (xy 406.479502 -395.864588)
			(xy 406.45842 -395.772386) (xy 406.446228 -395.755622) (xy 406.437338 -395.750288) (xy 406.416541 -395.737427)
			(xy 406.378637 -395.706537) (xy 406.345696 -395.670402) (xy 406.318434 -395.62981) (xy 406.297448 -395.585646)
			(xy 406.283195 -395.538873) (xy 406.275985 -395.49051) (xy 406.27554 -395.466062) (xy 406.276106 -395.438778)
			(xy 406.285055 -395.38495) (xy 406.302721 -395.333322) (xy 406.328623 -395.285295) (xy 406.36206 -395.242172)
			(xy 406.381712 -395.223238) (xy 406.389101 -395.215706) (xy 406.397632 -395.196434) (xy 406.398222 -395.1859)
			(xy 406.398222 -395.111224) (xy 406.397687 -395.100675) (xy 406.389155 -395.08138) (xy 406.381712 -395.073886)
			(xy 406.362074 -395.054939) (xy 406.328642 -395.011816) (xy 406.302738 -394.963791) (xy 406.285066 -394.912168)
			(xy 406.276103 -394.858344) (xy 406.27554 -394.831062) (xy 406.275794 -394.81887) (xy 406.276048 -394.809218)
			(xy 406.269952 -394.791184) (xy 406.211278 -394.723874) (xy 406.194514 -394.715238) (xy 406.184608 -394.714222)
			(xy 406.157707 -394.710812) (xy 406.105421 -394.696456) (xy 406.056178 -394.673764) (xy 406.011295 -394.643345)
			(xy 405.971973 -394.606013) (xy 405.939268 -394.562767) (xy 405.914053 -394.514767) (xy 405.897004 -394.463296)
			(xy 405.892254 -394.4366) (xy 405.89073 -394.427202) (xy 405.61768 -393.954762) (xy 405.610568 -393.94892)
			(xy 405.59183 -393.933147) (xy 405.558777 -393.897003) (xy 405.531422 -393.856376) (xy 405.510364 -393.812156)
			(xy 405.496064 -393.765311) (xy 405.488837 -393.716869) (xy 405.488394 -393.69238) (xy 404.971346 -393.69238)
			(xy 405.219916 -394.122402) (xy 405.227282 -394.128244) (xy 405.24606 -394.144046) (xy 405.279178 -394.180262)
			(xy 405.306588 -394.22097) (xy 405.327689 -394.265278) (xy 405.342019 -394.312216) (xy 405.349264 -394.360754)
			(xy 405.34971 -394.385292) (xy 405.349456 -394.397484) (xy 405.349202 -394.407136) (xy 405.355298 -394.42517)
			(xy 405.413972 -394.49248) (xy 405.430736 -394.501116) (xy 405.440642 -394.502132) (xy 405.467409 -394.505457)
			(xy 405.519432 -394.519686) (xy 405.568458 -394.542167) (xy 405.613187 -394.572304) (xy 405.652433 -394.609298)
			(xy 405.685158 -394.65217) (xy 405.710493 -394.699783) (xy 405.727768 -394.750876) (xy 405.736525 -394.804095)
			(xy 405.73706 -394.831062) (xy 405.73651 -394.858346) (xy 405.727557 -394.912175) (xy 405.709887 -394.963804)
			(xy 405.683981 -395.011831) (xy 405.650541 -395.054952) (xy 405.630888 -395.073886) (xy 405.623489 -395.081409)
			(xy 405.614963 -395.100688) (xy 405.614378 -395.111224) (xy 405.614378 -395.1859) (xy 405.6149 -395.19645)
			(xy 405.623441 -395.215745) (xy 405.630888 -395.223238) (xy 405.650538 -395.242174) (xy 405.683968 -395.2853)
			(xy 405.70987 -395.333327) (xy 405.727539 -395.384953) (xy 405.736499 -395.438779) (xy 405.73706 -395.466062)
			(xy 405.736608 -395.490178) (xy 405.729612 -395.5379) (xy 405.715763 -395.584101) (xy 405.695354 -395.627802)
			(xy 405.68245 -395.64818) (xy 405.676608 -395.65707) (xy 405.673052 -395.677136) (xy 405.694134 -395.769338)
			(xy 405.706326 -395.786102) (xy 405.715216 -395.791436) (xy 405.736013 -395.804298) (xy 405.773919 -395.835185)
			(xy 405.806863 -395.871319) (xy 405.834125 -395.911911) (xy 405.855111 -395.956076) (xy 405.869363 -396.00285)
			(xy 405.876571 -396.051213) (xy 405.877014 -396.075662) (xy 405.876588 -396.100035) (xy 405.869442 -396.148254)
			(xy 405.855301 -396.194903) (xy 405.834468 -396.238973) (xy 405.807396 -396.27951) (xy 405.774671 -396.315637)
			(xy 405.75611 -396.33144) (xy 405.74722 -396.338552) (xy 405.737822 -396.35811) (xy 405.735028 -396.457424)
			(xy 405.743664 -396.47749) (xy 405.752046 -396.48511) (xy 405.770493 -396.502574) (xy 405.801841 -396.542544)
			(xy 405.826138 -396.587152) (xy 405.842715 -396.635167) (xy 405.851115 -396.685264) (xy 405.851614 -396.710662)
			(xy 405.85151 -396.721943) (xy 405.849859 -396.744445) (xy 405.848312 -396.75562) (xy 405.847042 -396.764764)
			(xy 405.850344 -396.782036) (xy 405.894032 -396.853156) (xy 405.907748 -396.864078) (xy 405.916384 -396.866872)
			(xy 405.944549 -396.877069) (xy 405.996495 -396.90688) (xy 406.019508 -396.926054) (xy 406.040994 -396.945634)
			(xy 406.076806 -396.991414) (xy 406.090628 -397.016986) (xy 406.09139 -397.018256) (xy 406.483566 -397.696944)
			(xy 406.496375 -397.720285) (xy 406.5146 -397.770303) (xy 406.523867 -397.822726) (xy 406.52446 -397.849344)
			(xy 406.524101 -397.873353) (xy 406.516579 -397.92078) (xy 406.501726 -397.966444) (xy 406.479909 -398.00922)
			(xy 406.451665 -398.048055) (xy 406.417691 -398.08199) (xy 406.378825 -398.11019) (xy 406.336023 -398.131958)
			(xy 406.290342 -398.146759) (xy 406.242908 -398.154228) (xy 406.218898 -398.154652) (xy 406.195367 -398.15417)
			(xy 406.148861 -398.146969) (xy 406.104014 -398.132708) (xy 406.06189 -398.111725) (xy 406.023491 -398.084519)
			(xy 405.989728 -398.051736) (xy 405.961404 -398.014154) (xy 405.949912 -397.993616) (xy 405.949658 -397.993108)
			(xy 405.94915 -397.992346) (xy 405.55164 -397.303752) (xy 405.54107 -397.283824) (xy 405.525265 -397.241575)
			(xy 405.515857 -397.197459) (xy 405.514048 -397.174974) (xy 405.51354 -397.163798) (xy 405.51354 -397.156432)
			(xy 405.513631 -397.145087) (xy 405.515286 -397.122458) (xy 405.516842 -397.11122) (xy 405.518112 -397.10233)
			(xy 405.514556 -397.085058) (xy 405.471122 -397.013938) (xy 405.457406 -397.002762) (xy 405.44877 -396.999968)
			(xy 405.426368 -396.991972) (xy 405.384197 -396.969969) (xy 405.345949 -396.941692) (xy 405.312549 -396.907825)
			(xy 405.284806 -396.869188) (xy 405.26339 -396.826716) (xy 405.24882 -396.781436) (xy 405.241449 -396.734445)
			(xy 405.240998 -396.710662) (xy 405.241524 -396.685267) (xy 405.249934 -396.635178) (xy 405.266514 -396.587171)
			(xy 405.290808 -396.542568) (xy 405.322146 -396.502599) (xy 405.340566 -396.48511) (xy 405.348948 -396.47749)
			(xy 405.357584 -396.457424) (xy 405.35479 -396.35811) (xy 405.345392 -396.338552) (xy 405.336502 -396.33144)
			(xy 405.317975 -396.315601) (xy 405.285251 -396.279479) (xy 405.258178 -396.238948) (xy 405.237342 -396.194886)
			(xy 405.223192 -396.148244) (xy 405.216036 -396.100032) (xy 405.215598 -396.075662) (xy 405.216004 -396.051544)
			(xy 405.223012 -396.00382) (xy 405.236874 -395.957619) (xy 405.257297 -395.91392) (xy 405.270208 -395.893544)
			(xy 405.27605 -395.884654) (xy 405.279606 -395.864588) (xy 405.258524 -395.772386) (xy 405.246332 -395.755622)
			(xy 405.237442 -395.750288) (xy 405.216646 -395.737425) (xy 405.178742 -395.706536) (xy 405.1458 -395.670401)
			(xy 405.118539 -395.629809) (xy 405.097552 -395.585645) (xy 405.083299 -395.538872) (xy 405.076089 -395.49051)
			(xy 405.075644 -395.466062) (xy 405.076209 -395.438778) (xy 405.085158 -395.38495) (xy 405.102824 -395.333322)
			(xy 405.128727 -395.285294) (xy 405.162164 -395.242172) (xy 405.181816 -395.223238) (xy 405.189205 -395.215706)
			(xy 405.197736 -395.196434) (xy 405.198326 -395.1859) (xy 405.198326 -395.111224) (xy 405.19779 -395.100675)
			(xy 405.189259 -395.08138) (xy 405.181816 -395.073886) (xy 405.162179 -395.054938) (xy 405.128746 -395.011815)
			(xy 405.102843 -394.963791) (xy 405.08517 -394.912168) (xy 405.076207 -394.858344) (xy 405.075644 -394.831062)
			(xy 405.075898 -394.81887) (xy 405.076152 -394.809218) (xy 405.070056 -394.791184) (xy 405.011382 -394.723874)
			(xy 404.994618 -394.715238) (xy 404.984712 -394.714222) (xy 404.957811 -394.710809) (xy 404.905526 -394.696453)
			(xy 404.856282 -394.673762) (xy 404.811399 -394.643343) (xy 404.772078 -394.606012) (xy 404.739372 -394.562766)
			(xy 404.714157 -394.514766) (xy 404.697108 -394.463296) (xy 404.692358 -394.4366) (xy 404.690834 -394.427202)
			(xy 404.418038 -393.95527) (xy 404.410672 -393.949428) (xy 404.391919 -393.933598) (xy 404.358801 -393.897386)
			(xy 404.331389 -393.856684) (xy 404.310284 -393.812381) (xy 404.295948 -393.76545) (xy 404.288694 -393.716916)
			(xy 404.288244 -393.69238) (xy 403.77145 -393.69238) (xy 404.02002 -394.122402) (xy 404.027386 -394.128244)
			(xy 404.046164 -394.144045) (xy 404.079283 -394.180262) (xy 404.106692 -394.22097) (xy 404.127793 -394.265278)
			(xy 404.142123 -394.312216) (xy 404.149368 -394.360754) (xy 404.149814 -394.385292) (xy 404.14956 -394.397484)
			(xy 404.149306 -394.407136) (xy 404.155402 -394.42517) (xy 404.214076 -394.49248) (xy 404.23084 -394.501116)
			(xy 404.240492 -394.502132) (xy 404.267253 -394.505498) (xy 404.319276 -394.519719) (xy 404.368302 -394.542193)
			(xy 404.413031 -394.572324) (xy 404.452279 -394.609314) (xy 404.485005 -394.652181) (xy 404.510341 -394.699791)
			(xy 404.527617 -394.75088) (xy 404.536374 -394.804096) (xy 404.53691 -394.831062) (xy 404.536376 -394.858347)
			(xy 404.527421 -394.912178) (xy 404.509749 -394.963807) (xy 404.483839 -395.011834) (xy 404.450394 -395.054954)
			(xy 404.430738 -395.073886) (xy 404.423346 -395.081416) (xy 404.414815 -395.100689) (xy 404.414228 -395.111224)
			(xy 404.414228 -395.1859) (xy 404.414735 -395.196452) (xy 404.423285 -395.215748) (xy 404.430738 -395.223238)
			(xy 404.450379 -395.242183) (xy 404.483812 -395.285306) (xy 404.509716 -395.33333) (xy 404.527388 -395.384955)
			(xy 404.536349 -395.438779) (xy 404.53691 -395.466062) (xy 404.536466 -395.490178) (xy 404.529469 -395.537901)
			(xy 404.515618 -395.584102) (xy 404.495206 -395.627803) (xy 404.4823 -395.64818) (xy 404.476458 -395.65707)
			(xy 404.472902 -395.677136) (xy 404.493984 -395.769338) (xy 404.506176 -395.786102) (xy 404.515066 -395.791436)
			(xy 404.535874 -395.804279) (xy 404.573778 -395.835172) (xy 404.606719 -395.87131) (xy 404.633979 -395.911905)
			(xy 404.654963 -395.956072) (xy 404.669214 -396.002848) (xy 404.676421 -396.051213) (xy 404.676864 -396.075662)
			(xy 404.676456 -396.100036) (xy 404.669309 -396.148257) (xy 404.655165 -396.194907) (xy 404.63433 -396.238977)
			(xy 404.607254 -396.279514) (xy 404.574523 -396.315639) (xy 404.55596 -396.33144) (xy 404.54707 -396.338552)
			(xy 404.537672 -396.35811) (xy 404.534878 -396.457424) (xy 404.543514 -396.47749) (xy 404.551896 -396.48511)
			(xy 404.570334 -396.502584) (xy 404.601684 -396.54255) (xy 404.625984 -396.587155) (xy 404.642564 -396.635169)
			(xy 404.650964 -396.685264) (xy 404.651464 -396.710662) (xy 404.651361 -396.721943) (xy 404.649709 -396.744445)
			(xy 404.648162 -396.75562) (xy 404.646892 -396.76451) (xy 404.650448 -396.782036) (xy 404.693882 -396.852902)
			(xy 404.707598 -396.864078) (xy 404.716234 -396.866872) (xy 404.738475 -396.874817) (xy 404.780397 -396.896565)
			(xy 404.818471 -396.924507) (xy 404.851791 -396.957977) (xy 404.879561 -396.996177) (xy 404.890732 -397.016986)
			(xy 404.89124 -397.018002) (xy 405.28367 -397.696944) (xy 405.296479 -397.720285) (xy 405.314704 -397.770303)
			(xy 405.323971 -397.822726) (xy 405.324564 -397.849344) (xy 405.324201 -397.873353) (xy 405.316679 -397.920779)
			(xy 405.301826 -397.966443) (xy 405.280009 -398.009219) (xy 405.251766 -398.048053) (xy 405.217793 -398.081989)
			(xy 405.178927 -398.110188) (xy 405.136126 -398.131957) (xy 405.090446 -398.146759) (xy 405.043012 -398.154228)
			(xy 405.019002 -398.154652) (xy 404.995472 -398.154167) (xy 404.948966 -398.146967) (xy 404.904118 -398.132706)
			(xy 404.861995 -398.111724) (xy 404.823595 -398.084518) (xy 404.789832 -398.051735) (xy 404.761508 -398.014154)
			(xy 404.750016 -397.993616) (xy 404.749762 -397.993108) (xy 404.749254 -397.992346) (xy 404.35149 -397.304006)
			(xy 404.339616 -397.281328) (xy 404.322764 -397.232995) (xy 404.31419 -397.182533) (xy 404.313644 -397.15694)
			(xy 404.313644 -397.156432) (xy 404.313735 -397.145087) (xy 404.31539 -397.122458) (xy 404.316946 -397.11122)
			(xy 404.318216 -397.10233) (xy 404.31466 -397.085058) (xy 404.271226 -397.013938) (xy 404.257256 -397.003016)
			(xy 404.248874 -396.999968) (xy 404.226478 -396.991917) (xy 404.184259 -396.969962) (xy 404.145961 -396.941718)
			(xy 404.112514 -396.907869) (xy 404.084728 -396.869237) (xy 404.063278 -396.826759) (xy 404.048685 -396.781465)
			(xy 404.041301 -396.734455) (xy 404.040848 -396.710662) (xy 404.041358 -396.685266) (xy 404.049769 -396.635176)
			(xy 404.066352 -396.587167) (xy 404.09065 -396.542565) (xy 404.121993 -396.502597) (xy 404.140416 -396.48511)
			(xy 404.148798 -396.47749) (xy 404.157434 -396.457424) (xy 404.15464 -396.35811) (xy 404.145242 -396.338552)
			(xy 404.136352 -396.33144) (xy 404.117815 -396.315612) (xy 404.085094 -396.279486) (xy 404.058024 -396.238953)
			(xy 404.037189 -396.194889) (xy 404.023041 -396.148246) (xy 404.015886 -396.100033) (xy 404.015448 -396.075662)
			(xy 404.015862 -396.051544) (xy 404.022869 -396.003821) (xy 404.036729 -395.95762) (xy 404.057149 -395.91392)
			(xy 404.070058 -395.893544) (xy 404.0759 -395.884654) (xy 404.079456 -395.864588) (xy 404.058374 -395.772386)
			(xy 404.046182 -395.755622) (xy 404.037292 -395.750288) (xy 404.016508 -395.737407) (xy 403.978601 -395.706523)
			(xy 403.945656 -395.670392) (xy 403.918393 -395.629803) (xy 403.897405 -395.585642) (xy 403.88315 -395.53887)
			(xy 403.875939 -395.49051) (xy 403.875494 -395.466062) (xy 403.876043 -395.438777) (xy 403.884993 -395.384948)
			(xy 403.902662 -395.333318) (xy 403.928569 -395.285291) (xy 403.962011 -395.242171) (xy 403.981666 -395.223238)
			(xy 403.989048 -395.2157) (xy 403.997585 -395.196433) (xy 403.998176 -395.1859) (xy 403.998176 -395.111224)
			(xy 403.997655 -395.100673) (xy 403.989115 -395.081377) (xy 403.981666 -395.073886) (xy 403.962038 -395.054929)
			(xy 403.928602 -395.011809) (xy 403.902696 -394.963788) (xy 403.885021 -394.912166) (xy 403.876057 -394.858344)
			(xy 403.875494 -394.831062) (xy 403.875748 -394.81887) (xy 403.876002 -394.809218) (xy 403.869906 -394.791184)
			(xy 403.811232 -394.723874) (xy 403.794468 -394.715238) (xy 403.784816 -394.714222) (xy 403.757915 -394.710806)
			(xy 403.70563 -394.696451) (xy 403.656387 -394.67376) (xy 403.611503 -394.643342) (xy 403.572182 -394.60601)
			(xy 403.539476 -394.562766) (xy 403.514261 -394.514766) (xy 403.497212 -394.463296) (xy 403.492462 -394.4366)
			(xy 403.490938 -394.427202) (xy 403.218142 -393.95527) (xy 403.210776 -393.949428) (xy 403.192024 -393.933597)
			(xy 403.158906 -393.897386) (xy 403.131494 -393.856683) (xy 403.110388 -393.812381) (xy 403.096052 -393.76545)
			(xy 403.088798 -393.716916) (xy 403.088348 -393.69238) (xy 400.761078 -393.69238) (xy 400.780592 -393.702323)
			(xy 400.82264 -393.732873) (xy 400.859391 -393.769624) (xy 400.889941 -393.811672) (xy 400.913537 -393.857982)
			(xy 400.929598 -393.907412) (xy 400.937728 -393.958747) (xy 400.938238 -393.984734) (xy 400.937728 -394.010721)
			(xy 400.929598 -394.062056) (xy 400.913537 -394.111486) (xy 400.889941 -394.157796) (xy 400.859391 -394.199844)
			(xy 400.82264 -394.236595) (xy 400.793826 -394.25753) (xy 402.46173 -394.25753) (xy 402.46224 -394.231543)
			(xy 402.47037 -394.180208) (xy 402.486431 -394.130778) (xy 402.510027 -394.084468) (xy 402.540577 -394.04242)
			(xy 402.577328 -394.005669) (xy 402.619376 -393.975119) (xy 402.665686 -393.951523) (xy 402.715116 -393.935462)
			(xy 402.766451 -393.927332) (xy 402.818425 -393.927332) (xy 402.86976 -393.935462) (xy 402.91919 -393.951523)
			(xy 402.9655 -393.975119) (xy 403.007548 -394.005669) (xy 403.044299 -394.04242) (xy 403.074849 -394.084468)
			(xy 403.098445 -394.130778) (xy 403.114506 -394.180208) (xy 403.122636 -394.231543) (xy 403.123146 -394.25753)
			(xy 403.122763 -394.281206) (xy 403.11603 -394.328077) (xy 403.102665 -394.373504) (xy 403.093174 -394.395198)
			(xy 403.088856 -394.404596) (xy 403.088094 -394.424662) (xy 403.120352 -394.511022) (xy 403.134068 -394.525754)
			(xy 403.143466 -394.530072) (xy 403.167838 -394.541755) (xy 403.212708 -394.571884) (xy 403.252085 -394.608904)
			(xy 403.284922 -394.65183) (xy 403.310348 -394.699522) (xy 403.327686 -394.750712) (xy 403.336475 -394.804039)
			(xy 403.337014 -394.831062) (xy 403.336478 -394.858347) (xy 403.327524 -394.912177) (xy 403.309852 -394.963807)
			(xy 403.283942 -395.011833) (xy 403.250498 -395.054954) (xy 403.230842 -395.073886) (xy 403.223451 -395.081417)
			(xy 403.214919 -395.10069) (xy 403.214332 -395.111224) (xy 403.214332 -395.1859) (xy 403.214838 -395.196453)
			(xy 403.223388 -395.215748) (xy 403.230842 -395.223238) (xy 403.250483 -395.242182) (xy 403.283917 -395.285305)
			(xy 403.309821 -395.33333) (xy 403.327492 -395.384955) (xy 403.336453 -395.438779) (xy 403.337014 -395.466062)
			(xy 403.33657 -395.490178) (xy 403.329573 -395.537901) (xy 403.315722 -395.584102) (xy 403.29531 -395.627803)
			(xy 403.282404 -395.64818) (xy 403.276562 -395.65707) (xy 403.273006 -395.677136) (xy 403.294088 -395.769338)
			(xy 403.30628 -395.786102) (xy 403.31517 -395.791436) (xy 403.335979 -395.804278) (xy 403.373883 -395.835171)
			(xy 403.406824 -395.871309) (xy 403.434083 -395.911905) (xy 403.455067 -395.956072) (xy 403.469318 -396.002848)
			(xy 403.476525 -396.051213) (xy 403.476968 -396.075662) (xy 403.476559 -396.100036) (xy 403.469412 -396.148256)
			(xy 403.455268 -396.194907) (xy 403.434433 -396.238977) (xy 403.407357 -396.279513) (xy 403.374627 -396.315639)
			(xy 403.356064 -396.33144) (xy 403.347174 -396.338552) (xy 403.337776 -396.35811) (xy 403.334982 -396.457424)
			(xy 403.343618 -396.47749) (xy 403.352 -396.48511) (xy 403.370439 -396.502583) (xy 403.401789 -396.542549)
			(xy 403.426089 -396.587155) (xy 403.442668 -396.635168) (xy 403.451068 -396.685264) (xy 403.451568 -396.710662)
			(xy 403.451464 -396.721943) (xy 403.449813 -396.744445) (xy 403.448266 -396.75562) (xy 403.446996 -396.76451)
			(xy 403.450552 -396.782036) (xy 403.493986 -396.852902) (xy 403.507702 -396.864078) (xy 403.516338 -396.866872)
			(xy 403.53858 -396.874816) (xy 403.580502 -396.896564) (xy 403.618576 -396.924506) (xy 403.651895 -396.957977)
			(xy 403.679665 -396.996177) (xy 403.690836 -397.016986) (xy 403.691344 -397.018002) (xy 404.083774 -397.696944)
			(xy 404.096583 -397.720284) (xy 404.114808 -397.770303) (xy 404.124075 -397.822726) (xy 404.124668 -397.849344)
			(xy 404.124301 -397.873353) (xy 404.116779 -397.920778) (xy 404.101926 -397.966442) (xy 404.08011 -398.009218)
			(xy 404.051867 -398.048052) (xy 404.017895 -398.081987) (xy 403.979029 -398.110187) (xy 403.936229 -398.131956)
			(xy 403.890549 -398.146758) (xy 403.843116 -398.154228) (xy 403.819106 -398.154652) (xy 403.795576 -398.154164)
			(xy 403.74907 -398.146964) (xy 403.704223 -398.132704) (xy 403.662099 -398.111722) (xy 403.6237 -398.084517)
			(xy 403.589937 -398.051735) (xy 403.561612 -398.014154) (xy 403.55012 -397.993616) (xy 403.549866 -397.993108)
			(xy 403.549358 -397.992346) (xy 403.151594 -397.304006) (xy 403.139721 -397.281328) (xy 403.122868 -397.232995)
			(xy 403.114294 -397.182532) (xy 403.113748 -397.15694) (xy 403.113748 -397.156432) (xy 403.11384 -397.145087)
			(xy 403.115494 -397.122458) (xy 403.11705 -397.11122) (xy 403.11832 -397.10233) (xy 403.114764 -397.085058)
			(xy 403.07133 -397.013938) (xy 403.05736 -397.003016) (xy 403.048978 -396.999968) (xy 403.026583 -396.991915)
			(xy 402.984364 -396.96996) (xy 402.946066 -396.941716) (xy 402.912618 -396.907868) (xy 402.884833 -396.869236)
			(xy 402.863383 -396.826759) (xy 402.848789 -396.781465) (xy 402.841405 -396.734455) (xy 402.840952 -396.710662)
			(xy 402.841461 -396.685266) (xy 402.849872 -396.635176) (xy 402.866455 -396.587167) (xy 402.890753 -396.542564)
			(xy 402.922097 -396.502597) (xy 402.94052 -396.48511) (xy 402.948902 -396.47749) (xy 402.957538 -396.457424)
			(xy 402.954744 -396.35811) (xy 402.945346 -396.338552) (xy 402.936456 -396.33144) (xy 402.91792 -396.315611)
			(xy 402.885198 -396.279486) (xy 402.858128 -396.238953) (xy 402.837294 -396.194889) (xy 402.823146 -396.148246)
			(xy 402.81599 -396.100033) (xy 402.815552 -396.075662) (xy 402.815965 -396.051544) (xy 402.822973 -396.003821)
			(xy 402.836833 -395.95762) (xy 402.857253 -395.91392) (xy 402.870162 -395.893544) (xy 402.876004 -395.884654)
			(xy 402.87956 -395.864588) (xy 402.858478 -395.772386) (xy 402.846286 -395.755622) (xy 402.837396 -395.750288)
			(xy 402.816613 -395.737406) (xy 402.778706 -395.706522) (xy 402.745761 -395.670391) (xy 402.718497 -395.629803)
			(xy 402.697509 -395.585641) (xy 402.683254 -395.53887) (xy 402.676043 -395.49051) (xy 402.675598 -395.466062)
			(xy 402.676145 -395.438777) (xy 402.685096 -395.384947) (xy 402.702765 -395.333318) (xy 402.728673 -395.285291)
			(xy 402.762115 -395.242171) (xy 402.78177 -395.223238) (xy 402.789153 -395.2157) (xy 402.797689 -395.196433)
			(xy 402.79828 -395.1859) (xy 402.79828 -395.111224) (xy 402.797757 -395.100673) (xy 402.789218 -395.081378)
			(xy 402.78177 -395.073886) (xy 402.762143 -395.054928) (xy 402.728707 -395.011809) (xy 402.7028 -394.963788)
			(xy 402.685125 -394.912166) (xy 402.676161 -394.858344) (xy 402.675598 -394.831062) (xy 402.675983 -394.807386)
			(xy 402.682716 -394.760515) (xy 402.69608 -394.715089) (xy 402.70557 -394.693394) (xy 402.709888 -394.683996)
			(xy 402.71065 -394.66393) (xy 402.678392 -394.57757) (xy 402.664676 -394.562838) (xy 402.655278 -394.55852)
			(xy 402.630912 -394.546823) (xy 402.586041 -394.516698) (xy 402.546662 -394.479682) (xy 402.513822 -394.436758)
			(xy 402.488395 -394.389068) (xy 402.471057 -394.337879) (xy 402.462269 -394.284553) (xy 402.46173 -394.25753)
			(xy 400.793826 -394.25753) (xy 400.780592 -394.267145) (xy 400.734282 -394.290741) (xy 400.684852 -394.306802)
			(xy 400.633517 -394.314932) (xy 400.581543 -394.314932) (xy 400.530208 -394.306802) (xy 400.480778 -394.290741)
			(xy 400.434468 -394.267145) (xy 400.39242 -394.236595) (xy 400.355669 -394.199844) (xy 400.325119 -394.157796)
			(xy 400.301523 -394.111486) (xy 400.285462 -394.062056) (xy 400.277332 -394.010721) (xy 400.071889 -394.010721)
			(xy 400.066517 -394.047222) (xy 400.050449 -394.100629) (xy 400.026777 -394.151126) (xy 399.996004 -394.197639)
			(xy 399.958787 -394.239176) (xy 399.915919 -394.274851) (xy 399.868313 -394.303905) (xy 399.816984 -394.325717)
			(xy 399.763027 -394.339823) (xy 399.70759 -394.345923) (xy 399.651856 -394.343886) (xy 399.597013 -394.333756)
			(xy 399.544229 -394.315749) (xy 399.494629 -394.290248) (xy 399.449271 -394.257797) (xy 399.409122 -394.219088)
			(xy 399.375036 -394.174945) (xy 399.34774 -394.12631) (xy 399.327817 -394.074219) (xy 399.315691 -394.019782)
			(xy 399.31162 -393.96416) (xy 397.72844 -393.96416) (xy 397.72844 -394.55725) (xy 397.728904 -394.567126)
			(xy 397.736349 -394.585421) (xy 397.742918 -394.59281) (xy 397.761211 -394.612307) (xy 397.792719 -394.655496)
			(xy 397.81789 -394.702662) (xy 397.836229 -394.752879) (xy 397.847379 -394.805165) (xy 397.851121 -394.858496)
			(xy 397.850212 -394.871448) (xy 400.378676 -394.871448) (xy 400.379186 -394.845461) (xy 400.387316 -394.794126)
			(xy 400.403377 -394.744696) (xy 400.426973 -394.698386) (xy 400.457523 -394.656338) (xy 400.494274 -394.619587)
			(xy 400.536322 -394.589037) (xy 400.582632 -394.565441) (xy 400.632062 -394.54938) (xy 400.683397 -394.54125)
			(xy 400.735371 -394.54125) (xy 400.786706 -394.54938) (xy 400.836136 -394.565441) (xy 400.882446 -394.589037)
			(xy 400.924494 -394.619587) (xy 400.961245 -394.656338) (xy 400.991795 -394.698386) (xy 401.015391 -394.744696)
			(xy 401.031452 -394.794126) (xy 401.039582 -394.845461) (xy 401.040092 -394.871448) (xy 401.039556 -394.898777)
			(xy 401.030561 -394.952691) (xy 401.012823 -395.004392) (xy 400.986826 -395.052473) (xy 400.970496 -395.074394)
			(xy 400.964908 -395.08176) (xy 400.95932 -395.098524) (xy 400.962876 -395.182598) (xy 400.969734 -395.198854)
			(xy 400.97583 -395.205712) (xy 400.992214 -395.22411) (xy 401.019865 -395.264883) (xy 401.041166 -395.309305)
			(xy 401.055647 -395.356393) (xy 401.062988 -395.405108) (xy 401.06346 -395.42974) (xy 401.06295 -395.455727)
			(xy 401.05482 -395.507062) (xy 401.038759 -395.556492) (xy 401.015163 -395.602802) (xy 400.984613 -395.64485)
			(xy 400.947862 -395.681601) (xy 400.905814 -395.712151) (xy 400.859504 -395.735747) (xy 400.810074 -395.751808)
			(xy 400.758739 -395.759938) (xy 400.706765 -395.759938) (xy 400.65543 -395.751808) (xy 400.606 -395.735747)
			(xy 400.55969 -395.712151) (xy 400.517642 -395.681601) (xy 400.480891 -395.64485) (xy 400.450341 -395.602802)
			(xy 400.426745 -395.556492) (xy 400.410684 -395.507062) (xy 400.402554 -395.455727) (xy 400.402044 -395.42974)
			(xy 400.40264 -395.402413) (xy 400.411619 -395.348503) (xy 400.429339 -395.296802) (xy 400.455318 -395.248718)
			(xy 400.47164 -395.226794) (xy 400.477228 -395.219428) (xy 400.482816 -395.202664) (xy 400.47926 -395.11859)
			(xy 400.472402 -395.102334) (xy 400.466306 -395.095476) (xy 400.44997 -395.077037) (xy 400.422311 -395.036276)
			(xy 400.401 -394.991865) (xy 400.386508 -394.944785) (xy 400.379154 -394.896077) (xy 400.378676 -394.871448)
			(xy 397.850212 -394.871448) (xy 397.84738 -394.911826) (xy 397.836232 -394.964112) (xy 397.817893 -395.01433)
			(xy 397.792724 -395.061496) (xy 397.761216 -395.104687) (xy 397.742918 -395.124178) (xy 397.736343 -395.131562)
			(xy 397.728906 -395.149861) (xy 397.72844 -395.159738) (xy 397.72844 -396.168118) (xy 397.728012 -396.178185)
			(xy 397.720286 -396.196779) (xy 397.713454 -396.204186) (xy 397.57731 -396.34033) (xy 397.569476 -396.349)
			(xy 397.561946 -396.371095) (xy 397.562832 -396.382748) (xy 397.574516 -396.474188) (xy 397.587216 -396.493746)
			(xy 397.597376 -396.499588) (xy 397.618077 -396.512261) (xy 397.656391 -396.542059) (xy 397.690613 -396.576481)
			(xy 397.720186 -396.614969) (xy 397.732758 -396.635732) (xy 397.737584 -396.643606) (xy 397.7513 -396.654782)
			(xy 397.830802 -396.682722) (xy 397.848582 -396.682468) (xy 397.857218 -396.679166) (xy 397.886561 -396.668312)
			(xy 397.947234 -396.653046) (xy 398.009324 -396.645348) (xy 398.040606 -396.644876) (xy 398.072568 -396.645378)
			(xy 398.135987 -396.653391) (xy 398.197902 -396.669289) (xy 398.224131 -396.679674) (xy 399.436588 -396.679674)
			(xy 399.440659 -396.624052) (xy 399.452785 -396.569615) (xy 399.472708 -396.517524) (xy 399.500004 -396.468889)
			(xy 399.53409 -396.424746) (xy 399.574239 -396.386037) (xy 399.619597 -396.353586) (xy 399.669197 -396.328085)
			(xy 399.721981 -396.310078) (xy 399.776824 -396.299948) (xy 399.832558 -396.297911) (xy 399.887995 -396.304011)
			(xy 399.941952 -396.318117) (xy 399.993281 -396.339929) (xy 400.040887 -396.368983) (xy 400.083755 -396.404658)
			(xy 400.120972 -396.446195) (xy 400.151745 -396.492708) (xy 400.175417 -396.543205) (xy 400.191485 -396.596612)
			(xy 400.199605 -396.651788) (xy 400.200114 -396.679674) (xy 400.199667 -396.704137) (xy 400.402554 -396.704137)
			(xy 400.402554 -396.652163) (xy 400.410684 -396.600828) (xy 400.426745 -396.551398) (xy 400.450341 -396.505088)
			(xy 400.480891 -396.46304) (xy 400.517642 -396.426289) (xy 400.55969 -396.395739) (xy 400.606 -396.372143)
			(xy 400.65543 -396.356082) (xy 400.706765 -396.347952) (xy 400.758739 -396.347952) (xy 400.810074 -396.356082)
			(xy 400.859504 -396.372143) (xy 400.905814 -396.395739) (xy 400.947862 -396.426289) (xy 400.984613 -396.46304)
			(xy 401.015163 -396.505088) (xy 401.038759 -396.551398) (xy 401.05482 -396.600828) (xy 401.06295 -396.652163)
			(xy 401.06346 -396.67815) (xy 401.06295 -396.704137) (xy 401.05482 -396.755472) (xy 401.038759 -396.804902)
			(xy 401.015163 -396.851212) (xy 400.984613 -396.89326) (xy 400.947862 -396.930011) (xy 400.905814 -396.960561)
			(xy 400.859504 -396.984157) (xy 400.810074 -397.000218) (xy 400.758739 -397.008348) (xy 400.706765 -397.008348)
			(xy 400.65543 -397.000218) (xy 400.606 -396.984157) (xy 400.55969 -396.960561) (xy 400.517642 -396.930011)
			(xy 400.480891 -396.89326) (xy 400.450341 -396.851212) (xy 400.426745 -396.804902) (xy 400.410684 -396.755472)
			(xy 400.402554 -396.704137) (xy 400.199667 -396.704137) (xy 400.199605 -396.70756) (xy 400.191485 -396.762736)
			(xy 400.175417 -396.816143) (xy 400.151745 -396.86664) (xy 400.120972 -396.913153) (xy 400.083755 -396.95469)
			(xy 400.040887 -396.990365) (xy 399.993281 -397.019419) (xy 399.941952 -397.041231) (xy 399.887995 -397.055337)
			(xy 399.832558 -397.061437) (xy 399.776824 -397.0594) (xy 399.721981 -397.04927) (xy 399.669197 -397.031263)
			(xy 399.619597 -397.005762) (xy 399.574239 -396.973311) (xy 399.53409 -396.934602) (xy 399.500004 -396.890459)
			(xy 399.472708 -396.841824) (xy 399.452785 -396.789733) (xy 399.440659 -396.735296) (xy 399.436588 -396.679674)
			(xy 398.224131 -396.679674) (xy 398.257337 -396.692821) (xy 398.313353 -396.723617) (xy 398.365068 -396.76119)
			(xy 398.411666 -396.804949) (xy 398.452413 -396.854204) (xy 398.486664 -396.908176) (xy 398.513881 -396.966016)
			(xy 398.533635 -397.026811) (xy 398.545613 -397.089603) (xy 398.549627 -397.1534) (xy 398.545613 -397.217197)
			(xy 398.533635 -397.279989) (xy 398.513881 -397.340784) (xy 398.486664 -397.398624) (xy 398.452413 -397.452596)
			(xy 398.411666 -397.501851) (xy 398.365068 -397.54561) (xy 398.313353 -397.583183) (xy 398.257337 -397.613979)
			(xy 398.197902 -397.637511) (xy 398.135987 -397.653409) (xy 398.072568 -397.661422) (xy 398.040606 -397.661892)
			(xy 398.007216 -397.66136) (xy 397.941012 -397.652609) (xy 397.876522 -397.635272) (xy 397.814855 -397.609644)
			(xy 397.757072 -397.576169) (xy 397.704166 -397.53542) (xy 397.657046 -397.488099) (xy 397.616524 -397.435019)
			(xy 397.583295 -397.377093) (xy 397.557932 -397.315317) (xy 397.548862 -397.283178) (xy 397.546576 -397.274034)
			(xy 397.536416 -397.25981) (xy 397.467074 -397.21155) (xy 397.450056 -397.206978) (xy 397.440912 -397.207994)
			(xy 397.403574 -397.209772) (xy 397.370554 -397.208248) (xy 397.3576 -397.207232) (xy 397.334232 -397.217392)
			(xy 397.265652 -397.304514) (xy 397.261334 -397.32966) (xy 397.265398 -397.341852) (xy 397.274671 -397.371344)
			(xy 397.284632 -397.432354) (xy 397.28521 -397.463264) (xy 397.284749 -397.490518) (xy 397.276997 -397.544471)
			(xy 397.261645 -397.596771) (xy 397.239006 -397.646355) (xy 397.209541 -397.692211) (xy 397.17385 -397.733408)
			(xy 397.132659 -397.769106) (xy 397.086807 -397.798578) (xy 397.037227 -397.821224) (xy 396.984929 -397.836584)
			(xy 396.930977 -397.844345) (xy 396.87647 -397.844348) (xy 396.822517 -397.836594) (xy 396.770217 -397.821241)
			(xy 396.720634 -397.7986) (xy 396.674778 -397.769134) (xy 396.633583 -397.733441) (xy 396.597887 -397.692249)
			(xy 396.568416 -397.646396) (xy 396.545771 -397.596815) (xy 396.530413 -397.544516) (xy 396.522654 -397.490564)
			(xy 396.522653 -397.436057) (xy 396.530408 -397.382105) (xy 396.545764 -397.329805) (xy 396.568406 -397.280223)
			(xy 396.597874 -397.234368) (xy 396.633568 -397.193174) (xy 396.674761 -397.157479) (xy 396.720616 -397.12801)
			(xy 396.770197 -397.105367) (xy 396.822496 -397.09001) (xy 396.876448 -397.082253) (xy 396.903702 -397.081756)
			(xy 396.936722 -397.08328) (xy 396.949676 -397.084296) (xy 396.973044 -397.074136) (xy 397.041624 -396.987014)
			(xy 397.045942 -396.961868) (xy 397.041878 -396.949676) (xy 397.034025 -396.924814) (xy 397.024346 -396.873581)
			(xy 397.022574 -396.847568) (xy 397.022066 -396.837408) (xy 397.013938 -396.819882) (xy 396.947644 -396.757906)
			(xy 396.92961 -396.751048) (xy 396.91945 -396.751048) (xy 396.91056 -396.751048) (xy 396.878049 -396.75059)
			(xy 396.813435 -396.743308) (xy 396.750042 -396.728839) (xy 396.688667 -396.707365) (xy 396.630082 -396.679156)
			(xy 396.575022 -396.644567) (xy 396.52418 -396.604033) (xy 396.500858 -396.581376) (xy 396.415514 -396.496286)
			(xy 396.408174 -396.489464) (xy 396.389711 -396.481713) (xy 396.3797 -396.4813) (xy 395.996922 -396.4813)
			(xy 395.986858 -396.481738) (xy 395.968274 -396.489472) (xy 395.960854 -396.496286) (xy 395.85392 -396.60322)
			(xy 395.847613 -396.610161) (xy 395.84005 -396.627305) (xy 395.839145 -396.646022) (xy 395.841728 -396.655036)
			(xy 395.875002 -396.755112) (xy 395.896846 -396.7734) (xy 395.911324 -396.775432) (xy 395.938249 -396.779754)
			(xy 395.99058 -396.795087) (xy 396.040194 -396.817716) (xy 396.086079 -396.847181) (xy 396.127301 -396.88288)
			(xy 396.163018 -396.924086) (xy 396.192503 -396.969958) (xy 396.215154 -397.019562) (xy 396.23051 -397.071886)
			(xy 396.238258 -397.125864) (xy 396.23873 -397.15313) (xy 396.238242 -397.18038) (xy 396.230482 -397.234326)
			(xy 396.215125 -397.286618) (xy 396.192482 -397.336193) (xy 396.163016 -397.382042) (xy 396.127324 -397.42323)
			(xy 396.086135 -397.45892) (xy 396.040286 -397.488386) (xy 395.990711 -397.511028) (xy 395.938418 -397.526384)
			(xy 395.884472 -397.534143) (xy 395.857222 -397.534638) (xy 395.829854 -397.534161) (xy 395.775682 -397.526326)
			(xy 395.723187 -397.510828) (xy 395.673445 -397.487986) (xy 395.627479 -397.458268) (xy 395.606524 -397.440658)
			(xy 395.599412 -397.434562) (xy 395.582394 -397.428212) (xy 395.49705 -397.428212) (xy 395.480032 -397.434562)
			(xy 395.47292 -397.440658) (xy 395.45199 -397.458303) (xy 395.406025 -397.488035) (xy 395.356278 -397.510883)
			(xy 395.303774 -397.526378) (xy 395.249593 -397.5342) (xy 395.222222 -397.534638) (xy 395.196875 -397.534225)
			(xy 395.146628 -397.527516) (xy 395.097711 -397.514215) (xy 395.050985 -397.494554) (xy 395.028928 -397.48206)
			(xy 395.013942 -397.47317) (xy 394.979652 -397.477488) (xy 394.278866 -398.178274) (xy 394.272807 -398.184891)
			(xy 394.265331 -398.201188) (xy 394.263891 -398.219061) (xy 394.265912 -398.227804) (xy 394.293852 -398.32661)
			(xy 394.31341 -398.34566) (xy 394.327126 -398.348962) (xy 394.354536 -398.356055) (xy 394.407041 -398.377236)
			(xy 394.455834 -398.405952) (xy 394.499843 -398.441571) (xy 394.538097 -398.483308) (xy 394.569756 -398.530245)
			(xy 394.594123 -398.581349) (xy 394.610662 -398.635496) (xy 394.619008 -398.691494) (xy 394.61948 -398.719802)
			(xy 394.619017 -398.747054) (xy 394.611259 -398.801003) (xy 394.595903 -398.853299) (xy 394.57326 -398.902877)
			(xy 394.543791 -398.948728) (xy 394.508097 -398.989918) (xy 394.466904 -399.025609) (xy 394.421051 -399.055074)
			(xy 394.371471 -399.077713) (xy 394.319174 -399.093066) (xy 394.265224 -399.100819) (xy 394.237972 -399.10131)
			(xy 394.210603 -399.100836) (xy 394.156426 -399.093009) (xy 394.103925 -399.077519) (xy 394.054176 -399.054685)
			(xy 394.008201 -399.024975) (xy 393.987274 -399.00733) (xy 393.980162 -399.001234) (xy 393.963144 -398.994884)
			(xy 393.8778 -398.994884) (xy 393.860782 -399.001234) (xy 393.85367 -399.00733) (xy 393.832737 -399.024969)
			(xy 393.78677 -399.054689) (xy 393.737023 -399.077527) (xy 393.68452 -399.093011) (xy 393.630342 -399.100825)
			(xy 393.602972 -399.10131) (xy 393.574878 -399.10081) (xy 393.519297 -399.092571) (xy 393.465523 -399.076275)
			(xy 393.439904 -399.064734) (xy 393.425426 -399.057876) (xy 393.39393 -399.06321) (xy 393.20851 -399.24863)
			(xy 393.201144 -399.257774) (xy 393.183238 -399.285695) (xy 393.141989 -399.337643) (xy 393.118848 -399.361406)
			(xy 392.816842 -399.663412) (xy 392.793053 -399.686525) (xy 392.74111 -399.727772) (xy 392.71321 -399.745708)
			(xy 392.708384 -399.748756) (xy 392.406378 -400.050762) (xy 392.40333 -400.055842) (xy 392.385435 -400.083543)
			(xy 392.344311 -400.135101) (xy 392.321288 -400.158712) (xy 392.019282 -400.460718) (xy 391.995673 -400.483744)
			(xy 391.944114 -400.524867) (xy 391.916412 -400.54276) (xy 391.911332 -400.545808) (xy 391.741406 -400.715734)
			(xy 391.734564 -400.723134) (xy 391.726841 -400.741732) (xy 391.72642 -400.751802) (xy 391.72642 -401.308316)
			(xy 391.751058 -401.336764) (xy 391.769854 -401.339558) (xy 391.796741 -401.34392) (xy 391.849001 -401.359277)
			(xy 391.898544 -401.381913) (xy 391.944362 -401.411369) (xy 391.985523 -401.447044) (xy 392.021188 -401.488213)
			(xy 392.050632 -401.534038) (xy 392.073256 -401.583587) (xy 392.0886 -401.635851) (xy 392.09635 -401.689766)
			(xy 392.09635 -401.744235) (xy 392.088599 -401.79815) (xy 392.073256 -401.850414) (xy 392.050632 -401.899962)
			(xy 392.048725 -401.90293) (xy 392.326114 -401.90293) (xy 392.326568 -401.872233) (xy 392.333975 -401.811287)
			(xy 392.348671 -401.751678) (xy 392.370443 -401.694275) (xy 392.398974 -401.639913) (xy 392.41603 -401.614386)
			(xy 392.421474 -401.60562) (xy 392.425609 -401.585425) (xy 392.421494 -401.565226) (xy 392.41603 -401.556474)
			(xy 392.398989 -401.53094) (xy 392.37048 -401.476571) (xy 392.348718 -401.419168) (xy 392.334018 -401.359564)
			(xy 392.326594 -401.298625) (xy 392.326114 -401.26793) (xy 392.326566 -401.237198) (xy 392.333971 -401.176181)
			(xy 392.348678 -401.116502) (xy 392.370472 -401.05903) (xy 392.399034 -401.004606) (xy 392.433949 -400.95402)
			(xy 392.474707 -400.908013) (xy 392.520714 -400.867254) (xy 392.571299 -400.832339) (xy 392.625723 -400.803775)
			(xy 392.683194 -400.781981) (xy 392.742873 -400.767273) (xy 392.80389 -400.759866) (xy 392.834622 -400.759422)
			(xy 392.865318 -400.759899) (xy 392.926263 -400.7673) (xy 392.985872 -400.781991) (xy 393.043276 -400.803758)
			(xy 393.097639 -400.832284) (xy 393.123166 -400.849338) (xy 393.131918 -400.854809) (xy 393.152122 -400.858937)
			(xy 393.172326 -400.854809) (xy 393.181078 -400.849338) (xy 393.206598 -400.832276) (xy 393.260971 -400.80377)
			(xy 393.318378 -400.782012) (xy 393.377985 -400.767317) (xy 393.438926 -400.759899) (xy 393.469622 -400.759422)
			(xy 393.500318 -400.759899) (xy 393.561263 -400.7673) (xy 393.620872 -400.781991) (xy 393.678276 -400.803758)
			(xy 393.732639 -400.832284) (xy 393.758166 -400.849338) (xy 393.766918 -400.854809) (xy 393.787122 -400.858937)
			(xy 393.807326 -400.854809) (xy 393.816078 -400.849338) (xy 393.841598 -400.832276) (xy 393.895971 -400.80377)
			(xy 393.953378 -400.782012) (xy 394.012985 -400.767317) (xy 394.073926 -400.759899) (xy 394.104622 -400.759422)
			(xy 394.125704 -400.75993) (xy 394.136626 -400.760438) (xy 394.156184 -400.752818) (xy 394.22451 -400.684492)
			(xy 394.23213 -400.664934) (xy 394.231622 -400.654012) (xy 394.231114 -400.63293) (xy 394.231568 -400.602233)
			(xy 394.238975 -400.541287) (xy 394.253671 -400.481678) (xy 394.275443 -400.424275) (xy 394.303974 -400.369913)
			(xy 394.32103 -400.344386) (xy 394.326474 -400.33562) (xy 394.330609 -400.315425) (xy 394.326494 -400.295226)
			(xy 394.32103 -400.286474) (xy 394.303989 -400.26094) (xy 394.27548 -400.206571) (xy 394.253718 -400.149168)
			(xy 394.239018 -400.089564) (xy 394.231594 -400.028625) (xy 394.231114 -399.99793) (xy 394.231686 -399.964706)
			(xy 394.240349 -399.898824) (xy 394.25752 -399.834632) (xy 394.282904 -399.773223) (xy 394.316071 -399.715643)
			(xy 394.356454 -399.662874) (xy 394.403366 -399.615813) (xy 394.456008 -399.575264) (xy 394.513483 -399.541916)
			(xy 394.574812 -399.516337) (xy 394.638949 -399.498965) (xy 394.671804 -399.493994) (xy 394.683234 -399.49247)
			(xy 394.701776 -399.480532) (xy 394.755624 -399.395188) (xy 394.758418 -399.373344) (xy 394.754862 -399.362422)
			(xy 394.743561 -399.324624) (xy 394.731437 -399.246673) (xy 394.730732 -399.207228) (xy 394.731164 -399.176495)
			(xy 394.73857 -399.115477) (xy 394.753278 -399.055796) (xy 394.775073 -398.998324) (xy 394.803637 -398.943898)
			(xy 394.838553 -398.893312) (xy 394.879313 -398.847305) (xy 394.925322 -398.806546) (xy 394.975908 -398.77163)
			(xy 395.030335 -398.743068) (xy 395.087808 -398.721274) (xy 395.147489 -398.706568) (xy 395.208507 -398.699163)
			(xy 395.23924 -398.69872) (xy 395.269936 -398.699189) (xy 395.330882 -398.706591) (xy 395.390491 -398.721285)
			(xy 395.447894 -398.743054) (xy 395.502257 -398.771581) (xy 395.527784 -398.788636) (xy 395.536536 -398.794107)
			(xy 395.55674 -398.798235) (xy 395.576944 -398.794107) (xy 395.585696 -398.788636) (xy 395.611239 -398.771609)
			(xy 395.665605 -398.743097) (xy 395.723006 -398.721332) (xy 395.782608 -398.706629) (xy 395.843546 -398.699202)
			(xy 395.87424 -398.69872) (xy 395.904973 -398.699118) (xy 395.96599 -398.706532) (xy 396.025669 -398.721246)
			(xy 396.083139 -398.743046) (xy 396.137562 -398.771615) (xy 396.188145 -398.806535) (xy 396.234151 -398.847298)
			(xy 396.274907 -398.893308) (xy 396.30982 -398.943896) (xy 396.338382 -398.998323) (xy 396.360174 -399.055796)
			(xy 396.374881 -399.115477) (xy 396.382286 -399.176495) (xy 396.382748 -399.207228) (xy 396.382173 -399.242074)
			(xy 396.372658 -399.311113) (xy 396.35381 -399.378208) (xy 396.325982 -399.442103) (xy 396.308326 -399.47215)
			(xy 396.3035 -399.480024) (xy 396.299944 -399.497804) (xy 396.314422 -399.582132) (xy 396.323566 -399.59788)
			(xy 396.330932 -399.603722) (xy 396.3556 -399.624468) (xy 396.400007 -399.671187) (xy 396.438156 -399.723143)
			(xy 396.469434 -399.779502) (xy 396.493342 -399.839361) (xy 396.509495 -399.901761) (xy 396.517634 -399.965702)
			(xy 396.51813 -399.99793) (xy 396.517648 -400.028626) (xy 396.510247 -400.08957) (xy 396.495556 -400.149179)
			(xy 396.47379 -400.206583) (xy 396.445266 -400.260946) (xy 396.428214 -400.286474) (xy 396.422715 -400.295212)
			(xy 396.418594 -400.315425) (xy 396.422735 -400.335634) (xy 396.428214 -400.344386) (xy 396.445231 -400.369936)
			(xy 396.473745 -400.4243) (xy 396.495513 -400.481699) (xy 396.510218 -400.541299) (xy 396.517647 -400.602236)
			(xy 396.51813 -400.63293) (xy 396.517672 -400.663661) (xy 396.510261 -400.724674) (xy 396.495549 -400.784349)
			(xy 396.473753 -400.841816) (xy 396.445189 -400.896237) (xy 396.410273 -400.946818) (xy 396.369516 -400.992822)
			(xy 396.323511 -401.033578) (xy 396.27293 -401.068493) (xy 396.218508 -401.097056) (xy 396.161041 -401.118852)
			(xy 396.101366 -401.133562) (xy 396.040353 -401.140973) (xy 396.009622 -401.141438) (xy 395.98854 -401.14093)
			(xy 395.977618 -401.140422) (xy 395.95806 -401.148042) (xy 395.889734 -401.216368) (xy 395.882114 -401.235926)
			(xy 395.882622 -401.246848) (xy 395.88313 -401.26793) (xy 395.882648 -401.298626) (xy 395.875247 -401.35957)
			(xy 395.860556 -401.419179) (xy 395.83879 -401.476583) (xy 395.810266 -401.530946) (xy 395.793214 -401.556474)
			(xy 395.787715 -401.565212) (xy 395.783594 -401.585425) (xy 395.787735 -401.605634) (xy 395.793214 -401.614386)
			(xy 395.810231 -401.639936) (xy 395.838745 -401.6943) (xy 395.860513 -401.751699) (xy 395.875218 -401.811299)
			(xy 395.882647 -401.872236) (xy 395.88313 -401.90293) (xy 395.882672 -401.933661) (xy 395.875261 -401.994674)
			(xy 395.860549 -402.054349) (xy 395.838753 -402.111816) (xy 395.810189 -402.166237) (xy 395.775273 -402.216818)
			(xy 395.734516 -402.262822) (xy 395.688511 -402.303578) (xy 395.63793 -402.338493) (xy 395.583508 -402.367056)
			(xy 395.526041 -402.388852) (xy 395.466366 -402.403562) (xy 395.405353 -402.410973) (xy 395.374622 -402.411438)
			(xy 395.343925 -402.410979) (xy 395.28298 -402.403572) (xy 395.223372 -402.388876) (xy 395.165968 -402.367105)
			(xy 395.111605 -402.338577) (xy 395.086078 -402.321522) (xy 395.077326 -402.316051) (xy 395.057122 -402.311923)
			(xy 395.036918 -402.316051) (xy 395.028166 -402.321522) (xy 395.00263 -402.338561) (xy 394.948262 -402.367071)
			(xy 394.89086 -402.388834) (xy 394.831256 -402.403535) (xy 394.770317 -402.410958) (xy 394.739622 -402.411438)
			(xy 394.708925 -402.410979) (xy 394.64798 -402.403572) (xy 394.588372 -402.388876) (xy 394.530968 -402.367105)
			(xy 394.476605 -402.338577) (xy 394.451078 -402.321522) (xy 394.442326 -402.316051) (xy 394.422122 -402.311923)
			(xy 394.401918 -402.316051) (xy 394.393166 -402.321522) (xy 394.36763 -402.338561) (xy 394.313262 -402.367071)
			(xy 394.25586 -402.388834) (xy 394.196256 -402.403535) (xy 394.135317 -402.410958) (xy 394.104622 -402.411438)
			(xy 394.073925 -402.410979) (xy 394.01298 -402.403572) (xy 393.953372 -402.388876) (xy 393.895968 -402.367105)
			(xy 393.841605 -402.338577) (xy 393.816078 -402.321522) (xy 393.807326 -402.316051) (xy 393.787122 -402.311923)
			(xy 393.766918 -402.316051) (xy 393.758166 -402.321522) (xy 393.73263 -402.338561) (xy 393.678262 -402.367071)
			(xy 393.62086 -402.388834) (xy 393.561256 -402.403535) (xy 393.500317 -402.410958) (xy 393.469622 -402.411438)
			(xy 393.438925 -402.410979) (xy 393.37798 -402.403572) (xy 393.318372 -402.388876) (xy 393.260968 -402.367105)
			(xy 393.206605 -402.338577) (xy 393.181078 -402.321522) (xy 393.172326 -402.316051) (xy 393.152122 -402.311923)
			(xy 393.131918 -402.316051) (xy 393.123166 -402.321522) (xy 393.09763 -402.338561) (xy 393.043262 -402.367071)
			(xy 392.98586 -402.388834) (xy 392.926256 -402.403535) (xy 392.865317 -402.410958) (xy 392.834622 -402.411438)
			(xy 392.803893 -402.410923) (xy 392.742882 -402.403518) (xy 392.683208 -402.388813) (xy 392.625742 -402.367022)
			(xy 392.571322 -402.338463) (xy 392.520741 -402.303553) (xy 392.474736 -402.262801) (xy 392.433979 -402.2168)
			(xy 392.399064 -402.166223) (xy 392.3705 -402.111805) (xy 392.348703 -402.054342) (xy 392.333991 -401.99467)
			(xy 392.32658 -401.933659) (xy 392.326114 -401.90293) (xy 392.048725 -401.90293) (xy 392.021187 -401.945787)
			(xy 391.985522 -401.986956) (xy 391.944362 -402.022632) (xy 391.898544 -402.052087) (xy 391.849001 -402.074723)
			(xy 391.796741 -402.09008) (xy 391.769854 -402.094446) (xy 391.751058 -402.09724) (xy 391.72642 -402.125688)
			(xy 391.72642 -402.405088) (xy 391.728452 -402.411946) (xy 391.731331 -402.422467) (xy 391.735782 -402.443823)
			(xy 391.737342 -402.454618) (xy 391.738612 -402.462746) (xy 391.745978 -402.477478) (xy 392.394948 -403.126448)
			(xy 392.402357 -403.133135) (xy 392.420793 -403.140728) (xy 392.430762 -403.14118)
		)
		(stroke
			(width 0)
			(type solid)
		)
		(fill yes)
		(layer "In2.Cu")
		(net "P0V9_CPU0_RT2_2A_2D")
	)
	(gr_poly
		(pts
			(xy 76.201778 -395.53896) (xy 76.211841 -395.538521) (xy 76.230421 -395.530783) (xy 76.237846 -395.523974)
			(xy 76.832714 -394.929106) (xy 76.839571 -394.921712) (xy 76.847321 -394.903113) (xy 76.8477 -394.893038)
			(xy 76.8477 -394.213842) (xy 76.84717 -394.203851) (xy 76.839467 -394.185408) (xy 76.832714 -394.178028)
			(xy 76.60386 -393.949174) (xy 76.586814 -393.93146) (xy 76.557947 -393.891669) (xy 76.535666 -393.847849)
			(xy 76.520518 -393.801082) (xy 76.512879 -393.75252) (xy 76.51242 -393.72794) (xy 76.51242 -392.399266)
			(xy 76.513003 -392.371439) (xy 76.522806 -392.316657) (xy 76.54215 -392.264474) (xy 76.570423 -392.216539)
			(xy 76.588112 -392.19505) (xy 76.592125 -392.190158) (xy 76.597777 -392.178842) (xy 76.599288 -392.172698)
			(xy 76.60503 -392.147623) (xy 76.622358 -392.099189) (xy 76.64604 -392.053524) (xy 76.675647 -392.011458)
			(xy 76.710641 -391.973754) (xy 76.750387 -391.941098) (xy 76.794162 -391.914082) (xy 76.817474 -391.903204)
			(xy 76.831444 -391.897108) (xy 76.8477 -391.872216) (xy 76.8477 -391.206482) (xy 76.848127 -391.196413)
			(xy 76.855846 -391.177814) (xy 76.862686 -391.170414) (xy 77.29474 -390.73836) (xy 77.301852 -390.713214)
			(xy 77.298804 -390.700514) (xy 77.294867 -390.682161) (xy 77.290667 -390.644861) (xy 77.290422 -390.626092)
			(xy 77.290816 -390.602859) (xy 77.29732 -390.556849) (xy 77.3102 -390.512203) (xy 77.329201 -390.469798)
			(xy 77.353949 -390.43047) (xy 77.368654 -390.412478) (xy 77.37475 -390.405366) (xy 77.380846 -390.388856)
			(xy 77.380846 -390.304528) (xy 77.37475 -390.288018) (xy 77.368654 -390.280906) (xy 77.353943 -390.262917)
			(xy 77.329181 -390.223593) (xy 77.310171 -390.181189) (xy 77.297285 -390.13654) (xy 77.290779 -390.090527)
			(xy 77.290422 -390.067292) (xy 77.290932 -390.041305) (xy 77.299062 -389.98997) (xy 77.315123 -389.94054)
			(xy 77.338719 -389.89423) (xy 77.369269 -389.852182) (xy 77.40602 -389.815431) (xy 77.448068 -389.784881)
			(xy 77.494378 -389.761285) (xy 77.543808 -389.745224) (xy 77.595143 -389.737094) (xy 77.647117 -389.737094)
			(xy 77.698452 -389.745224) (xy 77.747882 -389.761285) (xy 77.794192 -389.784881) (xy 77.83624 -389.815431)
			(xy 77.872991 -389.852182) (xy 77.903541 -389.89423) (xy 77.927137 -389.94054) (xy 77.943198 -389.98997)
			(xy 77.951328 -390.041305) (xy 77.951838 -390.067292) (xy 77.951445 -390.090526) (xy 77.944944 -390.136538)
			(xy 77.938177 -390.160002) (xy 79.61301 -390.160002) (xy 79.61697 -390.110948) (xy 79.628747 -390.063164)
			(xy 79.648038 -390.017888) (xy 79.674341 -389.976292) (xy 79.706976 -389.939455) (xy 79.745097 -389.90833)
			(xy 79.787718 -389.883723) (xy 79.833734 -389.866271) (xy 79.881953 -389.856427) (xy 79.931128 -389.854446)
			(xy 79.979983 -389.860378) (xy 80.027254 -389.87407) (xy 80.071716 -389.895168) (xy 80.112219 -389.923124)
			(xy 80.147712 -389.957216) (xy 80.177277 -389.99656) (xy 80.200148 -390.040137) (xy 80.215732 -390.086818)
			(xy 80.223627 -390.135395) (xy 80.224122 -390.160002) (xy 80.81316 -390.160002) (xy 80.81712 -390.110948)
			(xy 80.828897 -390.063164) (xy 80.848188 -390.017888) (xy 80.874491 -389.976292) (xy 80.907126 -389.939455)
			(xy 80.945247 -389.90833) (xy 80.987868 -389.883723) (xy 81.033884 -389.866271) (xy 81.082103 -389.856427)
			(xy 81.131278 -389.854446) (xy 81.180133 -389.860378) (xy 81.227404 -389.87407) (xy 81.271866 -389.895168)
			(xy 81.312369 -389.923124) (xy 81.347862 -389.957216) (xy 81.377427 -389.99656) (xy 81.400298 -390.040137)
			(xy 81.415882 -390.086818) (xy 81.423777 -390.135395) (xy 81.424272 -390.160002) (xy 82.01331 -390.160002)
			(xy 82.01727 -390.110948) (xy 82.029047 -390.063164) (xy 82.048338 -390.017888) (xy 82.074641 -389.976292)
			(xy 82.107276 -389.939455) (xy 82.145397 -389.90833) (xy 82.188018 -389.883723) (xy 82.234034 -389.866271)
			(xy 82.282253 -389.856427) (xy 82.331428 -389.854446) (xy 82.380283 -389.860378) (xy 82.427554 -389.87407)
			(xy 82.472016 -389.895168) (xy 82.512519 -389.923124) (xy 82.548012 -389.957216) (xy 82.577577 -389.99656)
			(xy 82.600448 -390.040137) (xy 82.616032 -390.086818) (xy 82.623927 -390.135395) (xy 82.624422 -390.160002)
			(xy 83.213206 -390.160002) (xy 83.217166 -390.110948) (xy 83.228943 -390.063164) (xy 83.248234 -390.017888)
			(xy 83.274537 -389.976292) (xy 83.307172 -389.939455) (xy 83.345293 -389.90833) (xy 83.387914 -389.883723)
			(xy 83.43393 -389.866271) (xy 83.482149 -389.856427) (xy 83.531324 -389.854446) (xy 83.580179 -389.860378)
			(xy 83.62745 -389.87407) (xy 83.671912 -389.895168) (xy 83.712415 -389.923124) (xy 83.747908 -389.957216)
			(xy 83.777473 -389.99656) (xy 83.800344 -390.040137) (xy 83.815928 -390.086818) (xy 83.823823 -390.135395)
			(xy 83.824318 -390.160002) (xy 84.413356 -390.160002) (xy 84.417316 -390.110948) (xy 84.429093 -390.063164)
			(xy 84.448384 -390.017888) (xy 84.474687 -389.976292) (xy 84.507322 -389.939455) (xy 84.545443 -389.90833)
			(xy 84.588064 -389.883723) (xy 84.63408 -389.866271) (xy 84.682299 -389.856427) (xy 84.731474 -389.854446)
			(xy 84.780329 -389.860378) (xy 84.8276 -389.87407) (xy 84.872062 -389.895168) (xy 84.912565 -389.923124)
			(xy 84.948058 -389.957216) (xy 84.977623 -389.99656) (xy 85.000494 -390.040137) (xy 85.016078 -390.086818)
			(xy 85.023973 -390.135395) (xy 85.024468 -390.160002) (xy 85.613252 -390.160002) (xy 85.617212 -390.110948)
			(xy 85.628989 -390.063164) (xy 85.64828 -390.017888) (xy 85.674583 -389.976292) (xy 85.707218 -389.939455)
			(xy 85.745339 -389.90833) (xy 85.78796 -389.883723) (xy 85.833976 -389.866271) (xy 85.882195 -389.856427)
			(xy 85.93137 -389.854446) (xy 85.980225 -389.860378) (xy 86.027496 -389.87407) (xy 86.071958 -389.895168)
			(xy 86.112461 -389.923124) (xy 86.147954 -389.957216) (xy 86.177519 -389.99656) (xy 86.20039 -390.040137)
			(xy 86.215974 -390.086818) (xy 86.223869 -390.135395) (xy 86.224364 -390.160002) (xy 86.813148 -390.160002)
			(xy 86.817108 -390.110948) (xy 86.828885 -390.063164) (xy 86.848176 -390.017888) (xy 86.874479 -389.976292)
			(xy 86.907114 -389.939455) (xy 86.945235 -389.90833) (xy 86.987856 -389.883723) (xy 87.033872 -389.866271)
			(xy 87.082091 -389.856427) (xy 87.131266 -389.854446) (xy 87.180121 -389.860378) (xy 87.227392 -389.87407)
			(xy 87.271854 -389.895168) (xy 87.312357 -389.923124) (xy 87.34785 -389.957216) (xy 87.377415 -389.99656)
			(xy 87.400286 -390.040137) (xy 87.41587 -390.086818) (xy 87.423765 -390.135395) (xy 87.42426 -390.160002)
			(xy 88.013298 -390.160002) (xy 88.017258 -390.110948) (xy 88.029035 -390.063164) (xy 88.048326 -390.017888)
			(xy 88.074629 -389.976292) (xy 88.107264 -389.939455) (xy 88.145385 -389.90833) (xy 88.188006 -389.883723)
			(xy 88.234022 -389.866271) (xy 88.282241 -389.856427) (xy 88.331416 -389.854446) (xy 88.380271 -389.860378)
			(xy 88.427542 -389.87407) (xy 88.472004 -389.895168) (xy 88.512507 -389.923124) (xy 88.548 -389.957216)
			(xy 88.577565 -389.99656) (xy 88.600436 -390.040137) (xy 88.61602 -390.086818) (xy 88.623915 -390.135395)
			(xy 88.62441 -390.160002) (xy 89.213194 -390.160002) (xy 89.217154 -390.110948) (xy 89.228931 -390.063164)
			(xy 89.248222 -390.017888) (xy 89.274525 -389.976292) (xy 89.30716 -389.939455) (xy 89.345281 -389.90833)
			(xy 89.387902 -389.883723) (xy 89.433918 -389.866271) (xy 89.482137 -389.856427) (xy 89.531312 -389.854446)
			(xy 89.580167 -389.860378) (xy 89.627438 -389.87407) (xy 89.6719 -389.895168) (xy 89.712403 -389.923124)
			(xy 89.747896 -389.957216) (xy 89.777461 -389.99656) (xy 89.800332 -390.040137) (xy 89.815916 -390.086818)
			(xy 89.823811 -390.135395) (xy 89.824306 -390.160002) (xy 90.413344 -390.160002) (xy 90.417304 -390.110948)
			(xy 90.429081 -390.063164) (xy 90.448372 -390.017888) (xy 90.474675 -389.976292) (xy 90.50731 -389.939455)
			(xy 90.545431 -389.90833) (xy 90.588052 -389.883723) (xy 90.634068 -389.866271) (xy 90.682287 -389.856427)
			(xy 90.731462 -389.854446) (xy 90.780317 -389.860378) (xy 90.827588 -389.87407) (xy 90.87205 -389.895168)
			(xy 90.912553 -389.923124) (xy 90.948046 -389.957216) (xy 90.977611 -389.99656) (xy 91.000482 -390.040137)
			(xy 91.016066 -390.086818) (xy 91.023961 -390.135395) (xy 91.024456 -390.160002) (xy 91.61324 -390.160002)
			(xy 91.6172 -390.110948) (xy 91.628977 -390.063164) (xy 91.648268 -390.017888) (xy 91.674571 -389.976292)
			(xy 91.707206 -389.939455) (xy 91.745327 -389.90833) (xy 91.787948 -389.883723) (xy 91.833964 -389.866271)
			(xy 91.882183 -389.856427) (xy 91.931358 -389.854446) (xy 91.980213 -389.860378) (xy 92.027484 -389.87407)
			(xy 92.071946 -389.895168) (xy 92.112449 -389.923124) (xy 92.147942 -389.957216) (xy 92.177507 -389.99656)
			(xy 92.200378 -390.040137) (xy 92.215962 -390.086818) (xy 92.223857 -390.135395) (xy 92.224352 -390.160002)
			(xy 92.813136 -390.160002) (xy 92.817096 -390.110948) (xy 92.828873 -390.063164) (xy 92.848164 -390.017888)
			(xy 92.874467 -389.976292) (xy 92.907102 -389.939455) (xy 92.945223 -389.90833) (xy 92.987844 -389.883723)
			(xy 93.03386 -389.866271) (xy 93.082079 -389.856427) (xy 93.131254 -389.854446) (xy 93.180109 -389.860378)
			(xy 93.22738 -389.87407) (xy 93.271842 -389.895168) (xy 93.312345 -389.923124) (xy 93.347838 -389.957216)
			(xy 93.377403 -389.99656) (xy 93.400274 -390.040137) (xy 93.415858 -390.086818) (xy 93.423753 -390.135395)
			(xy 93.424248 -390.160002) (xy 94.013286 -390.160002) (xy 94.017246 -390.110948) (xy 94.029023 -390.063164)
			(xy 94.048314 -390.017888) (xy 94.074617 -389.976292) (xy 94.107252 -389.939455) (xy 94.145373 -389.90833)
			(xy 94.187994 -389.883723) (xy 94.23401 -389.866271) (xy 94.282229 -389.856427) (xy 94.331404 -389.854446)
			(xy 94.380259 -389.860378) (xy 94.42753 -389.87407) (xy 94.471992 -389.895168) (xy 94.512495 -389.923124)
			(xy 94.547988 -389.957216) (xy 94.577553 -389.99656) (xy 94.600424 -390.040137) (xy 94.616008 -390.086818)
			(xy 94.623903 -390.135395) (xy 94.624398 -390.160002) (xy 95.213182 -390.160002) (xy 95.217142 -390.110948)
			(xy 95.228919 -390.063164) (xy 95.24821 -390.017888) (xy 95.274513 -389.976292) (xy 95.307148 -389.939455)
			(xy 95.345269 -389.90833) (xy 95.38789 -389.883723) (xy 95.433906 -389.866271) (xy 95.482125 -389.856427)
			(xy 95.5313 -389.854446) (xy 95.580155 -389.860378) (xy 95.627426 -389.87407) (xy 95.671888 -389.895168)
			(xy 95.712391 -389.923124) (xy 95.747884 -389.957216) (xy 95.777449 -389.99656) (xy 95.80032 -390.040137)
			(xy 95.815904 -390.086818) (xy 95.823799 -390.135395) (xy 95.824294 -390.160002) (xy 96.413332 -390.160002)
			(xy 96.417292 -390.110948) (xy 96.429069 -390.063164) (xy 96.44836 -390.017888) (xy 96.474663 -389.976292)
			(xy 96.507298 -389.939455) (xy 96.545419 -389.90833) (xy 96.58804 -389.883723) (xy 96.634056 -389.866271)
			(xy 96.682275 -389.856427) (xy 96.73145 -389.854446) (xy 96.780305 -389.860378) (xy 96.827576 -389.87407)
			(xy 96.872038 -389.895168) (xy 96.912541 -389.923124) (xy 96.948034 -389.957216) (xy 96.977599 -389.99656)
			(xy 97.00047 -390.040137) (xy 97.016054 -390.086818) (xy 97.023949 -390.135395) (xy 97.024444 -390.160002)
			(xy 97.023949 -390.184609) (xy 97.016054 -390.233186) (xy 97.00047 -390.279867) (xy 96.977599 -390.323444)
			(xy 96.948034 -390.362788) (xy 96.912541 -390.39688) (xy 96.872038 -390.424836) (xy 96.827576 -390.445934)
			(xy 96.780305 -390.459626) (xy 96.73145 -390.465558) (xy 96.682275 -390.463577) (xy 96.634056 -390.453733)
			(xy 96.58804 -390.436281) (xy 96.545419 -390.411674) (xy 96.507298 -390.380549) (xy 96.474663 -390.343712)
			(xy 96.44836 -390.302116) (xy 96.429069 -390.25684) (xy 96.417292 -390.209056) (xy 96.413332 -390.160002)
			(xy 95.824294 -390.160002) (xy 95.823799 -390.184609) (xy 95.815904 -390.233186) (xy 95.80032 -390.279867)
			(xy 95.777449 -390.323444) (xy 95.747884 -390.362788) (xy 95.712391 -390.39688) (xy 95.671888 -390.424836)
			(xy 95.627426 -390.445934) (xy 95.580155 -390.459626) (xy 95.5313 -390.465558) (xy 95.482125 -390.463577)
			(xy 95.433906 -390.453733) (xy 95.38789 -390.436281) (xy 95.345269 -390.411674) (xy 95.307148 -390.380549)
			(xy 95.274513 -390.343712) (xy 95.24821 -390.302116) (xy 95.228919 -390.25684) (xy 95.217142 -390.209056)
			(xy 95.213182 -390.160002) (xy 94.624398 -390.160002) (xy 94.623903 -390.184609) (xy 94.616008 -390.233186)
			(xy 94.600424 -390.279867) (xy 94.577553 -390.323444) (xy 94.547988 -390.362788) (xy 94.512495 -390.39688)
			(xy 94.471992 -390.424836) (xy 94.42753 -390.445934) (xy 94.380259 -390.459626) (xy 94.331404 -390.465558)
			(xy 94.282229 -390.463577) (xy 94.23401 -390.453733) (xy 94.187994 -390.436281) (xy 94.145373 -390.411674)
			(xy 94.107252 -390.380549) (xy 94.074617 -390.343712) (xy 94.048314 -390.302116) (xy 94.029023 -390.25684)
			(xy 94.017246 -390.209056) (xy 94.013286 -390.160002) (xy 93.424248 -390.160002) (xy 93.423753 -390.184609)
			(xy 93.415858 -390.233186) (xy 93.400274 -390.279867) (xy 93.377403 -390.323444) (xy 93.347838 -390.362788)
			(xy 93.312345 -390.39688) (xy 93.271842 -390.424836) (xy 93.22738 -390.445934) (xy 93.180109 -390.459626)
			(xy 93.131254 -390.465558) (xy 93.082079 -390.463577) (xy 93.03386 -390.453733) (xy 92.987844 -390.436281)
			(xy 92.945223 -390.411674) (xy 92.907102 -390.380549) (xy 92.874467 -390.343712) (xy 92.848164 -390.302116)
			(xy 92.828873 -390.25684) (xy 92.817096 -390.209056) (xy 92.813136 -390.160002) (xy 92.224352 -390.160002)
			(xy 92.223857 -390.184609) (xy 92.215962 -390.233186) (xy 92.200378 -390.279867) (xy 92.177507 -390.323444)
			(xy 92.147942 -390.362788) (xy 92.112449 -390.39688) (xy 92.071946 -390.424836) (xy 92.027484 -390.445934)
			(xy 91.980213 -390.459626) (xy 91.931358 -390.465558) (xy 91.882183 -390.463577) (xy 91.833964 -390.453733)
			(xy 91.787948 -390.436281) (xy 91.745327 -390.411674) (xy 91.707206 -390.380549) (xy 91.674571 -390.343712)
			(xy 91.648268 -390.302116) (xy 91.628977 -390.25684) (xy 91.6172 -390.209056) (xy 91.61324 -390.160002)
			(xy 91.024456 -390.160002) (xy 91.023961 -390.184609) (xy 91.016066 -390.233186) (xy 91.000482 -390.279867)
			(xy 90.977611 -390.323444) (xy 90.948046 -390.362788) (xy 90.912553 -390.39688) (xy 90.87205 -390.424836)
			(xy 90.827588 -390.445934) (xy 90.780317 -390.459626) (xy 90.731462 -390.465558) (xy 90.682287 -390.463577)
			(xy 90.634068 -390.453733) (xy 90.588052 -390.436281) (xy 90.545431 -390.411674) (xy 90.50731 -390.380549)
			(xy 90.474675 -390.343712) (xy 90.448372 -390.302116) (xy 90.429081 -390.25684) (xy 90.417304 -390.209056)
			(xy 90.413344 -390.160002) (xy 89.824306 -390.160002) (xy 89.823811 -390.184609) (xy 89.815916 -390.233186)
			(xy 89.800332 -390.279867) (xy 89.777461 -390.323444) (xy 89.747896 -390.362788) (xy 89.712403 -390.39688)
			(xy 89.6719 -390.424836) (xy 89.627438 -390.445934) (xy 89.580167 -390.459626) (xy 89.531312 -390.465558)
			(xy 89.482137 -390.463577) (xy 89.433918 -390.453733) (xy 89.387902 -390.436281) (xy 89.345281 -390.411674)
			(xy 89.30716 -390.380549) (xy 89.274525 -390.343712) (xy 89.248222 -390.302116) (xy 89.228931 -390.25684)
			(xy 89.217154 -390.209056) (xy 89.213194 -390.160002) (xy 88.62441 -390.160002) (xy 88.623915 -390.184609)
			(xy 88.61602 -390.233186) (xy 88.600436 -390.279867) (xy 88.577565 -390.323444) (xy 88.548 -390.362788)
			(xy 88.512507 -390.39688) (xy 88.472004 -390.424836) (xy 88.427542 -390.445934) (xy 88.380271 -390.459626)
			(xy 88.331416 -390.465558) (xy 88.282241 -390.463577) (xy 88.234022 -390.453733) (xy 88.188006 -390.436281)
			(xy 88.145385 -390.411674) (xy 88.107264 -390.380549) (xy 88.074629 -390.343712) (xy 88.048326 -390.302116)
			(xy 88.029035 -390.25684) (xy 88.017258 -390.209056) (xy 88.013298 -390.160002) (xy 87.42426 -390.160002)
			(xy 87.423765 -390.184609) (xy 87.41587 -390.233186) (xy 87.400286 -390.279867) (xy 87.377415 -390.323444)
			(xy 87.34785 -390.362788) (xy 87.312357 -390.39688) (xy 87.271854 -390.424836) (xy 87.227392 -390.445934)
			(xy 87.180121 -390.459626) (xy 87.131266 -390.465558) (xy 87.082091 -390.463577) (xy 87.033872 -390.453733)
			(xy 86.987856 -390.436281) (xy 86.945235 -390.411674) (xy 86.907114 -390.380549) (xy 86.874479 -390.343712)
			(xy 86.848176 -390.302116) (xy 86.828885 -390.25684) (xy 86.817108 -390.209056) (xy 86.813148 -390.160002)
			(xy 86.224364 -390.160002) (xy 86.223869 -390.184609) (xy 86.215974 -390.233186) (xy 86.20039 -390.279867)
			(xy 86.177519 -390.323444) (xy 86.147954 -390.362788) (xy 86.112461 -390.39688) (xy 86.071958 -390.424836)
			(xy 86.027496 -390.445934) (xy 85.980225 -390.459626) (xy 85.93137 -390.465558) (xy 85.882195 -390.463577)
			(xy 85.833976 -390.453733) (xy 85.78796 -390.436281) (xy 85.745339 -390.411674) (xy 85.707218 -390.380549)
			(xy 85.674583 -390.343712) (xy 85.64828 -390.302116) (xy 85.628989 -390.25684) (xy 85.617212 -390.209056)
			(xy 85.613252 -390.160002) (xy 85.024468 -390.160002) (xy 85.023973 -390.184609) (xy 85.016078 -390.233186)
			(xy 85.000494 -390.279867) (xy 84.977623 -390.323444) (xy 84.948058 -390.362788) (xy 84.912565 -390.39688)
			(xy 84.872062 -390.424836) (xy 84.8276 -390.445934) (xy 84.780329 -390.459626) (xy 84.731474 -390.465558)
			(xy 84.682299 -390.463577) (xy 84.63408 -390.453733) (xy 84.588064 -390.436281) (xy 84.545443 -390.411674)
			(xy 84.507322 -390.380549) (xy 84.474687 -390.343712) (xy 84.448384 -390.302116) (xy 84.429093 -390.25684)
			(xy 84.417316 -390.209056) (xy 84.413356 -390.160002) (xy 83.824318 -390.160002) (xy 83.823823 -390.184609)
			(xy 83.815928 -390.233186) (xy 83.800344 -390.279867) (xy 83.777473 -390.323444) (xy 83.747908 -390.362788)
			(xy 83.712415 -390.39688) (xy 83.671912 -390.424836) (xy 83.62745 -390.445934) (xy 83.580179 -390.459626)
			(xy 83.531324 -390.465558) (xy 83.482149 -390.463577) (xy 83.43393 -390.453733) (xy 83.387914 -390.436281)
			(xy 83.345293 -390.411674) (xy 83.307172 -390.380549) (xy 83.274537 -390.343712) (xy 83.248234 -390.302116)
			(xy 83.228943 -390.25684) (xy 83.217166 -390.209056) (xy 83.213206 -390.160002) (xy 82.624422 -390.160002)
			(xy 82.623927 -390.184609) (xy 82.616032 -390.233186) (xy 82.600448 -390.279867) (xy 82.577577 -390.323444)
			(xy 82.548012 -390.362788) (xy 82.512519 -390.39688) (xy 82.472016 -390.424836) (xy 82.427554 -390.445934)
			(xy 82.380283 -390.459626) (xy 82.331428 -390.465558) (xy 82.282253 -390.463577) (xy 82.234034 -390.453733)
			(xy 82.188018 -390.436281) (xy 82.145397 -390.411674) (xy 82.107276 -390.380549) (xy 82.074641 -390.343712)
			(xy 82.048338 -390.302116) (xy 82.029047 -390.25684) (xy 82.01727 -390.209056) (xy 82.01331 -390.160002)
			(xy 81.424272 -390.160002) (xy 81.423777 -390.184609) (xy 81.415882 -390.233186) (xy 81.400298 -390.279867)
			(xy 81.377427 -390.323444) (xy 81.347862 -390.362788) (xy 81.312369 -390.39688) (xy 81.271866 -390.424836)
			(xy 81.227404 -390.445934) (xy 81.180133 -390.459626) (xy 81.131278 -390.465558) (xy 81.082103 -390.463577)
			(xy 81.033884 -390.453733) (xy 80.987868 -390.436281) (xy 80.945247 -390.411674) (xy 80.907126 -390.380549)
			(xy 80.874491 -390.343712) (xy 80.848188 -390.302116) (xy 80.828897 -390.25684) (xy 80.81712 -390.209056)
			(xy 80.81316 -390.160002) (xy 80.224122 -390.160002) (xy 80.223627 -390.184609) (xy 80.215732 -390.233186)
			(xy 80.200148 -390.279867) (xy 80.177277 -390.323444) (xy 80.147712 -390.362788) (xy 80.112219 -390.39688)
			(xy 80.071716 -390.424836) (xy 80.027254 -390.445934) (xy 79.979983 -390.459626) (xy 79.931128 -390.465558)
			(xy 79.881953 -390.463577) (xy 79.833734 -390.453733) (xy 79.787718 -390.436281) (xy 79.745097 -390.411674)
			(xy 79.706976 -390.380549) (xy 79.674341 -390.343712) (xy 79.648038 -390.302116) (xy 79.628747 -390.25684)
			(xy 79.61697 -390.209056) (xy 79.61301 -390.160002) (xy 77.938177 -390.160002) (xy 77.932068 -390.181186)
			(xy 77.913071 -390.223594) (xy 77.888327 -390.262927) (xy 77.873606 -390.280906) (xy 77.86751 -390.288018)
			(xy 77.861414 -390.304528) (xy 77.861414 -390.388856) (xy 77.86751 -390.405366) (xy 77.873606 -390.412478)
			(xy 77.88831 -390.43047) (xy 77.913057 -390.469797) (xy 77.932053 -390.512202) (xy 77.944925 -390.556849)
			(xy 77.951418 -390.602859) (xy 77.951838 -390.626092) (xy 77.951838 -390.62914) (xy 77.952334 -390.639139)
			(xy 77.960002 -390.657611) (xy 77.974155 -390.671742) (xy 77.992638 -390.679382) (xy 78.002638 -390.67994)
			(xy 97.446338 -390.67994) (xy 97.456404 -390.679508) (xy 97.474993 -390.671778) (xy 97.482406 -390.664954)
			(xy 97.71634 -390.43102) (xy 97.71634 -390.389364) (xy 97.701608 -390.374378) (xy 97.685236 -390.357129)
			(xy 97.657502 -390.318498) (xy 97.636095 -390.276033) (xy 97.621535 -390.230762) (xy 97.614173 -390.18378)
			(xy 97.613724 -390.160002) (xy 97.61417 -390.13601) (xy 97.621677 -390.088616) (xy 97.636506 -390.04298)
			(xy 97.658291 -390.000226) (xy 97.686497 -389.961407) (xy 97.720429 -389.927478) (xy 97.759251 -389.899276)
			(xy 97.802008 -389.877494) (xy 97.847645 -389.86267) (xy 97.89504 -389.855168) (xy 97.919032 -389.854694)
			(xy 97.942809 -389.855149) (xy 97.989787 -389.862522) (xy 98.035055 -389.877085) (xy 98.077521 -389.898486)
			(xy 98.116157 -389.926209) (xy 98.133408 -389.942578) (xy 98.148394 -389.95731) (xy 98.19005 -389.95731)
			(xy 98.432874 -389.714486) (xy 98.439721 -389.707088) (xy 98.447454 -389.68849) (xy 98.44786 -389.678418)
			(xy 98.44786 -389.621268) (xy 98.447662 -389.614601) (xy 98.444183 -389.60173) (xy 98.441002 -389.595868)
			(xy 98.05162 -388.922006) (xy 98.039689 -388.899345) (xy 98.022742 -388.85102) (xy 98.014102 -388.800544)
			(xy 98.01352 -388.77494) (xy 98.01352 -388.774432) (xy 98.013671 -388.763083) (xy 98.015452 -388.740453)
			(xy 98.017076 -388.72922) (xy 98.018346 -388.72033) (xy 98.01479 -388.703058) (xy 97.971356 -388.631938)
			(xy 97.957386 -388.621016) (xy 97.949004 -388.617968) (xy 97.9266 -388.60995) (xy 97.884401 -388.587966)
			(xy 97.846122 -388.559703) (xy 97.812689 -388.525846) (xy 97.784912 -388.487214) (xy 97.763461 -388.444741)
			(xy 97.748857 -388.399455) (xy 97.741453 -388.352453) (xy 97.740978 -388.328662) (xy 97.741477 -388.303264)
			(xy 97.749877 -388.253167) (xy 97.766453 -388.205151) (xy 97.79075 -388.160543) (xy 97.822097 -388.120572)
			(xy 97.840546 -388.10311) (xy 97.848928 -388.09549) (xy 97.857564 -388.075424) (xy 97.85477 -387.97611)
			(xy 97.845372 -387.956552) (xy 97.836482 -387.94944) (xy 97.817922 -387.933637) (xy 97.785197 -387.89751)
			(xy 97.758125 -387.856973) (xy 97.737294 -387.812903) (xy 97.723152 -387.766254) (xy 97.716007 -387.718035)
			(xy 97.715578 -387.693662) (xy 97.716017 -387.669546) (xy 97.723022 -387.621825) (xy 97.736879 -387.575627)
			(xy 97.757293 -387.531928) (xy 97.770188 -387.511544) (xy 97.77603 -387.502654) (xy 97.779586 -387.482588)
			(xy 97.758504 -387.390386) (xy 97.746312 -387.373622) (xy 97.737422 -387.368288) (xy 97.716622 -387.355431)
			(xy 97.678708 -387.324551) (xy 97.64576 -387.28842) (xy 97.618499 -387.247826) (xy 97.597519 -387.203657)
			(xy 97.58328 -387.156878) (xy 97.576092 -387.108511) (xy 97.575624 -387.084062) (xy 97.576185 -387.05678)
			(xy 97.585147 -387.002956) (xy 97.60282 -386.951333) (xy 97.628726 -386.90331) (xy 97.662162 -386.86019)
			(xy 97.681796 -386.841238) (xy 97.689245 -386.833746) (xy 97.697789 -386.814451) (xy 97.698306 -386.8039)
			(xy 97.698306 -386.729224) (xy 97.69772 -386.718689) (xy 97.689193 -386.699412) (xy 97.681796 -386.691886)
			(xy 97.662138 -386.672955) (xy 97.62869 -386.629836) (xy 97.602777 -386.581809) (xy 97.585103 -386.530179)
			(xy 97.576147 -386.476348) (xy 97.575624 -386.449062) (xy 97.575878 -386.43687) (xy 97.576132 -386.427218)
			(xy 97.570036 -386.409184) (xy 97.511362 -386.341874) (xy 97.494598 -386.333238) (xy 97.484692 -386.332222)
			(xy 97.457777 -386.328873) (xy 97.405473 -386.314532) (xy 97.356212 -386.291847) (xy 97.311313 -386.261425)
			(xy 97.271983 -386.224083) (xy 97.239274 -386.180822) (xy 97.214066 -386.132802) (xy 97.197033 -386.081312)
			(xy 97.192338 -386.0546) (xy 97.190814 -386.045202) (xy 96.917764 -385.572762) (xy 96.910652 -385.56692)
			(xy 96.89192 -385.55114) (xy 96.858867 -385.514995) (xy 96.83151 -385.47437) (xy 96.810447 -385.430152)
			(xy 96.796139 -385.38331) (xy 96.7889 -385.334869) (xy 96.788478 -385.31038) (xy 96.788989 -385.284393)
			(xy 96.797122 -385.233061) (xy 96.813185 -385.183632) (xy 96.836781 -385.137324) (xy 96.867331 -385.095277)
			(xy 96.904082 -385.058527) (xy 96.946129 -385.027978) (xy 96.992437 -385.004382) (xy 97.041866 -384.988321)
			(xy 97.093199 -384.980189) (xy 97.119186 -384.979672) (xy 97.145235 -384.980151) (xy 97.19669 -384.988301)
			(xy 97.246232 -385.004417) (xy 97.292634 -385.028101) (xy 97.334749 -385.058768) (xy 97.371536 -385.095657)
			(xy 97.402084 -385.137858) (xy 97.425638 -385.184327) (xy 97.441615 -385.233913) (xy 97.446084 -385.25958)
			(xy 97.447354 -385.268978) (xy 97.719896 -385.740402) (xy 97.727262 -385.746244) (xy 97.746042 -385.762047)
			(xy 97.779179 -385.798253) (xy 97.806602 -385.838957) (xy 97.827711 -385.883266) (xy 97.842042 -385.930208)
			(xy 97.849279 -385.978752) (xy 97.84969 -386.003292) (xy 97.849436 -386.015484) (xy 97.849182 -386.025136)
			(xy 97.855278 -386.04317) (xy 97.913952 -386.11048) (xy 97.930716 -386.119116) (xy 97.940622 -386.120132)
			(xy 97.967389 -386.12346) (xy 98.019414 -386.137686) (xy 98.068442 -386.160165) (xy 98.113173 -386.190301)
			(xy 98.152422 -386.227295) (xy 98.185148 -386.270167) (xy 98.210485 -386.317781) (xy 98.227761 -386.368875)
			(xy 98.236518 -386.422094) (xy 98.23704 -386.449062) (xy 98.236477 -386.476344) (xy 98.227514 -386.530167)
			(xy 98.20984 -386.58179) (xy 98.183936 -386.629813) (xy 98.150502 -386.672935) (xy 98.130868 -386.691886)
			(xy 98.123427 -386.699381) (xy 98.114899 -386.718676) (xy 98.114358 -386.729224) (xy 98.114358 -386.8039)
			(xy 98.11495 -386.814432) (xy 98.123491 -386.833695) (xy 98.130868 -386.841238) (xy 98.150521 -386.860172)
			(xy 98.18396 -386.903293) (xy 98.209864 -386.951321) (xy 98.227531 -387.002949) (xy 98.236481 -387.056778)
			(xy 98.23704 -387.084062) (xy 98.236607 -387.10818) (xy 98.229612 -387.155905) (xy 98.215765 -387.20211)
			(xy 98.195359 -387.245816) (xy 98.18243 -387.26618) (xy 98.176588 -387.27507) (xy 98.173032 -387.295136)
			(xy 98.194114 -387.387338) (xy 98.206306 -387.404102) (xy 98.215196 -387.409436) (xy 98.231432 -387.419374)
			(xy 98.261733 -387.442419) (xy 98.275648 -387.45541) (xy 98.286824 -387.466078) (xy 98.316796 -387.471666)
			(xy 98.416872 -387.429248) (xy 98.42587 -387.42491) (xy 98.439887 -387.410708) (xy 98.447437 -387.392237)
			(xy 98.44786 -387.382258) (xy 98.44786 -386.207762) (xy 98.447609 -386.200582) (xy 98.443605 -386.186791)
			(xy 98.439986 -386.180584) (xy 98.428173 -386.161303) (xy 98.40936 -386.120184) (xy 98.396342 -386.076881)
			(xy 98.392488 -386.0546) (xy 98.390964 -386.045202) (xy 98.118168 -385.57327) (xy 98.110802 -385.567428)
			(xy 98.092025 -385.551623) (xy 98.058895 -385.515415) (xy 98.031478 -385.47471) (xy 98.010375 -385.430401)
			(xy 97.99605 -385.383461) (xy 97.988817 -385.334919) (xy 97.988374 -385.31038) (xy 97.988742 -385.287432)
			(xy 97.995049 -385.241972) (xy 98.007595 -385.197824) (xy 98.026136 -385.15584) (xy 98.037904 -385.136136)
			(xy 98.047302 -385.120896) (xy 98.043238 -385.086098) (xy 97.89033 -384.93319) (xy 97.879662 -384.92938)
			(xy 97.856702 -384.920765) (xy 97.813412 -384.897729) (xy 97.773999 -384.868552) (xy 97.739326 -384.833876)
			(xy 97.710154 -384.794459) (xy 97.687122 -384.751167) (xy 97.678494 -384.728212) (xy 97.674684 -384.717544)
			(xy 96.829626 -383.872486) (xy 96.822228 -383.865642) (xy 96.803628 -383.857921) (xy 96.793558 -383.8575)
			(xy 77.968602 -383.8575) (xy 77.958532 -383.857923) (xy 77.939927 -383.865637) (xy 77.932534 -383.872486)
			(xy 77.863954 -383.941066) (xy 77.857119 -383.948433) (xy 77.849386 -383.966965) (xy 77.849388 -383.987045)
			(xy 77.857125 -384.005575) (xy 77.863954 -384.012948) (xy 77.871828 -384.020822) (xy 77.892656 -384.028442)
			(xy 77.903832 -384.02768) (xy 77.928978 -384.026664) (xy 77.954971 -384.027146) (xy 78.006316 -384.035275)
			(xy 78.055758 -384.051336) (xy 78.102078 -384.074935) (xy 78.144136 -384.105489) (xy 78.180896 -384.142247)
			(xy 78.211453 -384.184303) (xy 78.235055 -384.230622) (xy 78.25112 -384.280062) (xy 78.259253 -384.331407)
			(xy 78.259253 -384.383393) (xy 78.25112 -384.434738) (xy 78.235055 -384.484178) (xy 78.211453 -384.530497)
			(xy 78.180896 -384.572553) (xy 78.144136 -384.609311) (xy 78.102078 -384.639865) (xy 78.094533 -384.643709)
			(xy 79.65999 -384.643709) (xy 79.65999 -384.591735) (xy 79.66812 -384.5404) (xy 79.684181 -384.49097)
			(xy 79.707777 -384.44466) (xy 79.738327 -384.402612) (xy 79.775078 -384.365861) (xy 79.817126 -384.335311)
			(xy 79.863436 -384.311715) (xy 79.912866 -384.295654) (xy 79.964201 -384.287524) (xy 80.016175 -384.287524)
			(xy 80.06751 -384.295654) (xy 80.11694 -384.311715) (xy 80.16325 -384.335311) (xy 80.205298 -384.365861)
			(xy 80.242049 -384.402612) (xy 80.272599 -384.44466) (xy 80.296195 -384.49097) (xy 80.312256 -384.5404)
			(xy 80.320386 -384.591735) (xy 80.320896 -384.617722) (xy 80.320386 -384.643709) (xy 80.859886 -384.643709)
			(xy 80.859886 -384.591735) (xy 80.868016 -384.5404) (xy 80.884077 -384.49097) (xy 80.907673 -384.44466)
			(xy 80.938223 -384.402612) (xy 80.974974 -384.365861) (xy 81.017022 -384.335311) (xy 81.063332 -384.311715)
			(xy 81.112762 -384.295654) (xy 81.164097 -384.287524) (xy 81.216071 -384.287524) (xy 81.267406 -384.295654)
			(xy 81.316836 -384.311715) (xy 81.363146 -384.335311) (xy 81.405194 -384.365861) (xy 81.441945 -384.402612)
			(xy 81.472495 -384.44466) (xy 81.496091 -384.49097) (xy 81.512152 -384.5404) (xy 81.520282 -384.591735)
			(xy 81.520792 -384.617722) (xy 81.520282 -384.643709) (xy 82.060036 -384.643709) (xy 82.060036 -384.591735)
			(xy 82.068166 -384.5404) (xy 82.084227 -384.49097) (xy 82.107823 -384.44466) (xy 82.138373 -384.402612)
			(xy 82.175124 -384.365861) (xy 82.217172 -384.335311) (xy 82.263482 -384.311715) (xy 82.312912 -384.295654)
			(xy 82.364247 -384.287524) (xy 82.416221 -384.287524) (xy 82.467556 -384.295654) (xy 82.516986 -384.311715)
			(xy 82.563296 -384.335311) (xy 82.605344 -384.365861) (xy 82.642095 -384.402612) (xy 82.672645 -384.44466)
			(xy 82.696241 -384.49097) (xy 82.712302 -384.5404) (xy 82.720432 -384.591735) (xy 82.720942 -384.617722)
			(xy 82.720432 -384.643709) (xy 83.259932 -384.643709) (xy 83.259932 -384.591735) (xy 83.268062 -384.5404)
			(xy 83.284123 -384.49097) (xy 83.307719 -384.44466) (xy 83.338269 -384.402612) (xy 83.37502 -384.365861)
			(xy 83.417068 -384.335311) (xy 83.463378 -384.311715) (xy 83.512808 -384.295654) (xy 83.564143 -384.287524)
			(xy 83.616117 -384.287524) (xy 83.667452 -384.295654) (xy 83.716882 -384.311715) (xy 83.763192 -384.335311)
			(xy 83.80524 -384.365861) (xy 83.841991 -384.402612) (xy 83.872541 -384.44466) (xy 83.896137 -384.49097)
			(xy 83.912198 -384.5404) (xy 83.920328 -384.591735) (xy 83.920838 -384.617722) (xy 83.920328 -384.643709)
			(xy 84.460082 -384.643709) (xy 84.460082 -384.591735) (xy 84.468212 -384.5404) (xy 84.484273 -384.49097)
			(xy 84.507869 -384.44466) (xy 84.538419 -384.402612) (xy 84.57517 -384.365861) (xy 84.617218 -384.335311)
			(xy 84.663528 -384.311715) (xy 84.712958 -384.295654) (xy 84.764293 -384.287524) (xy 84.816267 -384.287524)
			(xy 84.867602 -384.295654) (xy 84.917032 -384.311715) (xy 84.963342 -384.335311) (xy 85.00539 -384.365861)
			(xy 85.042141 -384.402612) (xy 85.072691 -384.44466) (xy 85.096287 -384.49097) (xy 85.112348 -384.5404)
			(xy 85.120478 -384.591735) (xy 85.120988 -384.617722) (xy 85.120478 -384.643709) (xy 85.659978 -384.643709)
			(xy 85.659978 -384.591735) (xy 85.668108 -384.5404) (xy 85.684169 -384.49097) (xy 85.707765 -384.44466)
			(xy 85.738315 -384.402612) (xy 85.775066 -384.365861) (xy 85.817114 -384.335311) (xy 85.863424 -384.311715)
			(xy 85.912854 -384.295654) (xy 85.964189 -384.287524) (xy 86.016163 -384.287524) (xy 86.067498 -384.295654)
			(xy 86.116928 -384.311715) (xy 86.163238 -384.335311) (xy 86.205286 -384.365861) (xy 86.242037 -384.402612)
			(xy 86.272587 -384.44466) (xy 86.296183 -384.49097) (xy 86.312244 -384.5404) (xy 86.320374 -384.591735)
			(xy 86.320884 -384.617722) (xy 86.320374 -384.643709) (xy 86.859874 -384.643709) (xy 86.859874 -384.591735)
			(xy 86.868004 -384.5404) (xy 86.884065 -384.49097) (xy 86.907661 -384.44466) (xy 86.938211 -384.402612)
			(xy 86.974962 -384.365861) (xy 87.01701 -384.335311) (xy 87.06332 -384.311715) (xy 87.11275 -384.295654)
			(xy 87.164085 -384.287524) (xy 87.216059 -384.287524) (xy 87.267394 -384.295654) (xy 87.316824 -384.311715)
			(xy 87.363134 -384.335311) (xy 87.405182 -384.365861) (xy 87.441933 -384.402612) (xy 87.472483 -384.44466)
			(xy 87.496079 -384.49097) (xy 87.51214 -384.5404) (xy 87.52027 -384.591735) (xy 87.52078 -384.617722)
			(xy 87.52027 -384.643709) (xy 88.060024 -384.643709) (xy 88.060024 -384.591735) (xy 88.068154 -384.5404)
			(xy 88.084215 -384.49097) (xy 88.107811 -384.44466) (xy 88.138361 -384.402612) (xy 88.175112 -384.365861)
			(xy 88.21716 -384.335311) (xy 88.26347 -384.311715) (xy 88.3129 -384.295654) (xy 88.364235 -384.287524)
			(xy 88.416209 -384.287524) (xy 88.467544 -384.295654) (xy 88.516974 -384.311715) (xy 88.563284 -384.335311)
			(xy 88.605332 -384.365861) (xy 88.642083 -384.402612) (xy 88.672633 -384.44466) (xy 88.696229 -384.49097)
			(xy 88.71229 -384.5404) (xy 88.72042 -384.591735) (xy 88.72093 -384.617722) (xy 88.72042 -384.643709)
			(xy 89.25992 -384.643709) (xy 89.25992 -384.591735) (xy 89.26805 -384.5404) (xy 89.284111 -384.49097)
			(xy 89.307707 -384.44466) (xy 89.338257 -384.402612) (xy 89.375008 -384.365861) (xy 89.417056 -384.335311)
			(xy 89.463366 -384.311715) (xy 89.512796 -384.295654) (xy 89.564131 -384.287524) (xy 89.616105 -384.287524)
			(xy 89.66744 -384.295654) (xy 89.71687 -384.311715) (xy 89.76318 -384.335311) (xy 89.805228 -384.365861)
			(xy 89.841979 -384.402612) (xy 89.872529 -384.44466) (xy 89.896125 -384.49097) (xy 89.912186 -384.5404)
			(xy 89.920316 -384.591735) (xy 89.920826 -384.617722) (xy 89.920316 -384.643709) (xy 90.46007 -384.643709)
			(xy 90.46007 -384.591735) (xy 90.4682 -384.5404) (xy 90.484261 -384.49097) (xy 90.507857 -384.44466)
			(xy 90.538407 -384.402612) (xy 90.575158 -384.365861) (xy 90.617206 -384.335311) (xy 90.663516 -384.311715)
			(xy 90.712946 -384.295654) (xy 90.764281 -384.287524) (xy 90.816255 -384.287524) (xy 90.86759 -384.295654)
			(xy 90.91702 -384.311715) (xy 90.96333 -384.335311) (xy 91.005378 -384.365861) (xy 91.042129 -384.402612)
			(xy 91.072679 -384.44466) (xy 91.096275 -384.49097) (xy 91.112336 -384.5404) (xy 91.120466 -384.591735)
			(xy 91.120976 -384.617722) (xy 91.120466 -384.643709) (xy 91.659966 -384.643709) (xy 91.659966 -384.591735)
			(xy 91.668096 -384.5404) (xy 91.684157 -384.49097) (xy 91.707753 -384.44466) (xy 91.738303 -384.402612)
			(xy 91.775054 -384.365861) (xy 91.817102 -384.335311) (xy 91.863412 -384.311715) (xy 91.912842 -384.295654)
			(xy 91.964177 -384.287524) (xy 92.016151 -384.287524) (xy 92.067486 -384.295654) (xy 92.116916 -384.311715)
			(xy 92.163226 -384.335311) (xy 92.205274 -384.365861) (xy 92.242025 -384.402612) (xy 92.272575 -384.44466)
			(xy 92.296171 -384.49097) (xy 92.312232 -384.5404) (xy 92.320362 -384.591735) (xy 92.320872 -384.617722)
			(xy 92.320362 -384.643709) (xy 92.859862 -384.643709) (xy 92.859862 -384.591735) (xy 92.867992 -384.5404)
			(xy 92.884053 -384.49097) (xy 92.907649 -384.44466) (xy 92.938199 -384.402612) (xy 92.97495 -384.365861)
			(xy 93.016998 -384.335311) (xy 93.063308 -384.311715) (xy 93.112738 -384.295654) (xy 93.164073 -384.287524)
			(xy 93.216047 -384.287524) (xy 93.267382 -384.295654) (xy 93.316812 -384.311715) (xy 93.363122 -384.335311)
			(xy 93.40517 -384.365861) (xy 93.441921 -384.402612) (xy 93.472471 -384.44466) (xy 93.496067 -384.49097)
			(xy 93.512128 -384.5404) (xy 93.520258 -384.591735) (xy 93.520768 -384.617722) (xy 93.520258 -384.643709)
			(xy 94.060012 -384.643709) (xy 94.060012 -384.591735) (xy 94.068142 -384.5404) (xy 94.084203 -384.49097)
			(xy 94.107799 -384.44466) (xy 94.138349 -384.402612) (xy 94.1751 -384.365861) (xy 94.217148 -384.335311)
			(xy 94.263458 -384.311715) (xy 94.312888 -384.295654) (xy 94.364223 -384.287524) (xy 94.416197 -384.287524)
			(xy 94.467532 -384.295654) (xy 94.516962 -384.311715) (xy 94.563272 -384.335311) (xy 94.60532 -384.365861)
			(xy 94.642071 -384.402612) (xy 94.672621 -384.44466) (xy 94.696217 -384.49097) (xy 94.712278 -384.5404)
			(xy 94.720408 -384.591735) (xy 94.720918 -384.617722) (xy 94.720408 -384.643709) (xy 95.259908 -384.643709)
			(xy 95.259908 -384.591735) (xy 95.268038 -384.5404) (xy 95.284099 -384.49097) (xy 95.307695 -384.44466)
			(xy 95.338245 -384.402612) (xy 95.374996 -384.365861) (xy 95.417044 -384.335311) (xy 95.463354 -384.311715)
			(xy 95.512784 -384.295654) (xy 95.564119 -384.287524) (xy 95.616093 -384.287524) (xy 95.667428 -384.295654)
			(xy 95.716858 -384.311715) (xy 95.763168 -384.335311) (xy 95.805216 -384.365861) (xy 95.841967 -384.402612)
			(xy 95.872517 -384.44466) (xy 95.896113 -384.49097) (xy 95.912174 -384.5404) (xy 95.920304 -384.591735)
			(xy 95.920814 -384.617722) (xy 95.920304 -384.643709) (xy 96.460058 -384.643709) (xy 96.460058 -384.591735)
			(xy 96.468188 -384.5404) (xy 96.484249 -384.49097) (xy 96.507845 -384.44466) (xy 96.538395 -384.402612)
			(xy 96.575146 -384.365861) (xy 96.617194 -384.335311) (xy 96.663504 -384.311715) (xy 96.712934 -384.295654)
			(xy 96.764269 -384.287524) (xy 96.816243 -384.287524) (xy 96.867578 -384.295654) (xy 96.917008 -384.311715)
			(xy 96.963318 -384.335311) (xy 97.005366 -384.365861) (xy 97.042117 -384.402612) (xy 97.072667 -384.44466)
			(xy 97.096263 -384.49097) (xy 97.112324 -384.5404) (xy 97.120454 -384.591735) (xy 97.120964 -384.617722)
			(xy 97.120454 -384.643709) (xy 97.112324 -384.695044) (xy 97.096263 -384.744474) (xy 97.072667 -384.790784)
			(xy 97.042117 -384.832832) (xy 97.005366 -384.869583) (xy 96.963318 -384.900133) (xy 96.917008 -384.923729)
			(xy 96.867578 -384.93979) (xy 96.816243 -384.94792) (xy 96.764269 -384.94792) (xy 96.712934 -384.93979)
			(xy 96.663504 -384.923729) (xy 96.617194 -384.900133) (xy 96.575146 -384.869583) (xy 96.538395 -384.832832)
			(xy 96.507845 -384.790784) (xy 96.484249 -384.744474) (xy 96.468188 -384.695044) (xy 96.460058 -384.643709)
			(xy 95.920304 -384.643709) (xy 95.912174 -384.695044) (xy 95.896113 -384.744474) (xy 95.872517 -384.790784)
			(xy 95.841967 -384.832832) (xy 95.805216 -384.869583) (xy 95.763168 -384.900133) (xy 95.716858 -384.923729)
			(xy 95.667428 -384.93979) (xy 95.616093 -384.94792) (xy 95.564119 -384.94792) (xy 95.512784 -384.93979)
			(xy 95.463354 -384.923729) (xy 95.417044 -384.900133) (xy 95.374996 -384.869583) (xy 95.338245 -384.832832)
			(xy 95.307695 -384.790784) (xy 95.284099 -384.744474) (xy 95.268038 -384.695044) (xy 95.259908 -384.643709)
			(xy 94.720408 -384.643709) (xy 94.712278 -384.695044) (xy 94.696217 -384.744474) (xy 94.672621 -384.790784)
			(xy 94.642071 -384.832832) (xy 94.60532 -384.869583) (xy 94.563272 -384.900133) (xy 94.516962 -384.923729)
			(xy 94.467532 -384.93979) (xy 94.416197 -384.94792) (xy 94.364223 -384.94792) (xy 94.312888 -384.93979)
			(xy 94.263458 -384.923729) (xy 94.217148 -384.900133) (xy 94.1751 -384.869583) (xy 94.138349 -384.832832)
			(xy 94.107799 -384.790784) (xy 94.084203 -384.744474) (xy 94.068142 -384.695044) (xy 94.060012 -384.643709)
			(xy 93.520258 -384.643709) (xy 93.512128 -384.695044) (xy 93.496067 -384.744474) (xy 93.472471 -384.790784)
			(xy 93.441921 -384.832832) (xy 93.40517 -384.869583) (xy 93.363122 -384.900133) (xy 93.316812 -384.923729)
			(xy 93.267382 -384.93979) (xy 93.216047 -384.94792) (xy 93.164073 -384.94792) (xy 93.112738 -384.93979)
			(xy 93.063308 -384.923729) (xy 93.016998 -384.900133) (xy 92.97495 -384.869583) (xy 92.938199 -384.832832)
			(xy 92.907649 -384.790784) (xy 92.884053 -384.744474) (xy 92.867992 -384.695044) (xy 92.859862 -384.643709)
			(xy 92.320362 -384.643709) (xy 92.312232 -384.695044) (xy 92.296171 -384.744474) (xy 92.272575 -384.790784)
			(xy 92.242025 -384.832832) (xy 92.205274 -384.869583) (xy 92.163226 -384.900133) (xy 92.116916 -384.923729)
			(xy 92.067486 -384.93979) (xy 92.016151 -384.94792) (xy 91.964177 -384.94792) (xy 91.912842 -384.93979)
			(xy 91.863412 -384.923729) (xy 91.817102 -384.900133) (xy 91.775054 -384.869583) (xy 91.738303 -384.832832)
			(xy 91.707753 -384.790784) (xy 91.684157 -384.744474) (xy 91.668096 -384.695044) (xy 91.659966 -384.643709)
			(xy 91.120466 -384.643709) (xy 91.112336 -384.695044) (xy 91.096275 -384.744474) (xy 91.072679 -384.790784)
			(xy 91.042129 -384.832832) (xy 91.005378 -384.869583) (xy 90.96333 -384.900133) (xy 90.91702 -384.923729)
			(xy 90.86759 -384.93979) (xy 90.816255 -384.94792) (xy 90.764281 -384.94792) (xy 90.712946 -384.93979)
			(xy 90.663516 -384.923729) (xy 90.617206 -384.900133) (xy 90.575158 -384.869583) (xy 90.538407 -384.832832)
			(xy 90.507857 -384.790784) (xy 90.484261 -384.744474) (xy 90.4682 -384.695044) (xy 90.46007 -384.643709)
			(xy 89.920316 -384.643709) (xy 89.912186 -384.695044) (xy 89.896125 -384.744474) (xy 89.872529 -384.790784)
			(xy 89.841979 -384.832832) (xy 89.805228 -384.869583) (xy 89.76318 -384.900133) (xy 89.71687 -384.923729)
			(xy 89.66744 -384.93979) (xy 89.616105 -384.94792) (xy 89.564131 -384.94792) (xy 89.512796 -384.93979)
			(xy 89.463366 -384.923729) (xy 89.417056 -384.900133) (xy 89.375008 -384.869583) (xy 89.338257 -384.832832)
			(xy 89.307707 -384.790784) (xy 89.284111 -384.744474) (xy 89.26805 -384.695044) (xy 89.25992 -384.643709)
			(xy 88.72042 -384.643709) (xy 88.71229 -384.695044) (xy 88.696229 -384.744474) (xy 88.672633 -384.790784)
			(xy 88.642083 -384.832832) (xy 88.605332 -384.869583) (xy 88.563284 -384.900133) (xy 88.516974 -384.923729)
			(xy 88.467544 -384.93979) (xy 88.416209 -384.94792) (xy 88.364235 -384.94792) (xy 88.3129 -384.93979)
			(xy 88.26347 -384.923729) (xy 88.21716 -384.900133) (xy 88.175112 -384.869583) (xy 88.138361 -384.832832)
			(xy 88.107811 -384.790784) (xy 88.084215 -384.744474) (xy 88.068154 -384.695044) (xy 88.060024 -384.643709)
			(xy 87.52027 -384.643709) (xy 87.51214 -384.695044) (xy 87.496079 -384.744474) (xy 87.472483 -384.790784)
			(xy 87.441933 -384.832832) (xy 87.405182 -384.869583) (xy 87.363134 -384.900133) (xy 87.316824 -384.923729)
			(xy 87.267394 -384.93979) (xy 87.216059 -384.94792) (xy 87.164085 -384.94792) (xy 87.11275 -384.93979)
			(xy 87.06332 -384.923729) (xy 87.01701 -384.900133) (xy 86.974962 -384.869583) (xy 86.938211 -384.832832)
			(xy 86.907661 -384.790784) (xy 86.884065 -384.744474) (xy 86.868004 -384.695044) (xy 86.859874 -384.643709)
			(xy 86.320374 -384.643709) (xy 86.312244 -384.695044) (xy 86.296183 -384.744474) (xy 86.272587 -384.790784)
			(xy 86.242037 -384.832832) (xy 86.205286 -384.869583) (xy 86.163238 -384.900133) (xy 86.116928 -384.923729)
			(xy 86.067498 -384.93979) (xy 86.016163 -384.94792) (xy 85.964189 -384.94792) (xy 85.912854 -384.93979)
			(xy 85.863424 -384.923729) (xy 85.817114 -384.900133) (xy 85.775066 -384.869583) (xy 85.738315 -384.832832)
			(xy 85.707765 -384.790784) (xy 85.684169 -384.744474) (xy 85.668108 -384.695044) (xy 85.659978 -384.643709)
			(xy 85.120478 -384.643709) (xy 85.112348 -384.695044) (xy 85.096287 -384.744474) (xy 85.072691 -384.790784)
			(xy 85.042141 -384.832832) (xy 85.00539 -384.869583) (xy 84.963342 -384.900133) (xy 84.917032 -384.923729)
			(xy 84.867602 -384.93979) (xy 84.816267 -384.94792) (xy 84.764293 -384.94792) (xy 84.712958 -384.93979)
			(xy 84.663528 -384.923729) (xy 84.617218 -384.900133) (xy 84.57517 -384.869583) (xy 84.538419 -384.832832)
			(xy 84.507869 -384.790784) (xy 84.484273 -384.744474) (xy 84.468212 -384.695044) (xy 84.460082 -384.643709)
			(xy 83.920328 -384.643709) (xy 83.912198 -384.695044) (xy 83.896137 -384.744474) (xy 83.872541 -384.790784)
			(xy 83.841991 -384.832832) (xy 83.80524 -384.869583) (xy 83.763192 -384.900133) (xy 83.716882 -384.923729)
			(xy 83.667452 -384.93979) (xy 83.616117 -384.94792) (xy 83.564143 -384.94792) (xy 83.512808 -384.93979)
			(xy 83.463378 -384.923729) (xy 83.417068 -384.900133) (xy 83.37502 -384.869583) (xy 83.338269 -384.832832)
			(xy 83.307719 -384.790784) (xy 83.284123 -384.744474) (xy 83.268062 -384.695044) (xy 83.259932 -384.643709)
			(xy 82.720432 -384.643709) (xy 82.712302 -384.695044) (xy 82.696241 -384.744474) (xy 82.672645 -384.790784)
			(xy 82.642095 -384.832832) (xy 82.605344 -384.869583) (xy 82.563296 -384.900133) (xy 82.516986 -384.923729)
			(xy 82.467556 -384.93979) (xy 82.416221 -384.94792) (xy 82.364247 -384.94792) (xy 82.312912 -384.93979)
			(xy 82.263482 -384.923729) (xy 82.217172 -384.900133) (xy 82.175124 -384.869583) (xy 82.138373 -384.832832)
			(xy 82.107823 -384.790784) (xy 82.084227 -384.744474) (xy 82.068166 -384.695044) (xy 82.060036 -384.643709)
			(xy 81.520282 -384.643709) (xy 81.512152 -384.695044) (xy 81.496091 -384.744474) (xy 81.472495 -384.790784)
			(xy 81.441945 -384.832832) (xy 81.405194 -384.869583) (xy 81.363146 -384.900133) (xy 81.316836 -384.923729)
			(xy 81.267406 -384.93979) (xy 81.216071 -384.94792) (xy 81.164097 -384.94792) (xy 81.112762 -384.93979)
			(xy 81.063332 -384.923729) (xy 81.017022 -384.900133) (xy 80.974974 -384.869583) (xy 80.938223 -384.832832)
			(xy 80.907673 -384.790784) (xy 80.884077 -384.744474) (xy 80.868016 -384.695044) (xy 80.859886 -384.643709)
			(xy 80.320386 -384.643709) (xy 80.312256 -384.695044) (xy 80.296195 -384.744474) (xy 80.272599 -384.790784)
			(xy 80.242049 -384.832832) (xy 80.205298 -384.869583) (xy 80.16325 -384.900133) (xy 80.11694 -384.923729)
			(xy 80.06751 -384.93979) (xy 80.016175 -384.94792) (xy 79.964201 -384.94792) (xy 79.912866 -384.93979)
			(xy 79.863436 -384.923729) (xy 79.817126 -384.900133) (xy 79.775078 -384.869583) (xy 79.738327 -384.832832)
			(xy 79.707777 -384.790784) (xy 79.684181 -384.744474) (xy 79.66812 -384.695044) (xy 79.65999 -384.643709)
			(xy 78.094533 -384.643709) (xy 78.055758 -384.663464) (xy 78.006316 -384.679525) (xy 77.954971 -384.687654)
			(xy 77.928978 -384.68808) (xy 77.903786 -384.687605) (xy 77.853987 -384.679959) (xy 77.805924 -384.664847)
			(xy 77.760709 -384.642618) (xy 77.71939 -384.613788) (xy 77.682922 -384.579024) (xy 77.65215 -384.539129)
			(xy 77.627787 -384.495029) (xy 77.610395 -384.447743) (xy 77.604874 -384.423158) (xy 77.60208 -384.409442)
			(xy 77.583284 -384.388614) (xy 77.48397 -384.358896) (xy 77.475096 -384.356593) (xy 77.456816 -384.357779)
			(xy 77.440136 -384.365354) (xy 77.433424 -384.371596) (xy 77.431646 -384.373374) (xy 77.424246 -384.380215)
			(xy 77.405647 -384.387933) (xy 77.395578 -384.38836) (xy 77.044804 -384.38836) (xy 77.032388 -384.388979)
			(xy 77.010427 -384.400568) (xy 77.002894 -384.410458) (xy 76.948284 -384.489706) (xy 76.94549 -384.514344)
			(xy 76.950062 -384.526282) (xy 76.958034 -384.548128) (xy 76.969226 -384.593265) (xy 76.974859 -384.639428)
			(xy 76.975208 -384.66268) (xy 76.974722 -384.689931) (xy 76.966966 -384.743879) (xy 76.951611 -384.796174)
			(xy 76.928969 -384.845751) (xy 76.899503 -384.891601) (xy 76.863812 -384.932792) (xy 76.822621 -384.968483)
			(xy 76.776771 -384.997949) (xy 76.727194 -385.020591) (xy 76.674899 -385.035946) (xy 76.620951 -385.043702)
			(xy 76.566449 -385.043702) (xy 76.512501 -385.035946) (xy 76.460206 -385.020591) (xy 76.410629 -384.997949)
			(xy 76.364779 -384.968483) (xy 76.323588 -384.932792) (xy 76.287897 -384.891601) (xy 76.258431 -384.845751)
			(xy 76.235789 -384.796174) (xy 76.220434 -384.743879) (xy 76.212678 -384.689931) (xy 76.212192 -384.66268)
			(xy 76.212524 -384.639427) (xy 76.218155 -384.593263) (xy 76.229367 -384.548129) (xy 76.237338 -384.526282)
			(xy 76.24191 -384.514344) (xy 76.239116 -384.489706) (xy 76.184506 -384.410458) (xy 76.176977 -384.400569)
			(xy 76.15501 -384.388999) (xy 76.142596 -384.38836) (xy 75.906884 -384.38836) (xy 75.896816 -384.388788)
			(xy 75.878222 -384.396513) (xy 75.870816 -384.403346) (xy 75.710034 -384.564128) (xy 75.687243 -384.586328)
			(xy 75.637513 -384.626016) (xy 75.583651 -384.659885) (xy 75.526335 -384.687509) (xy 75.466286 -384.70854)
			(xy 75.404259 -384.722714) (xy 75.341035 -384.729853) (xy 75.309222 -384.730244) (xy 73.342246 -384.730244)
			(xy 73.310433 -384.729816) (xy 73.247208 -384.722693) (xy 73.185179 -384.708531) (xy 73.125127 -384.687509)
			(xy 73.067808 -384.659891) (xy 73.013944 -384.626025) (xy 72.964214 -384.586338) (xy 72.941434 -384.564128)
			(xy 72.780652 -384.403346) (xy 72.773253 -384.396502) (xy 72.754654 -384.388778) (xy 72.744584 -384.38836)
			(xy 72.714104 -384.38836) (xy 72.701772 -384.388943) (xy 72.679921 -384.400379) (xy 72.672448 -384.410204)
			(xy 72.617584 -384.488944) (xy 72.614536 -384.513582) (xy 72.618854 -384.525266) (xy 72.628914 -384.553685)
			(xy 72.643046 -384.612293) (xy 72.650162 -384.67216) (xy 72.650604 -384.702304) (xy 72.650102 -384.734265)
			(xy 72.642091 -384.797683) (xy 72.626194 -384.859597) (xy 72.602662 -384.91903) (xy 72.571868 -384.975045)
			(xy 72.534295 -385.02676) (xy 72.490538 -385.073357) (xy 72.441285 -385.114102) (xy 72.387314 -385.148353)
			(xy 72.329475 -385.17557) (xy 72.268682 -385.195323) (xy 72.205892 -385.207301) (xy 72.142096 -385.211315)
			(xy 72.0783 -385.207301) (xy 72.01551 -385.195323) (xy 71.954717 -385.17557) (xy 71.896878 -385.148353)
			(xy 71.842907 -385.114102) (xy 71.793654 -385.073357) (xy 71.749897 -385.02676) (xy 71.712324 -384.975045)
			(xy 71.68153 -384.91903) (xy 71.657998 -384.859597) (xy 71.642101 -384.797683) (xy 71.63409 -384.734265)
			(xy 71.633588 -384.702304) (xy 71.634001 -384.672158) (xy 71.641107 -384.612287) (xy 71.655255 -384.553679)
			(xy 71.665338 -384.525266) (xy 71.669656 -384.513582) (xy 71.666608 -384.488944) (xy 71.611744 -384.410204)
			(xy 71.604129 -384.400539) (xy 71.582369 -384.389137) (xy 71.570088 -384.38836) (xy 71.497952 -384.38836)
			(xy 71.47687 -384.399028) (xy 71.469504 -384.40868) (xy 71.445735 -384.439223) (xy 71.390502 -384.493433)
			(xy 71.359522 -384.51663) (xy 71.350098 -384.524291) (xy 71.339098 -384.545904) (xy 71.33844 -384.558032)
			(xy 71.33844 -384.640328) (xy 71.339072 -384.652459) (xy 71.350095 -384.674065) (xy 71.359522 -384.68173)
			(xy 71.383701 -384.699677) (xy 71.428082 -384.740375) (xy 71.467347 -384.786029) (xy 71.500948 -384.835999)
			(xy 71.528413 -384.889588) (xy 71.54936 -384.946044) (xy 71.563493 -385.004578) (xy 71.570617 -385.064372)
			(xy 71.571104 -385.09448) (xy 71.570645 -385.125139) (xy 71.563274 -385.186013) (xy 71.548635 -385.245558)
			(xy 71.526942 -385.302911) (xy 71.498509 -385.357239) (xy 71.46375 -385.407754) (xy 71.423168 -385.453721)
			(xy 71.377352 -385.494475) (xy 71.35241 -385.51231) (xy 71.343012 -385.518914) (xy 71.331582 -385.538726)
			(xy 71.328333 -385.58216) (xy 76.211682 -385.58216) (xy 76.215753 -385.526538) (xy 76.227879 -385.472101)
			(xy 76.247802 -385.42001) (xy 76.275098 -385.371375) (xy 76.309184 -385.327232) (xy 76.349333 -385.288523)
			(xy 76.394691 -385.256072) (xy 76.444291 -385.230571) (xy 76.497075 -385.212564) (xy 76.551918 -385.202434)
			(xy 76.607652 -385.200397) (xy 76.663089 -385.206497) (xy 76.717046 -385.220603) (xy 76.768375 -385.242415)
			(xy 76.815981 -385.271469) (xy 76.858849 -385.307144) (xy 76.896066 -385.348681) (xy 76.926839 -385.395194)
			(xy 76.950511 -385.445691) (xy 76.966579 -385.499098) (xy 76.974699 -385.554274) (xy 76.975208 -385.58216)
			(xy 76.974699 -385.610046) (xy 76.971951 -385.628721) (xy 77.177394 -385.628721) (xy 77.177394 -385.576747)
			(xy 77.185524 -385.525412) (xy 77.201585 -385.475982) (xy 77.225181 -385.429672) (xy 77.255731 -385.387624)
			(xy 77.292482 -385.350873) (xy 77.33453 -385.320323) (xy 77.38084 -385.296727) (xy 77.43027 -385.280666)
			(xy 77.481605 -385.272536) (xy 77.533579 -385.272536) (xy 77.584914 -385.280666) (xy 77.634344 -385.296727)
			(xy 77.66114 -385.31038) (xy 79.98841 -385.31038) (xy 79.988883 -385.284391) (xy 79.997017 -385.233054)
			(xy 80.013082 -385.183622) (xy 80.036682 -385.137311) (xy 80.067236 -385.095263) (xy 80.103992 -385.058511)
			(xy 80.146044 -385.027962) (xy 80.192357 -385.004368) (xy 80.241791 -384.988308) (xy 80.293129 -384.98018)
			(xy 80.319118 -384.979672) (xy 80.345129 -384.980125) (xy 80.396506 -384.988287) (xy 80.445973 -385.00439)
			(xy 80.492309 -385.028038) (xy 80.534372 -385.058648) (xy 80.571125 -385.095464) (xy 80.601661 -385.13758)
			(xy 80.625229 -385.183957) (xy 80.641247 -385.233451) (xy 80.645762 -385.259072) (xy 80.647286 -385.26847)
			(xy 80.671512 -385.31038) (xy 81.188306 -385.31038) (xy 81.188783 -385.284392) (xy 81.196917 -385.233055)
			(xy 81.212982 -385.183623) (xy 81.236581 -385.137313) (xy 81.267135 -385.095264) (xy 81.30389 -385.058513)
			(xy 81.345942 -385.027963) (xy 81.392254 -385.004369) (xy 81.441688 -384.988309) (xy 81.493026 -384.98018)
			(xy 81.519014 -384.979672) (xy 81.545025 -384.980129) (xy 81.596402 -384.98829) (xy 81.645868 -385.004392)
			(xy 81.692204 -385.02804) (xy 81.734267 -385.058649) (xy 81.77102 -385.095465) (xy 81.801557 -385.137581)
			(xy 81.825125 -385.183958) (xy 81.841143 -385.233452) (xy 81.845658 -385.259072) (xy 81.847182 -385.26847)
			(xy 81.871408 -385.31038) (xy 82.388456 -385.31038) (xy 82.388983 -385.284394) (xy 82.397115 -385.233062)
			(xy 82.413177 -385.183635) (xy 82.436772 -385.137327) (xy 82.46732 -385.095281) (xy 82.504069 -385.058531)
			(xy 82.546114 -385.02798) (xy 82.59242 -385.004383) (xy 82.641847 -384.988319) (xy 82.693178 -384.980184)
			(xy 82.719164 -384.979672) (xy 82.745207 -384.980166) (xy 82.796646 -384.988348) (xy 82.846169 -385.004485)
			(xy 82.892555 -385.028178) (xy 82.934657 -385.058844) (xy 82.971438 -385.095724) (xy 83.001989 -385.137909)
			(xy 83.025557 -385.184358) (xy 83.04156 -385.233924) (xy 83.046062 -385.25958) (xy 83.047332 -385.268978)
			(xy 83.071268 -385.31038) (xy 83.588352 -385.31038) (xy 83.588883 -385.284394) (xy 83.597015 -385.233063)
			(xy 83.613077 -385.183636) (xy 83.636671 -385.137329) (xy 83.667219 -385.095282) (xy 83.703967 -385.058532)
			(xy 83.746012 -385.027982) (xy 83.792317 -385.004384) (xy 83.841743 -384.98832) (xy 83.893074 -384.980185)
			(xy 83.91906 -384.979672) (xy 83.945072 -384.980087) (xy 83.996451 -384.988255) (xy 84.045918 -385.004364)
			(xy 84.092254 -385.028017) (xy 84.134317 -385.058632) (xy 84.171069 -385.095453) (xy 84.201605 -385.137573)
			(xy 84.225172 -385.183953) (xy 84.241189 -385.23345) (xy 84.245704 -385.259072) (xy 84.247228 -385.26847)
			(xy 84.271454 -385.31038) (xy 84.788248 -385.31038) (xy 84.788783 -385.284394) (xy 84.796915 -385.233064)
			(xy 84.812976 -385.183636) (xy 84.836571 -385.13733) (xy 84.867118 -385.095284) (xy 84.903866 -385.058533)
			(xy 84.945909 -385.027983) (xy 84.992214 -385.004385) (xy 85.04164 -384.988321) (xy 85.092971 -384.980185)
			(xy 85.118956 -384.979672) (xy 85.144968 -384.980091) (xy 85.196347 -384.988258) (xy 85.245814 -385.004366)
			(xy 85.29215 -385.028019) (xy 85.334213 -385.058633) (xy 85.370965 -385.095454) (xy 85.401501 -385.137573)
			(xy 85.425068 -385.183953) (xy 85.441085 -385.23345) (xy 85.4456 -385.259072) (xy 85.447124 -385.26847)
			(xy 85.47135 -385.31038) (xy 85.988398 -385.31038) (xy 85.988883 -385.284392) (xy 85.997017 -385.233056)
			(xy 86.013081 -385.183625) (xy 86.03668 -385.137315) (xy 86.067232 -385.095267) (xy 86.103987 -385.058516)
			(xy 86.146037 -385.027966) (xy 86.192349 -385.004371) (xy 86.241782 -384.988311) (xy 86.293118 -384.980181)
			(xy 86.319106 -384.979672) (xy 86.345116 -384.980136) (xy 86.396493 -384.988296) (xy 86.44596 -385.004397)
			(xy 86.492296 -385.028044) (xy 86.534359 -385.058652) (xy 86.571112 -385.095468) (xy 86.601649 -385.137582)
			(xy 86.625217 -385.183958) (xy 86.641235 -385.233452) (xy 86.64575 -385.259072) (xy 86.647274 -385.26847)
			(xy 86.6715 -385.31038) (xy 87.188294 -385.31038) (xy 87.188783 -385.284392) (xy 87.196917 -385.233057)
			(xy 87.212981 -385.183626) (xy 87.236579 -385.137316) (xy 87.267131 -385.095268) (xy 87.303885 -385.058517)
			(xy 87.345935 -385.027968) (xy 87.392246 -385.004372) (xy 87.441678 -384.988312) (xy 87.493014 -384.980181)
			(xy 87.519002 -384.979672) (xy 87.545012 -384.98014) (xy 87.596389 -384.988299) (xy 87.645855 -385.0044)
			(xy 87.692191 -385.028046) (xy 87.734254 -385.058654) (xy 87.771008 -385.095469) (xy 87.801545 -385.137583)
			(xy 87.825113 -385.183959) (xy 87.841131 -385.233452) (xy 87.845646 -385.259072) (xy 87.84717 -385.26847)
			(xy 87.871396 -385.31038) (xy 88.388444 -385.31038) (xy 88.388983 -385.284395) (xy 88.397115 -385.233064)
			(xy 88.413176 -385.183637) (xy 88.43677 -385.137331) (xy 88.467317 -385.095285) (xy 88.504064 -385.058535)
			(xy 88.546107 -385.027985) (xy 88.592411 -385.004386) (xy 88.641837 -384.988322) (xy 88.693167 -384.980185)
			(xy 88.719152 -384.979672) (xy 88.745194 -384.980177) (xy 88.796633 -384.988357) (xy 88.846156 -385.004493)
			(xy 88.892542 -385.028184) (xy 88.934644 -385.058848) (xy 88.971425 -385.095727) (xy 89.001976 -385.137911)
			(xy 89.025545 -385.184359) (xy 89.041548 -385.233925) (xy 89.04605 -385.25958) (xy 89.04732 -385.268978)
			(xy 89.071256 -385.31038) (xy 89.58834 -385.31038) (xy 89.588757 -385.284388) (xy 89.596893 -385.233044)
			(xy 89.61296 -385.183605) (xy 89.636565 -385.137289) (xy 89.667125 -385.095235) (xy 89.703887 -385.05848)
			(xy 89.745947 -385.027929) (xy 89.792268 -385.004334) (xy 89.84171 -384.988277) (xy 89.893056 -384.980152)
			(xy 89.919048 -384.979672) (xy 89.94506 -384.980098) (xy 89.996438 -384.988264) (xy 90.045905 -385.004371)
			(xy 90.092241 -385.028023) (xy 90.134304 -385.058636) (xy 90.171057 -385.095456) (xy 90.201593 -385.137575)
			(xy 90.22516 -385.183954) (xy 90.241177 -385.23345) (xy 90.245692 -385.259072) (xy 90.247216 -385.26847)
			(xy 90.271442 -385.31038) (xy 90.788236 -385.31038) (xy 90.788657 -385.284388) (xy 90.796792 -385.233044)
			(xy 90.81286 -385.183606) (xy 90.836464 -385.13729) (xy 90.867023 -385.095236) (xy 90.903785 -385.058482)
			(xy 90.945844 -385.027931) (xy 90.992165 -385.004336) (xy 91.041607 -384.988277) (xy 91.092952 -384.980152)
			(xy 91.118944 -384.979672) (xy 91.144955 -384.980102) (xy 91.196334 -384.988267) (xy 91.245801 -385.004374)
			(xy 91.292137 -385.028025) (xy 91.3342 -385.058638) (xy 91.370952 -385.095457) (xy 91.401489 -385.137576)
			(xy 91.425056 -385.183954) (xy 91.441073 -385.233451) (xy 91.445588 -385.259072) (xy 91.447112 -385.26847)
			(xy 91.471338 -385.31038) (xy 91.988386 -385.31038) (xy 91.988883 -385.284393) (xy 91.997016 -385.233058)
			(xy 92.01308 -385.183628) (xy 92.036678 -385.137319) (xy 92.067229 -385.095271) (xy 92.103981 -385.05852)
			(xy 92.14603 -385.02797) (xy 92.192341 -385.004374) (xy 92.241772 -384.988313) (xy 92.293107 -384.980182)
			(xy 92.319094 -384.979672) (xy 92.345104 -384.980147) (xy 92.39648 -384.988305) (xy 92.445947 -385.004405)
			(xy 92.492282 -385.02805) (xy 92.534346 -385.058657) (xy 92.571099 -385.095471) (xy 92.601636 -385.137585)
			(xy 92.625205 -385.18396) (xy 92.641223 -385.233452) (xy 92.645738 -385.259072) (xy 92.647262 -385.26847)
			(xy 92.671488 -385.31038) (xy 93.188282 -385.31038) (xy 93.188783 -385.284393) (xy 93.196916 -385.233059)
			(xy 93.212979 -385.183629) (xy 93.236577 -385.13732) (xy 93.267128 -385.095272) (xy 93.30388 -385.058521)
			(xy 93.345928 -385.027972) (xy 93.392238 -385.004376) (xy 93.441668 -384.988314) (xy 93.493003 -384.980182)
			(xy 93.51899 -384.979672) (xy 93.545 -384.980151) (xy 93.596376 -384.988308) (xy 93.645842 -385.004407)
			(xy 93.692178 -385.028052) (xy 93.734241 -385.058658) (xy 93.770995 -385.095472) (xy 93.801532 -385.137585)
			(xy 93.825101 -385.18396) (xy 93.841119 -385.233452) (xy 93.845634 -385.259072) (xy 93.847158 -385.26847)
			(xy 93.871384 -385.31038) (xy 94.388432 -385.31038) (xy 94.388857 -385.284388) (xy 94.396992 -385.233045)
			(xy 94.41306 -385.183607) (xy 94.436663 -385.137291) (xy 94.467222 -385.095238) (xy 94.503984 -385.058483)
			(xy 94.546042 -385.027932) (xy 94.592362 -385.004337) (xy 94.641804 -384.988278) (xy 94.693148 -384.980152)
			(xy 94.71914 -384.979672) (xy 94.745185 -384.980097) (xy 94.796627 -384.988291) (xy 94.846152 -385.004438)
			(xy 94.892538 -385.028141) (xy 94.934639 -385.058815) (xy 94.971419 -385.095703) (xy 95.001969 -385.137895)
			(xy 95.025535 -385.18435) (xy 95.041537 -385.233922) (xy 95.046038 -385.25958) (xy 95.047308 -385.268978)
			(xy 95.071244 -385.31038) (xy 95.588328 -385.31038) (xy 95.588757 -385.284388) (xy 95.596892 -385.233046)
			(xy 95.612959 -385.183608) (xy 95.636563 -385.137292) (xy 95.667121 -385.095239) (xy 95.703882 -385.058485)
			(xy 95.74594 -385.027933) (xy 95.79226 -385.004338) (xy 95.8417 -384.988279) (xy 95.893044 -384.980152)
			(xy 95.919036 -384.979672) (xy 95.945047 -384.980109) (xy 95.996425 -384.988273) (xy 96.045892 -385.004379)
			(xy 96.092228 -385.028029) (xy 96.134291 -385.058641) (xy 96.171044 -385.095459) (xy 96.20158 -385.137577)
			(xy 96.225148 -385.183955) (xy 96.241165 -385.233451) (xy 96.24568 -385.259072) (xy 96.247204 -385.26847)
			(xy 96.52 -385.740402) (xy 96.527366 -385.746244) (xy 96.546161 -385.762026) (xy 96.579275 -385.798249)
			(xy 96.60668 -385.838962) (xy 96.627778 -385.883273) (xy 96.642105 -385.930213) (xy 96.649349 -385.978753)
			(xy 96.649794 -386.003292) (xy 96.64954 -386.015484) (xy 96.649286 -386.025136) (xy 96.655382 -386.04317)
			(xy 96.714056 -386.11048) (xy 96.73082 -386.119116) (xy 96.740726 -386.120132) (xy 96.767491 -386.12347)
			(xy 96.819514 -386.137696) (xy 96.86854 -386.160175) (xy 96.913269 -386.19031) (xy 96.952516 -386.227303)
			(xy 96.985241 -386.270174) (xy 97.010577 -386.317786) (xy 97.027852 -386.368878) (xy 97.036609 -386.422095)
			(xy 97.037144 -386.449062) (xy 97.036599 -386.476347) (xy 97.027645 -386.530176) (xy 97.009975 -386.581805)
			(xy 96.984068 -386.629832) (xy 96.950626 -386.672953) (xy 96.930972 -386.691886) (xy 96.923585 -386.69942)
			(xy 96.91505 -386.71869) (xy 96.914462 -386.729224) (xy 96.914462 -386.8039) (xy 96.914989 -386.81445)
			(xy 96.923527 -386.833744) (xy 96.930972 -386.841238) (xy 96.950619 -386.860177) (xy 96.98405 -386.903302)
			(xy 97.009953 -386.951328) (xy 97.027623 -387.002954) (xy 97.036583 -387.056779) (xy 97.037144 -387.084062)
			(xy 97.036695 -387.108178) (xy 97.029699 -387.1559) (xy 97.015849 -387.202101) (xy 96.995439 -387.245802)
			(xy 96.982534 -387.26618) (xy 96.976692 -387.27507) (xy 96.973136 -387.295136) (xy 96.994218 -387.387338)
			(xy 97.00641 -387.404102) (xy 97.0153 -387.409436) (xy 97.036093 -387.422303) (xy 97.074 -387.453189)
			(xy 97.106945 -387.489322) (xy 97.134208 -387.529913) (xy 97.155194 -387.574077) (xy 97.169447 -387.620851)
			(xy 97.176655 -387.669214) (xy 97.177098 -387.693662) (xy 97.176678 -387.718035) (xy 97.169532 -387.766255)
			(xy 97.155389 -387.812904) (xy 97.134556 -387.856974) (xy 97.107483 -387.897511) (xy 97.074755 -387.933638)
			(xy 97.056194 -387.94944) (xy 97.047304 -387.956552) (xy 97.037906 -387.97611) (xy 97.035112 -388.075424)
			(xy 97.043748 -388.09549) (xy 97.05213 -388.10311) (xy 97.070574 -388.120577) (xy 97.101922 -388.160546)
			(xy 97.126221 -388.205153) (xy 97.142798 -388.253168) (xy 97.151198 -388.303264) (xy 97.151698 -388.328662)
			(xy 97.151594 -388.339943) (xy 97.149943 -388.362445) (xy 97.148396 -388.37362) (xy 97.147126 -388.382764)
			(xy 97.150428 -388.400036) (xy 97.194116 -388.471156) (xy 97.207832 -388.482078) (xy 97.216468 -388.484872)
			(xy 97.244632 -388.495072) (xy 97.296578 -388.524881) (xy 97.319592 -388.544054) (xy 97.341076 -388.563636)
			(xy 97.376889 -388.609414) (xy 97.390712 -388.634986) (xy 97.391474 -388.636256) (xy 97.78365 -389.314944)
			(xy 97.796457 -389.338285) (xy 97.814684 -389.388304) (xy 97.823951 -389.440726) (xy 97.824544 -389.467344)
			(xy 97.824102 -389.491349) (xy 97.816582 -389.538767) (xy 97.801734 -389.584424) (xy 97.779924 -389.627195)
			(xy 97.75169 -389.666026) (xy 97.717726 -389.69996) (xy 97.678871 -389.728161) (xy 97.636082 -389.749934)
			(xy 97.590412 -389.764743) (xy 97.542988 -389.772222) (xy 97.518982 -389.772652) (xy 97.495451 -389.772183)
			(xy 97.448944 -389.76498) (xy 97.404096 -389.750716) (xy 97.361973 -389.729731) (xy 97.323574 -389.702523)
			(xy 97.289811 -389.669738) (xy 97.261487 -389.632155) (xy 97.249996 -389.611616) (xy 97.249742 -389.611108)
			(xy 97.249234 -389.610346) (xy 96.851724 -388.921752) (xy 96.841152 -388.901825) (xy 96.825349 -388.859575)
			(xy 96.815941 -388.815459) (xy 96.814132 -388.792974) (xy 96.813624 -388.781798) (xy 96.813624 -388.774432)
			(xy 96.813715 -388.763087) (xy 96.81537 -388.740458) (xy 96.816926 -388.72922) (xy 96.818196 -388.72033)
			(xy 96.81464 -388.703058) (xy 96.771206 -388.631938) (xy 96.75749 -388.620762) (xy 96.748854 -388.617968)
			(xy 96.726448 -388.609981) (xy 96.684278 -388.587976) (xy 96.64603 -388.559697) (xy 96.612631 -388.525829)
			(xy 96.584888 -388.487191) (xy 96.563473 -388.444717) (xy 96.548904 -388.399437) (xy 96.541533 -388.352445)
			(xy 96.541082 -388.328662) (xy 96.541614 -388.303267) (xy 96.550022 -388.253179) (xy 96.566601 -388.205172)
			(xy 96.590894 -388.160569) (xy 96.622231 -388.120599) (xy 96.64065 -388.10311) (xy 96.649032 -388.09549)
			(xy 96.657668 -388.075424) (xy 96.654874 -387.97611) (xy 96.645476 -387.956552) (xy 96.636586 -387.94944)
			(xy 96.618056 -387.933604) (xy 96.585333 -387.897481) (xy 96.558261 -387.85695) (xy 96.537425 -387.812887)
			(xy 96.523276 -387.766245) (xy 96.51612 -387.718032) (xy 96.515682 -387.693662) (xy 96.516091 -387.669544)
			(xy 96.523098 -387.62182) (xy 96.53696 -387.575619) (xy 96.557382 -387.53192) (xy 96.570292 -387.511544)
			(xy 96.576134 -387.502654) (xy 96.57969 -387.482588) (xy 96.558608 -387.390386) (xy 96.546416 -387.373622)
			(xy 96.537526 -387.368288) (xy 96.516727 -387.355431) (xy 96.478823 -387.32454) (xy 96.445882 -387.288404)
			(xy 96.418621 -387.247811) (xy 96.397636 -387.203647) (xy 96.383383 -387.156873) (xy 96.376173 -387.10851)
			(xy 96.375728 -387.084062) (xy 96.376266 -387.056777) (xy 96.385218 -387.002946) (xy 96.402888 -386.951316)
			(xy 96.428798 -386.903289) (xy 96.462243 -386.86017) (xy 96.4819 -386.841238) (xy 96.489287 -386.833704)
			(xy 96.49782 -386.814433) (xy 96.49841 -386.8039) (xy 96.49841 -386.729224) (xy 96.497878 -386.718675)
			(xy 96.489345 -386.69938) (xy 96.4819 -386.691886) (xy 96.462278 -386.672922) (xy 96.42884 -386.629806)
			(xy 96.402932 -386.581786) (xy 96.385256 -386.530165) (xy 96.376291 -386.476343) (xy 96.375728 -386.449062)
			(xy 96.375982 -386.43687) (xy 96.376236 -386.427218) (xy 96.37014 -386.409184) (xy 96.311466 -386.341874)
			(xy 96.294702 -386.333238) (xy 96.284796 -386.332222) (xy 96.257893 -386.328822) (xy 96.205608 -386.314464)
			(xy 96.156364 -386.29177) (xy 96.111481 -386.261349) (xy 96.07216 -386.224016) (xy 96.039455 -386.180769)
			(xy 96.01424 -386.132768) (xy 95.997192 -386.081297) (xy 95.992442 -386.0546) (xy 95.990918 -386.045202)
			(xy 95.718122 -385.57327) (xy 95.710756 -385.567428) (xy 95.692 -385.551602) (xy 95.658883 -385.515389)
			(xy 95.631472 -385.474685) (xy 95.610367 -385.430382) (xy 95.596032 -385.38345) (xy 95.588778 -385.334916)
			(xy 95.588328 -385.31038) (xy 95.071244 -385.31038) (xy 95.31985 -385.740402) (xy 95.327216 -385.746244)
			(xy 95.346001 -385.762038) (xy 95.379117 -385.798257) (xy 95.406526 -385.838967) (xy 95.427625 -385.883276)
			(xy 95.441954 -385.930215) (xy 95.449199 -385.978754) (xy 95.449644 -386.003292) (xy 95.44939 -386.015484)
			(xy 95.449136 -386.025136) (xy 95.455232 -386.04317) (xy 95.513906 -386.11048) (xy 95.53067 -386.119116)
			(xy 95.540576 -386.120132) (xy 95.567335 -386.123511) (xy 95.619358 -386.13773) (xy 95.668384 -386.160201)
			(xy 95.713114 -386.190331) (xy 95.752362 -386.227318) (xy 95.785088 -386.270185) (xy 95.810425 -386.317793)
			(xy 95.827701 -386.368882) (xy 95.836458 -386.422097) (xy 95.836994 -386.449062) (xy 95.836465 -386.476347)
			(xy 95.82751 -386.530178) (xy 95.809837 -386.581808) (xy 95.783925 -386.629835) (xy 95.750479 -386.672954)
			(xy 95.730822 -386.691886) (xy 95.723428 -386.699414) (xy 95.714898 -386.718689) (xy 95.714312 -386.729224)
			(xy 95.714312 -386.8039) (xy 95.714824 -386.814452) (xy 95.723371 -386.833747) (xy 95.730822 -386.841238)
			(xy 95.75046 -386.860186) (xy 95.783894 -386.903308) (xy 95.809799 -386.951331) (xy 95.827472 -387.002955)
			(xy 95.836433 -387.05678) (xy 95.836994 -387.084062) (xy 95.836537 -387.108178) (xy 95.829542 -387.155899)
			(xy 95.815694 -387.2021) (xy 95.795287 -387.245802) (xy 95.782384 -387.26618) (xy 95.776542 -387.27507)
			(xy 95.772986 -387.295136) (xy 95.794068 -387.387338) (xy 95.80626 -387.404102) (xy 95.81515 -387.409436)
			(xy 95.835955 -387.422285) (xy 95.873859 -387.453176) (xy 95.906801 -387.489313) (xy 95.934062 -387.529907)
			(xy 95.955046 -387.574074) (xy 95.969298 -387.620849) (xy 95.976505 -387.669213) (xy 95.976948 -387.693662)
			(xy 95.976546 -387.718036) (xy 95.969399 -387.766257) (xy 95.955254 -387.812908) (xy 95.934417 -387.856978)
			(xy 95.90734 -387.897515) (xy 95.874608 -387.933639) (xy 95.856044 -387.94944) (xy 95.847154 -387.956552)
			(xy 95.837756 -387.97611) (xy 95.834962 -388.075424) (xy 95.843598 -388.09549) (xy 95.85198 -388.10311)
			(xy 95.870434 -388.120567) (xy 95.901779 -388.16054) (xy 95.926074 -388.20515) (xy 95.94265 -388.253166)
			(xy 95.951049 -388.303263) (xy 95.951548 -388.328662) (xy 95.951445 -388.339943) (xy 95.949793 -388.362445)
			(xy 95.948246 -388.37362) (xy 95.946976 -388.38251) (xy 95.950532 -388.400036) (xy 95.993966 -388.470902)
			(xy 96.007682 -388.482078) (xy 96.016318 -388.484872) (xy 96.038574 -388.492778) (xy 96.080494 -388.514537)
			(xy 96.118565 -388.542489) (xy 96.151881 -388.575967) (xy 96.179647 -388.614174) (xy 96.190816 -388.634986)
			(xy 96.191324 -388.636002) (xy 96.583754 -389.314944) (xy 96.596562 -389.338285) (xy 96.614788 -389.388304)
			(xy 96.624055 -389.440726) (xy 96.624648 -389.467344) (xy 96.624202 -389.491349) (xy 96.616682 -389.538767)
			(xy 96.601834 -389.584423) (xy 96.580025 -389.627194) (xy 96.551791 -389.666025) (xy 96.517828 -389.699959)
			(xy 96.478973 -389.72816) (xy 96.436184 -389.749933) (xy 96.390515 -389.764742) (xy 96.343091 -389.772222)
			(xy 96.319086 -389.772652) (xy 96.295555 -389.77218) (xy 96.249049 -389.764977) (xy 96.204201 -389.750714)
			(xy 96.162077 -389.72973) (xy 96.123678 -389.702522) (xy 96.089916 -389.669737) (xy 96.061591 -389.632154)
			(xy 96.0501 -389.611616) (xy 96.049846 -389.611108) (xy 96.049338 -389.610346) (xy 95.651574 -388.922006)
			(xy 95.639699 -388.899329) (xy 95.622848 -388.850996) (xy 95.614274 -388.800533) (xy 95.613728 -388.77494)
			(xy 95.613728 -388.774432) (xy 95.613819 -388.763087) (xy 95.615474 -388.740458) (xy 95.61703 -388.72922)
			(xy 95.6183 -388.72033) (xy 95.614744 -388.703058) (xy 95.57131 -388.631938) (xy 95.55734 -388.621016)
			(xy 95.548958 -388.617968) (xy 95.526559 -388.609926) (xy 95.48434 -388.587969) (xy 95.446043 -388.559723)
			(xy 95.412596 -388.525873) (xy 95.384811 -388.48724) (xy 95.363362 -388.444761) (xy 95.348769 -388.399466)
			(xy 95.341385 -388.352456) (xy 95.340932 -388.328662) (xy 95.341447 -388.303267) (xy 95.349858 -388.253177)
			(xy 95.36644 -388.205168) (xy 95.390736 -388.160566) (xy 95.422078 -388.120598) (xy 95.4405 -388.10311)
			(xy 95.448882 -388.09549) (xy 95.457518 -388.075424) (xy 95.454724 -387.97611) (xy 95.445326 -387.956552)
			(xy 95.436436 -387.94944) (xy 95.417895 -387.933616) (xy 95.385176 -387.897489) (xy 95.358106 -387.856955)
			(xy 95.337273 -387.81289) (xy 95.323125 -387.766246) (xy 95.31597 -387.718033) (xy 95.315532 -387.693662)
			(xy 95.315949 -387.669545) (xy 95.322955 -387.621821) (xy 95.336815 -387.575621) (xy 95.357233 -387.531921)
			(xy 95.370142 -387.511544) (xy 95.375984 -387.502654) (xy 95.37954 -387.482588) (xy 95.358458 -387.390386)
			(xy 95.346266 -387.373622) (xy 95.337376 -387.368288) (xy 95.316588 -387.355413) (xy 95.278682 -387.324527)
			(xy 95.245738 -387.288395) (xy 95.218475 -387.247805) (xy 95.197488 -387.203643) (xy 95.183233 -387.156871)
			(xy 95.176023 -387.10851) (xy 95.175578 -387.084062) (xy 95.176132 -387.056778) (xy 95.185082 -387.002948)
			(xy 95.20275 -386.951319) (xy 95.228656 -386.903292) (xy 95.262096 -386.860171) (xy 95.28175 -386.841238)
			(xy 95.289129 -386.833697) (xy 95.297668 -386.814432) (xy 95.29826 -386.8039) (xy 95.29826 -386.729224)
			(xy 95.297743 -386.718673) (xy 95.289201 -386.699376) (xy 95.28175 -386.691886) (xy 95.262119 -386.672932)
			(xy 95.228684 -386.629811) (xy 95.202779 -386.581789) (xy 95.185105 -386.530167) (xy 95.176141 -386.476344)
			(xy 95.175578 -386.449062) (xy 95.175832 -386.43687) (xy 95.176086 -386.427218) (xy 95.16999 -386.409184)
			(xy 95.111316 -386.341874) (xy 95.094552 -386.333238) (xy 95.084646 -386.332222) (xy 95.057738 -386.328862)
			(xy 95.005452 -386.314496) (xy 94.956208 -386.291795) (xy 94.911326 -386.261368) (xy 94.872006 -386.224029)
			(xy 94.839302 -386.180778) (xy 94.814089 -386.132773) (xy 94.797042 -386.081298) (xy 94.792292 -386.0546)
			(xy 94.790768 -386.045202) (xy 94.517718 -385.572762) (xy 94.510606 -385.56692) (xy 94.491876 -385.551138)
			(xy 94.458821 -385.514997) (xy 94.431463 -385.474372) (xy 94.410404 -385.430153) (xy 94.396103 -385.38331)
			(xy 94.388875 -385.334869) (xy 94.388432 -385.31038) (xy 93.871384 -385.31038) (xy 94.119954 -385.740402)
			(xy 94.12732 -385.746244) (xy 94.146106 -385.762037) (xy 94.179222 -385.798256) (xy 94.20663 -385.838966)
			(xy 94.22773 -385.883276) (xy 94.242058 -385.930214) (xy 94.249303 -385.978754) (xy 94.249748 -386.003292)
			(xy 94.249494 -386.015484) (xy 94.24924 -386.025136) (xy 94.255336 -386.04317) (xy 94.31401 -386.11048)
			(xy 94.330774 -386.119116) (xy 94.34068 -386.120132) (xy 94.36744 -386.123508) (xy 94.419462 -386.137727)
			(xy 94.468488 -386.160199) (xy 94.513218 -386.190329) (xy 94.552466 -386.227317) (xy 94.585192 -386.270184)
			(xy 94.610529 -386.317792) (xy 94.627805 -386.368881) (xy 94.636562 -386.422097) (xy 94.637098 -386.449062)
			(xy 94.636568 -386.476347) (xy 94.627613 -386.530178) (xy 94.60994 -386.581808) (xy 94.584029 -386.629834)
			(xy 94.550583 -386.672954) (xy 94.530926 -386.691886) (xy 94.523532 -386.699414) (xy 94.515002 -386.718689)
			(xy 94.514416 -386.729224) (xy 94.514416 -386.8039) (xy 94.514927 -386.814452) (xy 94.523475 -386.833747)
			(xy 94.530926 -386.841238) (xy 94.550564 -386.860185) (xy 94.583999 -386.903307) (xy 94.609904 -386.951331)
			(xy 94.627576 -387.002955) (xy 94.636537 -387.056779) (xy 94.637098 -387.084062) (xy 94.636656 -387.108179)
			(xy 94.629659 -387.155901) (xy 94.615807 -387.202102) (xy 94.595394 -387.245803) (xy 94.582488 -387.26618)
			(xy 94.576646 -387.27507) (xy 94.57309 -387.295136) (xy 94.594172 -387.387338) (xy 94.606364 -387.404102)
			(xy 94.615254 -387.409436) (xy 94.63606 -387.422284) (xy 94.673964 -387.453175) (xy 94.706906 -387.489312)
			(xy 94.734166 -387.529907) (xy 94.755151 -387.574073) (xy 94.769402 -387.620849) (xy 94.776609 -387.669213)
			(xy 94.777052 -387.693662) (xy 94.776648 -387.718036) (xy 94.769501 -387.766257) (xy 94.755357 -387.812908)
			(xy 94.73452 -387.856978) (xy 94.707443 -387.897514) (xy 94.674712 -387.933639) (xy 94.656148 -387.94944)
			(xy 94.647258 -387.956552) (xy 94.63786 -387.97611) (xy 94.635066 -388.075424) (xy 94.643702 -388.09549)
			(xy 94.652084 -388.10311) (xy 94.670539 -388.120566) (xy 94.701883 -388.160539) (xy 94.726179 -388.205149)
			(xy 94.742754 -388.253166) (xy 94.751153 -388.303263) (xy 94.751652 -388.328662) (xy 94.751549 -388.339943)
			(xy 94.749897 -388.362445) (xy 94.74835 -388.37362) (xy 94.74708 -388.382764) (xy 94.750382 -388.400036)
			(xy 94.79407 -388.471156) (xy 94.807786 -388.482078) (xy 94.816422 -388.484872) (xy 94.844591 -388.49506)
			(xy 94.896534 -388.524878) (xy 94.919546 -388.544054) (xy 94.941036 -388.563629) (xy 94.976845 -388.609412)
			(xy 94.990666 -388.634986) (xy 94.991428 -388.636256) (xy 95.383604 -389.314944) (xy 95.396337 -389.33831)
			(xy 95.414452 -389.388337) (xy 95.423662 -389.440741) (xy 95.424244 -389.467344) (xy 95.423778 -389.491335)
			(xy 95.416267 -389.538724) (xy 95.401435 -389.584356) (xy 95.379649 -389.627106) (xy 95.351445 -389.665923)
			(xy 95.317517 -389.69985) (xy 95.278699 -389.728054) (xy 95.235949 -389.749838) (xy 95.190317 -389.764668)
			(xy 95.142927 -389.772179) (xy 95.118936 -389.772652) (xy 95.095404 -389.77222) (xy 95.048895 -389.76501)
			(xy 95.004047 -389.75074) (xy 94.961923 -389.729749) (xy 94.923525 -389.702535) (xy 94.889763 -389.669745)
			(xy 94.86144 -389.632157) (xy 94.84995 -389.611616) (xy 94.849696 -389.611108) (xy 94.849188 -389.610346)
			(xy 94.451678 -388.921752) (xy 94.441103 -388.901827) (xy 94.425301 -388.859576) (xy 94.415895 -388.815459)
			(xy 94.414086 -388.792974) (xy 94.413578 -388.781798) (xy 94.413324 -388.774432) (xy 94.413481 -388.763083)
			(xy 94.415258 -388.740453) (xy 94.41688 -388.72922) (xy 94.41815 -388.72033) (xy 94.414594 -388.703058)
			(xy 94.37116 -388.631938) (xy 94.357444 -388.620762) (xy 94.348808 -388.617968) (xy 94.326414 -388.60995)
			(xy 94.284242 -388.587952) (xy 94.245992 -388.559679) (xy 94.212591 -388.525816) (xy 94.184846 -388.487182)
			(xy 94.163429 -388.444712) (xy 94.148859 -388.399434) (xy 94.141487 -388.352444) (xy 94.141036 -388.328662)
			(xy 94.14155 -388.303266) (xy 94.14996 -388.253176) (xy 94.166543 -388.205168) (xy 94.19084 -388.160565)
			(xy 94.222182 -388.120598) (xy 94.240604 -388.10311) (xy 94.248986 -388.09549) (xy 94.257622 -388.075424)
			(xy 94.254828 -387.97611) (xy 94.24543 -387.956552) (xy 94.23654 -387.94944) (xy 94.218 -387.933615)
			(xy 94.18528 -387.897488) (xy 94.158211 -387.856954) (xy 94.137377 -387.81289) (xy 94.123229 -387.766246)
			(xy 94.116074 -387.718033) (xy 94.115636 -387.693662) (xy 94.116052 -387.669545) (xy 94.123059 -387.621821)
			(xy 94.136918 -387.57562) (xy 94.157337 -387.531921) (xy 94.170246 -387.511544) (xy 94.176088 -387.502654)
			(xy 94.179644 -387.482588) (xy 94.158562 -387.390386) (xy 94.14637 -387.373622) (xy 94.13748 -387.368288)
			(xy 94.116693 -387.355411) (xy 94.078787 -387.324526) (xy 94.045843 -387.288394) (xy 94.01858 -387.247805)
			(xy 93.997592 -387.203643) (xy 93.983337 -387.156871) (xy 93.976127 -387.10851) (xy 93.975682 -387.084062)
			(xy 93.976234 -387.056778) (xy 93.985185 -387.002948) (xy 94.002853 -386.951319) (xy 94.028759 -386.903292)
			(xy 94.0622 -386.860171) (xy 94.081854 -386.841238) (xy 94.089234 -386.833698) (xy 94.097772 -386.814432)
			(xy 94.098364 -386.8039) (xy 94.098364 -386.729224) (xy 94.097846 -386.718673) (xy 94.089304 -386.699377)
			(xy 94.081854 -386.691886) (xy 94.062224 -386.672931) (xy 94.028789 -386.629811) (xy 94.002883 -386.581789)
			(xy 93.985209 -386.530167) (xy 93.976245 -386.476344) (xy 93.975682 -386.449062) (xy 93.975936 -386.43687)
			(xy 93.97619 -386.427218) (xy 93.970094 -386.409184) (xy 93.91142 -386.341874) (xy 93.894656 -386.333238)
			(xy 93.88475 -386.332222) (xy 93.857842 -386.328859) (xy 93.805556 -386.314493) (xy 93.756313 -386.291793)
			(xy 93.71143 -386.261367) (xy 93.672111 -386.224028) (xy 93.639406 -386.180777) (xy 93.614193 -386.132772)
			(xy 93.597146 -386.081298) (xy 93.592396 -386.0546) (xy 93.590872 -386.045202) (xy 93.318076 -385.57327)
			(xy 93.31071 -385.567428) (xy 93.291965 -385.551589) (xy 93.258845 -385.51538) (xy 93.231431 -385.474679)
			(xy 93.210324 -385.430379) (xy 93.195987 -385.383448) (xy 93.188733 -385.334916) (xy 93.188282 -385.31038)
			(xy 92.671488 -385.31038) (xy 92.920058 -385.740402) (xy 92.927424 -385.746244) (xy 92.94621 -385.762036)
			(xy 92.979327 -385.798255) (xy 93.006734 -385.838966) (xy 93.027834 -385.883276) (xy 93.042162 -385.930214)
			(xy 93.049407 -385.978754) (xy 93.049852 -386.003292) (xy 93.049598 -386.015484) (xy 93.049344 -386.025136)
			(xy 93.05544 -386.04317) (xy 93.114114 -386.11048) (xy 93.130878 -386.119116) (xy 93.14053 -386.120132)
			(xy 93.167295 -386.123467) (xy 93.219319 -386.137694) (xy 93.268344 -386.160173) (xy 93.313073 -386.190308)
			(xy 93.35232 -386.227302) (xy 93.385045 -386.270173) (xy 93.410381 -386.317785) (xy 93.427656 -386.368877)
			(xy 93.436413 -386.422095) (xy 93.436948 -386.449062) (xy 93.436438 -386.475049) (xy 93.428308 -386.526384)
			(xy 93.412247 -386.575814) (xy 93.388651 -386.622124) (xy 93.358101 -386.664172) (xy 93.32135 -386.700923)
			(xy 93.279302 -386.731473) (xy 93.232992 -386.755069) (xy 93.183562 -386.77113) (xy 93.132227 -386.77926)
			(xy 93.080253 -386.77926) (xy 93.028918 -386.77113) (xy 92.979488 -386.755069) (xy 92.933178 -386.731473)
			(xy 92.89113 -386.700923) (xy 92.854379 -386.664172) (xy 92.823829 -386.622124) (xy 92.800233 -386.575814)
			(xy 92.784172 -386.526384) (xy 92.776042 -386.475049) (xy 92.775532 -386.449062) (xy 92.775786 -386.43687)
			(xy 92.77604 -386.427218) (xy 92.769944 -386.409184) (xy 92.71127 -386.341874) (xy 92.694506 -386.333238)
			(xy 92.684854 -386.332222) (xy 92.657947 -386.328855) (xy 92.605661 -386.31449) (xy 92.556417 -386.291791)
			(xy 92.511535 -386.261365) (xy 92.472215 -386.224027) (xy 92.43951 -386.180777) (xy 92.414297 -386.132772)
			(xy 92.39725 -386.081298) (xy 92.3925 -386.0546) (xy 92.390976 -386.045202) (xy 92.11818 -385.57327)
			(xy 92.110814 -385.567428) (xy 92.09207 -385.551588) (xy 92.05895 -385.515379) (xy 92.031536 -385.474679)
			(xy 92.010429 -385.430379) (xy 91.996091 -385.383448) (xy 91.988837 -385.334916) (xy 91.988386 -385.31038)
			(xy 91.471338 -385.31038) (xy 91.719908 -385.740402) (xy 91.727274 -385.746244) (xy 91.746071 -385.762024)
			(xy 91.779184 -385.798247) (xy 91.806589 -385.838961) (xy 91.827686 -385.883273) (xy 91.842013 -385.930213)
			(xy 91.849257 -385.978753) (xy 91.849702 -386.003292) (xy 91.849448 -386.015484) (xy 91.849194 -386.025136)
			(xy 91.85529 -386.04317) (xy 91.913964 -386.11048) (xy 91.930728 -386.119116) (xy 91.940634 -386.120132)
			(xy 91.9674 -386.123464) (xy 92.019423 -386.137691) (xy 92.068449 -386.160171) (xy 92.113178 -386.190307)
			(xy 92.152425 -386.227301) (xy 92.185149 -386.270172) (xy 92.210485 -386.317785) (xy 92.22776 -386.368877)
			(xy 92.236517 -386.422095) (xy 92.237052 -386.449062) (xy 92.236635 -386.473264) (xy 92.22956 -386.52115)
			(xy 92.215572 -386.567489) (xy 92.194969 -386.611291) (xy 92.181934 -386.631688) (xy 92.177144 -386.639643)
			(xy 92.173112 -386.657756) (xy 92.17406 -386.666994) (xy 92.178378 -386.697982) (xy 92.180067 -386.707276)
			(xy 92.189343 -386.723718) (xy 92.196412 -386.729986) (xy 92.218489 -386.748681) (xy 92.258263 -386.790689)
			(xy 92.292428 -386.837374) (xy 92.320437 -386.887992) (xy 92.341846 -386.941735) (xy 92.356313 -386.997748)
			(xy 92.363607 -387.055137) (xy 92.364052 -387.084062) (xy 92.363461 -387.117383) (xy 92.353799 -387.183322)
			(xy 92.334673 -387.247161) (xy 92.321126 -387.27761) (xy 92.316862 -387.288071) (xy 92.316976 -387.310635)
			(xy 92.32672 -387.330988) (xy 92.335096 -387.33857) (xy 92.357325 -387.357264) (xy 92.39739 -387.399316)
			(xy 92.431812 -387.446098) (xy 92.460039 -387.49686) (xy 92.481618 -387.550785) (xy 92.4962 -387.607006)
			(xy 92.503553 -387.664621) (xy 92.504006 -387.693662) (xy 92.503546 -387.722668) (xy 92.496234 -387.780216)
			(xy 92.481711 -387.83638) (xy 92.460208 -387.890259) (xy 92.432071 -387.940989) (xy 92.39775 -387.987758)
			(xy 92.357795 -388.029817) (xy 92.335604 -388.0485) (xy 92.328492 -388.054088) (xy 92.319348 -388.069328)
			(xy 92.304108 -388.152132) (xy 92.306902 -388.169404) (xy 92.311474 -388.177532) (xy 92.324044 -388.200721)
			(xy 92.341921 -388.250341) (xy 92.351024 -388.302292) (xy 92.351606 -388.328662) (xy 92.940886 -388.328662)
			(xy 92.941408 -388.303407) (xy 92.949721 -388.253585) (xy 92.966122 -388.205811) (xy 92.990163 -388.161388)
			(xy 93.021187 -388.121528) (xy 93.058349 -388.087318) (xy 93.100635 -388.059692) (xy 93.146891 -388.039402)
			(xy 93.195856 -388.027002) (xy 93.246194 -388.022831) (xy 93.296532 -388.027002) (xy 93.345497 -388.039402)
			(xy 93.391753 -388.059692) (xy 93.434039 -388.087318) (xy 93.471201 -388.121528) (xy 93.502225 -388.161388)
			(xy 93.526266 -388.205811) (xy 93.542667 -388.253585) (xy 93.55098 -388.303407) (xy 93.551502 -388.328662)
			(xy 93.551398 -388.339943) (xy 93.549747 -388.362445) (xy 93.5482 -388.37362) (xy 93.54693 -388.38251)
			(xy 93.550486 -388.400036) (xy 93.59392 -388.470902) (xy 93.607636 -388.482078) (xy 93.616272 -388.484872)
			(xy 93.63852 -388.4928) (xy 93.680441 -388.514553) (xy 93.718514 -388.542499) (xy 93.751831 -388.575973)
			(xy 93.779599 -388.614176) (xy 93.79077 -388.634986) (xy 93.791278 -388.636002) (xy 94.183708 -389.314944)
			(xy 94.196441 -389.33831) (xy 94.214556 -389.388337) (xy 94.223766 -389.440741) (xy 94.224348 -389.467344)
			(xy 94.223878 -389.491334) (xy 94.216367 -389.538724) (xy 94.201536 -389.584355) (xy 94.17975 -389.627105)
			(xy 94.151546 -389.665922) (xy 94.117618 -389.699849) (xy 94.078802 -389.728052) (xy 94.036051 -389.749837)
			(xy 93.99042 -389.764668) (xy 93.94303 -389.772178) (xy 93.91904 -389.772652) (xy 93.895508 -389.772217)
			(xy 93.848999 -389.765007) (xy 93.804151 -389.750738) (xy 93.762027 -389.729747) (xy 93.723629 -389.702534)
			(xy 93.689867 -389.669744) (xy 93.661545 -389.632156) (xy 93.650054 -389.611616) (xy 93.6498 -389.611108)
			(xy 93.649292 -389.610346) (xy 93.251528 -388.922006) (xy 93.239615 -388.899337) (xy 93.222676 -388.851012)
			(xy 93.214016 -388.800542) (xy 93.213428 -388.77494) (xy 93.213428 -388.774432) (xy 93.213585 -388.763083)
			(xy 93.215362 -388.740453) (xy 93.216984 -388.72922) (xy 93.218254 -388.72033) (xy 93.214698 -388.703058)
			(xy 93.171264 -388.631938) (xy 93.157294 -388.621016) (xy 93.148912 -388.617968) (xy 93.126503 -388.609953)
			(xy 93.084286 -388.58799) (xy 93.04599 -388.559738) (xy 93.012545 -388.525884) (xy 92.984762 -388.487247)
			(xy 92.963314 -388.444766) (xy 92.948722 -388.399469) (xy 92.941339 -388.352456) (xy 92.940886 -388.328662)
			(xy 92.351606 -388.328662) (xy 92.351502 -388.339943) (xy 92.349851 -388.362445) (xy 92.348304 -388.37362)
			(xy 92.347034 -388.38251) (xy 92.35059 -388.400036) (xy 92.394024 -388.470902) (xy 92.40774 -388.482078)
			(xy 92.416376 -388.484872) (xy 92.438625 -388.492798) (xy 92.480545 -388.514551) (xy 92.518618 -388.542498)
			(xy 92.551936 -388.575972) (xy 92.579704 -388.614176) (xy 92.590874 -388.634986) (xy 92.591382 -388.636002)
			(xy 92.983812 -389.314944) (xy 92.996545 -389.338309) (xy 93.01466 -389.388337) (xy 93.02387 -389.440741)
			(xy 93.024452 -389.467344) (xy 93.023978 -389.491334) (xy 93.016467 -389.538723) (xy 93.001636 -389.584354)
			(xy 92.979851 -389.627104) (xy 92.951648 -389.66592) (xy 92.91772 -389.699848) (xy 92.878904 -389.728051)
			(xy 92.836154 -389.749836) (xy 92.790523 -389.764667) (xy 92.743134 -389.772178) (xy 92.719144 -389.772652)
			(xy 92.695612 -389.772214) (xy 92.649104 -389.765005) (xy 92.604255 -389.750736) (xy 92.562132 -389.729746)
			(xy 92.523733 -389.702533) (xy 92.489972 -389.669743) (xy 92.461649 -389.632156) (xy 92.450158 -389.611616)
			(xy 92.449904 -389.611108) (xy 92.449396 -389.610346) (xy 92.051632 -388.922006) (xy 92.039719 -388.899336)
			(xy 92.02278 -388.851012) (xy 92.01412 -388.800542) (xy 92.013532 -388.77494) (xy 92.013532 -388.774432)
			(xy 92.013689 -388.763083) (xy 92.015466 -388.740453) (xy 92.017088 -388.72922) (xy 92.018358 -388.72033)
			(xy 92.014802 -388.703058) (xy 91.971368 -388.631938) (xy 91.957398 -388.621016) (xy 91.949016 -388.617968)
			(xy 91.926608 -388.60995) (xy 91.884391 -388.587988) (xy 91.846095 -388.559737) (xy 91.81265 -388.525883)
			(xy 91.784866 -388.487246) (xy 91.763418 -388.444765) (xy 91.748826 -388.399469) (xy 91.741443 -388.352456)
			(xy 91.74099 -388.328662) (xy 91.741557 -388.302289) (xy 91.75064 -388.250331) (xy 91.768528 -388.20071)
			(xy 91.781122 -388.177532) (xy 91.785694 -388.169404) (xy 91.788488 -388.152132) (xy 91.773248 -388.069328)
			(xy 91.764104 -388.054088) (xy 91.756992 -388.0485) (xy 91.73482 -388.029796) (xy 91.694873 -387.987734)
			(xy 91.660556 -387.940966) (xy 91.632417 -387.890239) (xy 91.610908 -387.836366) (xy 91.596371 -387.780209)
			(xy 91.589041 -387.722666) (xy 91.58859 -387.693662) (xy 91.589185 -387.660341) (xy 91.598845 -387.594402)
			(xy 91.617969 -387.530563) (xy 91.631516 -387.500114) (xy 91.635743 -387.489642) (xy 91.635638 -387.467088)
			(xy 91.625912 -387.446739) (xy 91.617546 -387.439154) (xy 91.595289 -387.420492) (xy 91.555224 -387.378436)
			(xy 91.520803 -387.331648) (xy 91.492579 -387.280881) (xy 91.471005 -387.22695) (xy 91.456429 -387.170724)
			(xy 91.449084 -387.113105) (xy 91.448636 -387.084062) (xy 91.449093 -387.055136) (xy 91.456377 -386.997744)
			(xy 91.470835 -386.941728) (xy 91.492238 -386.88798) (xy 91.520244 -386.837359) (xy 91.554407 -386.790671)
			(xy 91.594181 -386.74866) (xy 91.616276 -386.729986) (xy 91.62325 -386.723641) (xy 91.632506 -386.707235)
			(xy 91.63431 -386.697982) (xy 91.638628 -386.666994) (xy 91.639535 -386.657757) (xy 91.635509 -386.639657)
			(xy 91.630754 -386.631688) (xy 91.617772 -386.611262) (xy 91.597189 -386.567462) (xy 91.5832 -386.521132)
			(xy 91.576104 -386.473259) (xy 91.575636 -386.449062) (xy 91.57589 -386.43687) (xy 91.576144 -386.427218)
			(xy 91.570048 -386.409184) (xy 91.511374 -386.341874) (xy 91.49461 -386.333238) (xy 91.484704 -386.332222)
			(xy 91.457802 -386.328816) (xy 91.405517 -386.314458) (xy 91.356273 -386.291766) (xy 91.31139 -386.261346)
			(xy 91.272069 -386.224014) (xy 91.239363 -386.180768) (xy 91.214149 -386.132767) (xy 91.1971 -386.081296)
			(xy 91.19235 -386.0546) (xy 91.190826 -386.045202) (xy 90.91803 -385.57327) (xy 90.910664 -385.567428)
			(xy 90.89191 -385.5516) (xy 90.858792 -385.515388) (xy 90.83138 -385.474684) (xy 90.810276 -385.430382)
			(xy 90.79594 -385.38345) (xy 90.788686 -385.334916) (xy 90.788236 -385.31038) (xy 90.271442 -385.31038)
			(xy 90.520012 -385.740402) (xy 90.527378 -385.746244) (xy 90.546155 -385.762047) (xy 90.579273 -385.798263)
			(xy 90.606684 -385.838971) (xy 90.627785 -385.883279) (xy 90.642115 -385.930216) (xy 90.64936 -385.978754)
			(xy 90.649806 -386.003292) (xy 90.649552 -386.015484) (xy 90.649298 -386.025136) (xy 90.655394 -386.04317)
			(xy 90.714068 -386.11048) (xy 90.730832 -386.119116) (xy 90.740484 -386.120132) (xy 90.767244 -386.123504)
			(xy 90.819267 -386.137724) (xy 90.868293 -386.160197) (xy 90.913022 -386.190327) (xy 90.95227 -386.227316)
			(xy 90.984996 -386.270183) (xy 91.010333 -386.317792) (xy 91.027609 -386.368881) (xy 91.036366 -386.422097)
			(xy 91.036902 -386.449062) (xy 91.03637 -386.476347) (xy 91.027415 -386.530178) (xy 91.009743 -386.581807)
			(xy 90.983832 -386.629834) (xy 90.950386 -386.672954) (xy 90.93073 -386.691886) (xy 90.923337 -386.699415)
			(xy 90.914807 -386.718689) (xy 90.91422 -386.729224) (xy 90.91422 -386.8039) (xy 90.91473 -386.814452)
			(xy 90.923278 -386.833748) (xy 90.93073 -386.841238) (xy 90.950369 -386.860185) (xy 90.983803 -386.903307)
			(xy 91.009708 -386.951331) (xy 91.02738 -387.002955) (xy 91.036341 -387.056779) (xy 91.036902 -387.084062)
			(xy 91.03646 -387.108179) (xy 91.029463 -387.155901) (xy 91.015611 -387.202102) (xy 90.995198 -387.245803)
			(xy 90.982292 -387.26618) (xy 90.97645 -387.27507) (xy 90.972894 -387.295136) (xy 90.993976 -387.387338)
			(xy 91.006168 -387.404102) (xy 91.015058 -387.409436) (xy 91.035864 -387.422282) (xy 91.073769 -387.453174)
			(xy 91.10671 -387.489312) (xy 91.13397 -387.529906) (xy 91.154955 -387.574073) (xy 91.169206 -387.620849)
			(xy 91.176413 -387.669213) (xy 91.176856 -387.693662) (xy 91.176451 -387.718036) (xy 91.169304 -387.766257)
			(xy 91.15516 -387.812907) (xy 91.134323 -387.856978) (xy 91.107247 -387.897514) (xy 91.074515 -387.933639)
			(xy 91.055952 -387.94944) (xy 91.047062 -387.956552) (xy 91.037664 -387.97611) (xy 91.03487 -388.075424)
			(xy 91.043506 -388.09549) (xy 91.051888 -388.10311) (xy 91.070343 -388.120566) (xy 91.101688 -388.160539)
			(xy 91.125983 -388.205149) (xy 91.142558 -388.253166) (xy 91.150957 -388.303263) (xy 91.151456 -388.328662)
			(xy 91.151353 -388.339943) (xy 91.149701 -388.362445) (xy 91.148154 -388.37362) (xy 91.146884 -388.38251)
			(xy 91.15044 -388.400036) (xy 91.193874 -388.470902) (xy 91.20759 -388.482078) (xy 91.216226 -388.484872)
			(xy 91.238466 -388.492821) (xy 91.280388 -388.514568) (xy 91.318463 -388.542509) (xy 91.351782 -388.575978)
			(xy 91.379552 -388.614178) (xy 91.390724 -388.634986) (xy 91.391232 -388.636002) (xy 91.783662 -389.314944)
			(xy 91.79647 -389.338285) (xy 91.814696 -389.388304) (xy 91.823963 -389.440726) (xy 91.824556 -389.467344)
			(xy 91.824102 -389.491349) (xy 91.816582 -389.538765) (xy 91.801735 -389.584421) (xy 91.779926 -389.627191)
			(xy 91.751693 -389.666022) (xy 91.717731 -389.699956) (xy 91.678878 -389.728157) (xy 91.63609 -389.749931)
			(xy 91.590422 -389.76474) (xy 91.542999 -389.772221) (xy 91.518994 -389.772652) (xy 91.495463 -389.772173)
			(xy 91.448957 -389.764972) (xy 91.404109 -389.75071) (xy 91.361986 -389.729727) (xy 91.323587 -389.70252)
			(xy 91.289824 -389.669736) (xy 91.261499 -389.632154) (xy 91.250008 -389.611616) (xy 91.249754 -389.611108)
			(xy 91.249246 -389.610346) (xy 90.851482 -388.922006) (xy 90.839608 -388.899328) (xy 90.822756 -388.850996)
			(xy 90.814182 -388.800533) (xy 90.813636 -388.77494) (xy 90.813636 -388.774432) (xy 90.813727 -388.763087)
			(xy 90.815382 -388.740458) (xy 90.816938 -388.72922) (xy 90.818208 -388.72033) (xy 90.814652 -388.703058)
			(xy 90.771218 -388.631938) (xy 90.757248 -388.621016) (xy 90.748866 -388.617968) (xy 90.726469 -388.609922)
			(xy 90.68425 -388.587966) (xy 90.645952 -388.55972) (xy 90.612505 -388.525871) (xy 90.58472 -388.487238)
			(xy 90.56327 -388.44476) (xy 90.548677 -388.399466) (xy 90.541293 -388.352455) (xy 90.54084 -388.328662)
			(xy 90.541353 -388.303266) (xy 90.549763 -388.253176) (xy 90.566346 -388.205168) (xy 90.590643 -388.160565)
			(xy 90.621986 -388.120598) (xy 90.640408 -388.10311) (xy 90.64879 -388.09549) (xy 90.657426 -388.075424)
			(xy 90.654632 -387.97611) (xy 90.645234 -387.956552) (xy 90.636344 -387.94944) (xy 90.617805 -387.933614)
			(xy 90.585085 -387.897488) (xy 90.558015 -387.856954) (xy 90.537181 -387.812889) (xy 90.523033 -387.766246)
			(xy 90.515878 -387.718033) (xy 90.51544 -387.693662) (xy 90.515855 -387.669545) (xy 90.522862 -387.621821)
			(xy 90.536722 -387.57562) (xy 90.557141 -387.531921) (xy 90.57005 -387.511544) (xy 90.575892 -387.502654)
			(xy 90.579448 -387.482588) (xy 90.558366 -387.390386) (xy 90.546174 -387.373622) (xy 90.537284 -387.368288)
			(xy 90.516498 -387.35541) (xy 90.478592 -387.324525) (xy 90.445647 -387.288394) (xy 90.418384 -387.247804)
			(xy 90.397396 -387.203642) (xy 90.383142 -387.156871) (xy 90.375931 -387.10851) (xy 90.375486 -387.084062)
			(xy 90.376037 -387.056778) (xy 90.384988 -387.002948) (xy 90.402656 -386.951319) (xy 90.428562 -386.903292)
			(xy 90.462004 -386.860171) (xy 90.481658 -386.841238) (xy 90.489039 -386.833698) (xy 90.497576 -386.814432)
			(xy 90.498168 -386.8039) (xy 90.498168 -386.729224) (xy 90.497649 -386.718673) (xy 90.489108 -386.699377)
			(xy 90.481658 -386.691886) (xy 90.462028 -386.67293) (xy 90.428593 -386.62981) (xy 90.402687 -386.581788)
			(xy 90.385013 -386.530166) (xy 90.376049 -386.476344) (xy 90.375486 -386.449062) (xy 90.37574 -386.43687)
			(xy 90.375994 -386.427218) (xy 90.369898 -386.409184) (xy 90.311224 -386.341874) (xy 90.29446 -386.333238)
			(xy 90.284808 -386.332222) (xy 90.257907 -386.328812) (xy 90.205621 -386.314456) (xy 90.156378 -386.291764)
			(xy 90.111495 -386.261345) (xy 90.072173 -386.224013) (xy 90.039468 -386.180767) (xy 90.014253 -386.132767)
			(xy 89.997204 -386.081296) (xy 89.992454 -386.0546) (xy 89.99093 -386.045202) (xy 89.718134 -385.57327)
			(xy 89.710768 -385.567428) (xy 89.692015 -385.551599) (xy 89.658896 -385.515387) (xy 89.631485 -385.474684)
			(xy 89.61038 -385.430382) (xy 89.596044 -385.38345) (xy 89.58879 -385.334916) (xy 89.58834 -385.31038)
			(xy 89.071256 -385.31038) (xy 89.319862 -385.740402) (xy 89.327228 -385.746244) (xy 89.346015 -385.762035)
			(xy 89.379131 -385.798255) (xy 89.406539 -385.838966) (xy 89.427638 -385.883276) (xy 89.441967 -385.930214)
			(xy 89.449211 -385.978754) (xy 89.449656 -386.003292) (xy 89.449402 -386.015484) (xy 89.449148 -386.025136)
			(xy 89.455244 -386.04317) (xy 89.513918 -386.11048) (xy 89.530682 -386.119116) (xy 89.540588 -386.120132)
			(xy 89.567349 -386.123501) (xy 89.619371 -386.137722) (xy 89.668397 -386.160195) (xy 89.713127 -386.190326)
			(xy 89.752375 -386.227315) (xy 89.785101 -386.270182) (xy 89.810437 -386.317791) (xy 89.827713 -386.368881)
			(xy 89.83647 -386.422096) (xy 89.837006 -386.449062) (xy 89.836473 -386.476347) (xy 89.827518 -386.530178)
			(xy 89.809846 -386.581807) (xy 89.783935 -386.629834) (xy 89.75049 -386.672954) (xy 89.730834 -386.691886)
			(xy 89.723441 -386.699415) (xy 89.714911 -386.718689) (xy 89.714324 -386.729224) (xy 89.714324 -386.8039)
			(xy 89.714833 -386.814452) (xy 89.723381 -386.833748) (xy 89.730834 -386.841238) (xy 89.750474 -386.860184)
			(xy 89.783908 -386.903306) (xy 89.809812 -386.951331) (xy 89.827484 -387.002955) (xy 89.836445 -387.056779)
			(xy 89.837006 -387.084062) (xy 89.836563 -387.108178) (xy 89.829566 -387.155901) (xy 89.815714 -387.202102)
			(xy 89.795302 -387.245803) (xy 89.782396 -387.26618) (xy 89.776554 -387.27507) (xy 89.772998 -387.295136)
			(xy 89.79408 -387.387338) (xy 89.806272 -387.404102) (xy 89.815162 -387.409436) (xy 89.835969 -387.422281)
			(xy 89.873873 -387.453173) (xy 89.906815 -387.489311) (xy 89.934075 -387.529906) (xy 89.955059 -387.574073)
			(xy 89.96931 -387.620848) (xy 89.976517 -387.669213) (xy 89.97696 -387.693662) (xy 89.976553 -387.718036)
			(xy 89.969407 -387.766257) (xy 89.955262 -387.812907) (xy 89.934427 -387.856978) (xy 89.90735 -387.897514)
			(xy 89.874619 -387.933639) (xy 89.856056 -387.94944) (xy 89.847166 -387.956552) (xy 89.837768 -387.97611)
			(xy 89.834974 -388.075424) (xy 89.84361 -388.09549) (xy 89.851992 -388.10311) (xy 89.870429 -388.120584)
			(xy 89.90178 -388.16055) (xy 89.92608 -388.205156) (xy 89.942659 -388.253169) (xy 89.95106 -388.303264)
			(xy 89.95156 -388.328662) (xy 89.951457 -388.339943) (xy 89.949805 -388.362445) (xy 89.948258 -388.37362)
			(xy 89.946988 -388.38251) (xy 89.950544 -388.400036) (xy 89.993978 -388.470902) (xy 90.007694 -388.482078)
			(xy 90.01633 -388.484872) (xy 90.038571 -388.492819) (xy 90.080493 -388.514567) (xy 90.118567 -388.542508)
			(xy 90.151886 -388.575978) (xy 90.179656 -388.614178) (xy 90.190828 -388.634986) (xy 90.191336 -388.636002)
			(xy 90.583766 -389.314944) (xy 90.596575 -389.338285) (xy 90.6148 -389.388303) (xy 90.624067 -389.440726)
			(xy 90.62466 -389.467344) (xy 90.624301 -389.491353) (xy 90.616779 -389.53878) (xy 90.601926 -389.584444)
			(xy 90.580109 -389.62722) (xy 90.551865 -389.666055) (xy 90.517891 -389.69999) (xy 90.479025 -389.72819)
			(xy 90.436223 -389.749958) (xy 90.390542 -389.764759) (xy 90.343108 -389.772228) (xy 90.319098 -389.772652)
			(xy 90.295567 -389.77217) (xy 90.249061 -389.764969) (xy 90.204214 -389.750708) (xy 90.16209 -389.729725)
			(xy 90.123691 -389.702519) (xy 90.089928 -389.669736) (xy 90.061604 -389.632154) (xy 90.050112 -389.611616)
			(xy 90.049858 -389.611108) (xy 90.04935 -389.610346) (xy 89.651586 -388.922006) (xy 89.639712 -388.899328)
			(xy 89.62286 -388.850996) (xy 89.614286 -388.800533) (xy 89.61374 -388.77494) (xy 89.61374 -388.774432)
			(xy 89.613831 -388.763087) (xy 89.615486 -388.740458) (xy 89.617042 -388.72922) (xy 89.618312 -388.72033)
			(xy 89.614756 -388.703058) (xy 89.571322 -388.631938) (xy 89.557352 -388.621016) (xy 89.54897 -388.617968)
			(xy 89.526574 -388.609919) (xy 89.484355 -388.587964) (xy 89.446057 -388.559719) (xy 89.41261 -388.52587)
			(xy 89.384824 -388.487238) (xy 89.363374 -388.444759) (xy 89.348781 -388.399466) (xy 89.341397 -388.352455)
			(xy 89.340944 -388.328662) (xy 89.341456 -388.303266) (xy 89.349866 -388.253176) (xy 89.366449 -388.205168)
			(xy 89.390747 -388.160565) (xy 89.42209 -388.120598) (xy 89.440512 -388.10311) (xy 89.448894 -388.09549)
			(xy 89.45753 -388.075424) (xy 89.454736 -387.97611) (xy 89.445338 -387.956552) (xy 89.436448 -387.94944)
			(xy 89.41791 -387.933613) (xy 89.385189 -387.897487) (xy 89.358119 -387.856954) (xy 89.337285 -387.812889)
			(xy 89.323137 -387.766246) (xy 89.315982 -387.718033) (xy 89.315544 -387.693662) (xy 89.315959 -387.669545)
			(xy 89.322966 -387.621821) (xy 89.336826 -387.57562) (xy 89.357245 -387.531921) (xy 89.370154 -387.511544)
			(xy 89.375996 -387.502654) (xy 89.379552 -387.482588) (xy 89.35847 -387.390386) (xy 89.346278 -387.373622)
			(xy 89.337388 -387.368288) (xy 89.316603 -387.355408) (xy 89.278696 -387.324524) (xy 89.245752 -387.288393)
			(xy 89.218488 -387.247804) (xy 89.1975 -387.203642) (xy 89.183246 -387.156871) (xy 89.176035 -387.10851)
			(xy 89.17559 -387.084062) (xy 89.17614 -387.056778) (xy 89.185091 -387.002948) (xy 89.202759 -386.951319)
			(xy 89.228666 -386.903292) (xy 89.262107 -386.860171) (xy 89.281762 -386.841238) (xy 89.289143 -386.833699)
			(xy 89.29768 -386.814432) (xy 89.298272 -386.8039) (xy 89.298272 -386.729224) (xy 89.297752 -386.718673)
			(xy 89.289211 -386.699377) (xy 89.281762 -386.691886) (xy 89.262133 -386.672929) (xy 89.228698 -386.62981)
			(xy 89.202792 -386.581788) (xy 89.185117 -386.530166) (xy 89.176153 -386.476344) (xy 89.17559 -386.449062)
			(xy 89.175844 -386.43687) (xy 89.176098 -386.427218) (xy 89.170002 -386.409184) (xy 89.111328 -386.341874)
			(xy 89.094564 -386.333238) (xy 89.084658 -386.332222) (xy 89.057751 -386.328852) (xy 89.005465 -386.314488)
			(xy 88.956222 -386.291789) (xy 88.911339 -386.261364) (xy 88.872019 -386.224026) (xy 88.839315 -386.180776)
			(xy 88.814101 -386.132771) (xy 88.797054 -386.081298) (xy 88.792304 -386.0546) (xy 88.79078 -386.045202)
			(xy 88.51773 -385.572762) (xy 88.510618 -385.56692) (xy 88.49189 -385.551135) (xy 88.458834 -385.514995)
			(xy 88.431476 -385.474371) (xy 88.410416 -385.430153) (xy 88.396115 -385.38331) (xy 88.388887 -385.334869)
			(xy 88.388444 -385.31038) (xy 87.871396 -385.31038) (xy 88.119966 -385.740402) (xy 88.127332 -385.746244)
			(xy 88.14612 -385.762034) (xy 88.179236 -385.798254) (xy 88.206643 -385.838965) (xy 88.227742 -385.883275)
			(xy 88.242071 -385.930214) (xy 88.249315 -385.978753) (xy 88.24976 -386.003292) (xy 88.249506 -386.015484)
			(xy 88.249252 -386.025136) (xy 88.255348 -386.04317) (xy 88.314022 -386.11048) (xy 88.330786 -386.119116)
			(xy 88.340692 -386.120132) (xy 88.367453 -386.123498) (xy 88.419476 -386.137719) (xy 88.468502 -386.160193)
			(xy 88.513231 -386.190324) (xy 88.552479 -386.227314) (xy 88.585205 -386.270181) (xy 88.610541 -386.317791)
			(xy 88.627817 -386.36888) (xy 88.636574 -386.422096) (xy 88.63711 -386.449062) (xy 88.636576 -386.476347)
			(xy 88.627621 -386.530178) (xy 88.609949 -386.581807) (xy 88.584039 -386.629834) (xy 88.550594 -386.672954)
			(xy 88.530938 -386.691886) (xy 88.523546 -386.699416) (xy 88.515015 -386.718689) (xy 88.514428 -386.729224)
			(xy 88.514428 -386.8039) (xy 88.514935 -386.814452) (xy 88.523485 -386.833748) (xy 88.530938 -386.841238)
			(xy 88.550579 -386.860183) (xy 88.584012 -386.903306) (xy 88.609916 -386.95133) (xy 88.627588 -387.002955)
			(xy 88.636549 -387.056779) (xy 88.63711 -387.084062) (xy 88.636666 -387.108178) (xy 88.629669 -387.155901)
			(xy 88.615818 -387.202102) (xy 88.595406 -387.245803) (xy 88.5825 -387.26618) (xy 88.576658 -387.27507)
			(xy 88.573102 -387.295136) (xy 88.594184 -387.387338) (xy 88.606376 -387.404102) (xy 88.615266 -387.409436)
			(xy 88.636074 -387.422279) (xy 88.673978 -387.453172) (xy 88.706919 -387.48931) (xy 88.734179 -387.529905)
			(xy 88.755163 -387.574072) (xy 88.769414 -387.620848) (xy 88.776621 -387.669213) (xy 88.777064 -387.693662)
			(xy 88.776656 -387.718036) (xy 88.769509 -387.766257) (xy 88.755365 -387.812907) (xy 88.73453 -387.856977)
			(xy 88.707454 -387.897514) (xy 88.674723 -387.933639) (xy 88.65616 -387.94944) (xy 88.64727 -387.956552)
			(xy 88.637872 -387.97611) (xy 88.635078 -388.075424) (xy 88.643714 -388.09549) (xy 88.652096 -388.10311)
			(xy 88.670534 -388.120584) (xy 88.701884 -388.16055) (xy 88.726184 -388.205155) (xy 88.742764 -388.253169)
			(xy 88.751164 -388.303264) (xy 88.751664 -388.328662) (xy 88.751561 -388.339943) (xy 88.749909 -388.362445)
			(xy 88.748362 -388.37362) (xy 88.747092 -388.382764) (xy 88.750394 -388.400036) (xy 88.794082 -388.471156)
			(xy 88.807798 -388.482078) (xy 88.816434 -388.484872) (xy 88.844604 -388.495057) (xy 88.896547 -388.524877)
			(xy 88.919558 -388.544054) (xy 88.941038 -388.56364) (xy 88.976854 -388.609415) (xy 88.990678 -388.634986)
			(xy 88.99144 -388.636256) (xy 89.383616 -389.314944) (xy 89.39635 -389.338309) (xy 89.414465 -389.388337)
			(xy 89.423674 -389.440741) (xy 89.424256 -389.467344) (xy 89.423778 -389.491334) (xy 89.416267 -389.538723)
			(xy 89.401436 -389.584353) (xy 89.379652 -389.627103) (xy 89.351449 -389.665919) (xy 89.317522 -389.699846)
			(xy 89.278706 -389.72805) (xy 89.235957 -389.749835) (xy 89.190327 -389.764666) (xy 89.142938 -389.772178)
			(xy 89.118948 -389.772652) (xy 89.095416 -389.772211) (xy 89.048908 -389.765002) (xy 89.00406 -389.750734)
			(xy 88.961936 -389.729744) (xy 88.923537 -389.702532) (xy 88.889776 -389.669743) (xy 88.861453 -389.632156)
			(xy 88.849962 -389.611616) (xy 88.849708 -389.611108) (xy 88.8492 -389.610346) (xy 88.45169 -388.921752)
			(xy 88.441116 -388.901826) (xy 88.425314 -388.859576) (xy 88.415907 -388.815459) (xy 88.414098 -388.792974)
			(xy 88.41359 -388.781798) (xy 88.413336 -388.774432) (xy 88.413493 -388.763083) (xy 88.41527 -388.740453)
			(xy 88.416892 -388.72922) (xy 88.418162 -388.72033) (xy 88.414606 -388.703058) (xy 88.371172 -388.631938)
			(xy 88.357456 -388.620762) (xy 88.34882 -388.617968) (xy 88.326428 -388.609943) (xy 88.284256 -388.587947)
			(xy 88.246006 -388.559675) (xy 88.212604 -388.525813) (xy 88.184859 -388.48718) (xy 88.163442 -388.444711)
			(xy 88.148871 -388.399433) (xy 88.141499 -388.352444) (xy 88.141048 -388.328662) (xy 88.141558 -388.303266)
			(xy 88.149969 -388.253176) (xy 88.166552 -388.205167) (xy 88.19085 -388.160565) (xy 88.222193 -388.120597)
			(xy 88.240616 -388.10311) (xy 88.248998 -388.09549) (xy 88.257634 -388.075424) (xy 88.25484 -387.97611)
			(xy 88.245442 -387.956552) (xy 88.236552 -387.94944) (xy 88.218015 -387.933612) (xy 88.185294 -387.897486)
			(xy 88.158224 -387.856953) (xy 88.137389 -387.812889) (xy 88.123241 -387.766246) (xy 88.116086 -387.718033)
			(xy 88.115648 -387.693662) (xy 88.116062 -387.669544) (xy 88.123069 -387.621821) (xy 88.136929 -387.57562)
			(xy 88.157349 -387.53192) (xy 88.170258 -387.511544) (xy 88.1761 -387.502654) (xy 88.179656 -387.482588)
			(xy 88.158574 -387.390386) (xy 88.146382 -387.373622) (xy 88.137492 -387.368288) (xy 88.116708 -387.355407)
			(xy 88.078801 -387.324523) (xy 88.045856 -387.288392) (xy 88.018593 -387.247803) (xy 87.997605 -387.203642)
			(xy 87.98335 -387.15687) (xy 87.976139 -387.10851) (xy 87.975694 -387.084062) (xy 87.976243 -387.056777)
			(xy 87.985193 -387.002948) (xy 88.002862 -386.951318) (xy 88.028769 -386.903291) (xy 88.062211 -386.860171)
			(xy 88.081866 -386.841238) (xy 88.089248 -386.8337) (xy 88.097785 -386.814433) (xy 88.098376 -386.8039)
			(xy 88.098376 -386.729224) (xy 88.097855 -386.718673) (xy 88.089315 -386.699377) (xy 88.081866 -386.691886)
			(xy 88.062238 -386.672929) (xy 88.028802 -386.629809) (xy 88.002896 -386.581788) (xy 87.985221 -386.530166)
			(xy 87.976257 -386.476344) (xy 87.975694 -386.449062) (xy 87.975948 -386.43687) (xy 87.976202 -386.427218)
			(xy 87.970106 -386.409184) (xy 87.911432 -386.341874) (xy 87.894668 -386.333238) (xy 87.884762 -386.332222)
			(xy 87.857855 -386.328849) (xy 87.80557 -386.314485) (xy 87.756326 -386.291787) (xy 87.711444 -386.261362)
			(xy 87.672124 -386.224025) (xy 87.639419 -386.180775) (xy 87.614205 -386.132771) (xy 87.597158 -386.081298)
			(xy 87.592408 -386.0546) (xy 87.590884 -386.045202) (xy 87.318088 -385.57327) (xy 87.310722 -385.567428)
			(xy 87.29198 -385.551586) (xy 87.258859 -385.515378) (xy 87.231444 -385.474678) (xy 87.210337 -385.430378)
			(xy 87.195999 -385.383448) (xy 87.188745 -385.334916) (xy 87.188294 -385.31038) (xy 86.6715 -385.31038)
			(xy 86.92007 -385.740402) (xy 86.927436 -385.746244) (xy 86.946225 -385.762033) (xy 86.97934 -385.798253)
			(xy 87.006748 -385.838965) (xy 87.027846 -385.883275) (xy 87.042175 -385.930214) (xy 87.049419 -385.978753)
			(xy 87.049864 -386.003292) (xy 87.04961 -386.015484) (xy 87.049356 -386.025136) (xy 87.055452 -386.04317)
			(xy 87.114126 -386.11048) (xy 87.13089 -386.119116) (xy 87.140542 -386.120132) (xy 87.167309 -386.123457)
			(xy 87.219332 -386.137686) (xy 87.268358 -386.160167) (xy 87.313087 -386.190304) (xy 87.352333 -386.227298)
			(xy 87.385058 -386.27017) (xy 87.410393 -386.317783) (xy 87.427668 -386.368876) (xy 87.436425 -386.422095)
			(xy 87.43696 -386.449062) (xy 87.43641 -386.476346) (xy 87.427457 -386.530175) (xy 87.409787 -386.581804)
			(xy 87.383881 -386.629831) (xy 87.350441 -386.672952) (xy 87.330788 -386.691886) (xy 87.323389 -386.699409)
			(xy 87.314863 -386.718688) (xy 87.314278 -386.729224) (xy 87.314278 -386.8039) (xy 87.3148 -386.81445)
			(xy 87.323341 -386.833745) (xy 87.330788 -386.841238) (xy 87.350438 -386.860174) (xy 87.383868 -386.9033)
			(xy 87.40977 -386.951327) (xy 87.427439 -387.002953) (xy 87.436399 -387.056779) (xy 87.43696 -387.084062)
			(xy 87.436508 -387.108178) (xy 87.429512 -387.1559) (xy 87.415663 -387.202101) (xy 87.395254 -387.245802)
			(xy 87.38235 -387.26618) (xy 87.376508 -387.27507) (xy 87.372952 -387.295136) (xy 87.394034 -387.387338)
			(xy 87.406226 -387.404102) (xy 87.415116 -387.409436) (xy 87.435913 -387.422298) (xy 87.473819 -387.453185)
			(xy 87.506763 -387.489319) (xy 87.534025 -387.529911) (xy 87.555011 -387.574076) (xy 87.569263 -387.62085)
			(xy 87.576471 -387.669213) (xy 87.576914 -387.693662) (xy 87.576488 -387.718035) (xy 87.569342 -387.766254)
			(xy 87.555201 -387.812903) (xy 87.534368 -387.856973) (xy 87.507296 -387.89751) (xy 87.474571 -387.933637)
			(xy 87.45601 -387.94944) (xy 87.44712 -387.956552) (xy 87.437722 -387.97611) (xy 87.434928 -388.075424)
			(xy 87.443564 -388.09549) (xy 87.451946 -388.10311) (xy 87.470393 -388.120574) (xy 87.501741 -388.160544)
			(xy 87.526038 -388.205152) (xy 87.542615 -388.253167) (xy 87.551015 -388.303264) (xy 87.551514 -388.328662)
			(xy 87.55141 -388.339943) (xy 87.549759 -388.362445) (xy 87.548212 -388.37362) (xy 87.546942 -388.38251)
			(xy 87.550498 -388.400036) (xy 87.593932 -388.470902) (xy 87.607648 -388.482078) (xy 87.616284 -388.484872)
			(xy 87.638534 -388.492794) (xy 87.680455 -388.514548) (xy 87.718527 -388.542496) (xy 87.751845 -388.575971)
			(xy 87.779612 -388.614175) (xy 87.790782 -388.634986) (xy 87.79129 -388.636002) (xy 88.18372 -389.314944)
			(xy 88.196454 -389.338309) (xy 88.214569 -389.388337) (xy 88.223778 -389.440741) (xy 88.22436 -389.467344)
			(xy 88.224002 -389.491341) (xy 88.216487 -389.538742) (xy 88.20165 -389.584385) (xy 88.179855 -389.627144)
			(xy 88.151639 -389.665968) (xy 88.117698 -389.699899) (xy 88.078866 -389.728103) (xy 88.0361 -389.749885)
			(xy 87.990453 -389.764709) (xy 87.943049 -389.772209) (xy 87.919052 -389.772652) (xy 87.89552 -389.772207)
			(xy 87.849012 -389.765) (xy 87.804164 -389.750732) (xy 87.76204 -389.729743) (xy 87.723642 -389.702531)
			(xy 87.68988 -389.669742) (xy 87.661557 -389.632156) (xy 87.650066 -389.611616) (xy 87.649812 -389.611108)
			(xy 87.649304 -389.610346) (xy 87.25154 -388.922006) (xy 87.239628 -388.899336) (xy 87.222688 -388.851012)
			(xy 87.214028 -388.800542) (xy 87.21344 -388.77494) (xy 87.21344 -388.774432) (xy 87.213597 -388.763083)
			(xy 87.215374 -388.740453) (xy 87.216996 -388.72922) (xy 87.218266 -388.72033) (xy 87.21471 -388.703058)
			(xy 87.171276 -388.631938) (xy 87.157306 -388.621016) (xy 87.148924 -388.617968) (xy 87.126518 -388.609946)
			(xy 87.0843 -388.587984) (xy 87.046004 -388.559734) (xy 87.012559 -388.525881) (xy 86.984775 -388.487245)
			(xy 86.963327 -388.444764) (xy 86.948734 -388.399468) (xy 86.941351 -388.352456) (xy 86.940898 -388.328662)
			(xy 86.941424 -388.303267) (xy 86.949834 -388.253178) (xy 86.966414 -388.205171) (xy 86.990708 -388.160568)
			(xy 87.022046 -388.120599) (xy 87.040466 -388.10311) (xy 87.048848 -388.09549) (xy 87.057484 -388.075424)
			(xy 87.05469 -387.97611) (xy 87.045292 -387.956552) (xy 87.036402 -387.94944) (xy 87.017875 -387.933601)
			(xy 86.985151 -387.897479) (xy 86.958078 -387.856948) (xy 86.937242 -387.812886) (xy 86.923092 -387.766244)
			(xy 86.915936 -387.718032) (xy 86.915498 -387.693662) (xy 86.915904 -387.669544) (xy 86.922912 -387.62182)
			(xy 86.936774 -387.575619) (xy 86.957197 -387.53192) (xy 86.970108 -387.511544) (xy 86.97595 -387.502654)
			(xy 86.979506 -387.482588) (xy 86.958424 -387.390386) (xy 86.946232 -387.373622) (xy 86.937342 -387.368288)
			(xy 86.916546 -387.355425) (xy 86.878642 -387.324536) (xy 86.8457 -387.288401) (xy 86.818439 -387.247809)
			(xy 86.797452 -387.203645) (xy 86.783199 -387.156872) (xy 86.775989 -387.10851) (xy 86.775544 -387.084062)
			(xy 86.776109 -387.056778) (xy 86.785058 -387.00295) (xy 86.802724 -386.951322) (xy 86.828627 -386.903294)
			(xy 86.862064 -386.860172) (xy 86.881716 -386.841238) (xy 86.889105 -386.833706) (xy 86.897636 -386.814434)
			(xy 86.898226 -386.8039) (xy 86.898226 -386.729224) (xy 86.89769 -386.718675) (xy 86.889159 -386.69938)
			(xy 86.881716 -386.691886) (xy 86.862079 -386.672938) (xy 86.828646 -386.629815) (xy 86.802743 -386.581791)
			(xy 86.78507 -386.530168) (xy 86.776107 -386.476344) (xy 86.775544 -386.449062) (xy 86.775798 -386.43687)
			(xy 86.776052 -386.427218) (xy 86.769956 -386.409184) (xy 86.711282 -386.341874) (xy 86.694518 -386.333238)
			(xy 86.684866 -386.332222) (xy 86.65796 -386.328846) (xy 86.605674 -386.314483) (xy 86.556431 -386.291785)
			(xy 86.511548 -386.261361) (xy 86.472228 -386.224024) (xy 86.439523 -386.180775) (xy 86.414309 -386.132771)
			(xy 86.397262 -386.081298) (xy 86.392512 -386.0546) (xy 86.390988 -386.045202) (xy 86.118192 -385.57327)
			(xy 86.110826 -385.567428) (xy 86.092064 -385.551609) (xy 86.058948 -385.515394) (xy 86.031539 -385.474688)
			(xy 86.010436 -385.430384) (xy 85.996101 -385.383451) (xy 85.988848 -385.334917) (xy 85.988398 -385.31038)
			(xy 85.47135 -385.31038) (xy 85.71992 -385.740402) (xy 85.727286 -385.746244) (xy 85.746064 -385.762045)
			(xy 85.779183 -385.798262) (xy 85.806592 -385.83897) (xy 85.827693 -385.883278) (xy 85.842023 -385.930216)
			(xy 85.849268 -385.978754) (xy 85.849714 -386.003292) (xy 85.84946 -386.015484) (xy 85.849206 -386.025136)
			(xy 85.855302 -386.04317) (xy 85.913976 -386.11048) (xy 85.93074 -386.119116) (xy 85.940646 -386.120132)
			(xy 85.967413 -386.123454) (xy 86.019437 -386.137683) (xy 86.068462 -386.160165) (xy 86.113191 -386.190302)
			(xy 86.152438 -386.227297) (xy 86.185162 -386.270169) (xy 86.210497 -386.317783) (xy 86.227772 -386.368876)
			(xy 86.236529 -386.422095) (xy 86.237064 -386.449062) (xy 86.236645 -386.473264) (xy 86.22957 -386.521149)
			(xy 86.215582 -386.567489) (xy 86.19498 -386.611291) (xy 86.181946 -386.631688) (xy 86.177156 -386.639644)
			(xy 86.173124 -386.657756) (xy 86.174072 -386.666994) (xy 86.17839 -386.697982) (xy 86.180075 -386.707277)
			(xy 86.189354 -386.723719) (xy 86.196424 -386.729986) (xy 86.218504 -386.748678) (xy 86.258277 -386.790687)
			(xy 86.292441 -386.837373) (xy 86.32045 -386.887991) (xy 86.341859 -386.941735) (xy 86.356325 -386.997747)
			(xy 86.363619 -387.055137) (xy 86.364064 -387.084062) (xy 86.363472 -387.117383) (xy 86.35381 -387.183322)
			(xy 86.334685 -387.247161) (xy 86.321138 -387.27761) (xy 86.31687 -387.28807) (xy 86.316984 -387.310636)
			(xy 86.32673 -387.330989) (xy 86.335108 -387.33857) (xy 86.35734 -387.357261) (xy 86.397404 -387.399314)
			(xy 86.431825 -387.446097) (xy 86.460052 -387.496859) (xy 86.48163 -387.550784) (xy 86.496213 -387.607006)
			(xy 86.503565 -387.664621) (xy 86.504018 -387.693662) (xy 86.503554 -387.722667) (xy 86.496242 -387.780216)
			(xy 86.481719 -387.836379) (xy 86.460217 -387.890258) (xy 86.43208 -387.940988) (xy 86.39776 -387.987757)
			(xy 86.357807 -388.029816) (xy 86.335616 -388.0485) (xy 86.328504 -388.054088) (xy 86.31936 -388.069328)
			(xy 86.30412 -388.152132) (xy 86.306914 -388.169404) (xy 86.311486 -388.177532) (xy 86.324057 -388.200721)
			(xy 86.341934 -388.250341) (xy 86.351036 -388.302292) (xy 86.351618 -388.328662) (xy 86.351514 -388.339943)
			(xy 86.349863 -388.362445) (xy 86.348316 -388.37362) (xy 86.347046 -388.38251) (xy 86.350602 -388.400036)
			(xy 86.394036 -388.470902) (xy 86.407752 -388.482078) (xy 86.416388 -388.484872) (xy 86.438639 -388.492792)
			(xy 86.48056 -388.514547) (xy 86.518632 -388.542495) (xy 86.551949 -388.575971) (xy 86.579716 -388.614175)
			(xy 86.590886 -388.634986) (xy 86.591394 -388.636002) (xy 86.983824 -389.314944) (xy 86.996558 -389.338309)
			(xy 87.014673 -389.388337) (xy 87.023882 -389.440741) (xy 87.024464 -389.467344) (xy 87.024078 -389.491339)
			(xy 87.016564 -389.538736) (xy 87.001728 -389.584375) (xy 86.979935 -389.62713) (xy 86.951722 -389.66595)
			(xy 86.917783 -389.699879) (xy 86.878955 -389.728081) (xy 86.836193 -389.749861) (xy 86.79055 -389.764684)
			(xy 86.743151 -389.772185) (xy 86.719156 -389.772652) (xy 86.695624 -389.772204) (xy 86.649117 -389.764997)
			(xy 86.604268 -389.75073) (xy 86.562145 -389.729741) (xy 86.523746 -389.70253) (xy 86.489984 -389.669742)
			(xy 86.461661 -389.632156) (xy 86.45017 -389.611616) (xy 86.449916 -389.611108) (xy 86.449408 -389.610346)
			(xy 86.051644 -388.922006) (xy 86.039732 -388.899336) (xy 86.022793 -388.851012) (xy 86.014132 -388.800542)
			(xy 86.013544 -388.77494) (xy 86.013544 -388.774432) (xy 86.013701 -388.763083) (xy 86.015478 -388.740453)
			(xy 86.0171 -388.72922) (xy 86.01837 -388.72033) (xy 86.014814 -388.703058) (xy 85.97138 -388.631938)
			(xy 85.95741 -388.621016) (xy 85.949028 -388.617968) (xy 85.926623 -388.609943) (xy 85.884405 -388.587982)
			(xy 85.846109 -388.559733) (xy 85.812663 -388.52588) (xy 85.784879 -388.487244) (xy 85.763431 -388.444764)
			(xy 85.748838 -388.399468) (xy 85.741455 -388.352456) (xy 85.741002 -388.328662) (xy 85.741567 -388.302289)
			(xy 85.750651 -388.25033) (xy 85.768539 -388.20071) (xy 85.781134 -388.177532) (xy 85.785706 -388.169404)
			(xy 85.7885 -388.152132) (xy 85.77326 -388.069328) (xy 85.764116 -388.054088) (xy 85.757004 -388.0485)
			(xy 85.734834 -388.029793) (xy 85.694887 -387.987732) (xy 85.660569 -387.940964) (xy 85.63243 -387.890238)
			(xy 85.61092 -387.836366) (xy 85.596384 -387.780209) (xy 85.589053 -387.722666) (xy 85.588602 -387.693662)
			(xy 85.589196 -387.660341) (xy 85.598856 -387.594402) (xy 85.617981 -387.530563) (xy 85.631528 -387.500114)
			(xy 85.635751 -387.489641) (xy 85.635646 -387.467089) (xy 85.625923 -387.44674) (xy 85.617558 -387.439154)
			(xy 85.595303 -387.420489) (xy 85.555238 -387.378433) (xy 85.520817 -387.331646) (xy 85.492592 -387.28088)
			(xy 85.471018 -387.22695) (xy 85.456441 -387.170723) (xy 85.449096 -387.113105) (xy 85.448648 -387.084062)
			(xy 85.449101 -387.055136) (xy 85.456384 -386.997743) (xy 85.470843 -386.941727) (xy 85.492247 -386.887979)
			(xy 85.520254 -386.837358) (xy 85.554417 -386.79067) (xy 85.594192 -386.74866) (xy 85.616288 -386.729986)
			(xy 85.623264 -386.723643) (xy 85.632519 -386.707236) (xy 85.634322 -386.697982) (xy 85.63864 -386.666994)
			(xy 85.639545 -386.657757) (xy 85.63552 -386.639657) (xy 85.630766 -386.631688) (xy 85.617786 -386.611261)
			(xy 85.597202 -386.567461) (xy 85.583212 -386.521132) (xy 85.576116 -386.473259) (xy 85.575648 -386.449062)
			(xy 85.575902 -386.43687) (xy 85.576156 -386.427218) (xy 85.57006 -386.409184) (xy 85.511386 -386.341874)
			(xy 85.494622 -386.333238) (xy 85.484716 -386.332222) (xy 85.457815 -386.328806) (xy 85.40553 -386.314451)
			(xy 85.356287 -386.29176) (xy 85.311403 -386.261342) (xy 85.272082 -386.22401) (xy 85.239376 -386.180766)
			(xy 85.214161 -386.132766) (xy 85.197112 -386.081296) (xy 85.192362 -386.0546) (xy 85.190838 -386.045202)
			(xy 84.918042 -385.57327) (xy 84.910676 -385.567428) (xy 84.891924 -385.551597) (xy 84.858806 -385.515386)
			(xy 84.831394 -385.474683) (xy 84.810288 -385.430381) (xy 84.795952 -385.38345) (xy 84.788698 -385.334916)
			(xy 84.788248 -385.31038) (xy 84.271454 -385.31038) (xy 84.520024 -385.740402) (xy 84.52739 -385.746244)
			(xy 84.546169 -385.762044) (xy 84.579287 -385.798261) (xy 84.606697 -385.83897) (xy 84.627798 -385.883278)
			(xy 84.642127 -385.930215) (xy 84.649372 -385.978754) (xy 84.649818 -386.003292) (xy 84.649564 -386.015484)
			(xy 84.64931 -386.025136) (xy 84.655406 -386.04317) (xy 84.71408 -386.11048) (xy 84.730844 -386.119116)
			(xy 84.740496 -386.120132) (xy 84.767257 -386.123495) (xy 84.81928 -386.137717) (xy 84.868306 -386.160191)
			(xy 84.913036 -386.190322) (xy 84.952283 -386.227312) (xy 84.985009 -386.27018) (xy 85.010346 -386.31779)
			(xy 85.027621 -386.36888) (xy 85.036378 -386.422096) (xy 85.036914 -386.449062) (xy 85.036404 -386.475049)
			(xy 85.028274 -386.526384) (xy 85.012213 -386.575814) (xy 84.988617 -386.622124) (xy 84.958067 -386.664172)
			(xy 84.921316 -386.700923) (xy 84.879268 -386.731473) (xy 84.832958 -386.755069) (xy 84.783528 -386.77113)
			(xy 84.732193 -386.77926) (xy 84.680219 -386.77926) (xy 84.628884 -386.77113) (xy 84.579454 -386.755069)
			(xy 84.533144 -386.731473) (xy 84.491096 -386.700923) (xy 84.454345 -386.664172) (xy 84.423795 -386.622124)
			(xy 84.400199 -386.575814) (xy 84.384138 -386.526384) (xy 84.376008 -386.475049) (xy 84.375498 -386.449062)
			(xy 84.375752 -386.43687) (xy 84.376006 -386.427218) (xy 84.36991 -386.409184) (xy 84.311236 -386.341874)
			(xy 84.294472 -386.333238) (xy 84.28482 -386.332222) (xy 84.257909 -386.328882) (xy 84.205622 -386.314512)
			(xy 84.156379 -386.291808) (xy 84.111497 -386.261378) (xy 84.072178 -386.224036) (xy 84.039474 -386.180783)
			(xy 84.014262 -386.132775) (xy 83.997215 -386.081299) (xy 83.992466 -386.0546) (xy 83.990942 -386.045202)
			(xy 83.718146 -385.57327) (xy 83.71078 -385.567428) (xy 83.692029 -385.551596) (xy 83.65891 -385.515385)
			(xy 83.631498 -385.474683) (xy 83.610393 -385.430381) (xy 83.596056 -385.383449) (xy 83.588802 -385.334916)
			(xy 83.588352 -385.31038) (xy 83.071268 -385.31038) (xy 83.319874 -385.740402) (xy 83.32724 -385.746244)
			(xy 83.34603 -385.762032) (xy 83.379145 -385.798253) (xy 83.406552 -385.838964) (xy 83.427651 -385.883275)
			(xy 83.441979 -385.930214) (xy 83.449223 -385.978753) (xy 83.449668 -386.003292) (xy 83.449414 -386.015484)
			(xy 83.44916 -386.025136) (xy 83.455256 -386.04317) (xy 83.51393 -386.11048) (xy 83.530694 -386.119116)
			(xy 83.5406 -386.120132) (xy 83.567362 -386.123492) (xy 83.619385 -386.137714) (xy 83.668411 -386.160189)
			(xy 83.71314 -386.190321) (xy 83.752388 -386.227311) (xy 83.785113 -386.270179) (xy 83.81045 -386.31779)
			(xy 83.827725 -386.36888) (xy 83.836482 -386.422096) (xy 83.837018 -386.449062) (xy 83.836481 -386.476347)
			(xy 83.827527 -386.530177) (xy 83.809855 -386.581806) (xy 83.783946 -386.629833) (xy 83.750502 -386.672954)
			(xy 83.730846 -386.691886) (xy 83.723455 -386.699417) (xy 83.714923 -386.71869) (xy 83.714336 -386.729224)
			(xy 83.714336 -386.8039) (xy 83.714841 -386.814453) (xy 83.723392 -386.833749) (xy 83.730846 -386.841238)
			(xy 83.750488 -386.860182) (xy 83.783921 -386.903305) (xy 83.809825 -386.95133) (xy 83.827496 -387.002955)
			(xy 83.836457 -387.056779) (xy 83.837018 -387.084062) (xy 83.836573 -387.108178) (xy 83.829576 -387.155901)
			(xy 83.815725 -387.202102) (xy 83.795314 -387.245803) (xy 83.782408 -387.26618) (xy 83.776566 -387.27507)
			(xy 83.77301 -387.295136) (xy 83.794092 -387.387338) (xy 83.806284 -387.404102) (xy 83.815174 -387.409436)
			(xy 83.835984 -387.422277) (xy 83.873888 -387.45317) (xy 83.906828 -387.489309) (xy 83.934088 -387.529904)
			(xy 83.955071 -387.574072) (xy 83.969322 -387.620848) (xy 83.976529 -387.669213) (xy 83.976972 -387.693662)
			(xy 83.976561 -387.718036) (xy 83.969415 -387.766256) (xy 83.955271 -387.812906) (xy 83.934436 -387.856977)
			(xy 83.90736 -387.897513) (xy 83.874631 -387.933639) (xy 83.856068 -387.94944) (xy 83.847178 -387.956552)
			(xy 83.83778 -387.97611) (xy 83.834986 -388.075424) (xy 83.843622 -388.09549) (xy 83.852004 -388.10311)
			(xy 83.870443 -388.120582) (xy 83.901793 -388.160549) (xy 83.926093 -388.205155) (xy 83.942672 -388.253168)
			(xy 83.951072 -388.303264) (xy 83.951572 -388.328662) (xy 84.540852 -388.328662) (xy 84.541374 -388.303407)
			(xy 84.549687 -388.253585) (xy 84.566088 -388.205811) (xy 84.590129 -388.161388) (xy 84.621153 -388.121528)
			(xy 84.658315 -388.087318) (xy 84.700601 -388.059692) (xy 84.746857 -388.039402) (xy 84.795822 -388.027002)
			(xy 84.84616 -388.022831) (xy 84.896498 -388.027002) (xy 84.945463 -388.039402) (xy 84.991719 -388.059692)
			(xy 85.034005 -388.087318) (xy 85.071167 -388.121528) (xy 85.102191 -388.161388) (xy 85.126232 -388.205811)
			(xy 85.142633 -388.253585) (xy 85.150946 -388.303407) (xy 85.151468 -388.328662) (xy 85.151364 -388.339943)
			(xy 85.149713 -388.362445) (xy 85.148166 -388.37362) (xy 85.146896 -388.38251) (xy 85.150452 -388.400036)
			(xy 85.193886 -388.470902) (xy 85.207602 -388.482078) (xy 85.216238 -388.484872) (xy 85.23848 -388.492816)
			(xy 85.280402 -388.514564) (xy 85.318476 -388.542506) (xy 85.351795 -388.575977) (xy 85.379565 -388.614177)
			(xy 85.390736 -388.634986) (xy 85.391244 -388.636002) (xy 85.783674 -389.314944) (xy 85.796483 -389.338284)
			(xy 85.814708 -389.388303) (xy 85.823975 -389.440726) (xy 85.824568 -389.467344) (xy 85.824201 -389.491353)
			(xy 85.816679 -389.538778) (xy 85.801826 -389.584442) (xy 85.78001 -389.627218) (xy 85.751767 -389.666052)
			(xy 85.717795 -389.699987) (xy 85.678929 -389.728187) (xy 85.636129 -389.749956) (xy 85.590449 -389.764758)
			(xy 85.543016 -389.772228) (xy 85.519006 -389.772652) (xy 85.495476 -389.772164) (xy 85.44897 -389.764964)
			(xy 85.404123 -389.750704) (xy 85.361999 -389.729722) (xy 85.3236 -389.702517) (xy 85.289837 -389.669735)
			(xy 85.261512 -389.632154) (xy 85.25002 -389.611616) (xy 85.249766 -389.611108) (xy 85.249258 -389.610346)
			(xy 84.851494 -388.922006) (xy 84.839621 -388.899328) (xy 84.822768 -388.850995) (xy 84.814194 -388.800532)
			(xy 84.813648 -388.77494) (xy 84.813648 -388.774432) (xy 84.81374 -388.763087) (xy 84.815394 -388.740458)
			(xy 84.81695 -388.72922) (xy 84.81822 -388.72033) (xy 84.814664 -388.703058) (xy 84.77123 -388.631938)
			(xy 84.75726 -388.621016) (xy 84.748878 -388.617968) (xy 84.726483 -388.609915) (xy 84.684264 -388.58796)
			(xy 84.645966 -388.559716) (xy 84.612518 -388.525868) (xy 84.584733 -388.487236) (xy 84.563283 -388.444759)
			(xy 84.548689 -388.399465) (xy 84.541305 -388.352455) (xy 84.540852 -388.328662) (xy 83.951572 -388.328662)
			(xy 83.951468 -388.339943) (xy 83.949817 -388.362445) (xy 83.94827 -388.37362) (xy 83.947 -388.38251)
			(xy 83.950556 -388.400036) (xy 83.99399 -388.470902) (xy 84.007706 -388.482078) (xy 84.016342 -388.484872)
			(xy 84.038585 -388.492814) (xy 84.080506 -388.514563) (xy 84.11858 -388.542506) (xy 84.151899 -388.575976)
			(xy 84.179669 -388.614177) (xy 84.19084 -388.634986) (xy 84.191348 -388.636002) (xy 84.583778 -389.314944)
			(xy 84.596588 -389.338284) (xy 84.614813 -389.388303) (xy 84.624079 -389.440726) (xy 84.624672 -389.467344)
			(xy 84.624301 -389.491353) (xy 84.616779 -389.538778) (xy 84.601927 -389.584441) (xy 84.580111 -389.627217)
			(xy 84.551868 -389.666051) (xy 84.517896 -389.699986) (xy 84.479031 -389.728185) (xy 84.436232 -389.749955)
			(xy 84.390552 -389.764757) (xy 84.343119 -389.772228) (xy 84.31911 -389.772652) (xy 84.295577 -389.772241)
			(xy 84.249067 -389.765027) (xy 84.204218 -389.750753) (xy 84.162095 -389.729759) (xy 84.123697 -389.702541)
			(xy 84.089936 -389.669748) (xy 84.061614 -389.632158) (xy 84.050124 -389.611616) (xy 84.04987 -389.611108)
			(xy 84.049362 -389.610346) (xy 83.651598 -388.922006) (xy 83.639725 -388.899328) (xy 83.622872 -388.850995)
			(xy 83.614298 -388.800532) (xy 83.613752 -388.77494) (xy 83.613752 -388.774432) (xy 83.613844 -388.763087)
			(xy 83.615498 -388.740458) (xy 83.617054 -388.72922) (xy 83.618324 -388.72033) (xy 83.614768 -388.703058)
			(xy 83.571334 -388.631938) (xy 83.557364 -388.621016) (xy 83.548982 -388.617968) (xy 83.526588 -388.609913)
			(xy 83.484369 -388.587959) (xy 83.446071 -388.559715) (xy 83.412623 -388.525867) (xy 83.384837 -388.487236)
			(xy 83.363387 -388.444758) (xy 83.348793 -388.399465) (xy 83.341409 -388.352455) (xy 83.340956 -388.328662)
			(xy 83.341464 -388.303266) (xy 83.349875 -388.253175) (xy 83.366458 -388.205167) (xy 83.390757 -388.160564)
			(xy 83.422101 -388.120597) (xy 83.440524 -388.10311) (xy 83.448906 -388.09549) (xy 83.457542 -388.075424)
			(xy 83.454748 -387.97611) (xy 83.44535 -387.956552) (xy 83.43646 -387.94944) (xy 83.417924 -387.93361)
			(xy 83.385203 -387.897485) (xy 83.358132 -387.856952) (xy 83.337298 -387.812888) (xy 83.32315 -387.766246)
			(xy 83.315994 -387.718033) (xy 83.315556 -387.693662) (xy 83.315969 -387.669544) (xy 83.322976 -387.621821)
			(xy 83.336836 -387.57562) (xy 83.357257 -387.53192) (xy 83.370166 -387.511544) (xy 83.376008 -387.502654)
			(xy 83.379564 -387.482588) (xy 83.358482 -387.390386) (xy 83.34629 -387.373622) (xy 83.3374 -387.368288)
			(xy 83.316618 -387.355404) (xy 83.27871 -387.324521) (xy 83.245765 -387.288391) (xy 83.218501 -387.247802)
			(xy 83.197513 -387.203641) (xy 83.183258 -387.15687) (xy 83.176047 -387.10851) (xy 83.175602 -387.084062)
			(xy 83.176148 -387.056777) (xy 83.185099 -387.002947) (xy 83.202768 -386.951318) (xy 83.228676 -386.903291)
			(xy 83.262119 -386.86017) (xy 83.281774 -386.841238) (xy 83.289157 -386.833701) (xy 83.297693 -386.814433)
			(xy 83.298284 -386.8039) (xy 83.298284 -386.729224) (xy 83.29776 -386.718674) (xy 83.289222 -386.699378)
			(xy 83.281774 -386.691886) (xy 83.262147 -386.672927) (xy 83.228711 -386.629808) (xy 83.202804 -386.581787)
			(xy 83.185129 -386.530166) (xy 83.176165 -386.476344) (xy 83.175602 -386.449062) (xy 83.175856 -386.43687)
			(xy 83.17611 -386.427218) (xy 83.170014 -386.409184) (xy 83.11134 -386.341874) (xy 83.094576 -386.333238)
			(xy 83.08467 -386.332222) (xy 83.057764 -386.328843) (xy 83.005479 -386.31448) (xy 82.956235 -386.291783)
			(xy 82.911352 -386.261359) (xy 82.872032 -386.224023) (xy 82.839327 -386.180774) (xy 82.814114 -386.13277)
			(xy 82.797066 -386.081297) (xy 82.792316 -386.0546) (xy 82.790792 -386.045202) (xy 82.517742 -385.572762)
			(xy 82.51063 -385.56692) (xy 82.491884 -385.551156) (xy 82.458833 -385.515009) (xy 82.43148 -385.47438)
			(xy 82.410423 -385.430158) (xy 82.396125 -385.383313) (xy 82.388898 -385.33487) (xy 82.388456 -385.31038)
			(xy 81.871408 -385.31038) (xy 82.119978 -385.740402) (xy 82.127344 -385.746244) (xy 82.146135 -385.762031)
			(xy 82.179249 -385.798252) (xy 82.206656 -385.838964) (xy 82.227755 -385.883275) (xy 82.242083 -385.930214)
			(xy 82.249327 -385.978753) (xy 82.249772 -386.003292) (xy 82.249518 -386.015484) (xy 82.249264 -386.025136)
			(xy 82.25536 -386.04317) (xy 82.314034 -386.11048) (xy 82.330798 -386.119116) (xy 82.340704 -386.120132)
			(xy 82.367466 -386.123488) (xy 82.419489 -386.137711) (xy 82.468515 -386.160187) (xy 82.513244 -386.190319)
			(xy 82.552492 -386.22731) (xy 82.585217 -386.270179) (xy 82.610554 -386.317789) (xy 82.627829 -386.368879)
			(xy 82.636586 -386.422096) (xy 82.637122 -386.449062) (xy 82.636584 -386.476347) (xy 82.62763 -386.530177)
			(xy 82.609958 -386.581806) (xy 82.584049 -386.629833) (xy 82.550605 -386.672953) (xy 82.53095 -386.691886)
			(xy 82.52356 -386.699418) (xy 82.515027 -386.71869) (xy 82.51444 -386.729224) (xy 82.51444 -386.8039)
			(xy 82.514944 -386.814453) (xy 82.523495 -386.833749) (xy 82.53095 -386.841238) (xy 82.550593 -386.860181)
			(xy 82.584026 -386.903304) (xy 82.609929 -386.95133) (xy 82.627601 -387.002954) (xy 82.636561 -387.056779)
			(xy 82.637122 -387.084062) (xy 82.636677 -387.108178) (xy 82.62968 -387.155901) (xy 82.615829 -387.202102)
			(xy 82.595417 -387.245803) (xy 82.582512 -387.26618) (xy 82.57667 -387.27507) (xy 82.573114 -387.295136)
			(xy 82.594196 -387.387338) (xy 82.606388 -387.404102) (xy 82.615278 -387.409436) (xy 82.636066 -387.422311)
			(xy 82.673974 -387.453195) (xy 82.70692 -387.489326) (xy 82.734184 -387.529916) (xy 82.755171 -387.574079)
			(xy 82.769425 -387.620852) (xy 82.776633 -387.669214) (xy 82.777076 -387.693662) (xy 82.776664 -387.718036)
			(xy 82.769517 -387.766256) (xy 82.755374 -387.812906) (xy 82.734539 -387.856976) (xy 82.707464 -387.897513)
			(xy 82.674735 -387.933638) (xy 82.656172 -387.94944) (xy 82.647282 -387.956552) (xy 82.637884 -387.97611)
			(xy 82.63509 -388.075424) (xy 82.643726 -388.09549) (xy 82.652108 -388.10311) (xy 82.670548 -388.120581)
			(xy 82.701898 -388.160548) (xy 82.726197 -388.205154) (xy 82.742776 -388.253168) (xy 82.751176 -388.303264)
			(xy 82.751676 -388.328662) (xy 82.751572 -388.339943) (xy 82.749921 -388.362445) (xy 82.748374 -388.37362)
			(xy 82.747104 -388.382764) (xy 82.750406 -388.400036) (xy 82.794094 -388.471156) (xy 82.80781 -388.482078)
			(xy 82.816446 -388.484872) (xy 82.844608 -388.495077) (xy 82.896555 -388.524883) (xy 82.91957 -388.544054)
			(xy 82.941051 -388.563638) (xy 82.976867 -388.609415) (xy 82.99069 -388.634986) (xy 82.991452 -388.636256)
			(xy 83.383628 -389.314944) (xy 83.396363 -389.338309) (xy 83.414477 -389.388337) (xy 83.423686 -389.440741)
			(xy 83.424268 -389.467344) (xy 83.423878 -389.491338) (xy 83.416364 -389.538735) (xy 83.401528 -389.584374)
			(xy 83.379736 -389.627129) (xy 83.351523 -389.665949) (xy 83.317585 -389.699878) (xy 83.278757 -389.728079)
			(xy 83.235996 -389.74986) (xy 83.190354 -389.764684) (xy 83.142955 -389.772184) (xy 83.11896 -389.772652)
			(xy 83.095428 -389.772201) (xy 83.048921 -389.764994) (xy 83.004073 -389.750728) (xy 82.961949 -389.72974)
			(xy 82.92355 -389.702529) (xy 82.889788 -389.669741) (xy 82.861465 -389.632156) (xy 82.849974 -389.611616)
			(xy 82.84972 -389.611108) (xy 82.849212 -389.610346) (xy 82.451702 -388.921752) (xy 82.441129 -388.901826)
			(xy 82.425326 -388.859576) (xy 82.415919 -388.815459) (xy 82.41411 -388.792974) (xy 82.413602 -388.781798)
			(xy 82.413348 -388.774432) (xy 82.413506 -388.763083) (xy 82.415282 -388.740454) (xy 82.416904 -388.72922)
			(xy 82.418174 -388.72033) (xy 82.414618 -388.703058) (xy 82.371184 -388.631938) (xy 82.357468 -388.620762)
			(xy 82.348832 -388.617968) (xy 82.326422 -388.609994) (xy 82.284252 -388.587985) (xy 82.246005 -388.559704)
			(xy 82.212607 -388.525834) (xy 82.184865 -388.487194) (xy 82.163451 -388.44472) (xy 82.148882 -388.399438)
			(xy 82.141511 -388.352446) (xy 82.14106 -388.328662) (xy 82.141566 -388.303266) (xy 82.149977 -388.253175)
			(xy 82.166561 -388.205167) (xy 82.19086 -388.160564) (xy 82.222205 -388.120597) (xy 82.240628 -388.10311)
			(xy 82.24901 -388.09549) (xy 82.257646 -388.075424) (xy 82.254852 -387.97611) (xy 82.245454 -387.956552)
			(xy 82.236564 -387.94944) (xy 82.218029 -387.933609) (xy 82.185308 -387.897485) (xy 82.158237 -387.856952)
			(xy 82.137402 -387.812888) (xy 82.123254 -387.766246) (xy 82.116098 -387.718033) (xy 82.11566 -387.693662)
			(xy 82.116072 -387.669544) (xy 82.123079 -387.621821) (xy 82.13694 -387.57562) (xy 82.15736 -387.53192)
			(xy 82.17027 -387.511544) (xy 82.176112 -387.502654) (xy 82.179668 -387.482588) (xy 82.158586 -387.390386)
			(xy 82.146394 -387.373622) (xy 82.137504 -387.368288) (xy 82.116722 -387.355403) (xy 82.078815 -387.32452)
			(xy 82.04587 -387.28839) (xy 82.018606 -387.247802) (xy 81.997617 -387.203641) (xy 81.983362 -387.15687)
			(xy 81.976151 -387.108509) (xy 81.975706 -387.084062) (xy 81.976251 -387.056777) (xy 81.985202 -387.002947)
			(xy 82.002871 -386.951318) (xy 82.028779 -386.903291) (xy 82.062223 -386.86017) (xy 82.081878 -386.841238)
			(xy 82.089262 -386.833701) (xy 82.097797 -386.814433) (xy 82.098388 -386.8039) (xy 82.098388 -386.729224)
			(xy 82.097863 -386.718674) (xy 82.089325 -386.699378) (xy 82.081878 -386.691886) (xy 82.062252 -386.672926)
			(xy 82.028816 -386.629808) (xy 82.002909 -386.581787) (xy 81.985233 -386.530166) (xy 81.976269 -386.476344)
			(xy 81.975706 -386.449062) (xy 81.97596 -386.43687) (xy 81.976214 -386.427218) (xy 81.970118 -386.409184)
			(xy 81.911444 -386.341874) (xy 81.89468 -386.333238) (xy 81.884774 -386.332222) (xy 81.857869 -386.328839)
			(xy 81.805583 -386.314478) (xy 81.75634 -386.291781) (xy 81.711457 -386.261358) (xy 81.672137 -386.224022)
			(xy 81.639432 -386.180773) (xy 81.614218 -386.13277) (xy 81.59717 -386.081297) (xy 81.59242 -386.0546)
			(xy 81.590896 -386.045202) (xy 81.3181 -385.57327) (xy 81.310734 -385.567428) (xy 81.291974 -385.551607)
			(xy 81.258858 -385.515392) (xy 81.231448 -385.474687) (xy 81.210344 -385.430384) (xy 81.196009 -385.383451)
			(xy 81.188756 -385.334917) (xy 81.188306 -385.31038) (xy 80.671512 -385.31038) (xy 80.920082 -385.740402)
			(xy 80.927448 -385.746244) (xy 80.946239 -385.76203) (xy 80.979354 -385.798252) (xy 81.006761 -385.838964)
			(xy 81.027859 -385.883274) (xy 81.042187 -385.930214) (xy 81.049431 -385.978753) (xy 81.049876 -386.003292)
			(xy 81.049622 -386.015484) (xy 81.049368 -386.025136) (xy 81.055464 -386.04317) (xy 81.114138 -386.11048)
			(xy 81.130902 -386.119116) (xy 81.140554 -386.120132) (xy 81.167311 -386.123529) (xy 81.219333 -386.137744)
			(xy 81.268359 -386.160213) (xy 81.313089 -386.190339) (xy 81.352338 -386.227325) (xy 81.385065 -386.270189)
			(xy 81.410402 -386.317796) (xy 81.427679 -386.368884) (xy 81.436436 -386.422097) (xy 81.436972 -386.449062)
			(xy 81.43645 -386.476348) (xy 81.427494 -386.530179) (xy 81.40982 -386.581809) (xy 81.383906 -386.629836)
			(xy 81.350458 -386.672955) (xy 81.3308 -386.691886) (xy 81.323403 -386.699411) (xy 81.314876 -386.718688)
			(xy 81.31429 -386.729224) (xy 81.31429 -386.8039) (xy 81.314808 -386.814451) (xy 81.323351 -386.833746)
			(xy 81.3308 -386.841238) (xy 81.350434 -386.86019) (xy 81.38387 -386.90331) (xy 81.409776 -386.951333)
			(xy 81.427449 -387.002956) (xy 81.436411 -387.05678) (xy 81.436972 -387.084062) (xy 81.436518 -387.108178)
			(xy 81.429523 -387.1559) (xy 81.415674 -387.202101) (xy 81.395266 -387.245802) (xy 81.382362 -387.26618)
			(xy 81.37652 -387.27507) (xy 81.372964 -387.295136) (xy 81.394046 -387.387338) (xy 81.406238 -387.404102)
			(xy 81.415128 -387.409436) (xy 81.435928 -387.422293) (xy 81.473833 -387.453182) (xy 81.506776 -387.489317)
			(xy 81.534038 -387.52991) (xy 81.555023 -387.574075) (xy 81.569275 -387.62085) (xy 81.576483 -387.669213)
			(xy 81.576926 -387.693662) (xy 81.576496 -387.718035) (xy 81.56935 -387.766253) (xy 81.555209 -387.812902)
			(xy 81.534378 -387.856972) (xy 81.507307 -387.897509) (xy 81.474582 -387.933637) (xy 81.456022 -387.94944)
			(xy 81.447132 -387.956552) (xy 81.437734 -387.97611) (xy 81.43494 -388.075424) (xy 81.443576 -388.09549)
			(xy 81.451958 -388.10311) (xy 81.470408 -388.120571) (xy 81.501754 -388.160542) (xy 81.526051 -388.205151)
			(xy 81.542627 -388.253167) (xy 81.551027 -388.303264) (xy 81.551526 -388.328662) (xy 81.551423 -388.339943)
			(xy 81.549771 -388.362445) (xy 81.548224 -388.37362) (xy 81.546954 -388.38251) (xy 81.55051 -388.400036)
			(xy 81.593944 -388.470902) (xy 81.60766 -388.482078) (xy 81.616296 -388.484872) (xy 81.638548 -388.492788)
			(xy 81.680469 -388.514544) (xy 81.718541 -388.542494) (xy 81.751857 -388.57597) (xy 81.779624 -388.614175)
			(xy 81.790794 -388.634986) (xy 81.791302 -388.636002) (xy 82.183732 -389.314944) (xy 82.196467 -389.338308)
			(xy 82.214581 -389.388337) (xy 82.22379 -389.440741) (xy 82.224372 -389.467344) (xy 82.223978 -389.491338)
			(xy 82.216464 -389.538735) (xy 82.201628 -389.584373) (xy 82.179836 -389.627128) (xy 82.151624 -389.665948)
			(xy 82.117687 -389.699876) (xy 82.078859 -389.728078) (xy 82.036099 -389.749859) (xy 81.990457 -389.764683)
			(xy 81.943058 -389.772184) (xy 81.919064 -389.772652) (xy 81.895533 -389.772198) (xy 81.849025 -389.764992)
			(xy 81.804177 -389.750726) (xy 81.762053 -389.729738) (xy 81.723655 -389.702528) (xy 81.689892 -389.669741)
			(xy 81.661569 -389.632155) (xy 81.650078 -389.611616) (xy 81.649824 -389.611108) (xy 81.649316 -389.610346)
			(xy 81.251552 -388.922006) (xy 81.239641 -388.899336) (xy 81.222701 -388.851012) (xy 81.21404 -388.800542)
			(xy 81.213452 -388.77494) (xy 81.213452 -388.774432) (xy 81.21361 -388.763083) (xy 81.215386 -388.740454)
			(xy 81.217008 -388.72922) (xy 81.218278 -388.72033) (xy 81.214722 -388.703058) (xy 81.171288 -388.631938)
			(xy 81.157318 -388.621016) (xy 81.148936 -388.617968) (xy 81.126532 -388.609939) (xy 81.084314 -388.587979)
			(xy 81.046018 -388.55973) (xy 81.012572 -388.525878) (xy 80.984788 -388.487243) (xy 80.963339 -388.444763)
			(xy 80.948746 -388.399468) (xy 80.941363 -388.352456) (xy 80.94091 -388.328662) (xy 80.941433 -388.303267)
			(xy 80.949842 -388.253178) (xy 80.966423 -388.20517) (xy 80.990718 -388.160567) (xy 81.022057 -388.120599)
			(xy 81.040478 -388.10311) (xy 81.04886 -388.09549) (xy 81.057496 -388.075424) (xy 81.054702 -387.97611)
			(xy 81.045304 -387.956552) (xy 81.036414 -387.94944) (xy 81.017869 -387.933621) (xy 80.98515 -387.897492)
			(xy 80.958082 -387.856957) (xy 80.93725 -387.812891) (xy 80.923103 -387.766247) (xy 80.915947 -387.718033)
			(xy 80.91551 -387.693662) (xy 80.91593 -387.669545) (xy 80.922936 -387.621822) (xy 80.936795 -387.575621)
			(xy 80.957212 -387.531921) (xy 80.97012 -387.511544) (xy 80.975962 -387.502654) (xy 80.979518 -387.482588)
			(xy 80.958436 -387.390386) (xy 80.946244 -387.373622) (xy 80.937354 -387.368288) (xy 80.916561 -387.355421)
			(xy 80.878656 -387.324533) (xy 80.845714 -387.288399) (xy 80.818452 -387.247808) (xy 80.797465 -387.203645)
			(xy 80.783211 -387.156872) (xy 80.776001 -387.10851) (xy 80.775556 -387.084062) (xy 80.776117 -387.056778)
			(xy 80.785066 -387.002949) (xy 80.802733 -386.951321) (xy 80.828637 -386.903294) (xy 80.862075 -386.860172)
			(xy 80.881728 -386.841238) (xy 80.889104 -386.833695) (xy 80.897646 -386.814432) (xy 80.898238 -386.8039)
			(xy 80.898238 -386.729224) (xy 80.897698 -386.718676) (xy 80.889169 -386.699381) (xy 80.881728 -386.691886)
			(xy 80.862093 -386.672936) (xy 80.82866 -386.629814) (xy 80.802755 -386.58179) (xy 80.785082 -386.530167)
			(xy 80.776119 -386.476344) (xy 80.775556 -386.449062) (xy 80.77581 -386.43687) (xy 80.776064 -386.427218)
			(xy 80.769968 -386.409184) (xy 80.711294 -386.341874) (xy 80.69453 -386.333238) (xy 80.684878 -386.332222)
			(xy 80.657973 -386.328836) (xy 80.605688 -386.314475) (xy 80.556444 -386.291779) (xy 80.511561 -386.261356)
			(xy 80.472241 -386.224021) (xy 80.439536 -386.180772) (xy 80.414322 -386.13277) (xy 80.397274 -386.081297)
			(xy 80.392524 -386.0546) (xy 80.391 -386.045202) (xy 80.118204 -385.57327) (xy 80.110838 -385.567428)
			(xy 80.092078 -385.551606) (xy 80.058962 -385.515392) (xy 80.031552 -385.474687) (xy 80.010448 -385.430383)
			(xy 79.996113 -385.383451) (xy 79.98886 -385.334916) (xy 79.98841 -385.31038) (xy 77.66114 -385.31038)
			(xy 77.680654 -385.320323) (xy 77.722702 -385.350873) (xy 77.759453 -385.387624) (xy 77.790003 -385.429672)
			(xy 77.813599 -385.475982) (xy 77.82966 -385.525412) (xy 77.83779 -385.576747) (xy 77.8383 -385.602734)
			(xy 77.83779 -385.628721) (xy 77.82966 -385.680056) (xy 77.813599 -385.729486) (xy 77.790003 -385.775796)
			(xy 77.759453 -385.817844) (xy 77.722702 -385.854595) (xy 77.693888 -385.87553) (xy 79.361792 -385.87553)
			(xy 79.362302 -385.849543) (xy 79.370432 -385.798208) (xy 79.386493 -385.748778) (xy 79.410089 -385.702468)
			(xy 79.440639 -385.66042) (xy 79.47739 -385.623669) (xy 79.519438 -385.593119) (xy 79.565748 -385.569523)
			(xy 79.615178 -385.553462) (xy 79.666513 -385.545332) (xy 79.718487 -385.545332) (xy 79.769822 -385.553462)
			(xy 79.819252 -385.569523) (xy 79.865562 -385.593119) (xy 79.90761 -385.623669) (xy 79.944361 -385.66042)
			(xy 79.974911 -385.702468) (xy 79.998507 -385.748778) (xy 80.014568 -385.798208) (xy 80.022698 -385.849543)
			(xy 80.023208 -385.87553) (xy 80.02282 -385.899206) (xy 80.016088 -385.946077) (xy 80.002725 -385.991503)
			(xy 79.993236 -386.013198) (xy 79.988918 -386.022596) (xy 79.988156 -386.042662) (xy 80.020414 -386.129022)
			(xy 80.03413 -386.143754) (xy 80.043528 -386.148072) (xy 80.067892 -386.159773) (xy 80.112763 -386.189897)
			(xy 80.152142 -386.226913) (xy 80.184981 -386.269836) (xy 80.210408 -386.317526) (xy 80.227747 -386.368714)
			(xy 80.236536 -386.42204) (xy 80.237076 -386.449062) (xy 80.236553 -386.476348) (xy 80.227597 -386.530179)
			(xy 80.209923 -386.581809) (xy 80.18401 -386.629836) (xy 80.150562 -386.672955) (xy 80.130904 -386.691886)
			(xy 80.123507 -386.699412) (xy 80.11498 -386.718689) (xy 80.114394 -386.729224) (xy 80.114394 -386.8039)
			(xy 80.114911 -386.814451) (xy 80.123455 -386.833746) (xy 80.130904 -386.841238) (xy 80.150538 -386.86019)
			(xy 80.183974 -386.90331) (xy 80.20988 -386.951333) (xy 80.227553 -387.002956) (xy 80.236515 -387.05678)
			(xy 80.237076 -387.084062) (xy 80.236622 -387.108178) (xy 80.229626 -387.1559) (xy 80.215778 -387.202101)
			(xy 80.19537 -387.245802) (xy 80.182466 -387.26618) (xy 80.176624 -387.27507) (xy 80.173068 -387.295136)
			(xy 80.19415 -387.387338) (xy 80.206342 -387.404102) (xy 80.215232 -387.409436) (xy 80.236032 -387.422292)
			(xy 80.273938 -387.453181) (xy 80.306881 -387.489316) (xy 80.334142 -387.529909) (xy 80.355128 -387.574075)
			(xy 80.369379 -387.62085) (xy 80.376587 -387.669213) (xy 80.37703 -387.693662) (xy 80.376598 -387.718035)
			(xy 80.369453 -387.766253) (xy 80.355312 -387.812902) (xy 80.334481 -387.856972) (xy 80.30741 -387.897509)
			(xy 80.274686 -387.933637) (xy 80.256126 -387.94944) (xy 80.247236 -387.956552) (xy 80.237838 -387.97611)
			(xy 80.235044 -388.075424) (xy 80.24368 -388.09549) (xy 80.252062 -388.10311) (xy 80.270512 -388.120571)
			(xy 80.301859 -388.160542) (xy 80.326155 -388.205151) (xy 80.342732 -388.253166) (xy 80.351131 -388.303264)
			(xy 80.35163 -388.328662) (xy 80.351527 -388.339943) (xy 80.349875 -388.362445) (xy 80.348328 -388.37362)
			(xy 80.347058 -388.38251) (xy 80.350614 -388.400036) (xy 80.394048 -388.470902) (xy 80.407764 -388.482078)
			(xy 80.4164 -388.484872) (xy 80.438653 -388.492786) (xy 80.480573 -388.514543) (xy 80.518645 -388.542493)
			(xy 80.551962 -388.575969) (xy 80.579729 -388.614175) (xy 80.590898 -388.634986) (xy 80.591406 -388.636002)
			(xy 80.983836 -389.314944) (xy 80.996571 -389.338308) (xy 81.014685 -389.388337) (xy 81.023894 -389.440741)
			(xy 81.024476 -389.467344) (xy 81.024078 -389.491338) (xy 81.016564 -389.538734) (xy 81.001729 -389.584372)
			(xy 80.979937 -389.627127) (xy 80.951725 -389.665946) (xy 80.917788 -389.699875) (xy 80.878962 -389.728077)
			(xy 80.836201 -389.749858) (xy 80.79056 -389.764682) (xy 80.743162 -389.772184) (xy 80.719168 -389.772652)
			(xy 80.695637 -389.772194) (xy 80.649129 -389.764989) (xy 80.604281 -389.750724) (xy 80.562158 -389.729737)
			(xy 80.523759 -389.702527) (xy 80.489997 -389.66974) (xy 80.461673 -389.632155) (xy 80.450182 -389.611616)
			(xy 80.449928 -389.611108) (xy 80.44942 -389.610346) (xy 80.051656 -388.922006) (xy 80.039745 -388.899335)
			(xy 80.022805 -388.851011) (xy 80.014144 -388.800542) (xy 80.013556 -388.77494) (xy 80.013556 -388.774432)
			(xy 80.013714 -388.763083) (xy 80.01549 -388.740454) (xy 80.017112 -388.72922) (xy 80.018382 -388.72033)
			(xy 80.014826 -388.703058) (xy 79.971392 -388.631938) (xy 79.957422 -388.621016) (xy 79.94904 -388.617968)
			(xy 79.926637 -388.609937) (xy 79.884419 -388.587977) (xy 79.846122 -388.559729) (xy 79.812676 -388.525877)
			(xy 79.784892 -388.487243) (xy 79.763443 -388.444763) (xy 79.74885 -388.399467) (xy 79.741467 -388.352456)
			(xy 79.741014 -388.328662) (xy 79.741535 -388.303267) (xy 79.749945 -388.253177) (xy 79.766526 -388.20517)
			(xy 79.790821 -388.160567) (xy 79.822161 -388.120598) (xy 79.840582 -388.10311) (xy 79.848964 -388.09549)
			(xy 79.8576 -388.075424) (xy 79.854806 -387.97611) (xy 79.845408 -387.956552) (xy 79.836518 -387.94944)
			(xy 79.817974 -387.93362) (xy 79.785255 -387.897492) (xy 79.758187 -387.856957) (xy 79.737354 -387.812891)
			(xy 79.723207 -387.766247) (xy 79.716051 -387.718033) (xy 79.715614 -387.693662) (xy 79.716034 -387.669545)
			(xy 79.72304 -387.621822) (xy 79.736899 -387.575621) (xy 79.757316 -387.531921) (xy 79.770224 -387.511544)
			(xy 79.776066 -387.502654) (xy 79.779622 -387.482588) (xy 79.75854 -387.390386) (xy 79.746348 -387.373622)
			(xy 79.737458 -387.368288) (xy 79.716666 -387.355419) (xy 79.678761 -387.324532) (xy 79.645818 -387.288398)
			(xy 79.618556 -387.247808) (xy 79.597569 -387.203644) (xy 79.583315 -387.156872) (xy 79.576105 -387.10851)
			(xy 79.57566 -387.084062) (xy 79.576219 -387.056778) (xy 79.585169 -387.002949) (xy 79.602836 -386.951321)
			(xy 79.62874 -386.903293) (xy 79.662179 -386.860172) (xy 79.681832 -386.841238) (xy 79.689209 -386.833695)
			(xy 79.69775 -386.814432) (xy 79.698342 -386.8039) (xy 79.698342 -386.729224) (xy 79.697801 -386.718676)
			(xy 79.689273 -386.699381) (xy 79.681832 -386.691886) (xy 79.662198 -386.672935) (xy 79.628764 -386.629813)
			(xy 79.60286 -386.58179) (xy 79.585186 -386.530167) (xy 79.576223 -386.476344) (xy 79.57566 -386.449062)
			(xy 79.57604 -386.425386) (xy 79.582774 -386.378515) (xy 79.596141 -386.333088) (xy 79.605632 -386.311394)
			(xy 79.60995 -386.301996) (xy 79.610712 -386.28193) (xy 79.578454 -386.19557) (xy 79.564738 -386.180838)
			(xy 79.55534 -386.17652) (xy 79.530966 -386.16484) (xy 79.486096 -386.134711) (xy 79.446719 -386.097691)
			(xy 79.413881 -386.054764) (xy 79.388456 -386.007071) (xy 79.371119 -385.955881) (xy 79.362331 -385.902553)
			(xy 79.361792 -385.87553) (xy 77.693888 -385.87553) (xy 77.680654 -385.885145) (xy 77.634344 -385.908741)
			(xy 77.584914 -385.924802) (xy 77.533579 -385.932932) (xy 77.481605 -385.932932) (xy 77.43027 -385.924802)
			(xy 77.38084 -385.908741) (xy 77.33453 -385.885145) (xy 77.292482 -385.854595) (xy 77.255731 -385.817844)
			(xy 77.225181 -385.775796) (xy 77.201585 -385.729486) (xy 77.185524 -385.680056) (xy 77.177394 -385.628721)
			(xy 76.971951 -385.628721) (xy 76.966579 -385.665222) (xy 76.950511 -385.718629) (xy 76.926839 -385.769126)
			(xy 76.896066 -385.815639) (xy 76.858849 -385.857176) (xy 76.815981 -385.892851) (xy 76.768375 -385.921905)
			(xy 76.717046 -385.943717) (xy 76.663089 -385.957823) (xy 76.607652 -385.963923) (xy 76.551918 -385.961886)
			(xy 76.497075 -385.951756) (xy 76.444291 -385.933749) (xy 76.394691 -385.908248) (xy 76.349333 -385.875797)
			(xy 76.309184 -385.837088) (xy 76.275098 -385.792945) (xy 76.247802 -385.74431) (xy 76.227879 -385.692219)
			(xy 76.215753 -385.637782) (xy 76.211682 -385.58216) (xy 71.328333 -385.58216) (xy 71.323962 -385.64058)
			(xy 71.332344 -385.661916) (xy 71.340726 -385.66979) (xy 71.362092 -385.690413) (xy 71.400369 -385.735816)
			(xy 71.433095 -385.785369) (xy 71.459824 -385.838398) (xy 71.480193 -385.89418) (xy 71.493922 -385.951956)
			(xy 71.500827 -386.010938) (xy 71.501254 -386.04063) (xy 71.500789 -386.071361) (xy 71.493377 -386.132374)
			(xy 71.478666 -386.192049) (xy 71.45687 -386.249517) (xy 71.428307 -386.303938) (xy 71.393393 -386.35452)
			(xy 71.352636 -386.400525) (xy 71.306633 -386.441283) (xy 71.256052 -386.476199) (xy 71.201631 -386.504764)
			(xy 71.144165 -386.526562) (xy 71.08449 -386.541275) (xy 71.023477 -386.548688) (xy 70.992746 -386.549138)
			(xy 70.961887 -386.54867) (xy 70.900629 -386.541155) (xy 70.870572 -386.534152) (xy 70.86092 -386.531866)
			(xy 70.842378 -386.534406) (xy 70.764654 -386.577586) (xy 70.752462 -386.592064) (xy 70.749414 -386.601462)
			(xy 70.738517 -386.633427) (xy 70.709442 -386.694382) (xy 70.672544 -386.750946) (xy 70.628476 -386.802121)
			(xy 70.603618 -386.824982) (xy 70.595194 -386.833237) (xy 70.586358 -386.855074) (xy 70.588204 -386.878558)
			(xy 70.593712 -386.88899) (xy 70.606438 -386.91121) (xy 70.62648 -386.958332) (xy 70.640042 -387.00771)
			(xy 70.64688 -387.058459) (xy 70.647306 -387.084062) (xy 70.64682 -387.111313) (xy 70.639064 -387.165261)
			(xy 70.623709 -387.217556) (xy 70.601067 -387.267133) (xy 70.571601 -387.312983) (xy 70.53591 -387.354174)
			(xy 70.494719 -387.389865) (xy 70.448869 -387.419331) (xy 70.399292 -387.441973) (xy 70.346997 -387.457328)
			(xy 70.293049 -387.465084) (xy 70.238547 -387.465084) (xy 70.184599 -387.457328) (xy 70.132304 -387.441973)
			(xy 70.082727 -387.419331) (xy 70.036877 -387.389865) (xy 69.995686 -387.354174) (xy 69.959995 -387.312983)
			(xy 69.930529 -387.267133) (xy 69.907887 -387.217556) (xy 69.892532 -387.165261) (xy 69.884776 -387.111313)
			(xy 69.88429 -387.084062) (xy 69.884705 -387.058459) (xy 69.891552 -387.007712) (xy 69.905119 -386.958335)
			(xy 69.925163 -386.911213) (xy 69.937884 -386.88899) (xy 69.943364 -386.878559) (xy 69.945146 -386.85509)
			(xy 69.93637 -386.833251) (xy 69.927978 -386.824982) (xy 69.904173 -386.803146) (xy 69.86172 -386.754455)
			(xy 69.825777 -386.700779) (xy 69.796923 -386.642982) (xy 69.775622 -386.581996) (xy 69.762217 -386.518804)
			(xy 69.759068 -386.486654) (xy 69.758052 -386.474716) (xy 69.74586 -386.454396) (xy 69.657976 -386.398008)
			(xy 69.634354 -386.395468) (xy 69.623178 -386.399532) (xy 69.591835 -386.410074) (xy 69.526699 -386.421445)
			(xy 69.493638 -386.422138) (xy 69.467674 -386.421703) (xy 69.416224 -386.414667) (xy 69.366204 -386.40072)
			(xy 69.318537 -386.380119) (xy 69.274103 -386.353245) (xy 69.233724 -386.320594) (xy 69.198145 -386.28277)
			(xy 69.182742 -386.261864) (xy 69.176138 -386.25272) (xy 69.157088 -386.241798) (xy 69.068442 -386.234178)
			(xy 69.057357 -386.233859) (xy 69.036563 -386.241502) (xy 69.02831 -386.24891) (xy 68.920106 -386.357114)
			(xy 68.91274 -386.379466) (xy 68.914264 -386.391404) (xy 68.91604 -386.404668) (xy 68.917949 -386.431363)
			(xy 68.918074 -386.444744) (xy 68.917562 -386.473324) (xy 68.909029 -386.529844) (xy 68.892161 -386.584459)
			(xy 68.867335 -386.635947) (xy 68.835107 -386.683156) (xy 68.796198 -386.72503) (xy 68.751478 -386.760631)
			(xy 68.701947 -386.789163) (xy 68.648715 -386.809988) (xy 68.592972 -386.82264) (xy 68.564506 -386.825236)
			(xy 68.555287 -386.826286) (xy 68.53847 -386.834091) (xy 68.53174 -386.840476) (xy 68.510658 -386.862066)
			(xy 68.504076 -386.869447) (xy 68.496629 -386.887746) (xy 68.49618 -386.897626) (xy 68.49618 -387.7945)
			(xy 71.957182 -387.7945) (xy 71.961253 -387.738878) (xy 71.973379 -387.684441) (xy 71.993302 -387.63235)
			(xy 72.020598 -387.583715) (xy 72.054684 -387.539572) (xy 72.094833 -387.500863) (xy 72.140191 -387.468412)
			(xy 72.189791 -387.442911) (xy 72.242575 -387.424904) (xy 72.297418 -387.414774) (xy 72.353152 -387.412737)
			(xy 72.408589 -387.418837) (xy 72.462546 -387.432943) (xy 72.513875 -387.454755) (xy 72.561481 -387.483809)
			(xy 72.604349 -387.519484) (xy 72.641566 -387.561021) (xy 72.672339 -387.607534) (xy 72.696011 -387.658031)
			(xy 72.712079 -387.711438) (xy 72.720199 -387.766614) (xy 72.72062 -387.789674) (xy 73.42886 -387.789674)
			(xy 73.42886 -386.926074) (xy 73.4293 -386.898803) (xy 73.437066 -386.844817) (xy 73.452436 -386.792485)
			(xy 73.475097 -386.742873) (xy 73.504587 -386.696991) (xy 73.540307 -386.655773) (xy 73.58153 -386.620059)
			(xy 73.627415 -386.590574) (xy 73.67703 -386.567919) (xy 73.729364 -386.552556) (xy 73.783351 -386.544797)
			(xy 73.810622 -386.544312) (xy 73.825737 -386.544475) (xy 73.855872 -386.546891) (xy 73.87082 -386.549138)
			(xy 73.881488 -386.550916) (xy 73.902316 -386.545328) (xy 73.978008 -386.484622) (xy 73.98766 -386.465572)
			(xy 73.988168 -386.45465) (xy 73.990422 -386.425847) (xy 74.002411 -386.369335) (xy 74.02278 -386.315274)
			(xy 74.051062 -386.2649) (xy 74.086612 -386.219364) (xy 74.128618 -386.179704) (xy 74.17612 -386.146827)
			(xy 74.228035 -386.121484) (xy 74.283176 -386.104252) (xy 74.340283 -386.095527) (xy 74.369168 -386.094986)
			(xy 74.396422 -386.095459) (xy 74.450375 -386.103212) (xy 74.502676 -386.118565) (xy 74.55226 -386.141206)
			(xy 74.598116 -386.170672) (xy 74.639312 -386.206365) (xy 74.675009 -386.247558) (xy 74.704479 -386.293412)
			(xy 74.727123 -386.342994) (xy 74.742481 -386.395293) (xy 74.750239 -386.449246) (xy 74.750239 -386.489448)
			(xy 77.278738 -386.489448) (xy 77.279248 -386.463461) (xy 77.287378 -386.412126) (xy 77.303439 -386.362696)
			(xy 77.327035 -386.316386) (xy 77.357585 -386.274338) (xy 77.394336 -386.237587) (xy 77.436384 -386.207037)
			(xy 77.482694 -386.183441) (xy 77.532124 -386.16738) (xy 77.583459 -386.15925) (xy 77.635433 -386.15925)
			(xy 77.686768 -386.16738) (xy 77.736198 -386.183441) (xy 77.782508 -386.207037) (xy 77.824556 -386.237587)
			(xy 77.861307 -386.274338) (xy 77.891857 -386.316386) (xy 77.915453 -386.362696) (xy 77.931514 -386.412126)
			(xy 77.939644 -386.463461) (xy 77.940154 -386.489448) (xy 77.939606 -386.516777) (xy 77.930613 -386.570689)
			(xy 77.912878 -386.62239) (xy 77.886886 -386.670472) (xy 77.870558 -386.692394) (xy 77.86497 -386.69976)
			(xy 77.859382 -386.716524) (xy 77.862938 -386.800598) (xy 77.869796 -386.816854) (xy 77.875892 -386.823712)
			(xy 77.89227 -386.842116) (xy 77.919923 -386.882887) (xy 77.941226 -386.927307) (xy 77.955708 -386.974394)
			(xy 77.96305 -387.023108) (xy 77.963522 -387.04774) (xy 77.963012 -387.073727) (xy 77.954882 -387.125062)
			(xy 77.938821 -387.174492) (xy 77.915225 -387.220802) (xy 77.884675 -387.26285) (xy 77.847924 -387.299601)
			(xy 77.805876 -387.330151) (xy 77.759566 -387.353747) (xy 77.710136 -387.369808) (xy 77.658801 -387.377938)
			(xy 77.606827 -387.377938) (xy 77.555492 -387.369808) (xy 77.506062 -387.353747) (xy 77.459752 -387.330151)
			(xy 77.417704 -387.299601) (xy 77.380953 -387.26285) (xy 77.350403 -387.220802) (xy 77.326807 -387.174492)
			(xy 77.310746 -387.125062) (xy 77.302616 -387.073727) (xy 77.302106 -387.04774) (xy 77.302689 -387.020413)
			(xy 77.31167 -386.966501) (xy 77.329393 -386.9148) (xy 77.355378 -386.866717) (xy 77.371702 -386.844794)
			(xy 77.37729 -386.837428) (xy 77.382878 -386.820664) (xy 77.379322 -386.73659) (xy 77.372464 -386.720334)
			(xy 77.366368 -386.713476) (xy 77.350025 -386.695043) (xy 77.322369 -386.654279) (xy 77.30106 -386.609866)
			(xy 77.286569 -386.562786) (xy 77.279216 -386.514078) (xy 77.278738 -386.489448) (xy 74.750239 -386.489448)
			(xy 74.750239 -386.503754) (xy 74.742481 -386.557707) (xy 74.727123 -386.610006) (xy 74.704479 -386.659588)
			(xy 74.675009 -386.705442) (xy 74.639312 -386.746635) (xy 74.598116 -386.782328) (xy 74.55226 -386.811794)
			(xy 74.502676 -386.834435) (xy 74.450375 -386.849788) (xy 74.396422 -386.857541) (xy 74.369168 -386.858002)
			(xy 74.346661 -386.857658) (xy 74.301967 -386.852306) (xy 74.280014 -386.847334) (xy 74.268525 -386.845217)
			(xy 74.245766 -386.850361) (xy 74.236326 -386.85724) (xy 74.21118 -386.87756) (xy 74.202376 -386.885287)
			(xy 74.192466 -386.906488) (xy 74.19213 -386.9182) (xy 74.192384 -386.926074) (xy 74.192384 -387.789674)
			(xy 74.191757 -387.820816) (xy 74.181585 -387.882263) (xy 74.161556 -387.941239) (xy 74.147426 -387.968998)
			(xy 74.142346 -387.978904) (xy 74.140822 -388.000494) (xy 74.175366 -388.092442) (xy 74.190606 -388.107936)
			(xy 74.200766 -388.111746) (xy 74.227437 -388.122441) (xy 74.277454 -388.150733) (xy 74.322655 -388.186213)
			(xy 74.362017 -388.228079) (xy 74.394646 -388.27538) (xy 74.419802 -388.327044) (xy 74.428858 -388.354316)
			(xy 74.432668 -388.367016) (xy 74.451464 -388.384796) (xy 74.560176 -388.413752) (xy 74.585068 -388.407656)
			(xy 74.59472 -388.398512) (xy 74.618314 -388.377319) (xy 74.669812 -388.340304) (xy 74.725516 -388.309984)
			(xy 74.78456 -388.286831) (xy 74.846025 -388.271204) (xy 74.908957 -388.263346) (xy 74.940668 -388.262876)
			(xy 74.972631 -388.263387) (xy 75.036052 -388.271395) (xy 75.09797 -388.28729) (xy 75.124201 -388.297674)
			(xy 76.33665 -388.297674) (xy 76.340721 -388.242052) (xy 76.352847 -388.187615) (xy 76.37277 -388.135524)
			(xy 76.400066 -388.086889) (xy 76.434152 -388.042746) (xy 76.474301 -388.004037) (xy 76.519659 -387.971586)
			(xy 76.569259 -387.946085) (xy 76.622043 -387.928078) (xy 76.676886 -387.917948) (xy 76.73262 -387.915911)
			(xy 76.788057 -387.922011) (xy 76.842014 -387.936117) (xy 76.893343 -387.957929) (xy 76.940949 -387.986983)
			(xy 76.983817 -388.022658) (xy 77.021034 -388.064195) (xy 77.051807 -388.110708) (xy 77.075479 -388.161205)
			(xy 77.091547 -388.214612) (xy 77.099667 -388.269788) (xy 77.100176 -388.297674) (xy 77.099729 -388.322137)
			(xy 77.302616 -388.322137) (xy 77.302616 -388.270163) (xy 77.310746 -388.218828) (xy 77.326807 -388.169398)
			(xy 77.350403 -388.123088) (xy 77.380953 -388.08104) (xy 77.417704 -388.044289) (xy 77.459752 -388.013739)
			(xy 77.506062 -387.990143) (xy 77.555492 -387.974082) (xy 77.606827 -387.965952) (xy 77.658801 -387.965952)
			(xy 77.710136 -387.974082) (xy 77.759566 -387.990143) (xy 77.805876 -388.013739) (xy 77.847924 -388.044289)
			(xy 77.884675 -388.08104) (xy 77.915225 -388.123088) (xy 77.938821 -388.169398) (xy 77.954882 -388.218828)
			(xy 77.963012 -388.270163) (xy 77.963522 -388.29615) (xy 77.963012 -388.322137) (xy 77.954882 -388.373472)
			(xy 77.938821 -388.422902) (xy 77.915225 -388.469212) (xy 77.884675 -388.51126) (xy 77.847924 -388.548011)
			(xy 77.805876 -388.578561) (xy 77.759566 -388.602157) (xy 77.710136 -388.618218) (xy 77.658801 -388.626348)
			(xy 77.606827 -388.626348) (xy 77.555492 -388.618218) (xy 77.506062 -388.602157) (xy 77.459752 -388.578561)
			(xy 77.417704 -388.548011) (xy 77.380953 -388.51126) (xy 77.350403 -388.469212) (xy 77.326807 -388.422902)
			(xy 77.310746 -388.373472) (xy 77.302616 -388.322137) (xy 77.099729 -388.322137) (xy 77.099667 -388.32556)
			(xy 77.091547 -388.380736) (xy 77.075479 -388.434143) (xy 77.051807 -388.48464) (xy 77.021034 -388.531153)
			(xy 76.983817 -388.57269) (xy 76.940949 -388.608365) (xy 76.893343 -388.637419) (xy 76.842014 -388.659231)
			(xy 76.788057 -388.673337) (xy 76.73262 -388.679437) (xy 76.676886 -388.6774) (xy 76.622043 -388.66727)
			(xy 76.569259 -388.649263) (xy 76.519659 -388.623762) (xy 76.474301 -388.591311) (xy 76.434152 -388.552602)
			(xy 76.400066 -388.508459) (xy 76.37277 -388.459824) (xy 76.352847 -388.407733) (xy 76.340721 -388.353296)
			(xy 76.33665 -388.297674) (xy 75.124201 -388.297674) (xy 75.157407 -388.310819) (xy 75.213427 -388.341613)
			(xy 75.265145 -388.379185) (xy 75.311746 -388.422944) (xy 75.352495 -388.472198) (xy 75.386749 -388.526171)
			(xy 75.413968 -388.584012) (xy 75.433723 -388.644808) (xy 75.445701 -388.707601) (xy 75.449716 -388.7714)
			(xy 75.445701 -388.835199) (xy 75.433723 -388.897992) (xy 75.413968 -388.958788) (xy 75.386749 -389.016629)
			(xy 75.352495 -389.070602) (xy 75.311746 -389.119856) (xy 75.265145 -389.163615) (xy 75.213427 -389.201187)
			(xy 75.157407 -389.231981) (xy 75.09797 -389.25551) (xy 75.036052 -389.271405) (xy 74.972631 -389.279413)
			(xy 74.940668 -389.279892) (xy 74.909581 -389.279395) (xy 74.84787 -389.271809) (xy 74.787546 -389.256752)
			(xy 74.729508 -389.234452) (xy 74.674623 -389.205239) (xy 74.623711 -389.16955) (xy 74.600308 -389.149082)
			(xy 74.590402 -389.140192) (xy 74.564494 -389.13435) (xy 74.455782 -389.166862) (xy 74.43724 -389.186166)
			(xy 74.433938 -389.19912) (xy 74.426478 -389.226028) (xy 74.404678 -389.277436) (xy 74.375622 -389.325119)
			(xy 74.339928 -389.36806) (xy 74.29836 -389.405344) (xy 74.251803 -389.436173) (xy 74.201252 -389.45989)
			(xy 74.147784 -389.47599) (xy 74.092541 -389.484128) (xy 74.064622 -389.484616) (xy 74.03737 -389.484124)
			(xy 73.983421 -389.47637) (xy 73.931124 -389.461018) (xy 73.881544 -389.438378) (xy 73.835691 -389.408913)
			(xy 73.794499 -389.373223) (xy 73.758805 -389.332033) (xy 73.729336 -389.286182) (xy 73.706693 -389.236604)
			(xy 73.691336 -389.184309) (xy 73.683578 -389.13036) (xy 73.683114 -389.103108) (xy 73.683581 -389.075738)
			(xy 73.691398 -389.021559) (xy 73.706887 -388.969055) (xy 73.729728 -388.919308) (xy 73.759453 -388.873342)
			(xy 73.777094 -388.85241) (xy 73.78319 -388.845298) (xy 73.78954 -388.82828) (xy 73.78954 -388.742936)
			(xy 73.78319 -388.725918) (xy 73.777094 -388.718806) (xy 73.759443 -388.697883) (xy 73.729733 -388.651908)
			(xy 73.7069 -388.602158) (xy 73.691411 -388.549655) (xy 73.683586 -388.495478) (xy 73.683114 -388.468108)
			(xy 73.683726 -388.436977) (xy 73.693795 -388.375535) (xy 73.713731 -388.316552) (xy 73.727818 -388.288784)
			(xy 73.732898 -388.279132) (xy 73.734422 -388.257542) (xy 73.700132 -388.165594) (xy 73.684638 -388.1501)
			(xy 73.674478 -388.14629) (xy 73.647768 -388.135527) (xy 73.59766 -388.107154) (xy 73.552383 -388.071575)
			(xy 73.512965 -388.029597) (xy 73.480301 -387.982174) (xy 73.455132 -387.930382) (xy 73.43803 -387.875397)
			(xy 73.429383 -387.818466) (xy 73.42886 -387.789674) (xy 72.72062 -387.789674) (xy 72.720708 -387.7945)
			(xy 72.720199 -387.822386) (xy 72.712079 -387.877562) (xy 72.696011 -387.930969) (xy 72.672339 -387.981466)
			(xy 72.641566 -388.027979) (xy 72.604349 -388.069516) (xy 72.561481 -388.105191) (xy 72.513875 -388.134245)
			(xy 72.462546 -388.156057) (xy 72.408589 -388.170163) (xy 72.353152 -388.176263) (xy 72.297418 -388.174226)
			(xy 72.242575 -388.164096) (xy 72.189791 -388.146089) (xy 72.140191 -388.120588) (xy 72.094833 -388.088137)
			(xy 72.054684 -388.049428) (xy 72.020598 -388.005285) (xy 71.993302 -387.95665) (xy 71.973379 -387.904559)
			(xy 71.961253 -387.850122) (xy 71.957182 -387.7945) (xy 68.49618 -387.7945) (xy 68.49618 -388.438644)
			(xy 68.496949 -388.450826) (xy 68.508225 -388.472436) (xy 68.51777 -388.480046) (xy 68.596256 -388.53491)
			(xy 68.620894 -388.538212) (xy 68.632578 -388.533894) (xy 68.664094 -388.523236) (xy 68.729618 -388.511744)
			(xy 68.76288 -388.511034) (xy 68.790248 -388.511511) (xy 68.84442 -388.519346) (xy 68.896916 -388.534843)
			(xy 68.946659 -388.557684) (xy 68.992626 -388.5874) (xy 69.013578 -388.605014) (xy 69.02069 -388.61111)
			(xy 69.037708 -388.61746) (xy 69.123052 -388.61746) (xy 69.14007 -388.61111) (xy 69.147182 -388.605014)
			(xy 69.168115 -388.587373) (xy 69.214083 -388.557649) (xy 69.263829 -388.534803) (xy 69.316331 -388.519307)
			(xy 69.370509 -388.511478) (xy 69.425251 -388.511478) (xy 69.479429 -388.519307) (xy 69.531931 -388.534803)
			(xy 69.581677 -388.557649) (xy 69.627645 -388.587373) (xy 69.648578 -388.605014) (xy 69.65569 -388.61111)
			(xy 69.672708 -388.61746) (xy 69.758052 -388.61746) (xy 69.77507 -388.61111) (xy 69.782182 -388.605014)
			(xy 69.803113 -388.58737) (xy 69.849078 -388.557641) (xy 69.898825 -388.534795) (xy 69.951329 -388.519301)
			(xy 70.005509 -388.51148) (xy 70.03288 -388.511034) (xy 70.060131 -388.511496) (xy 70.114078 -388.51925)
			(xy 70.166372 -388.534602) (xy 70.21595 -388.557241) (xy 70.2618 -388.586705) (xy 70.302991 -388.622395)
			(xy 70.338683 -388.663584) (xy 70.368149 -388.709433) (xy 70.390791 -388.759009) (xy 70.402342 -388.798348)
			(xy 71.741308 -388.798348) (xy 71.741308 -388.743852) (xy 71.749064 -388.68991) (xy 71.764417 -388.63762)
			(xy 71.787055 -388.588048) (xy 71.816517 -388.542202) (xy 71.852204 -388.501016) (xy 71.893389 -388.465327)
			(xy 71.939234 -388.435863) (xy 71.988805 -388.413222) (xy 72.041094 -388.397867) (xy 72.095036 -388.390109)
			(xy 72.122284 -388.389622) (xy 72.149654 -388.390092) (xy 72.203833 -388.397908) (xy 72.256337 -388.413396)
			(xy 72.306083 -388.436237) (xy 72.35205 -388.465961) (xy 72.372982 -388.483602) (xy 72.380094 -388.489698)
			(xy 72.397112 -388.496048) (xy 72.482456 -388.496048) (xy 72.499474 -388.489698) (xy 72.506586 -388.483602)
			(xy 72.527513 -388.465956) (xy 72.573487 -388.436245) (xy 72.623236 -388.413411) (xy 72.675738 -388.397921)
			(xy 72.729914 -388.390095) (xy 72.757284 -388.389622) (xy 72.78454 -388.390024) (xy 72.838497 -388.39778)
			(xy 72.890801 -388.413135) (xy 72.940387 -388.435779) (xy 72.986246 -388.465249) (xy 73.027443 -388.500945)
			(xy 73.063142 -388.542142) (xy 73.092613 -388.587999) (xy 73.115259 -388.637584) (xy 73.130617 -388.689888)
			(xy 73.138375 -388.743844) (xy 73.138375 -388.798356) (xy 73.130617 -388.852312) (xy 73.115259 -388.904616)
			(xy 73.092613 -388.954201) (xy 73.063142 -389.000058) (xy 73.027443 -389.041255) (xy 72.986246 -389.076951)
			(xy 72.940387 -389.106421) (xy 72.890801 -389.129065) (xy 72.838497 -389.14442) (xy 72.78454 -389.152176)
			(xy 72.757284 -389.152638) (xy 72.729913 -389.152196) (xy 72.675732 -389.144375) (xy 72.623228 -389.128881)
			(xy 72.573481 -389.106033) (xy 72.527516 -389.076303) (xy 72.506586 -389.058658) (xy 72.499474 -389.052562)
			(xy 72.482456 -389.046212) (xy 72.397112 -389.046212) (xy 72.380094 -389.052562) (xy 72.372982 -389.058658)
			(xy 72.352024 -389.076266) (xy 72.306059 -389.105984) (xy 72.256318 -389.128826) (xy 72.203823 -389.144325)
			(xy 72.149652 -389.15216) (xy 72.122284 -389.152638) (xy 72.095036 -389.152091) (xy 72.041094 -389.144333)
			(xy 71.988805 -389.128978) (xy 71.939234 -389.106337) (xy 71.893389 -389.076873) (xy 71.852204 -389.041184)
			(xy 71.816517 -388.999998) (xy 71.787055 -388.954152) (xy 71.764417 -388.90458) (xy 71.749064 -388.85229)
			(xy 71.741308 -388.798348) (xy 70.402342 -388.798348) (xy 70.406146 -388.811302) (xy 70.413903 -388.865249)
			(xy 70.413903 -388.919751) (xy 70.406146 -388.973698) (xy 70.390791 -389.025991) (xy 70.368149 -389.075567)
			(xy 70.338683 -389.121416) (xy 70.302991 -389.162605) (xy 70.2618 -389.198295) (xy 70.21595 -389.227759)
			(xy 70.166372 -389.250398) (xy 70.114078 -389.26575) (xy 70.060131 -389.273504) (xy 70.03288 -389.27405)
			(xy 70.005511 -389.273577) (xy 69.951335 -389.265749) (xy 69.898834 -389.250259) (xy 69.849086 -389.227422)
			(xy 69.803114 -389.197709) (xy 69.782182 -389.18007) (xy 69.77507 -389.173974) (xy 69.758052 -389.167624)
			(xy 69.672708 -389.167624) (xy 69.65569 -389.173974) (xy 69.648578 -389.18007) (xy 69.627645 -389.197711)
			(xy 69.581677 -389.227435) (xy 69.531931 -389.250281) (xy 69.479429 -389.265777) (xy 69.425251 -389.273606)
			(xy 69.370509 -389.273606) (xy 69.316331 -389.265777) (xy 69.263829 -389.250281) (xy 69.214083 -389.227435)
			(xy 69.168115 -389.197711) (xy 69.147182 -389.18007) (xy 69.14007 -389.173974) (xy 69.123052 -389.167624)
			(xy 69.037708 -389.167624) (xy 69.02069 -389.173974) (xy 69.013578 -389.18007) (xy 68.992647 -389.197712)
			(xy 68.94668 -389.227438) (xy 68.896934 -389.25028) (xy 68.84443 -389.265768) (xy 68.79025 -389.273584)
			(xy 68.76288 -389.27405) (xy 68.729617 -389.273351) (xy 68.664093 -389.261854) (xy 68.632578 -389.25119)
			(xy 68.620894 -389.246872) (xy 68.596256 -389.250174) (xy 68.51777 -389.305038) (xy 68.508172 -389.312607)
			(xy 68.496873 -389.334238) (xy 68.49618 -389.34644) (xy 68.49618 -390.365051) (xy 70.12228 -390.365051)
			(xy 70.12228 -390.310549) (xy 70.130036 -390.256603) (xy 70.14539 -390.20431) (xy 70.16803 -390.154733)
			(xy 70.197496 -390.108884) (xy 70.233186 -390.067694) (xy 70.274374 -390.032003) (xy 70.320223 -390.002536)
			(xy 70.369798 -389.979895) (xy 70.422091 -389.964538) (xy 70.476037 -389.956781) (xy 70.503288 -389.956294)
			(xy 70.530658 -389.956769) (xy 70.584837 -389.964585) (xy 70.63734 -389.980072) (xy 70.687087 -390.002912)
			(xy 70.733054 -390.032634) (xy 70.753986 -390.050274) (xy 70.761098 -390.05637) (xy 70.778116 -390.06272)
			(xy 70.86346 -390.06272) (xy 70.880478 -390.05637) (xy 70.88759 -390.050274) (xy 70.908512 -390.032622)
			(xy 70.954488 -390.002913) (xy 71.004238 -389.98008) (xy 71.056741 -389.964592) (xy 71.110918 -389.956767)
			(xy 71.138288 -389.956294) (xy 71.165542 -389.956753) (xy 71.219494 -389.964508) (xy 71.271794 -389.979863)
			(xy 71.321376 -390.002505) (xy 71.36723 -390.031973) (xy 71.408425 -390.067667) (xy 71.44412 -390.10886)
			(xy 71.473589 -390.154714) (xy 71.496233 -390.204295) (xy 71.511589 -390.256594) (xy 71.519347 -390.310546)
			(xy 71.519347 -390.365054) (xy 71.511589 -390.419006) (xy 71.496233 -390.471305) (xy 71.473589 -390.520886)
			(xy 71.44412 -390.56674) (xy 71.408425 -390.607933) (xy 71.36723 -390.643627) (xy 71.321376 -390.673095)
			(xy 71.271794 -390.695737) (xy 71.219494 -390.711092) (xy 71.165542 -390.718847) (xy 71.138288 -390.71931)
			(xy 71.110918 -390.718849) (xy 71.056738 -390.711029) (xy 71.004235 -390.695539) (xy 70.954489 -390.672696)
			(xy 70.908522 -390.642971) (xy 70.88759 -390.62533) (xy 70.880478 -390.619234) (xy 70.86346 -390.612884)
			(xy 70.778116 -390.612884) (xy 70.761098 -390.619234) (xy 70.753986 -390.62533) (xy 70.733036 -390.642947)
			(xy 70.687068 -390.672661) (xy 70.637325 -390.695501) (xy 70.584828 -390.710997) (xy 70.530656 -390.718832)
			(xy 70.503288 -390.71931) (xy 70.476037 -390.718819) (xy 70.422091 -390.711062) (xy 70.369798 -390.695705)
			(xy 70.320223 -390.673064) (xy 70.274374 -390.643597) (xy 70.233186 -390.607906) (xy 70.197496 -390.566716)
			(xy 70.16803 -390.520867) (xy 70.14539 -390.47129) (xy 70.130036 -390.418997) (xy 70.12228 -390.365051)
			(xy 68.49618 -390.365051) (xy 68.49618 -392.852148) (xy 68.496647 -392.862393) (xy 68.504641 -392.88126)
			(xy 68.511674 -392.888724) (xy 68.571872 -392.94689) (xy 68.591176 -392.954002) (xy 68.601336 -392.953748)
			(xy 68.615306 -392.953494) (xy 68.642557 -392.95398) (xy 68.696504 -392.961737) (xy 68.748797 -392.977093)
			(xy 68.798374 -392.999734) (xy 68.844223 -393.029201) (xy 68.885412 -393.064892) (xy 68.921103 -393.106082)
			(xy 68.950569 -393.151932) (xy 68.973209 -393.201508) (xy 68.988564 -393.253802) (xy 68.99632 -393.307749)
			(xy 68.99632 -393.362251) (xy 68.988564 -393.416198) (xy 68.973209 -393.468492) (xy 68.950569 -393.518068)
			(xy 68.94873 -393.52093) (xy 69.226176 -393.52093) (xy 69.226637 -393.490233) (xy 69.234043 -393.429288)
			(xy 69.248738 -393.369679) (xy 69.270509 -393.312276) (xy 69.299037 -393.257913) (xy 69.316092 -393.232386)
			(xy 69.321539 -393.223621) (xy 69.325677 -393.203425) (xy 69.321559 -393.183225) (xy 69.316092 -393.174474)
			(xy 69.299047 -393.148943) (xy 69.270539 -393.094573) (xy 69.248778 -393.037169) (xy 69.23408 -392.977564)
			(xy 69.226656 -392.916625) (xy 69.226176 -392.88593) (xy 69.226666 -392.855199) (xy 69.234071 -392.794185)
			(xy 69.248776 -392.734509) (xy 69.270568 -392.67704) (xy 69.299128 -392.622617) (xy 69.334039 -392.572033)
			(xy 69.374794 -392.526027) (xy 69.420797 -392.485268) (xy 69.471377 -392.450352) (xy 69.525798 -392.421787)
			(xy 69.583265 -392.39999) (xy 69.64294 -392.385279) (xy 69.703953 -392.377869) (xy 69.734684 -392.377422)
			(xy 69.765381 -392.377868) (xy 69.826327 -392.385276) (xy 69.885936 -392.399974) (xy 69.94334 -392.421749)
			(xy 69.997702 -392.450281) (xy 70.023228 -392.467338) (xy 70.03198 -392.472809) (xy 70.052184 -392.476937)
			(xy 70.072388 -392.472809) (xy 70.08114 -392.467338) (xy 70.106671 -392.450292) (xy 70.161041 -392.421784)
			(xy 70.218444 -392.400022) (xy 70.278049 -392.385324) (xy 70.338989 -392.377902) (xy 70.369684 -392.377422)
			(xy 70.400381 -392.377868) (xy 70.461327 -392.385276) (xy 70.520936 -392.399974) (xy 70.57834 -392.421749)
			(xy 70.632702 -392.450281) (xy 70.658228 -392.467338) (xy 70.66698 -392.472809) (xy 70.687184 -392.476937)
			(xy 70.707388 -392.472809) (xy 70.71614 -392.467338) (xy 70.741671 -392.450292) (xy 70.796041 -392.421784)
			(xy 70.853444 -392.400022) (xy 70.913049 -392.385324) (xy 70.973989 -392.377902) (xy 71.004684 -392.377422)
			(xy 71.025766 -392.37793) (xy 71.036688 -392.378438) (xy 71.056246 -392.370818) (xy 71.124572 -392.302492)
			(xy 71.132192 -392.282934) (xy 71.131684 -392.272012) (xy 71.131176 -392.25093) (xy 71.131637 -392.220233)
			(xy 71.139043 -392.159288) (xy 71.153738 -392.099679) (xy 71.175509 -392.042276) (xy 71.204037 -391.987913)
			(xy 71.221092 -391.962386) (xy 71.226539 -391.953621) (xy 71.230677 -391.933425) (xy 71.226559 -391.913225)
			(xy 71.221092 -391.904474) (xy 71.204047 -391.878943) (xy 71.175539 -391.824573) (xy 71.153778 -391.767169)
			(xy 71.13908 -391.707564) (xy 71.131656 -391.646625) (xy 71.131176 -391.61593) (xy 71.131729 -391.582694)
			(xy 71.140399 -391.51679) (xy 71.157582 -391.452578) (xy 71.182986 -391.391152) (xy 71.216177 -391.33356)
			(xy 71.256589 -391.280783) (xy 71.303533 -391.233723) (xy 71.356209 -391.19318) (xy 71.413719 -391.159846)
			(xy 71.475081 -391.13429) (xy 71.539251 -391.116947) (xy 71.57212 -391.111994) (xy 71.58355 -391.11047)
			(xy 71.602092 -391.098532) (xy 71.65594 -391.013188) (xy 71.658734 -390.991344) (xy 71.655178 -390.980168)
			(xy 71.64388 -390.942435) (xy 71.631763 -390.86461) (xy 71.631048 -390.825228) (xy 71.631582 -390.794499)
			(xy 71.638987 -390.73349) (xy 71.653691 -390.673817) (xy 71.67548 -390.616352) (xy 71.704037 -390.561932)
			(xy 71.738946 -390.511352) (xy 71.779696 -390.465347) (xy 71.825695 -390.42459) (xy 71.876271 -390.389675)
			(xy 71.930686 -390.36111) (xy 71.988148 -390.339312) (xy 72.047819 -390.3246) (xy 72.108827 -390.317187)
			(xy 72.139556 -390.31672) (xy 72.170253 -390.31718) (xy 72.231198 -390.324585) (xy 72.290807 -390.33928)
			(xy 72.348211 -390.361051) (xy 72.402573 -390.389581) (xy 72.4281 -390.406636) (xy 72.436852 -390.412107)
			(xy 72.457056 -390.416235) (xy 72.47726 -390.412107) (xy 72.486012 -390.406636) (xy 72.511551 -390.389602)
			(xy 72.565918 -390.361092) (xy 72.62332 -390.339328) (xy 72.682923 -390.324627) (xy 72.743862 -390.317201)
			(xy 72.774556 -390.31672) (xy 72.805288 -390.317179) (xy 72.866305 -390.324583) (xy 72.925984 -390.339289)
			(xy 72.983456 -390.361081) (xy 73.037881 -390.389643) (xy 73.088467 -390.424557) (xy 73.134474 -390.465314)
			(xy 73.175233 -390.511321) (xy 73.210149 -390.561905) (xy 73.238712 -390.616329) (xy 73.260507 -390.6738)
			(xy 73.275214 -390.733479) (xy 73.28262 -390.794496) (xy 73.283064 -390.825228) (xy 73.282486 -390.860074)
			(xy 73.272972 -390.929113) (xy 73.254125 -390.996208) (xy 73.226297 -391.060103) (xy 73.208642 -391.09015)
			(xy 73.203562 -391.098278) (xy 73.20026 -391.116058) (xy 73.214738 -391.200386) (xy 73.223882 -391.21588)
			(xy 73.230994 -391.221976) (xy 73.255613 -391.24275) (xy 73.299994 -391.289437) (xy 73.338127 -391.341352)
			(xy 73.369402 -391.397666) (xy 73.39332 -391.457477) (xy 73.409496 -391.519828) (xy 73.417673 -391.583723)
			(xy 73.418192 -391.61593) (xy 73.417716 -391.646626) (xy 73.410315 -391.707571) (xy 73.395623 -391.76718)
			(xy 73.373856 -391.824584) (xy 73.34533 -391.878947) (xy 73.328276 -391.904474) (xy 73.32278 -391.913213)
			(xy 73.318662 -391.933425) (xy 73.3228 -391.953633) (xy 73.328276 -391.962386) (xy 73.3453 -391.987931)
			(xy 73.373812 -392.042297) (xy 73.395578 -392.099697) (xy 73.410281 -392.159299) (xy 73.417709 -392.220236)
			(xy 73.418192 -392.25093) (xy 73.417772 -392.281662) (xy 73.41036 -392.342678) (xy 73.395647 -392.402356)
			(xy 73.373849 -392.459825) (xy 73.345282 -392.514248) (xy 73.310363 -392.56483) (xy 73.269603 -392.610835)
			(xy 73.223594 -392.651592) (xy 73.173008 -392.686506) (xy 73.118583 -392.715067) (xy 73.061112 -392.736861)
			(xy 73.001433 -392.751568) (xy 72.940416 -392.758975) (xy 72.909684 -392.759438) (xy 72.888602 -392.75893)
			(xy 72.87768 -392.758422) (xy 72.858122 -392.766042) (xy 72.789796 -392.834368) (xy 72.782176 -392.853926)
			(xy 72.782684 -392.864848) (xy 72.783192 -392.88593) (xy 72.782716 -392.916626) (xy 72.775315 -392.977571)
			(xy 72.760623 -393.03718) (xy 72.738856 -393.094584) (xy 72.71033 -393.148947) (xy 72.693276 -393.174474)
			(xy 72.68778 -393.183213) (xy 72.683662 -393.203425) (xy 72.6878 -393.223633) (xy 72.693276 -393.232386)
			(xy 72.7103 -393.257931) (xy 72.738812 -393.312297) (xy 72.760578 -393.369697) (xy 72.775281 -393.429299)
			(xy 72.782709 -393.490236) (xy 72.783192 -393.52093) (xy 73.638156 -393.52093) (xy 73.638626 -393.49356)
			(xy 73.646441 -393.43938) (xy 73.661928 -393.386877) (xy 73.684769 -393.33713) (xy 73.714494 -393.291163)
			(xy 73.732136 -393.270232) (xy 73.738232 -393.26312) (xy 73.744582 -393.246102) (xy 73.744582 -393.160758)
			(xy 73.738232 -393.14374) (xy 73.732136 -393.136628) (xy 73.714524 -393.115672) (xy 73.684798 -393.069708)
			(xy 73.66195 -393.019966) (xy 73.646451 -392.967467) (xy 73.638619 -392.913292) (xy 73.638616 -392.858553)
			(xy 73.646441 -392.804377) (xy 73.661934 -392.751877) (xy 73.684776 -392.702131) (xy 73.714497 -392.656165)
			(xy 73.732136 -392.635232) (xy 73.738232 -392.62812) (xy 73.744582 -392.611102) (xy 73.744582 -392.525758)
			(xy 73.738232 -392.50874) (xy 73.732136 -392.501628) (xy 73.714524 -392.480672) (xy 73.684798 -392.434708)
			(xy 73.66195 -392.384966) (xy 73.646451 -392.332467) (xy 73.638619 -392.278292) (xy 73.638616 -392.223553)
			(xy 73.646441 -392.169377) (xy 73.661934 -392.116877) (xy 73.684776 -392.067131) (xy 73.714497 -392.021165)
			(xy 73.732136 -392.000232) (xy 73.738232 -391.99312) (xy 73.744582 -391.976102) (xy 73.744582 -391.890758)
			(xy 73.738232 -391.87374) (xy 73.732136 -391.866628) (xy 73.714502 -391.845692) (xy 73.684788 -391.799721)
			(xy 73.661951 -391.749974) (xy 73.646459 -391.697474) (xy 73.63863 -391.643299) (xy 73.638156 -391.61593)
			(xy 73.638641 -391.58846) (xy 73.646525 -391.534089) (xy 73.66212 -391.481408) (xy 73.685104 -391.431507)
			(xy 73.715002 -391.385415) (xy 73.751198 -391.344083) (xy 73.77176 -391.325862) (xy 73.77938 -391.319258)
			(xy 73.788524 -391.301478) (xy 73.795636 -391.209276) (xy 73.789286 -391.189972) (xy 73.782428 -391.182352)
			(xy 73.765029 -391.161451) (xy 73.735723 -391.115641) (xy 73.713205 -391.066139) (xy 73.69793 -391.013946)
			(xy 73.690206 -390.960115) (xy 73.689718 -390.932924) (xy 73.690194 -390.905554) (xy 73.698009 -390.851375)
			(xy 73.713495 -390.798872) (xy 73.736335 -390.749125) (xy 73.766058 -390.703158) (xy 73.783698 -390.682226)
			(xy 73.789794 -390.675114) (xy 73.796144 -390.658096) (xy 73.796144 -390.572752) (xy 73.789794 -390.555734)
			(xy 73.783698 -390.548622) (xy 73.766055 -390.527693) (xy 73.736344 -390.481719) (xy 73.713509 -390.431971)
			(xy 73.698019 -390.37947) (xy 73.690191 -390.325293) (xy 73.689718 -390.297924) (xy 73.690204 -390.270673)
			(xy 73.69796 -390.216725) (xy 73.713315 -390.16443) (xy 73.735957 -390.114853) (xy 73.765423 -390.069003)
			(xy 73.801114 -390.027812) (xy 73.842305 -389.992121) (xy 73.888155 -389.962655) (xy 73.937732 -389.940013)
			(xy 73.990027 -389.924658) (xy 74.043975 -389.916902) (xy 74.098477 -389.916902) (xy 74.152425 -389.924658)
			(xy 74.20472 -389.940013) (xy 74.254297 -389.962655) (xy 74.300147 -389.992121) (xy 74.341338 -390.027812)
			(xy 74.377029 -390.069003) (xy 74.406495 -390.114853) (xy 74.429137 -390.16443) (xy 74.444492 -390.216725)
			(xy 74.452248 -390.270673) (xy 74.452734 -390.297924) (xy 74.452298 -390.325296) (xy 74.444475 -390.379477)
			(xy 74.42898 -390.431981) (xy 74.406131 -390.481727) (xy 74.376399 -390.527692) (xy 74.358754 -390.548622)
			(xy 74.352658 -390.555734) (xy 74.346308 -390.572752) (xy 74.346308 -390.658096) (xy 74.352658 -390.675114)
			(xy 74.358754 -390.682226) (xy 74.376365 -390.703181) (xy 74.406082 -390.749147) (xy 74.428925 -390.798888)
			(xy 74.444422 -390.851384) (xy 74.452257 -390.905556) (xy 74.452734 -390.932924) (xy 74.452148 -390.962534)
			(xy 74.442988 -391.021042) (xy 74.424907 -391.077434) (xy 74.398337 -391.13036) (xy 74.363917 -391.17855)
			(xy 74.32247 -391.22085) (xy 74.299064 -391.238994) (xy 74.290619 -391.245907) (xy 74.280083 -391.264993)
			(xy 74.278744 -391.275824) (xy 74.27468 -391.331958) (xy 74.285856 -391.342626) (xy 74.293208 -391.349138)
			(xy 74.311355 -391.356596) (xy 74.321162 -391.357104) (xy 74.353166 -391.357104) (xy 74.362983 -391.356641)
			(xy 74.381147 -391.34918) (xy 74.388472 -391.342626) (xy 74.40998 -391.322462) (xy 74.458038 -391.288317)
			(xy 74.510775 -391.261969) (xy 74.566937 -391.244046) (xy 74.625188 -391.234973) (xy 74.654664 -391.234422)
			(xy 74.682034 -391.234904) (xy 74.736212 -391.242717) (xy 74.788715 -391.258202) (xy 74.838463 -391.28104)
			(xy 74.88443 -391.310762) (xy 74.905362 -391.328402) (xy 74.912474 -391.334498) (xy 74.929492 -391.340848)
			(xy 75.014836 -391.340848) (xy 75.031854 -391.334498) (xy 75.038966 -391.328402) (xy 75.059899 -391.310761)
			(xy 75.105867 -391.281037) (xy 75.155613 -391.258191) (xy 75.208115 -391.242695) (xy 75.262293 -391.234866)
			(xy 75.317035 -391.234866) (xy 75.371213 -391.242695) (xy 75.423715 -391.258191) (xy 75.473461 -391.281037)
			(xy 75.519429 -391.310761) (xy 75.540362 -391.328402) (xy 75.547474 -391.334498) (xy 75.564492 -391.340848)
			(xy 75.649836 -391.340848) (xy 75.666854 -391.334498) (xy 75.673966 -391.328402) (xy 75.6949 -391.310766)
			(xy 75.740872 -391.281053) (xy 75.790619 -391.258217) (xy 75.84312 -391.242725) (xy 75.897295 -391.234896)
			(xy 75.924664 -391.234422) (xy 75.951917 -391.234889) (xy 76.00587 -391.242642) (xy 76.058169 -391.257995)
			(xy 76.107751 -391.280635) (xy 76.153606 -391.310102) (xy 76.1948 -391.345796) (xy 76.230494 -391.386989)
			(xy 76.259962 -391.432843) (xy 76.282603 -391.482425) (xy 76.297957 -391.534724) (xy 76.305711 -391.588677)
			(xy 76.306172 -391.61593) (xy 76.30573 -391.643301) (xy 76.297908 -391.697482) (xy 76.282413 -391.749985)
			(xy 76.259566 -391.799732) (xy 76.229836 -391.845697) (xy 76.212192 -391.866628) (xy 76.206096 -391.87374)
			(xy 76.199746 -391.890758) (xy 76.199746 -391.976102) (xy 76.206096 -391.99312) (xy 76.212192 -392.000232)
			(xy 76.229861 -392.021141) (xy 76.259583 -392.067114) (xy 76.282426 -392.116864) (xy 76.297919 -392.169369)
			(xy 76.305744 -392.223551) (xy 76.305741 -392.278294) (xy 76.297909 -392.332475) (xy 76.28241 -392.384979)
			(xy 76.259562 -392.434726) (xy 76.229834 -392.480695) (xy 76.212192 -392.501628) (xy 76.206096 -392.50874)
			(xy 76.199746 -392.525758) (xy 76.199746 -392.611102) (xy 76.206096 -392.62812) (xy 76.212192 -392.635232)
			(xy 76.229861 -392.656141) (xy 76.259583 -392.702114) (xy 76.282426 -392.751864) (xy 76.297919 -392.804369)
			(xy 76.305744 -392.858551) (xy 76.305741 -392.913294) (xy 76.297909 -392.967475) (xy 76.28241 -393.019979)
			(xy 76.259562 -393.069726) (xy 76.229834 -393.115695) (xy 76.212192 -393.136628) (xy 76.206096 -393.14374)
			(xy 76.199746 -393.160758) (xy 76.199746 -393.246102) (xy 76.206096 -393.26312) (xy 76.212192 -393.270232)
			(xy 76.229811 -393.29118) (xy 76.259526 -393.337148) (xy 76.282366 -393.386892) (xy 76.297862 -393.439389)
			(xy 76.305695 -393.493562) (xy 76.306172 -393.52093) (xy 76.305773 -393.548185) (xy 76.298011 -393.60214)
			(xy 76.282649 -393.654442) (xy 76.260001 -393.704024) (xy 76.230526 -393.749879) (xy 76.194826 -393.791072)
			(xy 76.153626 -393.826766) (xy 76.107766 -393.856232) (xy 76.05818 -393.878872) (xy 76.005876 -393.894225)
			(xy 75.951919 -393.901978) (xy 75.924664 -393.902438) (xy 75.897292 -393.902008) (xy 75.843111 -393.894184)
			(xy 75.790607 -393.878687) (xy 75.740861 -393.855837) (xy 75.694896 -393.826104) (xy 75.673966 -393.808458)
			(xy 75.666854 -393.802362) (xy 75.649836 -393.796012) (xy 75.564492 -393.796012) (xy 75.547474 -393.802362)
			(xy 75.540362 -393.808458) (xy 75.519429 -393.826099) (xy 75.473461 -393.855823) (xy 75.423715 -393.878669)
			(xy 75.371213 -393.894165) (xy 75.317035 -393.901994) (xy 75.262293 -393.901994) (xy 75.208115 -393.894165)
			(xy 75.155613 -393.878669) (xy 75.105867 -393.855823) (xy 75.059899 -393.826099) (xy 75.038966 -393.808458)
			(xy 75.031854 -393.802362) (xy 75.014836 -393.796012) (xy 74.929492 -393.796012) (xy 74.912474 -393.802362)
			(xy 74.905362 -393.808458) (xy 74.884429 -393.826099) (xy 74.838461 -393.855823) (xy 74.788715 -393.878669)
			(xy 74.736213 -393.894165) (xy 74.682035 -393.901994) (xy 74.627293 -393.901994) (xy 74.573115 -393.894165)
			(xy 74.520613 -393.878669) (xy 74.470867 -393.855823) (xy 74.424899 -393.826099) (xy 74.403966 -393.808458)
			(xy 74.396854 -393.802362) (xy 74.379836 -393.796012) (xy 74.294492 -393.796012) (xy 74.277474 -393.802362)
			(xy 74.270362 -393.808458) (xy 74.249412 -393.826075) (xy 74.203445 -393.855792) (xy 74.153702 -393.878632)
			(xy 74.101205 -393.894129) (xy 74.047032 -393.901962) (xy 74.019664 -393.902438) (xy 73.992413 -393.901956)
			(xy 73.938467 -393.894195) (xy 73.886174 -393.878837) (xy 73.836599 -393.856194) (xy 73.79075 -393.826727)
			(xy 73.749561 -393.791035) (xy 73.71387 -393.749845) (xy 73.684403 -393.703996) (xy 73.661761 -393.65442)
			(xy 73.646404 -393.602127) (xy 73.638644 -393.548181) (xy 73.638156 -393.52093) (xy 72.783192 -393.52093)
			(xy 72.782772 -393.551662) (xy 72.77536 -393.612678) (xy 72.760647 -393.672356) (xy 72.738849 -393.729825)
			(xy 72.710282 -393.784248) (xy 72.675363 -393.83483) (xy 72.634603 -393.880835) (xy 72.588594 -393.921592)
			(xy 72.538008 -393.956506) (xy 72.483583 -393.985067) (xy 72.426112 -394.006861) (xy 72.366433 -394.021568)
			(xy 72.305416 -394.028975) (xy 72.274684 -394.029438) (xy 72.243988 -394.028947) (xy 72.183044 -394.021548)
			(xy 72.123436 -394.006859) (xy 72.066032 -393.985096) (xy 72.011668 -393.956574) (xy 71.98614 -393.939522)
			(xy 71.977388 -393.934051) (xy 71.957184 -393.929923) (xy 71.93698 -393.934051) (xy 71.928228 -393.939522)
			(xy 71.902703 -393.956577) (xy 71.848332 -393.985085) (xy 71.790927 -394.006845) (xy 71.73132 -394.021541)
			(xy 71.670379 -394.02896) (xy 71.639684 -394.029438) (xy 71.608988 -394.028947) (xy 71.548044 -394.021548)
			(xy 71.488436 -394.006859) (xy 71.431032 -393.985096) (xy 71.376668 -393.956574) (xy 71.35114 -393.939522)
			(xy 71.342388 -393.934051) (xy 71.322184 -393.929923) (xy 71.30198 -393.934051) (xy 71.293228 -393.939522)
			(xy 71.267703 -393.956577) (xy 71.213332 -393.985085) (xy 71.155927 -394.006845) (xy 71.09632 -394.021541)
			(xy 71.035379 -394.02896) (xy 71.004684 -394.029438) (xy 70.973988 -394.028947) (xy 70.913044 -394.021548)
			(xy 70.853436 -394.006859) (xy 70.796032 -393.985096) (xy 70.741668 -393.956574) (xy 70.71614 -393.939522)
			(xy 70.707388 -393.934051) (xy 70.687184 -393.929923) (xy 70.66698 -393.934051) (xy 70.658228 -393.939522)
			(xy 70.632703 -393.956577) (xy 70.578332 -393.985085) (xy 70.520927 -394.006845) (xy 70.46132 -394.021541)
			(xy 70.400379 -394.02896) (xy 70.369684 -394.029438) (xy 70.338988 -394.028947) (xy 70.278044 -394.021548)
			(xy 70.218436 -394.006859) (xy 70.161032 -393.985096) (xy 70.106668 -393.956574) (xy 70.08114 -393.939522)
			(xy 70.072388 -393.934051) (xy 70.052184 -393.929923) (xy 70.03198 -393.934051) (xy 70.023228 -393.939522)
			(xy 69.997703 -393.956577) (xy 69.943332 -393.985085) (xy 69.885927 -394.006845) (xy 69.82632 -394.021541)
			(xy 69.765379 -394.02896) (xy 69.734684 -394.029438) (xy 69.703954 -394.028959) (xy 69.642942 -394.021549)
			(xy 69.583268 -394.00684) (xy 69.525801 -393.985045) (xy 69.471381 -393.956483) (xy 69.4208 -393.921569)
			(xy 69.374796 -393.880814) (xy 69.334039 -393.834811) (xy 69.299124 -393.784231) (xy 69.270561 -393.729811)
			(xy 69.248764 -393.672346) (xy 69.234053 -393.612672) (xy 69.226642 -393.55166) (xy 69.226176 -393.52093)
			(xy 68.94873 -393.52093) (xy 68.921103 -393.563918) (xy 68.885412 -393.605108) (xy 68.844223 -393.640799)
			(xy 68.798374 -393.670266) (xy 68.748797 -393.692907) (xy 68.696504 -393.708263) (xy 68.642557 -393.71602)
			(xy 68.615306 -393.71651) (xy 68.601336 -393.716256) (xy 68.591176 -393.716002) (xy 68.571872 -393.723114)
			(xy 68.511674 -393.78128) (xy 68.504626 -393.788733) (xy 68.496641 -393.807608) (xy 68.49618 -393.817856)
			(xy 68.49618 -393.922758) (xy 68.496613 -393.932824) (xy 68.50434 -393.951415) (xy 68.511166 -393.958826)
			(xy 70.076314 -395.523974) (xy 70.083712 -395.530821) (xy 70.10231 -395.538554) (xy 70.112382 -395.53896)
		)
		(stroke
			(width 0)
			(type solid)
		)
		(fill yes)
		(layer "In2.Cu")
		(net "P0V9_CPU1_RT1_2A_2D")
	)
	(gr_poly
		(pts
			(xy 449.479924 -430.42967) (xy 449.488625 -430.429226) (xy 449.504967 -430.423218) (xy 449.518348 -430.412079)
			(xy 449.523104 -430.404778) (xy 449.525644 -430.399952) (xy 449.563744 -430.315624) (xy 449.567313 -430.306648)
			(xy 449.568156 -430.287364) (xy 449.561827 -430.269129) (xy 449.55587 -430.261522) (xy 449.55587 -430.261268)
			(xy 449.53828 -430.240341) (xy 449.508647 -430.194402) (xy 449.485873 -430.144704) (xy 449.470426 -430.092265)
			(xy 449.46262 -430.038158) (xy 449.462144 -430.010824) (xy 449.46263 -429.983573) (xy 449.470386 -429.929625)
			(xy 449.485741 -429.87733) (xy 449.508383 -429.827753) (xy 449.537849 -429.781903) (xy 449.57354 -429.740712)
			(xy 449.614731 -429.705021) (xy 449.660581 -429.675555) (xy 449.710158 -429.652913) (xy 449.762453 -429.637558)
			(xy 449.816401 -429.629802) (xy 449.870903 -429.629802) (xy 449.924851 -429.637558) (xy 449.977146 -429.652913)
			(xy 450.026723 -429.675555) (xy 450.072573 -429.705021) (xy 450.113764 -429.740712) (xy 450.149455 -429.781903)
			(xy 450.178921 -429.827753) (xy 450.201563 -429.87733) (xy 450.216918 -429.929625) (xy 450.224674 -429.983573)
			(xy 450.22516 -430.010824) (xy 450.224689 -430.038157) (xy 450.216882 -430.092264) (xy 450.201431 -430.144702)
			(xy 450.178652 -430.194397) (xy 450.149013 -430.240332) (xy 450.131434 -430.261268) (xy 450.131434 -430.261522)
			(xy 450.125417 -430.269094) (xy 450.119066 -430.287346) (xy 450.119952 -430.30665) (xy 450.12356 -430.315624)
			(xy 450.16166 -430.399952) (xy 450.1642 -430.404778) (xy 450.16895 -430.412079) (xy 450.182341 -430.423199)
			(xy 450.198681 -430.429194) (xy 450.20738 -430.42967) (xy 450.207888 -430.42967) (xy 450.938138 -430.42967)
			(xy 450.943157 -430.429579) (xy 450.95301 -430.42766) (xy 450.957696 -430.42586) (xy 451.533768 -430.1871)
			(xy 451.538346 -430.185036) (xy 451.546662 -430.179409) (xy 451.550278 -430.175924) (xy 456.793346 -424.932856)
			(xy 456.79987 -424.925814) (xy 456.807575 -424.908249) (xy 456.808285 -424.889081) (xy 456.801901 -424.870993)
			(xy 456.795886 -424.863514) (xy 456.755483 -424.816103) (xy 456.679726 -424.717203) (xy 456.609977 -424.613979)
			(xy 456.546482 -424.506794) (xy 456.489464 -424.396028) (xy 456.439126 -424.282071) (xy 456.395644 -424.165325)
			(xy 456.359172 -424.046203) (xy 456.329839 -423.925126) (xy 456.307749 -423.80252) (xy 456.29298 -423.678818)
			(xy 456.285583 -423.554458) (xy 456.285092 -423.492168) (xy 456.28561 -423.426315) (xy 456.293882 -423.29487)
			(xy 456.310391 -423.164203) (xy 456.335072 -423.03483) (xy 456.367827 -422.907263) (xy 456.408528 -422.782004)
			(xy 456.457013 -422.659548) (xy 456.513092 -422.540377) (xy 456.576543 -422.424964) (xy 456.647116 -422.313761)
			(xy 456.724531 -422.20721) (xy 456.808484 -422.10573) (xy 456.898644 -422.009721) (xy 456.994654 -421.919563)
			(xy 457.096135 -421.835612) (xy 457.202688 -421.758198) (xy 457.313891 -421.687627) (xy 457.429306 -421.624178)
			(xy 457.548477 -421.568101) (xy 457.670934 -421.519617) (xy 457.796194 -421.478918) (xy 457.923762 -421.446165)
			(xy 458.053134 -421.421486) (xy 458.183801 -421.404979) (xy 458.315247 -421.396709) (xy 458.3811 -421.39616)
			(xy 458.443391 -421.396616) (xy 458.567752 -421.404015) (xy 458.691454 -421.418787) (xy 458.814061 -421.44088)
			(xy 458.935139 -421.470215) (xy 459.054261 -421.50669) (xy 459.171007 -421.550175) (xy 459.284963 -421.600517)
			(xy 459.395729 -421.657538) (xy 459.502913 -421.721037) (xy 459.606136 -421.79079) (xy 459.705035 -421.86655)
			(xy 459.752446 -421.906954) (xy 459.759953 -421.912931) (xy 459.778035 -421.919312) (xy 459.797197 -421.918623)
			(xy 459.814774 -421.910959) (xy 459.821788 -421.904414) (xy 461.581246 -420.144956) (xy 461.588091 -420.137558)
			(xy 461.595818 -420.118959) (xy 461.596232 -420.108888) (xy 461.596232 -406.197816) (xy 461.595726 -406.187766)
			(xy 461.588004 -406.169206) (xy 461.581246 -406.161748) (xy 459.294738 -403.87524) (xy 459.287897 -403.86784)
			(xy 459.280178 -403.849241) (xy 459.279752 -403.839172) (xy 459.279752 -396.46733) (xy 459.280189 -396.457267)
			(xy 459.287927 -396.438686) (xy 459.294738 -396.431262) (xy 461.286606 -394.439394) (xy 461.294005 -394.432549)
			(xy 461.312603 -394.424818) (xy 461.322674 -394.424408) (xy 464.496658 -394.424408) (xy 464.506724 -394.423975)
			(xy 464.525314 -394.416246) (xy 464.532726 -394.409422) (xy 465.8233 -393.118848) (xy 465.830138 -393.111447)
			(xy 465.837854 -393.092849) (xy 465.838286 -393.08278) (xy 465.838286 -377.134628) (xy 465.837849 -377.124564)
			(xy 465.830115 -377.10598) (xy 465.8233 -377.09856) (xy 464.266534 -375.541794) (xy 464.259422 -375.534428)
			(xy 464.240626 -375.526808) (xy 442.608462 -375.526808) (xy 442.598395 -375.527238) (xy 442.579801 -375.534963)
			(xy 442.572394 -375.541794) (xy 441.116212 -376.997976) (xy 441.109523 -377.005384) (xy 441.10193 -377.02382)
			(xy 441.10148 -377.03379) (xy 441.10148 -383.388882) (xy 441.915547 -383.388882) (xy 441.919279 -383.335628)
			(xy 441.930398 -383.283415) (xy 441.948686 -383.233261) (xy 441.973787 -383.186146) (xy 442.005209 -383.14299)
			(xy 442.042341 -383.104634) (xy 442.063124 -383.08788) (xy 442.071895 -383.080327) (xy 442.082072 -383.059561)
			(xy 442.082682 -383.048002) (xy 442.082682 -382.967738) (xy 442.082096 -382.956172) (xy 442.071913 -382.9354)
			(xy 442.063124 -382.92786) (xy 442.042313 -382.911141) (xy 442.005185 -382.872782) (xy 441.973767 -382.829623)
			(xy 441.948671 -382.782505) (xy 441.930388 -382.73235) (xy 441.919274 -382.680135) (xy 441.915547 -382.626882)
			(xy 441.919279 -382.573628) (xy 441.930398 -382.521415) (xy 441.948686 -382.471261) (xy 441.973787 -382.424146)
			(xy 442.005209 -382.38099) (xy 442.042341 -382.342634) (xy 442.063124 -382.32588) (xy 442.071895 -382.318327)
			(xy 442.082072 -382.297561) (xy 442.082682 -382.286002) (xy 442.082682 -382.205738) (xy 442.082096 -382.194172)
			(xy 442.071913 -382.1734) (xy 442.063124 -382.16586) (xy 442.040626 -382.147685) (xy 442.000891 -382.105663)
			(xy 441.967953 -382.058125) (xy 441.942567 -382.00616) (xy 441.925314 -381.950959) (xy 441.91659 -381.893787)
			(xy 441.916058 -381.86487) (xy 441.916544 -381.837619) (xy 441.9243 -381.783671) (xy 441.939655 -381.731376)
			(xy 441.962297 -381.681799) (xy 441.991763 -381.635949) (xy 442.027454 -381.594758) (xy 442.068645 -381.559067)
			(xy 442.114495 -381.529601) (xy 442.164072 -381.506959) (xy 442.216367 -381.491604) (xy 442.270315 -381.483848)
			(xy 442.324817 -381.483848) (xy 442.378765 -381.491604) (xy 442.43106 -381.506959) (xy 442.480637 -381.529601)
			(xy 442.526487 -381.559067) (xy 442.567678 -381.594758) (xy 442.603369 -381.635949) (xy 442.632835 -381.681799)
			(xy 442.655477 -381.731376) (xy 442.670832 -381.783671) (xy 442.678588 -381.837619) (xy 442.679074 -381.86487)
			(xy 442.678544 -381.893787) (xy 442.669819 -381.950958) (xy 442.652564 -382.006157) (xy 442.627174 -382.058119)
			(xy 442.594232 -382.105653) (xy 442.554493 -382.14767) (xy 442.532008 -382.16586) (xy 442.52327 -382.173445)
			(xy 442.513073 -382.194186) (xy 442.51245 -382.205738) (xy 442.51245 -382.286002) (xy 442.513002 -382.297573)
			(xy 442.523208 -382.318345) (xy 442.532008 -382.32588) (xy 442.552763 -382.342668) (xy 442.589896 -382.381016)
			(xy 442.62132 -382.424166) (xy 442.646422 -382.471275) (xy 442.664711 -382.521424) (xy 442.675831 -382.573632)
			(xy 442.679563 -382.626882) (xy 442.675836 -382.680131) (xy 442.664721 -382.732341) (xy 442.646437 -382.782491)
			(xy 442.621339 -382.829603) (xy 442.589919 -382.872756) (xy 442.55279 -382.911107) (xy 442.532008 -382.92786)
			(xy 442.52327 -382.935445) (xy 442.513073 -382.956186) (xy 442.51245 -382.967738) (xy 442.51245 -383.048002)
			(xy 442.513002 -383.059573) (xy 442.523208 -383.080345) (xy 442.532008 -383.08788) (xy 442.552763 -383.104668)
			(xy 442.589896 -383.143016) (xy 442.62132 -383.186166) (xy 442.646422 -383.233275) (xy 442.664711 -383.283424)
			(xy 442.675831 -383.335632) (xy 442.679563 -383.388882) (xy 445.725547 -383.388882) (xy 445.729279 -383.335628)
			(xy 445.740398 -383.283415) (xy 445.758686 -383.233261) (xy 445.783787 -383.186146) (xy 445.815209 -383.14299)
			(xy 445.852341 -383.104634) (xy 445.873124 -383.08788) (xy 445.881895 -383.080327) (xy 445.892072 -383.059561)
			(xy 445.892682 -383.048002) (xy 445.892682 -382.967738) (xy 445.892096 -382.956172) (xy 445.881913 -382.9354)
			(xy 445.873124 -382.92786) (xy 445.852313 -382.911141) (xy 445.815185 -382.872782) (xy 445.783767 -382.829623)
			(xy 445.758671 -382.782505) (xy 445.740388 -382.73235) (xy 445.729274 -382.680135) (xy 445.725547 -382.626882)
			(xy 445.729279 -382.573628) (xy 445.740398 -382.521415) (xy 445.758686 -382.471261) (xy 445.783787 -382.424146)
			(xy 445.815209 -382.38099) (xy 445.852341 -382.342634) (xy 445.873124 -382.32588) (xy 445.881895 -382.318327)
			(xy 445.892072 -382.297561) (xy 445.892682 -382.286002) (xy 445.892682 -382.205738) (xy 445.892096 -382.194172)
			(xy 445.881913 -382.1734) (xy 445.873124 -382.16586) (xy 445.850626 -382.147685) (xy 445.810891 -382.105663)
			(xy 445.777953 -382.058125) (xy 445.752567 -382.00616) (xy 445.735314 -381.950959) (xy 445.72659 -381.893787)
			(xy 445.726058 -381.86487) (xy 445.726544 -381.837619) (xy 445.7343 -381.783671) (xy 445.749655 -381.731376)
			(xy 445.772297 -381.681799) (xy 445.801763 -381.635949) (xy 445.837454 -381.594758) (xy 445.878645 -381.559067)
			(xy 445.924495 -381.529601) (xy 445.974072 -381.506959) (xy 446.026367 -381.491604) (xy 446.080315 -381.483848)
			(xy 446.134817 -381.483848) (xy 446.188765 -381.491604) (xy 446.24106 -381.506959) (xy 446.290637 -381.529601)
			(xy 446.336487 -381.559067) (xy 446.377678 -381.594758) (xy 446.413369 -381.635949) (xy 446.442835 -381.681799)
			(xy 446.465477 -381.731376) (xy 446.480832 -381.783671) (xy 446.488588 -381.837619) (xy 446.489074 -381.86487)
			(xy 446.488544 -381.893787) (xy 446.479819 -381.950958) (xy 446.462564 -382.006157) (xy 446.437174 -382.058119)
			(xy 446.404232 -382.105653) (xy 446.364493 -382.14767) (xy 446.342008 -382.16586) (xy 446.33327 -382.173445)
			(xy 446.323073 -382.194186) (xy 446.32245 -382.205738) (xy 446.32245 -382.286002) (xy 446.323002 -382.297573)
			(xy 446.333208 -382.318345) (xy 446.342008 -382.32588) (xy 446.362763 -382.342668) (xy 446.399896 -382.381016)
			(xy 446.43132 -382.424166) (xy 446.456422 -382.471275) (xy 446.474711 -382.521424) (xy 446.485831 -382.573632)
			(xy 446.489563 -382.626882) (xy 446.485836 -382.680131) (xy 446.474721 -382.732341) (xy 446.456437 -382.782491)
			(xy 446.431339 -382.829603) (xy 446.399919 -382.872756) (xy 446.36279 -382.911107) (xy 446.342008 -382.92786)
			(xy 446.33327 -382.935445) (xy 446.323073 -382.956186) (xy 446.32245 -382.967738) (xy 446.32245 -383.048002)
			(xy 446.323002 -383.059573) (xy 446.333208 -383.080345) (xy 446.342008 -383.08788) (xy 446.362763 -383.104668)
			(xy 446.399896 -383.143016) (xy 446.43132 -383.186166) (xy 446.456422 -383.233275) (xy 446.474711 -383.283424)
			(xy 446.485831 -383.335632) (xy 446.489563 -383.388882) (xy 447.681347 -383.388882) (xy 447.685079 -383.335628)
			(xy 447.696198 -383.283415) (xy 447.714486 -383.233261) (xy 447.739587 -383.186146) (xy 447.771009 -383.14299)
			(xy 447.808141 -383.104634) (xy 447.828924 -383.08788) (xy 447.837695 -383.080327) (xy 447.847872 -383.059561)
			(xy 447.848482 -383.048002) (xy 447.848482 -382.967738) (xy 447.847896 -382.956172) (xy 447.837713 -382.9354)
			(xy 447.828924 -382.92786) (xy 447.808113 -382.911141) (xy 447.770985 -382.872782) (xy 447.739567 -382.829623)
			(xy 447.714471 -382.782505) (xy 447.696188 -382.73235) (xy 447.685074 -382.680135) (xy 447.681347 -382.626882)
			(xy 447.685079 -382.573628) (xy 447.696198 -382.521415) (xy 447.714486 -382.471261) (xy 447.739587 -382.424146)
			(xy 447.771009 -382.38099) (xy 447.808141 -382.342634) (xy 447.828924 -382.32588) (xy 447.837695 -382.318327)
			(xy 447.847872 -382.297561) (xy 447.848482 -382.286002) (xy 447.848482 -382.205738) (xy 447.847896 -382.194172)
			(xy 447.837713 -382.1734) (xy 447.828924 -382.16586) (xy 447.806426 -382.147685) (xy 447.766691 -382.105663)
			(xy 447.733753 -382.058125) (xy 447.708367 -382.00616) (xy 447.691114 -381.950959) (xy 447.68239 -381.893787)
			(xy 447.681858 -381.86487) (xy 447.682344 -381.837619) (xy 447.6901 -381.783671) (xy 447.705455 -381.731376)
			(xy 447.728097 -381.681799) (xy 447.757563 -381.635949) (xy 447.793254 -381.594758) (xy 447.834445 -381.559067)
			(xy 447.880295 -381.529601) (xy 447.929872 -381.506959) (xy 447.982167 -381.491604) (xy 448.036115 -381.483848)
			(xy 448.090617 -381.483848) (xy 448.144565 -381.491604) (xy 448.19686 -381.506959) (xy 448.246437 -381.529601)
			(xy 448.292287 -381.559067) (xy 448.333478 -381.594758) (xy 448.369169 -381.635949) (xy 448.398635 -381.681799)
			(xy 448.421277 -381.731376) (xy 448.436632 -381.783671) (xy 448.444388 -381.837619) (xy 448.444874 -381.86487)
			(xy 448.444344 -381.893787) (xy 448.435619 -381.950958) (xy 448.418364 -382.006157) (xy 448.392974 -382.058119)
			(xy 448.360032 -382.105653) (xy 448.320293 -382.14767) (xy 448.297808 -382.16586) (xy 448.28907 -382.173445)
			(xy 448.278873 -382.194186) (xy 448.27825 -382.205738) (xy 448.27825 -382.286002) (xy 448.278802 -382.297573)
			(xy 448.289008 -382.318345) (xy 448.297808 -382.32588) (xy 448.318563 -382.342668) (xy 448.355696 -382.381016)
			(xy 448.38712 -382.424166) (xy 448.412222 -382.471275) (xy 448.430511 -382.521424) (xy 448.441631 -382.573632)
			(xy 448.445363 -382.626882) (xy 448.441636 -382.680131) (xy 448.430521 -382.732341) (xy 448.412237 -382.782491)
			(xy 448.387139 -382.829603) (xy 448.355719 -382.872756) (xy 448.31859 -382.911107) (xy 448.297808 -382.92786)
			(xy 448.28907 -382.935445) (xy 448.278873 -382.956186) (xy 448.27825 -382.967738) (xy 448.27825 -383.048002)
			(xy 448.278802 -383.059573) (xy 448.289008 -383.080345) (xy 448.297808 -383.08788) (xy 448.318563 -383.104668)
			(xy 448.355696 -383.143016) (xy 448.38712 -383.186166) (xy 448.412222 -383.233275) (xy 448.430511 -383.283424)
			(xy 448.441631 -383.335632) (xy 448.445363 -383.388882) (xy 451.491347 -383.388882) (xy 451.495079 -383.335628)
			(xy 451.506198 -383.283415) (xy 451.524486 -383.233261) (xy 451.549587 -383.186146) (xy 451.581009 -383.14299)
			(xy 451.618141 -383.104634) (xy 451.638924 -383.08788) (xy 451.647695 -383.080327) (xy 451.657872 -383.059561)
			(xy 451.658482 -383.048002) (xy 451.658482 -382.967738) (xy 451.657896 -382.956172) (xy 451.647713 -382.9354)
			(xy 451.638924 -382.92786) (xy 451.618113 -382.911141) (xy 451.580985 -382.872782) (xy 451.549567 -382.829623)
			(xy 451.524471 -382.782505) (xy 451.506188 -382.73235) (xy 451.495074 -382.680135) (xy 451.491347 -382.626882)
			(xy 451.495079 -382.573628) (xy 451.506198 -382.521415) (xy 451.524486 -382.471261) (xy 451.549587 -382.424146)
			(xy 451.581009 -382.38099) (xy 451.618141 -382.342634) (xy 451.638924 -382.32588) (xy 451.647695 -382.318327)
			(xy 451.657872 -382.297561) (xy 451.658482 -382.286002) (xy 451.658482 -382.205738) (xy 451.657896 -382.194172)
			(xy 451.647713 -382.1734) (xy 451.638924 -382.16586) (xy 451.616426 -382.147685) (xy 451.576691 -382.105663)
			(xy 451.543753 -382.058125) (xy 451.518367 -382.00616) (xy 451.501114 -381.950959) (xy 451.49239 -381.893787)
			(xy 451.491858 -381.86487) (xy 451.492344 -381.837619) (xy 451.5001 -381.783671) (xy 451.515455 -381.731376)
			(xy 451.538097 -381.681799) (xy 451.567563 -381.635949) (xy 451.603254 -381.594758) (xy 451.644445 -381.559067)
			(xy 451.690295 -381.529601) (xy 451.739872 -381.506959) (xy 451.792167 -381.491604) (xy 451.846115 -381.483848)
			(xy 451.900617 -381.483848) (xy 451.954565 -381.491604) (xy 452.00686 -381.506959) (xy 452.056437 -381.529601)
			(xy 452.102287 -381.559067) (xy 452.143478 -381.594758) (xy 452.179169 -381.635949) (xy 452.208635 -381.681799)
			(xy 452.231277 -381.731376) (xy 452.246632 -381.783671) (xy 452.254388 -381.837619) (xy 452.254874 -381.86487)
			(xy 452.254344 -381.893787) (xy 452.245619 -381.950958) (xy 452.228364 -382.006157) (xy 452.202974 -382.058119)
			(xy 452.170032 -382.105653) (xy 452.130293 -382.14767) (xy 452.107808 -382.16586) (xy 452.09907 -382.173445)
			(xy 452.088873 -382.194186) (xy 452.08825 -382.205738) (xy 452.08825 -382.286002) (xy 452.088802 -382.297573)
			(xy 452.099008 -382.318345) (xy 452.107808 -382.32588) (xy 452.128563 -382.342668) (xy 452.165696 -382.381016)
			(xy 452.19712 -382.424166) (xy 452.222222 -382.471275) (xy 452.240511 -382.521424) (xy 452.251631 -382.573632)
			(xy 452.255363 -382.626882) (xy 452.251636 -382.680131) (xy 452.240521 -382.732341) (xy 452.222237 -382.782491)
			(xy 452.197139 -382.829603) (xy 452.165719 -382.872756) (xy 452.12859 -382.911107) (xy 452.107808 -382.92786)
			(xy 452.09907 -382.935445) (xy 452.088873 -382.956186) (xy 452.08825 -382.967738) (xy 452.08825 -383.048002)
			(xy 452.088802 -383.059573) (xy 452.099008 -383.080345) (xy 452.107808 -383.08788) (xy 452.128563 -383.104668)
			(xy 452.165696 -383.143016) (xy 452.19712 -383.186166) (xy 452.222222 -383.233275) (xy 452.240511 -383.283424)
			(xy 452.251631 -383.335632) (xy 452.255363 -383.388882) (xy 453.777347 -383.388882) (xy 453.781079 -383.335628)
			(xy 453.792198 -383.283415) (xy 453.810486 -383.233261) (xy 453.835587 -383.186146) (xy 453.867009 -383.14299)
			(xy 453.904141 -383.104634) (xy 453.924924 -383.08788) (xy 453.933695 -383.080327) (xy 453.943872 -383.059561)
			(xy 453.944482 -383.048002) (xy 453.944482 -382.967738) (xy 453.943896 -382.956172) (xy 453.933713 -382.9354)
			(xy 453.924924 -382.92786) (xy 453.904113 -382.911141) (xy 453.866985 -382.872782) (xy 453.835567 -382.829623)
			(xy 453.810471 -382.782505) (xy 453.792188 -382.73235) (xy 453.781074 -382.680135) (xy 453.777347 -382.626882)
			(xy 453.781079 -382.573628) (xy 453.792198 -382.521415) (xy 453.810486 -382.471261) (xy 453.835587 -382.424146)
			(xy 453.867009 -382.38099) (xy 453.904141 -382.342634) (xy 453.924924 -382.32588) (xy 453.933695 -382.318327)
			(xy 453.943872 -382.297561) (xy 453.944482 -382.286002) (xy 453.944482 -382.205738) (xy 453.943896 -382.194172)
			(xy 453.933713 -382.1734) (xy 453.924924 -382.16586) (xy 453.902426 -382.147685) (xy 453.862691 -382.105663)
			(xy 453.829753 -382.058125) (xy 453.804367 -382.00616) (xy 453.787114 -381.950959) (xy 453.77839 -381.893787)
			(xy 453.777858 -381.86487) (xy 453.778344 -381.837619) (xy 453.7861 -381.783671) (xy 453.801455 -381.731376)
			(xy 453.824097 -381.681799) (xy 453.853563 -381.635949) (xy 453.889254 -381.594758) (xy 453.930445 -381.559067)
			(xy 453.976295 -381.529601) (xy 454.025872 -381.506959) (xy 454.078167 -381.491604) (xy 454.132115 -381.483848)
			(xy 454.186617 -381.483848) (xy 454.240565 -381.491604) (xy 454.29286 -381.506959) (xy 454.342437 -381.529601)
			(xy 454.388287 -381.559067) (xy 454.429478 -381.594758) (xy 454.465169 -381.635949) (xy 454.494635 -381.681799)
			(xy 454.517277 -381.731376) (xy 454.532632 -381.783671) (xy 454.540388 -381.837619) (xy 454.540874 -381.86487)
			(xy 454.540344 -381.893787) (xy 454.531619 -381.950958) (xy 454.514364 -382.006157) (xy 454.488974 -382.058119)
			(xy 454.456032 -382.105653) (xy 454.416293 -382.14767) (xy 454.393808 -382.16586) (xy 454.38507 -382.173445)
			(xy 454.374873 -382.194186) (xy 454.37425 -382.205738) (xy 454.37425 -382.286002) (xy 454.374802 -382.297573)
			(xy 454.385008 -382.318345) (xy 454.393808 -382.32588) (xy 454.414563 -382.342668) (xy 454.451696 -382.381016)
			(xy 454.48312 -382.424166) (xy 454.508222 -382.471275) (xy 454.526511 -382.521424) (xy 454.537631 -382.573632)
			(xy 454.541363 -382.626882) (xy 454.537636 -382.680131) (xy 454.526521 -382.732341) (xy 454.508237 -382.782491)
			(xy 454.483139 -382.829603) (xy 454.451719 -382.872756) (xy 454.41459 -382.911107) (xy 454.393808 -382.92786)
			(xy 454.38507 -382.935445) (xy 454.374873 -382.956186) (xy 454.37425 -382.967738) (xy 454.37425 -383.048002)
			(xy 454.374802 -383.059573) (xy 454.385008 -383.080345) (xy 454.393808 -383.08788) (xy 454.414563 -383.104668)
			(xy 454.451696 -383.143016) (xy 454.48312 -383.186166) (xy 454.508222 -383.233275) (xy 454.526511 -383.283424)
			(xy 454.537631 -383.335632) (xy 454.541363 -383.388882) (xy 457.587347 -383.388882) (xy 457.591079 -383.335628)
			(xy 457.602198 -383.283415) (xy 457.620486 -383.233261) (xy 457.645587 -383.186146) (xy 457.677009 -383.14299)
			(xy 457.714141 -383.104634) (xy 457.734924 -383.08788) (xy 457.743695 -383.080327) (xy 457.753872 -383.059561)
			(xy 457.754482 -383.048002) (xy 457.754482 -382.967738) (xy 457.753896 -382.956172) (xy 457.743713 -382.9354)
			(xy 457.734924 -382.92786) (xy 457.714113 -382.911141) (xy 457.676985 -382.872782) (xy 457.645567 -382.829623)
			(xy 457.620471 -382.782505) (xy 457.602188 -382.73235) (xy 457.591074 -382.680135) (xy 457.587347 -382.626882)
			(xy 457.591079 -382.573628) (xy 457.602198 -382.521415) (xy 457.620486 -382.471261) (xy 457.645587 -382.424146)
			(xy 457.677009 -382.38099) (xy 457.714141 -382.342634) (xy 457.734924 -382.32588) (xy 457.743695 -382.318327)
			(xy 457.753872 -382.297561) (xy 457.754482 -382.286002) (xy 457.754482 -382.205738) (xy 457.753896 -382.194172)
			(xy 457.743713 -382.1734) (xy 457.734924 -382.16586) (xy 457.712426 -382.147685) (xy 457.672691 -382.105663)
			(xy 457.639753 -382.058125) (xy 457.614367 -382.00616) (xy 457.597114 -381.950959) (xy 457.58839 -381.893787)
			(xy 457.587858 -381.86487) (xy 457.588344 -381.837619) (xy 457.5961 -381.783671) (xy 457.611455 -381.731376)
			(xy 457.634097 -381.681799) (xy 457.663563 -381.635949) (xy 457.699254 -381.594758) (xy 457.740445 -381.559067)
			(xy 457.786295 -381.529601) (xy 457.835872 -381.506959) (xy 457.888167 -381.491604) (xy 457.942115 -381.483848)
			(xy 457.996617 -381.483848) (xy 458.050565 -381.491604) (xy 458.10286 -381.506959) (xy 458.152437 -381.529601)
			(xy 458.198287 -381.559067) (xy 458.239478 -381.594758) (xy 458.275169 -381.635949) (xy 458.304635 -381.681799)
			(xy 458.327277 -381.731376) (xy 458.342632 -381.783671) (xy 458.350388 -381.837619) (xy 458.350874 -381.86487)
			(xy 458.350344 -381.893787) (xy 458.341619 -381.950958) (xy 458.324364 -382.006157) (xy 458.298974 -382.058119)
			(xy 458.266032 -382.105653) (xy 458.226293 -382.14767) (xy 458.203808 -382.16586) (xy 458.19507 -382.173445)
			(xy 458.184873 -382.194186) (xy 458.18425 -382.205738) (xy 458.18425 -382.286002) (xy 458.184802 -382.297573)
			(xy 458.195008 -382.318345) (xy 458.203808 -382.32588) (xy 458.224563 -382.342668) (xy 458.261696 -382.381016)
			(xy 458.29312 -382.424166) (xy 458.318222 -382.471275) (xy 458.336511 -382.521424) (xy 458.347631 -382.573632)
			(xy 458.351363 -382.626882) (xy 458.347636 -382.680131) (xy 458.336521 -382.732341) (xy 458.318237 -382.782491)
			(xy 458.293139 -382.829603) (xy 458.261719 -382.872756) (xy 458.22459 -382.911107) (xy 458.203808 -382.92786)
			(xy 458.19507 -382.935445) (xy 458.184873 -382.956186) (xy 458.18425 -382.967738) (xy 458.18425 -383.048002)
			(xy 458.184802 -383.059573) (xy 458.195008 -383.080345) (xy 458.203808 -383.08788) (xy 458.224563 -383.104668)
			(xy 458.261696 -383.143016) (xy 458.29312 -383.186166) (xy 458.318222 -383.233275) (xy 458.336511 -383.283424)
			(xy 458.347631 -383.335632) (xy 458.351363 -383.388882) (xy 459.873347 -383.388882) (xy 459.877079 -383.335628)
			(xy 459.888198 -383.283415) (xy 459.906486 -383.233261) (xy 459.931587 -383.186146) (xy 459.963009 -383.14299)
			(xy 460.000141 -383.104634) (xy 460.020924 -383.08788) (xy 460.029695 -383.080327) (xy 460.039872 -383.059561)
			(xy 460.040482 -383.048002) (xy 460.040482 -382.967738) (xy 460.039896 -382.956172) (xy 460.029713 -382.9354)
			(xy 460.020924 -382.92786) (xy 460.000113 -382.911141) (xy 459.962985 -382.872782) (xy 459.931567 -382.829623)
			(xy 459.906471 -382.782505) (xy 459.888188 -382.73235) (xy 459.877074 -382.680135) (xy 459.873347 -382.626882)
			(xy 459.877079 -382.573628) (xy 459.888198 -382.521415) (xy 459.906486 -382.471261) (xy 459.931587 -382.424146)
			(xy 459.963009 -382.38099) (xy 460.000141 -382.342634) (xy 460.020924 -382.32588) (xy 460.029695 -382.318327)
			(xy 460.039872 -382.297561) (xy 460.040482 -382.286002) (xy 460.040482 -382.205738) (xy 460.039896 -382.194172)
			(xy 460.029713 -382.1734) (xy 460.020924 -382.16586) (xy 459.998426 -382.147685) (xy 459.958691 -382.105663)
			(xy 459.925753 -382.058125) (xy 459.900367 -382.00616) (xy 459.883114 -381.950959) (xy 459.87439 -381.893787)
			(xy 459.873858 -381.86487) (xy 459.874344 -381.837619) (xy 459.8821 -381.783671) (xy 459.897455 -381.731376)
			(xy 459.920097 -381.681799) (xy 459.949563 -381.635949) (xy 459.985254 -381.594758) (xy 460.026445 -381.559067)
			(xy 460.072295 -381.529601) (xy 460.121872 -381.506959) (xy 460.174167 -381.491604) (xy 460.228115 -381.483848)
			(xy 460.282617 -381.483848) (xy 460.336565 -381.491604) (xy 460.38886 -381.506959) (xy 460.438437 -381.529601)
			(xy 460.484287 -381.559067) (xy 460.525478 -381.594758) (xy 460.561169 -381.635949) (xy 460.590635 -381.681799)
			(xy 460.613277 -381.731376) (xy 460.628632 -381.783671) (xy 460.636388 -381.837619) (xy 460.636874 -381.86487)
			(xy 460.636344 -381.893787) (xy 460.627619 -381.950958) (xy 460.610364 -382.006157) (xy 460.584974 -382.058119)
			(xy 460.552032 -382.105653) (xy 460.512293 -382.14767) (xy 460.489808 -382.16586) (xy 460.48107 -382.173445)
			(xy 460.470873 -382.194186) (xy 460.47025 -382.205738) (xy 460.47025 -382.286002) (xy 460.470802 -382.297573)
			(xy 460.481008 -382.318345) (xy 460.489808 -382.32588) (xy 460.510563 -382.342668) (xy 460.547696 -382.381016)
			(xy 460.57912 -382.424166) (xy 460.604222 -382.471275) (xy 460.622511 -382.521424) (xy 460.633631 -382.573632)
			(xy 460.637363 -382.626882) (xy 460.633636 -382.680131) (xy 460.622521 -382.732341) (xy 460.604237 -382.782491)
			(xy 460.579139 -382.829603) (xy 460.547719 -382.872756) (xy 460.51059 -382.911107) (xy 460.489808 -382.92786)
			(xy 460.48107 -382.935445) (xy 460.470873 -382.956186) (xy 460.47025 -382.967738) (xy 460.47025 -383.048002)
			(xy 460.470802 -383.059573) (xy 460.481008 -383.080345) (xy 460.489808 -383.08788) (xy 460.510563 -383.104668)
			(xy 460.547696 -383.143016) (xy 460.57912 -383.186166) (xy 460.604222 -383.233275) (xy 460.622511 -383.283424)
			(xy 460.633631 -383.335632) (xy 460.637363 -383.388882) (xy 463.683347 -383.388882) (xy 463.687079 -383.335628)
			(xy 463.698198 -383.283415) (xy 463.716486 -383.233261) (xy 463.741587 -383.186146) (xy 463.773009 -383.14299)
			(xy 463.810141 -383.104634) (xy 463.830924 -383.08788) (xy 463.839695 -383.080327) (xy 463.849872 -383.059561)
			(xy 463.850482 -383.048002) (xy 463.850482 -382.967738) (xy 463.849896 -382.956172) (xy 463.839713 -382.9354)
			(xy 463.830924 -382.92786) (xy 463.810113 -382.911141) (xy 463.772985 -382.872782) (xy 463.741567 -382.829623)
			(xy 463.716471 -382.782505) (xy 463.698188 -382.73235) (xy 463.687074 -382.680135) (xy 463.683347 -382.626882)
			(xy 463.687079 -382.573628) (xy 463.698198 -382.521415) (xy 463.716486 -382.471261) (xy 463.741587 -382.424146)
			(xy 463.773009 -382.38099) (xy 463.810141 -382.342634) (xy 463.830924 -382.32588) (xy 463.839695 -382.318327)
			(xy 463.849872 -382.297561) (xy 463.850482 -382.286002) (xy 463.850482 -382.205738) (xy 463.849896 -382.194172)
			(xy 463.839713 -382.1734) (xy 463.830924 -382.16586) (xy 463.808426 -382.147685) (xy 463.768691 -382.105663)
			(xy 463.735753 -382.058125) (xy 463.710367 -382.00616) (xy 463.693114 -381.950959) (xy 463.68439 -381.893787)
			(xy 463.683858 -381.86487) (xy 463.684344 -381.837619) (xy 463.6921 -381.783671) (xy 463.707455 -381.731376)
			(xy 463.730097 -381.681799) (xy 463.759563 -381.635949) (xy 463.795254 -381.594758) (xy 463.836445 -381.559067)
			(xy 463.882295 -381.529601) (xy 463.931872 -381.506959) (xy 463.984167 -381.491604) (xy 464.038115 -381.483848)
			(xy 464.092617 -381.483848) (xy 464.146565 -381.491604) (xy 464.19886 -381.506959) (xy 464.248437 -381.529601)
			(xy 464.294287 -381.559067) (xy 464.335478 -381.594758) (xy 464.371169 -381.635949) (xy 464.400635 -381.681799)
			(xy 464.423277 -381.731376) (xy 464.438632 -381.783671) (xy 464.446388 -381.837619) (xy 464.446874 -381.86487)
			(xy 464.446344 -381.893787) (xy 464.437619 -381.950958) (xy 464.420364 -382.006157) (xy 464.394974 -382.058119)
			(xy 464.362032 -382.105653) (xy 464.322293 -382.14767) (xy 464.299808 -382.16586) (xy 464.29107 -382.173445)
			(xy 464.280873 -382.194186) (xy 464.28025 -382.205738) (xy 464.28025 -382.286002) (xy 464.280802 -382.297573)
			(xy 464.291008 -382.318345) (xy 464.299808 -382.32588) (xy 464.320563 -382.342668) (xy 464.357696 -382.381016)
			(xy 464.38912 -382.424166) (xy 464.414222 -382.471275) (xy 464.432511 -382.521424) (xy 464.443631 -382.573632)
			(xy 464.447363 -382.626882) (xy 464.443636 -382.680131) (xy 464.432521 -382.732341) (xy 464.414237 -382.782491)
			(xy 464.389139 -382.829603) (xy 464.357719 -382.872756) (xy 464.32059 -382.911107) (xy 464.299808 -382.92786)
			(xy 464.29107 -382.935445) (xy 464.280873 -382.956186) (xy 464.28025 -382.967738) (xy 464.28025 -383.048002)
			(xy 464.280802 -383.059573) (xy 464.291008 -383.080345) (xy 464.299808 -383.08788) (xy 464.320563 -383.104668)
			(xy 464.357696 -383.143016) (xy 464.38912 -383.186166) (xy 464.414222 -383.233275) (xy 464.432511 -383.283424)
			(xy 464.443631 -383.335632) (xy 464.447363 -383.388882) (xy 464.443636 -383.442131) (xy 464.432521 -383.494341)
			(xy 464.414237 -383.544491) (xy 464.389139 -383.591603) (xy 464.357719 -383.634756) (xy 464.32059 -383.673107)
			(xy 464.299808 -383.68986) (xy 464.29107 -383.697445) (xy 464.280873 -383.718186) (xy 464.28025 -383.729738)
			(xy 464.28025 -383.810002) (xy 464.280802 -383.821573) (xy 464.291008 -383.842345) (xy 464.299808 -383.84988)
			(xy 464.322284 -383.86808) (xy 464.362019 -383.910098) (xy 464.394959 -383.957631) (xy 464.420348 -384.009591)
			(xy 464.437606 -384.064787) (xy 464.446338 -384.121955) (xy 464.446874 -384.15087) (xy 464.446388 -384.178121)
			(xy 464.438632 -384.232069) (xy 464.423277 -384.284364) (xy 464.400635 -384.333941) (xy 464.371169 -384.379791)
			(xy 464.335478 -384.420982) (xy 464.294287 -384.456673) (xy 464.248437 -384.486139) (xy 464.19886 -384.508781)
			(xy 464.146565 -384.524136) (xy 464.092617 -384.531892) (xy 464.038115 -384.531892) (xy 463.984167 -384.524136)
			(xy 463.931872 -384.508781) (xy 463.882295 -384.486139) (xy 463.836445 -384.456673) (xy 463.795254 -384.420982)
			(xy 463.759563 -384.379791) (xy 463.730097 -384.333941) (xy 463.707455 -384.284364) (xy 463.6921 -384.232069)
			(xy 463.684344 -384.178121) (xy 463.683858 -384.15087) (xy 463.684405 -384.121954) (xy 463.693125 -384.064783)
			(xy 463.710376 -384.009584) (xy 463.735762 -383.957622) (xy 463.768702 -383.910087) (xy 463.80844 -383.86807)
			(xy 463.830924 -383.84988) (xy 463.839695 -383.842327) (xy 463.849872 -383.821561) (xy 463.850482 -383.810002)
			(xy 463.850482 -383.729738) (xy 463.849896 -383.718172) (xy 463.839713 -383.6974) (xy 463.830924 -383.68986)
			(xy 463.810113 -383.673141) (xy 463.772985 -383.634782) (xy 463.741567 -383.591623) (xy 463.716471 -383.544505)
			(xy 463.698188 -383.49435) (xy 463.687074 -383.442135) (xy 463.683347 -383.388882) (xy 460.637363 -383.388882)
			(xy 460.633636 -383.442131) (xy 460.622521 -383.494341) (xy 460.604237 -383.544491) (xy 460.579139 -383.591603)
			(xy 460.547719 -383.634756) (xy 460.51059 -383.673107) (xy 460.489808 -383.68986) (xy 460.48107 -383.697445)
			(xy 460.470873 -383.718186) (xy 460.47025 -383.729738) (xy 460.47025 -383.810002) (xy 460.470802 -383.821573)
			(xy 460.481008 -383.842345) (xy 460.489808 -383.84988) (xy 460.512284 -383.86808) (xy 460.552019 -383.910098)
			(xy 460.584959 -383.957631) (xy 460.610348 -384.009591) (xy 460.627606 -384.064787) (xy 460.636338 -384.121955)
			(xy 460.636874 -384.15087) (xy 460.636388 -384.178121) (xy 460.628632 -384.232069) (xy 460.613277 -384.284364)
			(xy 460.590635 -384.333941) (xy 460.561169 -384.379791) (xy 460.525478 -384.420982) (xy 460.484287 -384.456673)
			(xy 460.438437 -384.486139) (xy 460.38886 -384.508781) (xy 460.336565 -384.524136) (xy 460.282617 -384.531892)
			(xy 460.228115 -384.531892) (xy 460.174167 -384.524136) (xy 460.121872 -384.508781) (xy 460.072295 -384.486139)
			(xy 460.026445 -384.456673) (xy 459.985254 -384.420982) (xy 459.949563 -384.379791) (xy 459.920097 -384.333941)
			(xy 459.897455 -384.284364) (xy 459.8821 -384.232069) (xy 459.874344 -384.178121) (xy 459.873858 -384.15087)
			(xy 459.874405 -384.121954) (xy 459.883125 -384.064783) (xy 459.900376 -384.009584) (xy 459.925762 -383.957622)
			(xy 459.958702 -383.910087) (xy 459.99844 -383.86807) (xy 460.020924 -383.84988) (xy 460.029695 -383.842327)
			(xy 460.039872 -383.821561) (xy 460.040482 -383.810002) (xy 460.040482 -383.729738) (xy 460.039896 -383.718172)
			(xy 460.029713 -383.6974) (xy 460.020924 -383.68986) (xy 460.000113 -383.673141) (xy 459.962985 -383.634782)
			(xy 459.931567 -383.591623) (xy 459.906471 -383.544505) (xy 459.888188 -383.49435) (xy 459.877074 -383.442135)
			(xy 459.873347 -383.388882) (xy 458.351363 -383.388882) (xy 458.347636 -383.442131) (xy 458.336521 -383.494341)
			(xy 458.318237 -383.544491) (xy 458.293139 -383.591603) (xy 458.261719 -383.634756) (xy 458.22459 -383.673107)
			(xy 458.203808 -383.68986) (xy 458.19507 -383.697445) (xy 458.184873 -383.718186) (xy 458.18425 -383.729738)
			(xy 458.18425 -383.810002) (xy 458.184802 -383.821573) (xy 458.195008 -383.842345) (xy 458.203808 -383.84988)
			(xy 458.226284 -383.86808) (xy 458.266019 -383.910098) (xy 458.298959 -383.957631) (xy 458.324348 -384.009591)
			(xy 458.341606 -384.064787) (xy 458.350338 -384.121955) (xy 458.350874 -384.15087) (xy 458.350388 -384.178121)
			(xy 458.342632 -384.232069) (xy 458.327277 -384.284364) (xy 458.304635 -384.333941) (xy 458.275169 -384.379791)
			(xy 458.239478 -384.420982) (xy 458.198287 -384.456673) (xy 458.152437 -384.486139) (xy 458.10286 -384.508781)
			(xy 458.050565 -384.524136) (xy 457.996617 -384.531892) (xy 457.942115 -384.531892) (xy 457.888167 -384.524136)
			(xy 457.835872 -384.508781) (xy 457.786295 -384.486139) (xy 457.740445 -384.456673) (xy 457.699254 -384.420982)
			(xy 457.663563 -384.379791) (xy 457.634097 -384.333941) (xy 457.611455 -384.284364) (xy 457.5961 -384.232069)
			(xy 457.588344 -384.178121) (xy 457.587858 -384.15087) (xy 457.588405 -384.121954) (xy 457.597125 -384.064783)
			(xy 457.614376 -384.009584) (xy 457.639762 -383.957622) (xy 457.672702 -383.910087) (xy 457.71244 -383.86807)
			(xy 457.734924 -383.84988) (xy 457.743695 -383.842327) (xy 457.753872 -383.821561) (xy 457.754482 -383.810002)
			(xy 457.754482 -383.729738) (xy 457.753896 -383.718172) (xy 457.743713 -383.6974) (xy 457.734924 -383.68986)
			(xy 457.714113 -383.673141) (xy 457.676985 -383.634782) (xy 457.645567 -383.591623) (xy 457.620471 -383.544505)
			(xy 457.602188 -383.49435) (xy 457.591074 -383.442135) (xy 457.587347 -383.388882) (xy 454.541363 -383.388882)
			(xy 454.537636 -383.442131) (xy 454.526521 -383.494341) (xy 454.508237 -383.544491) (xy 454.483139 -383.591603)
			(xy 454.451719 -383.634756) (xy 454.41459 -383.673107) (xy 454.393808 -383.68986) (xy 454.38507 -383.697445)
			(xy 454.374873 -383.718186) (xy 454.37425 -383.729738) (xy 454.37425 -383.810002) (xy 454.374802 -383.821573)
			(xy 454.385008 -383.842345) (xy 454.393808 -383.84988) (xy 454.416284 -383.86808) (xy 454.456019 -383.910098)
			(xy 454.488959 -383.957631) (xy 454.514348 -384.009591) (xy 454.531606 -384.064787) (xy 454.540338 -384.121955)
			(xy 454.540874 -384.15087) (xy 454.540388 -384.178121) (xy 454.532632 -384.232069) (xy 454.517277 -384.284364)
			(xy 454.494635 -384.333941) (xy 454.465169 -384.379791) (xy 454.429478 -384.420982) (xy 454.388287 -384.456673)
			(xy 454.342437 -384.486139) (xy 454.29286 -384.508781) (xy 454.240565 -384.524136) (xy 454.186617 -384.531892)
			(xy 454.132115 -384.531892) (xy 454.078167 -384.524136) (xy 454.025872 -384.508781) (xy 453.976295 -384.486139)
			(xy 453.930445 -384.456673) (xy 453.889254 -384.420982) (xy 453.853563 -384.379791) (xy 453.824097 -384.333941)
			(xy 453.801455 -384.284364) (xy 453.7861 -384.232069) (xy 453.778344 -384.178121) (xy 453.777858 -384.15087)
			(xy 453.778405 -384.121954) (xy 453.787125 -384.064783) (xy 453.804376 -384.009584) (xy 453.829762 -383.957622)
			(xy 453.862702 -383.910087) (xy 453.90244 -383.86807) (xy 453.924924 -383.84988) (xy 453.933695 -383.842327)
			(xy 453.943872 -383.821561) (xy 453.944482 -383.810002) (xy 453.944482 -383.729738) (xy 453.943896 -383.718172)
			(xy 453.933713 -383.6974) (xy 453.924924 -383.68986) (xy 453.904113 -383.673141) (xy 453.866985 -383.634782)
			(xy 453.835567 -383.591623) (xy 453.810471 -383.544505) (xy 453.792188 -383.49435) (xy 453.781074 -383.442135)
			(xy 453.777347 -383.388882) (xy 452.255363 -383.388882) (xy 452.251636 -383.442131) (xy 452.240521 -383.494341)
			(xy 452.222237 -383.544491) (xy 452.197139 -383.591603) (xy 452.165719 -383.634756) (xy 452.12859 -383.673107)
			(xy 452.107808 -383.68986) (xy 452.09907 -383.697445) (xy 452.088873 -383.718186) (xy 452.08825 -383.729738)
			(xy 452.08825 -383.810002) (xy 452.088802 -383.821573) (xy 452.099008 -383.842345) (xy 452.107808 -383.84988)
			(xy 452.130284 -383.86808) (xy 452.170019 -383.910098) (xy 452.202959 -383.957631) (xy 452.228348 -384.009591)
			(xy 452.245606 -384.064787) (xy 452.254338 -384.121955) (xy 452.254874 -384.15087) (xy 452.254388 -384.178121)
			(xy 452.246632 -384.232069) (xy 452.231277 -384.284364) (xy 452.208635 -384.333941) (xy 452.179169 -384.379791)
			(xy 452.143478 -384.420982) (xy 452.102287 -384.456673) (xy 452.056437 -384.486139) (xy 452.00686 -384.508781)
			(xy 451.954565 -384.524136) (xy 451.900617 -384.531892) (xy 451.846115 -384.531892) (xy 451.792167 -384.524136)
			(xy 451.739872 -384.508781) (xy 451.690295 -384.486139) (xy 451.644445 -384.456673) (xy 451.603254 -384.420982)
			(xy 451.567563 -384.379791) (xy 451.538097 -384.333941) (xy 451.515455 -384.284364) (xy 451.5001 -384.232069)
			(xy 451.492344 -384.178121) (xy 451.491858 -384.15087) (xy 451.492405 -384.121954) (xy 451.501125 -384.064783)
			(xy 451.518376 -384.009584) (xy 451.543762 -383.957622) (xy 451.576702 -383.910087) (xy 451.61644 -383.86807)
			(xy 451.638924 -383.84988) (xy 451.647695 -383.842327) (xy 451.657872 -383.821561) (xy 451.658482 -383.810002)
			(xy 451.658482 -383.729738) (xy 451.657896 -383.718172) (xy 451.647713 -383.6974) (xy 451.638924 -383.68986)
			(xy 451.618113 -383.673141) (xy 451.580985 -383.634782) (xy 451.549567 -383.591623) (xy 451.524471 -383.544505)
			(xy 451.506188 -383.49435) (xy 451.495074 -383.442135) (xy 451.491347 -383.388882) (xy 448.445363 -383.388882)
			(xy 448.441636 -383.442131) (xy 448.430521 -383.494341) (xy 448.412237 -383.544491) (xy 448.387139 -383.591603)
			(xy 448.355719 -383.634756) (xy 448.31859 -383.673107) (xy 448.297808 -383.68986) (xy 448.28907 -383.697445)
			(xy 448.278873 -383.718186) (xy 448.27825 -383.729738) (xy 448.27825 -383.810002) (xy 448.278802 -383.821573)
			(xy 448.289008 -383.842345) (xy 448.297808 -383.84988) (xy 448.320284 -383.86808) (xy 448.360019 -383.910098)
			(xy 448.392959 -383.957631) (xy 448.418348 -384.009591) (xy 448.435606 -384.064787) (xy 448.444338 -384.121955)
			(xy 448.444874 -384.15087) (xy 448.444388 -384.178121) (xy 448.436632 -384.232069) (xy 448.421277 -384.284364)
			(xy 448.398635 -384.333941) (xy 448.369169 -384.379791) (xy 448.333478 -384.420982) (xy 448.292287 -384.456673)
			(xy 448.246437 -384.486139) (xy 448.19686 -384.508781) (xy 448.144565 -384.524136) (xy 448.090617 -384.531892)
			(xy 448.036115 -384.531892) (xy 447.982167 -384.524136) (xy 447.929872 -384.508781) (xy 447.880295 -384.486139)
			(xy 447.834445 -384.456673) (xy 447.793254 -384.420982) (xy 447.757563 -384.379791) (xy 447.728097 -384.333941)
			(xy 447.705455 -384.284364) (xy 447.6901 -384.232069) (xy 447.682344 -384.178121) (xy 447.681858 -384.15087)
			(xy 447.682405 -384.121954) (xy 447.691125 -384.064783) (xy 447.708376 -384.009584) (xy 447.733762 -383.957622)
			(xy 447.766702 -383.910087) (xy 447.80644 -383.86807) (xy 447.828924 -383.84988) (xy 447.837695 -383.842327)
			(xy 447.847872 -383.821561) (xy 447.848482 -383.810002) (xy 447.848482 -383.729738) (xy 447.847896 -383.718172)
			(xy 447.837713 -383.6974) (xy 447.828924 -383.68986) (xy 447.808113 -383.673141) (xy 447.770985 -383.634782)
			(xy 447.739567 -383.591623) (xy 447.714471 -383.544505) (xy 447.696188 -383.49435) (xy 447.685074 -383.442135)
			(xy 447.681347 -383.388882) (xy 446.489563 -383.388882) (xy 446.485836 -383.442131) (xy 446.474721 -383.494341)
			(xy 446.456437 -383.544491) (xy 446.431339 -383.591603) (xy 446.399919 -383.634756) (xy 446.36279 -383.673107)
			(xy 446.342008 -383.68986) (xy 446.33327 -383.697445) (xy 446.323073 -383.718186) (xy 446.32245 -383.729738)
			(xy 446.32245 -383.810002) (xy 446.323002 -383.821573) (xy 446.333208 -383.842345) (xy 446.342008 -383.84988)
			(xy 446.364484 -383.86808) (xy 446.404219 -383.910098) (xy 446.437159 -383.957631) (xy 446.462548 -384.009591)
			(xy 446.479806 -384.064787) (xy 446.488538 -384.121955) (xy 446.489074 -384.15087) (xy 446.488588 -384.178121)
			(xy 446.480832 -384.232069) (xy 446.465477 -384.284364) (xy 446.442835 -384.333941) (xy 446.413369 -384.379791)
			(xy 446.377678 -384.420982) (xy 446.336487 -384.456673) (xy 446.290637 -384.486139) (xy 446.24106 -384.508781)
			(xy 446.188765 -384.524136) (xy 446.134817 -384.531892) (xy 446.080315 -384.531892) (xy 446.026367 -384.524136)
			(xy 445.974072 -384.508781) (xy 445.924495 -384.486139) (xy 445.878645 -384.456673) (xy 445.837454 -384.420982)
			(xy 445.801763 -384.379791) (xy 445.772297 -384.333941) (xy 445.749655 -384.284364) (xy 445.7343 -384.232069)
			(xy 445.726544 -384.178121) (xy 445.726058 -384.15087) (xy 445.726605 -384.121954) (xy 445.735325 -384.064783)
			(xy 445.752576 -384.009584) (xy 445.777962 -383.957622) (xy 445.810902 -383.910087) (xy 445.85064 -383.86807)
			(xy 445.873124 -383.84988) (xy 445.881895 -383.842327) (xy 445.892072 -383.821561) (xy 445.892682 -383.810002)
			(xy 445.892682 -383.729738) (xy 445.892096 -383.718172) (xy 445.881913 -383.6974) (xy 445.873124 -383.68986)
			(xy 445.852313 -383.673141) (xy 445.815185 -383.634782) (xy 445.783767 -383.591623) (xy 445.758671 -383.544505)
			(xy 445.740388 -383.49435) (xy 445.729274 -383.442135) (xy 445.725547 -383.388882) (xy 442.679563 -383.388882)
			(xy 442.675836 -383.442131) (xy 442.664721 -383.494341) (xy 442.646437 -383.544491) (xy 442.621339 -383.591603)
			(xy 442.589919 -383.634756) (xy 442.55279 -383.673107) (xy 442.532008 -383.68986) (xy 442.52327 -383.697445)
			(xy 442.513073 -383.718186) (xy 442.51245 -383.729738) (xy 442.51245 -383.810002) (xy 442.513002 -383.821573)
			(xy 442.523208 -383.842345) (xy 442.532008 -383.84988) (xy 442.554484 -383.86808) (xy 442.594219 -383.910098)
			(xy 442.627159 -383.957631) (xy 442.652548 -384.009591) (xy 442.669806 -384.064787) (xy 442.678538 -384.121955)
			(xy 442.679074 -384.15087) (xy 442.678588 -384.178121) (xy 442.670832 -384.232069) (xy 442.655477 -384.284364)
			(xy 442.632835 -384.333941) (xy 442.603369 -384.379791) (xy 442.567678 -384.420982) (xy 442.526487 -384.456673)
			(xy 442.480637 -384.486139) (xy 442.43106 -384.508781) (xy 442.378765 -384.524136) (xy 442.324817 -384.531892)
			(xy 442.270315 -384.531892) (xy 442.216367 -384.524136) (xy 442.164072 -384.508781) (xy 442.114495 -384.486139)
			(xy 442.068645 -384.456673) (xy 442.027454 -384.420982) (xy 441.991763 -384.379791) (xy 441.962297 -384.333941)
			(xy 441.939655 -384.284364) (xy 441.9243 -384.232069) (xy 441.916544 -384.178121) (xy 441.916058 -384.15087)
			(xy 441.916605 -384.121954) (xy 441.925325 -384.064783) (xy 441.942576 -384.009584) (xy 441.967962 -383.957622)
			(xy 442.000902 -383.910087) (xy 442.04064 -383.86807) (xy 442.063124 -383.84988) (xy 442.071895 -383.842327)
			(xy 442.082072 -383.821561) (xy 442.082682 -383.810002) (xy 442.082682 -383.729738) (xy 442.082096 -383.718172)
			(xy 442.071913 -383.6974) (xy 442.063124 -383.68986) (xy 442.042313 -383.673141) (xy 442.005185 -383.634782)
			(xy 441.973767 -383.591623) (xy 441.948671 -383.544505) (xy 441.930388 -383.49435) (xy 441.919274 -383.442135)
			(xy 441.915547 -383.388882) (xy 441.10148 -383.388882) (xy 441.10148 -385.039108) (xy 447.973196 -385.039108)
			(xy 447.973663 -385.011855) (xy 447.981419 -384.957904) (xy 447.996774 -384.905606) (xy 448.019416 -384.856026)
			(xy 448.048883 -384.810172) (xy 448.084577 -384.76898) (xy 448.125769 -384.733286) (xy 448.171622 -384.703818)
			(xy 448.221202 -384.681175) (xy 448.2735 -384.66582) (xy 448.327451 -384.658063) (xy 448.354704 -384.6576)
			(xy 448.383621 -384.658116) (xy 448.440792 -384.666845) (xy 448.495991 -384.684104) (xy 448.547953 -384.709496)
			(xy 448.595487 -384.74244) (xy 448.637504 -384.782181) (xy 448.655694 -384.804666) (xy 448.663251 -384.813432)
			(xy 448.684014 -384.82361) (xy 448.695572 -384.824224) (xy 448.775836 -384.824224) (xy 448.787403 -384.823643)
			(xy 448.808176 -384.813459) (xy 448.815714 -384.804666) (xy 448.833889 -384.782169) (xy 448.875913 -384.742436)
			(xy 448.923451 -384.7095) (xy 448.975416 -384.684114) (xy 449.030616 -384.66686) (xy 449.087787 -384.658134)
			(xy 449.116704 -384.6576) (xy 449.145443 -384.658121) (xy 449.20227 -384.666744) (xy 449.257161 -384.683795)
			(xy 449.308873 -384.708887) (xy 449.356235 -384.741453) (xy 449.377562 -384.760724) (xy 449.384674 -384.767328)
			(xy 449.4022 -384.77444) (xy 449.491608 -384.77444) (xy 449.509134 -384.767328) (xy 449.516246 -384.760724)
			(xy 449.537569 -384.741449) (xy 449.584933 -384.708884) (xy 449.636645 -384.683792) (xy 449.691537 -384.666743)
			(xy 449.748365 -384.658121) (xy 449.777104 -384.6576) (xy 449.804357 -384.658052) (xy 449.858309 -384.665809)
			(xy 449.910608 -384.681166) (xy 449.960188 -384.70381) (xy 450.006042 -384.733279) (xy 450.047235 -384.768974)
			(xy 450.082928 -384.810168) (xy 450.112396 -384.856022) (xy 450.135038 -384.905604) (xy 450.150393 -384.957903)
			(xy 450.158149 -385.011855) (xy 450.158612 -385.039108) (xy 450.158178 -385.06581) (xy 450.150724 -385.11869)
			(xy 450.135962 -385.170013) (xy 450.114183 -385.218773) (xy 450.085811 -385.264017) (xy 450.06895 -385.284726)
			(xy 450.062854 -385.292092) (xy 450.056758 -385.310126) (xy 450.060568 -385.397756) (xy 450.068188 -385.415282)
			(xy 450.074792 -385.421886) (xy 450.095606 -385.443472) (xy 450.130859 -385.491977) (xy 450.158087 -385.545401)
			(xy 450.176618 -385.602428) (xy 450.185997 -385.661653) (xy 450.186552 -385.691634) (xy 450.186008 -385.720693)
			(xy 450.177172 -385.778134) (xy 450.159725 -385.833571) (xy 450.134071 -385.88572) (xy 450.100803 -385.933374)
			(xy 450.081142 -385.954778) (xy 450.074538 -385.96189) (xy 450.067172 -385.979924) (xy 450.067172 -386.06984)
			(xy 450.074538 -386.087874) (xy 450.081142 -386.094986) (xy 450.100804 -386.116391) (xy 450.134085 -386.164037)
			(xy 450.159743 -386.216185) (xy 450.177186 -386.271625) (xy 450.186007 -386.329071) (xy 450.186552 -386.35813)
			(xy 450.186034 -386.386232) (xy 450.18508 -386.392674) (xy 450.3547 -386.392674) (xy 450.355208 -386.363935)
			(xy 450.363834 -386.307106) (xy 450.380888 -386.252216) (xy 450.405983 -386.200504) (xy 450.438552 -386.153142)
			(xy 450.457824 -386.131816) (xy 450.464428 -386.124704) (xy 450.47154 -386.107178) (xy 450.47154 -386.01777)
			(xy 450.464428 -386.000244) (xy 450.457824 -385.993132) (xy 450.438527 -385.971828) (xy 450.405963 -385.924461)
			(xy 450.380873 -385.872746) (xy 450.363825 -385.817852) (xy 450.355205 -385.761021) (xy 450.355207 -385.703541)
			(xy 450.363833 -385.646711) (xy 450.380887 -385.591819) (xy 450.405982 -385.540106) (xy 450.438551 -385.492743)
			(xy 450.457824 -385.471416) (xy 450.464428 -385.464304) (xy 450.47154 -385.446778) (xy 450.47154 -385.35737)
			(xy 450.464428 -385.339844) (xy 450.457824 -385.332732) (xy 450.438539 -385.311418) (xy 450.405975 -385.264052)
			(xy 450.380885 -385.212337) (xy 450.363838 -385.157444) (xy 450.355219 -385.100614) (xy 450.3547 -385.071874)
			(xy 450.355154 -385.044622) (xy 450.362914 -384.990672) (xy 450.378273 -384.938377) (xy 450.400917 -384.888799)
			(xy 450.430387 -384.842948) (xy 450.466082 -384.801758) (xy 450.507275 -384.766067) (xy 450.553129 -384.736601)
			(xy 450.602709 -384.713961) (xy 450.655006 -384.698607) (xy 450.708956 -384.690851) (xy 450.736208 -384.690366)
			(xy 450.764947 -384.690894) (xy 450.821773 -384.699517) (xy 450.876664 -384.716566) (xy 450.928376 -384.741657)
			(xy 450.975739 -384.77422) (xy 450.997066 -384.79349) (xy 451.004178 -384.800094) (xy 451.021704 -384.807206)
			(xy 451.111112 -384.807206) (xy 451.128638 -384.800094) (xy 451.13575 -384.79349) (xy 451.157082 -384.774224)
			(xy 451.204442 -384.741656) (xy 451.256152 -384.716561) (xy 451.311042 -384.69951) (xy 451.367869 -384.690887)
			(xy 451.396608 -384.690366) (xy 451.42367 -384.690813) (xy 451.477248 -384.69848) (xy 451.529203 -384.713646)
			(xy 451.578493 -384.736004) (xy 451.624126 -384.765107) (xy 451.665187 -384.800369) (xy 451.683374 -384.820414)
			(xy 451.690944 -384.828277) (xy 451.710823 -384.83723) (xy 451.721728 -384.837686) (xy 451.797928 -384.837686)
			(xy 451.808828 -384.83722) (xy 451.828698 -384.828258) (xy 451.836282 -384.820414) (xy 451.854456 -384.800357)
			(xy 451.895516 -384.765093) (xy 451.941151 -384.735992) (xy 451.990445 -384.71364) (xy 452.042405 -384.698487)
			(xy 452.095986 -384.690836) (xy 452.123048 -384.690366) (xy 452.150299 -384.690833) (xy 452.204246 -384.698595)
			(xy 452.25654 -384.713955) (xy 452.306115 -384.7366) (xy 452.351964 -384.766069) (xy 452.393153 -384.801762)
			(xy 452.428844 -384.842953) (xy 452.45831 -384.888804) (xy 452.480952 -384.938381) (xy 452.496309 -384.990675)
			(xy 452.504068 -385.044623) (xy 452.504556 -385.071874) (xy 452.504001 -385.100612) (xy 452.495384 -385.157437)
			(xy 452.47834 -385.212327) (xy 452.453256 -385.264039) (xy 452.420699 -385.311403) (xy 452.401432 -385.332732)
			(xy 452.394828 -385.339844) (xy 452.387716 -385.35737) (xy 452.387716 -385.446778) (xy 452.394828 -385.464304)
			(xy 452.401432 -385.471416) (xy 452.420675 -385.492766) (xy 452.453236 -385.540126) (xy 452.478325 -385.591835)
			(xy 452.495374 -385.646721) (xy 452.503998 -385.703544) (xy 452.504001 -385.761018) (xy 452.495383 -385.817842)
			(xy 452.478339 -385.87273) (xy 452.453255 -385.924441) (xy 452.420698 -385.971804) (xy 452.401432 -385.993132)
			(xy 452.394828 -386.000244) (xy 452.387716 -386.01777) (xy 452.387716 -386.107178) (xy 452.394828 -386.124704)
			(xy 452.401432 -386.131816) (xy 452.420675 -386.153166) (xy 452.453236 -386.200526) (xy 452.478325 -386.252235)
			(xy 452.495374 -386.307121) (xy 452.503998 -386.363944) (xy 452.504001 -386.421418) (xy 452.495383 -386.478242)
			(xy 452.478339 -386.53313) (xy 452.453255 -386.584841) (xy 452.420698 -386.632204) (xy 452.401432 -386.653532)
			(xy 452.394574 -386.660898) (xy 452.387716 -386.678678) (xy 452.388478 -386.768848) (xy 452.395844 -386.786882)
			(xy 452.402956 -386.793994) (xy 452.423192 -386.815485) (xy 452.457414 -386.86358) (xy 452.48382 -386.916372)
			(xy 452.50178 -386.972601) (xy 452.510866 -387.030926) (xy 452.511414 -387.06044) (xy 452.510909 -387.087809)
			(xy 452.5031 -387.141986) (xy 452.48762 -387.194489) (xy 452.464787 -387.244236) (xy 452.435071 -387.290205)
			(xy 452.417434 -387.311138) (xy 452.411338 -387.31825) (xy 452.404988 -387.335268) (xy 452.404988 -387.420612)
			(xy 452.411338 -387.43763) (xy 452.417434 -387.444742) (xy 452.435065 -387.465681) (xy 452.464777 -387.511652)
			(xy 452.487614 -387.561398) (xy 452.503107 -387.613897) (xy 452.503953 -387.619748) (xy 455.361802 -387.619748)
			(xy 455.362294 -387.591008) (xy 455.370924 -387.534179) (xy 455.387981 -387.479288) (xy 455.41308 -387.427577)
			(xy 455.445652 -387.380216) (xy 455.464926 -387.35889) (xy 455.47153 -387.351778) (xy 455.478642 -387.334252)
			(xy 455.478642 -387.244844) (xy 455.47153 -387.227318) (xy 455.464926 -387.220206) (xy 455.445703 -387.198838)
			(xy 455.413136 -387.151483) (xy 455.388041 -387.099778) (xy 455.370988 -387.044893) (xy 455.362361 -386.988071)
			(xy 455.362355 -386.930599) (xy 455.370972 -386.873775) (xy 455.388016 -386.818888) (xy 455.4131 -386.767178)
			(xy 455.445659 -386.719817) (xy 455.464926 -386.69849) (xy 455.47153 -386.691378) (xy 455.478642 -386.673852)
			(xy 455.478642 -386.584444) (xy 455.47153 -386.566918) (xy 455.464926 -386.559806) (xy 455.445703 -386.538438)
			(xy 455.413136 -386.491083) (xy 455.388041 -386.439378) (xy 455.370988 -386.384493) (xy 455.362361 -386.327671)
			(xy 455.362355 -386.270199) (xy 455.370972 -386.213375) (xy 455.388016 -386.158488) (xy 455.4131 -386.106778)
			(xy 455.445659 -386.059417) (xy 455.464926 -386.03809) (xy 455.47153 -386.030978) (xy 455.478642 -386.013452)
			(xy 455.478642 -385.924044) (xy 455.47153 -385.906518) (xy 455.464926 -385.899406) (xy 455.445629 -385.878102)
			(xy 455.413066 -385.830734) (xy 455.387979 -385.779016) (xy 455.370935 -385.72412) (xy 455.362319 -385.667289)
			(xy 455.361802 -385.638548) (xy 455.3623 -385.611296) (xy 455.370051 -385.557346) (xy 455.385401 -385.505048)
			(xy 455.408039 -385.455467) (xy 455.437503 -385.409613) (xy 455.473193 -385.36842) (xy 455.514383 -385.332725)
			(xy 455.560234 -385.303257) (xy 455.609812 -385.280614) (xy 455.662108 -385.265259) (xy 455.716058 -385.257503)
			(xy 455.74331 -385.25704) (xy 455.769625 -385.257509) (xy 455.821757 -385.264732) (xy 455.8724 -385.279054)
			(xy 455.920594 -385.300203) (xy 455.965422 -385.327778) (xy 456.006034 -385.361253) (xy 456.041657 -385.399994)
			(xy 456.057 -385.421378) (xy 456.064112 -385.431538) (xy 456.085448 -385.442968) (xy 456.193144 -385.444492)
			(xy 456.214988 -385.43357) (xy 456.222354 -385.423664) (xy 456.240463 -385.399945) (xy 456.2828 -385.357892)
			(xy 456.33117 -385.322946) (xy 456.384392 -385.295959) (xy 456.441168 -385.277591) (xy 456.500112 -385.26829)
			(xy 456.529948 -385.267708) (xy 456.557716 -385.26821) (xy 456.612668 -385.276252) (xy 456.665873 -385.292172)
			(xy 456.71621 -385.315634) (xy 456.762615 -385.346145) (xy 456.783694 -385.364228) (xy 456.790552 -385.370324)
			(xy 456.807824 -385.377182) (xy 456.89393 -385.377436) (xy 456.911202 -385.370832) (xy 456.918314 -385.364736)
			(xy 456.939286 -385.346929) (xy 456.985399 -385.316922) (xy 457.035341 -385.293845) (xy 457.088079 -385.278176)
			(xy 457.14252 -385.27024) (xy 457.170028 -385.26974) (xy 457.197284 -385.270129) (xy 457.25124 -385.277891)
			(xy 457.303542 -385.293253) (xy 457.353126 -385.315902) (xy 457.398981 -385.345378) (xy 457.440175 -385.381079)
			(xy 457.475868 -385.42228) (xy 457.505334 -385.468141) (xy 457.527974 -385.517729) (xy 457.543325 -385.570034)
			(xy 457.551076 -385.623992) (xy 457.551536 -385.651248) (xy 457.551032 -385.679988) (xy 457.542403 -385.736815)
			(xy 457.525348 -385.791706) (xy 457.500252 -385.843417) (xy 457.467684 -385.890779) (xy 457.448412 -385.912106)
			(xy 457.441808 -385.919218) (xy 457.434696 -385.936744) (xy 457.434696 -386.026152) (xy 457.441808 -386.043678)
			(xy 457.448412 -386.05079) (xy 457.467729 -386.072076) (xy 457.500289 -386.119447) (xy 457.525376 -386.171165)
			(xy 457.542421 -386.226062) (xy 457.551038 -386.282894) (xy 457.551033 -386.340376) (xy 457.542405 -386.397206)
			(xy 457.52535 -386.4521) (xy 457.500254 -386.503814) (xy 457.467685 -386.551178) (xy 457.448412 -386.572506)
			(xy 457.441808 -386.579618) (xy 457.434696 -386.597144) (xy 457.434696 -386.686552) (xy 457.441808 -386.704078)
			(xy 457.448412 -386.71119) (xy 457.467729 -386.732476) (xy 457.500289 -386.779847) (xy 457.525376 -386.831565)
			(xy 457.542421 -386.886462) (xy 457.551038 -386.943294) (xy 457.551033 -387.000776) (xy 457.542405 -387.057606)
			(xy 457.52535 -387.1125) (xy 457.500254 -387.164214) (xy 457.467685 -387.211578) (xy 457.448412 -387.232906)
			(xy 457.441808 -387.240018) (xy 457.434696 -387.257544) (xy 457.434696 -387.258347) (xy 458.670706 -387.258347)
			(xy 458.670706 -387.203853) (xy 458.678461 -387.149912) (xy 458.693813 -387.097625) (xy 458.716449 -387.048054)
			(xy 458.74591 -387.002209) (xy 458.781594 -386.961023) (xy 458.822777 -386.925334) (xy 458.868619 -386.895869)
			(xy 458.918187 -386.873227) (xy 458.970473 -386.857869) (xy 459.024413 -386.850109) (xy 459.05166 -386.84962)
			(xy 459.080399 -386.850129) (xy 459.137226 -386.858758) (xy 459.192116 -386.875813) (xy 459.243828 -386.900907)
			(xy 459.291191 -386.933473) (xy 459.312518 -386.952744) (xy 459.31963 -386.959348) (xy 459.337156 -386.96646)
			(xy 459.426564 -386.96646) (xy 459.44409 -386.959348) (xy 459.451202 -386.952744) (xy 459.472546 -386.933493)
			(xy 459.519904 -386.900924) (xy 459.571611 -386.875828) (xy 459.626498 -386.858772) (xy 459.683322 -386.850144)
			(xy 459.71206 -386.84962) (xy 459.739317 -386.850024) (xy 459.793276 -386.857777) (xy 459.845583 -386.873131)
			(xy 459.895171 -386.895773) (xy 459.941033 -386.925242) (xy 459.982234 -386.960938) (xy 460.017934 -387.002135)
			(xy 460.047408 -387.047993) (xy 460.070055 -387.09758) (xy 460.085414 -387.149885) (xy 460.093173 -387.203843)
			(xy 460.093173 -387.258357) (xy 460.087696 -387.296447) (xy 460.851306 -387.296447) (xy 460.851306 -387.241953)
			(xy 460.859061 -387.188014) (xy 460.874412 -387.135727) (xy 460.897048 -387.086157) (xy 460.926507 -387.040312)
			(xy 460.962191 -386.999126) (xy 461.003372 -386.963437) (xy 461.049213 -386.933972) (xy 461.09878 -386.91133)
			(xy 461.151065 -386.895971) (xy 461.205003 -386.88821) (xy 461.23225 -386.88772) (xy 461.260989 -386.888235)
			(xy 461.317816 -386.896863) (xy 461.372706 -386.913916) (xy 461.424417 -386.939009) (xy 461.47178 -386.971574)
			(xy 461.493108 -386.990844) (xy 461.50022 -386.997448) (xy 461.517746 -387.00456) (xy 461.607154 -387.00456)
			(xy 461.62468 -386.997448) (xy 461.631792 -386.990844) (xy 461.653099 -386.971551) (xy 461.700467 -386.938987)
			(xy 461.752183 -386.913899) (xy 461.807078 -386.896854) (xy 461.86391 -386.888237) (xy 461.89265 -386.88772)
			(xy 461.919907 -386.888124) (xy 461.973868 -386.895875) (xy 462.026175 -386.911228) (xy 462.075765 -386.933869)
			(xy 462.121628 -386.963338) (xy 462.16283 -386.999035) (xy 462.198532 -387.040232) (xy 462.228007 -387.086091)
			(xy 462.250654 -387.135678) (xy 462.266014 -387.187983) (xy 462.273773 -387.241943) (xy 462.273773 -387.296457)
			(xy 462.266014 -387.350416) (xy 462.255395 -387.386576) (xy 462.824828 -387.386576) (xy 462.828899 -387.330954)
			(xy 462.841025 -387.276517) (xy 462.860948 -387.224426) (xy 462.888244 -387.175791) (xy 462.92233 -387.131648)
			(xy 462.962479 -387.092939) (xy 463.007837 -387.060488) (xy 463.057437 -387.034987) (xy 463.110221 -387.01698)
			(xy 463.165064 -387.00685) (xy 463.220798 -387.004813) (xy 463.276235 -387.010913) (xy 463.330192 -387.025019)
			(xy 463.381521 -387.046831) (xy 463.429127 -387.075885) (xy 463.471995 -387.11156) (xy 463.509212 -387.153097)
			(xy 463.539985 -387.19961) (xy 463.563657 -387.250107) (xy 463.579725 -387.303514) (xy 463.587845 -387.35869)
			(xy 463.588354 -387.386576) (xy 463.587845 -387.414462) (xy 463.579725 -387.469638) (xy 463.563657 -387.523045)
			(xy 463.539985 -387.573542) (xy 463.509212 -387.620055) (xy 463.471995 -387.661592) (xy 463.429127 -387.697267)
			(xy 463.381521 -387.726321) (xy 463.330192 -387.748133) (xy 463.276235 -387.762239) (xy 463.220798 -387.768339)
			(xy 463.165064 -387.766302) (xy 463.110221 -387.756172) (xy 463.057437 -387.738165) (xy 463.007837 -387.712664)
			(xy 462.962479 -387.680213) (xy 462.92233 -387.641504) (xy 462.888244 -387.597361) (xy 462.860948 -387.548726)
			(xy 462.841025 -387.496635) (xy 462.828899 -387.442198) (xy 462.824828 -387.386576) (xy 462.255395 -387.386576)
			(xy 462.250654 -387.402722) (xy 462.228007 -387.452309) (xy 462.198532 -387.498168) (xy 462.16283 -387.539365)
			(xy 462.121628 -387.575062) (xy 462.075765 -387.604531) (xy 462.026175 -387.627172) (xy 461.973868 -387.642525)
			(xy 461.919907 -387.650276) (xy 461.89265 -387.650736) (xy 461.86391 -387.650233) (xy 461.807083 -387.641604)
			(xy 461.752192 -387.624548) (xy 461.700481 -387.599453) (xy 461.653119 -387.566884) (xy 461.631792 -387.547612)
			(xy 461.62468 -387.541008) (xy 461.607154 -387.533896) (xy 461.517746 -387.533896) (xy 461.50022 -387.541008)
			(xy 461.493108 -387.547612) (xy 461.471794 -387.566898) (xy 461.424429 -387.599464) (xy 461.372715 -387.624555)
			(xy 461.317821 -387.641601) (xy 461.26099 -387.650219) (xy 461.23225 -387.650736) (xy 461.205003 -387.65019)
			(xy 461.151065 -387.642429) (xy 461.09878 -387.62707) (xy 461.049213 -387.604428) (xy 461.003372 -387.574963)
			(xy 460.962191 -387.539274) (xy 460.926507 -387.498088) (xy 460.897048 -387.452243) (xy 460.874412 -387.402673)
			(xy 460.859061 -387.350386) (xy 460.851306 -387.296447) (xy 460.087696 -387.296447) (xy 460.085414 -387.312315)
			(xy 460.070055 -387.36462) (xy 460.047408 -387.414207) (xy 460.017934 -387.460065) (xy 459.982234 -387.501262)
			(xy 459.941033 -387.536958) (xy 459.895171 -387.566427) (xy 459.845583 -387.589069) (xy 459.793276 -387.604423)
			(xy 459.739317 -387.612176) (xy 459.71206 -387.612636) (xy 459.683321 -387.612127) (xy 459.626493 -387.603499)
			(xy 459.571603 -387.586445) (xy 459.519891 -387.561351) (xy 459.472529 -387.528783) (xy 459.451202 -387.509512)
			(xy 459.44409 -387.502908) (xy 459.426564 -387.495796) (xy 459.337156 -387.495796) (xy 459.31963 -387.502908)
			(xy 459.312518 -387.509512) (xy 459.2912 -387.528793) (xy 459.243836 -387.56136) (xy 459.192123 -387.586451)
			(xy 459.137229 -387.603499) (xy 459.0804 -387.612118) (xy 459.05166 -387.612636) (xy 459.024413 -387.612091)
			(xy 458.970473 -387.604331) (xy 458.918187 -387.588973) (xy 458.868619 -387.566331) (xy 458.822777 -387.536866)
			(xy 458.781594 -387.501177) (xy 458.74591 -387.459991) (xy 458.716449 -387.414146) (xy 458.693813 -387.364575)
			(xy 458.678461 -387.312288) (xy 458.670706 -387.258347) (xy 457.434696 -387.258347) (xy 457.434696 -387.346952)
			(xy 457.441808 -387.364478) (xy 457.448412 -387.37159) (xy 457.467697 -387.392905) (xy 457.500263 -387.440269)
			(xy 457.525354 -387.491984) (xy 457.542401 -387.546878) (xy 457.551018 -387.603708) (xy 457.551536 -387.632448)
			(xy 457.551061 -387.659007) (xy 457.543703 -387.711613) (xy 457.529123 -387.762691) (xy 457.507601 -387.811254)
			(xy 457.479554 -387.856364) (xy 457.46289 -387.87705) (xy 457.45654 -387.884416) (xy 457.450698 -387.90245)
			(xy 457.454508 -387.989826) (xy 457.462128 -388.007098) (xy 457.468732 -388.013956) (xy 457.489405 -388.035575)
			(xy 457.524504 -388.084004) (xy 457.542741 -388.119874) (xy 457.846428 -388.119874) (xy 457.850499 -388.064252)
			(xy 457.862625 -388.009815) (xy 457.882548 -387.957724) (xy 457.909844 -387.909089) (xy 457.94393 -387.864946)
			(xy 457.984079 -387.826237) (xy 458.029437 -387.793786) (xy 458.079037 -387.768285) (xy 458.131821 -387.750278)
			(xy 458.186664 -387.740148) (xy 458.242398 -387.738111) (xy 458.297835 -387.744211) (xy 458.351792 -387.758317)
			(xy 458.403121 -387.780129) (xy 458.450727 -387.809183) (xy 458.493595 -387.844858) (xy 458.530812 -387.886395)
			(xy 458.561585 -387.932908) (xy 458.585257 -387.983405) (xy 458.601325 -388.036812) (xy 458.609445 -388.091988)
			(xy 458.609954 -388.119874) (xy 458.609445 -388.14776) (xy 458.601325 -388.202936) (xy 458.585257 -388.256343)
			(xy 458.561585 -388.30684) (xy 458.530812 -388.353353) (xy 458.493595 -388.39489) (xy 458.450727 -388.430565)
			(xy 458.403121 -388.459619) (xy 458.351792 -388.481431) (xy 458.297835 -388.495537) (xy 458.242398 -388.501637)
			(xy 458.186664 -388.4996) (xy 458.131821 -388.48947) (xy 458.079037 -388.471463) (xy 458.029437 -388.445962)
			(xy 457.984079 -388.413511) (xy 457.94393 -388.374802) (xy 457.909844 -388.330659) (xy 457.882548 -388.282024)
			(xy 457.862625 -388.229933) (xy 457.850499 -388.175496) (xy 457.846428 -388.119874) (xy 457.542741 -388.119874)
			(xy 457.551611 -388.137319) (xy 457.570061 -388.194213) (xy 457.5794 -388.253291) (xy 457.579984 -388.283196)
			(xy 457.579541 -388.31045) (xy 457.571784 -388.364403) (xy 457.556427 -388.416702) (xy 457.533783 -388.466284)
			(xy 457.504313 -388.512138) (xy 457.468618 -388.553332) (xy 457.427422 -388.589025) (xy 457.381567 -388.618493)
			(xy 457.331984 -388.641134) (xy 457.279683 -388.656488) (xy 457.22573 -388.664242) (xy 457.198476 -388.664704)
			(xy 457.171906 -388.664233) (xy 457.119283 -388.656837) (xy 457.068197 -388.642205) (xy 457.019637 -388.620622)
			(xy 456.974545 -388.592504) (xy 456.953874 -388.575804) (xy 456.946508 -388.569708) (xy 456.928982 -388.563866)
			(xy 456.84186 -388.566914) (xy 456.824842 -388.57428) (xy 456.817984 -388.580884) (xy 456.796502 -388.600972)
			(xy 456.748506 -388.634959) (xy 456.695863 -388.66118) (xy 456.639821 -388.679013) (xy 456.581706 -388.688037)
			(xy 456.5523 -388.68858) (xy 456.524869 -388.688153) (xy 456.470576 -388.680275) (xy 456.417969 -388.66471)
			(xy 456.36813 -388.641778) (xy 456.322085 -388.611952) (xy 456.280781 -388.575844) (xy 456.245068 -388.534198)
			(xy 456.229974 -388.511288) (xy 456.223116 -388.500366) (xy 456.200764 -388.48792) (xy 456.09002 -388.486142)
			(xy 456.067414 -388.497826) (xy 456.060048 -388.508748) (xy 456.044731 -388.530502) (xy 456.009069 -388.569982)
			(xy 455.968269 -388.604127) (xy 455.923123 -388.632275) (xy 455.874505 -388.65388) (xy 455.823358 -388.668523)
			(xy 455.770673 -388.675922) (xy 455.744072 -388.676388) (xy 455.716819 -388.675948) (xy 455.662869 -388.668187)
			(xy 455.610572 -388.652828) (xy 455.560993 -388.630182) (xy 455.515142 -388.600711) (xy 455.473952 -388.565014)
			(xy 455.43826 -388.523819) (xy 455.408795 -388.477965) (xy 455.386156 -388.428383) (xy 455.370802 -388.376084)
			(xy 455.363048 -388.322133) (xy 455.362564 -388.29488) (xy 455.363074 -388.265401) (xy 455.372148 -388.207146)
			(xy 455.390076 -388.15098) (xy 455.416433 -388.098241) (xy 455.450589 -388.050185) (xy 455.470768 -388.028688)
			(xy 455.47788 -388.021322) (xy 455.485246 -388.003034) (xy 455.485246 -387.912102) (xy 455.477626 -387.893814)
			(xy 455.470768 -387.886702) (xy 455.450437 -387.865202) (xy 455.416059 -387.817042) (xy 455.389529 -387.764151)
			(xy 455.371483 -387.707798) (xy 455.362355 -387.649334) (xy 455.361802 -387.619748) (xy 452.503953 -387.619748)
			(xy 452.510938 -387.668071) (xy 452.511414 -387.69544) (xy 452.510874 -387.723834) (xy 452.502458 -387.779995)
			(xy 452.485804 -387.834286) (xy 452.46128 -387.885505) (xy 452.429428 -387.932519) (xy 452.410576 -387.953758)
			(xy 452.404226 -387.960616) (xy 452.397368 -387.977888) (xy 452.396098 -388.064248) (xy 452.402194 -388.08152)
			(xy 452.408544 -388.088632) (xy 452.425852 -388.109521) (xy 452.455038 -388.155246) (xy 452.47745 -388.204647)
			(xy 452.492635 -388.256725) (xy 452.500286 -388.310429) (xy 452.500746 -388.337552) (xy 452.50026 -388.364803)
			(xy 452.492504 -388.418751) (xy 452.477149 -388.471046) (xy 452.454507 -388.520623) (xy 452.425041 -388.566473)
			(xy 452.38935 -388.607664) (xy 452.348159 -388.643355) (xy 452.302309 -388.672821) (xy 452.252732 -388.695463)
			(xy 452.200437 -388.710818) (xy 452.146489 -388.718574) (xy 452.091987 -388.718574) (xy 452.038039 -388.710818)
			(xy 451.985744 -388.695463) (xy 451.936167 -388.672821) (xy 451.890317 -388.643355) (xy 451.849126 -388.607664)
			(xy 451.813435 -388.566473) (xy 451.783969 -388.520623) (xy 451.761327 -388.471046) (xy 451.745972 -388.418751)
			(xy 451.738216 -388.364803) (xy 451.73773 -388.337552) (xy 451.738128 -388.312092) (xy 451.744897 -388.261624)
			(xy 451.758321 -388.212505) (xy 451.778162 -388.16561) (xy 451.804066 -388.121772) (xy 451.835573 -388.08177)
			(xy 451.853554 -388.06374) (xy 451.860334 -388.056435) (xy 451.86817 -388.038128) (xy 451.868794 -388.02818)
			(xy 451.869556 -387.996176) (xy 451.869232 -387.98619) (xy 451.861915 -387.967623) (xy 451.855332 -387.960108)
			(xy 451.84314 -387.9469) (xy 451.835578 -387.93903) (xy 451.815692 -387.930084) (xy 451.804786 -387.929628)
			(xy 451.728586 -387.929628) (xy 451.717691 -387.930128) (xy 451.697822 -387.939068) (xy 451.690232 -387.9469)
			(xy 451.672054 -387.966953) (xy 451.630995 -388.002217) (xy 451.58536 -388.031318) (xy 451.536067 -388.05367)
			(xy 451.484108 -388.068825) (xy 451.430528 -388.076477) (xy 451.403466 -388.076948) (xy 451.374727 -388.076432)
			(xy 451.3179 -388.067806) (xy 451.263009 -388.050753) (xy 451.211298 -388.02566) (xy 451.163935 -387.993095)
			(xy 451.142608 -387.973824) (xy 451.135496 -387.96722) (xy 451.11797 -387.960108) (xy 451.028562 -387.960108)
			(xy 451.011036 -387.96722) (xy 451.003924 -387.973824) (xy 450.982605 -387.993105) (xy 450.935242 -388.025671)
			(xy 450.883528 -388.050762) (xy 450.828635 -388.06781) (xy 450.771806 -388.076429) (xy 450.743066 -388.076948)
			(xy 450.715816 -388.076454) (xy 450.66187 -388.068694) (xy 450.609578 -388.053336) (xy 450.560004 -388.030694)
			(xy 450.514155 -388.001228) (xy 450.472966 -387.965538) (xy 450.437275 -387.92435) (xy 450.407809 -387.878502)
			(xy 450.385166 -387.828927) (xy 450.369807 -387.776635) (xy 450.362046 -387.72269) (xy 450.361558 -387.69544)
			(xy 450.362033 -387.66807) (xy 450.369847 -387.613891) (xy 450.385333 -387.561387) (xy 450.408173 -387.51164)
			(xy 450.437897 -387.465673) (xy 450.455538 -387.444742) (xy 450.461634 -387.43763) (xy 450.467984 -387.420612)
			(xy 450.467984 -387.335268) (xy 450.461634 -387.31825) (xy 450.455538 -387.311138) (xy 450.437909 -387.290198)
			(xy 450.408194 -387.244228) (xy 450.385356 -387.194482) (xy 450.369863 -387.141983) (xy 450.362033 -387.087809)
			(xy 450.361558 -387.06044) (xy 450.362056 -387.0317) (xy 450.370687 -386.974872) (xy 450.387744 -386.919982)
			(xy 450.41284 -386.86827) (xy 450.44541 -386.820909) (xy 450.464682 -386.799582) (xy 450.47154 -386.792216)
			(xy 450.478398 -386.774436) (xy 450.477636 -386.684266) (xy 450.47027 -386.666232) (xy 450.463158 -386.65912)
			(xy 450.442931 -386.637621) (xy 450.408707 -386.589528) (xy 450.382299 -386.536738) (xy 450.364337 -386.480511)
			(xy 450.35525 -386.422187) (xy 450.3547 -386.392674) (xy 450.18508 -386.392674) (xy 450.177797 -386.441828)
			(xy 450.16149 -386.495614) (xy 450.137467 -386.546424) (xy 450.106249 -386.59316) (xy 450.06851 -386.634808)
			(xy 450.047106 -386.653024) (xy 450.03847 -386.660136) (xy 450.028818 -386.680202) (xy 450.027294 -386.780532)
			(xy 450.036438 -386.800598) (xy 450.045074 -386.808218) (xy 450.065287 -386.826445) (xy 450.100884 -386.867614)
			(xy 450.130271 -386.913424) (xy 450.152851 -386.962944) (xy 450.168167 -387.015169) (xy 450.175906 -387.069041)
			(xy 450.176392 -387.096254) (xy 450.175903 -387.124994) (xy 450.167272 -387.181823) (xy 450.150214 -387.236714)
			(xy 450.125115 -387.288426) (xy 450.092542 -387.335786) (xy 450.073268 -387.357112) (xy 450.066664 -387.364224)
			(xy 450.059552 -387.38175) (xy 450.059552 -387.471158) (xy 450.066664 -387.488684) (xy 450.073268 -387.495796)
			(xy 450.092565 -387.5171) (xy 450.125128 -387.564468) (xy 450.150215 -387.616186) (xy 450.167259 -387.671082)
			(xy 450.175875 -387.727913) (xy 450.176392 -387.756654) (xy 450.175902 -387.783906) (xy 450.168151 -387.837857)
			(xy 450.1528 -387.890156) (xy 450.130161 -387.939737) (xy 450.100697 -387.985591) (xy 450.065006 -388.026784)
			(xy 450.023815 -388.062479) (xy 449.977963 -388.091947) (xy 449.928384 -388.114589) (xy 449.876087 -388.129944)
			(xy 449.822136 -388.1377) (xy 449.794884 -388.138162) (xy 449.769022 -388.137724) (xy 449.717771 -388.13074)
			(xy 449.667935 -388.11689) (xy 449.620431 -388.096427) (xy 449.57613 -388.069728) (xy 449.535847 -388.037283)
			(xy 449.51777 -388.018782) (xy 449.510244 -388.011554) (xy 449.491108 -388.003288) (xy 449.480686 -388.00278)
			(xy 449.448682 -388.00278) (xy 449.43825 -388.003245) (xy 449.419097 -388.011514) (xy 449.411598 -388.018782)
			(xy 449.407534 -388.0231) (xy 449.400168 -388.030466) (xy 449.392802 -388.04977) (xy 449.39585 -388.14375)
			(xy 449.404486 -388.162546) (xy 449.41236 -388.169404) (xy 449.431867 -388.187546) (xy 449.466085 -388.228374)
			(xy 449.494285 -388.27357) (xy 449.515917 -388.322252) (xy 449.530559 -388.373472) (xy 449.537926 -388.426232)
			(xy 449.538344 -388.452868) (xy 449.537792 -388.480117) (xy 449.530041 -388.53406) (xy 449.514692 -388.586352)
			(xy 449.492057 -388.635926) (xy 449.462597 -388.681775) (xy 449.426913 -388.722965) (xy 449.385729 -388.758657)
			(xy 449.339886 -388.788124) (xy 449.290315 -388.810768) (xy 449.238027 -388.826126) (xy 449.184085 -388.833887)
			(xy 449.156836 -388.834376) (xy 449.12792 -388.833841) (xy 449.070749 -388.825117) (xy 449.01555 -388.807863)
			(xy 448.963588 -388.782474) (xy 448.916054 -388.749533) (xy 448.874036 -388.709794) (xy 448.855846 -388.68731)
			(xy 448.848258 -388.678575) (xy 448.827519 -388.668376) (xy 448.815968 -388.667752) (xy 448.735704 -388.667752)
			(xy 448.724134 -388.668307) (xy 448.703362 -388.678511) (xy 448.695826 -388.68731) (xy 448.677623 -388.709783)
			(xy 448.635605 -388.749519) (xy 448.588073 -388.782458) (xy 448.536114 -388.807848) (xy 448.480919 -388.825107)
			(xy 448.423751 -388.833839) (xy 448.394836 -388.834376) (xy 448.367583 -388.833911) (xy 448.31363 -388.826158)
			(xy 448.26133 -388.810805) (xy 448.211748 -388.788164) (xy 448.165893 -388.758697) (xy 448.124699 -388.723003)
			(xy 448.089005 -388.68181) (xy 448.059537 -388.635955) (xy 448.036896 -388.586374) (xy 448.021543 -388.534074)
			(xy 448.013789 -388.480121) (xy 448.013328 -388.452868) (xy 448.013848 -388.423354) (xy 448.022944 -388.36503)
			(xy 448.040916 -388.308804) (xy 448.067333 -388.256017) (xy 448.101565 -388.207928) (xy 448.121786 -388.186422)
			(xy 448.129152 -388.179056) (xy 448.136518 -388.159752) (xy 448.13347 -388.065772) (xy 448.124834 -388.046976)
			(xy 448.11696 -388.040118) (xy 448.097468 -388.021961) (xy 448.063247 -387.981136) (xy 448.035045 -387.935944)
			(xy 448.013411 -387.887265) (xy 447.998766 -387.836047) (xy 447.991395 -387.783289) (xy 447.990976 -387.756654)
			(xy 447.991478 -387.727914) (xy 448.000107 -387.671086) (xy 448.017162 -387.616196) (xy 448.042259 -387.564484)
			(xy 448.074828 -387.517122) (xy 448.0941 -387.495796) (xy 448.100704 -387.488684) (xy 448.107816 -387.471158)
			(xy 448.107816 -387.38175) (xy 448.100704 -387.364224) (xy 448.0941 -387.357112) (xy 448.074818 -387.335794)
			(xy 448.042251 -387.288431) (xy 448.01716 -387.236717) (xy 448.000112 -387.181824) (xy 447.991494 -387.124994)
			(xy 447.990976 -387.096254) (xy 447.991473 -387.068151) (xy 447.999713 -387.012554) (xy 448.016023 -386.958767)
			(xy 448.04005 -386.907956) (xy 448.071273 -386.861222) (xy 448.109016 -386.819575) (xy 448.130422 -386.80136)
			(xy 448.139058 -386.794248) (xy 448.14871 -386.774182) (xy 448.150234 -386.673852) (xy 448.14109 -386.653786)
			(xy 448.132454 -386.646166) (xy 448.112239 -386.627941) (xy 448.076641 -386.586772) (xy 448.047253 -386.540963)
			(xy 448.024673 -386.491442) (xy 448.009359 -386.439215) (xy 448.001621 -386.385343) (xy 448.001136 -386.35813)
			(xy 448.001696 -386.329072) (xy 448.010524 -386.27163) (xy 448.027966 -386.216192) (xy 448.053618 -386.164043)
			(xy 448.086885 -386.11639) (xy 448.106546 -386.094986) (xy 448.11315 -386.087874) (xy 448.120516 -386.06984)
			(xy 448.120516 -385.979924) (xy 448.11315 -385.96189) (xy 448.106546 -385.954778) (xy 448.086865 -385.93339)
			(xy 448.053587 -385.885739) (xy 448.027932 -385.833586) (xy 448.010495 -385.778143) (xy 448.001679 -385.720695)
			(xy 448.001136 -385.691634) (xy 448.001606 -385.664934) (xy 448.009054 -385.612055) (xy 448.023807 -385.560733)
			(xy 448.045578 -385.511973) (xy 448.073941 -385.466727) (xy 448.090798 -385.446016) (xy 448.096894 -385.43865)
			(xy 448.10299 -385.420616) (xy 448.09918 -385.332986) (xy 448.09156 -385.31546) (xy 448.084956 -385.308856)
			(xy 448.064171 -385.287243) (xy 448.028912 -385.238746) (xy 448.001679 -385.185329) (xy 447.98314 -385.128308)
			(xy 447.973755 -385.069088) (xy 447.973196 -385.039108) (xy 441.10148 -385.039108) (xy 441.10148 -386.394706)
			(xy 442.279024 -386.394706) (xy 442.279461 -386.367452) (xy 442.287218 -386.313498) (xy 442.302575 -386.261198)
			(xy 442.325219 -386.211616) (xy 442.354689 -386.165761) (xy 442.390386 -386.124568) (xy 442.431582 -386.088874)
			(xy 442.477439 -386.059407) (xy 442.527022 -386.036766) (xy 442.579324 -386.021412) (xy 442.633278 -386.013659)
			(xy 442.660532 -386.013198) (xy 442.687801 -386.013699) (xy 442.741781 -386.02148) (xy 442.794103 -386.036866)
			(xy 442.843704 -386.059542) (xy 442.889571 -386.089047) (xy 442.930772 -386.124781) (xy 442.966467 -386.166015)
			(xy 442.981588 -386.188712) (xy 442.989127 -386.198999) (xy 443.011525 -386.21113) (xy 443.02426 -386.211826)
			(xy 443.055756 -386.211826) (xy 443.06422 -386.211559) (xy 443.080231 -386.20607) (xy 443.093566 -386.195646)
			(xy 443.098428 -386.188712) (xy 443.118748 -386.16001) (xy 443.12459 -386.152644) (xy 443.129924 -386.134356)
			(xy 443.123066 -386.04698) (xy 443.114938 -386.029708) (xy 443.107826 -386.023358) (xy 443.089012 -386.005256)
			(xy 443.056035 -385.96478) (xy 443.028882 -385.920186) (xy 443.008061 -385.872308) (xy 442.993959 -385.822039)
			(xy 442.986841 -385.770317) (xy 442.986414 -385.744212) (xy 442.986867 -385.716958) (xy 442.994622 -385.663006)
			(xy 443.009978 -385.610707) (xy 443.032621 -385.561125) (xy 443.06209 -385.515271) (xy 443.097785 -385.474077)
			(xy 443.138979 -385.438384) (xy 443.184834 -385.408916) (xy 443.234416 -385.386275) (xy 443.286716 -385.37092)
			(xy 443.340668 -385.363166) (xy 443.367922 -385.362704) (xy 443.394158 -385.363146) (xy 443.446135 -385.370344)
			(xy 443.496634 -385.384602) (xy 443.5447 -385.405649) (xy 443.589427 -385.433089) (xy 443.629968 -385.466403)
			(xy 443.648084 -385.485386) (xy 443.65545 -385.493006) (xy 443.6745 -385.501642) (xy 443.769496 -385.502404)
			(xy 443.7888 -385.494276) (xy 443.796166 -385.486656) (xy 443.814239 -385.468464) (xy 443.854381 -385.436556)
			(xy 443.898434 -385.41031) (xy 443.945606 -385.390201) (xy 443.995046 -385.37659) (xy 444.045863 -385.369723)
			(xy 444.071502 -385.369308) (xy 444.097485 -385.369722) (xy 444.148968 -385.376788) (xy 444.199017 -385.390774)
			(xy 444.246704 -385.411422) (xy 444.291149 -385.43835) (xy 444.331529 -385.471061) (xy 444.349632 -385.489704)
			(xy 444.357159 -385.496931) (xy 444.376294 -385.505198) (xy 444.386716 -385.505706) (xy 444.460884 -385.505706)
			(xy 444.471315 -385.505227) (xy 444.490468 -385.496968) (xy 444.497968 -385.489704) (xy 444.516083 -385.471073)
			(xy 444.556457 -385.438359) (xy 444.600899 -385.41143) (xy 444.648585 -385.390784) (xy 444.698633 -385.376803)
			(xy 444.750116 -385.369748) (xy 444.776098 -385.369308) (xy 444.803352 -385.369757) (xy 444.857304 -385.377514)
			(xy 444.909603 -385.392871) (xy 444.959184 -385.415514) (xy 445.005038 -385.444984) (xy 445.046231 -385.480679)
			(xy 445.081925 -385.521873) (xy 445.111392 -385.567728) (xy 445.134034 -385.61731) (xy 445.149389 -385.66961)
			(xy 445.157144 -385.723562) (xy 445.157606 -385.750816) (xy 445.157128 -385.77795) (xy 445.149441 -385.831671)
			(xy 445.134212 -385.883758) (xy 445.111748 -385.933158) (xy 445.082504 -385.978871) (xy 445.06515 -385.999736)
			(xy 445.059054 -386.006848) (xy 445.052704 -386.02412) (xy 445.053974 -386.110226) (xy 445.060832 -386.127244)
			(xy 445.066928 -386.134356) (xy 445.085435 -386.155533) (xy 445.116711 -386.202273) (xy 445.140793 -386.253095)
			(xy 445.157162 -386.3069) (xy 445.165462 -386.362523) (xy 445.165988 -386.390642) (xy 445.165412 -386.419767)
			(xy 445.156552 -386.477339) (xy 445.139044 -386.532895) (xy 445.113296 -386.585145) (xy 445.079906 -386.632874)
			(xy 445.039649 -386.674974) (xy 445.01689 -386.693156) (xy 445.007492 -386.700268) (xy 444.997078 -386.721604)
			(xy 444.997586 -386.826252) (xy 445.008 -386.847588) (xy 445.017652 -386.8547) (xy 445.040752 -386.872847)
			(xy 445.081617 -386.915042) (xy 445.115533 -386.963003) (xy 445.141697 -387.015595) (xy 445.159491 -387.071575)
			(xy 445.168495 -387.129622) (xy 445.169036 -387.158992) (xy 445.168581 -387.186363) (xy 445.160763 -387.240543)
			(xy 445.145272 -387.293047) (xy 445.122427 -387.342794) (xy 445.092699 -387.388759) (xy 445.075056 -387.40969)
			(xy 445.06896 -387.416802) (xy 445.06261 -387.43382) (xy 445.06261 -387.519164) (xy 445.06896 -387.536182)
			(xy 445.075056 -387.543294) (xy 445.09269 -387.564233) (xy 445.122416 -387.610199) (xy 445.145263 -387.659944)
			(xy 445.16076 -387.712446) (xy 445.16859 -387.766624) (xy 445.168591 -387.821364) (xy 445.160763 -387.875543)
			(xy 445.145267 -387.928044) (xy 445.122422 -387.97779) (xy 445.092697 -388.023758) (xy 445.075056 -388.04469)
			(xy 445.06896 -388.051802) (xy 445.06261 -388.06882) (xy 445.06261 -388.154164) (xy 445.06896 -388.171182)
			(xy 445.075056 -388.178294) (xy 445.092699 -388.199223) (xy 445.122412 -388.245196) (xy 445.145248 -388.294944)
			(xy 445.160738 -388.347446) (xy 445.168564 -388.401623) (xy 445.169036 -388.428992) (xy 445.168515 -388.456242)
			(xy 445.16076 -388.510187) (xy 445.145407 -388.562479) (xy 445.122769 -388.612055) (xy 445.093306 -388.657904)
			(xy 445.057619 -388.699093) (xy 445.016432 -388.734785) (xy 444.970586 -388.764252) (xy 444.921013 -388.786895)
			(xy 444.868722 -388.802253) (xy 444.814778 -388.810012) (xy 444.787528 -388.8105) (xy 444.761546 -388.810064)
			(xy 444.710064 -388.803002) (xy 444.660016 -388.78902) (xy 444.612328 -388.768376) (xy 444.567883 -388.741452)
			(xy 444.527502 -388.708746) (xy 444.509398 -388.690104) (xy 444.501859 -388.682891) (xy 444.482733 -388.674616)
			(xy 444.472314 -388.674102) (xy 444.398146 -388.674102) (xy 444.387711 -388.674541) (xy 444.368558 -388.682828)
			(xy 444.361062 -388.690104) (xy 444.342982 -388.70877) (xy 444.3026 -388.741481) (xy 444.258151 -388.768405)
			(xy 444.210458 -388.789045) (xy 444.160404 -388.803018) (xy 444.108916 -388.810065) (xy 444.082932 -388.8105)
			(xy 444.05568 -388.810015) (xy 444.001729 -388.802262) (xy 443.949431 -388.78691) (xy 443.899851 -388.76427)
			(xy 443.853997 -388.734805) (xy 443.812804 -388.699113) (xy 443.777109 -388.657922) (xy 443.747641 -388.612071)
			(xy 443.724999 -388.562491) (xy 443.709643 -388.510194) (xy 443.701887 -388.456244) (xy 443.701424 -388.428992)
			(xy 443.70188 -388.401621) (xy 443.709699 -388.347442) (xy 443.72519 -388.294938) (xy 443.748034 -388.245191)
			(xy 443.777762 -388.199225) (xy 443.795404 -388.178294) (xy 443.8015 -388.171182) (xy 443.80785 -388.154164)
			(xy 443.80785 -388.06882) (xy 443.8015 -388.051802) (xy 443.795404 -388.04469) (xy 443.777747 -388.023772)
			(xy 443.748038 -387.977795) (xy 443.725205 -387.928044) (xy 443.709718 -387.875541) (xy 443.701895 -387.821362)
			(xy 443.701424 -387.793992) (xy 443.701952 -387.764514) (xy 443.711023 -387.70626) (xy 443.728948 -387.650095)
			(xy 443.7553 -387.597356) (xy 443.789452 -387.549299) (xy 443.809628 -387.5278) (xy 443.816159 -387.520463)
			(xy 443.823606 -387.502304) (xy 443.824106 -387.492494) (xy 443.824106 -387.439154) (xy 443.81039 -387.425946)
			(xy 443.802262 -387.417564) (xy 443.780672 -387.40969) (xy 443.678818 -387.419596) (xy 443.65926 -387.431534)
			(xy 443.65291 -387.441186) (xy 443.637716 -387.463474) (xy 443.602042 -387.503932) (xy 443.561022 -387.538959)
			(xy 443.515476 -387.567856) (xy 443.466313 -387.590047) (xy 443.414513 -387.605089) (xy 443.36111 -387.612682)
			(xy 443.33414 -387.613144) (xy 443.3054 -387.612645) (xy 443.248572 -387.604015) (xy 443.193682 -387.586958)
			(xy 443.141971 -387.561861) (xy 443.094609 -387.529292) (xy 443.073282 -387.51002) (xy 443.06617 -387.503416)
			(xy 443.048644 -387.496304) (xy 442.959236 -387.496304) (xy 442.94171 -387.503416) (xy 442.934598 -387.51002)
			(xy 442.913248 -387.529265) (xy 442.865893 -387.561836) (xy 442.814187 -387.586934) (xy 442.759301 -387.603991)
			(xy 442.702478 -387.61262) (xy 442.67374 -387.613144) (xy 442.64649 -387.612608) (xy 442.592543 -387.604857)
			(xy 442.540249 -387.589508) (xy 442.490671 -387.566873) (xy 442.44482 -387.537412) (xy 442.403628 -387.501726)
			(xy 442.367933 -387.460541) (xy 442.338464 -387.414695) (xy 442.315819 -387.365122) (xy 442.300459 -387.312831)
			(xy 442.292698 -387.258886) (xy 442.292232 -387.231636) (xy 442.292795 -387.203509) (xy 442.30105 -387.147864)
			(xy 442.317387 -387.094035) (xy 442.341452 -387.043188) (xy 442.372723 -386.996426) (xy 442.410521 -386.954764)
			(xy 442.454028 -386.919103) (xy 442.477906 -386.90423) (xy 442.489844 -386.897118) (xy 442.503052 -386.87375)
			(xy 442.50102 -386.757926) (xy 442.487304 -386.734812) (xy 442.475112 -386.728208) (xy 442.450014 -386.713677)
			(xy 442.404186 -386.678139) (xy 442.364263 -386.636074) (xy 442.331165 -386.588453) (xy 442.305654 -386.536372)
			(xy 442.288319 -386.481031) (xy 442.279557 -386.423703) (xy 442.279024 -386.394706) (xy 441.10148 -386.394706)
			(xy 441.10148 -387.700774) (xy 441.100982 -387.726755) (xy 441.092821 -387.778073) (xy 441.076726 -387.827481)
			(xy 441.053096 -387.873761) (xy 441.022512 -387.91577) (xy 441.004452 -387.934454) (xy 440.800248 -388.13867)
			(xy 441.467492 -388.13867) (xy 441.471563 -388.083048) (xy 441.483689 -388.028611) (xy 441.503612 -387.97652)
			(xy 441.530908 -387.927885) (xy 441.564994 -387.883742) (xy 441.605143 -387.845033) (xy 441.650501 -387.812582)
			(xy 441.700101 -387.787081) (xy 441.752885 -387.769074) (xy 441.807728 -387.758944) (xy 441.863462 -387.756907)
			(xy 441.918899 -387.763007) (xy 441.972856 -387.777113) (xy 442.024185 -387.798925) (xy 442.071791 -387.827979)
			(xy 442.114659 -387.863654) (xy 442.151876 -387.905191) (xy 442.182649 -387.951704) (xy 442.206321 -388.002201)
			(xy 442.222389 -388.055608) (xy 442.230509 -388.110784) (xy 442.231018 -388.13867) (xy 442.230509 -388.166556)
			(xy 442.222389 -388.221732) (xy 442.206321 -388.275139) (xy 442.182649 -388.325636) (xy 442.151876 -388.372149)
			(xy 442.114659 -388.413686) (xy 442.071791 -388.449361) (xy 442.024185 -388.478415) (xy 441.972856 -388.500227)
			(xy 441.918899 -388.514333) (xy 441.863462 -388.520433) (xy 441.807728 -388.518396) (xy 441.752885 -388.508266)
			(xy 441.700101 -388.490259) (xy 441.650501 -388.464758) (xy 441.605143 -388.432307) (xy 441.564994 -388.393598)
			(xy 441.530908 -388.349455) (xy 441.503612 -388.30082) (xy 441.483689 -388.248729) (xy 441.471563 -388.194292)
			(xy 441.467492 -388.13867) (xy 440.800248 -388.13867) (xy 436.65013 -392.28903) (xy 436.643321 -392.296375)
			(xy 436.635594 -392.314838) (xy 436.635144 -392.324844) (xy 436.635144 -394.569696) (xy 436.635568 -394.579766)
			(xy 436.643286 -394.598367) (xy 436.65013 -394.605764) (xy 438.63768 -396.593314) (xy 438.644526 -396.600712)
			(xy 438.652259 -396.619311) (xy 438.652666 -396.629382) (xy 438.652666 -396.743936) (xy 438.653111 -396.753723)
			(xy 438.660424 -396.771881) (xy 438.66689 -396.779242) (xy 438.675272 -396.787878) (xy 438.675526 -396.788132)
			(xy 438.693497 -396.806845) (xy 438.723977 -396.848828) (xy 438.747534 -396.895052) (xy 438.76359 -396.944385)
			(xy 438.771753 -396.995619) (xy 438.7723 -397.021558) (xy 438.7723 -402.87829) (xy 438.771801 -402.904271)
			(xy 438.763638 -402.955588) (xy 438.747542 -403.004995) (xy 438.723912 -403.051274) (xy 438.693328 -403.093283)
			(xy 438.675272 -403.11197) (xy 437.710072 -404.077424) (xy 437.70343 -404.084783) (xy 437.695863 -404.103083)
			(xy 437.69534 -404.112984) (xy 437.69534 -406.931622) (xy 439.08929 -406.931622) (xy 439.093361 -406.876)
			(xy 439.105487 -406.821563) (xy 439.12541 -406.769472) (xy 439.152706 -406.720837) (xy 439.186792 -406.676694)
			(xy 439.226941 -406.637985) (xy 439.272299 -406.605534) (xy 439.321899 -406.580033) (xy 439.374683 -406.562026)
			(xy 439.429526 -406.551896) (xy 439.48526 -406.549859) (xy 439.540697 -406.555959) (xy 439.594654 -406.570065)
			(xy 439.645983 -406.591877) (xy 439.693589 -406.620931) (xy 439.736457 -406.656606) (xy 439.773674 -406.698143)
			(xy 439.804447 -406.744656) (xy 439.828119 -406.795153) (xy 439.844187 -406.84856) (xy 439.852307 -406.903736)
			(xy 439.852816 -406.931622) (xy 439.852307 -406.959508) (xy 439.844187 -407.014684) (xy 439.828119 -407.068091)
			(xy 439.804447 -407.118588) (xy 439.773674 -407.165101) (xy 439.736457 -407.206638) (xy 439.693589 -407.242313)
			(xy 439.645983 -407.271367) (xy 439.594654 -407.293179) (xy 439.540697 -407.307285) (xy 439.48526 -407.313385)
			(xy 439.429526 -407.311348) (xy 439.374683 -407.301218) (xy 439.321899 -407.283211) (xy 439.272299 -407.25771)
			(xy 439.226941 -407.225259) (xy 439.186792 -407.18655) (xy 439.152706 -407.142407) (xy 439.12541 -407.093772)
			(xy 439.105487 -407.041681) (xy 439.093361 -406.987244) (xy 439.08929 -406.931622) (xy 437.69534 -406.931622)
			(xy 437.69534 -413.092138) (xy 437.694845 -413.11812) (xy 437.686688 -413.16944) (xy 437.670596 -413.218851)
			(xy 437.646967 -413.265132) (xy 437.616383 -413.307143) (xy 437.598312 -413.325818) (xy 437.360314 -413.56407)
			(xy 437.353513 -413.571418) (xy 437.345804 -413.589881) (xy 437.345328 -413.599884) (xy 437.345328 -418.463006)
			(xy 438.119782 -418.463006) (xy 438.119818 -418.408486) (xy 438.127616 -418.354527) (xy 438.143016 -418.302227)
			(xy 438.165706 -418.252652) (xy 438.195222 -418.206813) (xy 438.230964 -418.165643) (xy 438.272203 -418.129981)
			(xy 438.318099 -418.100553) (xy 438.367717 -418.077959) (xy 438.420047 -418.062659) (xy 438.474021 -418.054966)
			(xy 438.501282 -418.054536) (xy 438.511696 -418.054536) (xy 438.530238 -418.046916) (xy 438.563766 -418.013388)
			(xy 438.570599 -418.005982) (xy 438.578324 -417.987388) (xy 438.578752 -417.97732) (xy 438.578752 -415.986214)
			(xy 438.57939 -415.961232) (xy 438.589125 -415.912225) (xy 438.608224 -415.866055) (xy 438.635956 -415.824493)
			(xy 438.653174 -415.806382) (xy 440.141868 -414.317688) (xy 440.148558 -414.310205) (xy 440.15615 -414.291647)
			(xy 440.1566 -414.28162) (xy 440.1566 -406.58288) (xy 440.156241 -406.572833) (xy 440.148647 -406.554236)
			(xy 440.141868 -406.546812) (xy 439.405268 -405.810212) (xy 439.388036 -405.792094) (xy 439.360218 -405.750559)
			(xy 439.341038 -405.704394) (xy 439.331232 -405.655375) (xy 439.330592 -405.63038) (xy 439.330592 -394.324332)
			(xy 439.330235 -394.314285) (xy 439.322637 -394.295689) (xy 439.31586 -394.288264) (xy 438.62625 -393.598654)
			(xy 438.609039 -393.580534) (xy 438.581296 -393.538978) (xy 438.562185 -393.492811) (xy 438.552441 -393.443805)
			(xy 438.551828 -393.418822) (xy 438.551828 -392.420348) (xy 438.551574 -392.420348) (xy 438.551574 -392.31443)
			(xy 438.55132 -392.313922) (xy 438.55132 -391.815828) (xy 438.526174 -391.787126) (xy 438.507378 -391.784586)
			(xy 438.480208 -391.780522) (xy 438.427343 -391.765581) (xy 438.377168 -391.743212) (xy 438.33072 -391.713877)
			(xy 438.288961 -391.678183) (xy 438.252752 -391.636868) (xy 438.222845 -391.590787) (xy 438.199856 -391.540892)
			(xy 438.184262 -391.488216) (xy 438.176385 -391.433848) (xy 438.175908 -391.40638) (xy 438.176359 -391.379128)
			(xy 438.184119 -391.325178) (xy 438.199477 -391.272881) (xy 438.222122 -391.223303) (xy 438.251592 -391.177452)
			(xy 438.287287 -391.136262) (xy 438.328481 -391.10057) (xy 438.374335 -391.071105) (xy 438.423915 -391.048465)
			(xy 438.476213 -391.033111) (xy 438.530163 -391.025357) (xy 438.557416 -391.024872) (xy 438.583782 -391.025269)
			(xy 438.636008 -391.032558) (xy 438.686734 -391.046966) (xy 438.734993 -391.068221) (xy 438.779867 -391.095916)
			(xy 438.820502 -391.129524) (xy 438.856123 -391.168407) (xy 438.886053 -391.211822) (xy 438.898284 -391.235184)
			(xy 438.904888 -391.248138) (xy 438.929272 -391.263124) (xy 439.04916 -391.263124) (xy 439.07329 -391.248138)
			(xy 439.079894 -391.23493) (xy 439.092167 -391.211565) (xy 439.122096 -391.168096) (xy 439.157728 -391.129165)
			(xy 439.198386 -391.095516) (xy 439.243291 -391.06779) (xy 439.291589 -391.046516) (xy 439.342358 -391.032099)
			(xy 439.394628 -391.024816) (xy 439.421016 -391.024364) (xy 439.448266 -391.024863) (xy 439.502212 -391.032621)
			(xy 439.554505 -391.047977) (xy 439.60408 -391.070617) (xy 439.649929 -391.100083) (xy 439.691119 -391.135773)
			(xy 439.72681 -391.176961) (xy 439.756277 -391.222809) (xy 439.778919 -391.272384) (xy 439.794277 -391.324676)
			(xy 439.802036 -391.378622) (xy 439.802524 -391.405872) (xy 439.802075 -391.432698) (xy 439.794541 -391.485819)
			(xy 439.779644 -391.537362) (xy 439.75768 -391.586312) (xy 439.729079 -391.631705) (xy 439.694405 -391.672648)
			(xy 439.654342 -391.708334) (xy 439.609677 -391.73806) (xy 439.561291 -391.761242) (xy 439.510137 -391.777422)
			(xy 439.483754 -391.7823) (xy 439.465212 -391.785348) (xy 439.441336 -391.813542) (xy 439.441336 -392.31316)
			(xy 439.441336 -392.418824) (xy 439.441336 -392.419332) (xy 439.441336 -393.134342) (xy 439.44173 -393.144415)
			(xy 439.449472 -393.163013) (xy 439.456322 -393.17041) (xy 440.145932 -393.86002) (xy 440.163179 -393.878124)
			(xy 440.190994 -393.919665) (xy 440.21017 -393.965833) (xy 440.219971 -394.014856) (xy 440.220608 -394.039852)
			(xy 440.220608 -398.764547) (xy 440.398206 -398.764547) (xy 440.398206 -398.710053) (xy 440.405961 -398.656113)
			(xy 440.421312 -398.603826) (xy 440.443949 -398.554256) (xy 440.473408 -398.508411) (xy 440.509092 -398.467225)
			(xy 440.550274 -398.431536) (xy 440.596115 -398.402071) (xy 440.645683 -398.379429) (xy 440.697968 -398.364071)
			(xy 440.751907 -398.356309) (xy 440.779154 -398.35582) (xy 440.806334 -398.356309) (xy 440.860137 -398.364081)
			(xy 440.886342 -398.371314) (xy 440.899804 -398.375124) (xy 440.926474 -398.368266) (xy 440.936634 -398.35836)
			(xy 440.943431 -398.350968) (xy 440.95114 -398.332445) (xy 440.951146 -398.312382) (xy 440.943446 -398.293855)
			(xy 440.936634 -398.286478) (xy 440.882024 -398.231868) (xy 440.874558 -398.225155) (xy 440.855987 -398.217576)
			(xy 440.845956 -398.217136) (xy 440.786266 -398.217136) (xy 440.759018 -398.216591) (xy 440.705078 -398.208832)
			(xy 440.652792 -398.193475) (xy 440.603222 -398.170833) (xy 440.55738 -398.141368) (xy 440.516197 -398.105679)
			(xy 440.480511 -398.064493) (xy 440.45105 -398.018648) (xy 440.428413 -397.969077) (xy 440.413061 -397.916788)
			(xy 440.405306 -397.862848) (xy 440.405306 -397.808352) (xy 440.413061 -397.754412) (xy 440.428413 -397.702123)
			(xy 440.45105 -397.652552) (xy 440.480511 -397.606707) (xy 440.516197 -397.565521) (xy 440.55738 -397.529832)
			(xy 440.603222 -397.500367) (xy 440.652792 -397.477725) (xy 440.705078 -397.462368) (xy 440.759018 -397.454609)
			(xy 440.786266 -397.45412) (xy 441.025026 -397.45412) (xy 441.055003 -397.454705) (xy 441.114218 -397.464099)
			(xy 441.171236 -397.482635) (xy 441.224655 -397.509859) (xy 441.27316 -397.5451) (xy 441.294774 -397.56588)
			(xy 443.012107 -399.2834) (xy 445.415396 -399.2834) (xy 445.419379 -399.230248) (xy 445.431241 -399.178283)
			(xy 445.450715 -399.128667) (xy 445.477367 -399.082508) (xy 445.510601 -399.040836) (xy 445.549675 -399.004584)
			(xy 445.593717 -398.974561) (xy 445.641741 -398.951438) (xy 445.692675 -398.935731) (xy 445.745381 -398.927791)
			(xy 445.772032 -398.92732) (xy 445.798392 -398.927815) (xy 445.850533 -398.9356) (xy 445.900956 -398.950994)
			(xy 445.948554 -398.973661) (xy 445.992286 -399.003103) (xy 446.012062 -399.020538) (xy 446.019174 -399.026888)
			(xy 446.036954 -399.033746) (xy 446.12433 -399.033746) (xy 446.14211 -399.026888) (xy 446.149222 -399.020538)
			(xy 446.169016 -399.003127) (xy 446.212754 -398.973702) (xy 446.260349 -398.95104) (xy 446.310763 -398.935634)
			(xy 446.362895 -398.92782) (xy 446.389252 -398.92732) (xy 446.415612 -398.927803) (xy 446.467754 -398.935591)
			(xy 446.518177 -398.950988) (xy 446.565775 -398.973657) (xy 446.609506 -399.003102) (xy 446.629282 -399.020538)
			(xy 446.636394 -399.026888) (xy 446.654174 -399.033746) (xy 446.74155 -399.033746) (xy 446.75933 -399.026888)
			(xy 446.766442 -399.020538) (xy 446.786228 -399.003117) (xy 446.829969 -398.973694) (xy 446.877566 -398.951034)
			(xy 446.927981 -398.93563) (xy 446.980115 -398.927819) (xy 447.006472 -398.92732) (xy 447.031468 -398.927745)
			(xy 447.080968 -398.93474) (xy 447.129005 -398.948582) (xy 447.174638 -398.968999) (xy 447.21697 -398.995592)
			(xy 447.236342 -399.011394) (xy 447.243454 -399.01749) (xy 447.259964 -399.023586) (xy 447.344038 -399.023586)
			(xy 447.360548 -399.01749) (xy 447.36766 -399.011394) (xy 447.387032 -398.995591) (xy 447.42936 -398.968989)
			(xy 447.474992 -398.948567) (xy 447.523031 -398.934727) (xy 447.572533 -398.92774) (xy 447.59753 -398.92732)
			(xy 447.624436 -398.927823) (xy 447.677639 -398.9359) (xy 447.72902 -398.951895) (xy 447.777406 -398.975444)
			(xy 447.821695 -399.00601) (xy 447.841624 -399.024094) (xy 447.848736 -399.030698) (xy 447.865754 -399.03781)
			(xy 447.953384 -399.039588) (xy 447.970656 -399.033238) (xy 447.978022 -399.026888) (xy 447.998965 -399.009317)
			(xy 448.044897 -398.979676) (xy 448.094591 -398.956895) (xy 448.147027 -398.941443) (xy 448.201133 -398.933634)
			(xy 448.228466 -398.933162) (xy 448.255718 -398.933683) (xy 448.309669 -398.941435) (xy 448.361966 -398.956787)
			(xy 448.411547 -398.979426) (xy 448.457401 -399.008891) (xy 448.498594 -399.044582) (xy 448.534289 -399.085772)
			(xy 448.563758 -399.131623) (xy 448.586401 -399.181202) (xy 448.601757 -399.233498) (xy 448.609515 -399.287448)
			(xy 448.609515 -399.341952) (xy 448.601757 -399.395902) (xy 448.586401 -399.448198) (xy 448.563758 -399.497777)
			(xy 448.534289 -399.543628) (xy 448.498594 -399.584818) (xy 448.457401 -399.620509) (xy 448.411547 -399.649974)
			(xy 448.361966 -399.672613) (xy 448.309669 -399.687965) (xy 448.255718 -399.695717) (xy 448.228466 -399.696178)
			(xy 448.202545 -399.69574) (xy 448.151182 -399.688705) (xy 448.101244 -399.674782) (xy 448.05365 -399.654229)
			(xy 448.009276 -399.627422) (xy 447.968939 -399.594855) (xy 447.950844 -399.57629) (xy 447.94424 -399.569178)
			(xy 447.927476 -399.561304) (xy 447.840354 -399.554446) (xy 447.822574 -399.559526) (xy 447.814954 -399.565622)
			(xy 447.79142 -399.582994) (xy 447.739865 -399.610621) (xy 447.684487 -399.629448) (xy 447.626776 -399.638967)
			(xy 447.59753 -399.639536) (xy 447.572535 -399.639096) (xy 447.523036 -399.632103) (xy 447.474999 -399.618264)
			(xy 447.429367 -399.59785) (xy 447.387033 -399.571261) (xy 447.36766 -399.555462) (xy 447.360548 -399.549366)
			(xy 447.344038 -399.54327) (xy 447.259964 -399.54327) (xy 447.243454 -399.549366) (xy 447.236342 -399.555462)
			(xy 447.216976 -399.571273) (xy 447.174646 -399.597872) (xy 447.129012 -399.618291) (xy 447.080972 -399.63213)
			(xy 447.031469 -399.639116) (xy 447.006472 -399.639536) (xy 446.980113 -399.639024) (xy 446.927973 -399.631241)
			(xy 446.877551 -399.61585) (xy 446.829953 -399.593188) (xy 446.78622 -399.56375) (xy 446.766442 -399.546318)
			(xy 446.75933 -399.539968) (xy 446.74155 -399.53311) (xy 446.654174 -399.53311) (xy 446.636394 -399.539968)
			(xy 446.629282 -399.546318) (xy 446.60948 -399.56372) (xy 446.565744 -399.593147) (xy 446.518152 -399.615812)
			(xy 446.46774 -399.63122) (xy 446.415608 -399.639035) (xy 446.389252 -399.639536) (xy 446.362893 -399.639036)
			(xy 446.310752 -399.63125) (xy 446.26033 -399.615856) (xy 446.212732 -399.593191) (xy 446.168999 -399.563751)
			(xy 446.149222 -399.546318) (xy 446.14211 -399.539968) (xy 446.12433 -399.53311) (xy 446.036954 -399.53311)
			(xy 446.019174 -399.539968) (xy 446.012062 -399.546318) (xy 445.992268 -399.563729) (xy 445.94853 -399.593155)
			(xy 445.900935 -399.615818) (xy 445.850522 -399.631224) (xy 445.798389 -399.639036) (xy 445.772032 -399.639536)
			(xy 445.745381 -399.639009) (xy 445.692675 -399.631069) (xy 445.641741 -399.615362) (xy 445.593716 -399.592239)
			(xy 445.549675 -399.562216) (xy 445.510601 -399.525964) (xy 445.477367 -399.484292) (xy 445.450715 -399.438133)
			(xy 445.431241 -399.388517) (xy 445.419379 -399.336552) (xy 445.415396 -399.2834) (xy 443.012107 -399.2834)
			(xy 443.625732 -399.897092) (xy 443.633206 -399.903795) (xy 443.651771 -399.911378) (xy 443.6618 -399.911824)
			(xy 445.595502 -399.911824) (xy 445.625479 -399.912423) (xy 445.684693 -399.921813) (xy 445.741711 -399.940346)
			(xy 445.79513 -399.967567) (xy 445.843635 -400.002805) (xy 445.86525 -400.023584) (xy 445.994516 -400.15287)
			(xy 447.338958 -400.15287) (xy 447.33945 -400.12562) (xy 447.34721 -400.071674) (xy 447.362567 -400.019381)
			(xy 447.385209 -399.969806) (xy 447.414675 -399.923958) (xy 447.450366 -399.882769) (xy 447.491554 -399.847078)
			(xy 447.537403 -399.817611) (xy 447.586978 -399.794968) (xy 447.63927 -399.77961) (xy 447.693216 -399.77185)
			(xy 447.720466 -399.771362) (xy 447.749383 -399.771881) (xy 447.806555 -399.780607) (xy 447.861755 -399.797863)
			(xy 447.913718 -399.823254) (xy 447.961251 -399.856199) (xy 448.003267 -399.895941) (xy 448.021456 -399.918428)
			(xy 448.029036 -399.92717) (xy 448.049781 -399.937363) (xy 448.061334 -399.937986) (xy 448.141598 -399.937986)
			(xy 448.153166 -399.937419) (xy 448.173937 -399.927222) (xy 448.181476 -399.918428) (xy 448.199688 -399.895962)
			(xy 448.241702 -399.856224) (xy 448.289233 -399.823282) (xy 448.34119 -399.797891) (xy 448.396384 -399.780631)
			(xy 448.453551 -399.771899) (xy 448.482466 -399.771362) (xy 448.509717 -399.771887) (xy 448.563664 -399.779638)
			(xy 448.615959 -399.794989) (xy 448.665537 -399.817625) (xy 448.711389 -399.847087) (xy 448.752581 -399.882774)
			(xy 448.788275 -399.92396) (xy 448.817744 -399.969807) (xy 448.840389 -400.019381) (xy 448.855748 -400.071674)
			(xy 448.863509 -400.125619) (xy 448.863649 -400.13382) (xy 449.300598 -400.13382) (xy 449.304669 -400.078198)
			(xy 449.316795 -400.023761) (xy 449.336718 -399.97167) (xy 449.364014 -399.923035) (xy 449.3981 -399.878892)
			(xy 449.438249 -399.840183) (xy 449.483607 -399.807732) (xy 449.533207 -399.782231) (xy 449.585991 -399.764224)
			(xy 449.640834 -399.754094) (xy 449.696568 -399.752057) (xy 449.752005 -399.758157) (xy 449.805962 -399.772263)
			(xy 449.857291 -399.794075) (xy 449.904897 -399.823129) (xy 449.947765 -399.858804) (xy 449.984982 -399.900341)
			(xy 450.015755 -399.946854) (xy 450.039427 -399.997351) (xy 450.055495 -400.050758) (xy 450.063615 -400.105934)
			(xy 450.064124 -400.13382) (xy 450.063615 -400.161706) (xy 450.055495 -400.216882) (xy 450.039427 -400.270289)
			(xy 450.015755 -400.320786) (xy 449.984982 -400.367299) (xy 449.947765 -400.408836) (xy 449.904897 -400.444511)
			(xy 449.857291 -400.473565) (xy 449.805962 -400.495377) (xy 449.752005 -400.509483) (xy 449.696568 -400.515583)
			(xy 449.640834 -400.513546) (xy 449.585991 -400.503416) (xy 449.533207 -400.485409) (xy 449.483607 -400.459908)
			(xy 449.438249 -400.427457) (xy 449.3981 -400.388748) (xy 449.364014 -400.344605) (xy 449.336718 -400.29597)
			(xy 449.316795 -400.243879) (xy 449.304669 -400.189442) (xy 449.300598 -400.13382) (xy 448.863649 -400.13382)
			(xy 448.863974 -400.15287) (xy 448.863572 -400.17856) (xy 448.856669 -400.229474) (xy 448.842996 -400.279001)
			(xy 448.8228 -400.326246) (xy 448.796448 -400.370354) (xy 448.764416 -400.410526) (xy 448.727283 -400.446038)
			(xy 448.706748 -400.46148) (xy 448.695572 -400.469608) (xy 448.684396 -400.495008) (xy 448.698366 -400.610578)
			(xy 448.71513 -400.632676) (xy 448.728084 -400.637756) (xy 448.754033 -400.648907) (xy 448.802616 -400.677708)
			(xy 448.846423 -400.713356) (xy 448.884496 -400.755072) (xy 448.916005 -400.801944) (xy 448.94026 -400.852948)
			(xy 448.956732 -400.90697) (xy 448.965062 -400.962831) (xy 448.965574 -400.99107) (xy 448.965117 -401.018324)
			(xy 448.957363 -401.072277) (xy 448.942009 -401.124577) (xy 448.919367 -401.174159) (xy 448.889899 -401.220014)
			(xy 448.854205 -401.261208) (xy 448.813011 -401.296902) (xy 448.767155 -401.326369) (xy 448.717573 -401.34901)
			(xy 448.665273 -401.364364) (xy 448.61132 -401.372117) (xy 448.584066 -401.372578) (xy 448.55515 -401.372021)
			(xy 448.497981 -401.363301) (xy 448.442782 -401.346051) (xy 448.39082 -401.320667) (xy 448.343285 -401.28773)
			(xy 448.301267 -401.247995) (xy 448.283076 -401.225512) (xy 448.275518 -401.216746) (xy 448.254757 -401.206564)
			(xy 448.243198 -401.205954) (xy 448.162934 -401.205954) (xy 448.151366 -401.206525) (xy 448.130594 -401.216717)
			(xy 448.123056 -401.225512) (xy 448.104893 -401.248019) (xy 448.062867 -401.287752) (xy 448.015326 -401.320688)
			(xy 447.963359 -401.346072) (xy 447.908157 -401.363323) (xy 447.850984 -401.372046) (xy 447.822066 -401.372578)
			(xy 447.794813 -401.372154) (xy 447.740861 -401.364392) (xy 447.688563 -401.349031) (xy 447.638984 -401.326384)
			(xy 447.593132 -401.296911) (xy 447.551942 -401.261213) (xy 447.516251 -401.220016) (xy 447.486786 -401.17416)
			(xy 447.464147 -401.124577) (xy 447.448795 -401.072276) (xy 447.441042 -401.018324) (xy 447.440558 -400.99107)
			(xy 447.440976 -400.96538) (xy 447.447875 -400.914467) (xy 447.461545 -400.864939) (xy 447.481737 -400.817694)
			(xy 447.508086 -400.773586) (xy 447.540117 -400.733413) (xy 447.577249 -400.697902) (xy 447.597784 -400.68246)
			(xy 447.60896 -400.674332) (xy 447.620136 -400.648932) (xy 447.606166 -400.533362) (xy 447.589402 -400.511264)
			(xy 447.576448 -400.506184) (xy 447.550498 -400.495035) (xy 447.501919 -400.466229) (xy 447.458116 -400.430579)
			(xy 447.420045 -400.388863) (xy 447.388537 -400.341991) (xy 447.364281 -400.290988) (xy 447.347806 -400.236967)
			(xy 447.339473 -400.181108) (xy 447.338958 -400.15287) (xy 445.994516 -400.15287) (xy 447.535554 -401.694142)
			(xy 447.54301 -401.700902) (xy 447.561571 -401.708623) (xy 447.571622 -401.709128) (xy 449.10629 -401.709128)
			(xy 449.116361 -401.708716) (xy 449.13496 -401.700988) (xy 449.142358 -401.694142) (xy 450.27977 -400.55673)
			(xy 450.286585 -400.54931) (xy 450.29432 -400.530726) (xy 450.294756 -400.520662) (xy 450.294756 -399.212308)
			(xy 450.294279 -399.202375) (xy 450.286706 -399.184006) (xy 450.272729 -399.169886) (xy 450.263768 -399.165572)
			(xy 450.163692 -399.1229) (xy 450.133466 -399.128488) (xy 450.122544 -399.139156) (xy 450.101084 -399.159057)
			(xy 450.05322 -399.192736) (xy 450.000775 -399.218711) (xy 449.944978 -399.236372) (xy 449.887139 -399.245306)
			(xy 449.857876 -399.245836) (xy 449.830628 -399.245292) (xy 449.776687 -399.237533) (xy 449.724399 -399.222177)
			(xy 449.674828 -399.199537) (xy 449.628984 -399.170072) (xy 449.5878 -399.134383) (xy 449.552114 -399.093196)
			(xy 449.522652 -399.047351) (xy 449.500014 -398.997779) (xy 449.484661 -398.94549) (xy 449.476906 -398.891548)
			(xy 449.476906 -398.837052) (xy 449.484661 -398.78311) (xy 449.500014 -398.730821) (xy 449.522652 -398.681249)
			(xy 449.552114 -398.635404) (xy 449.5878 -398.594217) (xy 449.628984 -398.558528) (xy 449.674828 -398.529063)
			(xy 449.724399 -398.506423) (xy 449.776687 -398.491067) (xy 449.830628 -398.483308) (xy 449.857876 -398.48282)
			(xy 449.887134 -398.483423) (xy 449.944963 -398.49236) (xy 450.000753 -398.510013) (xy 450.053197 -398.53597)
			(xy 450.101068 -398.569622) (xy 450.122544 -398.5895) (xy 450.133466 -398.600168) (xy 450.163692 -398.605756)
			(xy 450.263768 -398.563084) (xy 450.272739 -398.558783) (xy 450.286731 -398.544668) (xy 450.294288 -398.526286)
			(xy 450.294756 -398.516348) (xy 450.294756 -398.487646) (xy 450.294318 -398.477578) (xy 450.286607 -398.458979)
			(xy 450.27977 -398.451578) (xy 450.18706 -398.358868) (xy 450.179582 -398.35217) (xy 450.16102 -398.344582)
			(xy 450.150992 -398.344136) (xy 449.854066 -398.344136) (xy 449.826818 -398.343591) (xy 449.772878 -398.335832)
			(xy 449.720592 -398.320475) (xy 449.671022 -398.297833) (xy 449.62518 -398.268368) (xy 449.583997 -398.232679)
			(xy 449.548311 -398.191493) (xy 449.51885 -398.145648) (xy 449.496213 -398.096077) (xy 449.480861 -398.043788)
			(xy 449.473106 -397.989848) (xy 449.473106 -397.935352) (xy 449.480861 -397.881412) (xy 449.496213 -397.829123)
			(xy 449.51885 -397.779552) (xy 449.548311 -397.733707) (xy 449.583997 -397.692521) (xy 449.62518 -397.656832)
			(xy 449.671022 -397.627367) (xy 449.720592 -397.604725) (xy 449.772878 -397.589368) (xy 449.826818 -397.581609)
			(xy 449.854066 -397.58112) (xy 450.330062 -397.58112) (xy 450.360038 -397.581745) (xy 450.419251 -397.591129)
			(xy 450.476268 -397.609656) (xy 450.529688 -397.636871) (xy 450.578194 -397.672103) (xy 450.59981 -397.69288)
			(xy 450.945758 -398.038828) (xy 450.966505 -398.06046) (xy 451.001693 -398.108976) (xy 451.028864 -398.162396)
			(xy 451.047348 -398.219408) (xy 451.056691 -398.278609) (xy 451.057264 -398.308576) (xy 451.057264 -399.2834)
			(xy 454.494221 -399.2834) (xy 454.498203 -399.230259) (xy 454.51006 -399.178305) (xy 454.529528 -399.128698)
			(xy 454.556171 -399.082546) (xy 454.589394 -399.040881) (xy 454.628456 -399.004632) (xy 454.672484 -398.974609)
			(xy 454.720494 -398.951483) (xy 454.771415 -398.93577) (xy 454.824109 -398.927821) (xy 454.850754 -398.92732)
			(xy 454.877114 -398.927802) (xy 454.929257 -398.93559) (xy 454.979679 -398.950987) (xy 455.027277 -398.973657)
			(xy 455.071008 -399.003102) (xy 455.090784 -399.020538) (xy 455.097896 -399.026888) (xy 455.115676 -399.033746)
			(xy 455.203052 -399.033746) (xy 455.220832 -399.026888) (xy 455.227944 -399.020538) (xy 455.247729 -399.003116)
			(xy 455.29147 -398.973694) (xy 455.339067 -398.951033) (xy 455.389482 -398.93563) (xy 455.441616 -398.927819)
			(xy 455.467974 -398.92732) (xy 455.494335 -398.92779) (xy 455.546478 -398.935581) (xy 455.5969 -398.950981)
			(xy 455.644498 -398.973653) (xy 455.688228 -399.003101) (xy 455.708004 -399.020538) (xy 455.715116 -399.026888)
			(xy 455.732896 -399.033746) (xy 455.820272 -399.033746) (xy 455.838052 -399.026888) (xy 455.845164 -399.020538)
			(xy 455.864941 -399.003107) (xy 455.908684 -398.973685) (xy 455.956283 -398.951027) (xy 456.0067 -398.935626)
			(xy 456.058836 -398.927817) (xy 456.085194 -398.92732) (xy 456.11019 -398.927733) (xy 456.159691 -398.93473)
			(xy 456.207729 -398.948575) (xy 456.253361 -398.968996) (xy 456.295692 -398.995591) (xy 456.315064 -399.011394)
			(xy 456.322176 -399.01749) (xy 456.338686 -399.023586) (xy 456.42276 -399.023586) (xy 456.43927 -399.01749)
			(xy 456.446382 -399.011394) (xy 456.465746 -398.995581) (xy 456.508076 -398.96898) (xy 456.55371 -398.94856)
			(xy 456.601751 -398.934722) (xy 456.651255 -398.927738) (xy 456.676252 -398.92732) (xy 456.701833 -398.927781)
			(xy 456.75247 -398.935097) (xy 456.801538 -398.949585) (xy 456.848027 -398.970947) (xy 456.89098 -398.998743)
			(xy 456.929513 -399.032401) (xy 456.946508 -399.051526) (xy 456.952858 -399.059146) (xy 456.97013 -399.068036)
			(xy 457.059792 -399.076926) (xy 457.078334 -399.071338) (xy 457.086208 -399.065242) (xy 457.106427 -399.049888)
			(xy 457.150186 -399.024146) (xy 457.196972 -399.004433) (xy 457.245959 -398.991098) (xy 457.296281 -398.984375)
			(xy 457.321666 -398.983962) (xy 457.348918 -398.984483) (xy 457.402869 -398.992235) (xy 457.455166 -399.007587)
			(xy 457.504747 -399.030226) (xy 457.550601 -399.059691) (xy 457.591794 -399.095382) (xy 457.627489 -399.136572)
			(xy 457.656958 -399.182423) (xy 457.679601 -399.232002) (xy 457.694957 -399.284298) (xy 457.702715 -399.338248)
			(xy 457.702715 -399.392752) (xy 457.694957 -399.446702) (xy 457.679601 -399.498998) (xy 457.656958 -399.548577)
			(xy 457.627489 -399.594428) (xy 457.591794 -399.635618) (xy 457.550601 -399.671309) (xy 457.504747 -399.700774)
			(xy 457.455166 -399.723413) (xy 457.402869 -399.738765) (xy 457.348918 -399.746517) (xy 457.321666 -399.746978)
			(xy 457.292465 -399.746417) (xy 457.234744 -399.737518) (xy 457.179057 -399.719918) (xy 457.126706 -399.694029)
			(xy 457.078917 -399.660458) (xy 457.036808 -399.619989) (xy 457.018644 -399.597118) (xy 457.012548 -399.589244)
			(xy 456.996038 -399.579338) (xy 456.906884 -399.565622) (xy 456.888088 -399.56994) (xy 456.87996 -399.575528)
			(xy 456.857414 -399.59061) (xy 456.808731 -399.61453) (xy 456.756986 -399.630793) (xy 456.703373 -399.639024)
			(xy 456.676252 -399.639536) (xy 456.651257 -399.639084) (xy 456.601759 -399.632094) (xy 456.553722 -399.618257)
			(xy 456.508089 -399.597846) (xy 456.465756 -399.57126) (xy 456.446382 -399.555462) (xy 456.43927 -399.549366)
			(xy 456.42276 -399.54327) (xy 456.338686 -399.54327) (xy 456.322176 -399.549366) (xy 456.315064 -399.555462)
			(xy 456.29569 -399.571262) (xy 456.253362 -399.597863) (xy 456.207731 -399.618285) (xy 456.159692 -399.632126)
			(xy 456.11019 -399.639114) (xy 456.085194 -399.639536) (xy 456.058833 -399.639071) (xy 456.006691 -399.631277)
			(xy 455.956269 -399.615875) (xy 455.908672 -399.593202) (xy 455.86494 -399.563754) (xy 455.845164 -399.546318)
			(xy 455.838052 -399.539968) (xy 455.820272 -399.53311) (xy 455.732896 -399.53311) (xy 455.715116 -399.539968)
			(xy 455.708004 -399.546318) (xy 455.688233 -399.563757) (xy 455.644489 -399.593179) (xy 455.596888 -399.615836)
			(xy 455.54647 -399.631236) (xy 455.494333 -399.639041) (xy 455.467974 -399.639536) (xy 455.441615 -399.639023)
			(xy 455.389475 -399.63124) (xy 455.339054 -399.615849) (xy 455.291455 -399.593187) (xy 455.247722 -399.56375)
			(xy 455.227944 -399.546318) (xy 455.220832 -399.539968) (xy 455.203052 -399.53311) (xy 455.115676 -399.53311)
			(xy 455.097896 -399.539968) (xy 455.090784 -399.546318) (xy 455.070981 -399.563719) (xy 455.027246 -399.593146)
			(xy 454.979653 -399.615811) (xy 454.929242 -399.631219) (xy 454.87711 -399.639035) (xy 454.850754 -399.639536)
			(xy 454.824109 -399.638979) (xy 454.771415 -399.63103) (xy 454.720494 -399.615317) (xy 454.672484 -399.592191)
			(xy 454.628456 -399.562168) (xy 454.589394 -399.525919) (xy 454.556171 -399.484254) (xy 454.529528 -399.438102)
			(xy 454.51006 -399.388495) (xy 454.498203 -399.336541) (xy 454.494221 -399.2834) (xy 451.057264 -399.2834)
			(xy 451.057264 -400.20367) (xy 456.432158 -400.20367) (xy 456.43265 -400.17642) (xy 456.44041 -400.122474)
			(xy 456.455767 -400.070181) (xy 456.478409 -400.020606) (xy 456.507875 -399.974758) (xy 456.543566 -399.933569)
			(xy 456.584754 -399.897878) (xy 456.630603 -399.868411) (xy 456.680178 -399.845768) (xy 456.73247 -399.83041)
			(xy 456.786416 -399.82265) (xy 456.813666 -399.822162) (xy 456.842583 -399.822681) (xy 456.899755 -399.831407)
			(xy 456.954955 -399.848663) (xy 457.006918 -399.874054) (xy 457.054451 -399.906999) (xy 457.096467 -399.946741)
			(xy 457.114656 -399.969228) (xy 457.122236 -399.97797) (xy 457.142981 -399.988163) (xy 457.154534 -399.988786)
			(xy 457.234798 -399.988786) (xy 457.246366 -399.988219) (xy 457.267137 -399.978022) (xy 457.274676 -399.969228)
			(xy 457.292888 -399.946762) (xy 457.334902 -399.907024) (xy 457.382433 -399.874082) (xy 457.43439 -399.848691)
			(xy 457.489584 -399.831431) (xy 457.546751 -399.822699) (xy 457.575666 -399.822162) (xy 457.602917 -399.822687)
			(xy 457.656864 -399.830438) (xy 457.709159 -399.845789) (xy 457.758737 -399.868425) (xy 457.804589 -399.897887)
			(xy 457.845781 -399.933574) (xy 457.881475 -399.97476) (xy 457.910944 -400.020607) (xy 457.933589 -400.070181)
			(xy 457.948948 -400.122474) (xy 457.956709 -400.176419) (xy 457.957174 -400.20367) (xy 457.956772 -400.22936)
			(xy 457.949869 -400.280274) (xy 457.936196 -400.329801) (xy 457.916 -400.377046) (xy 457.889648 -400.421154)
			(xy 457.857616 -400.461326) (xy 457.820483 -400.496838) (xy 457.799948 -400.51228) (xy 457.788772 -400.520408)
			(xy 457.777596 -400.545808) (xy 457.791566 -400.661378) (xy 457.80833 -400.683476) (xy 457.821284 -400.688556)
			(xy 457.847233 -400.699707) (xy 457.895816 -400.728508) (xy 457.939623 -400.764156) (xy 457.977696 -400.805872)
			(xy 458.009205 -400.852744) (xy 458.03346 -400.903748) (xy 458.049932 -400.95777) (xy 458.058262 -401.013631)
			(xy 458.058774 -401.04187) (xy 458.058317 -401.069124) (xy 458.050563 -401.123077) (xy 458.035209 -401.175377)
			(xy 458.012567 -401.224959) (xy 457.983099 -401.270814) (xy 457.947405 -401.312008) (xy 457.906211 -401.347702)
			(xy 457.860355 -401.377169) (xy 457.810773 -401.39981) (xy 457.758473 -401.415164) (xy 457.70452 -401.422917)
			(xy 457.677266 -401.423378) (xy 457.64835 -401.422821) (xy 457.591181 -401.414101) (xy 457.535982 -401.396851)
			(xy 457.48402 -401.371467) (xy 457.436485 -401.33853) (xy 457.394467 -401.298795) (xy 457.376276 -401.276312)
			(xy 457.368718 -401.267546) (xy 457.347957 -401.257364) (xy 457.336398 -401.256754) (xy 457.256134 -401.256754)
			(xy 457.244566 -401.257325) (xy 457.223794 -401.267517) (xy 457.216256 -401.276312) (xy 457.198093 -401.298819)
			(xy 457.156067 -401.338552) (xy 457.108526 -401.371488) (xy 457.056559 -401.396872) (xy 457.001357 -401.414123)
			(xy 456.944184 -401.422846) (xy 456.915266 -401.423378) (xy 456.888013 -401.422954) (xy 456.834061 -401.415192)
			(xy 456.781763 -401.399831) (xy 456.732184 -401.377184) (xy 456.686332 -401.347711) (xy 456.645142 -401.312013)
			(xy 456.609451 -401.270816) (xy 456.579986 -401.22496) (xy 456.557347 -401.175377) (xy 456.541995 -401.123076)
			(xy 456.534242 -401.069124) (xy 456.533758 -401.04187) (xy 456.534176 -401.01618) (xy 456.541075 -400.965267)
			(xy 456.554745 -400.915739) (xy 456.574937 -400.868494) (xy 456.601286 -400.824386) (xy 456.633317 -400.784213)
			(xy 456.670449 -400.748702) (xy 456.690984 -400.73326) (xy 456.70216 -400.725132) (xy 456.713336 -400.699732)
			(xy 456.699366 -400.584162) (xy 456.682602 -400.562064) (xy 456.669648 -400.556984) (xy 456.643698 -400.545835)
			(xy 456.595119 -400.517029) (xy 456.551316 -400.481379) (xy 456.513245 -400.439663) (xy 456.481737 -400.392791)
			(xy 456.457481 -400.341788) (xy 456.441006 -400.287767) (xy 456.432673 -400.231908) (xy 456.432158 -400.20367)
			(xy 451.057264 -400.20367) (xy 451.057264 -400.699732) (xy 451.056722 -400.729704) (xy 451.047407 -400.788919)
			(xy 451.028934 -400.845944) (xy 451.001757 -400.899372) (xy 450.966548 -400.947885) (xy 450.945758 -400.96948)
			(xy 450.042026 -401.873212) (xy 451.885048 -401.873212) (xy 451.889119 -401.81759) (xy 451.901245 -401.763153)
			(xy 451.921168 -401.711062) (xy 451.948464 -401.662427) (xy 451.98255 -401.618284) (xy 452.022699 -401.579575)
			(xy 452.068057 -401.547124) (xy 452.117657 -401.521623) (xy 452.170441 -401.503616) (xy 452.225284 -401.493486)
			(xy 452.281018 -401.491449) (xy 452.336455 -401.497549) (xy 452.390412 -401.511655) (xy 452.441741 -401.533467)
			(xy 452.489347 -401.562521) (xy 452.532215 -401.598196) (xy 452.569432 -401.639733) (xy 452.600205 -401.686246)
			(xy 452.623877 -401.736743) (xy 452.639945 -401.79015) (xy 452.648065 -401.845326) (xy 452.648574 -401.873212)
			(xy 452.648065 -401.901098) (xy 452.639945 -401.956274) (xy 452.623877 -402.009681) (xy 452.600205 -402.060178)
			(xy 452.569432 -402.106691) (xy 452.532215 -402.148228) (xy 452.489347 -402.183903) (xy 452.441741 -402.212957)
			(xy 452.390412 -402.234769) (xy 452.336455 -402.248875) (xy 452.281018 -402.254975) (xy 452.225284 -402.252938)
			(xy 452.170441 -402.242808) (xy 452.117657 -402.224801) (xy 452.068057 -402.1993) (xy 452.022699 -402.166849)
			(xy 451.98255 -402.12814) (xy 451.948464 -402.083997) (xy 451.921168 -402.035362) (xy 451.901245 -401.983271)
			(xy 451.889119 -401.928834) (xy 451.885048 -401.873212) (xy 450.042026 -401.873212) (xy 449.555108 -402.36013)
			(xy 449.5335 -402.380903) (xy 449.484978 -402.416089) (xy 449.431551 -402.443255) (xy 449.374534 -402.461733)
			(xy 449.315329 -402.471068) (xy 449.28536 -402.471636) (xy 447.392552 -402.471636) (xy 447.362579 -402.471113)
			(xy 447.303363 -402.461794) (xy 447.246338 -402.443317) (xy 447.19291 -402.416136) (xy 447.144398 -402.380923)
			(xy 447.122804 -402.36013) (xy 445.4525 -400.689572) (xy 445.445008 -400.682892) (xy 445.426457 -400.675294)
			(xy 445.416432 -400.67484) (xy 445.201548 -400.67484) (xy 445.191108 -400.675348) (xy 445.171917 -400.683559)
			(xy 445.157576 -400.698729) (xy 445.153542 -400.708368) (xy 445.11595 -400.813778) (xy 445.124586 -400.844766)
			(xy 445.137286 -400.854926) (xy 445.158776 -400.873136) (xy 445.196647 -400.914834) (xy 445.22798 -400.961643)
			(xy 445.252094 -401.012549) (xy 445.268465 -401.066446) (xy 445.276738 -401.122164) (xy 445.27724 -401.150328)
			(xy 445.276754 -401.177579) (xy 445.268998 -401.231527) (xy 445.253643 -401.283822) (xy 445.231001 -401.333399)
			(xy 445.201535 -401.379249) (xy 445.165844 -401.42044) (xy 445.124653 -401.456131) (xy 445.078803 -401.485597)
			(xy 445.029226 -401.508239) (xy 444.976931 -401.523594) (xy 444.922983 -401.53135) (xy 444.868481 -401.53135)
			(xy 444.814533 -401.523594) (xy 444.762238 -401.508239) (xy 444.712661 -401.485597) (xy 444.666811 -401.456131)
			(xy 444.62562 -401.42044) (xy 444.589929 -401.379249) (xy 444.560463 -401.333399) (xy 444.537821 -401.283822)
			(xy 444.522466 -401.231527) (xy 444.51471 -401.177579) (xy 444.514224 -401.150328) (xy 444.514693 -401.122164)
			(xy 444.52298 -401.066448) (xy 444.539362 -401.012554) (xy 444.563485 -400.961652) (xy 444.594825 -400.914846)
			(xy 444.632701 -400.873153) (xy 444.654178 -400.854926) (xy 444.666878 -400.844766) (xy 444.675514 -400.813778)
			(xy 444.637922 -400.708368) (xy 444.633918 -400.698706) (xy 444.619576 -400.68351) (xy 444.600366 -400.675289)
			(xy 444.589916 -400.67484) (xy 443.48273 -400.67484) (xy 443.452753 -400.674231) (xy 443.393539 -400.664845)
			(xy 443.336521 -400.646315) (xy 443.283102 -400.619096) (xy 443.234597 -400.583859) (xy 443.212982 -400.56308)
			(xy 441.333636 -398.683734) (xy 441.326386 -398.677068) (xy 441.308276 -398.669375) (xy 441.288601 -398.669123)
			(xy 441.27928 -398.672304) (xy 441.178442 -398.711928) (xy 441.160916 -398.736566) (xy 441.160408 -398.751806)
			(xy 441.158889 -398.778358) (xy 441.149507 -398.830705) (xy 441.132945 -398.881242) (xy 441.109525 -398.928989)
			(xy 441.079702 -398.973021) (xy 441.044052 -399.012484) (xy 441.003267 -399.046614) (xy 440.958137 -399.074748)
			(xy 440.909537 -399.096343) (xy 440.858409 -399.110978) (xy 440.805745 -399.118372) (xy 440.779154 -399.118836)
			(xy 440.751907 -399.118291) (xy 440.697968 -399.110529) (xy 440.645683 -399.095171) (xy 440.596115 -399.072529)
			(xy 440.550274 -399.043064) (xy 440.509092 -399.007375) (xy 440.473408 -398.966189) (xy 440.443949 -398.920344)
			(xy 440.421312 -398.870774) (xy 440.405961 -398.818487) (xy 440.398206 -398.764547) (xy 440.220608 -398.764547)
			(xy 440.220608 -401.44192) (xy 440.397898 -401.44192) (xy 440.401969 -401.386298) (xy 440.414095 -401.331861)
			(xy 440.434018 -401.27977) (xy 440.461314 -401.231135) (xy 440.4954 -401.186992) (xy 440.535549 -401.148283)
			(xy 440.580907 -401.115832) (xy 440.630507 -401.090331) (xy 440.683291 -401.072324) (xy 440.738134 -401.062194)
			(xy 440.793868 -401.060157) (xy 440.849305 -401.066257) (xy 440.903262 -401.080363) (xy 440.954591 -401.102175)
			(xy 441.002197 -401.131229) (xy 441.045065 -401.166904) (xy 441.082282 -401.208441) (xy 441.113055 -401.254954)
			(xy 441.136727 -401.305451) (xy 441.152795 -401.358858) (xy 441.160915 -401.414034) (xy 441.161424 -401.44192)
			(xy 441.160915 -401.469806) (xy 441.152795 -401.524982) (xy 441.136727 -401.578389) (xy 441.113055 -401.628886)
			(xy 441.082282 -401.675399) (xy 441.045065 -401.716936) (xy 441.002197 -401.752611) (xy 440.954591 -401.781665)
			(xy 440.903262 -401.803477) (xy 440.849305 -401.817583) (xy 440.793868 -401.823683) (xy 440.738134 -401.821646)
			(xy 440.683291 -401.811516) (xy 440.630507 -401.793509) (xy 440.580907 -401.768008) (xy 440.535549 -401.735557)
			(xy 440.4954 -401.696848) (xy 440.461314 -401.652705) (xy 440.434018 -401.60407) (xy 440.414095 -401.551979)
			(xy 440.401969 -401.497542) (xy 440.397898 -401.44192) (xy 440.220608 -401.44192) (xy 440.220608 -402.41982)
			(xy 440.683648 -402.41982) (xy 440.687719 -402.364198) (xy 440.699845 -402.309761) (xy 440.719768 -402.25767)
			(xy 440.747064 -402.209035) (xy 440.78115 -402.164892) (xy 440.821299 -402.126183) (xy 440.866657 -402.093732)
			(xy 440.916257 -402.068231) (xy 440.969041 -402.050224) (xy 441.023884 -402.040094) (xy 441.079618 -402.038057)
			(xy 441.135055 -402.044157) (xy 441.189012 -402.058263) (xy 441.240341 -402.080075) (xy 441.287947 -402.109129)
			(xy 441.330815 -402.144804) (xy 441.368032 -402.186341) (xy 441.398805 -402.232854) (xy 441.422477 -402.283351)
			(xy 441.438545 -402.336758) (xy 441.446665 -402.391934) (xy 441.447174 -402.41982) (xy 441.446665 -402.447706)
			(xy 441.438545 -402.502882) (xy 441.422477 -402.556289) (xy 441.398805 -402.606786) (xy 441.368032 -402.653299)
			(xy 441.330815 -402.694836) (xy 441.287947 -402.730511) (xy 441.240341 -402.759565) (xy 441.189012 -402.781377)
			(xy 441.135055 -402.795483) (xy 441.079618 -402.801583) (xy 441.023884 -402.799546) (xy 440.969041 -402.789416)
			(xy 440.916257 -402.771409) (xy 440.866657 -402.745908) (xy 440.821299 -402.713457) (xy 440.78115 -402.674748)
			(xy 440.747064 -402.630605) (xy 440.719768 -402.58197) (xy 440.699845 -402.529879) (xy 440.687719 -402.475442)
			(xy 440.683648 -402.41982) (xy 440.220608 -402.41982) (xy 440.220608 -405.3459) (xy 440.221001 -405.355943)
			(xy 440.228574 -405.374539) (xy 440.23534 -405.381968) (xy 440.97194 -406.118568) (xy 440.989243 -406.136625)
			(xy 441.017057 -406.178179) (xy 441.03623 -406.224362) (xy 441.046024 -406.273398) (xy 441.046616 -406.2984)
			(xy 441.046616 -414.038796) (xy 441.53836 -414.038796) (xy 441.53836 -405.533098) (xy 441.538884 -405.51062)
			(xy 441.546857 -405.466374) (xy 441.562453 -405.424207) (xy 441.573412 -405.404574) (xy 441.581853 -405.390678)
			(xy 441.601724 -405.364944) (xy 441.613036 -405.353266) (xy 442.345826 -404.620476) (xy 442.352673 -404.613081)
			(xy 442.360388 -404.594478) (xy 442.360812 -404.584408) (xy 442.360812 -402.870416) (xy 442.361462 -402.845435)
			(xy 442.371195 -402.796429) (xy 442.390291 -402.75026) (xy 442.418018 -402.708696) (xy 442.435234 -402.690584)
			(xy 443.127638 -401.99818) (xy 443.139309 -401.98686) (xy 443.165046 -401.966991) (xy 443.178946 -401.958556)
			(xy 443.198564 -401.947563) (xy 443.24073 -401.931944) (xy 443.284988 -401.923999) (xy 443.30747 -401.923504)
			(xy 443.385956 -401.923504) (xy 443.404752 -401.915884) (xy 443.411864 -401.908518) (xy 443.433454 -401.887655)
			(xy 443.48199 -401.852322) (xy 443.535464 -401.825032) (xy 443.592553 -401.806458) (xy 443.651848 -401.79706)
			(xy 443.681866 -401.796504) (xy 443.709142 -401.796988) (xy 443.763137 -401.804754) (xy 443.815476 -401.820132)
			(xy 443.865091 -401.842809) (xy 443.910969 -401.872321) (xy 443.952176 -401.908068) (xy 443.98787 -401.949321)
			(xy 444.017324 -401.995237) (xy 444.039938 -402.04488) (xy 444.055249 -402.097238) (xy 444.062946 -402.151244)
			(xy 444.063374 -402.17852) (xy 444.063374 -402.178774) (xy 444.063793 -402.188844) (xy 444.069842 -402.203412)
			(xy 445.01003 -402.203412) (xy 445.014101 -402.14779) (xy 445.026227 -402.093353) (xy 445.04615 -402.041262)
			(xy 445.073446 -401.992627) (xy 445.107532 -401.948484) (xy 445.147681 -401.909775) (xy 445.193039 -401.877324)
			(xy 445.242639 -401.851823) (xy 445.295423 -401.833816) (xy 445.350266 -401.823686) (xy 445.406 -401.821649)
			(xy 445.461437 -401.827749) (xy 445.515394 -401.841855) (xy 445.566723 -401.863667) (xy 445.614329 -401.892721)
			(xy 445.657197 -401.928396) (xy 445.694414 -401.969933) (xy 445.725187 -402.016446) (xy 445.748859 -402.066943)
			(xy 445.764927 -402.12035) (xy 445.773047 -402.175526) (xy 445.773556 -402.203412) (xy 445.773047 -402.231298)
			(xy 445.764927 -402.286474) (xy 445.748859 -402.339881) (xy 445.725187 -402.390378) (xy 445.694414 -402.436891)
			(xy 445.657197 -402.478428) (xy 445.614329 -402.514103) (xy 445.566723 -402.543157) (xy 445.515394 -402.564969)
			(xy 445.461437 -402.579075) (xy 445.406 -402.585175) (xy 445.350266 -402.583138) (xy 445.295423 -402.573008)
			(xy 445.242639 -402.555001) (xy 445.193039 -402.5295) (xy 445.147681 -402.497049) (xy 445.107532 -402.45834)
			(xy 445.073446 -402.414197) (xy 445.04615 -402.365562) (xy 445.026227 -402.313471) (xy 445.014101 -402.259034)
			(xy 445.01003 -402.203412) (xy 444.069842 -402.203412) (xy 444.071516 -402.207443) (xy 444.07836 -402.214842)
			(xy 444.565066 -402.701548) (xy 450.670706 -402.701548) (xy 450.670706 -402.647052) (xy 450.678461 -402.59311)
			(xy 450.693814 -402.540821) (xy 450.716452 -402.491249) (xy 450.745914 -402.445404) (xy 450.7816 -402.404217)
			(xy 450.822784 -402.368528) (xy 450.868628 -402.339063) (xy 450.918199 -402.316423) (xy 450.970487 -402.301067)
			(xy 451.024428 -402.293308) (xy 451.051676 -402.29282) (xy 451.080593 -402.293348) (xy 451.137764 -402.302074)
			(xy 451.192963 -402.31933) (xy 451.244925 -402.344719) (xy 451.292459 -402.377661) (xy 451.334476 -402.417401)
			(xy 451.352666 -402.439886) (xy 451.360249 -402.448626) (xy 451.380992 -402.458822) (xy 451.392544 -402.459444)
			(xy 451.472808 -402.459444) (xy 451.48438 -402.458898) (xy 451.505151 -402.448688) (xy 451.512686 -402.439886)
			(xy 451.530881 -402.417406) (xy 451.572901 -402.377672) (xy 451.620435 -402.344732) (xy 451.672395 -402.319344)
			(xy 451.727592 -402.302086) (xy 451.78476 -402.293356) (xy 451.813676 -402.29282) (xy 451.840932 -402.293225)
			(xy 451.89489 -402.30098) (xy 451.947194 -402.316335) (xy 451.996781 -402.338978) (xy 452.042641 -402.368448)
			(xy 452.083839 -402.404144) (xy 452.119538 -402.44534) (xy 452.149011 -402.491198) (xy 452.171656 -402.540783)
			(xy 452.187015 -402.593087) (xy 452.194773 -402.647044) (xy 452.194773 -402.701556) (xy 452.187015 -402.755513)
			(xy 452.171656 -402.807817) (xy 452.149011 -402.857402) (xy 452.119538 -402.90326) (xy 452.083839 -402.944456)
			(xy 452.042641 -402.980152) (xy 451.996781 -403.009622) (xy 451.947194 -403.032265) (xy 451.89489 -403.04762)
			(xy 451.840932 -403.055375) (xy 451.813676 -403.055836) (xy 451.78476 -403.055287) (xy 451.727589 -403.046568)
			(xy 451.67239 -403.029318) (xy 451.620427 -403.003932) (xy 451.572893 -402.970992) (xy 451.530876 -402.931254)
			(xy 451.512686 -402.90877) (xy 451.505131 -402.900001) (xy 451.484367 -402.889823) (xy 451.472808 -402.889212)
			(xy 451.392544 -402.889212) (xy 451.380979 -402.889803) (xy 451.360207 -402.899983) (xy 451.352666 -402.90877)
			(xy 451.334487 -402.931264) (xy 451.292465 -402.970999) (xy 451.244928 -403.003938) (xy 451.192965 -403.029325)
			(xy 451.137765 -403.046579) (xy 451.080593 -403.055304) (xy 451.051676 -403.055836) (xy 451.024428 -403.055292)
			(xy 450.970487 -403.047533) (xy 450.918199 -403.032177) (xy 450.868628 -403.009537) (xy 450.822784 -402.980072)
			(xy 450.7816 -402.944383) (xy 450.745914 -402.903196) (xy 450.716452 -402.857351) (xy 450.693814 -402.807779)
			(xy 450.678461 -402.75549) (xy 450.670706 -402.701548) (xy 444.565066 -402.701548) (xy 445.202056 -403.338538)
			(xy 445.209415 -403.345216) (xy 445.227698 -403.352943) (xy 445.237616 -403.353524) (xy 445.238124 -403.353524)
			(xy 452.169276 -403.353524) (xy 452.179202 -403.352958) (xy 452.197505 -403.345252) (xy 452.204836 -403.338538)
			(xy 452.488808 -403.054566) (xy 452.492293 -403.05095) (xy 452.49792 -403.042634) (xy 452.499984 -403.038056)
			(xy 453.030336 -401.757642) (xy 453.03313 -401.749006) (xy 453.0344 -401.73783) (xy 453.0344 -401.363942)
			(xy 453.033892 -401.356576) (xy 453.032381 -401.348513) (xy 453.025008 -401.333872) (xy 453.019414 -401.327874)
			(xy 452.99849 -401.306293) (xy 452.963082 -401.25772) (xy 452.935733 -401.204193) (xy 452.91712 -401.147039)
			(xy 452.907703 -401.087673) (xy 452.907146 -401.057618) (xy 452.907695 -401.030369) (xy 452.915448 -400.976426)
			(xy 452.930798 -400.924136) (xy 452.953434 -400.874562) (xy 452.982894 -400.828713) (xy 453.018579 -400.787524)
			(xy 453.059762 -400.751832) (xy 453.105605 -400.722365) (xy 453.155176 -400.699721) (xy 453.207464 -400.684361)
			(xy 453.261405 -400.676599) (xy 453.288654 -400.67611) (xy 453.314382 -400.676536) (xy 453.365371 -400.683452)
			(xy 453.414966 -400.697164) (xy 453.462265 -400.717423) (xy 453.506409 -400.743862) (xy 453.546596 -400.775998)
			(xy 453.582093 -400.813248) (xy 453.597518 -400.833844) (xy 453.597772 -400.834098) (xy 453.603868 -400.842226)
			(xy 453.611996 -400.847306) (xy 453.616317 -400.849776) (xy 453.625649 -400.853233) (xy 453.630538 -400.854164)
			(xy 453.70115 -400.866102) (xy 453.711017 -400.867272) (xy 453.730361 -400.862807) (xy 453.738742 -400.857466)
			(xy 453.763002 -400.840983) (xy 453.815524 -400.814883) (xy 453.871423 -400.797134) (xy 453.929381 -400.788154)
			(xy 453.958706 -400.787616) (xy 453.985959 -400.788054) (xy 454.039909 -400.795812) (xy 454.092206 -400.811169)
			(xy 454.141786 -400.833811) (xy 454.187639 -400.86328) (xy 454.228831 -400.898974) (xy 454.264524 -400.940166)
			(xy 454.293991 -400.986019) (xy 454.316634 -401.035599) (xy 454.331989 -401.087897) (xy 454.339746 -401.141847)
			(xy 454.339746 -401.196353) (xy 454.331989 -401.250303) (xy 454.316634 -401.302601) (xy 454.293991 -401.352181)
			(xy 454.264524 -401.398034) (xy 454.228831 -401.439226) (xy 454.187639 -401.47492) (xy 454.141786 -401.504389)
			(xy 454.092206 -401.527031) (xy 454.039909 -401.542388) (xy 453.985959 -401.550146) (xy 453.958706 -401.550632)
			(xy 453.931702 -401.550153) (xy 453.878237 -401.542517) (xy 453.826384 -401.527412) (xy 453.777183 -401.505141)
			(xy 453.731616 -401.476148) (xy 453.710802 -401.458938) (xy 453.710548 -401.458938) (xy 453.710548 -401.458684)
			(xy 453.702949 -401.452815) (xy 453.684759 -401.446711) (xy 453.665597 -401.447708) (xy 453.6567 -401.451318)
			(xy 453.572626 -401.489926) (xy 453.564125 -401.494282) (xy 453.55085 -401.507993) (xy 453.543505 -401.525606)
			(xy 453.542908 -401.535138) (xy 453.542908 -401.536154) (xy 453.542908 -401.799044) (xy 453.542334 -401.82396)
			(xy 453.532614 -401.872835) (xy 453.523604 -401.896072) (xy 453.417328 -402.152612) (xy 454.098658 -402.152612)
			(xy 454.102729 -402.09699) (xy 454.114855 -402.042553) (xy 454.134778 -401.990462) (xy 454.162074 -401.941827)
			(xy 454.19616 -401.897684) (xy 454.236309 -401.858975) (xy 454.281667 -401.826524) (xy 454.331267 -401.801023)
			(xy 454.384051 -401.783016) (xy 454.438894 -401.772886) (xy 454.494628 -401.770849) (xy 454.550065 -401.776949)
			(xy 454.604022 -401.791055) (xy 454.655351 -401.812867) (xy 454.702957 -401.841921) (xy 454.745825 -401.877596)
			(xy 454.783042 -401.919133) (xy 454.813815 -401.965646) (xy 454.837487 -402.016143) (xy 454.853555 -402.06955)
			(xy 454.861675 -402.124726) (xy 454.862184 -402.152612) (xy 454.861675 -402.180498) (xy 454.853555 -402.235674)
			(xy 454.837487 -402.289081) (xy 454.813815 -402.339578) (xy 454.783042 -402.386091) (xy 454.745825 -402.427628)
			(xy 454.702957 -402.463303) (xy 454.655351 -402.492357) (xy 454.604022 -402.514169) (xy 454.550065 -402.528275)
			(xy 454.494628 -402.534375) (xy 454.438894 -402.532338) (xy 454.384051 -402.522208) (xy 454.331267 -402.504201)
			(xy 454.281667 -402.4787) (xy 454.236309 -402.446249) (xy 454.19616 -402.40754) (xy 454.162074 -402.363397)
			(xy 454.134778 -402.314762) (xy 454.114855 -402.262671) (xy 454.102729 -402.208234) (xy 454.098658 -402.152612)
			(xy 453.417328 -402.152612) (xy 452.94677 -403.2885) (xy 452.936689 -403.311385) (xy 452.908926 -403.352968)
			(xy 452.891652 -403.37105) (xy 452.475092 -403.78761) (xy 452.456992 -403.804843) (xy 452.41543 -403.832584)
			(xy 452.369257 -403.851689) (xy 452.320245 -403.861425) (xy 452.29526 -403.862032) (xy 445.111632 -403.862032)
			(xy 445.086647 -403.861449) (xy 445.037637 -403.851697) (xy 444.991468 -403.832582) (xy 444.949909 -403.804835)
			(xy 444.9318 -403.78761) (xy 443.718696 -402.574506) (xy 443.711291 -402.567673) (xy 443.692696 -402.559949)
			(xy 443.682628 -402.55952) (xy 443.682374 -402.55952) (xy 443.65153 -402.558959) (xy 443.590638 -402.549088)
			(xy 443.532123 -402.52956) (xy 443.477507 -402.500882) (xy 443.452504 -402.482812) (xy 443.44525 -402.477735)
			(xy 443.428337 -402.472533) (xy 443.419484 -402.472652) (xy 443.389766 -402.474176) (xy 443.380399 -402.475009)
			(xy 443.363201 -402.482585) (xy 443.356238 -402.488908) (xy 442.884306 -402.96084) (xy 442.877457 -402.968233)
			(xy 442.869742 -402.986838) (xy 442.86932 -402.996908) (xy 442.86932 -403.27707) (xy 443.122048 -403.27707)
			(xy 443.126119 -403.221448) (xy 443.138245 -403.167011) (xy 443.158168 -403.11492) (xy 443.185464 -403.066285)
			(xy 443.21955 -403.022142) (xy 443.259699 -402.983433) (xy 443.305057 -402.950982) (xy 443.354657 -402.925481)
			(xy 443.407441 -402.907474) (xy 443.462284 -402.897344) (xy 443.518018 -402.895307) (xy 443.573455 -402.901407)
			(xy 443.627412 -402.915513) (xy 443.678741 -402.937325) (xy 443.726347 -402.966379) (xy 443.769215 -403.002054)
			(xy 443.806432 -403.043591) (xy 443.837205 -403.090104) (xy 443.860877 -403.140601) (xy 443.876945 -403.194008)
			(xy 443.885065 -403.249184) (xy 443.885574 -403.27707) (xy 443.885065 -403.304956) (xy 443.876945 -403.360132)
			(xy 443.860877 -403.413539) (xy 443.837205 -403.464036) (xy 443.806432 -403.510549) (xy 443.769215 -403.552086)
			(xy 443.726347 -403.587761) (xy 443.678741 -403.616815) (xy 443.627412 -403.638627) (xy 443.573455 -403.652733)
			(xy 443.518018 -403.658833) (xy 443.462284 -403.656796) (xy 443.407441 -403.646666) (xy 443.354657 -403.628659)
			(xy 443.305057 -403.603158) (xy 443.259699 -403.570707) (xy 443.21955 -403.531998) (xy 443.185464 -403.487855)
			(xy 443.158168 -403.43922) (xy 443.138245 -403.387129) (xy 443.126119 -403.332692) (xy 443.122048 -403.27707)
			(xy 442.86932 -403.27707) (xy 442.86932 -404.7109) (xy 442.868698 -404.735883) (xy 442.858959 -404.784891)
			(xy 442.839855 -404.831061) (xy 442.812119 -404.872622) (xy 442.794898 -404.890732) (xy 442.062362 -405.623522)
			(xy 442.055608 -405.630901) (xy 442.047906 -405.649345) (xy 442.047376 -405.659336) (xy 442.047376 -406.209246)
			(xy 448.698112 -406.209246) (xy 448.698678 -406.179635) (xy 448.707823 -406.121123) (xy 448.7259 -406.064727)
			(xy 448.752476 -406.011803) (xy 448.786911 -405.963621) (xy 448.828378 -405.92134) (xy 448.875882 -405.885974)
			(xy 448.90182 -405.87168) (xy 448.913621 -405.865041) (xy 448.933432 -405.846593) (xy 448.947695 -405.823585)
			(xy 448.955406 -405.797636) (xy 448.956023 -405.770573) (xy 448.949502 -405.7443) (xy 448.936302 -405.720666)
			(xy 448.917353 -405.701334) (xy 448.905884 -405.694134) (xy 448.881637 -405.679373) (xy 448.837444 -405.643748)
			(xy 448.799017 -405.601968) (xy 448.767207 -405.554953) (xy 448.742716 -405.503744) (xy 448.726084 -405.449471)
			(xy 448.717679 -405.393332) (xy 448.717162 -405.36495) (xy 448.717648 -405.337699) (xy 448.725404 -405.283751)
			(xy 448.740759 -405.231456) (xy 448.763401 -405.181879) (xy 448.792867 -405.136029) (xy 448.828558 -405.094838)
			(xy 448.869749 -405.059147) (xy 448.915599 -405.029681) (xy 448.965176 -405.007039) (xy 449.017471 -404.991684)
			(xy 449.071419 -404.983928) (xy 449.125921 -404.983928) (xy 449.179869 -404.991684) (xy 449.232164 -405.007039)
			(xy 449.281741 -405.029681) (xy 449.327591 -405.059147) (xy 449.368782 -405.094838) (xy 449.404473 -405.136029)
			(xy 449.433939 -405.181879) (xy 449.456581 -405.231456) (xy 449.471936 -405.283751) (xy 449.479692 -405.337699)
			(xy 449.480178 -405.36495) (xy 449.479614 -405.394561) (xy 449.47047 -405.453073) (xy 449.452392 -405.509469)
			(xy 449.425817 -405.562394) (xy 449.391381 -405.610576) (xy 449.349913 -405.652857) (xy 449.302409 -405.688222)
			(xy 449.27647 -405.702516) (xy 449.264673 -405.709161) (xy 449.244864 -405.727609) (xy 449.230603 -405.750616)
			(xy 449.222893 -405.776563) (xy 449.222275 -405.803624) (xy 449.228795 -405.829896) (xy 449.241992 -405.853529)
			(xy 449.260939 -405.872861) (xy 449.272406 -405.880062) (xy 449.296649 -405.894829) (xy 449.340843 -405.930453)
			(xy 449.37927 -405.972232) (xy 449.41108 -406.019245) (xy 449.435572 -406.070453) (xy 449.452205 -406.124726)
			(xy 449.46061 -406.180864) (xy 449.461128 -406.209246) (xy 449.460642 -406.236497) (xy 449.452886 -406.290445)
			(xy 449.437531 -406.34274) (xy 449.433305 -406.351994) (xy 456.067414 -406.351994) (xy 456.067927 -406.323785)
			(xy 456.076229 -406.267981) (xy 456.092666 -406.214011) (xy 456.116878 -406.163053) (xy 456.148338 -406.11622)
			(xy 456.186356 -406.074536) (xy 456.230104 -406.038912) (xy 456.254104 -406.02408) (xy 456.266496 -406.016145)
			(xy 456.286401 -405.994487) (xy 456.299322 -405.968061) (xy 456.30419 -405.939051) (xy 456.300602 -405.909854)
			(xy 456.288857 -405.882886) (xy 456.269923 -405.860373) (xy 456.257914 -405.851868) (xy 456.235704 -405.836632)
			(xy 456.195365 -405.800945) (xy 456.160445 -405.759942) (xy 456.131636 -405.714436) (xy 456.109511 -405.665331)
			(xy 456.09451 -405.613604) (xy 456.08693 -405.560281) (xy 456.086464 -405.533352) (xy 456.08695 -405.506101)
			(xy 456.094706 -405.452153) (xy 456.110061 -405.399858) (xy 456.132703 -405.350281) (xy 456.162169 -405.304431)
			(xy 456.19786 -405.26324) (xy 456.239051 -405.227549) (xy 456.284901 -405.198083) (xy 456.334478 -405.175441)
			(xy 456.386773 -405.160086) (xy 456.440721 -405.15233) (xy 456.495223 -405.15233) (xy 456.549171 -405.160086)
			(xy 456.601466 -405.175441) (xy 456.651043 -405.198083) (xy 456.696893 -405.227549) (xy 456.738084 -405.26324)
			(xy 456.773775 -405.304431) (xy 456.803241 -405.350281) (xy 456.825883 -405.399858) (xy 456.841238 -405.452153)
			(xy 456.848994 -405.506101) (xy 456.84948 -405.533352) (xy 456.848927 -405.56156) (xy 456.840633 -405.617362)
			(xy 456.824203 -405.671331) (xy 456.799998 -405.722289) (xy 456.768544 -405.769122) (xy 456.730531 -405.810808)
			(xy 456.686788 -405.846434) (xy 456.66279 -405.861266) (xy 456.650449 -405.869273) (xy 456.630548 -405.890916)
			(xy 456.617626 -405.917326) (xy 456.612753 -405.946321) (xy 456.61633 -405.975505) (xy 456.628062 -406.002465)
			(xy 456.646979 -406.024973) (xy 456.65898 -406.033478) (xy 456.68121 -406.048686) (xy 456.721549 -406.084377)
			(xy 456.756468 -406.125386) (xy 456.785275 -406.170896) (xy 456.807396 -406.220005) (xy 456.822393 -406.271737)
			(xy 456.829967 -406.325063) (xy 456.83043 -406.351994) (xy 456.829944 -406.379245) (xy 456.822188 -406.433193)
			(xy 456.806833 -406.485488) (xy 456.784191 -406.535065) (xy 456.754725 -406.580915) (xy 456.719034 -406.622106)
			(xy 456.677843 -406.657797) (xy 456.631993 -406.687263) (xy 456.582416 -406.709905) (xy 456.530121 -406.72526)
			(xy 456.476173 -406.733016) (xy 456.421671 -406.733016) (xy 456.367723 -406.72526) (xy 456.315428 -406.709905)
			(xy 456.265851 -406.687263) (xy 456.220001 -406.657797) (xy 456.17881 -406.622106) (xy 456.143119 -406.580915)
			(xy 456.113653 -406.535065) (xy 456.091011 -406.485488) (xy 456.075656 -406.433193) (xy 456.0679 -406.379245)
			(xy 456.067414 -406.351994) (xy 449.433305 -406.351994) (xy 449.414889 -406.392317) (xy 449.385423 -406.438167)
			(xy 449.349732 -406.479358) (xy 449.308541 -406.515049) (xy 449.262691 -406.544515) (xy 449.213114 -406.567157)
			(xy 449.160819 -406.582512) (xy 449.106871 -406.590268) (xy 449.052369 -406.590268) (xy 448.998421 -406.582512)
			(xy 448.946126 -406.567157) (xy 448.896549 -406.544515) (xy 448.850699 -406.515049) (xy 448.809508 -406.479358)
			(xy 448.773817 -406.438167) (xy 448.744351 -406.392317) (xy 448.721709 -406.34274) (xy 448.706354 -406.290445)
			(xy 448.698598 -406.236497) (xy 448.698112 -406.209246) (xy 442.047376 -406.209246) (xy 442.047376 -407.199846)
			(xy 448.698112 -407.199846) (xy 448.698598 -407.172595) (xy 448.706354 -407.118647) (xy 448.721709 -407.066352)
			(xy 448.744351 -407.016775) (xy 448.773817 -406.970925) (xy 448.809508 -406.929734) (xy 448.850699 -406.894043)
			(xy 448.896549 -406.864577) (xy 448.946126 -406.841935) (xy 448.998421 -406.82658) (xy 449.052369 -406.818824)
			(xy 449.106871 -406.818824) (xy 449.160819 -406.82658) (xy 449.213114 -406.841935) (xy 449.262691 -406.864577)
			(xy 449.308541 -406.894043) (xy 449.349732 -406.929734) (xy 449.385423 -406.970925) (xy 449.414889 -407.016775)
			(xy 449.437531 -407.066352) (xy 449.452886 -407.118647) (xy 449.460642 -407.172595) (xy 449.461128 -407.199846)
			(xy 449.460563 -407.228837) (xy 449.451777 -407.286151) (xy 449.43798 -407.330148) (xy 456.075796 -407.330148)
			(xy 456.076282 -407.302897) (xy 456.084038 -407.248949) (xy 456.099393 -407.196654) (xy 456.122035 -407.147077)
			(xy 456.151501 -407.101227) (xy 456.187192 -407.060036) (xy 456.228383 -407.024345) (xy 456.274233 -406.994879)
			(xy 456.32381 -406.972237) (xy 456.376105 -406.956882) (xy 456.430053 -406.949126) (xy 456.484555 -406.949126)
			(xy 456.538503 -406.956882) (xy 456.590798 -406.972237) (xy 456.640375 -406.994879) (xy 456.686225 -407.024345)
			(xy 456.727416 -407.060036) (xy 456.763107 -407.101227) (xy 456.792573 -407.147077) (xy 456.815215 -407.196654)
			(xy 456.83057 -407.248949) (xy 456.838326 -407.302897) (xy 456.838812 -407.330148) (xy 456.838291 -407.35901)
			(xy 456.829609 -407.416078) (xy 456.812419 -407.471184) (xy 456.787116 -407.523067) (xy 456.754278 -407.570541)
			(xy 456.714656 -407.612519) (xy 456.669156 -407.648043) (xy 456.644248 -407.662634) (xy 456.632498 -407.669733)
			(xy 456.61303 -407.689076) (xy 456.599416 -407.712904) (xy 456.592637 -407.739497) (xy 456.593184 -407.766935)
			(xy 456.601016 -407.793237) (xy 456.615569 -407.816504) (xy 456.635792 -407.835056) (xy 456.647804 -407.841704)
			(xy 456.670957 -407.854001) (xy 456.713937 -407.884023) (xy 456.752403 -407.919644) (xy 456.785633 -407.960193)
			(xy 456.813001 -408.004909) (xy 456.833993 -408.05295) (xy 456.848213 -408.103411) (xy 456.855393 -408.155343)
			(xy 456.85583 -408.181556) (xy 456.855344 -408.208807) (xy 456.847588 -408.262755) (xy 456.832233 -408.31505)
			(xy 456.809591 -408.364627) (xy 456.780125 -408.410477) (xy 456.744434 -408.451668) (xy 456.703243 -408.487359)
			(xy 456.657393 -408.516825) (xy 456.607816 -408.539467) (xy 456.555521 -408.554822) (xy 456.501573 -408.562578)
			(xy 456.447071 -408.562578) (xy 456.393123 -408.554822) (xy 456.340828 -408.539467) (xy 456.291251 -408.516825)
			(xy 456.245401 -408.487359) (xy 456.20421 -408.451668) (xy 456.168519 -408.410477) (xy 456.139053 -408.364627)
			(xy 456.116411 -408.31505) (xy 456.101056 -408.262755) (xy 456.0933 -408.208807) (xy 456.092814 -408.181556)
			(xy 456.093325 -408.152693) (xy 456.102008 -408.095624) (xy 456.119198 -408.040518) (xy 456.144503 -407.988634)
			(xy 456.177343 -407.94116) (xy 456.216967 -407.899183) (xy 456.262469 -407.863661) (xy 456.287378 -407.84907)
			(xy 456.299122 -407.841963) (xy 456.318584 -407.822619) (xy 456.332195 -407.798793) (xy 456.338971 -407.772203)
			(xy 456.338425 -407.744769) (xy 456.330596 -407.718469) (xy 456.316048 -407.695203) (xy 456.295831 -407.67665)
			(xy 456.283822 -407.67) (xy 456.260676 -407.657689) (xy 456.217696 -407.62767) (xy 456.179228 -407.592052)
			(xy 456.145997 -407.551504) (xy 456.118628 -407.50679) (xy 456.097635 -407.458752) (xy 456.083415 -407.408292)
			(xy 456.076233 -407.356361) (xy 456.075796 -407.330148) (xy 449.43798 -407.330148) (xy 449.434427 -407.341477)
			(xy 449.408913 -407.393546) (xy 449.375822 -407.441159) (xy 449.335914 -407.483223) (xy 449.290106 -407.51877)
			(xy 449.26504 -407.533348) (xy 449.25296 -407.540612) (xy 449.233005 -407.560503) (xy 449.219245 -407.585089)
			(xy 449.212726 -407.6125) (xy 449.213945 -407.640649) (xy 449.222808 -407.667394) (xy 449.238641 -407.690699)
			(xy 449.260239 -407.708792) (xy 449.272914 -407.714958) (xy 449.29783 -407.726553) (xy 449.344309 -407.755877)
			(xy 449.386098 -407.791567) (xy 449.422332 -407.832886) (xy 449.452262 -407.878977) (xy 449.475267 -407.928886)
			(xy 449.490871 -407.98158) (xy 449.498752 -408.035968) (xy 449.499228 -408.063446) (xy 449.498742 -408.090697)
			(xy 449.490986 -408.144645) (xy 449.475631 -408.19694) (xy 449.452989 -408.246517) (xy 449.423523 -408.292367)
			(xy 449.387832 -408.333558) (xy 449.346641 -408.369249) (xy 449.300791 -408.398715) (xy 449.251214 -408.421357)
			(xy 449.198919 -408.436712) (xy 449.144971 -408.444468) (xy 449.090469 -408.444468) (xy 449.036521 -408.436712)
			(xy 448.984226 -408.421357) (xy 448.934649 -408.398715) (xy 448.888799 -408.369249) (xy 448.847608 -408.333558)
			(xy 448.811917 -408.292367) (xy 448.782451 -408.246517) (xy 448.759809 -408.19694) (xy 448.744454 -408.144645)
			(xy 448.736698 -408.090697) (xy 448.736212 -408.063446) (xy 448.73675 -408.034453) (xy 448.745539 -407.977138)
			(xy 448.762892 -407.92181) (xy 448.788409 -407.869741) (xy 448.821505 -407.822128) (xy 448.861418 -407.780065)
			(xy 448.907232 -407.74452) (xy 448.9323 -407.729944) (xy 448.944382 -407.722687) (xy 448.964329 -407.702791)
			(xy 448.978083 -407.678204) (xy 448.984598 -407.650795) (xy 448.983379 -407.622649) (xy 448.974518 -407.595905)
			(xy 448.95869 -407.5726) (xy 448.937098 -407.554503) (xy 448.924426 -407.548334) (xy 448.899516 -407.536726)
			(xy 448.853036 -407.507406) (xy 448.811245 -407.471718) (xy 448.775009 -407.430402) (xy 448.745078 -407.384313)
			(xy 448.722072 -407.334405) (xy 448.706468 -407.281711) (xy 448.698588 -407.227324) (xy 448.698112 -407.199846)
			(xy 442.047376 -407.199846) (xy 442.047376 -410.578554) (xy 446.710306 -410.578554) (xy 446.714377 -410.522932)
			(xy 446.726503 -410.468495) (xy 446.746426 -410.416404) (xy 446.773722 -410.367769) (xy 446.807808 -410.323626)
			(xy 446.847957 -410.284917) (xy 446.893315 -410.252466) (xy 446.942915 -410.226965) (xy 446.995699 -410.208958)
			(xy 447.050542 -410.198828) (xy 447.106276 -410.196791) (xy 447.161713 -410.202891) (xy 447.21567 -410.216997)
			(xy 447.266999 -410.238809) (xy 447.314605 -410.267863) (xy 447.357473 -410.303538) (xy 447.39469 -410.345075)
			(xy 447.425463 -410.391588) (xy 447.449135 -410.442085) (xy 447.465203 -410.495492) (xy 447.473323 -410.550668)
			(xy 447.473832 -410.578554) (xy 447.599306 -410.578554) (xy 447.603377 -410.522932) (xy 447.615503 -410.468495)
			(xy 447.635426 -410.416404) (xy 447.662722 -410.367769) (xy 447.696808 -410.323626) (xy 447.736957 -410.284917)
			(xy 447.782315 -410.252466) (xy 447.831915 -410.226965) (xy 447.884699 -410.208958) (xy 447.939542 -410.198828)
			(xy 447.995276 -410.196791) (xy 448.050713 -410.202891) (xy 448.10467 -410.216997) (xy 448.155999 -410.238809)
			(xy 448.203605 -410.267863) (xy 448.246473 -410.303538) (xy 448.28369 -410.345075) (xy 448.314463 -410.391588)
			(xy 448.338135 -410.442085) (xy 448.354203 -410.495492) (xy 448.362323 -410.550668) (xy 448.362832 -410.578554)
			(xy 448.488306 -410.578554) (xy 448.492377 -410.522932) (xy 448.504503 -410.468495) (xy 448.524426 -410.416404)
			(xy 448.551722 -410.367769) (xy 448.585808 -410.323626) (xy 448.625957 -410.284917) (xy 448.671315 -410.252466)
			(xy 448.720915 -410.226965) (xy 448.773699 -410.208958) (xy 448.828542 -410.198828) (xy 448.884276 -410.196791)
			(xy 448.939713 -410.202891) (xy 448.99367 -410.216997) (xy 449.044999 -410.238809) (xy 449.092605 -410.267863)
			(xy 449.135473 -410.303538) (xy 449.17269 -410.345075) (xy 449.203463 -410.391588) (xy 449.227135 -410.442085)
			(xy 449.243203 -410.495492) (xy 449.251323 -410.550668) (xy 449.251832 -410.578554) (xy 449.251323 -410.60644)
			(xy 449.243203 -410.661616) (xy 449.227135 -410.715023) (xy 449.203463 -410.76552) (xy 449.17269 -410.812033)
			(xy 449.135473 -410.85357) (xy 449.092605 -410.889245) (xy 449.071044 -410.902404) (xy 451.091808 -410.902404)
			(xy 451.092365 -410.87228) (xy 451.101847 -410.812782) (xy 451.12056 -410.755513) (xy 451.14804 -410.701897)
			(xy 451.183603 -410.653264) (xy 451.204584 -410.63164) (xy 451.21195 -410.624528) (xy 451.21957 -410.605732)
			(xy 451.21957 -410.513276) (xy 451.21195 -410.49448) (xy 451.204584 -410.487368) (xy 451.183608 -410.465739)
			(xy 451.14804 -410.417111) (xy 451.12056 -410.363495) (xy 451.10185 -410.306226) (xy 451.092377 -410.246728)
			(xy 451.091808 -410.216604) (xy 451.092259 -410.189351) (xy 451.100016 -410.135398) (xy 451.115372 -410.083099)
			(xy 451.138015 -410.033518) (xy 451.167485 -409.987664) (xy 451.20318 -409.946471) (xy 451.244374 -409.910777)
			(xy 451.290229 -409.88131) (xy 451.339811 -409.858668) (xy 451.39211 -409.843313) (xy 451.446063 -409.835558)
			(xy 451.473316 -409.835096) (xy 451.503441 -409.835643) (xy 451.562939 -409.845128) (xy 451.620207 -409.863844)
			(xy 451.673824 -409.891325) (xy 451.722457 -409.92689) (xy 451.74408 -409.947872) (xy 451.751192 -409.955238)
			(xy 451.769988 -409.962858) (xy 451.862444 -409.962858) (xy 451.88124 -409.955238) (xy 451.888352 -409.947872)
			(xy 451.909987 -409.926903) (xy 451.958612 -409.89133) (xy 452.012225 -409.863847) (xy 452.069494 -409.845136)
			(xy 452.128992 -409.835665) (xy 452.159116 -409.835096) (xy 452.186487 -409.835554) (xy 452.240666 -409.843374)
			(xy 452.293169 -409.858865) (xy 452.342916 -409.881708) (xy 452.388882 -409.911434) (xy 452.409814 -409.929076)
			(xy 452.416926 -409.935172) (xy 452.433944 -409.941522) (xy 452.519288 -409.941522) (xy 452.536306 -409.935172)
			(xy 452.543418 -409.929076) (xy 452.564367 -409.911458) (xy 452.610336 -409.881744) (xy 452.660079 -409.858904)
			(xy 452.712576 -409.843408) (xy 452.766748 -409.835574) (xy 452.794116 -409.835096) (xy 452.821368 -409.835563)
			(xy 452.875316 -409.843322) (xy 452.927612 -409.858679) (xy 452.977189 -409.881322) (xy 453.02304 -409.910791)
			(xy 453.06423 -409.946484) (xy 453.099921 -409.987676) (xy 453.129387 -410.033528) (xy 453.152028 -410.083107)
			(xy 453.167383 -410.135403) (xy 453.175139 -410.189352) (xy 453.175624 -410.216604) (xy 453.175063 -410.246728)
			(xy 453.165581 -410.306225) (xy 453.146868 -410.363493) (xy 453.11939 -410.41711) (xy 453.083828 -410.465744)
			(xy 453.062848 -410.487368) (xy 453.055482 -410.49448) (xy 453.047862 -410.513276) (xy 453.047862 -410.6037)
			(xy 454.780648 -410.6037) (xy 454.784719 -410.548078) (xy 454.796845 -410.493641) (xy 454.816768 -410.44155)
			(xy 454.844064 -410.392915) (xy 454.87815 -410.348772) (xy 454.918299 -410.310063) (xy 454.963657 -410.277612)
			(xy 455.013257 -410.252111) (xy 455.066041 -410.234104) (xy 455.120884 -410.223974) (xy 455.176618 -410.221937)
			(xy 455.232055 -410.228037) (xy 455.286012 -410.242143) (xy 455.337341 -410.263955) (xy 455.384947 -410.293009)
			(xy 455.427815 -410.328684) (xy 455.465032 -410.370221) (xy 455.495805 -410.416734) (xy 455.519477 -410.467231)
			(xy 455.535545 -410.520638) (xy 455.543665 -410.575814) (xy 455.544174 -410.6037) (xy 455.669648 -410.6037)
			(xy 455.673719 -410.548078) (xy 455.685845 -410.493641) (xy 455.705768 -410.44155) (xy 455.733064 -410.392915)
			(xy 455.76715 -410.348772) (xy 455.807299 -410.310063) (xy 455.852657 -410.277612) (xy 455.902257 -410.252111)
			(xy 455.955041 -410.234104) (xy 456.009884 -410.223974) (xy 456.065618 -410.221937) (xy 456.121055 -410.228037)
			(xy 456.175012 -410.242143) (xy 456.226341 -410.263955) (xy 456.273947 -410.293009) (xy 456.316815 -410.328684)
			(xy 456.354032 -410.370221) (xy 456.384805 -410.416734) (xy 456.408477 -410.467231) (xy 456.424545 -410.520638)
			(xy 456.432665 -410.575814) (xy 456.433174 -410.6037) (xy 456.558648 -410.6037) (xy 456.562719 -410.548078)
			(xy 456.574845 -410.493641) (xy 456.594768 -410.44155) (xy 456.622064 -410.392915) (xy 456.65615 -410.348772)
			(xy 456.696299 -410.310063) (xy 456.741657 -410.277612) (xy 456.791257 -410.252111) (xy 456.844041 -410.234104)
			(xy 456.898884 -410.223974) (xy 456.954618 -410.221937) (xy 457.010055 -410.228037) (xy 457.064012 -410.242143)
			(xy 457.115341 -410.263955) (xy 457.162947 -410.293009) (xy 457.205815 -410.328684) (xy 457.243032 -410.370221)
			(xy 457.273805 -410.416734) (xy 457.297477 -410.467231) (xy 457.313545 -410.520638) (xy 457.321665 -410.575814)
			(xy 457.322174 -410.6037) (xy 457.321665 -410.631586) (xy 457.313545 -410.686762) (xy 457.297477 -410.740169)
			(xy 457.273805 -410.790666) (xy 457.243032 -410.837179) (xy 457.205815 -410.878716) (xy 457.162947 -410.914391)
			(xy 457.115341 -410.943445) (xy 457.064012 -410.965257) (xy 457.010055 -410.979363) (xy 456.954618 -410.985463)
			(xy 456.898884 -410.983426) (xy 456.844041 -410.973296) (xy 456.791257 -410.955289) (xy 456.741657 -410.929788)
			(xy 456.696299 -410.897337) (xy 456.65615 -410.858628) (xy 456.622064 -410.814485) (xy 456.594768 -410.76585)
			(xy 456.574845 -410.713759) (xy 456.562719 -410.659322) (xy 456.558648 -410.6037) (xy 456.433174 -410.6037)
			(xy 456.432665 -410.631586) (xy 456.424545 -410.686762) (xy 456.408477 -410.740169) (xy 456.384805 -410.790666)
			(xy 456.354032 -410.837179) (xy 456.316815 -410.878716) (xy 456.273947 -410.914391) (xy 456.226341 -410.943445)
			(xy 456.175012 -410.965257) (xy 456.121055 -410.979363) (xy 456.065618 -410.985463) (xy 456.009884 -410.983426)
			(xy 455.955041 -410.973296) (xy 455.902257 -410.955289) (xy 455.852657 -410.929788) (xy 455.807299 -410.897337)
			(xy 455.76715 -410.858628) (xy 455.733064 -410.814485) (xy 455.705768 -410.76585) (xy 455.685845 -410.713759)
			(xy 455.673719 -410.659322) (xy 455.669648 -410.6037) (xy 455.544174 -410.6037) (xy 455.543665 -410.631586)
			(xy 455.535545 -410.686762) (xy 455.519477 -410.740169) (xy 455.495805 -410.790666) (xy 455.465032 -410.837179)
			(xy 455.427815 -410.878716) (xy 455.384947 -410.914391) (xy 455.337341 -410.943445) (xy 455.286012 -410.965257)
			(xy 455.232055 -410.979363) (xy 455.176618 -410.985463) (xy 455.120884 -410.983426) (xy 455.066041 -410.973296)
			(xy 455.013257 -410.955289) (xy 454.963657 -410.929788) (xy 454.918299 -410.897337) (xy 454.87815 -410.858628)
			(xy 454.844064 -410.814485) (xy 454.816768 -410.76585) (xy 454.796845 -410.713759) (xy 454.784719 -410.659322)
			(xy 454.780648 -410.6037) (xy 453.047862 -410.6037) (xy 453.047862 -410.605732) (xy 453.055482 -410.624528)
			(xy 453.062848 -410.63164) (xy 453.083816 -410.653277) (xy 453.119388 -410.701901) (xy 453.146871 -410.755515)
			(xy 453.165582 -410.812783) (xy 453.175055 -410.87228) (xy 453.175624 -410.902404) (xy 453.175126 -410.929655)
			(xy 453.167369 -410.983601) (xy 453.152015 -411.035895) (xy 453.129374 -411.085471) (xy 453.099909 -411.13132)
			(xy 453.064219 -411.17251) (xy 453.02303 -411.208202) (xy 452.977181 -411.237668) (xy 452.927606 -411.26031)
			(xy 452.875313 -411.275667) (xy 452.821367 -411.283425) (xy 452.794116 -411.283912) (xy 452.766746 -411.283434)
			(xy 452.712568 -411.275618) (xy 452.660065 -411.260132) (xy 452.610318 -411.237293) (xy 452.56435 -411.207572)
			(xy 452.543418 -411.189932) (xy 452.536306 -411.183836) (xy 452.519288 -411.177486) (xy 452.433944 -411.177486)
			(xy 452.416926 -411.183836) (xy 452.409814 -411.189932) (xy 452.388892 -411.207583) (xy 452.342916 -411.237292)
			(xy 452.293166 -411.260125) (xy 452.240663 -411.275613) (xy 452.186486 -411.283439) (xy 452.159116 -411.283912)
			(xy 452.128992 -411.283342) (xy 452.069496 -411.273862) (xy 452.012227 -411.255152) (xy 451.95861 -411.227675)
			(xy 451.909976 -411.192116) (xy 451.888352 -411.171136) (xy 451.88124 -411.16377) (xy 451.862444 -411.15615)
			(xy 451.769988 -411.15615) (xy 451.751192 -411.16377) (xy 451.74408 -411.171136) (xy 451.722432 -411.192091)
			(xy 451.673811 -411.227665) (xy 451.6202 -411.255151) (xy 451.562935 -411.273865) (xy 451.503439 -411.283341)
			(xy 451.473316 -411.283912) (xy 451.446064 -411.28343) (xy 451.392114 -411.275675) (xy 451.339816 -411.260321)
			(xy 451.290237 -411.237681) (xy 451.244384 -411.208215) (xy 451.203191 -411.172523) (xy 451.167497 -411.131332)
			(xy 451.138029 -411.085481) (xy 451.115386 -411.035902) (xy 451.100029 -410.983606) (xy 451.092272 -410.929656)
			(xy 451.091808 -410.902404) (xy 449.071044 -410.902404) (xy 449.044999 -410.918299) (xy 448.99367 -410.940111)
			(xy 448.939713 -410.954217) (xy 448.884276 -410.960317) (xy 448.828542 -410.95828) (xy 448.773699 -410.94815)
			(xy 448.720915 -410.930143) (xy 448.671315 -410.904642) (xy 448.625957 -410.872191) (xy 448.585808 -410.833482)
			(xy 448.551722 -410.789339) (xy 448.524426 -410.740704) (xy 448.504503 -410.688613) (xy 448.492377 -410.634176)
			(xy 448.488306 -410.578554) (xy 448.362832 -410.578554) (xy 448.362323 -410.60644) (xy 448.354203 -410.661616)
			(xy 448.338135 -410.715023) (xy 448.314463 -410.76552) (xy 448.28369 -410.812033) (xy 448.246473 -410.85357)
			(xy 448.203605 -410.889245) (xy 448.155999 -410.918299) (xy 448.10467 -410.940111) (xy 448.050713 -410.954217)
			(xy 447.995276 -410.960317) (xy 447.939542 -410.95828) (xy 447.884699 -410.94815) (xy 447.831915 -410.930143)
			(xy 447.782315 -410.904642) (xy 447.736957 -410.872191) (xy 447.696808 -410.833482) (xy 447.662722 -410.789339)
			(xy 447.635426 -410.740704) (xy 447.615503 -410.688613) (xy 447.603377 -410.634176) (xy 447.599306 -410.578554)
			(xy 447.473832 -410.578554) (xy 447.473323 -410.60644) (xy 447.465203 -410.661616) (xy 447.449135 -410.715023)
			(xy 447.425463 -410.76552) (xy 447.39469 -410.812033) (xy 447.357473 -410.85357) (xy 447.314605 -410.889245)
			(xy 447.266999 -410.918299) (xy 447.21567 -410.940111) (xy 447.161713 -410.954217) (xy 447.106276 -410.960317)
			(xy 447.050542 -410.95828) (xy 446.995699 -410.94815) (xy 446.942915 -410.930143) (xy 446.893315 -410.904642)
			(xy 446.847957 -410.872191) (xy 446.807808 -410.833482) (xy 446.773722 -410.789339) (xy 446.746426 -410.740704)
			(xy 446.726503 -410.688613) (xy 446.714377 -410.634176) (xy 446.710306 -410.578554) (xy 442.047376 -410.578554)
			(xy 442.047376 -413.912558) (xy 442.047817 -413.922565) (xy 442.055549 -413.941028) (xy 442.062362 -413.948372)
			(xy 443.261127 -415.147252) (xy 449.363338 -415.147252) (xy 449.363825 -415.119882) (xy 449.371637 -415.065704)
			(xy 449.38712 -415.013201) (xy 449.409957 -414.963453) (xy 449.439678 -414.917486) (xy 449.457318 -414.896554)
			(xy 449.463414 -414.889442) (xy 449.469764 -414.872424) (xy 449.469764 -414.78708) (xy 449.463414 -414.770062)
			(xy 449.457318 -414.76295) (xy 449.439692 -414.742008) (xy 449.409977 -414.696038) (xy 449.387139 -414.646293)
			(xy 449.371645 -414.593795) (xy 449.363813 -414.539621) (xy 449.363338 -414.512252) (xy 449.363733 -414.484997)
			(xy 449.371498 -414.431044) (xy 449.386861 -414.378745) (xy 449.409511 -414.329164) (xy 449.438987 -414.283312)
			(xy 449.474688 -414.242121) (xy 449.515887 -414.20643) (xy 449.561747 -414.176966) (xy 449.611333 -414.154328)
			(xy 449.663636 -414.138978) (xy 449.717591 -414.131227) (xy 449.744846 -414.130744) (xy 449.774968 -414.13135)
			(xy 449.834463 -414.140823) (xy 449.89173 -414.159526) (xy 449.945348 -414.186993) (xy 449.993984 -414.222544)
			(xy 450.01561 -414.24352) (xy 450.022722 -414.250886) (xy 450.041518 -414.258506) (xy 450.133974 -414.258506)
			(xy 450.15277 -414.250886) (xy 450.159882 -414.24352) (xy 450.181495 -414.222527) (xy 450.230127 -414.186959)
			(xy 450.283746 -414.159481) (xy 450.341019 -414.140776) (xy 450.400521 -414.13131) (xy 450.430646 -414.130744)
			(xy 450.457896 -414.131235) (xy 450.511841 -414.138996) (xy 450.564133 -414.154355) (xy 450.613707 -414.176998)
			(xy 450.659555 -414.206465) (xy 450.700743 -414.242155) (xy 450.736434 -414.283343) (xy 450.765901 -414.329191)
			(xy 450.788544 -414.378765) (xy 450.803903 -414.431057) (xy 450.811665 -414.485002) (xy 450.812154 -414.512252)
			(xy 450.811597 -414.541729) (xy 450.802533 -414.599982) (xy 450.784616 -414.656147) (xy 450.75827 -414.708887)
			(xy 450.724123 -414.756945) (xy 450.70395 -414.778444) (xy 450.697396 -414.785764) (xy 450.689964 -414.803936)
			(xy 450.689472 -414.81375) (xy 450.689472 -414.86709) (xy 450.702426 -414.879536) (xy 450.710329 -414.886933)
			(xy 450.730463 -414.894828) (xy 450.741288 -414.894776) (xy 450.7738 -414.892998) (xy 450.784574 -414.891856)
			(xy 450.803779 -414.881872) (xy 450.810884 -414.873694) (xy 450.829064 -414.851551) (xy 450.870964 -414.812479)
			(xy 450.918237 -414.780112) (xy 450.969818 -414.755179) (xy 451.024548 -414.738242) (xy 451.081196 -414.729679)
			(xy 451.109842 -414.729168) (xy 451.139964 -414.72977) (xy 451.199459 -414.739243) (xy 451.256727 -414.757946)
			(xy 451.310345 -414.785415) (xy 451.35898 -414.820968) (xy 451.380606 -414.841944) (xy 451.387718 -414.84931)
			(xy 451.406514 -414.85693) (xy 451.49897 -414.85693) (xy 451.517766 -414.84931) (xy 451.524878 -414.841944)
			(xy 451.546497 -414.820957) (xy 451.595126 -414.785388) (xy 451.648744 -414.757908) (xy 451.706016 -414.739202)
			(xy 451.765517 -414.729734) (xy 451.795642 -414.729168) (xy 451.821941 -414.729585) (xy 451.87404 -414.73681)
			(xy 451.92465 -414.751129) (xy 451.972811 -414.772271) (xy 452.017608 -414.799834) (xy 452.058189 -414.833295)
			(xy 452.076312 -414.852358) (xy 452.083424 -414.859978) (xy 452.101712 -414.86836) (xy 452.194168 -414.871662)
			(xy 452.213218 -414.864804) (xy 452.220584 -414.857692) (xy 452.241902 -414.838411) (xy 452.289266 -414.805844)
			(xy 452.340979 -414.780753) (xy 452.395873 -414.763705) (xy 452.452702 -414.755087) (xy 452.481442 -414.754568)
			(xy 452.510242 -414.755066) (xy 452.567191 -414.763698) (xy 452.622196 -414.78079) (xy 452.674009 -414.805954)
			(xy 452.721451 -414.838618) (xy 452.742808 -414.857946) (xy 452.74992 -414.864804) (xy 452.767954 -414.871916)
			(xy 452.85787 -414.871154) (xy 452.875904 -414.864042) (xy 452.883016 -414.857184) (xy 452.904484 -414.837172)
			(xy 452.9524 -414.803287) (xy 453.004938 -414.777135) (xy 453.060861 -414.759334) (xy 453.118849 -414.750304)
			(xy 453.148192 -414.749742) (xy 453.17451 -414.750141) (xy 453.226647 -414.75737) (xy 453.277297 -414.771693)
			(xy 453.325499 -414.792837) (xy 453.370339 -414.820403) (xy 453.410968 -414.853867) (xy 453.429116 -414.872932)
			(xy 453.43626 -414.879989) (xy 453.454426 -414.888492) (xy 453.464422 -414.889442) (xy 453.51827 -414.891474)
			(xy 453.52462 -414.885124) (xy 453.531732 -414.878012) (xy 453.539352 -414.859724) (xy 453.540368 -414.76803)
			(xy 453.533002 -414.749742) (xy 453.52589 -414.742376) (xy 453.505877 -414.720922) (xy 453.472052 -414.672985)
			(xy 453.44596 -414.620436) (xy 453.428217 -414.564514) (xy 453.419239 -414.506535) (xy 453.418702 -414.4772)
			(xy 453.419188 -414.449949) (xy 453.426944 -414.396001) (xy 453.442299 -414.343706) (xy 453.464941 -414.294129)
			(xy 453.494407 -414.248279) (xy 453.530098 -414.207088) (xy 453.571289 -414.171397) (xy 453.617139 -414.141931)
			(xy 453.666716 -414.119289) (xy 453.719011 -414.103934) (xy 453.772959 -414.096178) (xy 453.827461 -414.096178)
			(xy 453.881409 -414.103934) (xy 453.933704 -414.119289) (xy 453.983281 -414.141931) (xy 454.029131 -414.171397)
			(xy 454.070322 -414.207088) (xy 454.106013 -414.248279) (xy 454.135479 -414.294129) (xy 454.158121 -414.343706)
			(xy 454.173476 -414.396001) (xy 454.181232 -414.449949) (xy 454.181718 -414.4772) (xy 454.181157 -414.507324)
			(xy 454.171675 -414.566821) (xy 454.152962 -414.62409) (xy 454.125484 -414.677707) (xy 454.089923 -414.72634)
			(xy 454.068942 -414.747964) (xy 454.06183 -414.755076) (xy 454.05421 -414.773364) (xy 454.053194 -414.865058)
			(xy 454.06056 -414.883346) (xy 454.067672 -414.890712) (xy 454.087673 -414.912177) (xy 454.121501 -414.960111)
			(xy 454.147596 -415.012656) (xy 454.165342 -415.068577) (xy 454.174322 -415.126554) (xy 454.17486 -415.155888)
			(xy 454.174371 -415.183386) (xy 454.166481 -415.237812) (xy 454.150863 -415.290544) (xy 454.12784 -415.340488)
			(xy 454.097888 -415.386612) (xy 454.080118 -415.407602) (xy 454.073768 -415.414714) (xy 454.067418 -415.43224)
			(xy 454.068688 -415.519362) (xy 454.075546 -415.536634) (xy 454.081896 -415.543746) (xy 454.100923 -415.565062)
			(xy 454.133149 -415.612242) (xy 454.157985 -415.663697) (xy 454.174875 -415.718278) (xy 454.183443 -415.774767)
			(xy 454.184004 -415.803334) (xy 454.183554 -415.830586) (xy 454.175793 -415.884535) (xy 454.160433 -415.936831)
			(xy 454.137788 -415.986409) (xy 454.108317 -416.032259) (xy 454.072622 -416.073449) (xy 454.031429 -416.10914)
			(xy 453.985575 -416.138606) (xy 453.935995 -416.161246) (xy 453.883698 -416.176601) (xy 453.829748 -416.184357)
			(xy 453.802496 -416.184842) (xy 453.776975 -416.18445) (xy 453.726387 -416.177654) (xy 453.677158 -416.164171)
			(xy 453.630167 -416.144242) (xy 453.586254 -416.118222) (xy 453.546205 -416.086578) (xy 453.528176 -416.06851)
			(xy 453.521572 -416.061652) (xy 453.5043 -416.053778) (xy 453.416162 -416.048698) (xy 453.398128 -416.05454)
			(xy 453.390762 -416.06089) (xy 453.37018 -416.077259) (xy 453.325366 -416.104777) (xy 453.277195 -416.125875)
			(xy 453.226582 -416.140152) (xy 453.174487 -416.147338) (xy 453.148192 -416.147758) (xy 453.119392 -416.14726)
			(xy 453.062442 -416.138631) (xy 453.007436 -416.12154) (xy 452.955623 -416.096376) (xy 452.908182 -416.06371)
			(xy 452.886826 -416.04438) (xy 452.879714 -416.037522) (xy 452.86168 -416.03041) (xy 452.771764 -416.031172)
			(xy 452.75373 -416.038284) (xy 452.746618 -416.045142) (xy 452.725182 -416.06519) (xy 452.677257 -416.099069)
			(xy 452.62471 -416.125214) (xy 452.568781 -416.143006) (xy 452.510787 -416.152027) (xy 452.481442 -416.152584)
			(xy 452.45132 -416.151977) (xy 452.391826 -416.142503) (xy 452.334559 -416.1238) (xy 452.280941 -416.096333)
			(xy 452.232305 -416.060783) (xy 452.210678 -416.039808) (xy 452.203566 -416.032442) (xy 452.18477 -416.024822)
			(xy 452.092314 -416.024822) (xy 452.073518 -416.032442) (xy 452.066406 -416.039808) (xy 452.046782 -416.05891)
			(xy 452.003043 -416.091863) (xy 451.955042 -416.118223) (xy 451.903764 -416.137449) (xy 451.850264 -416.149145)
			(xy 451.795642 -416.15307) (xy 451.74102 -416.149145) (xy 451.68752 -416.137449) (xy 451.636242 -416.118223)
			(xy 451.588241 -416.091863) (xy 451.544502 -416.05891) (xy 451.524878 -416.039808) (xy 451.517766 -416.032442)
			(xy 451.49897 -416.024822) (xy 451.406514 -416.024822) (xy 451.387718 -416.032442) (xy 451.380606 -416.039808)
			(xy 451.359003 -416.060812) (xy 451.310368 -416.096377) (xy 451.256746 -416.123852) (xy 451.199471 -416.142555)
			(xy 451.139968 -416.152019) (xy 451.109842 -416.152584) (xy 451.080711 -416.152045) (xy 451.023129 -416.14317)
			(xy 450.967568 -416.125637) (xy 450.915322 -416.099853) (xy 450.867607 -416.06642) (xy 450.84619 -416.046666)
			(xy 450.838824 -416.039808) (xy 450.820282 -416.032442) (xy 450.728588 -416.033966) (xy 450.710554 -416.04184)
			(xy 450.703188 -416.049206) (xy 450.681532 -416.070516) (xy 450.632677 -416.106631) (xy 450.578715 -416.134546)
			(xy 450.521011 -416.153554) (xy 450.461023 -416.163175) (xy 450.430646 -416.16376) (xy 450.403392 -416.163302)
			(xy 450.349438 -416.15555) (xy 450.297138 -416.140197) (xy 450.247554 -416.117557) (xy 450.201699 -416.088089)
			(xy 450.160504 -416.052394) (xy 450.12481 -416.0112) (xy 450.095343 -415.965344) (xy 450.072702 -415.915761)
			(xy 450.05735 -415.86346) (xy 450.049598 -415.809506) (xy 450.049138 -415.782252) (xy 450.0497 -415.752775)
			(xy 450.058762 -415.694522) (xy 450.076679 -415.638357) (xy 450.103024 -415.585618) (xy 450.137169 -415.537559)
			(xy 450.157342 -415.51606) (xy 450.163893 -415.508738) (xy 450.171327 -415.490568) (xy 450.17182 -415.480754)
			(xy 450.17182 -415.427414) (xy 450.159882 -415.415984) (xy 450.15277 -415.408618) (xy 450.133974 -415.400998)
			(xy 450.041518 -415.400998) (xy 450.022722 -415.408618) (xy 450.01561 -415.415984) (xy 449.994001 -415.436982)
			(xy 449.945368 -415.472548) (xy 449.891748 -415.500026) (xy 449.834474 -415.51873) (xy 449.774971 -415.528195)
			(xy 449.744846 -415.52876) (xy 449.717592 -415.528302) (xy 449.663638 -415.52055) (xy 449.611338 -415.505197)
			(xy 449.561754 -415.482557) (xy 449.515899 -415.453089) (xy 449.474704 -415.417394) (xy 449.43901 -415.3762)
			(xy 449.409543 -415.330344) (xy 449.386902 -415.280761) (xy 449.37155 -415.22846) (xy 449.363798 -415.174506)
			(xy 449.363338 -415.147252) (xy 443.261127 -415.147252) (xy 444.702692 -416.588956) (xy 444.714012 -416.600627)
			(xy 444.733881 -416.626364) (xy 444.742316 -416.640264) (xy 444.753313 -416.659879) (xy 444.768931 -416.702046)
			(xy 444.776874 -416.746305) (xy 444.777368 -416.768788) (xy 444.777368 -417.403788) (xy 444.777796 -417.413797)
			(xy 444.785537 -417.43226) (xy 444.792354 -417.439602) (xy 445.552532 -418.199824) (xy 448.144898 -418.199824)
			(xy 448.148969 -418.144202) (xy 448.161095 -418.089765) (xy 448.181018 -418.037674) (xy 448.208314 -417.989039)
			(xy 448.2424 -417.944896) (xy 448.282549 -417.906187) (xy 448.327907 -417.873736) (xy 448.377507 -417.848235)
			(xy 448.430291 -417.830228) (xy 448.485134 -417.820098) (xy 448.540868 -417.818061) (xy 448.596305 -417.824161)
			(xy 448.650262 -417.838267) (xy 448.701591 -417.860079) (xy 448.749197 -417.889133) (xy 448.792065 -417.924808)
			(xy 448.829282 -417.966345) (xy 448.860055 -418.012858) (xy 448.883727 -418.063355) (xy 448.899795 -418.116762)
			(xy 448.907915 -418.171938) (xy 448.908424 -418.199824) (xy 448.907915 -418.22771) (xy 448.899795 -418.282886)
			(xy 448.883727 -418.336293) (xy 448.860055 -418.38679) (xy 448.829282 -418.433303) (xy 448.792065 -418.47484)
			(xy 448.749197 -418.510515) (xy 448.701591 -418.539569) (xy 448.650262 -418.561381) (xy 448.596305 -418.575487)
			(xy 448.540868 -418.581587) (xy 448.485134 -418.57955) (xy 448.430291 -418.56942) (xy 448.377507 -418.551413)
			(xy 448.327907 -418.525912) (xy 448.282549 -418.493461) (xy 448.2424 -418.454752) (xy 448.208314 -418.410609)
			(xy 448.181018 -418.361974) (xy 448.161095 -418.309883) (xy 448.148969 -418.255446) (xy 448.144898 -418.199824)
			(xy 445.552532 -418.199824) (xy 446.949452 -419.596824) (xy 448.925948 -419.596824) (xy 448.930019 -419.541202)
			(xy 448.942145 -419.486765) (xy 448.962068 -419.434674) (xy 448.989364 -419.386039) (xy 449.02345 -419.341896)
			(xy 449.063599 -419.303187) (xy 449.108957 -419.270736) (xy 449.158557 -419.245235) (xy 449.211341 -419.227228)
			(xy 449.266184 -419.217098) (xy 449.321918 -419.215061) (xy 449.377355 -419.221161) (xy 449.431312 -419.235267)
			(xy 449.482641 -419.257079) (xy 449.530247 -419.286133) (xy 449.573115 -419.321808) (xy 449.610332 -419.363345)
			(xy 449.641105 -419.409858) (xy 449.664777 -419.460355) (xy 449.680845 -419.513762) (xy 449.688965 -419.568938)
			(xy 449.689474 -419.596824) (xy 449.688965 -419.62471) (xy 449.680845 -419.679886) (xy 449.664777 -419.733293)
			(xy 449.641105 -419.78379) (xy 449.610332 -419.830303) (xy 449.573115 -419.87184) (xy 449.530247 -419.907515)
			(xy 449.482641 -419.936569) (xy 449.431312 -419.958381) (xy 449.377355 -419.972487) (xy 449.321918 -419.978587)
			(xy 449.266184 -419.97655) (xy 449.211341 -419.96642) (xy 449.158557 -419.948413) (xy 449.108957 -419.922912)
			(xy 449.063599 -419.890461) (xy 449.02345 -419.851752) (xy 448.989364 -419.807609) (xy 448.962068 -419.758974)
			(xy 448.942145 -419.706883) (xy 448.930019 -419.652446) (xy 448.925948 -419.596824) (xy 446.949452 -419.596824)
			(xy 448.348658 -420.99611) (xy 450.196458 -420.99611) (xy 450.196941 -420.968612) (xy 450.204832 -420.914185)
			(xy 450.220451 -420.861453) (xy 450.243476 -420.811509) (xy 450.27343 -420.765386) (xy 450.2912 -420.744396)
			(xy 450.29755 -420.737284) (xy 450.3039 -420.720266) (xy 450.3039 -420.634668) (xy 450.29755 -420.61765)
			(xy 450.2912 -420.610538) (xy 450.273442 -420.589537) (xy 450.243486 -420.543417) (xy 450.220458 -420.493476)
			(xy 450.204835 -420.440747) (xy 450.19694 -420.386321) (xy 450.196458 -420.358824) (xy 450.196944 -420.331573)
			(xy 450.2047 -420.277625) (xy 450.220055 -420.22533) (xy 450.242697 -420.175753) (xy 450.272163 -420.129903)
			(xy 450.307854 -420.088712) (xy 450.349045 -420.053021) (xy 450.394895 -420.023555) (xy 450.444472 -420.000913)
			(xy 450.496767 -419.985558) (xy 450.550715 -419.977802) (xy 450.605217 -419.977802) (xy 450.659165 -419.985558)
			(xy 450.71146 -420.000913) (xy 450.761037 -420.023555) (xy 450.806887 -420.053021) (xy 450.848078 -420.088712)
			(xy 450.883769 -420.129903) (xy 450.913235 -420.175753) (xy 450.935877 -420.22533) (xy 450.951232 -420.277625)
			(xy 450.958988 -420.331573) (xy 450.959474 -420.358824) (xy 450.959003 -420.386322) (xy 450.951108 -420.44075)
			(xy 450.935486 -420.493481) (xy 450.912458 -420.543425) (xy 450.882503 -420.589548) (xy 450.864732 -420.610538)
			(xy 450.858382 -420.61765) (xy 450.852032 -420.634668) (xy 450.852032 -420.720266) (xy 450.858382 -420.737284)
			(xy 450.864732 -420.744396) (xy 450.882511 -420.76538) (xy 450.912463 -420.811505) (xy 450.935486 -420.861451)
			(xy 450.951105 -420.914183) (xy 450.958995 -420.968611) (xy 450.959474 -420.99611) (xy 450.958988 -421.023361)
			(xy 450.951232 -421.077309) (xy 450.935877 -421.129604) (xy 450.913235 -421.179181) (xy 450.883769 -421.225031)
			(xy 450.848078 -421.266222) (xy 450.806887 -421.301913) (xy 450.761037 -421.331379) (xy 450.71146 -421.354021)
			(xy 450.659165 -421.369376) (xy 450.605217 -421.377132) (xy 450.550715 -421.377132) (xy 450.496767 -421.369376)
			(xy 450.444472 -421.354021) (xy 450.394895 -421.331379) (xy 450.349045 -421.301913) (xy 450.307854 -421.266222)
			(xy 450.272163 -421.225031) (xy 450.242697 -421.179181) (xy 450.220055 -421.129604) (xy 450.2047 -421.077309)
			(xy 450.196944 -421.023361) (xy 450.196458 -420.99611) (xy 448.348658 -420.99611) (xy 449.223384 -421.870886)
			(xy 449.234696 -421.882565) (xy 449.25457 -421.908297) (xy 449.263008 -421.922194) (xy 449.273978 -421.941824)
			(xy 449.289606 -421.983983) (xy 449.29756 -422.028237) (xy 449.29806 -422.050718) (xy 449.29806 -422.46804)
			(xy 449.298449 -422.478114) (xy 449.306193 -422.496712) (xy 449.313046 -422.504108) (xy 449.333893 -422.525711)
			(xy 449.369226 -422.574245) (xy 449.396518 -422.627716) (xy 449.415096 -422.684802) (xy 449.4245 -422.744094)
			(xy 449.42506 -422.77411) (xy 449.424574 -422.801361) (xy 449.416818 -422.855309) (xy 449.401463 -422.907604)
			(xy 449.378821 -422.957181) (xy 449.349355 -423.003031) (xy 449.313664 -423.044222) (xy 449.272473 -423.079913)
			(xy 449.226623 -423.109379) (xy 449.177046 -423.132021) (xy 449.124751 -423.147376) (xy 449.070803 -423.155132)
			(xy 449.016301 -423.155132) (xy 448.962353 -423.147376) (xy 448.910058 -423.132021) (xy 448.860481 -423.109379)
			(xy 448.814631 -423.079913) (xy 448.77344 -423.044222) (xy 448.737749 -423.003031) (xy 448.708283 -422.957181)
			(xy 448.685641 -422.907604) (xy 448.670286 -422.855309) (xy 448.66253 -422.801361) (xy 448.662044 -422.77411)
			(xy 448.662617 -422.744095) (xy 448.672029 -422.684806) (xy 448.690606 -422.627722) (xy 448.717891 -422.574251)
			(xy 448.753211 -422.52571) (xy 448.774058 -422.504108) (xy 448.780881 -422.496694) (xy 448.788612 -422.478106)
			(xy 448.789044 -422.46804) (xy 448.789044 -422.176956) (xy 448.78859 -422.166951) (xy 448.780866 -422.148488)
			(xy 448.774058 -422.141142) (xy 444.343028 -417.709858) (xy 444.331711 -417.698184) (xy 444.311841 -417.672449)
			(xy 444.303404 -417.65855) (xy 444.292414 -417.638931) (xy 444.276793 -417.596766) (xy 444.268847 -417.552508)
			(xy 444.268352 -417.530026) (xy 444.268352 -416.895026) (xy 444.267912 -416.885019) (xy 444.260178 -416.866556)
			(xy 444.253366 -416.859212) (xy 441.613036 -414.218628) (xy 441.601728 -414.206946) (xy 441.581852 -414.181216)
			(xy 441.573412 -414.16732) (xy 441.562411 -414.147706) (xy 441.546794 -414.105539) (xy 441.538852 -414.061279)
			(xy 441.53836 -414.038796) (xy 441.046616 -414.038796) (xy 441.046616 -414.5661) (xy 441.045998 -414.591097)
			(xy 441.036191 -414.640122) (xy 441.017012 -414.686293) (xy 440.989198 -414.727837) (xy 440.97194 -414.745932)
			(xy 439.483246 -416.234626) (xy 439.476408 -416.242028) (xy 439.468686 -416.260626) (xy 439.46826 -416.270694)
			(xy 439.46826 -417.982908) (xy 439.468731 -417.992912) (xy 439.476443 -418.011375) (xy 439.483246 -418.018722)
			(xy 439.504582 -418.040312) (xy 439.511474 -418.046622) (xy 439.528551 -418.054171) (xy 439.537856 -418.055044)
			(xy 439.566709 -418.057155) (xy 439.623323 -418.069057) (xy 439.677493 -418.089367) (xy 439.727977 -418.117619)
			(xy 439.773619 -418.153166) (xy 439.813374 -418.195195) (xy 439.846331 -418.242741) (xy 439.871735 -418.294716)
			(xy 439.889004 -418.34993) (xy 439.897743 -418.407118) (xy 439.898282 -418.436044) (xy 439.897868 -418.463308)
			(xy 439.890098 -418.517281) (xy 439.874725 -418.569597) (xy 439.852059 -418.619192) (xy 439.822565 -418.665055)
			(xy 439.786841 -418.706252) (xy 439.745616 -418.741943) (xy 439.69973 -418.771402) (xy 439.650117 -418.794029)
			(xy 439.597789 -418.809362) (xy 439.543811 -418.817089) (xy 439.489282 -418.817052) (xy 439.435314 -418.809254)
			(xy 439.383006 -418.793851) (xy 439.333424 -418.771159) (xy 439.287577 -418.741639) (xy 439.246399 -418.705892)
			(xy 439.210731 -418.664648) (xy 439.181297 -418.618745) (xy 439.158698 -418.56912) (xy 439.143394 -418.516783)
			(xy 439.135696 -418.462801) (xy 439.135266 -418.435536) (xy 439.135266 -418.425122) (xy 439.127646 -418.40658)
			(xy 439.044588 -418.323776) (xy 439.037227 -418.317007) (xy 439.018765 -418.30936) (xy 438.998783 -418.30936)
			(xy 438.980321 -418.317007) (xy 438.97296 -418.323776) (xy 438.889902 -418.40658) (xy 438.882282 -418.425122)
			(xy 438.882282 -418.435536) (xy 438.88192 -418.462815) (xy 438.874216 -418.516824) (xy 438.858897 -418.569186)
			(xy 438.836276 -418.618832) (xy 438.806815 -418.66475) (xy 438.771114 -418.706004) (xy 438.729901 -418.741752)
			(xy 438.684017 -418.771266) (xy 438.634397 -418.793943) (xy 438.582053 -418.809322) (xy 438.528052 -418.817089)
			(xy 438.500774 -418.817552) (xy 438.473514 -418.816998) (xy 438.41955 -418.809233) (xy 438.367241 -418.793863)
			(xy 438.317653 -418.771204) (xy 438.271796 -418.741715) (xy 438.230604 -418.705997) (xy 438.194917 -418.66478)
			(xy 438.165462 -418.618901) (xy 438.142839 -418.569297) (xy 438.127508 -418.516976) (xy 438.119782 -418.463006)
			(xy 437.345328 -418.463006) (xy 437.345328 -419.59911) (xy 440.425584 -419.59911) (xy 440.429655 -419.543488)
			(xy 440.441781 -419.489051) (xy 440.461704 -419.43696) (xy 440.489 -419.388325) (xy 440.523086 -419.344182)
			(xy 440.563235 -419.305473) (xy 440.608593 -419.273022) (xy 440.658193 -419.247521) (xy 440.710977 -419.229514)
			(xy 440.76582 -419.219384) (xy 440.821554 -419.217347) (xy 440.876991 -419.223447) (xy 440.930948 -419.237553)
			(xy 440.982277 -419.259365) (xy 441.029883 -419.288419) (xy 441.072751 -419.324094) (xy 441.109968 -419.365631)
			(xy 441.140741 -419.412144) (xy 441.140751 -419.412166) (xy 442.711584 -419.412166) (xy 442.715655 -419.356544)
			(xy 442.727781 -419.302107) (xy 442.747704 -419.250016) (xy 442.775 -419.201381) (xy 442.809086 -419.157238)
			(xy 442.849235 -419.118529) (xy 442.894593 -419.086078) (xy 442.944193 -419.060577) (xy 442.996977 -419.04257)
			(xy 443.05182 -419.03244) (xy 443.107554 -419.030403) (xy 443.162991 -419.036503) (xy 443.216948 -419.050609)
			(xy 443.268277 -419.072421) (xy 443.315883 -419.101475) (xy 443.358751 -419.13715) (xy 443.395968 -419.178687)
			(xy 443.426741 -419.2252) (xy 443.450413 -419.275697) (xy 443.466481 -419.329104) (xy 443.474601 -419.38428)
			(xy 443.47511 -419.412166) (xy 443.474601 -419.440052) (xy 443.466481 -419.495228) (xy 443.450413 -419.548635)
			(xy 443.426741 -419.599132) (xy 443.395968 -419.645645) (xy 443.358751 -419.687182) (xy 443.315883 -419.722857)
			(xy 443.268277 -419.751911) (xy 443.216948 -419.773723) (xy 443.162991 -419.787829) (xy 443.107554 -419.793929)
			(xy 443.05182 -419.791892) (xy 442.996977 -419.781762) (xy 442.944193 -419.763755) (xy 442.894593 -419.738254)
			(xy 442.849235 -419.705803) (xy 442.809086 -419.667094) (xy 442.775 -419.622951) (xy 442.747704 -419.574316)
			(xy 442.727781 -419.522225) (xy 442.715655 -419.467788) (xy 442.711584 -419.412166) (xy 441.140751 -419.412166)
			(xy 441.164413 -419.462641) (xy 441.180481 -419.516048) (xy 441.188601 -419.571224) (xy 441.18911 -419.59911)
			(xy 441.188601 -419.626996) (xy 441.180481 -419.682172) (xy 441.164413 -419.735579) (xy 441.140741 -419.786076)
			(xy 441.109968 -419.832589) (xy 441.072751 -419.874126) (xy 441.029883 -419.909801) (xy 440.982277 -419.938855)
			(xy 440.930948 -419.960667) (xy 440.876991 -419.974773) (xy 440.821554 -419.980873) (xy 440.76582 -419.978836)
			(xy 440.710977 -419.968706) (xy 440.658193 -419.950699) (xy 440.608593 -419.925198) (xy 440.563235 -419.892747)
			(xy 440.523086 -419.854038) (xy 440.489 -419.809895) (xy 440.461704 -419.76126) (xy 440.441781 -419.709169)
			(xy 440.429655 -419.654732) (xy 440.425584 -419.59911) (xy 437.345328 -419.59911) (xy 437.345328 -420.23411)
			(xy 444.235584 -420.23411) (xy 444.239655 -420.178488) (xy 444.251781 -420.124051) (xy 444.271704 -420.07196)
			(xy 444.299 -420.023325) (xy 444.333086 -419.979182) (xy 444.373235 -419.940473) (xy 444.418593 -419.908022)
			(xy 444.468193 -419.882521) (xy 444.520977 -419.864514) (xy 444.57582 -419.854384) (xy 444.631554 -419.852347)
			(xy 444.686991 -419.858447) (xy 444.740948 -419.872553) (xy 444.792277 -419.894365) (xy 444.839883 -419.923419)
			(xy 444.882751 -419.959094) (xy 444.919968 -420.000631) (xy 444.950741 -420.047144) (xy 444.974413 -420.097641)
			(xy 444.990481 -420.151048) (xy 444.998601 -420.206224) (xy 444.99911 -420.23411) (xy 445.505584 -420.23411)
			(xy 445.509655 -420.178488) (xy 445.521781 -420.124051) (xy 445.541704 -420.07196) (xy 445.569 -420.023325)
			(xy 445.603086 -419.979182) (xy 445.643235 -419.940473) (xy 445.688593 -419.908022) (xy 445.738193 -419.882521)
			(xy 445.790977 -419.864514) (xy 445.84582 -419.854384) (xy 445.901554 -419.852347) (xy 445.956991 -419.858447)
			(xy 446.010948 -419.872553) (xy 446.062277 -419.894365) (xy 446.109883 -419.923419) (xy 446.152751 -419.959094)
			(xy 446.189968 -420.000631) (xy 446.220741 -420.047144) (xy 446.244413 -420.097641) (xy 446.260481 -420.151048)
			(xy 446.268601 -420.206224) (xy 446.26911 -420.23411) (xy 446.268601 -420.261996) (xy 446.260481 -420.317172)
			(xy 446.244413 -420.370579) (xy 446.220741 -420.421076) (xy 446.189968 -420.467589) (xy 446.152751 -420.509126)
			(xy 446.109883 -420.544801) (xy 446.062277 -420.573855) (xy 446.010948 -420.595667) (xy 445.956991 -420.609773)
			(xy 445.901554 -420.615873) (xy 445.84582 -420.613836) (xy 445.790977 -420.603706) (xy 445.738193 -420.585699)
			(xy 445.688593 -420.560198) (xy 445.643235 -420.527747) (xy 445.603086 -420.489038) (xy 445.569 -420.444895)
			(xy 445.541704 -420.39626) (xy 445.521781 -420.344169) (xy 445.509655 -420.289732) (xy 445.505584 -420.23411)
			(xy 444.99911 -420.23411) (xy 444.998601 -420.261996) (xy 444.990481 -420.317172) (xy 444.974413 -420.370579)
			(xy 444.950741 -420.421076) (xy 444.919968 -420.467589) (xy 444.882751 -420.509126) (xy 444.839883 -420.544801)
			(xy 444.792277 -420.573855) (xy 444.740948 -420.595667) (xy 444.686991 -420.609773) (xy 444.631554 -420.615873)
			(xy 444.57582 -420.613836) (xy 444.520977 -420.603706) (xy 444.468193 -420.585699) (xy 444.418593 -420.560198)
			(xy 444.373235 -420.527747) (xy 444.333086 -420.489038) (xy 444.299 -420.444895) (xy 444.271704 -420.39626)
			(xy 444.251781 -420.344169) (xy 444.239655 -420.289732) (xy 444.235584 -420.23411) (xy 437.345328 -420.23411)
			(xy 437.345328 -420.86911) (xy 440.180982 -420.86911) (xy 440.185053 -420.813488) (xy 440.197179 -420.759051)
			(xy 440.217102 -420.70696) (xy 440.244398 -420.658325) (xy 440.278484 -420.614182) (xy 440.318633 -420.575473)
			(xy 440.363991 -420.543022) (xy 440.413591 -420.517521) (xy 440.466375 -420.499514) (xy 440.521218 -420.489384)
			(xy 440.576952 -420.487347) (xy 440.632389 -420.493447) (xy 440.686346 -420.507553) (xy 440.737675 -420.529365)
			(xy 440.785281 -420.558419) (xy 440.828149 -420.594094) (xy 440.865366 -420.635631) (xy 440.896139 -420.682144)
			(xy 440.919811 -420.732641) (xy 440.92266 -420.74211) (xy 442.838584 -420.74211) (xy 442.842655 -420.686488)
			(xy 442.854781 -420.632051) (xy 442.874704 -420.57996) (xy 442.902 -420.531325) (xy 442.936086 -420.487182)
			(xy 442.976235 -420.448473) (xy 443.021593 -420.416022) (xy 443.071193 -420.390521) (xy 443.123977 -420.372514)
			(xy 443.17882 -420.362384) (xy 443.234554 -420.360347) (xy 443.289991 -420.366447) (xy 443.343948 -420.380553)
			(xy 443.395277 -420.402365) (xy 443.442883 -420.431419) (xy 443.485751 -420.467094) (xy 443.522968 -420.508631)
			(xy 443.553741 -420.555144) (xy 443.577413 -420.605641) (xy 443.593481 -420.659048) (xy 443.601601 -420.714224)
			(xy 443.60211 -420.74211) (xy 443.601601 -420.769996) (xy 443.593481 -420.825172) (xy 443.577413 -420.878579)
			(xy 443.553741 -420.929076) (xy 443.522968 -420.975589) (xy 443.485751 -421.017126) (xy 443.442883 -421.052801)
			(xy 443.395277 -421.081855) (xy 443.343948 -421.103667) (xy 443.289991 -421.117773) (xy 443.234554 -421.123873)
			(xy 443.17882 -421.121836) (xy 443.123977 -421.111706) (xy 443.071193 -421.093699) (xy 443.021593 -421.068198)
			(xy 442.976235 -421.035747) (xy 442.936086 -420.997038) (xy 442.902 -420.952895) (xy 442.874704 -420.90426)
			(xy 442.854781 -420.852169) (xy 442.842655 -420.797732) (xy 442.838584 -420.74211) (xy 440.92266 -420.74211)
			(xy 440.935879 -420.786048) (xy 440.943999 -420.841224) (xy 440.944508 -420.86911) (xy 440.943999 -420.896996)
			(xy 440.935879 -420.952172) (xy 440.919811 -421.005579) (xy 440.896139 -421.056076) (xy 440.865366 -421.102589)
			(xy 440.828149 -421.144126) (xy 440.785281 -421.179801) (xy 440.737675 -421.208855) (xy 440.686346 -421.230667)
			(xy 440.632389 -421.244773) (xy 440.576952 -421.250873) (xy 440.521218 -421.248836) (xy 440.466375 -421.238706)
			(xy 440.413591 -421.220699) (xy 440.363991 -421.195198) (xy 440.318633 -421.162747) (xy 440.278484 -421.124038)
			(xy 440.244398 -421.079895) (xy 440.217102 -421.03126) (xy 440.197179 -420.979169) (xy 440.185053 -420.924732)
			(xy 440.180982 -420.86911) (xy 437.345328 -420.86911) (xy 437.345328 -423.215562) (xy 440.204098 -423.215562)
			(xy 440.204539 -423.188278) (xy 440.212331 -423.134267) (xy 440.227736 -423.081918) (xy 440.25044 -423.032296)
			(xy 440.279981 -422.986414) (xy 440.315756 -422.945208) (xy 440.357035 -422.909517) (xy 440.402977 -422.880069)
			(xy 440.427618 -422.868344) (xy 440.44102 -422.861668) (xy 440.463477 -422.841883) (xy 440.479241 -422.816442)
			(xy 440.486961 -422.787526) (xy 440.485975 -422.757613) (xy 440.476368 -422.729268) (xy 440.458964 -422.70492)
			(xy 440.44743 -422.69537) (xy 440.424753 -422.677154) (xy 440.384614 -422.63506) (xy 440.351326 -422.587363)
			(xy 440.325662 -422.535167) (xy 440.308214 -422.479682) (xy 440.299387 -422.422192) (xy 440.29884 -422.39311)
			(xy 440.299326 -422.365859) (xy 440.307082 -422.311911) (xy 440.322437 -422.259616) (xy 440.345079 -422.210039)
			(xy 440.374545 -422.164189) (xy 440.410236 -422.122998) (xy 440.451427 -422.087307) (xy 440.497277 -422.057841)
			(xy 440.546854 -422.035199) (xy 440.599149 -422.019844) (xy 440.653097 -422.012088) (xy 440.707599 -422.012088)
			(xy 440.761547 -422.019844) (xy 440.813842 -422.035199) (xy 440.863419 -422.057841) (xy 440.909269 -422.087307)
			(xy 440.95046 -422.122998) (xy 440.986151 -422.164189) (xy 441.015617 -422.210039) (xy 441.038259 -422.259616)
			(xy 441.053614 -422.311911) (xy 441.06137 -422.365859) (xy 441.061856 -422.39311) (xy 441.061419 -422.420395)
			(xy 441.05363 -422.474406) (xy 441.038226 -422.526757) (xy 441.015522 -422.57638) (xy 440.98598 -422.622263)
			(xy 440.950204 -422.663469) (xy 440.908923 -422.699159) (xy 440.862979 -422.728605) (xy 440.838336 -422.740328)
			(xy 440.824956 -422.747048) (xy 440.802492 -422.76682) (xy 440.786721 -422.792252) (xy 440.778996 -422.821163)
			(xy 440.779978 -422.851072) (xy 440.789584 -422.879414) (xy 440.80699 -422.903756) (xy 440.818524 -422.913302)
			(xy 440.841247 -422.931463) (xy 440.881381 -422.97357) (xy 440.914661 -423.021279) (xy 440.940317 -423.073485)
			(xy 440.957756 -423.128979) (xy 440.966572 -423.186477) (xy 440.967114 -423.215562) (xy 440.966628 -423.242813)
			(xy 440.958872 -423.296761) (xy 440.943517 -423.349056) (xy 440.920875 -423.398633) (xy 440.891409 -423.444483)
			(xy 440.855718 -423.485674) (xy 440.814527 -423.521365) (xy 440.768677 -423.550831) (xy 440.7191 -423.573473)
			(xy 440.666805 -423.588828) (xy 440.612857 -423.596584) (xy 440.558355 -423.596584) (xy 440.504407 -423.588828)
			(xy 440.452112 -423.573473) (xy 440.402535 -423.550831) (xy 440.356685 -423.521365) (xy 440.315494 -423.485674)
			(xy 440.279803 -423.444483) (xy 440.250337 -423.398633) (xy 440.227695 -423.349056) (xy 440.21234 -423.296761)
			(xy 440.204584 -423.242813) (xy 440.204098 -423.215562) (xy 437.345328 -423.215562) (xy 437.345328 -423.478452)
			(xy 437.345446 -423.483548) (xy 437.347502 -423.49353) (xy 437.349392 -423.498264) (xy 437.360822 -423.524934)
			(xy 437.367426 -423.531792) (xy 437.385875 -423.551319) (xy 437.417667 -423.59462) (xy 437.443072 -423.641953)
			(xy 437.461585 -423.692381) (xy 437.472842 -423.744908) (xy 437.47662 -423.798494) (xy 437.472844 -423.852081)
			(xy 437.461589 -423.904608) (xy 437.443076 -423.955037) (xy 437.417673 -424.00237) (xy 437.385882 -424.045672)
			(xy 437.367426 -424.065192) (xy 437.360822 -424.07205) (xy 437.349392 -424.09872) (xy 437.347524 -424.10346)
			(xy 437.345483 -424.11344) (xy 437.345328 -424.118532) (xy 437.345328 -424.80611) (xy 437.580784 -424.80611)
			(xy 437.584855 -424.750488) (xy 437.596981 -424.696051) (xy 437.616904 -424.64396) (xy 437.6442 -424.595325)
			(xy 437.678286 -424.551182) (xy 437.718435 -424.512473) (xy 437.763793 -424.480022) (xy 437.813393 -424.454521)
			(xy 437.866177 -424.436514) (xy 437.92102 -424.426384) (xy 437.976754 -424.424347) (xy 438.032191 -424.430447)
			(xy 438.086148 -424.444553) (xy 438.137477 -424.466365) (xy 438.185083 -424.495419) (xy 438.227951 -424.531094)
			(xy 438.265168 -424.572631) (xy 438.295941 -424.619144) (xy 438.313008 -424.655552) (xy 447.233765 -424.655552)
			(xy 447.233765 -424.601048) (xy 447.241522 -424.547098) (xy 447.256878 -424.494801) (xy 447.27952 -424.445222)
			(xy 447.308987 -424.39937) (xy 447.34468 -424.358179) (xy 447.385872 -424.322486) (xy 447.431724 -424.293019)
			(xy 447.481303 -424.270377) (xy 447.5336 -424.255022) (xy 447.58755 -424.247265) (xy 447.614802 -424.246802)
			(xy 447.642246 -424.247291) (xy 447.696568 -424.255158) (xy 447.749197 -424.270743) (xy 447.799044 -424.293723)
			(xy 447.82232 -424.30827) (xy 447.834456 -424.315613) (xy 447.861559 -424.323945) (xy 447.889908 -424.324497)
			(xy 447.917314 -424.317226) (xy 447.941661 -424.302693) (xy 447.961068 -424.282021) (xy 447.974037 -424.256806)
			(xy 447.97726 -424.242992) (xy 447.983544 -424.214555) (xy 448.003543 -424.159862) (xy 448.031619 -424.108841)
			(xy 448.067119 -424.062677) (xy 448.10922 -424.022442) (xy 448.156944 -423.989069) (xy 448.209184 -423.963333)
			(xy 448.264727 -423.945832) (xy 448.322285 -423.936971) (xy 448.351402 -423.936414) (xy 448.378655 -423.936856)
			(xy 448.432605 -423.944613) (xy 448.484903 -423.959969) (xy 448.534483 -423.982612) (xy 448.580336 -424.01208)
			(xy 448.621528 -424.047774) (xy 448.657221 -424.088966) (xy 448.686689 -424.134819) (xy 448.709331 -424.184399)
			(xy 448.724687 -424.236697) (xy 448.732444 -424.290647) (xy 448.732444 -424.345153) (xy 448.724687 -424.399103)
			(xy 448.709331 -424.451401) (xy 448.686689 -424.500981) (xy 448.657221 -424.546834) (xy 448.621528 -424.588026)
			(xy 448.580336 -424.62372) (xy 448.534483 -424.653188) (xy 448.484903 -424.675831) (xy 448.432605 -424.691187)
			(xy 448.378655 -424.698944) (xy 448.351402 -424.69943) (xy 448.323958 -424.698934) (xy 448.269637 -424.691069)
			(xy 448.217008 -424.675486) (xy 448.167161 -424.652508) (xy 448.143884 -424.637962) (xy 448.131723 -424.630667)
			(xy 448.104631 -424.622343) (xy 448.076293 -424.621793) (xy 448.048898 -424.629059) (xy 448.024558 -424.64358)
			(xy 448.005151 -424.664236) (xy 447.992174 -424.689434) (xy 447.988944 -424.70324) (xy 447.982701 -424.731688)
			(xy 447.962704 -424.786389) (xy 447.934628 -424.837415) (xy 447.899125 -424.883583) (xy 447.857018 -424.923821)
			(xy 447.809287 -424.957193) (xy 447.757038 -424.982924) (xy 447.701487 -425.000418) (xy 447.643922 -425.009268)
			(xy 447.614802 -425.009818) (xy 447.58755 -425.009335) (xy 447.5336 -425.001578) (xy 447.481303 -424.986223)
			(xy 447.431724 -424.963581) (xy 447.385872 -424.934114) (xy 447.34468 -424.898421) (xy 447.308987 -424.85723)
			(xy 447.27952 -424.811378) (xy 447.256878 -424.761799) (xy 447.241522 -424.709502) (xy 447.233765 -424.655552)
			(xy 438.313008 -424.655552) (xy 438.319613 -424.669641) (xy 438.335681 -424.723048) (xy 438.343801 -424.778224)
			(xy 438.34431 -424.80611) (xy 438.343801 -424.833996) (xy 438.335681 -424.889172) (xy 438.319613 -424.942579)
			(xy 438.295941 -424.993076) (xy 438.265168 -425.039589) (xy 438.246781 -425.06011) (xy 440.298584 -425.06011)
			(xy 440.302655 -425.004488) (xy 440.314781 -424.950051) (xy 440.334704 -424.89796) (xy 440.362 -424.849325)
			(xy 440.396086 -424.805182) (xy 440.436235 -424.766473) (xy 440.481593 -424.734022) (xy 440.531193 -424.708521)
			(xy 440.583977 -424.690514) (xy 440.63882 -424.680384) (xy 440.694554 -424.678347) (xy 440.749991 -424.684447)
			(xy 440.803948 -424.698553) (xy 440.855277 -424.720365) (xy 440.902883 -424.749419) (xy 440.945751 -424.785094)
			(xy 440.982968 -424.826631) (xy 441.013741 -424.873144) (xy 441.037413 -424.923641) (xy 441.053481 -424.977048)
			(xy 441.061601 -425.032224) (xy 441.06211 -425.06011) (xy 441.061601 -425.087996) (xy 441.053481 -425.143172)
			(xy 441.037413 -425.196579) (xy 441.013741 -425.247076) (xy 440.982968 -425.293589) (xy 440.945751 -425.335126)
			(xy 440.902883 -425.370801) (xy 440.855277 -425.399855) (xy 440.803948 -425.421667) (xy 440.749991 -425.435773)
			(xy 440.694554 -425.441873) (xy 440.63882 -425.439836) (xy 440.583977 -425.429706) (xy 440.531193 -425.411699)
			(xy 440.481593 -425.386198) (xy 440.436235 -425.353747) (xy 440.396086 -425.315038) (xy 440.362 -425.270895)
			(xy 440.334704 -425.22226) (xy 440.314781 -425.170169) (xy 440.302655 -425.115732) (xy 440.298584 -425.06011)
			(xy 438.246781 -425.06011) (xy 438.227951 -425.081126) (xy 438.185083 -425.116801) (xy 438.137477 -425.145855)
			(xy 438.086148 -425.167667) (xy 438.032191 -425.181773) (xy 437.976754 -425.187873) (xy 437.92102 -425.185836)
			(xy 437.866177 -425.175706) (xy 437.813393 -425.157699) (xy 437.763793 -425.132198) (xy 437.718435 -425.099747)
			(xy 437.678286 -425.061038) (xy 437.6442 -425.016895) (xy 437.616904 -424.96826) (xy 437.596981 -424.916169)
			(xy 437.584855 -424.861732) (xy 437.580784 -424.80611) (xy 437.345328 -424.80611) (xy 437.345328 -426.07611)
			(xy 448.045584 -426.07611) (xy 448.049655 -426.020488) (xy 448.061781 -425.966051) (xy 448.081704 -425.91396)
			(xy 448.109 -425.865325) (xy 448.143086 -425.821182) (xy 448.183235 -425.782473) (xy 448.228593 -425.750022)
			(xy 448.278193 -425.724521) (xy 448.330977 -425.706514) (xy 448.38582 -425.696384) (xy 448.441554 -425.694347)
			(xy 448.496991 -425.700447) (xy 448.550948 -425.714553) (xy 448.602277 -425.736365) (xy 448.649883 -425.765419)
			(xy 448.692751 -425.801094) (xy 448.729968 -425.842631) (xy 448.760741 -425.889144) (xy 448.776945 -425.92371)
			(xy 450.299834 -425.92371) (xy 450.303905 -425.868088) (xy 450.316031 -425.813651) (xy 450.335954 -425.76156)
			(xy 450.36325 -425.712925) (xy 450.397336 -425.668782) (xy 450.437485 -425.630073) (xy 450.482843 -425.597622)
			(xy 450.532443 -425.572121) (xy 450.585227 -425.554114) (xy 450.64007 -425.543984) (xy 450.695804 -425.541947)
			(xy 450.751241 -425.548047) (xy 450.805198 -425.562153) (xy 450.856527 -425.583965) (xy 450.904133 -425.613019)
			(xy 450.947001 -425.648694) (xy 450.984218 -425.690231) (xy 451.014991 -425.736744) (xy 451.038663 -425.787241)
			(xy 451.054731 -425.840648) (xy 451.062851 -425.895824) (xy 451.06336 -425.92371) (xy 451.062851 -425.951596)
			(xy 451.054731 -426.006772) (xy 451.038663 -426.060179) (xy 451.014991 -426.110676) (xy 450.984218 -426.157189)
			(xy 450.947001 -426.198726) (xy 450.904133 -426.234401) (xy 450.856527 -426.263455) (xy 450.805198 -426.285267)
			(xy 450.751241 -426.299373) (xy 450.695804 -426.305473) (xy 450.64007 -426.303436) (xy 450.585227 -426.293306)
			(xy 450.532443 -426.275299) (xy 450.482843 -426.249798) (xy 450.437485 -426.217347) (xy 450.397336 -426.178638)
			(xy 450.36325 -426.134495) (xy 450.335954 -426.08586) (xy 450.316031 -426.033769) (xy 450.303905 -425.979332)
			(xy 450.299834 -425.92371) (xy 448.776945 -425.92371) (xy 448.784413 -425.939641) (xy 448.800481 -425.993048)
			(xy 448.808601 -426.048224) (xy 448.80911 -426.07611) (xy 448.808601 -426.103996) (xy 448.800481 -426.159172)
			(xy 448.784413 -426.212579) (xy 448.760741 -426.263076) (xy 448.729968 -426.309589) (xy 448.692751 -426.351126)
			(xy 448.649883 -426.386801) (xy 448.602277 -426.415855) (xy 448.550948 -426.437667) (xy 448.496991 -426.451773)
			(xy 448.441554 -426.457873) (xy 448.38582 -426.455836) (xy 448.330977 -426.445706) (xy 448.278193 -426.427699)
			(xy 448.228593 -426.402198) (xy 448.183235 -426.369747) (xy 448.143086 -426.331038) (xy 448.109 -426.286895)
			(xy 448.081704 -426.23826) (xy 448.061781 -426.186169) (xy 448.049655 -426.131732) (xy 448.045584 -426.07611)
			(xy 437.345328 -426.07611) (xy 437.345328 -426.83811) (xy 440.247784 -426.83811) (xy 440.251855 -426.782488)
			(xy 440.263981 -426.728051) (xy 440.283904 -426.67596) (xy 440.3112 -426.627325) (xy 440.345286 -426.583182)
			(xy 440.385435 -426.544473) (xy 440.430793 -426.512022) (xy 440.480393 -426.486521) (xy 440.533177 -426.468514)
			(xy 440.58802 -426.458384) (xy 440.643754 -426.456347) (xy 440.699191 -426.462447) (xy 440.753148 -426.476553)
			(xy 440.804477 -426.498365) (xy 440.852083 -426.527419) (xy 440.894951 -426.563094) (xy 440.932168 -426.604631)
			(xy 440.962941 -426.651144) (xy 440.986613 -426.701641) (xy 441.002681 -426.755048) (xy 441.010801 -426.810224)
			(xy 441.01131 -426.83811) (xy 441.010801 -426.865996) (xy 441.002681 -426.921172) (xy 440.986613 -426.974579)
			(xy 440.962941 -427.025076) (xy 440.932168 -427.071589) (xy 440.894951 -427.113126) (xy 440.852083 -427.148801)
			(xy 440.804477 -427.177855) (xy 440.753148 -427.199667) (xy 440.699191 -427.213773) (xy 440.643754 -427.219873)
			(xy 440.58802 -427.217836) (xy 440.533177 -427.207706) (xy 440.480393 -427.189699) (xy 440.430793 -427.164198)
			(xy 440.385435 -427.131747) (xy 440.345286 -427.093038) (xy 440.3112 -427.048895) (xy 440.283904 -427.00026)
			(xy 440.263981 -426.948169) (xy 440.251855 -426.893732) (xy 440.247784 -426.83811) (xy 437.345328 -426.83811)
			(xy 437.345328 -427.482) (xy 437.345752 -427.49207) (xy 437.353469 -427.510671) (xy 437.360314 -427.518068)
			(xy 437.442356 -427.60011) (xy 447.029584 -427.60011) (xy 447.033655 -427.544488) (xy 447.045781 -427.490051)
			(xy 447.065704 -427.43796) (xy 447.093 -427.389325) (xy 447.127086 -427.345182) (xy 447.167235 -427.306473)
			(xy 447.212593 -427.274022) (xy 447.262193 -427.248521) (xy 447.314977 -427.230514) (xy 447.36982 -427.220384)
			(xy 447.425554 -427.218347) (xy 447.480991 -427.224447) (xy 447.534948 -427.238553) (xy 447.586277 -427.260365)
			(xy 447.633883 -427.289419) (xy 447.676751 -427.325094) (xy 447.713968 -427.366631) (xy 447.744741 -427.413144)
			(xy 447.768413 -427.463641) (xy 447.784481 -427.517048) (xy 447.792601 -427.572224) (xy 447.79311 -427.60011)
			(xy 447.792601 -427.627996) (xy 447.784481 -427.683172) (xy 447.768413 -427.736579) (xy 447.744741 -427.787076)
			(xy 447.713968 -427.833589) (xy 447.676751 -427.875126) (xy 447.633883 -427.910801) (xy 447.586277 -427.939855)
			(xy 447.534948 -427.961667) (xy 447.480991 -427.975773) (xy 447.425554 -427.981873) (xy 447.36982 -427.979836)
			(xy 447.314977 -427.969706) (xy 447.262193 -427.951699) (xy 447.212593 -427.926198) (xy 447.167235 -427.893747)
			(xy 447.127086 -427.855038) (xy 447.093 -427.810895) (xy 447.065704 -427.76226) (xy 447.045781 -427.710169)
			(xy 447.033655 -427.655732) (xy 447.029584 -427.60011) (xy 437.442356 -427.60011) (xy 438.1681 -428.325854)
			(xy 443.607365 -428.325854) (xy 443.607365 -428.271346) (xy 443.615123 -428.217392) (xy 443.630481 -428.165093)
			(xy 443.653126 -428.115511) (xy 443.682598 -428.069657) (xy 443.718295 -428.028464) (xy 443.759492 -427.992771)
			(xy 443.805349 -427.963305) (xy 443.854934 -427.940666) (xy 443.907236 -427.925314) (xy 443.96119 -427.917562)
			(xy 443.988444 -427.917102) (xy 444.017293 -427.917646) (xy 444.074335 -427.926313) (xy 444.129421 -427.943475)
			(xy 444.181293 -427.968738) (xy 444.228767 -428.001527) (xy 444.270761 -428.041093) (xy 444.306316 -428.086533)
			(xy 444.32093 -428.111412) (xy 444.3281 -428.123128) (xy 444.347478 -428.142576) (xy 444.371341 -428.156153)
			(xy 444.39796 -428.162874) (xy 444.425407 -428.162254) (xy 444.451695 -428.154337) (xy 444.47492 -428.139697)
			(xy 444.4934 -428.119393) (xy 444.5 -428.107348) (xy 444.512235 -428.084067) (xy 444.54219 -428.040838)
			(xy 444.577801 -428.002135) (xy 444.618393 -427.968693) (xy 444.663195 -427.941146) (xy 444.711358 -427.920018)
			(xy 444.761968 -427.905708) (xy 444.814063 -427.898489) (xy 444.84036 -427.898052) (xy 444.867612 -427.898593)
			(xy 444.921561 -427.906344) (xy 444.973859 -427.921695) (xy 445.023439 -427.944333) (xy 445.069292 -427.973797)
			(xy 445.110485 -428.009487) (xy 445.146179 -428.050676) (xy 445.175648 -428.096526) (xy 445.198291 -428.146104)
			(xy 445.213647 -428.198399) (xy 445.221405 -428.252348) (xy 445.221405 -428.306852) (xy 445.213647 -428.360801)
			(xy 445.198291 -428.413096) (xy 445.175648 -428.462674) (xy 445.146179 -428.508524) (xy 445.110485 -428.549713)
			(xy 445.069292 -428.585403) (xy 445.023439 -428.614867) (xy 444.973859 -428.637505) (xy 444.921561 -428.652856)
			(xy 444.867612 -428.660607) (xy 444.84036 -428.661068) (xy 444.811511 -428.660536) (xy 444.754467 -428.651868)
			(xy 444.69938 -428.634706) (xy 444.647508 -428.609441) (xy 444.600033 -428.57665) (xy 444.55804 -428.537081)
			(xy 444.522487 -428.491638) (xy 444.507874 -428.466758) (xy 444.500695 -428.45505) (xy 444.481316 -428.435607)
			(xy 444.457456 -428.422035) (xy 444.43084 -428.415316) (xy 444.403397 -428.415935) (xy 444.377112 -428.423849)
			(xy 444.353888 -428.438484) (xy 444.335406 -428.458781) (xy 444.328804 -428.470822) (xy 444.316553 -428.494094)
			(xy 444.286602 -428.537325) (xy 444.250993 -428.576029) (xy 444.210404 -428.609472) (xy 444.165604 -428.63702)
			(xy 444.117443 -428.65815) (xy 444.066835 -428.672461) (xy 444.01474 -428.679681) (xy 443.988444 -428.680118)
			(xy 443.96119 -428.679638) (xy 443.907236 -428.671886) (xy 443.854934 -428.656534) (xy 443.805349 -428.633895)
			(xy 443.759492 -428.604429) (xy 443.718295 -428.568736) (xy 443.682598 -428.527543) (xy 443.653126 -428.481689)
			(xy 443.630481 -428.432107) (xy 443.615123 -428.379808) (xy 443.607365 -428.325854) (xy 438.1681 -428.325854)
			(xy 438.585864 -428.743618) (xy 438.593262 -428.750463) (xy 438.611861 -428.758187) (xy 438.621932 -428.758604)
			(xy 440.361324 -428.758604) (xy 440.371392 -428.759032) (xy 440.38999 -428.766753) (xy 440.397392 -428.77359)
			(xy 442.038486 -430.414684) (xy 442.045888 -430.421519) (xy 442.064487 -430.429224) (xy 442.074554 -430.42967)
			(xy 449.479416 -430.42967)
		)
		(stroke
			(width 0)
			(type solid)
		)
		(fill yes)
		(layer "In2.Cu")
		(net "GND")
	)
	(gr_poly
		(pts
			(xy 20.433538 -416.80892) (xy 20.443606 -416.808491) (xy 20.462202 -416.800769) (xy 20.469606 -416.793934)
			(xy 24.251158 -413.012382) (xy 24.258006 -413.004985) (xy 24.265741 -412.986386) (xy 24.266144 -412.976314)
			(xy 24.266144 -410.306012) (xy 24.265722 -410.295942) (xy 24.258004 -410.27734) (xy 24.251158 -410.269944)
			(xy 21.29917 -407.317956) (xy 21.281949 -407.299846) (xy 21.254212 -407.258285) (xy 21.235106 -407.212115)
			(xy 21.225364 -407.163107) (xy 21.224748 -407.138124) (xy 21.224748 -404.097744) (xy 21.225355 -404.072759)
			(xy 21.235089 -404.023746) (xy 21.254192 -403.977571) (xy 21.281931 -403.936007) (xy 21.29917 -403.917912)
			(xy 22.525736 -402.691346) (xy 22.532517 -402.683922) (xy 22.540122 -402.665326) (xy 22.540468 -402.655278)
			(xy 22.540468 -400.797522) (xy 22.540025 -400.787492) (xy 22.532441 -400.768927) (xy 22.525736 -400.761454)
			(xy 21.942552 -400.178524) (xy 21.935191 -400.171755) (xy 21.916729 -400.164108) (xy 21.896747 -400.164108)
			(xy 21.878285 -400.171755) (xy 21.870924 -400.178524) (xy 21.841714 -400.20748) (xy 21.823618 -400.224735)
			(xy 21.782071 -400.252541) (xy 21.735901 -400.271713) (xy 21.686878 -400.281515) (xy 21.661882 -400.282156)
			(xy 14.473936 -400.282156) (xy 14.44894 -400.281518) (xy 14.399918 -400.271716) (xy 14.353749 -400.25254)
			(xy 14.312207 -400.224728) (xy 14.294104 -400.20748) (xy 13.795248 -399.708624) (xy 13.777991 -399.690529)
			(xy 13.75018 -399.648983) (xy 13.731004 -399.602813) (xy 13.721199 -399.553789) (xy 13.720572 -399.528792)
			(xy 13.720572 -398.70761) (xy 13.721213 -398.682616) (xy 13.73102 -398.633597) (xy 13.7502 -398.587433)
			(xy 13.778017 -398.545897) (xy 13.795248 -398.527778) (xy 14.701012 -397.622014) (xy 14.70779 -397.614589)
			(xy 14.715387 -397.595993) (xy 14.715744 -397.585946) (xy 14.715744 -393.573) (xy 14.716376 -393.548002)
			(xy 14.726168 -393.498973) (xy 14.745335 -393.452795) (xy 14.773142 -393.411244) (xy 14.79042 -393.393168)
			(xy 15.258542 -392.925046) (xy 15.266162 -392.906504) (xy 15.266162 -392.89609) (xy 15.266591 -392.868813)
			(xy 15.274291 -392.814808) (xy 15.289605 -392.762449) (xy 15.312219 -392.712806) (xy 15.341673 -392.666889)
			(xy 15.377367 -392.625635) (xy 15.418572 -392.589885) (xy 15.464449 -392.560368) (xy 15.514061 -392.537687)
			(xy 15.566399 -392.522302) (xy 15.620394 -392.514528) (xy 15.64767 -392.514074) (xy 15.67629 -392.51459)
			(xy 15.732888 -392.523142) (xy 15.787575 -392.540045) (xy 15.839128 -392.56492) (xy 15.863062 -392.580622)
			(xy 15.871698 -392.586464) (xy 15.891256 -392.590528) (xy 15.983204 -392.571986) (xy 15.999968 -392.56081)
			(xy 16.005556 -392.55192) (xy 16.020717 -392.529372) (xy 16.056406 -392.488404) (xy 16.097546 -392.452913)
			(xy 16.143304 -392.423616) (xy 16.192756 -392.401108) (xy 16.244901 -392.385841) (xy 16.298683 -392.378127)
			(xy 16.32585 -392.377676) (xy 16.353101 -392.378162) (xy 16.407048 -392.385918) (xy 16.459342 -392.401273)
			(xy 16.508919 -392.423914) (xy 16.554769 -392.45338) (xy 16.595959 -392.489071) (xy 16.63165 -392.530261)
			(xy 16.661116 -392.576111) (xy 16.683757 -392.625688) (xy 16.699112 -392.677982) (xy 16.706868 -392.731929)
			(xy 16.706868 -392.786431) (xy 16.699112 -392.840378) (xy 16.683757 -392.892672) (xy 16.661116 -392.942249)
			(xy 16.63165 -392.988099) (xy 16.595959 -393.029289) (xy 16.554769 -393.06498) (xy 16.508919 -393.094446)
			(xy 16.459342 -393.117087) (xy 16.407048 -393.132442) (xy 16.353101 -393.140198) (xy 16.32585 -393.140692)
			(xy 16.29723 -393.140178) (xy 16.240631 -393.131627) (xy 16.185943 -393.114726) (xy 16.134389 -393.089851)
			(xy 16.110458 -393.074144) (xy 16.101822 -393.068302) (xy 16.082264 -393.064238) (xy 15.990316 -393.08278)
			(xy 15.973552 -393.093956) (xy 15.967964 -393.102846) (xy 15.952781 -393.125421) (xy 15.917035 -393.166432)
			(xy 15.875826 -393.20195) (xy 15.829989 -393.231252) (xy 15.780454 -393.253745) (xy 15.728226 -393.268973)
			(xy 15.674364 -393.276626) (xy 15.647162 -393.27709) (xy 15.636748 -393.27709) (xy 15.618206 -393.28471)
			(xy 15.320772 -393.582144) (xy 16.440148 -393.582144) (xy 16.444219 -393.526522) (xy 16.456345 -393.472085)
			(xy 16.476268 -393.419994) (xy 16.503564 -393.371359) (xy 16.53765 -393.327216) (xy 16.577799 -393.288507)
			(xy 16.623157 -393.256056) (xy 16.672757 -393.230555) (xy 16.725541 -393.212548) (xy 16.780384 -393.202418)
			(xy 16.836118 -393.200381) (xy 16.891555 -393.206481) (xy 16.945512 -393.220587) (xy 16.996841 -393.242399)
			(xy 17.044447 -393.271453) (xy 17.087315 -393.307128) (xy 17.124532 -393.348665) (xy 17.155305 -393.395178)
			(xy 17.178977 -393.445675) (xy 17.195045 -393.499082) (xy 17.203165 -393.554258) (xy 17.203674 -393.582144)
			(xy 17.203165 -393.61003) (xy 17.195045 -393.665206) (xy 17.178977 -393.718613) (xy 17.155305 -393.76911)
			(xy 17.124532 -393.815623) (xy 17.087315 -393.85716) (xy 17.044447 -393.892835) (xy 16.996841 -393.921889)
			(xy 16.945512 -393.943701) (xy 16.891555 -393.957807) (xy 16.836118 -393.963907) (xy 16.780384 -393.96187)
			(xy 16.725541 -393.95174) (xy 16.672757 -393.933733) (xy 16.623157 -393.908232) (xy 16.577799 -393.875781)
			(xy 16.53765 -393.837072) (xy 16.503564 -393.792929) (xy 16.476268 -393.744294) (xy 16.456345 -393.692203)
			(xy 16.444219 -393.637766) (xy 16.440148 -393.582144) (xy 15.320772 -393.582144) (xy 15.239492 -393.663424)
			(xy 15.232719 -393.67085) (xy 15.225135 -393.689447) (xy 15.22476 -393.699492) (xy 15.22476 -394.310452)
			(xy 22.100762 -394.310452) (xy 22.100762 -394.255948) (xy 22.108518 -394.201998) (xy 22.123874 -394.149702)
			(xy 22.146516 -394.100123) (xy 22.175983 -394.054271) (xy 22.211675 -394.013079) (xy 22.252866 -393.977386)
			(xy 22.298718 -393.947918) (xy 22.348296 -393.925276) (xy 22.400593 -393.90992) (xy 22.454542 -393.902162)
			(xy 22.481794 -393.901676) (xy 22.510712 -393.90217) (xy 22.567886 -393.9109) (xy 22.623086 -393.928161)
			(xy 22.675049 -393.953557) (xy 22.722582 -393.986506) (xy 22.764596 -394.026253) (xy 22.782784 -394.048742)
			(xy 22.79035 -394.057499) (xy 22.811106 -394.067683) (xy 22.822662 -394.0683) (xy 22.902926 -394.0683)
			(xy 22.914488 -394.067687) (xy 22.93526 -394.057523) (xy 22.942804 -394.048742) (xy 22.961003 -394.026265)
			(xy 23.00302 -393.986528) (xy 23.050553 -393.953587) (xy 23.102513 -393.928197) (xy 23.157709 -393.91094)
			(xy 23.214878 -393.902211) (xy 23.243794 -393.901676) (xy 23.271046 -393.902171) (xy 23.324995 -393.909927)
			(xy 23.377292 -393.925282) (xy 23.42687 -393.947923) (xy 23.472722 -393.97739) (xy 23.513914 -394.013082)
			(xy 23.549607 -394.054273) (xy 23.579074 -394.100124) (xy 23.601716 -394.149703) (xy 23.617072 -394.201999)
			(xy 23.624829 -394.255948) (xy 23.624829 -394.310452) (xy 23.617072 -394.364401) (xy 23.601716 -394.416697)
			(xy 23.579074 -394.466276) (xy 23.549607 -394.512127) (xy 23.513914 -394.553318) (xy 23.472722 -394.58901)
			(xy 23.42687 -394.618477) (xy 23.377292 -394.641118) (xy 23.324995 -394.656473) (xy 23.271046 -394.664229)
			(xy 23.243794 -394.664692) (xy 23.214877 -394.664181) (xy 23.157705 -394.655451) (xy 23.102506 -394.638191)
			(xy 23.050544 -394.612799) (xy 23.003011 -394.579854) (xy 22.960994 -394.540112) (xy 22.942804 -394.517626)
			(xy 22.935249 -394.508858) (xy 22.914484 -394.498681) (xy 22.902926 -394.498068) (xy 22.822662 -394.498068)
			(xy 22.811095 -394.49865) (xy 22.790322 -394.508834) (xy 22.782784 -394.517626) (xy 22.764609 -394.540123)
			(xy 22.722585 -394.579856) (xy 22.675046 -394.612792) (xy 22.623082 -394.638178) (xy 22.567882 -394.655432)
			(xy 22.510711 -394.664158) (xy 22.481794 -394.664692) (xy 22.454542 -394.664238) (xy 22.400593 -394.65648)
			(xy 22.348296 -394.641124) (xy 22.298718 -394.618482) (xy 22.252866 -394.589014) (xy 22.211675 -394.553321)
			(xy 22.175983 -394.512129) (xy 22.146516 -394.466277) (xy 22.123874 -394.416698) (xy 22.108518 -394.364402)
			(xy 22.100762 -394.310452) (xy 15.22476 -394.310452) (xy 15.22476 -395.964664) (xy 19.52498 -395.964664)
			(xy 19.525405 -395.937292) (xy 19.53323 -395.88311) (xy 19.548728 -395.830606) (xy 19.571579 -395.78086)
			(xy 19.601314 -395.734896) (xy 19.61896 -395.713966) (xy 19.625056 -395.706854) (xy 19.631406 -395.689836)
			(xy 19.631406 -395.604492) (xy 19.625056 -395.587474) (xy 19.61896 -395.580362) (xy 19.60133 -395.559423)
			(xy 19.571618 -395.513451) (xy 19.548781 -395.463706) (xy 19.533287 -395.411207) (xy 19.525456 -395.357033)
			(xy 19.52498 -395.329664) (xy 19.525466 -395.302413) (xy 19.533222 -395.248465) (xy 19.548577 -395.19617)
			(xy 19.571219 -395.146593) (xy 19.600685 -395.100743) (xy 19.636376 -395.059552) (xy 19.677567 -395.023861)
			(xy 19.723417 -394.994395) (xy 19.772994 -394.971753) (xy 19.825289 -394.956398) (xy 19.879237 -394.948642)
			(xy 19.933739 -394.948642) (xy 19.987687 -394.956398) (xy 20.039982 -394.971753) (xy 20.089559 -394.994395)
			(xy 20.135409 -395.023861) (xy 20.1766 -395.059552) (xy 20.212291 -395.100743) (xy 20.241757 -395.146593)
			(xy 20.264399 -395.19617) (xy 20.279754 -395.248465) (xy 20.28751 -395.302413) (xy 20.287996 -395.329664)
			(xy 20.28751 -395.357034) (xy 20.279697 -395.411212) (xy 20.264213 -395.463715) (xy 20.241375 -395.513462)
			(xy 20.211655 -395.55943) (xy 20.194016 -395.580362) (xy 20.18792 -395.587474) (xy 20.18157 -395.604492)
			(xy 20.18157 -395.689836) (xy 20.18792 -395.706854) (xy 20.194016 -395.713966) (xy 20.211655 -395.734898)
			(xy 20.241366 -395.780871) (xy 20.264202 -395.830619) (xy 20.279693 -395.883119) (xy 20.287522 -395.937295)
			(xy 20.287996 -395.964664) (xy 20.28751 -395.991915) (xy 20.279754 -396.045863) (xy 20.264399 -396.098158)
			(xy 20.241757 -396.147735) (xy 20.212291 -396.193585) (xy 20.1766 -396.234776) (xy 20.135409 -396.270467)
			(xy 20.089559 -396.299933) (xy 20.039982 -396.322575) (xy 19.987687 -396.33793) (xy 19.933739 -396.345686)
			(xy 19.879237 -396.345686) (xy 19.825289 -396.33793) (xy 19.772994 -396.322575) (xy 19.723417 -396.299933)
			(xy 19.677567 -396.270467) (xy 19.636376 -396.234776) (xy 19.600685 -396.193585) (xy 19.571219 -396.147735)
			(xy 19.548577 -396.098158) (xy 19.533222 -396.045863) (xy 19.525466 -395.991915) (xy 19.52498 -395.964664)
			(xy 15.22476 -395.964664) (xy 15.22476 -397.712438) (xy 15.224124 -397.737435) (xy 15.214327 -397.78646)
			(xy 15.195155 -397.832632) (xy 15.167345 -397.874178) (xy 15.150084 -397.89227) (xy 14.24432 -398.798034)
			(xy 14.237546 -398.805459) (xy 14.229961 -398.824057) (xy 14.229588 -398.834102) (xy 14.229588 -398.878552)
			(xy 19.56308 -398.878552) (xy 19.563557 -398.851182) (xy 19.571369 -398.797003) (xy 19.586855 -398.744499)
			(xy 19.609694 -398.694752) (xy 19.639419 -398.648785) (xy 19.65706 -398.627854) (xy 19.663156 -398.620742)
			(xy 19.669506 -398.603724) (xy 19.669506 -398.51838) (xy 19.663156 -398.501362) (xy 19.65706 -398.49425)
			(xy 19.639424 -398.473315) (xy 19.609713 -398.427343) (xy 19.586877 -398.377596) (xy 19.571385 -398.325096)
			(xy 19.563555 -398.270921) (xy 19.56308 -398.243552) (xy 19.563499 -398.217882) (xy 19.570385 -398.167007)
			(xy 19.584026 -398.117513) (xy 19.604176 -398.070293) (xy 19.630472 -398.026199) (xy 19.662439 -397.986026)
			(xy 19.680682 -397.967962) (xy 19.687787 -397.960528) (xy 19.69591 -397.941656) (xy 19.69643 -397.931386)
			(xy 19.69643 -397.85798) (xy 19.695957 -397.847701) (xy 19.687813 -397.828823) (xy 19.680682 -397.821404)
			(xy 19.662461 -397.803318) (xy 19.630484 -397.763154) (xy 19.604181 -397.719066) (xy 19.584026 -397.67185)
			(xy 19.570383 -397.622358) (xy 19.563498 -397.571483) (xy 19.56308 -397.545814) (xy 19.563535 -397.518443)
			(xy 19.571352 -397.464263) (xy 19.586843 -397.411759) (xy 19.609688 -397.362012) (xy 19.639416 -397.316046)
			(xy 19.65706 -397.295116) (xy 19.663156 -397.288004) (xy 19.669506 -397.270986) (xy 19.669506 -397.185642)
			(xy 19.663156 -397.168624) (xy 19.65706 -397.161512) (xy 19.639406 -397.140592) (xy 19.609698 -397.094615)
			(xy 19.586865 -397.044864) (xy 19.571378 -396.992361) (xy 19.563552 -396.938184) (xy 19.56308 -396.910814)
			(xy 19.563566 -396.883563) (xy 19.571322 -396.829615) (xy 19.586677 -396.77732) (xy 19.609319 -396.727743)
			(xy 19.638785 -396.681893) (xy 19.674476 -396.640702) (xy 19.715667 -396.605011) (xy 19.761517 -396.575545)
			(xy 19.811094 -396.552903) (xy 19.863389 -396.537548) (xy 19.917337 -396.529792) (xy 19.971839 -396.529792)
			(xy 20.025787 -396.537548) (xy 20.078082 -396.552903) (xy 20.127659 -396.575545) (xy 20.173509 -396.605011)
			(xy 20.2147 -396.640702) (xy 20.250391 -396.681893) (xy 20.279857 -396.727743) (xy 20.302499 -396.77732)
			(xy 20.317854 -396.829615) (xy 20.32561 -396.883563) (xy 20.326096 -396.910814) (xy 20.325639 -396.938185)
			(xy 20.317819 -396.992364) (xy 20.302328 -397.044867) (xy 20.279484 -397.094614) (xy 20.249758 -397.140581)
			(xy 20.232116 -397.161512) (xy 20.22602 -397.168624) (xy 20.21967 -397.185642) (xy 20.21967 -397.270986)
			(xy 20.22602 -397.288004) (xy 20.232116 -397.295116) (xy 20.249732 -397.316067) (xy 20.279446 -397.362035)
			(xy 20.302287 -397.411778) (xy 20.317783 -397.464274) (xy 20.325618 -397.518446) (xy 20.326096 -397.545814)
			(xy 20.325662 -397.571483) (xy 20.31878 -397.622359) (xy 20.305143 -397.671853) (xy 20.284995 -397.719073)
			(xy 20.258702 -397.763167) (xy 20.226736 -397.80334) (xy 20.208494 -397.821404) (xy 20.201401 -397.828847)
			(xy 20.193272 -397.847712) (xy 20.192746 -397.85798) (xy 20.192746 -397.931386) (xy 20.193244 -397.941662)
			(xy 20.201371 -397.960539) (xy 20.208494 -397.967962) (xy 20.226761 -397.986003) (xy 20.258731 -398.026178)
			(xy 20.285026 -398.070276) (xy 20.305172 -398.117501) (xy 20.318807 -398.167) (xy 20.325682 -398.217881)
			(xy 20.326096 -398.243552) (xy 20.325527 -398.273028) (xy 20.316465 -398.33128) (xy 20.29855 -398.387445)
			(xy 20.272207 -398.440185) (xy 20.238064 -398.488244) (xy 20.217892 -398.509744) (xy 20.211344 -398.517069)
			(xy 20.203907 -398.535237) (xy 20.203414 -398.54505) (xy 20.203414 -398.577054) (xy 20.203878 -398.586871)
			(xy 20.211338 -398.605035) (xy 20.217892 -398.61236) (xy 20.231608 -398.627346) (xy 20.239228 -398.635982)
			(xy 20.260056 -398.644872) (xy 20.36191 -398.641316) (xy 20.381976 -398.631156) (xy 20.389088 -398.621758)
			(xy 20.407229 -398.598733) (xy 20.449382 -398.558002) (xy 20.497271 -398.524202) (xy 20.549769 -398.498128)
			(xy 20.605639 -398.480395) (xy 20.663564 -398.471421) (xy 20.692872 -398.470882) (xy 20.721929 -398.471455)
			(xy 20.77937 -398.480283) (xy 20.834807 -398.497722) (xy 20.886956 -398.52337) (xy 20.934611 -398.556633)
			(xy 20.956016 -398.576292) (xy 20.963382 -398.58315) (xy 20.981162 -398.590262) (xy 21.071332 -398.590262)
			(xy 21.089112 -398.58315) (xy 21.096478 -398.576292) (xy 21.117891 -398.556639) (xy 21.165535 -398.523356)
			(xy 21.217681 -398.497695) (xy 21.273119 -398.480251) (xy 21.330563 -398.471428) (xy 21.359622 -398.470882)
			(xy 21.386871 -398.47139) (xy 21.440815 -398.479149) (xy 21.493106 -398.494505) (xy 21.542679 -398.517147)
			(xy 21.588525 -398.546613) (xy 21.629712 -398.582304) (xy 21.6654 -398.623492) (xy 21.694864 -398.66934)
			(xy 21.717502 -398.718915) (xy 21.732856 -398.771206) (xy 21.740612 -398.825151) (xy 21.740612 -398.879649)
			(xy 21.732856 -398.933594) (xy 21.717502 -398.985885) (xy 21.694864 -399.03546) (xy 21.6654 -399.081308)
			(xy 21.629712 -399.122496) (xy 21.588526 -399.158187) (xy 21.542679 -399.187653) (xy 21.493106 -399.210295)
			(xy 21.440815 -399.225651) (xy 21.386871 -399.23341) (xy 21.359622 -399.233898) (xy 21.330564 -399.233334)
			(xy 21.273123 -399.224505) (xy 21.217686 -399.207064) (xy 21.165536 -399.181413) (xy 21.117882 -399.148148)
			(xy 21.096478 -399.128488) (xy 21.089112 -399.12163) (xy 21.071332 -399.114518) (xy 20.981162 -399.114518)
			(xy 20.963382 -399.12163) (xy 20.956016 -399.128488) (xy 20.934618 -399.148157) (xy 20.886969 -399.181435)
			(xy 20.834819 -399.207092) (xy 20.779378 -399.224533) (xy 20.721932 -399.233353) (xy 20.692872 -399.233898)
			(xy 20.665778 -399.233464) (xy 20.612138 -399.225788) (xy 20.560125 -399.210593) (xy 20.510787 -399.188187)
			(xy 20.465119 -399.159021) (xy 20.42404 -399.123682) (xy 20.405852 -399.103596) (xy 20.398232 -399.09496)
			(xy 20.377404 -399.08607) (xy 20.27555 -399.089626) (xy 20.255484 -399.099786) (xy 20.248372 -399.109184)
			(xy 20.230239 -399.132216) (xy 20.188086 -399.172949) (xy 20.140196 -399.20675) (xy 20.087696 -399.232823)
			(xy 20.031824 -399.250554) (xy 19.973897 -399.259524) (xy 19.944588 -399.26006) (xy 19.917333 -399.259656)
			(xy 19.863377 -399.251896) (xy 19.811075 -399.236536) (xy 19.761492 -399.213889) (xy 19.715636 -399.184415)
			(xy 19.674442 -399.148715) (xy 19.638749 -399.107516) (xy 19.609282 -399.061656) (xy 19.586643 -399.012069)
			(xy 19.571291 -398.959764) (xy 19.56354 -398.905807) (xy 19.56308 -398.878552) (xy 14.229588 -398.878552)
			(xy 14.229588 -399.4023) (xy 14.230034 -399.412329) (xy 14.237619 -399.430893) (xy 14.24432 -399.438368)
			(xy 14.56436 -399.758408) (xy 14.571783 -399.765191) (xy 14.590379 -399.772798) (xy 14.600428 -399.77314)
			(xy 21.53539 -399.77314) (xy 21.545418 -399.772694) (xy 21.563978 -399.765103) (xy 21.571458 -399.758408)
			(xy 24.373332 -396.956534) (xy 24.380112 -396.94911) (xy 24.387713 -396.930513) (xy 24.388064 -396.920466)
			(xy 24.388064 -393.074144) (xy 24.387579 -393.064182) (xy 24.379989 -393.045758) (xy 24.373332 -393.03833)
			(xy 24.352442 -393.01672) (xy 24.317043 -392.968148) (xy 24.289696 -392.914628) (xy 24.271076 -392.857483)
			(xy 24.261643 -392.798125) (xy 24.261064 -392.768074) (xy 24.261552 -392.740823) (xy 24.269311 -392.686877)
			(xy 24.284668 -392.634584) (xy 24.30731 -392.585008) (xy 24.336777 -392.539159) (xy 24.372468 -392.497969)
			(xy 24.413657 -392.462278) (xy 24.459506 -392.432811) (xy 24.509082 -392.410169) (xy 24.561375 -392.394811)
			(xy 24.615321 -392.387052) (xy 24.642572 -392.386566) (xy 24.668494 -392.387) (xy 24.71986 -392.394022)
			(xy 24.7698 -392.40794) (xy 24.817394 -392.428497) (xy 24.861763 -392.455315) (xy 24.902088 -392.487898)
			(xy 24.920194 -392.506454) (xy 24.92756 -392.514328) (xy 24.946864 -392.522456) (xy 25.043384 -392.521186)
			(xy 25.062434 -392.51255) (xy 25.0698 -392.504422) (xy 25.087965 -392.484843) (xy 25.128825 -392.45045)
			(xy 25.174083 -392.422092) (xy 25.222853 -392.400323) (xy 25.274182 -392.385568) (xy 25.327068 -392.378115)
			(xy 25.353772 -392.377676) (xy 25.381027 -392.378137) (xy 25.434984 -392.385891) (xy 25.487287 -392.401245)
			(xy 25.536873 -392.423887) (xy 25.582731 -392.453356) (xy 25.623929 -392.489051) (xy 25.659628 -392.530246)
			(xy 25.689099 -392.576103) (xy 25.711745 -392.625687) (xy 25.727103 -392.677989) (xy 25.734861 -392.731945)
			(xy 25.734861 -392.786455) (xy 25.727103 -392.840411) (xy 25.711745 -392.892713) (xy 25.689099 -392.942297)
			(xy 25.659627 -392.988154) (xy 25.623929 -393.029349) (xy 25.582731 -393.065044) (xy 25.536873 -393.094513)
			(xy 25.487287 -393.117155) (xy 25.434984 -393.132509) (xy 25.381027 -393.140263) (xy 25.353772 -393.140692)
			(xy 25.327848 -393.140261) (xy 25.276479 -393.133245) (xy 25.226533 -393.119333) (xy 25.178933 -393.098782)
			(xy 25.134557 -393.07197) (xy 25.094224 -393.039392) (xy 25.07615 -393.020804) (xy 25.068784 -393.01293)
			(xy 25.04948 -393.004802) (xy 24.95296 -393.006072) (xy 24.93391 -393.014708) (xy 24.926544 -393.022836)
			(xy 24.911812 -393.03833) (xy 24.905131 -393.045741) (xy 24.897558 -393.064177) (xy 24.89708 -393.074144)
			(xy 24.89708 -393.761468) (xy 25.528776 -393.761468) (xy 25.532847 -393.705846) (xy 25.544973 -393.651409)
			(xy 25.564896 -393.599318) (xy 25.592192 -393.550683) (xy 25.626278 -393.50654) (xy 25.666427 -393.467831)
			(xy 25.711785 -393.43538) (xy 25.761385 -393.409879) (xy 25.814169 -393.391872) (xy 25.869012 -393.381742)
			(xy 25.924746 -393.379705) (xy 25.980183 -393.385805) (xy 26.03414 -393.399911) (xy 26.085469 -393.421723)
			(xy 26.133075 -393.450777) (xy 26.175943 -393.486452) (xy 26.21316 -393.527989) (xy 26.243933 -393.574502)
			(xy 26.267605 -393.624999) (xy 26.283673 -393.678406) (xy 26.291793 -393.733582) (xy 26.292302 -393.761468)
			(xy 26.291793 -393.789354) (xy 26.283673 -393.84453) (xy 26.267605 -393.897937) (xy 26.243933 -393.948434)
			(xy 26.21316 -393.994947) (xy 26.175943 -394.036484) (xy 26.133075 -394.072159) (xy 26.085469 -394.101213)
			(xy 26.03414 -394.123025) (xy 25.980183 -394.137131) (xy 25.924746 -394.143231) (xy 25.869012 -394.141194)
			(xy 25.814169 -394.131064) (xy 25.761385 -394.113057) (xy 25.711785 -394.087556) (xy 25.666427 -394.055105)
			(xy 25.626278 -394.016396) (xy 25.592192 -393.972253) (xy 25.564896 -393.923618) (xy 25.544973 -393.871527)
			(xy 25.532847 -393.81709) (xy 25.528776 -393.761468) (xy 24.89708 -393.761468) (xy 24.89708 -395.77772)
			(xy 28.172664 -395.77772) (xy 28.173126 -395.750349) (xy 28.180943 -395.69617) (xy 28.196432 -395.643666)
			(xy 28.219275 -395.593919) (xy 28.249001 -395.547953) (xy 28.266644 -395.527022) (xy 28.27274 -395.51991)
			(xy 28.27909 -395.502892) (xy 28.27909 -395.417548) (xy 28.27274 -395.40053) (xy 28.266644 -395.393418)
			(xy 28.249007 -395.372484) (xy 28.219293 -395.326513) (xy 28.196456 -395.276766) (xy 28.180965 -395.224265)
			(xy 28.173137 -395.170089) (xy 28.172664 -395.14272) (xy 28.17315 -395.115469) (xy 28.180906 -395.061521)
			(xy 28.196261 -395.009226) (xy 28.218903 -394.959649) (xy 28.248369 -394.913799) (xy 28.28406 -394.872608)
			(xy 28.325251 -394.836917) (xy 28.371101 -394.807451) (xy 28.420678 -394.784809) (xy 28.472973 -394.769454)
			(xy 28.526921 -394.761698) (xy 28.581423 -394.761698) (xy 28.635371 -394.769454) (xy 28.687666 -394.784809)
			(xy 28.737243 -394.807451) (xy 28.783093 -394.836917) (xy 28.824284 -394.872608) (xy 28.859975 -394.913799)
			(xy 28.889441 -394.959649) (xy 28.912083 -395.009226) (xy 28.927438 -395.061521) (xy 28.935194 -395.115469)
			(xy 28.93568 -395.14272) (xy 28.935231 -395.170091) (xy 28.927409 -395.224271) (xy 28.911917 -395.276774)
			(xy 28.889071 -395.326521) (xy 28.859343 -395.372487) (xy 28.8417 -395.393418) (xy 28.835604 -395.40053)
			(xy 28.829254 -395.417548) (xy 28.829254 -395.502892) (xy 28.835604 -395.51991) (xy 28.8417 -395.527022)
			(xy 28.859316 -395.547973) (xy 28.889031 -395.59394) (xy 28.911872 -395.643683) (xy 28.927368 -395.69618)
			(xy 28.935203 -395.750352) (xy 28.93568 -395.77772) (xy 28.935194 -395.804971) (xy 28.927438 -395.858919)
			(xy 28.912083 -395.911214) (xy 28.889441 -395.960791) (xy 28.859975 -396.006641) (xy 28.824284 -396.047832)
			(xy 28.783093 -396.083523) (xy 28.737243 -396.112989) (xy 28.687666 -396.135631) (xy 28.635371 -396.150986)
			(xy 28.581423 -396.158742) (xy 28.526921 -396.158742) (xy 28.472973 -396.150986) (xy 28.420678 -396.135631)
			(xy 28.371101 -396.112989) (xy 28.325251 -396.083523) (xy 28.28406 -396.047832) (xy 28.248369 -396.006641)
			(xy 28.218903 -395.960791) (xy 28.196261 -395.911214) (xy 28.180906 -395.858919) (xy 28.17315 -395.804971)
			(xy 28.172664 -395.77772) (xy 24.89708 -395.77772) (xy 24.89708 -397.046958) (xy 24.896442 -397.071954)
			(xy 24.886642 -397.120978) (xy 24.867469 -397.167148) (xy 24.839658 -397.208693) (xy 24.822404 -397.22679)
			(xy 24.535413 -397.51381) (xy 28.152598 -397.51381) (xy 28.15307 -397.48644) (xy 28.160887 -397.432261)
			(xy 28.176374 -397.379758) (xy 28.199215 -397.330011) (xy 28.228938 -397.284044) (xy 28.246578 -397.263112)
			(xy 28.252674 -397.256) (xy 28.259024 -397.238982) (xy 28.259024 -397.153638) (xy 28.252674 -397.13662)
			(xy 28.246578 -397.129508) (xy 28.228926 -397.108587) (xy 28.199217 -397.06261) (xy 28.176384 -397.01286)
			(xy 28.160896 -396.960357) (xy 28.15307 -396.90618) (xy 28.152598 -396.87881) (xy 28.153084 -396.851559)
			(xy 28.16084 -396.797611) (xy 28.176195 -396.745316) (xy 28.198837 -396.695739) (xy 28.228303 -396.649889)
			(xy 28.263994 -396.608698) (xy 28.305185 -396.573007) (xy 28.351035 -396.543541) (xy 28.400612 -396.520899)
			(xy 28.452907 -396.505544) (xy 28.506855 -396.497788) (xy 28.561357 -396.497788) (xy 28.615305 -396.505544)
			(xy 28.6676 -396.520899) (xy 28.717177 -396.543541) (xy 28.763027 -396.573007) (xy 28.804218 -396.608698)
			(xy 28.839909 -396.649889) (xy 28.869375 -396.695739) (xy 28.892017 -396.745316) (xy 28.907372 -396.797611)
			(xy 28.915128 -396.851559) (xy 28.915614 -396.87881) (xy 28.91515 -396.90618) (xy 28.907331 -396.960359)
			(xy 28.891842 -397.012862) (xy 28.868999 -397.062609) (xy 28.839275 -397.108576) (xy 28.821634 -397.129508)
			(xy 28.815538 -397.13662) (xy 28.809188 -397.153638) (xy 28.809188 -397.238982) (xy 28.815538 -397.256)
			(xy 28.821634 -397.263112) (xy 28.839251 -397.284062) (xy 28.868965 -397.33003) (xy 28.891804 -397.379773)
			(xy 28.907301 -397.43227) (xy 28.915136 -397.486442) (xy 28.915614 -397.51381) (xy 28.915128 -397.541061)
			(xy 28.907372 -397.595009) (xy 28.892017 -397.647304) (xy 28.869375 -397.696881) (xy 28.839909 -397.742731)
			(xy 28.804218 -397.783922) (xy 28.763027 -397.819613) (xy 28.717177 -397.849079) (xy 28.6676 -397.871721)
			(xy 28.615305 -397.887076) (xy 28.561357 -397.894832) (xy 28.506855 -397.894832) (xy 28.452907 -397.887076)
			(xy 28.400612 -397.871721) (xy 28.351035 -397.849079) (xy 28.305185 -397.819613) (xy 28.263994 -397.783922)
			(xy 28.228303 -397.742731) (xy 28.198837 -397.696881) (xy 28.176195 -397.647304) (xy 28.16084 -397.595009)
			(xy 28.153084 -397.541061) (xy 28.152598 -397.51381) (xy 24.535413 -397.51381) (xy 22.30247 -399.746978)
			(xy 22.295759 -399.754378) (xy 22.288122 -399.772816) (xy 22.288119 -399.792773) (xy 22.295752 -399.811212)
			(xy 22.30247 -399.818606) (xy 22.966683 -400.48307) (xy 23.694136 -400.48307) (xy 23.694576 -400.455699)
			(xy 23.702399 -400.401518) (xy 23.717893 -400.349014) (xy 23.740741 -400.299268) (xy 23.770472 -400.253303)
			(xy 23.788116 -400.232372) (xy 23.794212 -400.22526) (xy 23.800562 -400.208242) (xy 23.800562 -400.122898)
			(xy 23.794212 -400.10588) (xy 23.788116 -400.098768) (xy 23.770498 -400.077819) (xy 23.740782 -400.031851)
			(xy 23.717942 -399.982108) (xy 23.702446 -399.929611) (xy 23.694613 -399.875438) (xy 23.694136 -399.84807)
			(xy 23.694527 -399.820814) (xy 23.702289 -399.766859) (xy 23.717651 -399.714557) (xy 23.740301 -399.664973)
			(xy 23.769776 -399.619118) (xy 23.805477 -399.577925) (xy 23.846678 -399.542231) (xy 23.892538 -399.512765)
			(xy 23.942126 -399.490125) (xy 23.994431 -399.474774) (xy 24.048388 -399.467022) (xy 24.075644 -399.466562)
			(xy 24.105766 -399.467165) (xy 24.165261 -399.476638) (xy 24.222529 -399.495341) (xy 24.276146 -399.52281)
			(xy 24.324782 -399.558362) (xy 24.346408 -399.579338) (xy 24.35352 -399.586704) (xy 24.372316 -399.594324)
			(xy 24.464772 -399.594324) (xy 24.483568 -399.586704) (xy 24.49068 -399.579338) (xy 24.512297 -399.558349)
			(xy 24.560927 -399.52278) (xy 24.614545 -399.495301) (xy 24.671818 -399.476595) (xy 24.731319 -399.467128)
			(xy 24.761444 -399.466562) (xy 24.788814 -399.467046) (xy 24.842993 -399.474857) (xy 24.895496 -399.490341)
			(xy 24.945243 -399.513179) (xy 24.99121 -399.542902) (xy 25.012142 -399.560542) (xy 25.019254 -399.566638)
			(xy 25.036272 -399.572988) (xy 25.121616 -399.572988) (xy 25.138634 -399.566638) (xy 25.145746 -399.560542)
			(xy 25.166693 -399.542921) (xy 25.212661 -399.513205) (xy 25.262405 -399.490365) (xy 25.314902 -399.47487)
			(xy 25.369076 -399.467038) (xy 25.396444 -399.466562) (xy 25.423695 -399.467037) (xy 25.477642 -399.474799)
			(xy 25.529935 -399.490158) (xy 25.57951 -399.512802) (xy 25.625359 -399.54227) (xy 25.666548 -399.577962)
			(xy 25.702239 -399.619152) (xy 25.731705 -399.665002) (xy 25.754347 -399.714579) (xy 25.769704 -399.766872)
			(xy 25.777464 -399.820819) (xy 25.777952 -399.84807) (xy 25.77748 -399.87544) (xy 25.769665 -399.929619)
			(xy 25.754178 -399.982123) (xy 25.731338 -400.03187) (xy 25.701613 -400.077837) (xy 25.683972 -400.098768)
			(xy 25.677876 -400.10588) (xy 25.671526 -400.122898) (xy 25.671526 -400.208242) (xy 25.677876 -400.22526)
			(xy 25.683972 -400.232372) (xy 25.701607 -400.253307) (xy 25.73132 -400.299279) (xy 25.754158 -400.349025)
			(xy 25.76965 -400.401526) (xy 25.777478 -400.455701) (xy 25.777952 -400.48307) (xy 25.777394 -400.510318)
			(xy 25.769643 -400.564261) (xy 25.754294 -400.616552) (xy 25.731659 -400.666126) (xy 25.725734 -400.675348)
			(xy 27.191462 -400.675348) (xy 27.191889 -400.64897) (xy 27.199135 -400.596713) (xy 27.21351 -400.545953)
			(xy 27.234739 -400.497656) (xy 27.262418 -400.452744) (xy 27.29602 -400.412072) (xy 27.31516 -400.393916)
			(xy 27.322678 -400.386475) (xy 27.33123 -400.367147) (xy 27.33167 -400.356578) (xy 27.33167 -400.281648)
			(xy 27.331059 -400.271115) (xy 27.322551 -400.251837) (xy 27.31516 -400.24431) (xy 27.295999 -400.226174)
			(xy 27.262389 -400.185504) (xy 27.234707 -400.140589) (xy 27.213481 -400.092288) (xy 27.199116 -400.041521)
			(xy 27.191887 -399.989258) (xy 27.191462 -399.962878) (xy 27.191948 -399.935627) (xy 27.199704 -399.881679)
			(xy 27.215059 -399.829384) (xy 27.237701 -399.779807) (xy 27.267167 -399.733957) (xy 27.302858 -399.692766)
			(xy 27.344049 -399.657075) (xy 27.389899 -399.627609) (xy 27.439476 -399.604967) (xy 27.491771 -399.589612)
			(xy 27.545719 -399.581856) (xy 27.600221 -399.581856) (xy 27.654169 -399.589612) (xy 27.706464 -399.604967)
			(xy 27.756041 -399.627609) (xy 27.801891 -399.657075) (xy 27.843082 -399.692766) (xy 27.878773 -399.733957)
			(xy 27.908239 -399.779807) (xy 27.930881 -399.829384) (xy 27.946236 -399.881679) (xy 27.953992 -399.935627)
			(xy 27.954478 -399.962878) (xy 27.954055 -399.989256) (xy 27.946806 -400.041512) (xy 27.93243 -400.092272)
			(xy 27.9112 -400.140569) (xy 27.883521 -400.185481) (xy 27.84992 -400.226153) (xy 27.83078 -400.24431)
			(xy 27.82331 -400.251783) (xy 27.814786 -400.271093) (xy 27.81427 -400.281648) (xy 27.81427 -400.356578)
			(xy 27.814855 -400.367114) (xy 27.82338 -400.386393) (xy 27.83078 -400.393916) (xy 27.849913 -400.412081)
			(xy 27.883524 -400.452745) (xy 27.911209 -400.497654) (xy 27.932439 -400.54595) (xy 27.946811 -400.596712)
			(xy 27.954048 -400.648969) (xy 27.954478 -400.675348) (xy 27.953992 -400.702599) (xy 27.946236 -400.756547)
			(xy 27.930881 -400.808842) (xy 27.908239 -400.858419) (xy 27.878773 -400.904269) (xy 27.843082 -400.94546)
			(xy 27.801891 -400.981151) (xy 27.756041 -401.010617) (xy 27.706464 -401.033259) (xy 27.654169 -401.048614)
			(xy 27.600221 -401.05637) (xy 27.545719 -401.05637) (xy 27.491771 -401.048614) (xy 27.439476 -401.033259)
			(xy 27.389899 -401.010617) (xy 27.344049 -400.981151) (xy 27.302858 -400.94546) (xy 27.267167 -400.904269)
			(xy 27.237701 -400.858419) (xy 27.215059 -400.808842) (xy 27.199704 -400.756547) (xy 27.191948 -400.702599)
			(xy 27.191462 -400.675348) (xy 25.725734 -400.675348) (xy 25.7022 -400.711974) (xy 25.666516 -400.753164)
			(xy 25.625334 -400.788856) (xy 25.579491 -400.818324) (xy 25.529921 -400.840968) (xy 25.477634 -400.856327)
			(xy 25.423692 -400.864089) (xy 25.396444 -400.864578) (xy 25.369074 -400.864092) (xy 25.314896 -400.856279)
			(xy 25.262393 -400.840795) (xy 25.212646 -400.817958) (xy 25.166678 -400.788237) (xy 25.145746 -400.770598)
			(xy 25.138634 -400.764502) (xy 25.121616 -400.758152) (xy 25.036272 -400.758152) (xy 25.019254 -400.764502)
			(xy 25.012142 -400.770598) (xy 24.991205 -400.788231) (xy 24.945233 -400.817943) (xy 24.895487 -400.840781)
			(xy 24.842988 -400.856273) (xy 24.788813 -400.864103) (xy 24.761444 -400.864578) (xy 24.731322 -400.863971)
			(xy 24.671828 -400.854498) (xy 24.614561 -400.835795) (xy 24.560943 -400.808327) (xy 24.512306 -400.772777)
			(xy 24.49068 -400.751802) (xy 24.483568 -400.744436) (xy 24.464772 -400.736816) (xy 24.372316 -400.736816)
			(xy 24.35352 -400.744436) (xy 24.346408 -400.751802) (xy 24.324803 -400.772804) (xy 24.276169 -400.808369)
			(xy 24.222547 -400.835845) (xy 24.165273 -400.854548) (xy 24.10577 -400.864013) (xy 24.075644 -400.864578)
			(xy 24.048391 -400.864104) (xy 23.994439 -400.856352) (xy 23.942139 -400.841) (xy 23.892557 -400.81836)
			(xy 23.846703 -400.788894) (xy 23.805509 -400.753201) (xy 23.769814 -400.712009) (xy 23.740346 -400.666155)
			(xy 23.717705 -400.616574) (xy 23.702351 -400.564275) (xy 23.694597 -400.510323) (xy 23.694136 -400.48307)
			(xy 22.966683 -400.48307) (xy 22.974808 -400.491198) (xy 22.99206 -400.509295) (xy 23.019862 -400.550843)
			(xy 23.039029 -400.597014) (xy 23.048828 -400.646035) (xy 23.049484 -400.67103) (xy 23.049484 -402.78177)
			(xy 23.048845 -402.806766) (xy 23.039043 -402.855788) (xy 23.019868 -402.901957) (xy 22.992057 -402.943501)
			(xy 22.974808 -402.961602) (xy 21.748242 -404.188168) (xy 21.741402 -404.195568) (xy 21.733685 -404.214167)
			(xy 21.733256 -404.224236) (xy 21.733256 -406.020778) (xy 22.643338 -406.020778) (xy 22.64375 -405.995078)
			(xy 22.65065 -405.944142) (xy 22.664322 -405.894593) (xy 22.684518 -405.847326) (xy 22.710874 -405.803197)
			(xy 22.742913 -405.763003) (xy 22.761194 -405.744934) (xy 22.768814 -405.737822) (xy 22.776688 -405.71928)
			(xy 22.777704 -405.625554) (xy 22.770084 -405.607012) (xy 22.762464 -405.599646) (xy 22.741488 -405.578031)
			(xy 22.705977 -405.529382) (xy 22.678555 -405.475756) (xy 22.659903 -405.418487) (xy 22.650485 -405.358998)
			(xy 22.649942 -405.328882) (xy 22.650387 -405.301511) (xy 22.658209 -405.247331) (xy 22.673702 -405.194827)
			(xy 22.696549 -405.14508) (xy 22.726278 -405.099115) (xy 22.743922 -405.078184) (xy 22.750018 -405.071072)
			(xy 22.756368 -405.054054) (xy 22.756368 -404.96871) (xy 22.750018 -404.951692) (xy 22.743922 -404.94458)
			(xy 22.726264 -404.923661) (xy 22.69654 -404.877691) (xy 22.673696 -404.827942) (xy 22.658202 -404.775438)
			(xy 22.650375 -404.721258) (xy 22.650377 -404.666515) (xy 22.658207 -404.612335) (xy 22.673706 -404.559832)
			(xy 22.696553 -404.510085) (xy 22.72628 -404.464117) (xy 22.743922 -404.443184) (xy 22.750018 -404.436072)
			(xy 22.756368 -404.419054) (xy 22.756368 -404.33371) (xy 22.750018 -404.316692) (xy 22.743922 -404.30958)
			(xy 22.72631 -404.288626) (xy 22.696594 -404.242659) (xy 22.673752 -404.192918) (xy 22.658255 -404.140422)
			(xy 22.65042 -404.08625) (xy 22.649942 -404.058882) (xy 22.650428 -404.031631) (xy 22.658184 -403.977683)
			(xy 22.673539 -403.925388) (xy 22.696181 -403.875811) (xy 22.725647 -403.829961) (xy 22.761338 -403.78877)
			(xy 22.802529 -403.753079) (xy 22.848379 -403.723613) (xy 22.897956 -403.700971) (xy 22.950251 -403.685616)
			(xy 23.004199 -403.67786) (xy 23.058701 -403.67786) (xy 23.112649 -403.685616) (xy 23.164944 -403.700971)
			(xy 23.214521 -403.723613) (xy 23.260371 -403.753079) (xy 23.301562 -403.78877) (xy 23.337253 -403.829961)
			(xy 23.366719 -403.875811) (xy 23.389361 -403.925388) (xy 23.404716 -403.977683) (xy 23.412472 -404.031631)
			(xy 23.412958 -404.058882) (xy 23.412492 -404.086252) (xy 23.404675 -404.140432) (xy 23.389187 -404.192935)
			(xy 23.366345 -404.242682) (xy 23.33662 -404.288649) (xy 23.318978 -404.30958) (xy 23.312882 -404.316692)
			(xy 23.306532 -404.33371) (xy 23.306532 -404.419054) (xy 23.312882 -404.436072) (xy 23.318978 -404.443184)
			(xy 23.323804 -404.448772) (xy 23.330662 -404.4569) (xy 23.34895 -404.466298) (xy 23.443692 -404.472394)
			(xy 23.462996 -404.465282) (xy 23.470616 -404.45817) (xy 23.491895 -404.439221) (xy 23.539032 -404.407212)
			(xy 23.590401 -404.382562) (xy 23.644862 -404.365818) (xy 23.701207 -404.357351) (xy 23.729696 -404.356824)
			(xy 23.759819 -404.357405) (xy 23.819314 -404.366885) (xy 23.876582 -404.385593) (xy 23.930199 -404.413067)
			(xy 23.978834 -404.448623) (xy 24.00046 -404.4696) (xy 24.007572 -404.476966) (xy 24.026368 -404.484586)
			(xy 24.118824 -404.484586) (xy 24.13762 -404.476966) (xy 24.144732 -404.4696) (xy 24.166364 -404.448627)
			(xy 24.214991 -404.413058) (xy 24.268605 -404.385577) (xy 24.325874 -404.366867) (xy 24.385372 -404.357393)
			(xy 24.415496 -404.356824) (xy 24.441793 -404.357286) (xy 24.493889 -404.364503) (xy 24.544499 -404.378814)
			(xy 24.59266 -404.399948) (xy 24.637458 -404.427503) (xy 24.678041 -404.460956) (xy 24.696166 -404.480014)
			(xy 24.703278 -404.487634) (xy 24.721566 -404.496016) (xy 24.814022 -404.499318) (xy 24.833072 -404.49246)
			(xy 24.840438 -404.485348) (xy 24.861768 -404.466081) (xy 24.909129 -404.433514) (xy 24.96084 -404.40842)
			(xy 25.01573 -404.391369) (xy 25.072557 -404.382745) (xy 25.101296 -404.382224) (xy 25.131419 -404.382805)
			(xy 25.190914 -404.392285) (xy 25.248182 -404.410993) (xy 25.301799 -404.438467) (xy 25.350434 -404.474023)
			(xy 25.37206 -404.495) (xy 25.379172 -404.502366) (xy 25.397968 -404.509986) (xy 25.490424 -404.509986)
			(xy 25.50922 -404.502366) (xy 25.516332 -404.495) (xy 25.537964 -404.474027) (xy 25.586591 -404.438458)
			(xy 25.640205 -404.410977) (xy 25.697474 -404.392267) (xy 25.756972 -404.382793) (xy 25.787096 -404.382224)
			(xy 25.81435 -404.382659) (xy 25.868304 -404.390416) (xy 25.920604 -404.405774) (xy 25.970186 -404.428418)
			(xy 26.016041 -404.457888) (xy 26.057235 -404.493585) (xy 26.092928 -404.534781) (xy 26.122396 -404.580638)
			(xy 26.145036 -404.630222) (xy 26.16039 -404.682524) (xy 26.168143 -404.736478) (xy 26.168604 -404.763732)
			(xy 26.168156 -404.791103) (xy 26.160333 -404.845283) (xy 26.14484 -404.897786) (xy 26.121995 -404.947532)
			(xy 26.092267 -404.993499) (xy 26.074624 -405.01443) (xy 26.068528 -405.021542) (xy 26.062178 -405.03856)
			(xy 26.062178 -405.123904) (xy 26.068528 -405.140922) (xy 26.074624 -405.148034) (xy 26.092249 -405.168977)
			(xy 26.121962 -405.214947) (xy 26.144801 -405.264692) (xy 26.160295 -405.31719) (xy 26.168127 -405.371364)
			(xy 26.168604 -405.398732) (xy 26.168145 -405.425093) (xy 26.160898 -405.477315) (xy 26.146532 -405.528043)
			(xy 26.125321 -405.57631) (xy 26.097669 -405.621199) (xy 26.081228 -405.64181) (xy 26.075132 -405.649176)
			(xy 26.06929 -405.666702) (xy 26.0731 -405.754078) (xy 26.080466 -405.771096) (xy 26.087324 -405.777954)
			(xy 26.107808 -405.799505) (xy 26.142506 -405.847786) (xy 26.169292 -405.900866) (xy 26.187517 -405.95746)
			(xy 26.196739 -406.016196) (xy 26.197306 -406.045924) (xy 26.196845 -406.073176) (xy 26.189085 -406.127125)
			(xy 26.173726 -406.17942) (xy 26.151082 -406.228997) (xy 26.121613 -406.274848) (xy 26.085919 -406.316038)
			(xy 26.044727 -406.351729) (xy 25.998875 -406.381195) (xy 25.949296 -406.403836) (xy 25.896999 -406.41919)
			(xy 25.84305 -406.426946) (xy 25.815798 -406.427432) (xy 25.785674 -406.426868) (xy 25.726177 -406.417386)
			(xy 25.668909 -406.398674) (xy 25.615292 -406.371196) (xy 25.566658 -406.335636) (xy 25.545034 -406.314656)
			(xy 25.537922 -406.30729) (xy 25.519126 -406.29967) (xy 25.42667 -406.29967) (xy 25.407874 -406.30729)
			(xy 25.400762 -406.314656) (xy 25.379126 -406.335624) (xy 25.330501 -406.371196) (xy 25.276887 -406.398679)
			(xy 25.219619 -406.41739) (xy 25.160122 -406.426863) (xy 25.129998 -406.427432) (xy 25.1037 -406.426988)
			(xy 25.051602 -406.419769) (xy 25.000992 -406.405455) (xy 24.952831 -406.384318) (xy 24.908034 -406.356759)
			(xy 24.867451 -406.323303) (xy 24.849328 -406.304242) (xy 24.842216 -406.296622) (xy 24.823928 -406.28824)
			(xy 24.731472 -406.284938) (xy 24.712422 -406.291796) (xy 24.705056 -406.298908) (xy 24.683722 -406.31817)
			(xy 24.636363 -406.35074) (xy 24.584653 -406.375835) (xy 24.529763 -406.392887) (xy 24.472937 -406.401511)
			(xy 24.444198 -406.402032) (xy 24.414074 -406.401468) (xy 24.354577 -406.391986) (xy 24.297309 -406.373274)
			(xy 24.243692 -406.345796) (xy 24.195058 -406.310236) (xy 24.173434 -406.289256) (xy 24.166322 -406.28189)
			(xy 24.147526 -406.27427) (xy 24.05507 -406.27427) (xy 24.036274 -406.28189) (xy 24.029162 -406.289256)
			(xy 24.007526 -406.310224) (xy 23.958901 -406.345796) (xy 23.905287 -406.373279) (xy 23.848019 -406.39199)
			(xy 23.788522 -406.401463) (xy 23.758398 -406.402032) (xy 23.730987 -406.401592) (xy 23.676728 -406.393743)
			(xy 23.624152 -406.378209) (xy 23.574342 -406.355307) (xy 23.528323 -406.325511) (xy 23.487043 -406.289434)
			(xy 23.468838 -406.268936) (xy 23.461472 -406.260554) (xy 23.441406 -406.251156) (xy 23.342092 -406.251156)
			(xy 23.321772 -406.260554) (xy 23.31466 -406.268936) (xy 23.296441 -406.28946) (xy 23.255134 -406.325592)
			(xy 23.209079 -406.355436) (xy 23.159225 -406.378377) (xy 23.106598 -406.393941) (xy 23.052286 -406.401807)
			(xy 23.024846 -406.402286) (xy 22.997593 -406.401802) (xy 22.943642 -406.394051) (xy 22.891343 -406.378699)
			(xy 22.841762 -406.35606) (xy 22.795907 -406.326595) (xy 22.754714 -406.290903) (xy 22.719019 -406.249712)
			(xy 22.689551 -406.203859) (xy 22.666909 -406.154279) (xy 22.651555 -406.101982) (xy 22.6438 -406.048031)
			(xy 22.643338 -406.020778) (xy 21.733256 -406.020778) (xy 21.733256 -407.011632) (xy 21.733687 -407.021698)
			(xy 21.741415 -407.040289) (xy 21.748242 -407.0477) (xy 23.218394 -408.517852) (xy 32.401762 -408.517852)
			(xy 32.405833 -408.46223) (xy 32.417959 -408.407793) (xy 32.437882 -408.355702) (xy 32.465178 -408.307067)
			(xy 32.499264 -408.262924) (xy 32.539413 -408.224215) (xy 32.584771 -408.191764) (xy 32.634371 -408.166263)
			(xy 32.687155 -408.148256) (xy 32.741998 -408.138126) (xy 32.797732 -408.136089) (xy 32.853169 -408.142189)
			(xy 32.907126 -408.156295) (xy 32.958455 -408.178107) (xy 33.006061 -408.207161) (xy 33.048929 -408.242836)
			(xy 33.086146 -408.284373) (xy 33.116919 -408.330886) (xy 33.140591 -408.381383) (xy 33.156659 -408.43479)
			(xy 33.164779 -408.489966) (xy 33.165288 -408.517852) (xy 33.164779 -408.545738) (xy 33.156659 -408.600914)
			(xy 33.140591 -408.654321) (xy 33.116919 -408.704818) (xy 33.086146 -408.751331) (xy 33.048929 -408.792868)
			(xy 33.006061 -408.828543) (xy 32.958455 -408.857597) (xy 32.907126 -408.879409) (xy 32.853169 -408.893515)
			(xy 32.797732 -408.899615) (xy 32.741998 -408.897578) (xy 32.687155 -408.887448) (xy 32.634371 -408.869441)
			(xy 32.584771 -408.84394) (xy 32.539413 -408.811489) (xy 32.499264 -408.77278) (xy 32.465178 -408.728637)
			(xy 32.437882 -408.680002) (xy 32.417959 -408.627911) (xy 32.405833 -408.573474) (xy 32.401762 -408.517852)
			(xy 23.218394 -408.517852) (xy 24.70023 -409.999688) (xy 24.717447 -410.0178) (xy 24.745177 -410.059362)
			(xy 24.764275 -410.105532) (xy 24.774009 -410.154538) (xy 24.774652 -410.17952) (xy 24.774652 -411.34284)
			(xy 30.531052 -411.34284) (xy 30.535123 -411.287218) (xy 30.547249 -411.232781) (xy 30.567172 -411.18069)
			(xy 30.594468 -411.132055) (xy 30.628554 -411.087912) (xy 30.668703 -411.049203) (xy 30.714061 -411.016752)
			(xy 30.763661 -410.991251) (xy 30.816445 -410.973244) (xy 30.871288 -410.963114) (xy 30.927022 -410.961077)
			(xy 30.982459 -410.967177) (xy 31.036416 -410.981283) (xy 31.087745 -411.003095) (xy 31.135351 -411.032149)
			(xy 31.178219 -411.067824) (xy 31.215436 -411.109361) (xy 31.246209 -411.155874) (xy 31.269881 -411.206371)
			(xy 31.285949 -411.259778) (xy 31.294069 -411.314954) (xy 31.294578 -411.34284) (xy 31.294069 -411.370726)
			(xy 31.285949 -411.425902) (xy 31.269881 -411.479309) (xy 31.246209 -411.529806) (xy 31.215436 -411.576319)
			(xy 31.178219 -411.617856) (xy 31.135351 -411.653531) (xy 31.087745 -411.682585) (xy 31.036416 -411.704397)
			(xy 30.982459 -411.718503) (xy 30.927022 -411.724603) (xy 30.871288 -411.722566) (xy 30.816445 -411.712436)
			(xy 30.763661 -411.694429) (xy 30.714061 -411.668928) (xy 30.668703 -411.636477) (xy 30.628554 -411.597768)
			(xy 30.594468 -411.553625) (xy 30.567172 -411.50499) (xy 30.547249 -411.452899) (xy 30.535123 -411.398462)
			(xy 30.531052 -411.34284) (xy 24.774652 -411.34284) (xy 24.774652 -411.928564) (xy 29.502352 -411.928564)
			(xy 29.506423 -411.872942) (xy 29.518549 -411.818505) (xy 29.538472 -411.766414) (xy 29.565768 -411.717779)
			(xy 29.599854 -411.673636) (xy 29.640003 -411.634927) (xy 29.685361 -411.602476) (xy 29.734961 -411.576975)
			(xy 29.787745 -411.558968) (xy 29.842588 -411.548838) (xy 29.898322 -411.546801) (xy 29.953759 -411.552901)
			(xy 30.007716 -411.567007) (xy 30.059045 -411.588819) (xy 30.106651 -411.617873) (xy 30.149519 -411.653548)
			(xy 30.186736 -411.695085) (xy 30.217509 -411.741598) (xy 30.241181 -411.792095) (xy 30.257249 -411.845502)
			(xy 30.265369 -411.900678) (xy 30.265878 -411.928564) (xy 30.265369 -411.95645) (xy 30.257249 -412.011626)
			(xy 30.241181 -412.065033) (xy 30.217509 -412.11553) (xy 30.186736 -412.162043) (xy 30.149519 -412.20358)
			(xy 30.106651 -412.239255) (xy 30.059045 -412.268309) (xy 30.007716 -412.290121) (xy 29.953759 -412.304227)
			(xy 29.898322 -412.310327) (xy 29.842588 -412.30829) (xy 29.787745 -412.29816) (xy 29.734961 -412.280153)
			(xy 29.685361 -412.254652) (xy 29.640003 -412.222201) (xy 29.599854 -412.183492) (xy 29.565768 -412.139349)
			(xy 29.538472 -412.090714) (xy 29.518549 -412.038623) (xy 29.506423 -411.984186) (xy 29.502352 -411.928564)
			(xy 24.774652 -411.928564) (xy 24.774652 -412.633414) (xy 28.730954 -412.633414) (xy 28.735025 -412.577792)
			(xy 28.747151 -412.523355) (xy 28.767074 -412.471264) (xy 28.79437 -412.422629) (xy 28.828456 -412.378486)
			(xy 28.868605 -412.339777) (xy 28.913963 -412.307326) (xy 28.963563 -412.281825) (xy 29.016347 -412.263818)
			(xy 29.07119 -412.253688) (xy 29.126924 -412.251651) (xy 29.182361 -412.257751) (xy 29.236318 -412.271857)
			(xy 29.287647 -412.293669) (xy 29.335253 -412.322723) (xy 29.378121 -412.358398) (xy 29.415338 -412.399935)
			(xy 29.446111 -412.446448) (xy 29.469783 -412.496945) (xy 29.485851 -412.550352) (xy 29.493971 -412.605528)
			(xy 29.49448 -412.633414) (xy 29.493971 -412.6613) (xy 29.485851 -412.716476) (xy 29.469783 -412.769883)
			(xy 29.446111 -412.82038) (xy 29.415338 -412.866893) (xy 29.378121 -412.90843) (xy 29.335253 -412.944105)
			(xy 29.287647 -412.973159) (xy 29.236318 -412.994971) (xy 29.182361 -413.009077) (xy 29.126924 -413.015177)
			(xy 29.07119 -413.01314) (xy 29.016347 -413.00301) (xy 28.963563 -412.985003) (xy 28.913963 -412.959502)
			(xy 28.868605 -412.927051) (xy 28.828456 -412.888342) (xy 28.79437 -412.844199) (xy 28.767074 -412.795564)
			(xy 28.747151 -412.743473) (xy 28.735025 -412.689036) (xy 28.730954 -412.633414) (xy 24.774652 -412.633414)
			(xy 24.774652 -413.102806) (xy 24.77404 -413.127789) (xy 24.764298 -413.176797) (xy 24.745188 -413.222965)
			(xy 24.717445 -413.264522) (xy 24.70023 -413.282638) (xy 23.104208 -414.878792) (xy 31.194104 -414.878792)
			(xy 31.201855 -414.824833) (xy 31.217206 -414.772526) (xy 31.239845 -414.722937) (xy 31.269311 -414.677075)
			(xy 31.305004 -414.635872) (xy 31.346198 -414.600169) (xy 31.392053 -414.570691) (xy 31.441636 -414.54804)
			(xy 31.493939 -414.532675) (xy 31.547896 -414.52491) (xy 31.602408 -414.524904) (xy 31.656367 -414.532655)
			(xy 31.708674 -414.548006) (xy 31.758263 -414.570645) (xy 31.804125 -414.600111) (xy 31.845328 -414.635804)
			(xy 31.881031 -414.676998) (xy 31.910509 -414.722853) (xy 31.93316 -414.772436) (xy 31.948525 -414.824739)
			(xy 31.95629 -414.878696) (xy 31.956756 -414.905952) (xy 31.956134 -414.936594) (xy 31.946309 -414.997085)
			(xy 31.937198 -415.026348) (xy 31.933225 -415.039865) (xy 31.931982 -415.067997) (xy 31.938465 -415.0954)
			(xy 31.952182 -415.119992) (xy 31.972092 -415.139906) (xy 31.996682 -415.153628) (xy 32.024084 -415.160117)
			(xy 32.052217 -415.158878) (xy 32.065722 -415.154872) (xy 32.094984 -415.145761) (xy 32.155476 -415.135942)
			(xy 32.186118 -415.135314) (xy 32.213367 -415.135797) (xy 32.267311 -415.143556) (xy 32.319601 -415.158912)
			(xy 32.369174 -415.181553) (xy 32.41502 -415.211019) (xy 32.456207 -415.246709) (xy 32.491894 -415.287898)
			(xy 32.521357 -415.333746) (xy 32.543996 -415.38332) (xy 32.559349 -415.435611) (xy 32.567104 -415.489555)
			(xy 32.567103 -415.544054) (xy 32.559347 -415.597998) (xy 32.543993 -415.650289) (xy 32.521353 -415.699862)
			(xy 32.491889 -415.74571) (xy 32.4562 -415.786897) (xy 32.415013 -415.822586) (xy 32.369166 -415.852051)
			(xy 32.319593 -415.874691) (xy 32.267302 -415.890046) (xy 32.213358 -415.897803) (xy 32.158859 -415.897804)
			(xy 32.104915 -415.89005) (xy 32.052624 -415.874697) (xy 32.003049 -415.852059) (xy 31.957201 -415.822597)
			(xy 31.916012 -415.786909) (xy 31.880322 -415.745724) (xy 31.850855 -415.699878) (xy 31.828213 -415.650305)
			(xy 31.812857 -415.598015) (xy 31.805098 -415.544071) (xy 31.80461 -415.516822) (xy 31.805223 -415.48618)
			(xy 31.815054 -415.425688) (xy 31.824168 -415.396426) (xy 31.828086 -415.382898) (xy 31.82932 -415.354779)
			(xy 31.822836 -415.32739) (xy 31.809124 -415.30281) (xy 31.789226 -415.282903) (xy 31.764651 -415.269181)
			(xy 31.737265 -415.262684) (xy 31.709146 -415.263906) (xy 31.695644 -415.267902) (xy 31.666377 -415.276997)
			(xy 31.605889 -415.286826) (xy 31.575248 -415.28746) (xy 31.547992 -415.287096) (xy 31.494033 -415.279345)
			(xy 31.441726 -415.263994) (xy 31.392137 -415.241355) (xy 31.346275 -415.211889) (xy 31.305072 -415.176196)
			(xy 31.269369 -415.135002) (xy 31.239891 -415.089147) (xy 31.21724 -415.039564) (xy 31.201875 -414.987261)
			(xy 31.19411 -414.933304) (xy 31.194104 -414.878792) (xy 23.104208 -414.878792) (xy 22.631063 -415.351976)
			(xy 29.832806 -415.351976) (xy 29.836877 -415.296354) (xy 29.849003 -415.241917) (xy 29.868926 -415.189826)
			(xy 29.896222 -415.141191) (xy 29.930308 -415.097048) (xy 29.970457 -415.058339) (xy 30.015815 -415.025888)
			(xy 30.065415 -415.000387) (xy 30.118199 -414.98238) (xy 30.173042 -414.97225) (xy 30.228776 -414.970213)
			(xy 30.284213 -414.976313) (xy 30.33817 -414.990419) (xy 30.389499 -415.012231) (xy 30.437105 -415.041285)
			(xy 30.479973 -415.07696) (xy 30.51719 -415.118497) (xy 30.547963 -415.16501) (xy 30.571635 -415.215507)
			(xy 30.587703 -415.268914) (xy 30.595823 -415.32409) (xy 30.596332 -415.351976) (xy 30.595823 -415.379862)
			(xy 30.587703 -415.435038) (xy 30.571635 -415.488445) (xy 30.547963 -415.538942) (xy 30.51719 -415.585455)
			(xy 30.479973 -415.626992) (xy 30.437105 -415.662667) (xy 30.389499 -415.691721) (xy 30.33817 -415.713533)
			(xy 30.284213 -415.727639) (xy 30.228776 -415.733739) (xy 30.173042 -415.731702) (xy 30.118199 -415.721572)
			(xy 30.065415 -415.703565) (xy 30.015815 -415.678064) (xy 29.970457 -415.645613) (xy 29.930308 -415.606904)
			(xy 29.896222 -415.562761) (xy 29.868926 -415.514126) (xy 29.849003 -415.462035) (xy 29.836877 -415.407598)
			(xy 29.832806 -415.351976) (xy 22.631063 -415.351976) (xy 21.618194 -416.364928) (xy 21.611359 -416.37229)
			(xy 21.603601 -416.390805) (xy 21.603537 -416.410879) (xy 21.607018 -416.4203) (xy 21.613114 -416.434524)
			(xy 21.63826 -416.451542) (xy 24.758142 -416.451542) (xy 24.766808 -416.451234) (xy 24.783162 -416.445508)
			(xy 24.790146 -416.440366) (xy 24.815901 -416.420253) (xy 24.871128 -416.385317) (xy 24.929932 -416.356812)
			(xy 24.991568 -416.335097) (xy 25.055254 -416.320449) (xy 25.120184 -416.313053) (xy 25.152858 -416.312604)
			(xy 27.254962 -416.312604) (xy 27.263475 -416.312275) (xy 27.279558 -416.306681) (xy 27.286458 -416.301682)
			(xy 27.312143 -416.281792) (xy 27.367159 -416.247241) (xy 27.425695 -416.219062) (xy 27.487016 -416.197609)
			(xy 27.550353 -416.183151) (xy 27.614909 -416.175871) (xy 27.647392 -416.175444) (xy 28.074112 -416.175444)
			(xy 28.108305 -416.175961) (xy 28.176213 -416.184043) (xy 28.242698 -416.200058) (xy 28.306837 -416.223784)
			(xy 28.367739 -416.254892) (xy 28.396438 -416.273488) (xy 28.404994 -416.278704) (xy 28.424632 -416.282613)
			(xy 28.44427 -416.278704) (xy 28.452826 -416.273488) (xy 28.481513 -416.25487) (xy 28.542416 -416.223758)
			(xy 28.606558 -416.20003) (xy 28.673046 -416.184016) (xy 28.740957 -416.175938) (xy 28.775152 -416.175444)
			(xy 29.201872 -416.175444) (xy 29.236066 -416.175958) (xy 29.303975 -416.184036) (xy 29.370463 -416.200048)
			(xy 29.434604 -416.22377) (xy 29.49551 -416.254874) (xy 29.524198 -416.273488) (xy 29.532754 -416.278704)
			(xy 29.552392 -416.282613) (xy 29.57203 -416.278704) (xy 29.580586 -416.273488) (xy 29.609274 -416.254873)
			(xy 29.670178 -416.223768) (xy 29.73432 -416.200046) (xy 29.800808 -416.184039) (xy 29.868718 -416.175968)
			(xy 29.902912 -416.175444) (xy 30.329632 -416.175444) (xy 30.363827 -416.175956) (xy 30.431738 -416.18403)
			(xy 30.498227 -416.200037) (xy 30.562372 -416.223756) (xy 30.623281 -416.254857) (xy 30.651958 -416.273488)
			(xy 30.660514 -416.278704) (xy 30.680152 -416.282613) (xy 30.69979 -416.278704) (xy 30.708346 -416.273488)
			(xy 30.737033 -416.254871) (xy 30.797937 -416.223761) (xy 30.862078 -416.200036) (xy 30.928567 -416.184023)
			(xy 30.996478 -416.175948) (xy 31.030672 -416.175444) (xy 31.457392 -416.175444) (xy 31.491585 -416.17596)
			(xy 31.559494 -416.18404) (xy 31.62598 -416.200053) (xy 31.690121 -416.223777) (xy 31.751024 -416.254883)
			(xy 31.779718 -416.273488) (xy 31.788274 -416.278704) (xy 31.807912 -416.282613) (xy 31.82755 -416.278704)
			(xy 31.836106 -416.273488) (xy 31.864794 -416.254874) (xy 31.925699 -416.223771) (xy 31.989841 -416.200051)
			(xy 32.056329 -416.184046) (xy 32.124238 -416.175978) (xy 32.158432 -416.175444) (xy 32.585152 -416.175444)
			(xy 32.617632 -416.175916) (xy 32.68218 -416.183213) (xy 32.745509 -416.197676) (xy 32.806826 -416.219123)
			(xy 32.865363 -416.247287) (xy 32.920386 -416.281815) (xy 32.946086 -416.301682) (xy 32.95297 -416.306706)
			(xy 32.969065 -416.312279) (xy 32.977582 -416.312604) (xy 34.00298 -416.312604) (xy 34.012941 -416.312115)
			(xy 34.031362 -416.304525) (xy 34.038794 -416.297872) (xy 34.133282 -416.203384) (xy 34.140128 -416.195985)
			(xy 34.147859 -416.177387) (xy 34.148268 -416.167316) (xy 34.148268 -416.081464) (xy 34.142172 -416.064954)
			(xy 34.13633 -416.057842) (xy 34.119447 -416.03711) (xy 34.091034 -415.99182) (xy 34.06921 -415.943012)
			(xy 34.054402 -415.891638) (xy 34.046899 -415.838702) (xy 34.046414 -415.81197) (xy 34.046854 -415.785232)
			(xy 34.054313 -415.732278) (xy 34.069106 -415.680889) (xy 34.090945 -415.632075) (xy 34.119398 -415.586796)
			(xy 34.13633 -415.566098) (xy 34.141821 -415.559047) (xy 34.147925 -415.542263) (xy 34.148268 -415.533332)
			(xy 34.148268 -403.213062) (xy 34.147252 -403.203156) (xy 32.784034 -396.34922) (xy 32.783221 -396.345578)
			(xy 32.780664 -396.338567) (xy 32.778954 -396.33525) (xy 31.501334 -393.944856) (xy 31.499497 -393.941602)
			(xy 31.495036 -393.935609) (xy 31.492444 -393.932918) (xy 30.277054 -392.717528) (xy 30.270213 -392.710128)
			(xy 30.262496 -392.691529) (xy 30.262068 -392.68146) (xy 30.262068 -383.138934) (xy 30.261052 -383.129028)
			(xy 29.856938 -381.097536) (xy 29.854144 -381.087884) (xy 28.618434 -378.104908) (xy 28.614338 -378.09613)
			(xy 28.600824 -378.082276) (xy 28.583131 -378.074429) (xy 28.573476 -378.073666) (xy 28.466288 -378.069602)
			(xy 28.440888 -378.084588) (xy 28.43403 -378.09805) (xy 28.421759 -378.1213) (xy 28.391786 -378.16449)
			(xy 28.356165 -378.203154) (xy 28.315572 -378.236559) (xy 28.270775 -378.264073) (xy 28.222624 -378.285173)
			(xy 28.172031 -378.299459) (xy 28.119956 -378.306662) (xy 28.09367 -378.307092) (xy 28.06556 -378.30659)
			(xy 28.009947 -378.298341) (xy 27.956146 -378.282026) (xy 27.905319 -378.257997) (xy 27.858566 -378.226773)
			(xy 27.837384 -378.208286) (xy 27.830272 -378.201682) (xy 27.813 -378.195078) (xy 27.725624 -378.194824)
			(xy 27.708352 -378.201682) (xy 27.700986 -378.208032) (xy 27.679861 -378.226441) (xy 27.633224 -378.257502)
			(xy 27.582543 -378.281401) (xy 27.528909 -378.297624) (xy 27.473479 -378.305821) (xy 27.445462 -378.30633)
			(xy 27.416724 -378.305806) (xy 27.359901 -378.297177) (xy 27.305015 -378.28012) (xy 27.25331 -378.255021)
			(xy 27.205955 -378.222449) (xy 27.184604 -378.203206) (xy 27.177492 -378.196602) (xy 27.159966 -378.18949)
			(xy 27.070558 -378.18949) (xy 27.053032 -378.196602) (xy 27.04592 -378.203206) (xy 27.024594 -378.222479)
			(xy 26.977232 -378.25505) (xy 26.925521 -378.280147) (xy 26.87063 -378.297205) (xy 26.813802 -378.305836)
			(xy 26.785062 -378.30633) (xy 26.754196 -378.305716) (xy 26.693276 -378.29574) (xy 26.634756 -378.276085)
			(xy 26.580164 -378.247265) (xy 26.555192 -378.229114) (xy 26.547572 -378.223526) (xy 26.529792 -378.218446)
			(xy 26.443686 -378.225304) (xy 26.426922 -378.233178) (xy 26.420318 -378.240036) (xy 26.402266 -378.258348)
			(xy 26.362093 -378.290446) (xy 26.317971 -378.316855) (xy 26.2707 -378.337095) (xy 26.221138 -378.350799)
			(xy 26.170185 -378.357719) (xy 26.144474 -378.358146) (xy 26.117223 -378.357658) (xy 26.063276 -378.349899)
			(xy 26.010982 -378.334542) (xy 25.961406 -378.3119) (xy 25.915556 -378.282434) (xy 25.874366 -378.246743)
			(xy 25.838674 -378.205554) (xy 25.809206 -378.159705) (xy 25.786562 -378.110129) (xy 25.771203 -378.057836)
			(xy 25.763442 -378.003889) (xy 25.762966 -377.976638) (xy 25.763436 -377.949667) (xy 25.771041 -377.896262)
			(xy 25.78609 -377.844461) (xy 25.808283 -377.795295) (xy 25.837179 -377.749744) (xy 25.872201 -377.708716)
			(xy 25.912651 -377.673028) (xy 25.957724 -377.643392) (xy 25.981914 -377.631452) (xy 25.992836 -377.626372)
			(xy 26.007314 -377.60783) (xy 26.029158 -377.50496) (xy 26.023062 -377.4821) (xy 26.015188 -377.472956)
			(xy 25.997598 -377.452029) (xy 25.967965 -377.40609) (xy 25.945192 -377.356392) (xy 25.929745 -377.303953)
			(xy 25.921941 -377.249846) (xy 25.921462 -377.222512) (xy 25.921995 -377.193596) (xy 25.930722 -377.136425)
			(xy 25.947977 -377.081226) (xy 25.973364 -377.029263) (xy 26.006304 -376.981728) (xy 26.04604 -376.939708)
			(xy 26.068528 -376.921522) (xy 26.077313 -376.91398) (xy 26.087488 -376.893208) (xy 26.088086 -376.881644)
			(xy 26.088086 -376.80138) (xy 26.087473 -376.789822) (xy 26.077291 -376.769063) (xy 26.068528 -376.761502)
			(xy 26.047746 -376.744748) (xy 26.010616 -376.706393) (xy 25.979196 -376.663237) (xy 25.954098 -376.616123)
			(xy 25.935811 -376.565971) (xy 25.924695 -376.513759) (xy 25.920964 -376.460507) (xy 25.924692 -376.407256)
			(xy 25.935807 -376.355043) (xy 25.954092 -376.30489) (xy 25.979188 -376.257775) (xy 26.010607 -376.214618)
			(xy 26.047735 -376.176262) (xy 26.068528 -376.159522) (xy 26.077313 -376.15198) (xy 26.087488 -376.131208)
			(xy 26.088086 -376.119644) (xy 26.088086 -376.03938) (xy 26.087473 -376.027822) (xy 26.077291 -376.007063)
			(xy 26.068528 -375.999502) (xy 26.046045 -375.981312) (xy 26.006308 -375.939294) (xy 25.97337 -375.89176)
			(xy 25.947986 -375.839797) (xy 25.930738 -375.784598) (xy 25.92202 -375.727428) (xy 25.921462 -375.698512)
			(xy 25.922015 -375.668963) (xy 25.931126 -375.610571) (xy 25.949131 -375.554282) (xy 25.975601 -375.501443)
			(xy 26.009901 -375.453317) (xy 26.030174 -375.431812) (xy 26.037286 -375.424446) (xy 26.044652 -375.406666)
			(xy 26.04516 -375.315988) (xy 26.038048 -375.297954) (xy 26.030936 -375.290588) (xy 26.011263 -375.269161)
			(xy 25.977977 -375.221458) (xy 25.952315 -375.169258) (xy 25.93487 -375.113768) (xy 25.926046 -375.056274)
			(xy 25.925526 -375.02719) (xy 25.926012 -374.999939) (xy 25.933768 -374.945991) (xy 25.949123 -374.893696)
			(xy 25.971765 -374.844119) (xy 26.001231 -374.798269) (xy 26.036922 -374.757078) (xy 26.078113 -374.721387)
			(xy 26.123963 -374.691921) (xy 26.17354 -374.669279) (xy 26.225835 -374.653924) (xy 26.279783 -374.646168)
			(xy 26.334285 -374.646168) (xy 26.388233 -374.653924) (xy 26.440528 -374.669279) (xy 26.490105 -374.691921)
			(xy 26.535955 -374.721387) (xy 26.577146 -374.757078) (xy 26.612837 -374.798269) (xy 26.642303 -374.844119)
			(xy 26.664945 -374.893696) (xy 26.6803 -374.945991) (xy 26.688056 -374.999939) (xy 26.688542 -375.02719)
			(xy 26.687988 -375.056738) (xy 26.678875 -375.115128) (xy 26.660866 -375.171414) (xy 26.634391 -375.224249)
			(xy 26.600085 -375.272369) (xy 26.57983 -375.29389) (xy 26.572718 -375.301256) (xy 26.565352 -375.319036)
			(xy 26.564844 -375.409714) (xy 26.571956 -375.427748) (xy 26.579068 -375.435114) (xy 26.598741 -375.456541)
			(xy 26.632026 -375.504244) (xy 26.657688 -375.556444) (xy 26.675133 -375.611934) (xy 26.683956 -375.669428)
			(xy 26.684478 -375.698512) (xy 26.683943 -375.727428) (xy 26.675214 -375.784598) (xy 26.657958 -375.839795)
			(xy 26.63257 -375.891757) (xy 26.599632 -375.939292) (xy 26.559897 -375.981313) (xy 26.537412 -375.999502)
			(xy 26.528625 -376.007042) (xy 26.518451 -376.027815) (xy 26.517854 -376.03938) (xy 26.517854 -376.119644)
			(xy 26.518473 -376.131198) (xy 26.528666 -376.151944) (xy 26.537412 -376.159522) (xy 26.551649 -376.170899)
			(xy 26.578114 -376.195958) (xy 26.590244 -376.20956) (xy 26.597356 -376.217688) (xy 26.61666 -376.226578)
			(xy 26.713434 -376.228356) (xy 26.733246 -376.220228) (xy 26.740612 -376.212354) (xy 26.758708 -376.193789)
			(xy 26.799046 -376.161224) (xy 26.84342 -376.134418) (xy 26.891013 -376.113863) (xy 26.940951 -376.099938)
			(xy 26.992313 -376.0929) (xy 27.018234 -376.092466) (xy 27.046972 -376.09299) (xy 27.103796 -376.101618)
			(xy 27.158682 -376.118675) (xy 27.210388 -376.143773) (xy 27.257743 -376.176344) (xy 27.279092 -376.19559)
			(xy 27.286204 -376.202194) (xy 27.30373 -376.209306) (xy 27.393138 -376.209306) (xy 27.410664 -376.202194)
			(xy 27.417776 -376.19559) (xy 27.436434 -376.178642) (xy 27.477418 -376.149296) (xy 27.52191 -376.125606)
			(xy 27.569136 -376.107984) (xy 27.618272 -376.096737) (xy 27.643328 -376.09399) (xy 27.655266 -376.092974)
			(xy 27.675586 -376.080274) (xy 27.7241 -375.999756) (xy 27.729763 -375.989198) (xy 27.731614 -375.965344)
			(xy 27.727656 -375.954036) (xy 27.498802 -375.401586) (xy 27.496795 -375.397022) (xy 27.491296 -375.388707)
			(xy 27.48788 -375.385076) (xy 26.585418 -374.482614) (xy 26.578016 -374.475779) (xy 26.559417 -374.468072)
			(xy 26.54935 -374.467628) (xy 14.877796 -374.467628) (xy 14.845283 -374.467172) (xy 14.780667 -374.459894)
			(xy 14.71727 -374.44543) (xy 14.655891 -374.423961) (xy 14.5973 -374.395758) (xy 14.542234 -374.361174)
			(xy 14.491385 -374.320645) (xy 14.468094 -374.297956) (xy 13.444982 -373.274844) (xy 13.422303 -373.251534)
			(xy 13.381734 -373.200699) (xy 13.347109 -373.145644) (xy 13.318862 -373.08706) (xy 13.297347 -373.025684)
			(xy 13.282835 -372.962285) (xy 13.275508 -372.897661) (xy 13.275056 -372.865142) (xy 13.275056 -369.557808)
			(xy 13.274637 -369.547789) (xy 13.266967 -369.529277) (xy 13.252793 -369.515113) (xy 13.234275 -369.507456)
			(xy 13.224256 -369.507008) (xy 5.261864 -369.507008) (xy 5.251797 -369.507438) (xy 5.233203 -369.515162)
			(xy 5.225796 -369.521994) (xy 4.476242 -370.271548) (xy 4.469434 -370.278894) (xy 4.461713 -370.297357)
			(xy 4.461256 -370.307362) (xy 4.461256 -376.70105) (xy 8.208781 -376.70105) (xy 8.21251 -376.647799)
			(xy 8.223627 -376.595587) (xy 8.241913 -376.545435) (xy 8.267012 -376.498321) (xy 8.298433 -376.455167)
			(xy 8.335563 -376.416813) (xy 8.356346 -376.40006) (xy 8.365129 -376.392519) (xy 8.375299 -376.371744)
			(xy 8.375904 -376.360182) (xy 8.375904 -376.279918) (xy 8.375322 -376.268352) (xy 8.365135 -376.247581)
			(xy 8.356346 -376.24004) (xy 8.335563 -376.223287) (xy 8.298433 -376.184933) (xy 8.267012 -376.141779)
			(xy 8.241913 -376.094665) (xy 8.223627 -376.044513) (xy 8.21251 -375.992301) (xy 8.208781 -375.93905)
			(xy 8.21251 -375.885799) (xy 8.223627 -375.833587) (xy 8.241913 -375.783435) (xy 8.267012 -375.736321)
			(xy 8.298433 -375.693167) (xy 8.335563 -375.654813) (xy 8.356346 -375.63806) (xy 8.365129 -375.630519)
			(xy 8.375299 -375.609744) (xy 8.375904 -375.598182) (xy 8.375904 -375.517918) (xy 8.375322 -375.506352)
			(xy 8.365135 -375.485581) (xy 8.356346 -375.47804) (xy 8.33387 -375.45984) (xy 8.294137 -375.417821)
			(xy 8.261199 -375.370287) (xy 8.23581 -375.318328) (xy 8.218551 -375.263133) (xy 8.209818 -375.205965)
			(xy 8.20928 -375.17705) (xy 8.209766 -375.149799) (xy 8.217522 -375.095851) (xy 8.232877 -375.043556)
			(xy 8.255519 -374.993979) (xy 8.284985 -374.948129) (xy 8.320676 -374.906938) (xy 8.361867 -374.871247)
			(xy 8.407717 -374.841781) (xy 8.457294 -374.819139) (xy 8.509589 -374.803784) (xy 8.563537 -374.796028)
			(xy 8.618039 -374.796028) (xy 8.671987 -374.803784) (xy 8.724282 -374.819139) (xy 8.773859 -374.841781)
			(xy 8.819709 -374.871247) (xy 8.8609 -374.906938) (xy 8.896591 -374.948129) (xy 8.926057 -374.993979)
			(xy 8.948699 -375.043556) (xy 8.964054 -375.095851) (xy 8.97181 -375.149799) (xy 8.972296 -375.17705)
			(xy 8.971743 -375.205966) (xy 8.963022 -375.263135) (xy 8.945771 -375.318334) (xy 8.920385 -375.370295)
			(xy 8.887448 -375.41783) (xy 8.847713 -375.459849) (xy 8.82523 -375.47804) (xy 8.816443 -375.485577)
			(xy 8.806276 -375.506355) (xy 8.805672 -375.517918) (xy 8.805672 -375.598182) (xy 8.806228 -375.609752)
			(xy 8.81643 -375.630525) (xy 8.82523 -375.63806) (xy 8.846013 -375.654813) (xy 8.883144 -375.693166)
			(xy 8.914565 -375.736321) (xy 8.939664 -375.783435) (xy 8.95795 -375.833587) (xy 8.969067 -375.885798)
			(xy 8.972797 -375.93905) (xy 8.969067 -375.992302) (xy 8.95795 -376.044513) (xy 8.939664 -376.094665)
			(xy 8.914565 -376.141779) (xy 8.883144 -376.184934) (xy 8.846013 -376.223287) (xy 8.82523 -376.24004)
			(xy 8.816443 -376.247577) (xy 8.806276 -376.268355) (xy 8.805672 -376.279918) (xy 8.805672 -376.360182)
			(xy 8.806228 -376.371752) (xy 8.81643 -376.392525) (xy 8.82523 -376.40006) (xy 8.846013 -376.416813)
			(xy 8.883144 -376.455166) (xy 8.914565 -376.498321) (xy 8.939664 -376.545435) (xy 8.95795 -376.595587)
			(xy 8.969067 -376.647798) (xy 8.972797 -376.70105) (xy 10.494781 -376.70105) (xy 10.49851 -376.647799)
			(xy 10.509627 -376.595587) (xy 10.527913 -376.545435) (xy 10.553012 -376.498321) (xy 10.584433 -376.455167)
			(xy 10.621563 -376.416813) (xy 10.642346 -376.40006) (xy 10.651129 -376.392519) (xy 10.661299 -376.371744)
			(xy 10.661904 -376.360182) (xy 10.661904 -376.279918) (xy 10.661322 -376.268352) (xy 10.651135 -376.247581)
			(xy 10.642346 -376.24004) (xy 10.621563 -376.223287) (xy 10.584433 -376.184933) (xy 10.553012 -376.141779)
			(xy 10.527913 -376.094665) (xy 10.509627 -376.044513) (xy 10.49851 -375.992301) (xy 10.494781 -375.93905)
			(xy 10.49851 -375.885799) (xy 10.509627 -375.833587) (xy 10.527913 -375.783435) (xy 10.553012 -375.736321)
			(xy 10.584433 -375.693167) (xy 10.621563 -375.654813) (xy 10.642346 -375.63806) (xy 10.651129 -375.630519)
			(xy 10.661299 -375.609744) (xy 10.661904 -375.598182) (xy 10.661904 -375.517918) (xy 10.661322 -375.506352)
			(xy 10.651135 -375.485581) (xy 10.642346 -375.47804) (xy 10.61987 -375.45984) (xy 10.580137 -375.417821)
			(xy 10.547199 -375.370287) (xy 10.52181 -375.318328) (xy 10.504551 -375.263133) (xy 10.495818 -375.205965)
			(xy 10.49528 -375.17705) (xy 10.495766 -375.149799) (xy 10.503522 -375.095851) (xy 10.518877 -375.043556)
			(xy 10.541519 -374.993979) (xy 10.570985 -374.948129) (xy 10.606676 -374.906938) (xy 10.647867 -374.871247)
			(xy 10.693717 -374.841781) (xy 10.743294 -374.819139) (xy 10.795589 -374.803784) (xy 10.849537 -374.796028)
			(xy 10.904039 -374.796028) (xy 10.957987 -374.803784) (xy 11.010282 -374.819139) (xy 11.059859 -374.841781)
			(xy 11.105709 -374.871247) (xy 11.1469 -374.906938) (xy 11.182591 -374.948129) (xy 11.212057 -374.993979)
			(xy 11.234699 -375.043556) (xy 11.250054 -375.095851) (xy 11.25781 -375.149799) (xy 11.258296 -375.17705)
			(xy 11.257743 -375.205966) (xy 11.249022 -375.263135) (xy 11.231771 -375.318334) (xy 11.206385 -375.370295)
			(xy 11.173448 -375.41783) (xy 11.133713 -375.459849) (xy 11.11123 -375.47804) (xy 11.102443 -375.485577)
			(xy 11.092276 -375.506355) (xy 11.091672 -375.517918) (xy 11.091672 -375.598182) (xy 11.092228 -375.609752)
			(xy 11.10243 -375.630525) (xy 11.11123 -375.63806) (xy 11.132013 -375.654813) (xy 11.169144 -375.693166)
			(xy 11.200565 -375.736321) (xy 11.225664 -375.783435) (xy 11.24395 -375.833587) (xy 11.255067 -375.885798)
			(xy 11.258797 -375.93905) (xy 11.255067 -375.992302) (xy 11.24395 -376.044513) (xy 11.225664 -376.094665)
			(xy 11.200565 -376.141779) (xy 11.169144 -376.184934) (xy 11.132013 -376.223287) (xy 11.11123 -376.24004)
			(xy 11.102443 -376.247577) (xy 11.092276 -376.268355) (xy 11.091672 -376.279918) (xy 11.091672 -376.360182)
			(xy 11.092228 -376.371752) (xy 11.10243 -376.392525) (xy 11.11123 -376.40006) (xy 11.132013 -376.416813)
			(xy 11.169144 -376.455166) (xy 11.200565 -376.498321) (xy 11.225664 -376.545435) (xy 11.24395 -376.595587)
			(xy 11.255067 -376.647798) (xy 11.258797 -376.70105) (xy 11.255067 -376.754302) (xy 11.24395 -376.806513)
			(xy 11.225664 -376.856665) (xy 11.200565 -376.903779) (xy 11.169144 -376.946934) (xy 11.132013 -376.985287)
			(xy 11.11123 -377.00204) (xy 11.102443 -377.009577) (xy 11.092276 -377.030355) (xy 11.091672 -377.041918)
			(xy 11.091672 -377.122182) (xy 11.092228 -377.133752) (xy 11.10243 -377.154525) (xy 11.11123 -377.16206)
			(xy 11.133701 -377.180266) (xy 11.173435 -377.222284) (xy 11.206375 -377.269816) (xy 11.231765 -377.321774)
			(xy 11.249025 -377.376968) (xy 11.257758 -377.434135) (xy 11.258296 -377.46305) (xy 11.25781 -377.490301)
			(xy 11.250054 -377.544249) (xy 11.234699 -377.596544) (xy 11.212057 -377.646121) (xy 11.182591 -377.691971)
			(xy 11.1469 -377.733162) (xy 11.105709 -377.768853) (xy 11.059859 -377.798319) (xy 11.010282 -377.820961)
			(xy 10.957987 -377.836316) (xy 10.904039 -377.844072) (xy 10.849537 -377.844072) (xy 10.795589 -377.836316)
			(xy 10.743294 -377.820961) (xy 10.693717 -377.798319) (xy 10.647867 -377.768853) (xy 10.606676 -377.733162)
			(xy 10.570985 -377.691971) (xy 10.541519 -377.646121) (xy 10.518877 -377.596544) (xy 10.503522 -377.544249)
			(xy 10.495766 -377.490301) (xy 10.49528 -377.46305) (xy 10.495804 -377.434133) (xy 10.504528 -377.376961)
			(xy 10.521783 -377.321761) (xy 10.547173 -377.269798) (xy 10.580117 -377.222265) (xy 10.61986 -377.180249)
			(xy 10.642346 -377.16206) (xy 10.651129 -377.154519) (xy 10.661299 -377.133744) (xy 10.661904 -377.122182)
			(xy 10.661904 -377.041918) (xy 10.661322 -377.030352) (xy 10.651135 -377.009581) (xy 10.642346 -377.00204)
			(xy 10.621563 -376.985287) (xy 10.584433 -376.946933) (xy 10.553012 -376.903779) (xy 10.527913 -376.856665)
			(xy 10.509627 -376.806513) (xy 10.49851 -376.754301) (xy 10.494781 -376.70105) (xy 8.972797 -376.70105)
			(xy 8.969067 -376.754302) (xy 8.95795 -376.806513) (xy 8.939664 -376.856665) (xy 8.914565 -376.903779)
			(xy 8.883144 -376.946934) (xy 8.846013 -376.985287) (xy 8.82523 -377.00204) (xy 8.816443 -377.009577)
			(xy 8.806276 -377.030355) (xy 8.805672 -377.041918) (xy 8.805672 -377.122182) (xy 8.806228 -377.133752)
			(xy 8.81643 -377.154525) (xy 8.82523 -377.16206) (xy 8.847701 -377.180266) (xy 8.887435 -377.222284)
			(xy 8.920375 -377.269816) (xy 8.945765 -377.321774) (xy 8.963025 -377.376968) (xy 8.971758 -377.434135)
			(xy 8.972296 -377.46305) (xy 8.97181 -377.490301) (xy 8.964054 -377.544249) (xy 8.948699 -377.596544)
			(xy 8.926057 -377.646121) (xy 8.896591 -377.691971) (xy 8.8609 -377.733162) (xy 8.819709 -377.768853)
			(xy 8.773859 -377.798319) (xy 8.724282 -377.820961) (xy 8.671987 -377.836316) (xy 8.618039 -377.844072)
			(xy 8.563537 -377.844072) (xy 8.509589 -377.836316) (xy 8.457294 -377.820961) (xy 8.407717 -377.798319)
			(xy 8.361867 -377.768853) (xy 8.320676 -377.733162) (xy 8.284985 -377.691971) (xy 8.255519 -377.646121)
			(xy 8.232877 -377.596544) (xy 8.217522 -377.544249) (xy 8.209766 -377.490301) (xy 8.20928 -377.46305)
			(xy 8.209804 -377.434133) (xy 8.218528 -377.376961) (xy 8.235783 -377.321761) (xy 8.261173 -377.269798)
			(xy 8.294117 -377.222265) (xy 8.33386 -377.180249) (xy 8.356346 -377.16206) (xy 8.365129 -377.154519)
			(xy 8.375299 -377.133744) (xy 8.375904 -377.122182) (xy 8.375904 -377.041918) (xy 8.375322 -377.030352)
			(xy 8.365135 -377.009581) (xy 8.356346 -377.00204) (xy 8.335563 -376.985287) (xy 8.298433 -376.946933)
			(xy 8.267012 -376.903779) (xy 8.241913 -376.856665) (xy 8.223627 -376.806513) (xy 8.21251 -376.754301)
			(xy 8.208781 -376.70105) (xy 4.461256 -376.70105) (xy 4.461256 -377.963938) (xy 14.292072 -377.963938)
			(xy 14.292535 -377.937592) (xy 14.299764 -377.885398) (xy 14.314103 -377.834694) (xy 14.335281 -377.786445)
			(xy 14.362894 -377.741567) (xy 14.396418 -377.700914) (xy 14.415516 -377.68276) (xy 14.42339 -377.675648)
			(xy 14.431772 -377.656852) (xy 14.43355 -377.562364) (xy 14.42593 -377.543314) (xy 14.41831 -377.535694)
			(xy 14.397291 -377.514057) (xy 14.361641 -377.465399) (xy 14.334096 -377.411735) (xy 14.315343 -377.354404)
			(xy 14.30585 -377.294836) (xy 14.30528 -377.264676) (xy 14.305729 -377.23727) (xy 14.313582 -377.183025)
			(xy 14.329122 -377.130463) (xy 14.352029 -377.080668) (xy 14.38183 -377.034666) (xy 14.399514 -377.013724)
			(xy 14.40561 -377.006612) (xy 14.41196 -376.989594) (xy 14.41196 -376.903996) (xy 14.40561 -376.886978)
			(xy 14.399514 -376.879866) (xy 14.381832 -376.858924) (xy 14.352039 -376.812919) (xy 14.329139 -376.763124)
			(xy 14.313605 -376.710562) (xy 14.305756 -376.656318) (xy 14.30528 -376.628914) (xy 14.305825 -376.598573)
			(xy 14.315443 -376.538657) (xy 14.334423 -376.481018) (xy 14.362287 -376.427111) (xy 14.398332 -376.378293)
			(xy 14.41958 -376.356626) (xy 14.4272 -376.34926) (xy 14.43482 -376.330718) (xy 14.43482 -376.237246)
			(xy 14.4272 -376.218704) (xy 14.41958 -376.211338) (xy 14.39832 -376.189683) (xy 14.362282 -376.140862)
			(xy 14.334429 -376.08695) (xy 14.315462 -376.029309) (xy 14.305862 -375.969391) (xy 14.30528 -375.93905)
			(xy 14.305804 -375.910133) (xy 14.314528 -375.852961) (xy 14.331783 -375.797761) (xy 14.357173 -375.745798)
			(xy 14.390117 -375.698265) (xy 14.42986 -375.656249) (xy 14.452346 -375.63806) (xy 14.461129 -375.630519)
			(xy 14.471299 -375.609744) (xy 14.471904 -375.598182) (xy 14.471904 -375.517918) (xy 14.471322 -375.506352)
			(xy 14.461135 -375.485581) (xy 14.452346 -375.47804) (xy 14.42987 -375.45984) (xy 14.390137 -375.417821)
			(xy 14.357199 -375.370287) (xy 14.33181 -375.318328) (xy 14.314551 -375.263133) (xy 14.305818 -375.205965)
			(xy 14.30528 -375.17705) (xy 14.305766 -375.149799) (xy 14.313522 -375.095851) (xy 14.328877 -375.043556)
			(xy 14.351519 -374.993979) (xy 14.380985 -374.948129) (xy 14.416676 -374.906938) (xy 14.457867 -374.871247)
			(xy 14.503717 -374.841781) (xy 14.553294 -374.819139) (xy 14.605589 -374.803784) (xy 14.659537 -374.796028)
			(xy 14.714039 -374.796028) (xy 14.767987 -374.803784) (xy 14.820282 -374.819139) (xy 14.869859 -374.841781)
			(xy 14.915709 -374.871247) (xy 14.9569 -374.906938) (xy 14.992591 -374.948129) (xy 15.022057 -374.993979)
			(xy 15.044699 -375.043556) (xy 15.060054 -375.095851) (xy 15.06781 -375.149799) (xy 15.068296 -375.17705)
			(xy 15.067743 -375.205966) (xy 15.059022 -375.263135) (xy 15.041771 -375.318334) (xy 15.016385 -375.370295)
			(xy 14.983448 -375.41783) (xy 14.943713 -375.459849) (xy 14.92123 -375.47804) (xy 14.912443 -375.485577)
			(xy 14.902276 -375.506355) (xy 14.901672 -375.517918) (xy 14.901672 -375.598182) (xy 14.902228 -375.609752)
			(xy 14.91243 -375.630525) (xy 14.92123 -375.63806) (xy 14.943701 -375.656266) (xy 14.983435 -375.698284)
			(xy 15.016375 -375.745816) (xy 15.041765 -375.797774) (xy 15.059025 -375.852968) (xy 15.067758 -375.910135)
			(xy 15.068296 -375.93905) (xy 15.067706 -375.969389) (xy 15.058096 -376.029302) (xy 15.039125 -376.086939)
			(xy 15.011272 -376.140847) (xy 14.975238 -376.189668) (xy 14.953996 -376.211338) (xy 14.946376 -376.218704)
			(xy 14.938756 -376.237246) (xy 14.938756 -376.330718) (xy 14.946376 -376.34926) (xy 14.953996 -376.356626)
			(xy 14.975234 -376.378301) (xy 15.011276 -376.427116) (xy 15.039134 -376.481023) (xy 15.058105 -376.53866)
			(xy 15.067711 -376.598574) (xy 15.068296 -376.628914) (xy 15.067847 -376.65632) (xy 15.059995 -376.710566)
			(xy 15.044456 -376.763128) (xy 15.021548 -376.812923) (xy 14.991746 -376.858924) (xy 14.974062 -376.879866)
			(xy 14.967966 -376.886978) (xy 14.961616 -376.903996) (xy 14.961616 -376.989594) (xy 14.967966 -377.006612)
			(xy 14.974062 -377.013724) (xy 14.991735 -377.034673) (xy 15.021531 -377.080675) (xy 15.044432 -377.130469)
			(xy 15.059969 -377.183029) (xy 15.06782 -377.237272) (xy 15.068296 -377.264676) (xy 15.067853 -377.291023)
			(xy 15.060621 -377.343219) (xy 15.046279 -377.393923) (xy 15.025097 -377.442172) (xy 14.99748 -377.48705)
			(xy 14.963953 -377.527701) (xy 14.944852 -377.545854) (xy 14.936978 -377.552966) (xy 14.928596 -377.571762)
			(xy 14.926818 -377.66625) (xy 14.934438 -377.6853) (xy 14.942058 -377.69292) (xy 14.963096 -377.71454)
			(xy 14.998741 -377.763204) (xy 15.026281 -377.816872) (xy 15.045029 -377.874206) (xy 15.054519 -377.933777)
			(xy 15.054911 -377.95454) (xy 16.559276 -377.95454) (xy 16.559865 -377.924417) (xy 16.56934 -377.864921)
			(xy 16.588047 -377.807653) (xy 16.615519 -377.754036) (xy 16.651074 -377.705401) (xy 16.672052 -377.683776)
			(xy 16.679418 -377.67641) (xy 16.687038 -377.658376) (xy 16.687546 -377.56592) (xy 16.68018 -377.547632)
			(xy 16.672814 -377.540266) (xy 16.652346 -377.5187) (xy 16.617644 -377.470424) (xy 16.590855 -377.417347)
			(xy 16.572626 -377.360757) (xy 16.563401 -377.302023) (xy 16.562832 -377.272296) (xy 16.563335 -377.243378)
			(xy 16.572066 -377.186206) (xy 16.589326 -377.131006) (xy 16.61472 -377.079044) (xy 16.647667 -377.031511)
			(xy 16.687411 -376.989495) (xy 16.709898 -376.971306) (xy 16.718652 -376.963737) (xy 16.72884 -376.942984)
			(xy 16.729456 -376.931428) (xy 16.729456 -376.851164) (xy 16.728864 -376.839599) (xy 16.718686 -376.818826)
			(xy 16.709898 -376.811286) (xy 16.687407 -376.793103) (xy 16.647673 -376.751082) (xy 16.614735 -376.703545)
			(xy 16.589347 -376.651582) (xy 16.572093 -376.596383) (xy 16.563366 -376.539212) (xy 16.562832 -376.510296)
			(xy 16.563308 -376.483052) (xy 16.571066 -376.429118) (xy 16.586423 -376.376839) (xy 16.609066 -376.327278)
			(xy 16.638534 -376.281445) (xy 16.674227 -376.240275) (xy 16.715418 -376.204605) (xy 16.738092 -376.189494)
			(xy 16.74876 -376.182382) (xy 16.760952 -376.160538) (xy 16.763746 -376.051064) (xy 16.752316 -376.028458)
			(xy 16.742156 -376.021092) (xy 16.721253 -376.00571) (xy 16.68343 -375.970175) (xy 16.650778 -375.929836)
			(xy 16.623903 -375.885439) (xy 16.6033 -375.837806) (xy 16.589352 -375.787818) (xy 16.582316 -375.736399)
			(xy 16.581882 -375.71045) (xy 16.582315 -375.684786) (xy 16.589185 -375.633921) (xy 16.602819 -375.584437)
			(xy 16.622972 -375.537232) (xy 16.649278 -375.493158) (xy 16.681262 -375.453015) (xy 16.718345 -375.417527)
			(xy 16.738854 -375.402094) (xy 16.747998 -375.39549) (xy 16.758666 -375.376186) (xy 16.76654 -375.276618)
			(xy 16.75892 -375.256044) (xy 16.750792 -375.247916) (xy 16.729976 -375.226332) (xy 16.694724 -375.177826)
			(xy 16.667497 -375.124401) (xy 16.648966 -375.067374) (xy 16.639587 -375.008149) (xy 16.639032 -374.978168)
			(xy 16.639518 -374.950917) (xy 16.647274 -374.896969) (xy 16.662629 -374.844674) (xy 16.685271 -374.795097)
			(xy 16.714737 -374.749247) (xy 16.750428 -374.708056) (xy 16.791619 -374.672365) (xy 16.837469 -374.642899)
			(xy 16.887046 -374.620257) (xy 16.939341 -374.604902) (xy 16.993289 -374.597146) (xy 17.047791 -374.597146)
			(xy 17.101739 -374.604902) (xy 17.154034 -374.620257) (xy 17.203611 -374.642899) (xy 17.249461 -374.672365)
			(xy 17.290652 -374.708056) (xy 17.326343 -374.749247) (xy 17.355809 -374.795097) (xy 17.378451 -374.844674)
			(xy 17.393806 -374.896969) (xy 17.401562 -374.950917) (xy 17.402048 -374.978168) (xy 17.401616 -375.003832)
			(xy 17.394745 -375.054697) (xy 17.38111 -375.10418) (xy 17.360956 -375.151385) (xy 17.33465 -375.195458)
			(xy 17.302666 -375.235602) (xy 17.265584 -375.27109) (xy 17.245076 -375.286524) (xy 17.235932 -375.293128)
			(xy 17.225264 -375.312432) (xy 17.21739 -375.412) (xy 17.22501 -375.432574) (xy 17.233138 -375.440702)
			(xy 17.25395 -375.46229) (xy 17.289205 -375.510794) (xy 17.316434 -375.564217) (xy 17.334966 -375.621244)
			(xy 17.344343 -375.680469) (xy 17.344898 -375.71045) (xy 17.344444 -375.737695) (xy 17.33668 -375.791629)
			(xy 17.321318 -375.843908) (xy 17.298671 -375.893469) (xy 17.2692 -375.939301) (xy 17.233505 -375.980471)
			(xy 17.192313 -376.016141) (xy 17.169638 -376.031252) (xy 17.15897 -376.038364) (xy 17.146778 -376.060208)
			(xy 17.143984 -376.169682) (xy 17.155414 -376.192288) (xy 17.165574 -376.199654) (xy 17.186458 -376.21506)
			(xy 17.224281 -376.250592) (xy 17.256933 -376.290928) (xy 17.28381 -376.33532) (xy 17.304416 -376.382949)
			(xy 17.318368 -376.432933) (xy 17.32541 -376.484348) (xy 17.325848 -376.510296) (xy 17.325346 -376.539214)
			(xy 17.316617 -376.596387) (xy 17.299357 -376.651587) (xy 17.273962 -376.703549) (xy 17.241015 -376.751082)
			(xy 17.20127 -376.793097) (xy 17.178782 -376.811286) (xy 17.170028 -376.818855) (xy 17.159841 -376.839608)
			(xy 17.159224 -376.851164) (xy 17.159224 -376.931428) (xy 17.159827 -376.942992) (xy 17.169998 -376.963764)
			(xy 17.178782 -376.971306) (xy 17.201265 -376.989498) (xy 17.241001 -377.031517) (xy 17.27394 -377.079052)
			(xy 17.299329 -377.131013) (xy 17.316585 -377.18621) (xy 17.325314 -377.24338) (xy 17.325848 -377.272296)
			(xy 17.325275 -377.302419) (xy 17.315795 -377.361916) (xy 17.297085 -377.419184) (xy 17.269609 -377.472801)
			(xy 17.234051 -377.521435) (xy 17.213072 -377.54306) (xy 17.205706 -377.550426) (xy 17.198086 -377.56846)
			(xy 17.197578 -377.660916) (xy 17.204944 -377.679204) (xy 17.21231 -377.68657) (xy 17.232799 -377.708117)
			(xy 17.267497 -377.756399) (xy 17.294282 -377.80948) (xy 17.312506 -377.866075) (xy 17.321726 -377.924812)
			(xy 17.322292 -377.95454) (xy 17.321806 -377.981791) (xy 17.31405 -378.035739) (xy 17.298695 -378.088034)
			(xy 17.276053 -378.137611) (xy 17.246587 -378.183461) (xy 17.210896 -378.224652) (xy 17.169705 -378.260343)
			(xy 17.123855 -378.289809) (xy 17.074278 -378.312451) (xy 17.021983 -378.327806) (xy 16.968035 -378.335562)
			(xy 16.913533 -378.335562) (xy 16.859585 -378.327806) (xy 16.80729 -378.312451) (xy 16.757713 -378.289809)
			(xy 16.711863 -378.260343) (xy 16.670672 -378.224652) (xy 16.634981 -378.183461) (xy 16.605515 -378.137611)
			(xy 16.582873 -378.088034) (xy 16.567518 -378.035739) (xy 16.559762 -377.981791) (xy 16.559276 -377.95454)
			(xy 15.054911 -377.95454) (xy 15.055088 -377.963938) (xy 15.054596 -377.991648) (xy 15.046568 -378.046482)
			(xy 15.030685 -378.099577) (xy 15.007284 -378.149813) (xy 14.976857 -378.196133) (xy 14.958822 -378.217176)
			(xy 14.952726 -378.224288) (xy 14.946122 -378.24156) (xy 14.946376 -378.328174) (xy 14.95298 -378.345446)
			(xy 14.95933 -378.352558) (xy 14.977614 -378.373652) (xy 15.00844 -378.420193) (xy 15.032153 -378.470729)
			(xy 15.048248 -378.524181) (xy 15.056381 -378.579408) (xy 15.056866 -378.60732) (xy 15.05638 -378.634571)
			(xy 15.048624 -378.688519) (xy 15.033269 -378.740814) (xy 15.010627 -378.790391) (xy 14.981161 -378.836241)
			(xy 14.94547 -378.877432) (xy 14.904279 -378.913123) (xy 14.858429 -378.942589) (xy 14.808852 -378.965231)
			(xy 14.756557 -378.980586) (xy 14.702609 -378.988342) (xy 14.648107 -378.988342) (xy 14.594159 -378.980586)
			(xy 14.541864 -378.965231) (xy 14.492287 -378.942589) (xy 14.446437 -378.913123) (xy 14.405246 -378.877432)
			(xy 14.369555 -378.836241) (xy 14.340089 -378.790391) (xy 14.317447 -378.740814) (xy 14.302092 -378.688519)
			(xy 14.294336 -378.634571) (xy 14.29385 -378.60732) (xy 14.294333 -378.57961) (xy 14.302366 -378.524776)
			(xy 14.318251 -378.471681) (xy 14.341654 -378.421445) (xy 14.372081 -378.375126) (xy 14.390116 -378.354082)
			(xy 14.396212 -378.34697) (xy 14.402816 -378.329698) (xy 14.402562 -378.243084) (xy 14.395958 -378.225812)
			(xy 14.389608 -378.2187) (xy 14.371357 -378.197578) (xy 14.340525 -378.151046) (xy 14.316805 -378.100517)
			(xy 14.300702 -378.047071) (xy 14.292561 -377.991848) (xy 14.292072 -377.963938) (xy 4.461256 -377.963938)
			(xy 4.461256 -381.41402) (xy 6.528562 -381.41402) (xy 6.528988 -381.38764) (xy 6.536251 -381.335383)
			(xy 6.55064 -381.284623) (xy 6.571882 -381.236329) (xy 6.599573 -381.19142) (xy 6.633183 -381.150752)
			(xy 6.672074 -381.115099) (xy 6.715503 -381.085142) (xy 6.738874 -381.072898) (xy 6.752082 -381.066548)
			(xy 6.767068 -381.042164) (xy 6.767068 -380.922276) (xy 6.752082 -380.897892) (xy 6.738874 -380.891542)
			(xy 6.715506 -380.879296) (xy 6.672083 -380.849334) (xy 6.633198 -380.813679) (xy 6.599593 -380.77301)
			(xy 6.571906 -380.728102) (xy 6.550665 -380.679809) (xy 6.536274 -380.629053) (xy 6.529009 -380.576799)
			(xy 6.528562 -380.55042) (xy 6.529097 -380.523171) (xy 6.53685 -380.469226) (xy 6.552201 -380.416934)
			(xy 6.574837 -380.367359) (xy 6.604299 -380.32151) (xy 6.639985 -380.280321) (xy 6.68117 -380.244629)
			(xy 6.727015 -380.215161) (xy 6.776587 -380.192518) (xy 6.828877 -380.17716) (xy 6.882821 -380.1694)
			(xy 6.91007 -380.168912) (xy 6.939203 -380.16946) (xy 6.996792 -380.178316) (xy 7.052364 -380.195826)
			(xy 7.104628 -380.221582) (xy 7.152367 -380.254987) (xy 7.194471 -380.295263) (xy 7.229961 -380.341472)
			(xy 7.258012 -380.392542) (xy 7.277971 -380.447282) (xy 7.284212 -380.475744) (xy 7.287768 -380.493524)
			(xy 7.315708 -380.516384) (xy 7.859522 -380.516384) (xy 7.88452 -380.516989) (xy 7.933545 -380.5268)
			(xy 7.979716 -380.545983) (xy 8.02126 -380.5738) (xy 8.039354 -380.59106) (xy 8.304345 -380.856051)
			(xy 9.436082 -380.856051) (xy 9.436082 -380.801549) (xy 9.443838 -380.747602) (xy 9.459193 -380.695308)
			(xy 9.481834 -380.645731) (xy 9.5113 -380.599881) (xy 9.546991 -380.558691) (xy 9.588181 -380.523)
			(xy 9.634031 -380.493534) (xy 9.683608 -380.470893) (xy 9.735902 -380.455538) (xy 9.789849 -380.447782)
			(xy 9.8171 -380.447296) (xy 9.842716 -380.447723) (xy 9.893486 -380.454584) (xy 9.942881 -380.46818)
			(xy 9.990009 -380.488269) (xy 10.034024 -380.514487) (xy 10.054336 -380.5301) (xy 10.062464 -380.53645)
			(xy 10.082276 -380.542038) (xy 10.17524 -380.529846) (xy 10.19302 -380.519432) (xy 10.199116 -380.51105)
			(xy 10.208935 -380.498203) (xy 10.230428 -380.474041) (xy 10.242042 -380.46279) (xy 10.249916 -380.45517)
			(xy 10.25779 -380.435866) (xy 10.256012 -380.3396) (xy 10.247376 -380.32055) (xy 10.239248 -380.313184)
			(xy 10.219468 -380.294997) (xy 10.184674 -380.254051) (xy 10.155972 -380.208626) (xy 10.133932 -380.159621)
			(xy 10.118989 -380.108008) (xy 10.11144 -380.054808) (xy 10.110978 -380.027942) (xy 10.111464 -380.000691)
			(xy 10.11922 -379.946743) (xy 10.134575 -379.894448) (xy 10.157217 -379.844871) (xy 10.186683 -379.799021)
			(xy 10.222374 -379.75783) (xy 10.263565 -379.722139) (xy 10.309415 -379.692673) (xy 10.358992 -379.670031)
			(xy 10.411287 -379.654676) (xy 10.465235 -379.64692) (xy 10.519737 -379.64692) (xy 10.573685 -379.654676)
			(xy 10.62598 -379.670031) (xy 10.675557 -379.692673) (xy 10.721407 -379.722139) (xy 10.762598 -379.75783)
			(xy 10.798289 -379.799021) (xy 10.827755 -379.844871) (xy 10.850397 -379.894448) (xy 10.865752 -379.946743)
			(xy 10.873508 -380.000691) (xy 10.873994 -380.027942) (xy 10.873606 -380.053088) (xy 12.10945 -380.053088)
			(xy 12.109966 -380.025484) (xy 12.117913 -379.97085) (xy 12.133654 -379.917933) (xy 12.15686 -379.867839)
			(xy 12.187045 -379.821613) (xy 12.22358 -379.780222) (xy 12.244324 -379.762004) (xy 12.252452 -379.755146)
			(xy 12.26185 -379.735842) (xy 12.264898 -379.63856) (xy 12.25677 -379.619002) (xy 12.248896 -379.611382)
			(xy 12.230736 -379.593319) (xy 12.198897 -379.553199) (xy 12.17271 -379.50918) (xy 12.152646 -379.462055)
			(xy 12.139067 -379.412668) (xy 12.132215 -379.36191) (xy 12.131802 -379.3363) (xy 12.132268 -379.30893)
			(xy 12.140085 -379.254751) (xy 12.155575 -379.202247) (xy 12.178416 -379.152501) (xy 12.208141 -379.106534)
			(xy 12.225782 -379.085602) (xy 12.231878 -379.07849) (xy 12.238228 -379.061472) (xy 12.238228 -378.976128)
			(xy 12.231878 -378.95911) (xy 12.225782 -378.951998) (xy 12.208126 -378.93108) (xy 12.178417 -378.885103)
			(xy 12.155585 -378.835352) (xy 12.140098 -378.782848) (xy 12.132274 -378.72867) (xy 12.131802 -378.7013)
			(xy 12.132288 -378.674049) (xy 12.140044 -378.620101) (xy 12.155399 -378.567806) (xy 12.178041 -378.518229)
			(xy 12.207507 -378.472379) (xy 12.243198 -378.431188) (xy 12.284389 -378.395497) (xy 12.330239 -378.366031)
			(xy 12.379816 -378.343389) (xy 12.432111 -378.328034) (xy 12.486059 -378.320278) (xy 12.540561 -378.320278)
			(xy 12.594509 -378.328034) (xy 12.646804 -378.343389) (xy 12.696381 -378.366031) (xy 12.742231 -378.395497)
			(xy 12.783422 -378.431188) (xy 12.819113 -378.472379) (xy 12.848579 -378.518229) (xy 12.871221 -378.567806)
			(xy 12.886576 -378.620101) (xy 12.894332 -378.674049) (xy 12.894818 -378.7013) (xy 12.894372 -378.728671)
			(xy 12.886552 -378.782852) (xy 12.87106 -378.835356) (xy 12.848213 -378.885103) (xy 12.818482 -378.931068)
			(xy 12.800838 -378.951998) (xy 12.794742 -378.95911) (xy 12.788392 -378.976128) (xy 12.788392 -379.061472)
			(xy 12.794742 -379.07849) (xy 12.800838 -379.085602) (xy 12.818498 -379.106517) (xy 12.848205 -379.152495)
			(xy 12.871037 -379.202247) (xy 12.886523 -379.254751) (xy 12.894347 -379.30893) (xy 12.894818 -379.3363)
			(xy 12.894374 -379.363907) (xy 12.886414 -379.418544) (xy 12.870659 -379.471463) (xy 12.84744 -379.521558)
			(xy 12.817241 -379.567781) (xy 12.780694 -379.609168) (xy 12.759944 -379.627384) (xy 12.751816 -379.634242)
			(xy 12.742418 -379.653546) (xy 12.73937 -379.750828) (xy 12.747498 -379.770386) (xy 12.755372 -379.778006)
			(xy 12.773568 -379.796033) (xy 12.805406 -379.836161) (xy 12.831589 -379.880187) (xy 12.851646 -379.927319)
			(xy 12.865217 -379.976712) (xy 12.872058 -380.027476) (xy 12.872466 -380.053088) (xy 12.872004 -380.080663)
			(xy 12.864052 -380.135236) (xy 12.848327 -380.188097) (xy 12.825157 -380.238143) (xy 12.795023 -380.284332)
			(xy 12.758554 -380.325703) (xy 12.737846 -380.343918) (xy 12.72921 -380.351284) (xy 12.719812 -380.37135)
			(xy 12.72032 -380.471934) (xy 12.729718 -380.492) (xy 12.738354 -380.499366) (xy 12.759369 -380.517586)
			(xy 12.796408 -380.559077) (xy 12.827037 -380.605502) (xy 12.850607 -380.655879) (xy 12.866619 -380.709142)
			(xy 12.874734 -380.764165) (xy 12.87526 -380.791974) (xy 12.874774 -380.819225) (xy 12.867018 -380.873173)
			(xy 12.851663 -380.925468) (xy 12.829021 -380.975045) (xy 12.799555 -381.020895) (xy 12.763864 -381.062086)
			(xy 12.722673 -381.097777) (xy 12.676823 -381.127243) (xy 12.627246 -381.149885) (xy 12.574951 -381.16524)
			(xy 12.521003 -381.172996) (xy 12.466501 -381.172996) (xy 12.412553 -381.16524) (xy 12.360258 -381.149885)
			(xy 12.310681 -381.127243) (xy 12.264831 -381.097777) (xy 12.22364 -381.062086) (xy 12.187949 -381.020895)
			(xy 12.158483 -380.975045) (xy 12.135841 -380.925468) (xy 12.120486 -380.873173) (xy 12.11273 -380.819225)
			(xy 12.112244 -380.791974) (xy 12.112745 -380.764401) (xy 12.120688 -380.709829) (xy 12.136405 -380.656969)
			(xy 12.159569 -380.606922) (xy 12.189696 -380.560732) (xy 12.226159 -380.51936) (xy 12.246864 -380.501144)
			(xy 12.2555 -380.493778) (xy 12.264898 -380.473712) (xy 12.26439 -380.373128) (xy 12.254992 -380.353062)
			(xy 12.246356 -380.345696) (xy 12.225325 -380.327494) (xy 12.188286 -380.286) (xy 12.157659 -380.239571)
			(xy 12.134092 -380.18919) (xy 12.118084 -380.135924) (xy 12.109973 -380.080898) (xy 12.10945 -380.053088)
			(xy 10.873606 -380.053088) (xy 10.873597 -380.053653) (xy 10.866669 -380.104608) (xy 10.852958 -380.154169)
			(xy 10.832712 -380.20144) (xy 10.806299 -380.245561) (xy 10.774197 -380.285734) (xy 10.755884 -380.303786)
			(xy 10.74801 -380.311406) (xy 10.740136 -380.33071) (xy 10.741914 -380.426976) (xy 10.75055 -380.446026)
			(xy 10.758678 -380.453392) (xy 10.7785 -380.471535) (xy 10.81329 -380.512491) (xy 10.841985 -380.557926)
			(xy 10.864018 -380.606939) (xy 10.878952 -380.658559) (xy 10.886491 -380.711765) (xy 10.886948 -380.738634)
			(xy 10.886454 -380.765884) (xy 10.878694 -380.81983) (xy 10.863336 -380.872122) (xy 10.840694 -380.921696)
			(xy 10.811228 -380.967545) (xy 10.775538 -381.008734) (xy 10.73435 -381.044425) (xy 10.688502 -381.073891)
			(xy 10.638927 -381.096534) (xy 10.586635 -381.111893) (xy 10.53269 -381.119654) (xy 10.50544 -381.120142)
			(xy 10.479824 -381.119706) (xy 10.429054 -381.11285) (xy 10.379659 -381.099256) (xy 10.33253 -381.079169)
			(xy 10.288516 -381.052951) (xy 10.268204 -381.037338) (xy 10.260076 -381.030988) (xy 10.240264 -381.0254)
			(xy 10.1473 -381.037592) (xy 10.12952 -381.048006) (xy 10.123424 -381.056388) (xy 10.105294 -381.079848)
			(xy 10.062978 -381.121375) (xy 10.014752 -381.155861) (xy 9.961775 -381.182479) (xy 9.90532 -381.200587)
			(xy 9.846744 -381.209752) (xy 9.8171 -381.210312) (xy 9.789849 -381.209818) (xy 9.735902 -381.202062)
			(xy 9.683608 -381.186707) (xy 9.634031 -381.164066) (xy 9.588181 -381.1346) (xy 9.546991 -381.098909)
			(xy 9.5113 -381.057719) (xy 9.481834 -381.011869) (xy 9.459193 -380.962292) (xy 9.443838 -380.909998)
			(xy 9.436082 -380.856051) (xy 8.304345 -380.856051) (xy 8.853424 -381.40513) (xy 15.882112 -381.40513)
			(xy 15.882593 -381.37776) (xy 15.890407 -381.323582) (xy 15.905892 -381.271079) (xy 15.928731 -381.221332)
			(xy 15.958452 -381.175364) (xy 15.976092 -381.154432) (xy 15.982188 -381.14732) (xy 15.988538 -381.130302)
			(xy 15.988538 -381.044958) (xy 15.982188 -381.02794) (xy 15.976092 -381.020828) (xy 15.958482 -380.999871)
			(xy 15.928759 -380.953906) (xy 15.905914 -380.904164) (xy 15.890417 -380.851666) (xy 15.882586 -380.797491)
			(xy 15.882583 -380.742754) (xy 15.890407 -380.688578) (xy 15.905898 -380.636078) (xy 15.928737 -380.586333)
			(xy 15.958455 -380.540365) (xy 15.976092 -380.519432) (xy 15.982188 -380.51232) (xy 15.988538 -380.495302)
			(xy 15.988538 -380.409958) (xy 15.982188 -380.39294) (xy 15.976092 -380.385828) (xy 15.958482 -380.364871)
			(xy 15.928759 -380.318906) (xy 15.905914 -380.269164) (xy 15.890417 -380.216666) (xy 15.882586 -380.162491)
			(xy 15.882583 -380.107754) (xy 15.890407 -380.053578) (xy 15.905898 -380.001078) (xy 15.928737 -379.951333)
			(xy 15.958455 -379.905365) (xy 15.976092 -379.884432) (xy 15.982188 -379.87732) (xy 15.988538 -379.860302)
			(xy 15.988538 -379.774958) (xy 15.982188 -379.75794) (xy 15.976092 -379.750828) (xy 15.958482 -379.729871)
			(xy 15.928759 -379.683906) (xy 15.905914 -379.634164) (xy 15.890417 -379.581666) (xy 15.882586 -379.527491)
			(xy 15.882583 -379.472754) (xy 15.890407 -379.418578) (xy 15.905898 -379.366078) (xy 15.928737 -379.316333)
			(xy 15.958455 -379.270365) (xy 15.976092 -379.249432) (xy 15.982188 -379.24232) (xy 15.988538 -379.225302)
			(xy 15.988538 -379.139958) (xy 15.982188 -379.12294) (xy 15.976092 -379.115828) (xy 15.958451 -379.094897)
			(xy 15.92874 -379.048924) (xy 15.905904 -378.999176) (xy 15.890414 -378.946675) (xy 15.882586 -378.892499)
			(xy 15.882112 -378.86513) (xy 15.882598 -378.837879) (xy 15.890354 -378.783931) (xy 15.905709 -378.731636)
			(xy 15.928351 -378.682059) (xy 15.957817 -378.636209) (xy 15.993508 -378.595018) (xy 16.034699 -378.559327)
			(xy 16.080549 -378.529861) (xy 16.130126 -378.507219) (xy 16.182421 -378.491864) (xy 16.236369 -378.484108)
			(xy 16.290871 -378.484108) (xy 16.344819 -378.491864) (xy 16.397114 -378.507219) (xy 16.446691 -378.529861)
			(xy 16.492541 -378.559327) (xy 16.533732 -378.595018) (xy 16.569423 -378.636209) (xy 16.598889 -378.682059)
			(xy 16.621531 -378.731636) (xy 16.636886 -378.783931) (xy 16.644642 -378.837879) (xy 16.645128 -378.86513)
			(xy 16.644697 -378.892502) (xy 16.636873 -378.946683) (xy 16.621377 -378.999187) (xy 16.598527 -379.048934)
			(xy 16.568794 -379.094898) (xy 16.551148 -379.115828) (xy 16.545052 -379.12294) (xy 16.538702 -379.139958)
			(xy 16.538702 -379.225302) (xy 16.545052 -379.24232) (xy 16.551148 -379.249432) (xy 16.568819 -379.27034)
			(xy 16.598545 -379.316312) (xy 16.62139 -379.366062) (xy 16.636885 -379.418568) (xy 16.644711 -379.47275)
			(xy 16.644708 -379.527495) (xy 16.636875 -379.581676) (xy 16.621374 -379.63418) (xy 16.598523 -379.683928)
			(xy 16.568792 -379.729896) (xy 16.551148 -379.750828) (xy 16.545052 -379.75794) (xy 16.538702 -379.774958)
			(xy 16.538702 -379.860302) (xy 16.545052 -379.87732) (xy 16.551148 -379.884432) (xy 16.568819 -379.90534)
			(xy 16.598545 -379.951312) (xy 16.62139 -380.001062) (xy 16.636885 -380.053568) (xy 16.644711 -380.10775)
			(xy 16.644708 -380.162495) (xy 16.636875 -380.216676) (xy 16.621374 -380.26918) (xy 16.598523 -380.318928)
			(xy 16.568792 -380.364896) (xy 16.551148 -380.385828) (xy 16.545052 -380.39294) (xy 16.538702 -380.409958)
			(xy 16.538702 -380.495302) (xy 16.545052 -380.51232) (xy 16.551148 -380.519432) (xy 16.568819 -380.54034)
			(xy 16.598545 -380.586312) (xy 16.62139 -380.636062) (xy 16.636885 -380.688568) (xy 16.644711 -380.74275)
			(xy 16.644708 -380.797495) (xy 16.644405 -380.799594) (xy 18.005552 -380.799594) (xy 18.005939 -380.774164)
			(xy 18.012698 -380.723755) (xy 18.026095 -380.674691) (xy 18.045893 -380.627843) (xy 18.071741 -380.584041)
			(xy 18.103179 -380.544061) (xy 18.121122 -380.526036) (xy 18.128488 -380.518924) (xy 18.136362 -380.500382)
			(xy 18.136616 -380.406656) (xy 18.128742 -380.388114) (xy 18.121376 -380.380748) (xy 18.10012 -380.35909)
			(xy 18.064082 -380.310269) (xy 18.036228 -380.256358) (xy 18.01726 -380.198718) (xy 18.007659 -380.138801)
			(xy 18.007076 -380.10846) (xy 18.007582 -380.079721) (xy 18.01621 -380.022893) (xy 18.033264 -379.968002)
			(xy 18.05836 -379.916291) (xy 18.090928 -379.868929) (xy 18.1102 -379.847602) (xy 18.116804 -379.84049)
			(xy 18.123916 -379.822964) (xy 18.123916 -379.733556) (xy 18.116804 -379.71603) (xy 18.1102 -379.708918)
			(xy 18.090929 -379.687591) (xy 18.058364 -379.640229) (xy 18.033273 -379.588517) (xy 18.016223 -379.533626)
			(xy 18.007601 -379.476799) (xy 18.007601 -379.419321) (xy 18.016223 -379.362494) (xy 18.033273 -379.307603)
			(xy 18.058364 -379.255891) (xy 18.090929 -379.208529) (xy 18.1102 -379.187202) (xy 18.116804 -379.18009)
			(xy 18.123916 -379.162564) (xy 18.123916 -379.073156) (xy 18.116804 -379.05563) (xy 18.1102 -379.048518)
			(xy 18.090921 -379.027198) (xy 18.058354 -378.979835) (xy 18.033262 -378.928122) (xy 18.016213 -378.873229)
			(xy 18.007595 -378.8164) (xy 18.007076 -378.78766) (xy 18.007541 -378.760408) (xy 18.015302 -378.706461)
			(xy 18.030661 -378.654167) (xy 18.053306 -378.60459) (xy 18.082775 -378.558741) (xy 18.118469 -378.517552)
			(xy 18.15966 -378.481861) (xy 18.205511 -378.452395) (xy 18.255089 -378.429753) (xy 18.307384 -378.414397)
			(xy 18.361332 -378.406639) (xy 18.388584 -378.406152) (xy 18.417229 -378.406637) (xy 18.473874 -378.415214)
			(xy 18.528601 -378.432164) (xy 18.580178 -378.457104) (xy 18.627447 -378.489474) (xy 18.669346 -378.528548)
			(xy 18.687542 -378.550678) (xy 18.6944 -378.559314) (xy 18.713704 -378.56922) (xy 18.811748 -378.574554)
			(xy 18.832068 -378.56668) (xy 18.839688 -378.558806) (xy 18.861356 -378.537509) (xy 18.910208 -378.501392)
			(xy 18.964166 -378.473475) (xy 19.021868 -378.454464) (xy 19.081854 -378.444839) (xy 19.11223 -378.444252)
			(xy 19.14149 -378.444813) (xy 19.199321 -378.453759) (xy 19.255112 -378.471422) (xy 19.307555 -378.497388)
			(xy 19.355424 -378.53105) (xy 19.376898 -378.550932) (xy 19.38401 -378.55779) (xy 19.402044 -378.565156)
			(xy 19.492468 -378.565156) (xy 19.510502 -378.55779) (xy 19.517614 -378.550932) (xy 19.539048 -378.531001)
			(xy 19.586919 -378.497327) (xy 19.639371 -378.471358) (xy 19.695174 -378.453703) (xy 19.753018 -378.444778)
			(xy 19.782282 -378.444252) (xy 19.811862 -378.444836) (xy 19.870315 -378.453966) (xy 19.926657 -378.472009)
			(xy 19.979539 -378.498533) (xy 20.027693 -378.532901) (xy 20.069964 -378.574291) (xy 20.088098 -378.597668)
			(xy 20.095686 -378.606789) (xy 20.116888 -378.617376) (xy 20.128738 -378.617988) (xy 20.210272 -378.617988)
			(xy 20.222117 -378.617357) (xy 20.243308 -378.60677) (xy 20.250912 -378.597668) (xy 20.260074 -378.585618)
			(xy 20.280037 -378.562857) (xy 20.29079 -378.552202) (xy 20.298664 -378.544582) (xy 20.306538 -378.525024)
			(xy 20.303744 -378.428504) (xy 20.294854 -378.409454) (xy 20.286726 -378.402342) (xy 20.266449 -378.384128)
			(xy 20.230747 -378.342943) (xy 20.201264 -378.297102) (xy 20.178597 -378.247534) (xy 20.163208 -378.195247)
			(xy 20.155409 -378.141304) (xy 20.1549 -378.114052) (xy 20.155347 -378.086223) (xy 20.163428 -378.031153)
			(xy 20.179427 -377.977844) (xy 20.203003 -377.927425) (xy 20.233657 -377.880968) (xy 20.270736 -377.839458)
			(xy 20.313455 -377.803779) (xy 20.360905 -377.774686) (xy 20.386294 -377.763278) (xy 20.395946 -377.759214)
			(xy 20.41017 -377.744482) (xy 20.443444 -377.656344) (xy 20.442428 -377.63577) (xy 20.43811 -377.626372)
			(xy 20.42649 -377.600731) (xy 20.410102 -377.546875) (xy 20.4018 -377.491197) (xy 20.40128 -377.46305)
			(xy 20.401804 -377.434133) (xy 20.410528 -377.376961) (xy 20.427783 -377.321761) (xy 20.453173 -377.269798)
			(xy 20.486117 -377.222265) (xy 20.52586 -377.180249) (xy 20.548346 -377.16206) (xy 20.557129 -377.154519)
			(xy 20.567299 -377.133744) (xy 20.567904 -377.122182) (xy 20.567904 -377.041918) (xy 20.567322 -377.030352)
			(xy 20.557135 -377.009581) (xy 20.548346 -377.00204) (xy 20.527563 -376.985287) (xy 20.490433 -376.946933)
			(xy 20.459012 -376.903779) (xy 20.433913 -376.856665) (xy 20.415627 -376.806513) (xy 20.40451 -376.754301)
			(xy 20.400781 -376.70105) (xy 20.40451 -376.647799) (xy 20.415627 -376.595587) (xy 20.433913 -376.545435)
			(xy 20.459012 -376.498321) (xy 20.490433 -376.455167) (xy 20.527563 -376.416813) (xy 20.548346 -376.40006)
			(xy 20.557129 -376.392519) (xy 20.567299 -376.371744) (xy 20.567904 -376.360182) (xy 20.567904 -376.279918)
			(xy 20.567322 -376.268352) (xy 20.557135 -376.247581) (xy 20.548346 -376.24004) (xy 20.527563 -376.223287)
			(xy 20.490433 -376.184933) (xy 20.459012 -376.141779) (xy 20.433913 -376.094665) (xy 20.415627 -376.044513)
			(xy 20.40451 -375.992301) (xy 20.400781 -375.93905) (xy 20.40451 -375.885799) (xy 20.415627 -375.833587)
			(xy 20.433913 -375.783435) (xy 20.459012 -375.736321) (xy 20.490433 -375.693167) (xy 20.527563 -375.654813)
			(xy 20.548346 -375.63806) (xy 20.557129 -375.630519) (xy 20.567299 -375.609744) (xy 20.567904 -375.598182)
			(xy 20.567904 -375.517918) (xy 20.567322 -375.506352) (xy 20.557135 -375.485581) (xy 20.548346 -375.47804)
			(xy 20.52587 -375.45984) (xy 20.486137 -375.417821) (xy 20.453199 -375.370287) (xy 20.42781 -375.318328)
			(xy 20.410551 -375.263133) (xy 20.401818 -375.205965) (xy 20.40128 -375.17705) (xy 20.401766 -375.149799)
			(xy 20.409522 -375.095851) (xy 20.424877 -375.043556) (xy 20.447519 -374.993979) (xy 20.476985 -374.948129)
			(xy 20.512676 -374.906938) (xy 20.553867 -374.871247) (xy 20.599717 -374.841781) (xy 20.649294 -374.819139)
			(xy 20.701589 -374.803784) (xy 20.755537 -374.796028) (xy 20.810039 -374.796028) (xy 20.863987 -374.803784)
			(xy 20.916282 -374.819139) (xy 20.965859 -374.841781) (xy 21.011709 -374.871247) (xy 21.0529 -374.906938)
			(xy 21.088591 -374.948129) (xy 21.118057 -374.993979) (xy 21.140699 -375.043556) (xy 21.156054 -375.095851)
			(xy 21.16381 -375.149799) (xy 21.164296 -375.17705) (xy 21.163743 -375.205966) (xy 21.155022 -375.263135)
			(xy 21.137771 -375.318334) (xy 21.112385 -375.370295) (xy 21.079448 -375.41783) (xy 21.039713 -375.459849)
			(xy 21.01723 -375.47804) (xy 21.008443 -375.485577) (xy 20.998276 -375.506355) (xy 20.997672 -375.517918)
			(xy 20.997672 -375.598182) (xy 20.998228 -375.609752) (xy 21.00843 -375.630525) (xy 21.01723 -375.63806)
			(xy 21.038013 -375.654813) (xy 21.075144 -375.693166) (xy 21.106565 -375.736321) (xy 21.131664 -375.783435)
			(xy 21.14995 -375.833587) (xy 21.161067 -375.885798) (xy 21.164797 -375.93905) (xy 21.161067 -375.992302)
			(xy 21.14995 -376.044513) (xy 21.131664 -376.094665) (xy 21.106565 -376.141779) (xy 21.075144 -376.184934)
			(xy 21.038013 -376.223287) (xy 21.01723 -376.24004) (xy 21.008443 -376.247577) (xy 20.998276 -376.268355)
			(xy 20.997672 -376.279918) (xy 20.997672 -376.360182) (xy 20.998228 -376.371752) (xy 21.00843 -376.392525)
			(xy 21.01723 -376.40006) (xy 21.038013 -376.416813) (xy 21.075144 -376.455166) (xy 21.106565 -376.498321)
			(xy 21.131664 -376.545435) (xy 21.14995 -376.595587) (xy 21.154341 -376.616209) (xy 22.153395 -376.616209)
			(xy 22.157124 -376.562959) (xy 22.168239 -376.510749) (xy 22.186523 -376.460598) (xy 22.211619 -376.413485)
			(xy 22.243037 -376.370331) (xy 22.280165 -376.331978) (xy 22.300946 -376.315224) (xy 22.3097 -376.307655)
			(xy 22.319886 -376.286901) (xy 22.320504 -376.275346) (xy 22.320504 -376.195082) (xy 22.319942 -376.183513)
			(xy 22.309741 -376.162742) (xy 22.300946 -376.155204) (xy 22.280177 -376.138434) (xy 22.243048 -376.100082)
			(xy 22.211628 -376.056929) (xy 22.18653 -376.009818) (xy 22.168243 -375.959668) (xy 22.157126 -375.907458)
			(xy 22.153395 -375.854209) (xy 22.157124 -375.800959) (xy 22.168239 -375.748749) (xy 22.186523 -375.698598)
			(xy 22.211619 -375.651485) (xy 22.243037 -375.608331) (xy 22.280165 -375.569978) (xy 22.300946 -375.553224)
			(xy 22.3097 -375.545655) (xy 22.319886 -375.524901) (xy 22.320504 -375.513346) (xy 22.320504 -375.433082)
			(xy 22.319942 -375.421513) (xy 22.309741 -375.400742) (xy 22.300946 -375.393204) (xy 22.278453 -375.375024)
			(xy 22.238721 -375.333001) (xy 22.205785 -375.285463) (xy 22.180398 -375.2335) (xy 22.163144 -375.178301)
			(xy 22.154415 -375.12113) (xy 22.15388 -375.092214) (xy 22.154366 -375.064963) (xy 22.162122 -375.011015)
			(xy 22.177477 -374.95872) (xy 22.200119 -374.909143) (xy 22.229585 -374.863293) (xy 22.265276 -374.822102)
			(xy 22.306467 -374.786411) (xy 22.352317 -374.756945) (xy 22.401894 -374.734303) (xy 22.454189 -374.718948)
			(xy 22.508137 -374.711192) (xy 22.562639 -374.711192) (xy 22.616587 -374.718948) (xy 22.668882 -374.734303)
			(xy 22.718459 -374.756945) (xy 22.764309 -374.786411) (xy 22.8055 -374.822102) (xy 22.841191 -374.863293)
			(xy 22.870657 -374.909143) (xy 22.893299 -374.95872) (xy 22.908654 -375.011015) (xy 22.91641 -375.064963)
			(xy 22.916896 -375.092214) (xy 22.916318 -375.121129) (xy 22.907601 -375.178297) (xy 22.890355 -375.233495)
			(xy 22.864975 -375.285457) (xy 22.832042 -375.332992) (xy 22.792311 -375.375012) (xy 22.76983 -375.393204)
			(xy 22.761059 -375.400757) (xy 22.750883 -375.421523) (xy 22.750272 -375.433082) (xy 22.750272 -375.513346)
			(xy 22.750848 -375.524914) (xy 22.761036 -375.545686) (xy 22.76983 -375.553224) (xy 22.790627 -375.569961)
			(xy 22.827759 -375.608315) (xy 22.859181 -375.651472) (xy 22.884281 -375.698587) (xy 22.902567 -375.748741)
			(xy 22.913683 -375.800955) (xy 22.917412 -375.854209) (xy 22.913681 -375.907462) (xy 22.902562 -375.959675)
			(xy 22.884274 -376.009829) (xy 22.859172 -376.056943) (xy 22.827748 -376.100098) (xy 22.790614 -376.138451)
			(xy 22.76983 -376.155204) (xy 22.761059 -376.162757) (xy 22.750883 -376.183523) (xy 22.750272 -376.195082)
			(xy 22.750272 -376.275346) (xy 22.750848 -376.286914) (xy 22.761036 -376.307686) (xy 22.76983 -376.315224)
			(xy 22.790627 -376.331961) (xy 22.827759 -376.370315) (xy 22.859181 -376.413472) (xy 22.884281 -376.460587)
			(xy 22.902567 -376.510741) (xy 22.913683 -376.562955) (xy 22.917412 -376.616209) (xy 22.913681 -376.669462)
			(xy 22.902562 -376.721675) (xy 22.884274 -376.771829) (xy 22.859172 -376.818943) (xy 22.827748 -376.862098)
			(xy 22.790614 -376.900451) (xy 22.76983 -376.917204) (xy 22.761059 -376.924757) (xy 22.750883 -376.945523)
			(xy 22.750272 -376.957082) (xy 22.750272 -377.037346) (xy 22.750848 -377.048914) (xy 22.761036 -377.069686)
			(xy 22.76983 -377.077224) (xy 22.792331 -377.095394) (xy 22.832064 -377.137419) (xy 22.865 -377.184958)
			(xy 22.890385 -377.236924) (xy 22.907638 -377.292125) (xy 22.916363 -377.349297) (xy 22.916896 -377.378214)
			(xy 22.916393 -377.405147) (xy 22.908811 -377.458476) (xy 22.8938 -377.510208) (xy 22.87166 -377.559313)
			(xy 22.84283 -377.604813) (xy 22.82571 -377.62561) (xy 22.818852 -377.633738) (xy 22.812756 -377.653804)
			(xy 22.823678 -377.7488) (xy 22.834346 -377.767088) (xy 22.842982 -377.773438) (xy 22.866608 -377.791547)
			(xy 22.908468 -377.833868) (xy 22.943245 -377.882178) (xy 22.970093 -377.935305) (xy 22.988361 -377.991958)
			(xy 22.997606 -378.050761) (xy 22.998176 -378.080524) (xy 22.997696 -378.10853) (xy 22.989523 -378.163942)
			(xy 22.973341 -378.217566) (xy 22.949498 -378.26825) (xy 22.918505 -378.314906) (xy 22.900132 -378.336048)
			(xy 22.893528 -378.343414) (xy 22.886924 -378.36094) (xy 22.888448 -378.450348) (xy 22.895814 -378.46762)
			(xy 22.902672 -378.474732) (xy 22.922864 -378.496215) (xy 22.957006 -378.544279) (xy 22.983348 -378.597023)
			(xy 23.001265 -378.653191) (xy 23.010329 -378.711446) (xy 23.010876 -378.740924) (xy 23.01039 -378.768175)
			(xy 23.002634 -378.822123) (xy 22.987279 -378.874418) (xy 22.964637 -378.923995) (xy 22.935171 -378.969845)
			(xy 22.89948 -379.011036) (xy 22.858289 -379.046727) (xy 22.812439 -379.076193) (xy 22.762862 -379.098835)
			(xy 22.710567 -379.11419) (xy 22.656619 -379.121946) (xy 22.602117 -379.121946) (xy 22.548169 -379.11419)
			(xy 22.495874 -379.098835) (xy 22.446297 -379.076193) (xy 22.400447 -379.046727) (xy 22.359256 -379.011036)
			(xy 22.323565 -378.969845) (xy 22.294099 -378.923995) (xy 22.271457 -378.874418) (xy 22.256102 -378.822123)
			(xy 22.248346 -378.768175) (xy 22.24786 -378.740924) (xy 22.248385 -378.71292) (xy 22.256549 -378.65751)
			(xy 22.272722 -378.603888) (xy 22.296554 -378.553203) (xy 22.327536 -378.506545) (xy 22.345904 -378.4854)
			(xy 22.352508 -378.478034) (xy 22.359112 -378.460508) (xy 22.357588 -378.3711) (xy 22.350222 -378.353828)
			(xy 22.343364 -378.346716) (xy 22.323201 -378.325207) (xy 22.289054 -378.277151) (xy 22.262705 -378.224414)
			(xy 22.244782 -378.168251) (xy 22.23571 -378.11) (xy 22.23516 -378.080524) (xy 22.235614 -378.053589)
			(xy 22.243206 -378.000258) (xy 22.258227 -377.948525) (xy 22.280379 -377.899421) (xy 22.30922 -377.853922)
			(xy 22.326346 -377.833128) (xy 22.333204 -377.825) (xy 22.3393 -377.804934) (xy 22.328378 -377.709938)
			(xy 22.31771 -377.69165) (xy 22.309074 -377.6853) (xy 22.28543 -377.667212) (xy 22.243569 -377.624889)
			(xy 22.208792 -377.576575) (xy 22.181946 -377.523443) (xy 22.163683 -377.466786) (xy 22.154445 -377.407978)
			(xy 22.15388 -377.378214) (xy 22.154378 -377.349296) (xy 22.163107 -377.292122) (xy 22.180367 -377.236922)
			(xy 22.205762 -377.18496) (xy 22.238711 -377.137426) (xy 22.278458 -377.095412) (xy 22.300946 -377.077224)
			(xy 22.3097 -377.069655) (xy 22.319886 -377.048901) (xy 22.320504 -377.037346) (xy 22.320504 -376.957082)
			(xy 22.319942 -376.945513) (xy 22.309741 -376.924742) (xy 22.300946 -376.917204) (xy 22.280177 -376.900434)
			(xy 22.243048 -376.862082) (xy 22.211628 -376.818929) (xy 22.18653 -376.771818) (xy 22.168243 -376.721668)
			(xy 22.157126 -376.669458) (xy 22.153395 -376.616209) (xy 21.154341 -376.616209) (xy 21.161067 -376.647798)
			(xy 21.164797 -376.70105) (xy 21.161067 -376.754302) (xy 21.14995 -376.806513) (xy 21.131664 -376.856665)
			(xy 21.106565 -376.903779) (xy 21.075144 -376.946934) (xy 21.038013 -376.985287) (xy 21.01723 -377.00204)
			(xy 21.008443 -377.009577) (xy 20.998276 -377.030355) (xy 20.997672 -377.041918) (xy 20.997672 -377.122182)
			(xy 20.998228 -377.133752) (xy 21.00843 -377.154525) (xy 21.01723 -377.16206) (xy 21.039701 -377.180266)
			(xy 21.079435 -377.222284) (xy 21.112375 -377.269816) (xy 21.137765 -377.321774) (xy 21.155025 -377.376968)
			(xy 21.163758 -377.434135) (xy 21.164296 -377.46305) (xy 21.163853 -377.49088) (xy 21.155772 -377.545949)
			(xy 21.139772 -377.599259) (xy 21.116195 -377.649678) (xy 21.085541 -377.696135) (xy 21.048461 -377.737644)
			(xy 21.005742 -377.773324) (xy 20.958291 -377.802416) (xy 20.932902 -377.813824) (xy 20.92325 -377.817888)
			(xy 20.909026 -377.83262) (xy 20.875752 -377.920758) (xy 20.876768 -377.941332) (xy 20.881086 -377.95073)
			(xy 20.888452 -377.966986) (xy 20.892425 -377.975526) (xy 20.905503 -377.989068) (xy 20.922589 -377.996973)
			(xy 20.941376 -377.998175) (xy 20.959329 -377.992513) (xy 20.974027 -377.980749) (xy 20.97913 -377.972828)
			(xy 20.993908 -377.94856) (xy 21.029543 -377.904305) (xy 21.071346 -377.865824) (xy 21.118394 -377.833968)
			(xy 21.169645 -377.809441) (xy 21.223967 -377.792785) (xy 21.280159 -377.78437) (xy 21.308568 -377.783852)
			(xy 21.335817 -377.784408) (xy 21.38976 -377.792159) (xy 21.442051 -377.807508) (xy 21.491625 -377.830143)
			(xy 21.537474 -377.859602) (xy 21.578663 -377.895286) (xy 21.614355 -377.936469) (xy 21.643823 -377.982312)
			(xy 21.666467 -378.031882) (xy 21.681826 -378.08417) (xy 21.689587 -378.138111) (xy 21.690076 -378.16536)
			(xy 21.689633 -378.19266) (xy 21.681852 -378.246704) (xy 21.666445 -378.299085) (xy 21.643725 -378.348734)
			(xy 21.614157 -378.394636) (xy 21.596604 -378.41555) (xy 21.59 -378.422916) (xy 21.583904 -378.44095)
			(xy 21.587206 -378.530104) (xy 21.594826 -378.547376) (xy 21.601938 -378.554488) (xy 21.623017 -378.576118)
			(xy 21.658744 -378.624811) (xy 21.686349 -378.678527) (xy 21.705141 -378.735923) (xy 21.714652 -378.795563)
			(xy 21.715222 -378.82576) (xy 21.714729 -378.8545) (xy 21.706098 -378.911328) (xy 21.68904 -378.966219)
			(xy 21.663942 -379.01793) (xy 21.631371 -379.065292) (xy 21.612098 -379.086618) (xy 21.605494 -379.09373)
			(xy 21.598382 -379.111256) (xy 21.598382 -379.200664) (xy 21.605494 -379.21819) (xy 21.612098 -379.225302)
			(xy 21.631339 -379.246655) (xy 21.663911 -379.294009) (xy 21.689011 -379.345714) (xy 21.706068 -379.400599)
			(xy 21.714697 -379.457423) (xy 21.715222 -379.48616) (xy 21.714752 -379.51353) (xy 21.706938 -379.56771)
			(xy 21.691451 -379.620214) (xy 21.668609 -379.669961) (xy 21.638884 -379.715927) (xy 21.621242 -379.736858)
			(xy 21.615146 -379.74397) (xy 21.608796 -379.760988) (xy 21.608796 -379.846332) (xy 21.615146 -379.86335)
			(xy 21.621242 -379.870462) (xy 21.638884 -379.891392) (xy 21.668594 -379.937366) (xy 21.691429 -379.987114)
			(xy 21.706919 -380.039615) (xy 21.714748 -380.093791) (xy 21.715222 -380.12116) (xy 21.714631 -380.151355)
			(xy 21.705111 -380.210989) (xy 21.686316 -380.26838) (xy 21.658718 -380.322094) (xy 21.623003 -380.370792)
			(xy 21.601938 -380.392432) (xy 21.594826 -380.399544) (xy 21.587206 -380.416816) (xy 21.583904 -380.50597)
			(xy 21.59 -380.524004) (xy 21.596604 -380.53137) (xy 21.614134 -380.552301) (xy 21.643695 -380.598202)
			(xy 21.666411 -380.647848) (xy 21.68182 -380.700224) (xy 21.689607 -380.754262) (xy 21.690076 -380.78156)
			(xy 21.689631 -380.807303) (xy 21.68954 -380.807976) (xy 25.408128 -380.807976) (xy 25.408547 -380.781076)
			(xy 25.416102 -380.727809) (xy 25.431074 -380.676133) (xy 25.453165 -380.627077) (xy 25.481935 -380.581616)
			(xy 25.516812 -380.540652) (xy 25.536652 -380.52248) (xy 25.544526 -380.515368) (xy 25.553416 -380.496826)
			(xy 25.556718 -380.402084) (xy 25.549352 -380.383034) (xy 25.541986 -380.375414) (xy 25.521744 -380.353929)
			(xy 25.487525 -380.305831) (xy 25.461121 -380.253037) (xy 25.443162 -380.196807) (xy 25.434077 -380.138482)
			(xy 25.433528 -380.108968) (xy 25.433968 -380.081597) (xy 25.441791 -380.027416) (xy 25.457286 -379.974913)
			(xy 25.480134 -379.925166) (xy 25.509864 -379.879201) (xy 25.527508 -379.85827) (xy 25.533604 -379.851158)
			(xy 25.539954 -379.83414) (xy 25.539954 -379.748796) (xy 25.533604 -379.731778) (xy 25.527508 -379.724666)
			(xy 25.509888 -379.703719) (xy 25.480173 -379.65775) (xy 25.457333 -379.608007) (xy 25.441838 -379.555509)
			(xy 25.434005 -379.501336) (xy 25.433528 -379.473968) (xy 25.434095 -379.444527) (xy 25.443132 -379.386344)
			(xy 25.461004 -379.33024) (xy 25.487284 -379.277549) (xy 25.521349 -379.229522) (xy 25.541478 -379.20803)
			(xy 25.54859 -379.200918) (xy 25.555956 -379.182122) (xy 25.554178 -379.089412) (xy 25.54605 -379.071124)
			(xy 25.538684 -379.064012) (xy 25.520399 -379.045947) (xy 25.488359 -379.005753) (xy 25.462003 -378.961624)
			(xy 25.441808 -378.914356) (xy 25.428139 -378.864805) (xy 25.421245 -378.813869) (xy 25.420828 -378.788168)
			(xy 25.421225 -378.760913) (xy 25.428987 -378.706957) (xy 25.444349 -378.654656) (xy 25.466998 -378.605073)
			(xy 25.496473 -378.559219) (xy 25.532174 -378.518025) (xy 25.573373 -378.482332) (xy 25.619233 -378.452866)
			(xy 25.66882 -378.430226) (xy 25.721124 -378.414873) (xy 25.775081 -378.40712) (xy 25.802336 -378.40666)
			(xy 25.831075 -378.407173) (xy 25.887903 -378.415799) (xy 25.942793 -378.432853) (xy 25.994505 -378.457947)
			(xy 26.041867 -378.490513) (xy 26.063194 -378.509784) (xy 26.070306 -378.516388) (xy 26.087832 -378.5235)
			(xy 26.17724 -378.5235) (xy 26.194766 -378.516388) (xy 26.201878 -378.509784) (xy 26.223205 -378.490514)
			(xy 26.270568 -378.457949) (xy 26.322279 -378.432858) (xy 26.37717 -378.415808) (xy 26.433997 -378.407186)
			(xy 26.491475 -378.407186) (xy 26.548302 -378.415808) (xy 26.603193 -378.432858) (xy 26.654904 -378.457949)
			(xy 26.702267 -378.490514) (xy 26.723594 -378.509784) (xy 26.730706 -378.516388) (xy 26.748232 -378.5235)
			(xy 26.83764 -378.5235) (xy 26.855166 -378.516388) (xy 26.862278 -378.509784) (xy 26.883597 -378.490504)
			(xy 26.93096 -378.457937) (xy 26.982674 -378.432846) (xy 27.037567 -378.415797) (xy 27.094396 -378.407178)
			(xy 27.123136 -378.40666) (xy 27.152189 -378.40722) (xy 27.209625 -378.416011) (xy 27.265063 -378.433414)
			(xy 27.317218 -378.459027) (xy 27.364884 -378.492256) (xy 27.406957 -378.532332) (xy 27.425142 -378.554996)
			(xy 27.432254 -378.56414) (xy 27.45232 -378.5743) (xy 27.554428 -378.57684) (xy 27.575002 -378.567696)
			(xy 27.582622 -378.558806) (xy 27.600825 -378.538308) (xy 27.642111 -378.502243) (xy 27.688133 -378.472457)
			(xy 27.737943 -378.449563) (xy 27.790517 -378.434032) (xy 27.844772 -378.426185) (xy 27.872182 -378.42571)
			(xy 27.899435 -378.426172) (xy 27.953387 -378.433927) (xy 28.005686 -378.449282) (xy 28.055267 -378.471923)
			(xy 28.101121 -378.501391) (xy 28.142315 -378.537085) (xy 28.178009 -378.578279) (xy 28.207477 -378.624133)
			(xy 28.230118 -378.673714) (xy 28.245473 -378.726013) (xy 28.253228 -378.779965) (xy 28.25369 -378.807218)
			(xy 28.25318 -378.835957) (xy 28.244554 -378.892786) (xy 28.227501 -378.947677) (xy 28.202407 -378.999388)
			(xy 28.169838 -379.04675) (xy 28.150566 -379.068076) (xy 28.143962 -379.075188) (xy 28.13685 -379.092714)
			(xy 28.13685 -379.182122) (xy 28.143962 -379.199648) (xy 28.150566 -379.20676) (xy 28.169855 -379.228071)
			(xy 28.202421 -379.275436) (xy 28.227512 -379.32715) (xy 28.244561 -379.382043) (xy 28.253182 -379.438873)
			(xy 28.25318 -379.496353) (xy 28.244555 -379.553182) (xy 28.227502 -379.608074) (xy 28.202407 -379.659787)
			(xy 28.169839 -379.707149) (xy 28.150566 -379.728476) (xy 28.143962 -379.735588) (xy 28.13685 -379.753114)
			(xy 28.13685 -379.842522) (xy 28.143962 -379.860048) (xy 28.150566 -379.86716) (xy 28.169846 -379.888479)
			(xy 28.202411 -379.935843) (xy 28.227501 -379.987557) (xy 28.24455 -380.04245) (xy 28.25317 -380.099278)
			(xy 28.25369 -380.128018) (xy 28.25311 -380.157458) (xy 28.244074 -380.215641) (xy 28.226206 -380.271744)
			(xy 28.199929 -380.324436) (xy 28.165867 -380.372464) (xy 28.14574 -380.393956) (xy 28.138882 -380.401068)
			(xy 28.131516 -380.418848) (xy 28.130754 -380.509018) (xy 28.137866 -380.527052) (xy 28.144724 -380.534418)
			(xy 28.164114 -380.555734) (xy 28.196836 -380.603167) (xy 28.222048 -380.654983) (xy 28.239178 -380.710002)
			(xy 28.247835 -380.766972) (xy 28.248356 -380.795784) (xy 28.247898 -380.823389) (xy 28.239929 -380.87802)
			(xy 28.224171 -380.930933) (xy 28.200952 -380.981023) (xy 28.170757 -381.027244) (xy 28.152852 -381.04826)
			(xy 28.146248 -381.05588) (xy 28.139644 -381.07493) (xy 28.145486 -381.166624) (xy 28.154122 -381.184912)
			(xy 28.161742 -381.191516) (xy 28.181621 -381.209687) (xy 28.216553 -381.250681) (xy 28.245368 -381.296182)
			(xy 28.267495 -381.345285) (xy 28.282492 -381.397013) (xy 28.290061 -381.450337) (xy 28.29052 -381.477266)
			(xy 28.290013 -381.504517) (xy 28.282261 -381.558466) (xy 28.26691 -381.610763) (xy 28.244272 -381.660342)
			(xy 28.214809 -381.706194) (xy 28.17912 -381.747387) (xy 28.137931 -381.783081) (xy 28.092082 -381.81255)
			(xy 28.042506 -381.835194) (xy 27.990211 -381.850551) (xy 27.936263 -381.85831) (xy 27.909012 -381.858774)
			(xy 27.882656 -381.858307) (xy 27.830447 -381.851041) (xy 27.779735 -381.836659) (xy 27.731484 -381.815435)
			(xy 27.686613 -381.787773) (xy 27.645976 -381.754199) (xy 27.627834 -381.735076) (xy 27.620722 -381.727456)
			(xy 27.602942 -381.719074) (xy 27.51074 -381.714756) (xy 27.492198 -381.721614) (xy 27.484578 -381.728472)
			(xy 27.463411 -381.747032) (xy 27.41662 -381.778333) (xy 27.365739 -381.802421) (xy 27.311871 -381.818773)
			(xy 27.256186 -381.827034) (xy 27.228038 -381.827532) (xy 27.200375 -381.827041) (xy 27.145625 -381.819074)
			(xy 27.0926 -381.803286) (xy 27.042409 -381.780008) (xy 26.996104 -381.749729) (xy 26.975054 -381.731774)
			(xy 26.967942 -381.72517) (xy 26.950162 -381.71882) (xy 26.86177 -381.720598) (xy 26.844244 -381.727964)
			(xy 26.837386 -381.734568) (xy 26.81591 -381.754503) (xy 26.768013 -381.788255) (xy 26.71552 -381.814291)
			(xy 26.659666 -381.831999) (xy 26.601761 -381.840963) (xy 26.572464 -381.841502) (xy 26.546974 -381.84109)
			(xy 26.496449 -381.834307) (xy 26.447277 -381.820855) (xy 26.400335 -381.800972) (xy 26.35646 -381.775012)
			(xy 26.316435 -381.74344) (xy 26.298398 -381.725424) (xy 26.291032 -381.717804) (xy 26.271728 -381.709676)
			(xy 26.17597 -381.711454) (xy 26.15692 -381.720344) (xy 26.149808 -381.728218) (xy 26.131629 -381.747742)
			(xy 26.090799 -381.782074) (xy 26.045582 -381.810379) (xy 25.996861 -381.832107) (xy 25.945588 -381.846831)
			(xy 25.892763 -381.854265) (xy 25.86609 -381.85471) (xy 25.838839 -381.854232) (xy 25.784891 -381.846474)
			(xy 25.732596 -381.831117) (xy 25.683019 -381.808475) (xy 25.637169 -381.779008) (xy 25.595978 -381.743316)
			(xy 25.560287 -381.702125) (xy 25.530821 -381.656274) (xy 25.50818 -381.606697) (xy 25.492825 -381.554401)
			(xy 25.485068 -381.500453) (xy 25.484582 -381.473202) (xy 25.485165 -381.442144) (xy 25.495229 -381.38085)
			(xy 25.515091 -381.321996) (xy 25.544226 -381.267138) (xy 25.56256 -381.242062) (xy 25.568656 -381.233934)
			(xy 25.57399 -381.215392) (xy 25.563576 -381.125476) (xy 25.554432 -381.108458) (xy 25.546558 -381.102108)
			(xy 25.52529 -381.083892) (xy 25.487817 -381.042282) (xy 25.456825 -380.995644) (xy 25.432982 -380.944977)
			(xy 25.416797 -380.891371) (xy 25.408618 -380.835974) (xy 25.408128 -380.807976) (xy 21.68954 -380.807976)
			(xy 21.682701 -380.85832) (xy 21.668976 -380.907942) (xy 21.648705 -380.955269) (xy 21.622254 -380.999441)
			(xy 21.60651 -381.019812) (xy 21.600668 -381.027178) (xy 21.59508 -381.044958) (xy 21.600414 -381.132334)
			(xy 21.608034 -381.149098) (xy 21.615146 -381.155956) (xy 21.633035 -381.17399) (xy 21.664398 -381.213947)
			(xy 21.690182 -381.257712) (xy 21.709931 -381.304511) (xy 21.723296 -381.353517) (xy 21.730041 -381.403862)
			(xy 21.730462 -381.42926) (xy 21.729976 -381.456511) (xy 21.72222 -381.510459) (xy 21.706865 -381.562754)
			(xy 21.684223 -381.612331) (xy 21.654757 -381.658181) (xy 21.619066 -381.699372) (xy 21.577875 -381.735063)
			(xy 21.532025 -381.764529) (xy 21.482448 -381.787171) (xy 21.430153 -381.802526) (xy 21.376205 -381.810282)
			(xy 21.321703 -381.810282) (xy 21.267755 -381.802526) (xy 21.21546 -381.787171) (xy 21.165883 -381.764529)
			(xy 21.120033 -381.735063) (xy 21.078842 -381.699372) (xy 21.043151 -381.658181) (xy 21.013685 -381.612331)
			(xy 20.991043 -381.562754) (xy 20.975688 -381.510459) (xy 20.967932 -381.456511) (xy 20.967446 -381.42926)
			(xy 20.967897 -381.403517) (xy 20.974825 -381.3525) (xy 20.988548 -381.302878) (xy 21.008819 -381.255551)
			(xy 21.035268 -381.211379) (xy 21.051012 -381.191008) (xy 21.056854 -381.183642) (xy 21.062442 -381.165862)
			(xy 21.057108 -381.078486) (xy 21.049488 -381.061722) (xy 21.042376 -381.054864) (xy 21.033534 -381.046143)
			(xy 21.016883 -381.027713) (xy 21.009102 -381.018034) (xy 21.001736 -381.008382) (xy 20.979892 -380.998222)
			(xy 20.87372 -381.001778) (xy 20.852638 -381.013208) (xy 20.84578 -381.023368) (xy 20.830474 -381.044859)
			(xy 20.794837 -381.083769) (xy 20.754179 -381.117397) (xy 20.709276 -381.145103) (xy 20.660984 -381.166358)
			(xy 20.610223 -381.180756) (xy 20.557963 -381.188023) (xy 20.531582 -381.188468) (xy 20.503346 -381.187942)
			(xy 20.447491 -381.179616) (xy 20.393474 -381.163148) (xy 20.342474 -381.138898) (xy 20.295605 -381.107396)
			(xy 20.253891 -381.06933) (xy 20.235672 -381.047752) (xy 20.228068 -381.039366) (xy 20.20761 -381.029744)
			(xy 20.196302 -381.02921) (xy 20.117562 -381.02921) (xy 20.106274 -381.02982) (xy 20.085845 -381.039433)
			(xy 20.078192 -381.047752) (xy 20.059979 -381.069337) (xy 20.018268 -381.107409) (xy 19.971399 -381.138916)
			(xy 19.920397 -381.163168) (xy 19.866377 -381.179636) (xy 19.810519 -381.187959) (xy 19.782282 -381.188468)
			(xy 19.753023 -381.187894) (xy 19.695192 -381.178951) (xy 19.639402 -381.161291) (xy 19.586959 -381.135327)
			(xy 19.539089 -381.101669) (xy 19.517614 -381.081788) (xy 19.510502 -381.07493) (xy 19.492468 -381.067564)
			(xy 19.402044 -381.067564) (xy 19.38401 -381.07493) (xy 19.376898 -381.081788) (xy 19.355462 -381.101717)
			(xy 19.307591 -381.135391) (xy 19.25514 -381.16136) (xy 19.199338 -381.179014) (xy 19.141494 -381.187941)
			(xy 19.11223 -381.188468) (xy 19.08491 -381.188023) (xy 19.03083 -381.180225) (xy 18.978417 -381.164786)
			(xy 18.928746 -381.142022) (xy 18.882833 -381.112399) (xy 18.841621 -381.076524) (xy 18.823432 -381.056134)
			(xy 18.816066 -381.047752) (xy 18.796508 -381.038608) (xy 18.69821 -381.037592) (xy 18.678144 -381.046482)
			(xy 18.670778 -381.05461) (xy 18.652632 -381.074166) (xy 18.611793 -381.108492) (xy 18.566569 -381.136791)
			(xy 18.517842 -381.158512) (xy 18.466563 -381.17323) (xy 18.413734 -381.180659) (xy 18.38706 -381.181102)
			(xy 18.359807 -381.180659) (xy 18.305858 -381.172897) (xy 18.253562 -381.157537) (xy 18.203984 -381.134891)
			(xy 18.158134 -381.10542) (xy 18.116944 -381.069724) (xy 18.081253 -381.028529) (xy 18.051787 -380.982675)
			(xy 18.029147 -380.933095) (xy 18.013793 -380.880797) (xy 18.006037 -380.826847) (xy 18.005552 -380.799594)
			(xy 16.644405 -380.799594) (xy 16.636875 -380.851676) (xy 16.621374 -380.90418) (xy 16.598523 -380.953928)
			(xy 16.568792 -380.999896) (xy 16.551148 -381.020828) (xy 16.545052 -381.02794) (xy 16.538702 -381.044958)
			(xy 16.538702 -381.130302) (xy 16.545052 -381.14732) (xy 16.551148 -381.154432) (xy 16.568761 -381.175386)
			(xy 16.598478 -381.221352) (xy 16.62132 -381.271094) (xy 16.636817 -381.32359) (xy 16.644651 -381.377762)
			(xy 16.645128 -381.40513) (xy 16.644642 -381.432381) (xy 16.636886 -381.486329) (xy 16.621531 -381.538624)
			(xy 16.598889 -381.588201) (xy 16.569423 -381.634051) (xy 16.533732 -381.675242) (xy 16.492541 -381.710933)
			(xy 16.446691 -381.740399) (xy 16.397114 -381.763041) (xy 16.344819 -381.778396) (xy 16.290871 -381.786152)
			(xy 16.236369 -381.786152) (xy 16.182421 -381.778396) (xy 16.130126 -381.763041) (xy 16.080549 -381.740399)
			(xy 16.034699 -381.710933) (xy 15.993508 -381.675242) (xy 15.957817 -381.634051) (xy 15.928351 -381.588201)
			(xy 15.905709 -381.538624) (xy 15.890354 -381.486329) (xy 15.882598 -381.432381) (xy 15.882112 -381.40513)
			(xy 8.853424 -381.40513) (xy 10.950448 -383.502154) (xy 10.967714 -383.520241) (xy 10.995525 -383.561788)
			(xy 11.014696 -383.607962) (xy 11.02449 -383.656989) (xy 11.025124 -383.681986) (xy 11.025124 -390.219184)
			(xy 11.85037 -390.219184) (xy 11.85081 -390.192438) (xy 11.858264 -390.139468) (xy 11.873052 -390.088061)
			(xy 11.894882 -390.039227) (xy 11.923326 -389.993925) (xy 11.957825 -389.953045) (xy 11.997701 -389.91739)
			(xy 12.042171 -389.887662) (xy 12.090361 -389.864444) (xy 12.141324 -389.848192) (xy 12.167616 -389.843264)
			(xy 12.18184 -389.840724) (xy 12.202922 -389.822182) (xy 12.234672 -389.72236) (xy 12.237024 -389.713383)
			(xy 12.235976 -389.694873) (xy 12.228455 -389.677928) (xy 12.222226 -389.671052) (xy 12.122404 -389.571484)
			(xy 12.115292 -389.567674) (xy 12.092204 -389.555377) (xy 12.049365 -389.525356) (xy 12.01103 -389.489762)
			(xy 11.977921 -389.449263) (xy 11.950657 -389.404618) (xy 11.929751 -389.356666) (xy 11.915595 -389.306307)
			(xy 11.908455 -389.254486) (xy 11.908028 -389.22833) (xy 11.908537 -389.201097) (xy 11.916284 -389.147184)
			(xy 11.931625 -389.094923) (xy 11.954248 -389.045377) (xy 11.983691 -388.999555) (xy 12.019356 -388.95839)
			(xy 12.060517 -388.92272) (xy 12.106335 -388.893271) (xy 12.155878 -388.870642) (xy 12.208137 -388.855294)
			(xy 12.262049 -388.84754) (xy 12.289282 -388.847076) (xy 12.318746 -388.847076) (xy 12.348718 -388.847626)
			(xy 12.407931 -388.856942) (xy 12.464955 -388.875414) (xy 12.518383 -388.902589) (xy 12.566897 -388.937794)
			(xy 12.588494 -388.958582) (xy 14.521983 -390.89228) (xy 16.845547 -390.89228) (xy 16.849529 -390.839131)
			(xy 16.861389 -390.787169) (xy 16.880861 -390.737556) (xy 16.90751 -390.691398) (xy 16.940741 -390.649728)
			(xy 16.979811 -390.613476) (xy 17.023848 -390.583452) (xy 17.071868 -390.560327) (xy 17.122798 -390.544617)
			(xy 17.175501 -390.536674) (xy 17.20215 -390.536176) (xy 17.22851 -390.536672) (xy 17.280651 -390.544458)
			(xy 17.331072 -390.559853) (xy 17.37867 -390.582519) (xy 17.422403 -390.61196) (xy 17.44218 -390.629394)
			(xy 17.449292 -390.635744) (xy 17.467072 -390.642602) (xy 17.554448 -390.642602) (xy 17.572228 -390.635744)
			(xy 17.57934 -390.629394) (xy 17.599135 -390.611984) (xy 17.642872 -390.582557) (xy 17.690467 -390.559894)
			(xy 17.74088 -390.544488) (xy 17.793013 -390.536675) (xy 17.81937 -390.536176) (xy 17.84573 -390.53666)
			(xy 17.897872 -390.544449) (xy 17.948294 -390.559846) (xy 17.995891 -390.582515) (xy 18.039623 -390.611959)
			(xy 18.0594 -390.629394) (xy 18.066512 -390.635744) (xy 18.084292 -390.642602) (xy 18.171668 -390.642602)
			(xy 18.189448 -390.635744) (xy 18.19656 -390.629394) (xy 18.216347 -390.611974) (xy 18.260086 -390.582549)
			(xy 18.307683 -390.559888) (xy 18.358098 -390.544484) (xy 18.410232 -390.536674) (xy 18.43659 -390.536176)
			(xy 18.461586 -390.536601) (xy 18.511085 -390.543597) (xy 18.559123 -390.55744) (xy 18.604755 -390.577857)
			(xy 18.647087 -390.604449) (xy 18.66646 -390.62025) (xy 18.673572 -390.626346) (xy 18.690082 -390.632442)
			(xy 18.774156 -390.632442) (xy 18.790666 -390.626346) (xy 18.797778 -390.62025) (xy 18.817138 -390.604432)
			(xy 18.85947 -390.577833) (xy 18.905105 -390.557415) (xy 18.953146 -390.543578) (xy 19.002651 -390.536595)
			(xy 19.027648 -390.536176) (xy 19.053974 -390.536628) (xy 19.106051 -390.544396) (xy 19.156413 -390.559754)
			(xy 19.203962 -390.582368) (xy 19.247659 -390.611743) (xy 19.267424 -390.62914) (xy 19.277076 -390.637776)
			(xy 19.301714 -390.643872) (xy 19.408648 -390.616948) (xy 19.427444 -390.599676) (xy 19.431762 -390.587738)
			(xy 19.44086 -390.563228) (xy 19.464763 -390.516732) (xy 19.494791 -390.473936) (xy 19.530383 -390.435642)
			(xy 19.57087 -390.402567) (xy 19.615495 -390.37533) (xy 19.663421 -390.354442) (xy 19.71375 -390.340295)
			(xy 19.76554 -390.333153) (xy 19.79168 -390.332722) (xy 19.818936 -390.333124) (xy 19.872893 -390.340879)
			(xy 19.925198 -390.356234) (xy 19.974784 -390.378878) (xy 20.020644 -390.408347) (xy 20.061842 -390.444044)
			(xy 20.087094 -390.473184) (xy 20.905976 -390.473184) (xy 20.910047 -390.417562) (xy 20.922173 -390.363125)
			(xy 20.942096 -390.311034) (xy 20.969392 -390.262399) (xy 21.003478 -390.218256) (xy 21.043627 -390.179547)
			(xy 21.088985 -390.147096) (xy 21.138585 -390.121595) (xy 21.191369 -390.103588) (xy 21.246212 -390.093458)
			(xy 21.301946 -390.091421) (xy 21.357383 -390.097521) (xy 21.41134 -390.111627) (xy 21.462669 -390.133439)
			(xy 21.510275 -390.162493) (xy 21.553143 -390.198168) (xy 21.59036 -390.239705) (xy 21.621133 -390.286218)
			(xy 21.644805 -390.336715) (xy 21.660873 -390.390122) (xy 21.668993 -390.445298) (xy 21.669502 -390.473184)
			(xy 21.668993 -390.50107) (xy 21.660873 -390.556246) (xy 21.644805 -390.609653) (xy 21.621133 -390.66015)
			(xy 21.59036 -390.706663) (xy 21.553143 -390.7482) (xy 21.510275 -390.783875) (xy 21.462669 -390.812929)
			(xy 21.41134 -390.834741) (xy 21.357383 -390.848847) (xy 21.301946 -390.854947) (xy 21.246212 -390.85291)
			(xy 21.191369 -390.84278) (xy 21.138585 -390.824773) (xy 21.088985 -390.799272) (xy 21.043627 -390.766821)
			(xy 21.003478 -390.728112) (xy 20.969392 -390.683969) (xy 20.942096 -390.635334) (xy 20.922173 -390.583243)
			(xy 20.910047 -390.528806) (xy 20.905976 -390.473184) (xy 20.087094 -390.473184) (xy 20.097541 -390.48524)
			(xy 20.127013 -390.531098) (xy 20.149659 -390.580683) (xy 20.165017 -390.632987) (xy 20.172775 -390.686944)
			(xy 20.172775 -390.741456) (xy 20.165017 -390.795413) (xy 20.149659 -390.847717) (xy 20.127013 -390.897302)
			(xy 20.097541 -390.94316) (xy 20.061842 -390.984356) (xy 20.020644 -391.020053) (xy 19.974784 -391.049522)
			(xy 19.925198 -391.072166) (xy 19.872893 -391.087521) (xy 19.818936 -391.095276) (xy 19.79168 -391.095738)
			(xy 19.762096 -391.095179) (xy 19.703637 -391.086042) (xy 19.64729 -391.06799) (xy 19.594405 -391.041455)
			(xy 19.546251 -391.007075) (xy 19.524726 -390.986772) (xy 19.515582 -390.977882) (xy 19.491198 -390.97077)
			(xy 19.383248 -390.993884) (xy 19.363944 -391.010394) (xy 19.359118 -391.022332) (xy 19.348961 -391.046979)
			(xy 19.322322 -391.093153) (xy 19.289095 -391.134839) (xy 19.250024 -391.171104) (xy 19.205982 -391.201138)
			(xy 19.157955 -391.22427) (xy 19.107015 -391.239981) (xy 19.054302 -391.247922) (xy 19.027648 -391.248392)
			(xy 19.002653 -391.247952) (xy 18.953153 -391.240961) (xy 18.905116 -391.227122) (xy 18.859484 -391.206708)
			(xy 18.817151 -391.180118) (xy 18.797778 -391.164318) (xy 18.790666 -391.158222) (xy 18.774156 -391.152126)
			(xy 18.690082 -391.152126) (xy 18.673572 -391.158222) (xy 18.66646 -391.164318) (xy 18.647082 -391.180114)
			(xy 18.604756 -391.206717) (xy 18.559125 -391.22714) (xy 18.511088 -391.240982) (xy 18.461586 -391.247971)
			(xy 18.43659 -391.248392) (xy 18.410229 -391.247941) (xy 18.358085 -391.240145) (xy 18.307663 -391.22474)
			(xy 18.260065 -391.202064) (xy 18.216335 -391.172613) (xy 18.19656 -391.155174) (xy 18.189448 -391.148824)
			(xy 18.171668 -391.141966) (xy 18.084292 -391.141966) (xy 18.066512 -391.148824) (xy 18.0594 -391.155174)
			(xy 18.039599 -391.172577) (xy 17.995862 -391.202002) (xy 17.948269 -391.224666) (xy 17.897857 -391.240074)
			(xy 17.845726 -391.24789) (xy 17.81937 -391.248392) (xy 17.79301 -391.247893) (xy 17.740869 -391.240108)
			(xy 17.690447 -391.224715) (xy 17.642849 -391.202049) (xy 17.599117 -391.172608) (xy 17.57934 -391.155174)
			(xy 17.572228 -391.148824) (xy 17.554448 -391.141966) (xy 17.467072 -391.141966) (xy 17.449292 -391.148824)
			(xy 17.44218 -391.155174) (xy 17.422387 -391.172586) (xy 17.378648 -391.20201) (xy 17.331053 -391.224672)
			(xy 17.280639 -391.240078) (xy 17.228507 -391.247892) (xy 17.20215 -391.248392) (xy 17.175501 -391.247886)
			(xy 17.122798 -391.239943) (xy 17.071868 -391.224233) (xy 17.023848 -391.201108) (xy 16.979811 -391.171084)
			(xy 16.940741 -391.134832) (xy 16.90751 -391.093162) (xy 16.880861 -391.047004) (xy 16.861389 -390.997391)
			(xy 16.849529 -390.945429) (xy 16.845547 -390.89228) (xy 14.521983 -390.89228) (xy 14.939772 -391.310114)
			(xy 14.947186 -391.316936) (xy 14.965775 -391.324666) (xy 14.97584 -391.3251) (xy 16.482822 -391.3251)
			(xy 16.507765 -391.325497) (xy 16.557224 -391.332002) (xy 16.605414 -391.344898) (xy 16.628618 -391.354056)
			(xy 17.25676 -391.614152) (xy 17.27971 -391.62405) (xy 17.323031 -391.648978) (xy 17.362727 -391.679346)
			(xy 17.380712 -391.696702) (xy 17.445725 -391.761726) (xy 18.769076 -391.761726) (xy 18.769579 -391.734475)
			(xy 18.777332 -391.680526) (xy 18.792684 -391.62823) (xy 18.815323 -391.578651) (xy 18.844787 -391.532798)
			(xy 18.880476 -391.491606) (xy 18.921665 -391.455912) (xy 18.967514 -391.426443) (xy 19.01709 -391.403799)
			(xy 19.069385 -391.388441) (xy 19.123333 -391.380682) (xy 19.150584 -391.380218) (xy 19.176567 -391.380641)
			(xy 19.22805 -391.387704) (xy 19.278098 -391.401688) (xy 19.325786 -391.422335) (xy 19.370231 -391.449262)
			(xy 19.410611 -391.481971) (xy 19.428714 -391.500614) (xy 19.435826 -391.508234) (xy 19.454114 -391.516362)
			(xy 19.546824 -391.519156) (xy 19.56562 -391.51179) (xy 19.572986 -391.504678) (xy 19.594416 -391.48501)
			(xy 19.642122 -391.451735) (xy 19.694323 -391.42608) (xy 19.749811 -391.408639) (xy 19.807302 -391.399815)
			(xy 19.836384 -391.399268) (xy 19.863634 -391.399793) (xy 19.917579 -391.407547) (xy 19.969871 -391.422899)
			(xy 20.019447 -391.445536) (xy 20.065296 -391.474998) (xy 20.106486 -391.510686) (xy 20.142178 -391.551872)
			(xy 20.171645 -391.597718) (xy 20.194287 -391.647291) (xy 20.209645 -391.699582) (xy 20.215843 -391.742676)
			(xy 20.730716 -391.742676) (xy 20.734787 -391.687054) (xy 20.746913 -391.632617) (xy 20.766836 -391.580526)
			(xy 20.794132 -391.531891) (xy 20.828218 -391.487748) (xy 20.868367 -391.449039) (xy 20.913725 -391.416588)
			(xy 20.963325 -391.391087) (xy 21.016109 -391.37308) (xy 21.070952 -391.36295) (xy 21.126686 -391.360913)
			(xy 21.182123 -391.367013) (xy 21.23608 -391.381119) (xy 21.287409 -391.402931) (xy 21.335015 -391.431985)
			(xy 21.377883 -391.46766) (xy 21.4151 -391.509197) (xy 21.445873 -391.55571) (xy 21.469545 -391.606207)
			(xy 21.485613 -391.659614) (xy 21.493733 -391.71479) (xy 21.494242 -391.742676) (xy 21.493733 -391.770562)
			(xy 21.485613 -391.825738) (xy 21.469545 -391.879145) (xy 21.445873 -391.929642) (xy 21.4151 -391.976155)
			(xy 21.377883 -392.017692) (xy 21.335015 -392.053367) (xy 21.287409 -392.082421) (xy 21.23608 -392.104233)
			(xy 21.182123 -392.118339) (xy 21.126686 -392.124439) (xy 21.070952 -392.122402) (xy 21.016109 -392.112272)
			(xy 20.963325 -392.094265) (xy 20.913725 -392.068764) (xy 20.868367 -392.036313) (xy 20.828218 -391.997604)
			(xy 20.794132 -391.953461) (xy 20.766836 -391.904826) (xy 20.746913 -391.852735) (xy 20.734787 -391.798298)
			(xy 20.730716 -391.742676) (xy 20.215843 -391.742676) (xy 20.217404 -391.753526) (xy 20.217892 -391.780776)
			(xy 20.217454 -391.807389) (xy 20.210053 -391.860097) (xy 20.195392 -391.911264) (xy 20.173755 -391.959893)
			(xy 20.145564 -392.00504) (xy 20.111367 -392.045826) (xy 20.091908 -392.063986) (xy 20.081748 -392.07313)
			(xy 20.07362 -392.099038) (xy 20.098004 -392.212068) (xy 20.116292 -392.232134) (xy 20.1295 -392.236198)
			(xy 20.154903 -392.244743) (xy 20.203216 -392.267948) (xy 20.247807 -392.297683) (xy 20.2878 -392.333364)
			(xy 20.322409 -392.374289) (xy 20.350951 -392.419653) (xy 20.372867 -392.468564) (xy 20.387726 -392.52006)
			(xy 20.395234 -392.573128) (xy 20.395692 -392.599926) (xy 20.395246 -392.627179) (xy 20.387486 -392.681129)
			(xy 20.372127 -392.733425) (xy 20.349481 -392.783003) (xy 20.320011 -392.828855) (xy 20.284315 -392.870045)
			(xy 20.243121 -392.905736) (xy 20.197267 -392.935201) (xy 20.147686 -392.957841) (xy 20.095388 -392.973195)
			(xy 20.041437 -392.980949) (xy 20.014184 -392.981434) (xy 19.985268 -392.98088) (xy 19.928097 -392.972162)
			(xy 19.872898 -392.954913) (xy 19.820936 -392.929528) (xy 19.773401 -392.896589) (xy 19.731384 -392.856852)
			(xy 19.713194 -392.834368) (xy 19.705636 -392.825602) (xy 19.684874 -392.815422) (xy 19.673316 -392.81481)
			(xy 19.593052 -392.81481) (xy 19.581488 -392.815407) (xy 19.560716 -392.825583) (xy 19.553174 -392.834368)
			(xy 19.53499 -392.856857) (xy 19.492969 -392.896594) (xy 19.445433 -392.929533) (xy 19.393471 -392.954921)
			(xy 19.338272 -392.972175) (xy 19.281101 -392.980901) (xy 19.252184 -392.981434) (xy 19.224934 -392.980937)
			(xy 19.170988 -392.973179) (xy 19.118695 -392.957823) (xy 19.069119 -392.935182) (xy 19.02327 -392.905717)
			(xy 18.982081 -392.870026) (xy 18.946389 -392.828838) (xy 18.916923 -392.78299) (xy 18.89428 -392.733415)
			(xy 18.878923 -392.681122) (xy 18.871164 -392.627176) (xy 18.870676 -392.599926) (xy 18.871129 -392.574237)
			(xy 18.878021 -392.523325) (xy 18.891684 -392.473798) (xy 18.91187 -392.426553) (xy 18.938215 -392.382444)
			(xy 18.970241 -392.342271) (xy 19.007369 -392.306759) (xy 19.027902 -392.291316) (xy 19.039078 -392.283188)
			(xy 19.050254 -392.257788) (xy 19.036284 -392.142218) (xy 19.01952 -392.12012) (xy 19.006566 -392.11504)
			(xy 18.980604 -392.103918) (xy 18.932023 -392.07511) (xy 18.888218 -392.039457) (xy 18.850147 -391.997737)
			(xy 18.81864 -391.950861) (xy 18.794387 -391.899854) (xy 18.777916 -391.845829) (xy 18.769588 -391.789966)
			(xy 18.769076 -391.761726) (xy 17.445725 -391.761726) (xy 18.82267 -393.138914) (xy 18.830085 -393.145735)
			(xy 18.848673 -393.153465) (xy 18.858738 -393.1539) (xy 20.735798 -393.1539) (xy 20.745871 -393.1535)
			(xy 20.76447 -393.145765) (xy 20.771866 -393.138914) (xy 22.118828 -391.791952) (xy 22.125529 -391.784476)
			(xy 22.133115 -391.765913) (xy 22.13356 -391.755884) (xy 22.13356 -390.386824) (xy 22.133215 -390.376776)
			(xy 22.12561 -390.35818) (xy 22.118828 -390.350756) (xy 21.735796 -389.967724) (xy 21.728311 -389.961036)
			(xy 21.709754 -389.953444) (xy 21.699728 -389.952992) (xy 21.284184 -389.952992) (xy 21.256932 -389.952537)
			(xy 21.202984 -389.944778) (xy 21.150689 -389.929421) (xy 21.101112 -389.906778) (xy 21.055261 -389.87731)
			(xy 21.014071 -389.841617) (xy 20.97838 -389.800426) (xy 20.948914 -389.754574) (xy 20.926273 -389.704996)
			(xy 20.910918 -389.6527) (xy 20.903162 -389.598752) (xy 20.903162 -389.544248) (xy 20.910918 -389.4903)
			(xy 20.926273 -389.438004) (xy 20.948914 -389.388426) (xy 20.97838 -389.342574) (xy 21.014071 -389.301383)
			(xy 21.055261 -389.26569) (xy 21.101112 -389.236222) (xy 21.150689 -389.213579) (xy 21.202984 -389.198222)
			(xy 21.256932 -389.190463) (xy 21.284184 -389.189976) (xy 21.878798 -389.189976) (xy 21.908776 -389.190563)
			(xy 21.967991 -389.199953) (xy 22.02501 -389.218489) (xy 22.078428 -389.245712) (xy 22.126932 -389.280955)
			(xy 22.148546 -389.301736) (xy 22.784816 -389.938006) (xy 22.805644 -389.959579) (xy 22.840894 -390.008088)
			(xy 22.868119 -390.061516) (xy 22.886647 -390.118545) (xy 22.896022 -390.177772) (xy 22.896576 -390.207754)
			(xy 22.896576 -390.8923) (xy 25.924276 -390.8923) (xy 25.928259 -390.839151) (xy 25.940119 -390.787188)
			(xy 25.95959 -390.737574) (xy 25.986238 -390.691416) (xy 26.019467 -390.649744) (xy 26.058536 -390.613491)
			(xy 26.102572 -390.583464) (xy 26.150591 -390.560336) (xy 26.20152 -390.544623) (xy 26.254223 -390.536676)
			(xy 26.280872 -390.536176) (xy 26.307232 -390.536658) (xy 26.359374 -390.544448) (xy 26.409796 -390.559846)
			(xy 26.457393 -390.582515) (xy 26.501125 -390.611959) (xy 26.520902 -390.629394) (xy 26.528014 -390.635744)
			(xy 26.545794 -390.642602) (xy 26.63317 -390.642602) (xy 26.65095 -390.635744) (xy 26.658062 -390.629394)
			(xy 26.677848 -390.611973) (xy 26.721588 -390.582548) (xy 26.769185 -390.559887) (xy 26.8196 -390.544484)
			(xy 26.871734 -390.536674) (xy 26.898092 -390.536176) (xy 26.924453 -390.536646) (xy 26.976595 -390.544439)
			(xy 27.027017 -390.55984) (xy 27.074614 -390.582511) (xy 27.118346 -390.611958) (xy 27.138122 -390.629394)
			(xy 27.145234 -390.635744) (xy 27.163014 -390.642602) (xy 27.25039 -390.642602) (xy 27.26817 -390.635744)
			(xy 27.275282 -390.629394) (xy 27.29506 -390.611964) (xy 27.338802 -390.58254) (xy 27.386401 -390.559881)
			(xy 27.436818 -390.54448) (xy 27.488954 -390.536672) (xy 27.515312 -390.536176) (xy 27.540308 -390.536589)
			(xy 27.589808 -390.543588) (xy 27.637846 -390.557433) (xy 27.683478 -390.577853) (xy 27.72581 -390.604448)
			(xy 27.745182 -390.62025) (xy 27.752294 -390.626346) (xy 27.768804 -390.632442) (xy 27.852878 -390.632442)
			(xy 27.869388 -390.626346) (xy 27.8765 -390.62025) (xy 27.895852 -390.604422) (xy 27.938186 -390.577825)
			(xy 27.983823 -390.557409) (xy 28.031866 -390.543574) (xy 28.081372 -390.536593) (xy 28.10637 -390.536176)
			(xy 28.133805 -390.53668) (xy 28.188024 -390.545101) (xy 28.21432 -390.55294) (xy 28.22575 -390.556496)
			(xy 28.24861 -390.553194) (xy 28.334462 -390.49452) (xy 28.345892 -390.4742) (xy 28.346654 -390.462516)
			(xy 28.348971 -390.433797) (xy 28.361097 -390.377473) (xy 28.381556 -390.323614) (xy 28.409882 -390.273444)
			(xy 28.445432 -390.228105) (xy 28.487397 -390.188628) (xy 28.534821 -390.155912) (xy 28.586626 -390.130701)
			(xy 28.641634 -390.113568) (xy 28.698593 -390.104903) (xy 28.7274 -390.104376) (xy 28.75465 -390.104894)
			(xy 28.808595 -390.11265) (xy 28.860888 -390.128005) (xy 28.910463 -390.150645) (xy 28.956311 -390.18011)
			(xy 28.9975 -390.2158) (xy 29.03319 -390.256989) (xy 29.062655 -390.302837) (xy 29.085295 -390.352412)
			(xy 29.10065 -390.404705) (xy 29.108406 -390.45865) (xy 29.108406 -390.51315) (xy 29.10065 -390.567095)
			(xy 29.085295 -390.619388) (xy 29.062655 -390.668963) (xy 29.03319 -390.714811) (xy 28.9975 -390.756)
			(xy 28.956311 -390.79169) (xy 28.910463 -390.821155) (xy 28.860888 -390.843795) (xy 28.808595 -390.85915)
			(xy 28.75465 -390.866906) (xy 28.7274 -390.867392) (xy 28.693996 -390.866697) (xy 28.628208 -390.855075)
			(xy 28.59659 -390.844278) (xy 28.585414 -390.840214) (xy 28.5623 -390.8425) (xy 28.474162 -390.897618)
			(xy 28.461716 -390.91743) (xy 28.460446 -390.929114) (xy 28.457324 -390.955063) (xy 28.444379 -391.0057)
			(xy 28.424171 -391.053902) (xy 28.397134 -391.098631) (xy 28.36385 -391.138928) (xy 28.325032 -391.173926)
			(xy 28.281516 -391.202875) (xy 28.234235 -391.225151) (xy 28.184206 -391.240277) (xy 28.132503 -391.247927)
			(xy 28.10637 -391.248392) (xy 28.081375 -391.24794) (xy 28.031876 -391.240951) (xy 27.983839 -391.227115)
			(xy 27.938206 -391.206704) (xy 27.895873 -391.180117) (xy 27.8765 -391.164318) (xy 27.869388 -391.158222)
			(xy 27.852878 -391.152126) (xy 27.768804 -391.152126) (xy 27.752294 -391.158222) (xy 27.745182 -391.164318)
			(xy 27.725796 -391.180103) (xy 27.683472 -391.206708) (xy 27.637844 -391.227133) (xy 27.589808 -391.240977)
			(xy 27.540308 -391.247969) (xy 27.515312 -391.248392) (xy 27.488951 -391.247927) (xy 27.436808 -391.240135)
			(xy 27.386386 -391.224733) (xy 27.338788 -391.20206) (xy 27.295058 -391.172611) (xy 27.275282 -391.155174)
			(xy 27.26817 -391.148824) (xy 27.25039 -391.141966) (xy 27.163014 -391.141966) (xy 27.145234 -391.148824)
			(xy 27.138122 -391.155174) (xy 27.118352 -391.172614) (xy 27.074607 -391.202033) (xy 27.027006 -391.22469)
			(xy 26.976587 -391.24009) (xy 26.924451 -391.247896) (xy 26.898092 -391.248392) (xy 26.871731 -391.247939)
			(xy 26.819587 -391.240144) (xy 26.769165 -391.22474) (xy 26.721567 -391.202064) (xy 26.677837 -391.172612)
			(xy 26.658062 -391.155174) (xy 26.65095 -391.148824) (xy 26.63317 -391.141966) (xy 26.545794 -391.141966)
			(xy 26.528014 -391.148824) (xy 26.520902 -391.155174) (xy 26.50114 -391.172623) (xy 26.457393 -391.202042)
			(xy 26.40979 -391.224696) (xy 26.359369 -391.240094) (xy 26.307231 -391.247897) (xy 26.280872 -391.248392)
			(xy 26.254223 -391.247924) (xy 26.20152 -391.239977) (xy 26.150591 -391.224264) (xy 26.102572 -391.201136)
			(xy 26.058536 -391.171109) (xy 26.019467 -391.134856) (xy 25.986238 -391.093184) (xy 25.95959 -391.047026)
			(xy 25.940119 -390.997412) (xy 25.928259 -390.945449) (xy 25.924276 -390.8923) (xy 22.896576 -390.8923)
			(xy 22.896576 -391.812526) (xy 27.862276 -391.812526) (xy 27.862779 -391.785275) (xy 27.870532 -391.731326)
			(xy 27.885884 -391.67903) (xy 27.908523 -391.629451) (xy 27.937987 -391.583598) (xy 27.973676 -391.542406)
			(xy 28.014865 -391.506712) (xy 28.060714 -391.477243) (xy 28.11029 -391.454599) (xy 28.162585 -391.439241)
			(xy 28.216533 -391.431482) (xy 28.243784 -391.431018) (xy 28.273907 -391.431608) (xy 28.333402 -391.441086)
			(xy 28.390669 -391.459793) (xy 28.444286 -391.487264) (xy 28.492922 -391.522818) (xy 28.514548 -391.543794)
			(xy 28.522422 -391.551668) (xy 28.542234 -391.559288) (xy 28.640024 -391.554208) (xy 28.659074 -391.544302)
			(xy 28.665932 -391.535666) (xy 28.68415 -391.513789) (xy 28.725992 -391.475185) (xy 28.773102 -391.443223)
			(xy 28.824436 -391.41861) (xy 28.878856 -391.401893) (xy 28.935155 -391.393442) (xy 28.96362 -391.392918)
			(xy 28.990875 -391.393336) (xy 29.044828 -391.401097) (xy 29.097129 -391.416457) (xy 29.146711 -391.439103)
			(xy 29.192565 -391.468576) (xy 29.233758 -391.504274) (xy 29.269452 -391.545472) (xy 29.298919 -391.59133)
			(xy 29.321559 -391.640914) (xy 29.336913 -391.693217) (xy 29.344667 -391.747171) (xy 29.345128 -391.774426)
			(xy 29.344717 -391.800035) (xy 29.337855 -391.850792) (xy 29.324271 -391.900177) (xy 29.304209 -391.947303)
			(xy 29.278029 -391.991325) (xy 29.246201 -392.031453) (xy 29.228034 -392.049508) (xy 29.218636 -392.058398)
			(xy 29.211016 -392.082782) (xy 29.231082 -392.191494) (xy 29.247084 -392.211306) (xy 29.259022 -392.216386)
			(xy 29.284595 -392.227703) (xy 29.332418 -392.256689) (xy 29.375495 -392.292347) (xy 29.412903 -392.333914)
			(xy 29.443839 -392.380499) (xy 29.46764 -392.431103) (xy 29.483795 -392.484639) (xy 29.491959 -392.539961)
			(xy 29.492448 -392.567922) (xy 29.491943 -392.595172) (xy 29.484184 -392.649117) (xy 29.468828 -392.701409)
			(xy 29.446188 -392.750983) (xy 29.416723 -392.796832) (xy 29.381034 -392.838021) (xy 29.339846 -392.873712)
			(xy 29.293999 -392.903179) (xy 29.244426 -392.925822) (xy 29.192135 -392.94118) (xy 29.13819 -392.948942)
			(xy 29.11094 -392.94943) (xy 29.080673 -392.948837) (xy 29.0209 -392.939271) (xy 28.963386 -392.920389)
			(xy 28.909575 -392.892664) (xy 28.860815 -392.856792) (xy 28.83916 -392.835638) (xy 28.832048 -392.828272)
			(xy 28.813506 -392.820652) (xy 28.720288 -392.820652) (xy 28.701746 -392.828272) (xy 28.694634 -392.835638)
			(xy 28.672998 -392.856814) (xy 28.624238 -392.892693) (xy 28.570422 -392.92042) (xy 28.512903 -392.939298)
			(xy 28.453123 -392.948853) (xy 28.422854 -392.94943) (xy 28.395603 -392.948965) (xy 28.341655 -392.941203)
			(xy 28.289362 -392.925843) (xy 28.239786 -392.903198) (xy 28.193936 -392.873729) (xy 28.152747 -392.838036)
			(xy 28.117057 -392.796844) (xy 28.08759 -392.750993) (xy 28.064949 -392.701416) (xy 28.049592 -392.649121)
			(xy 28.041833 -392.595173) (xy 28.041346 -392.567922) (xy 28.041819 -392.541189) (xy 28.049324 -392.488253)
			(xy 28.064134 -392.436879) (xy 28.085961 -392.38807) (xy 28.114378 -392.342781) (xy 28.131262 -392.32205)
			(xy 28.138882 -392.312652) (xy 28.14447 -392.289284) (xy 28.120086 -392.186414) (xy 28.104592 -392.167872)
			(xy 28.093416 -392.1633) (xy 28.068068 -392.151839) (xy 28.020679 -392.122711) (xy 27.978019 -392.087013)
			(xy 27.940992 -392.045501) (xy 27.910382 -391.999054) (xy 27.886838 -391.948656) (xy 27.870858 -391.895375)
			(xy 27.862781 -391.840339) (xy 27.862276 -391.812526) (xy 22.896576 -391.812526) (xy 22.896576 -391.934954)
			(xy 22.895947 -391.96493) (xy 22.886564 -392.024143) (xy 22.868038 -392.08116) (xy 22.840824 -392.134579)
			(xy 22.805592 -392.183086) (xy 22.784816 -392.204702) (xy 21.50745 -393.482068) (xy 23.315166 -393.482068)
			(xy 23.319237 -393.426446) (xy 23.331363 -393.372009) (xy 23.351286 -393.319918) (xy 23.378582 -393.271283)
			(xy 23.412668 -393.22714) (xy 23.452817 -393.188431) (xy 23.498175 -393.15598) (xy 23.547775 -393.130479)
			(xy 23.600559 -393.112472) (xy 23.655402 -393.102342) (xy 23.711136 -393.100305) (xy 23.766573 -393.106405)
			(xy 23.82053 -393.120511) (xy 23.871859 -393.142323) (xy 23.919465 -393.171377) (xy 23.962333 -393.207052)
			(xy 23.99955 -393.248589) (xy 24.030323 -393.295102) (xy 24.053995 -393.345599) (xy 24.070063 -393.399006)
			(xy 24.078183 -393.454182) (xy 24.078692 -393.482068) (xy 24.078183 -393.509954) (xy 24.070063 -393.56513)
			(xy 24.053995 -393.618537) (xy 24.030323 -393.669034) (xy 23.99955 -393.715547) (xy 23.962333 -393.757084)
			(xy 23.919465 -393.792759) (xy 23.871859 -393.821813) (xy 23.82053 -393.843625) (xy 23.766573 -393.857731)
			(xy 23.711136 -393.863831) (xy 23.655402 -393.861794) (xy 23.600559 -393.851664) (xy 23.547775 -393.833657)
			(xy 23.498175 -393.808156) (xy 23.452817 -393.775705) (xy 23.412668 -393.736996) (xy 23.378582 -393.692853)
			(xy 23.351286 -393.644218) (xy 23.331363 -393.592127) (xy 23.319237 -393.53769) (xy 23.315166 -393.482068)
			(xy 21.50745 -393.482068) (xy 21.184616 -393.804902) (xy 21.163016 -393.825683) (xy 21.114491 -393.860866)
			(xy 21.061062 -393.888029) (xy 21.004043 -393.906505) (xy 20.944837 -393.915839) (xy 20.914868 -393.916408)
			(xy 18.679668 -393.916408) (xy 18.649697 -393.915854) (xy 18.590483 -393.90654) (xy 18.533459 -393.888068)
			(xy 18.48003 -393.860895) (xy 18.431517 -393.82569) (xy 18.40992 -393.804902) (xy 16.902176 -392.296904)
			(xy 16.898538 -392.293496) (xy 16.890228 -392.287992) (xy 16.885666 -392.285982) (xy 16.416274 -392.091672)
			(xy 16.411667 -392.089806) (xy 16.401939 -392.087764) (xy 16.39697 -392.087608) (xy 14.79677 -392.087608)
			(xy 14.766799 -392.087052) (xy 14.707585 -392.077739) (xy 14.650561 -392.059268) (xy 14.597133 -392.032095)
			(xy 14.548619 -391.99689) (xy 14.527022 -391.976102) (xy 12.78001 -390.228836) (xy 12.773176 -390.222536)
			(xy 12.756218 -390.214956) (xy 12.73767 -390.213941) (xy 12.728702 -390.21639) (xy 12.62888 -390.24814)
			(xy 12.610338 -390.269222) (xy 12.607798 -390.283446) (xy 12.602819 -390.309723) (xy 12.586548 -390.360669)
			(xy 12.56332 -390.408842) (xy 12.533589 -390.453298) (xy 12.497939 -390.493164) (xy 12.45707 -390.527659)
			(xy 12.411782 -390.556106) (xy 12.362964 -390.577947) (xy 12.311573 -390.592754) (xy 12.258618 -390.600236)
			(xy 12.231878 -390.600692) (xy 12.204625 -390.600243) (xy 12.150676 -390.592483) (xy 12.098379 -390.577124)
			(xy 12.048801 -390.554479) (xy 12.00295 -390.525009) (xy 11.961759 -390.489314) (xy 11.926068 -390.44812)
			(xy 11.896603 -390.402266) (xy 11.873963 -390.352685) (xy 11.858609 -390.300387) (xy 11.850855 -390.246437)
			(xy 11.85037 -390.219184) (xy 11.025124 -390.219184) (xy 11.025124 -392.674094) (xy 11.892278 -392.674094)
			(xy 11.896349 -392.618472) (xy 11.908475 -392.564035) (xy 11.928398 -392.511944) (xy 11.955694 -392.463309)
			(xy 11.98978 -392.419166) (xy 12.029929 -392.380457) (xy 12.075287 -392.348006) (xy 12.124887 -392.322505)
			(xy 12.177671 -392.304498) (xy 12.232514 -392.294368) (xy 12.288248 -392.292331) (xy 12.343685 -392.298431)
			(xy 12.397642 -392.312537) (xy 12.448971 -392.334349) (xy 12.496577 -392.363403) (xy 12.539445 -392.399078)
			(xy 12.576662 -392.440615) (xy 12.607435 -392.487128) (xy 12.631107 -392.537625) (xy 12.647175 -392.591032)
			(xy 12.655295 -392.646208) (xy 12.655804 -392.674094) (xy 12.655295 -392.70198) (xy 12.647175 -392.757156)
			(xy 12.631107 -392.810563) (xy 12.607435 -392.86106) (xy 12.576662 -392.907573) (xy 12.539445 -392.94911)
			(xy 12.496577 -392.984785) (xy 12.448971 -393.013839) (xy 12.397642 -393.035651) (xy 12.343685 -393.049757)
			(xy 12.288248 -393.055857) (xy 12.232514 -393.05382) (xy 12.177671 -393.04369) (xy 12.124887 -393.025683)
			(xy 12.075287 -393.000182) (xy 12.029929 -392.967731) (xy 11.98978 -392.929022) (xy 11.955694 -392.884879)
			(xy 11.928398 -392.836244) (xy 11.908475 -392.784153) (xy 11.896349 -392.729716) (xy 11.892278 -392.674094)
			(xy 11.025124 -392.674094) (xy 11.025124 -394.028676) (xy 12.113766 -394.028676) (xy 12.117837 -393.973054)
			(xy 12.129963 -393.918617) (xy 12.149886 -393.866526) (xy 12.177182 -393.817891) (xy 12.211268 -393.773748)
			(xy 12.251417 -393.735039) (xy 12.296775 -393.702588) (xy 12.346375 -393.677087) (xy 12.399159 -393.65908)
			(xy 12.454002 -393.64895) (xy 12.509736 -393.646913) (xy 12.565173 -393.653013) (xy 12.61913 -393.667119)
			(xy 12.670459 -393.688931) (xy 12.718065 -393.717985) (xy 12.760933 -393.75366) (xy 12.79815 -393.795197)
			(xy 12.828923 -393.84171) (xy 12.852595 -393.892207) (xy 12.868663 -393.945614) (xy 12.876783 -394.00079)
			(xy 12.877292 -394.028676) (xy 12.877028 -394.043154) (xy 13.681962 -394.043154) (xy 13.686033 -393.987532)
			(xy 13.698159 -393.933095) (xy 13.718082 -393.881004) (xy 13.745378 -393.832369) (xy 13.779464 -393.788226)
			(xy 13.819613 -393.749517) (xy 13.864971 -393.717066) (xy 13.914571 -393.691565) (xy 13.967355 -393.673558)
			(xy 14.022198 -393.663428) (xy 14.077932 -393.661391) (xy 14.133369 -393.667491) (xy 14.187326 -393.681597)
			(xy 14.238655 -393.703409) (xy 14.286261 -393.732463) (xy 14.329129 -393.768138) (xy 14.366346 -393.809675)
			(xy 14.397119 -393.856188) (xy 14.420791 -393.906685) (xy 14.436859 -393.960092) (xy 14.444979 -394.015268)
			(xy 14.445488 -394.043154) (xy 14.444979 -394.07104) (xy 14.436859 -394.126216) (xy 14.420791 -394.179623)
			(xy 14.397119 -394.23012) (xy 14.366346 -394.276633) (xy 14.329129 -394.31817) (xy 14.286261 -394.353845)
			(xy 14.238655 -394.382899) (xy 14.187326 -394.404711) (xy 14.133369 -394.418817) (xy 14.077932 -394.424917)
			(xy 14.022198 -394.42288) (xy 13.967355 -394.41275) (xy 13.914571 -394.394743) (xy 13.864971 -394.369242)
			(xy 13.819613 -394.336791) (xy 13.779464 -394.298082) (xy 13.745378 -394.253939) (xy 13.718082 -394.205304)
			(xy 13.698159 -394.153213) (xy 13.686033 -394.098776) (xy 13.681962 -394.043154) (xy 12.877028 -394.043154)
			(xy 12.876783 -394.056562) (xy 12.868663 -394.111738) (xy 12.852595 -394.165145) (xy 12.828923 -394.215642)
			(xy 12.79815 -394.262155) (xy 12.760933 -394.303692) (xy 12.718065 -394.339367) (xy 12.670459 -394.368421)
			(xy 12.61913 -394.390233) (xy 12.565173 -394.404339) (xy 12.509736 -394.410439) (xy 12.454002 -394.408402)
			(xy 12.399159 -394.398272) (xy 12.346375 -394.380265) (xy 12.296775 -394.354764) (xy 12.251417 -394.322313)
			(xy 12.211268 -394.283604) (xy 12.177182 -394.239461) (xy 12.149886 -394.190826) (xy 12.129963 -394.138735)
			(xy 12.117837 -394.084298) (xy 12.113766 -394.028676) (xy 11.025124 -394.028676) (xy 11.025124 -394.962888)
			(xy 12.04036 -394.962888) (xy 12.044431 -394.907266) (xy 12.056557 -394.852829) (xy 12.07648 -394.800738)
			(xy 12.103776 -394.752103) (xy 12.137862 -394.70796) (xy 12.178011 -394.669251) (xy 12.223369 -394.6368)
			(xy 12.272969 -394.611299) (xy 12.325753 -394.593292) (xy 12.380596 -394.583162) (xy 12.43633 -394.581125)
			(xy 12.491767 -394.587225) (xy 12.545724 -394.601331) (xy 12.597053 -394.623143) (xy 12.644659 -394.652197)
			(xy 12.687527 -394.687872) (xy 12.724744 -394.729409) (xy 12.755517 -394.775922) (xy 12.779189 -394.826419)
			(xy 12.795257 -394.879826) (xy 12.803377 -394.935002) (xy 12.803886 -394.962888) (xy 12.803377 -394.990774)
			(xy 12.795257 -395.04595) (xy 12.779189 -395.099357) (xy 12.755517 -395.149854) (xy 12.724744 -395.196367)
			(xy 12.687527 -395.237904) (xy 12.644659 -395.273579) (xy 12.597053 -395.302633) (xy 12.545724 -395.324445)
			(xy 12.491767 -395.338551) (xy 12.43633 -395.344651) (xy 12.380596 -395.342614) (xy 12.325753 -395.332484)
			(xy 12.272969 -395.314477) (xy 12.223369 -395.288976) (xy 12.178011 -395.256525) (xy 12.137862 -395.217816)
			(xy 12.103776 -395.173673) (xy 12.07648 -395.125038) (xy 12.056557 -395.072947) (xy 12.044431 -395.01851)
			(xy 12.04036 -394.962888) (xy 11.025124 -394.962888) (xy 11.025124 -396.06093) (xy 12.002514 -396.06093)
			(xy 12.006585 -396.005308) (xy 12.018711 -395.950871) (xy 12.038634 -395.89878) (xy 12.06593 -395.850145)
			(xy 12.100016 -395.806002) (xy 12.140165 -395.767293) (xy 12.185523 -395.734842) (xy 12.235123 -395.709341)
			(xy 12.287907 -395.691334) (xy 12.34275 -395.681204) (xy 12.398484 -395.679167) (xy 12.453921 -395.685267)
			(xy 12.507878 -395.699373) (xy 12.559207 -395.721185) (xy 12.606813 -395.750239) (xy 12.649681 -395.785914)
			(xy 12.686898 -395.827451) (xy 12.717671 -395.873964) (xy 12.741343 -395.924461) (xy 12.757411 -395.977868)
			(xy 12.765531 -396.033044) (xy 12.76604 -396.06093) (xy 12.765531 -396.088816) (xy 12.757411 -396.143992)
			(xy 12.741343 -396.197399) (xy 12.717671 -396.247896) (xy 12.686898 -396.294409) (xy 12.649681 -396.335946)
			(xy 12.606813 -396.371621) (xy 12.559207 -396.400675) (xy 12.507878 -396.422487) (xy 12.453921 -396.436593)
			(xy 12.398484 -396.442693) (xy 12.34275 -396.440656) (xy 12.287907 -396.430526) (xy 12.235123 -396.412519)
			(xy 12.185523 -396.387018) (xy 12.140165 -396.354567) (xy 12.100016 -396.315858) (xy 12.06593 -396.271715)
			(xy 12.038634 -396.22308) (xy 12.018711 -396.170989) (xy 12.006585 -396.116552) (xy 12.002514 -396.06093)
			(xy 11.025124 -396.06093) (xy 11.025124 -398.934686) (xy 11.025468 -398.944734) (xy 11.033074 -398.96333)
			(xy 11.039856 -398.970754) (xy 13.495345 -401.426243) (xy 19.533319 -401.426243) (xy 19.533319 -401.371737)
			(xy 19.541076 -401.317787) (xy 19.556432 -401.265489) (xy 19.579075 -401.21591) (xy 19.608543 -401.170057)
			(xy 19.644236 -401.128865) (xy 19.685428 -401.093171) (xy 19.731281 -401.063704) (xy 19.780861 -401.041062)
			(xy 19.833159 -401.025706) (xy 19.887109 -401.017949) (xy 19.914362 -401.017486) (xy 19.944485 -401.018071)
			(xy 20.003981 -401.027547) (xy 20.061249 -401.046254) (xy 20.114867 -401.073727) (xy 20.163501 -401.109284)
			(xy 20.185126 -401.130262) (xy 20.192238 -401.137628) (xy 20.211034 -401.145248) (xy 20.30349 -401.145248)
			(xy 20.322286 -401.137628) (xy 20.329398 -401.130262) (xy 20.351011 -401.109268) (xy 20.399642 -401.073699)
			(xy 20.453261 -401.046221) (xy 20.510534 -401.027516) (xy 20.570037 -401.018051) (xy 20.600162 -401.017486)
			(xy 20.627531 -401.017978) (xy 20.681709 -401.02579) (xy 20.734212 -401.041273) (xy 20.783959 -401.064109)
			(xy 20.829927 -401.093828) (xy 20.85086 -401.111466) (xy 20.857972 -401.117562) (xy 20.87499 -401.123912)
			(xy 20.960334 -401.123912) (xy 20.977352 -401.117562) (xy 20.984464 -401.111466) (xy 21.005394 -401.093825)
			(xy 21.051368 -401.064115) (xy 21.101116 -401.04128) (xy 21.153617 -401.025789) (xy 21.207793 -401.01796)
			(xy 21.235162 -401.017486) (xy 21.262416 -401.017959) (xy 21.31637 -401.025711) (xy 21.368672 -401.041064)
			(xy 21.418256 -401.063704) (xy 21.464113 -401.09317) (xy 21.50531 -401.128863) (xy 21.541007 -401.170056)
			(xy 21.570478 -401.215911) (xy 21.593123 -401.265492) (xy 21.608481 -401.317792) (xy 21.616239 -401.371746)
			(xy 21.616239 -401.426254) (xy 21.608481 -401.480208) (xy 21.593123 -401.532508) (xy 21.570478 -401.582089)
			(xy 21.541007 -401.627944) (xy 21.50531 -401.669137) (xy 21.464113 -401.70483) (xy 21.418256 -401.734296)
			(xy 21.368672 -401.756936) (xy 21.31637 -401.772289) (xy 21.262416 -401.780041) (xy 21.235162 -401.780502)
			(xy 21.207793 -401.779999) (xy 21.153616 -401.77219) (xy 21.101113 -401.75671) (xy 21.051365 -401.733876)
			(xy 21.005397 -401.704159) (xy 20.984464 -401.686522) (xy 20.977352 -401.680426) (xy 20.960334 -401.674076)
			(xy 20.87499 -401.674076) (xy 20.857972 -401.680426) (xy 20.85086 -401.686522) (xy 20.829919 -401.70415)
			(xy 20.783948 -401.733863) (xy 20.734203 -401.7567) (xy 20.681704 -401.772194) (xy 20.62753 -401.780026)
			(xy 20.600162 -401.780502) (xy 20.570039 -401.779906) (xy 20.510544 -401.770433) (xy 20.453275 -401.751729)
			(xy 20.399658 -401.724258) (xy 20.351023 -401.688703) (xy 20.329398 -401.667726) (xy 20.322286 -401.66036)
			(xy 20.30349 -401.65274) (xy 20.211034 -401.65274) (xy 20.192238 -401.66036) (xy 20.185126 -401.667726)
			(xy 20.1635 -401.688706) (xy 20.114873 -401.724277) (xy 20.061257 -401.751758) (xy 20.003986 -401.770466)
			(xy 19.944486 -401.779935) (xy 19.914362 -401.780502) (xy 19.887109 -401.780031) (xy 19.833159 -401.772274)
			(xy 19.780861 -401.756918) (xy 19.731281 -401.734276) (xy 19.685428 -401.704809) (xy 19.644236 -401.669115)
			(xy 19.608543 -401.627923) (xy 19.579075 -401.58207) (xy 19.556432 -401.532491) (xy 19.541076 -401.480193)
			(xy 19.533319 -401.426243) (xy 13.495345 -401.426243) (xy 14.092682 -402.02358) (xy 14.109914 -402.041681)
			(xy 14.137652 -402.083244) (xy 14.156757 -402.129417) (xy 14.166494 -402.178427) (xy 14.167104 -402.203412)
			(xy 14.167104 -403.220174) (xy 14.510764 -403.220174) (xy 14.514835 -403.164552) (xy 14.526961 -403.110115)
			(xy 14.546884 -403.058024) (xy 14.57418 -403.009389) (xy 14.608266 -402.965246) (xy 14.648415 -402.926537)
			(xy 14.693773 -402.894086) (xy 14.743373 -402.868585) (xy 14.796157 -402.850578) (xy 14.851 -402.840448)
			(xy 14.906734 -402.838411) (xy 14.962171 -402.844511) (xy 15.016128 -402.858617) (xy 15.067457 -402.880429)
			(xy 15.115063 -402.909483) (xy 15.157931 -402.945158) (xy 15.195148 -402.986695) (xy 15.225921 -403.033208)
			(xy 15.249593 -403.083705) (xy 15.265661 -403.137112) (xy 15.273781 -403.192288) (xy 15.27429 -403.220174)
			(xy 15.780764 -403.220174) (xy 15.784835 -403.164552) (xy 15.796961 -403.110115) (xy 15.816884 -403.058024)
			(xy 15.84418 -403.009389) (xy 15.878266 -402.965246) (xy 15.918415 -402.926537) (xy 15.963773 -402.894086)
			(xy 16.013373 -402.868585) (xy 16.066157 -402.850578) (xy 16.121 -402.840448) (xy 16.176734 -402.838411)
			(xy 16.232171 -402.844511) (xy 16.286128 -402.858617) (xy 16.337457 -402.880429) (xy 16.385063 -402.909483)
			(xy 16.427931 -402.945158) (xy 16.465148 -402.986695) (xy 16.495921 -403.033208) (xy 16.519593 -403.083705)
			(xy 16.535661 -403.137112) (xy 16.543781 -403.192288) (xy 16.54429 -403.220174) (xy 16.543781 -403.24806)
			(xy 16.535661 -403.303236) (xy 16.528937 -403.325584) (xy 16.923764 -403.325584) (xy 16.927835 -403.269962)
			(xy 16.939961 -403.215525) (xy 16.959884 -403.163434) (xy 16.98718 -403.114799) (xy 17.021266 -403.070656)
			(xy 17.061415 -403.031947) (xy 17.106773 -402.999496) (xy 17.156373 -402.973995) (xy 17.209157 -402.955988)
			(xy 17.264 -402.945858) (xy 17.319734 -402.943821) (xy 17.375171 -402.949921) (xy 17.429128 -402.964027)
			(xy 17.480457 -402.985839) (xy 17.528063 -403.014893) (xy 17.570931 -403.050568) (xy 17.608148 -403.092105)
			(xy 17.638921 -403.138618) (xy 17.662593 -403.189115) (xy 17.663073 -403.19071) (xy 18.073622 -403.19071)
			(xy 18.077693 -403.135088) (xy 18.089819 -403.080651) (xy 18.109742 -403.02856) (xy 18.137038 -402.979925)
			(xy 18.171124 -402.935782) (xy 18.211273 -402.897073) (xy 18.256631 -402.864622) (xy 18.306231 -402.839121)
			(xy 18.359015 -402.821114) (xy 18.413858 -402.810984) (xy 18.469592 -402.808947) (xy 18.525029 -402.815047)
			(xy 18.578986 -402.829153) (xy 18.630315 -402.850965) (xy 18.677921 -402.880019) (xy 18.720789 -402.915694)
			(xy 18.758006 -402.957231) (xy 18.788779 -403.003744) (xy 18.812451 -403.054241) (xy 18.828519 -403.107648)
			(xy 18.836639 -403.162824) (xy 18.837148 -403.19071) (xy 18.836639 -403.218596) (xy 18.828519 -403.273772)
			(xy 18.812451 -403.327179) (xy 18.788779 -403.377676) (xy 18.758006 -403.424189) (xy 18.720789 -403.465726)
			(xy 18.677921 -403.501401) (xy 18.630315 -403.530455) (xy 18.578986 -403.552267) (xy 18.525029 -403.566373)
			(xy 18.469592 -403.572473) (xy 18.413858 -403.570436) (xy 18.359015 -403.560306) (xy 18.306231 -403.542299)
			(xy 18.256631 -403.516798) (xy 18.211273 -403.484347) (xy 18.171124 -403.445638) (xy 18.137038 -403.401495)
			(xy 18.109742 -403.35286) (xy 18.089819 -403.300769) (xy 18.077693 -403.246332) (xy 18.073622 -403.19071)
			(xy 17.663073 -403.19071) (xy 17.678661 -403.242522) (xy 17.686781 -403.297698) (xy 17.68729 -403.325584)
			(xy 17.686781 -403.35347) (xy 17.678661 -403.408646) (xy 17.662593 -403.462053) (xy 17.638921 -403.51255)
			(xy 17.608148 -403.559063) (xy 17.570931 -403.6006) (xy 17.528063 -403.636275) (xy 17.480457 -403.665329)
			(xy 17.429128 -403.687141) (xy 17.375171 -403.701247) (xy 17.319734 -403.707347) (xy 17.264 -403.70531)
			(xy 17.209157 -403.69518) (xy 17.156373 -403.677173) (xy 17.106773 -403.651672) (xy 17.061415 -403.619221)
			(xy 17.021266 -403.580512) (xy 16.98718 -403.536369) (xy 16.959884 -403.487734) (xy 16.939961 -403.435643)
			(xy 16.927835 -403.381206) (xy 16.923764 -403.325584) (xy 16.528937 -403.325584) (xy 16.519593 -403.356643)
			(xy 16.495921 -403.40714) (xy 16.465148 -403.453653) (xy 16.427931 -403.49519) (xy 16.385063 -403.530865)
			(xy 16.337457 -403.559919) (xy 16.286128 -403.581731) (xy 16.232171 -403.595837) (xy 16.176734 -403.601937)
			(xy 16.121 -403.5999) (xy 16.066157 -403.58977) (xy 16.013373 -403.571763) (xy 15.963773 -403.546262)
			(xy 15.918415 -403.513811) (xy 15.878266 -403.475102) (xy 15.84418 -403.430959) (xy 15.816884 -403.382324)
			(xy 15.796961 -403.330233) (xy 15.784835 -403.275796) (xy 15.780764 -403.220174) (xy 15.27429 -403.220174)
			(xy 15.273781 -403.24806) (xy 15.265661 -403.303236) (xy 15.249593 -403.356643) (xy 15.225921 -403.40714)
			(xy 15.195148 -403.453653) (xy 15.157931 -403.49519) (xy 15.115063 -403.530865) (xy 15.067457 -403.559919)
			(xy 15.016128 -403.581731) (xy 14.962171 -403.595837) (xy 14.906734 -403.601937) (xy 14.851 -403.5999)
			(xy 14.796157 -403.58977) (xy 14.743373 -403.571763) (xy 14.693773 -403.546262) (xy 14.648415 -403.513811)
			(xy 14.608266 -403.475102) (xy 14.57418 -403.430959) (xy 14.546884 -403.382324) (xy 14.526961 -403.330233)
			(xy 14.514835 -403.275796) (xy 14.510764 -403.220174) (xy 14.167104 -403.220174) (xy 14.167104 -404.68931)
			(xy 20.193506 -404.68931) (xy 20.197577 -404.633688) (xy 20.209703 -404.579251) (xy 20.229626 -404.52716)
			(xy 20.256922 -404.478525) (xy 20.291008 -404.434382) (xy 20.331157 -404.395673) (xy 20.376515 -404.363222)
			(xy 20.426115 -404.337721) (xy 20.478899 -404.319714) (xy 20.533742 -404.309584) (xy 20.589476 -404.307547)
			(xy 20.644913 -404.313647) (xy 20.69887 -404.327753) (xy 20.750199 -404.349565) (xy 20.797805 -404.378619)
			(xy 20.840673 -404.414294) (xy 20.87789 -404.455831) (xy 20.908663 -404.502344) (xy 20.932335 -404.552841)
			(xy 20.948403 -404.606248) (xy 20.956523 -404.661424) (xy 20.957032 -404.68931) (xy 20.956523 -404.717196)
			(xy 20.948403 -404.772372) (xy 20.932335 -404.825779) (xy 20.908663 -404.876276) (xy 20.87789 -404.922789)
			(xy 20.840673 -404.964326) (xy 20.797805 -405.000001) (xy 20.750199 -405.029055) (xy 20.69887 -405.050867)
			(xy 20.644913 -405.064973) (xy 20.589476 -405.071073) (xy 20.533742 -405.069036) (xy 20.478899 -405.058906)
			(xy 20.426115 -405.040899) (xy 20.376515 -405.015398) (xy 20.331157 -404.982947) (xy 20.291008 -404.944238)
			(xy 20.256922 -404.900095) (xy 20.229626 -404.85146) (xy 20.209703 -404.799369) (xy 20.197577 -404.744932)
			(xy 20.193506 -404.68931) (xy 14.167104 -404.68931) (xy 14.167104 -405.934751) (xy 14.302972 -405.934751)
			(xy 14.302972 -405.880249) (xy 14.310728 -405.826301) (xy 14.326083 -405.774005) (xy 14.348724 -405.724428)
			(xy 14.378191 -405.678577) (xy 14.413882 -405.637386) (xy 14.455072 -405.601694) (xy 14.500923 -405.572227)
			(xy 14.5505 -405.549585) (xy 14.602795 -405.53423) (xy 14.656743 -405.526472) (xy 14.683994 -405.525986)
			(xy 14.713337 -405.526528) (xy 14.771331 -405.535514) (xy 14.827264 -405.553275) (xy 14.879819 -405.579391)
			(xy 14.927754 -405.613248) (xy 14.969939 -405.654045) (xy 15.005379 -405.700822) (xy 15.019782 -405.726392)
			(xy 15.027447 -405.739632) (xy 15.049269 -405.76106) (xy 15.076451 -405.775076) (xy 15.106563 -405.780428)
			(xy 15.136911 -405.776636) (xy 15.16478 -405.764039) (xy 15.187677 -405.743765) (xy 15.196058 -405.730964)
			(xy 15.21095 -405.707329) (xy 15.2466 -405.66432) (xy 15.288146 -405.626974) (xy 15.334697 -405.596092)
			(xy 15.385257 -405.572334) (xy 15.438742 -405.556209) (xy 15.494008 -405.548062) (xy 15.52194 -405.547576)
			(xy 15.549192 -405.548054) (xy 15.60314 -405.55581) (xy 15.655435 -405.571166) (xy 15.705013 -405.593807)
			(xy 15.750864 -405.623274) (xy 15.792054 -405.658966) (xy 15.827746 -405.700156) (xy 15.857213 -405.746007)
			(xy 15.879854 -405.795585) (xy 15.89521 -405.84788) (xy 15.902966 -405.901828) (xy 15.902966 -405.956332)
			(xy 15.89521 -406.01028) (xy 15.879854 -406.062575) (xy 15.857213 -406.112153) (xy 15.827746 -406.158004)
			(xy 15.792054 -406.199194) (xy 15.750864 -406.234886) (xy 15.705013 -406.264353) (xy 15.655435 -406.286994)
			(xy 15.60314 -406.30235) (xy 15.549192 -406.310106) (xy 15.52194 -406.310592) (xy 15.492597 -406.310034)
			(xy 15.434604 -406.301053) (xy 15.37867 -406.283296) (xy 15.326115 -406.257182) (xy 15.27818 -406.223328)
			(xy 15.235995 -406.182531) (xy 15.200555 -406.135756) (xy 15.186152 -406.110186) (xy 15.178439 -406.096978)
			(xy 15.156625 -406.075557) (xy 15.129453 -406.061544) (xy 15.099353 -406.05619) (xy 15.069016 -406.059975)
			(xy 15.041153 -406.07256) (xy 15.018258 -406.09282) (xy 15.009876 -406.105614) (xy 14.994953 -406.129229)
			(xy 14.959309 -406.172239) (xy 14.917769 -406.209586) (xy 14.871223 -406.240472) (xy 14.820668 -406.264233)
			(xy 14.767187 -406.280362) (xy 14.711924 -406.288514) (xy 14.683994 -406.289002) (xy 14.656743 -406.288528)
			(xy 14.602795 -406.28077) (xy 14.5505 -406.265415) (xy 14.500923 -406.242773) (xy 14.455072 -406.213306)
			(xy 14.413882 -406.177614) (xy 14.378191 -406.136423) (xy 14.348724 -406.090572) (xy 14.326083 -406.040995)
			(xy 14.310728 -405.988699) (xy 14.302972 -405.934751) (xy 14.167104 -405.934751) (xy 14.167104 -406.199594)
			(xy 14.167505 -406.209667) (xy 14.17524 -406.228266) (xy 14.18209 -406.235662) (xy 14.527276 -406.580848)
			(xy 14.53474 -406.587564) (xy 14.553312 -406.595141) (xy 14.563344 -406.59558) (xy 15.967456 -406.59558)
			(xy 15.977502 -406.595219) (xy 15.996098 -406.587624) (xy 16.003524 -406.580848) (xy 16.50492 -406.079452)
			(xy 16.523021 -406.062202) (xy 16.564563 -406.034389) (xy 16.610733 -406.015213) (xy 16.659756 -406.005413)
			(xy 16.684752 -406.004776) (xy 18.812256 -406.004776) (xy 18.837252 -406.005424) (xy 18.886274 -406.015222)
			(xy 18.932445 -406.034392) (xy 18.973992 -406.062198) (xy 18.992088 -406.079452) (xy 20.48256 -407.569924)
			(xy 20.499814 -407.588022) (xy 20.527626 -407.629565) (xy 20.5468 -407.675736) (xy 20.5566 -407.72476)
			(xy 20.557236 -407.749756) (xy 20.557236 -409.421584) (xy 21.165564 -409.421584) (xy 21.169635 -409.365962)
			(xy 21.181761 -409.311525) (xy 21.201684 -409.259434) (xy 21.22898 -409.210799) (xy 21.263066 -409.166656)
			(xy 21.303215 -409.127947) (xy 21.348573 -409.095496) (xy 21.398173 -409.069995) (xy 21.450957 -409.051988)
			(xy 21.5058 -409.041858) (xy 21.561534 -409.039821) (xy 21.616971 -409.045921) (xy 21.670928 -409.060027)
			(xy 21.722257 -409.081839) (xy 21.769863 -409.110893) (xy 21.812731 -409.146568) (xy 21.849948 -409.188105)
			(xy 21.880721 -409.234618) (xy 21.904393 -409.285115) (xy 21.920461 -409.338522) (xy 21.928581 -409.393698)
			(xy 21.92909 -409.421584) (xy 21.928581 -409.44947) (xy 21.920461 -409.504646) (xy 21.904393 -409.558053)
			(xy 21.880721 -409.60855) (xy 21.849948 -409.655063) (xy 21.812731 -409.6966) (xy 21.769863 -409.732275)
			(xy 21.722257 -409.761329) (xy 21.670928 -409.783141) (xy 21.616971 -409.797247) (xy 21.561534 -409.803347)
			(xy 21.5058 -409.80131) (xy 21.450957 -409.79118) (xy 21.398173 -409.773173) (xy 21.348573 -409.747672)
			(xy 21.303215 -409.715221) (xy 21.263066 -409.676512) (xy 21.22898 -409.632369) (xy 21.201684 -409.583734)
			(xy 21.181761 -409.531643) (xy 21.169635 -409.477206) (xy 21.165564 -409.421584) (xy 20.557236 -409.421584)
			(xy 20.557236 -414.164018) (xy 20.556623 -414.189015) (xy 20.546813 -414.23804) (xy 20.527633 -414.28421)
			(xy 20.499819 -414.325755) (xy 20.48256 -414.34385) (xy 20.124166 -414.702244) (xy 20.117309 -414.709631)
			(xy 20.1096 -414.72824) (xy 20.10918 -414.738312) (xy 20.10918 -415.386266) (xy 20.134834 -415.414968)
			(xy 20.153884 -415.417254) (xy 20.181279 -415.421097) (xy 20.234645 -415.435666) (xy 20.285347 -415.457789)
			(xy 20.332323 -415.487001) (xy 20.374589 -415.522691) (xy 20.411258 -415.56411) (xy 20.441561 -415.61039)
			(xy 20.464863 -415.660561) (xy 20.480677 -415.713571) (xy 20.48867 -415.768309) (xy 20.489164 -415.795968)
			(xy 20.488715 -415.823222) (xy 20.480961 -415.877176) (xy 20.465607 -415.929477) (xy 20.442965 -415.97906)
			(xy 20.413496 -416.024915) (xy 20.377801 -416.066109) (xy 20.336605 -416.101803) (xy 20.290749 -416.131271)
			(xy 20.241165 -416.153911) (xy 20.188864 -416.169264) (xy 20.13491 -416.177016) (xy 20.107656 -416.177476)
			(xy 20.081293 -416.176993) (xy 20.029072 -416.169715) (xy 19.978349 -416.155318) (xy 19.930092 -416.134076)
			(xy 19.885218 -416.106393) (xy 19.844581 -416.072796) (xy 19.808957 -416.033925) (xy 19.779022 -415.99052)
			(xy 19.766788 -415.967164) (xy 19.760184 -415.95421) (xy 19.7358 -415.939224) (xy 19.615912 -415.939224)
			(xy 19.591528 -415.95421) (xy 19.585178 -415.967164) (xy 19.572923 -415.99054) (xy 19.542993 -416.034009)
			(xy 19.507357 -416.07294) (xy 19.466698 -416.106588) (xy 19.421789 -416.134314) (xy 19.373489 -416.155586)
			(xy 19.322718 -416.17) (xy 19.270445 -416.17728) (xy 19.244056 -416.17773) (xy 19.216805 -416.177263)
			(xy 19.162857 -416.169501) (xy 19.110564 -416.154142) (xy 19.060988 -416.131497) (xy 19.015139 -416.102028)
			(xy 18.973949 -416.066335) (xy 18.938259 -416.025144) (xy 18.908792 -415.979293) (xy 18.886151 -415.929716)
			(xy 18.870794 -415.877421) (xy 18.863035 -415.823473) (xy 18.862548 -415.796222) (xy 18.862979 -415.76959)
			(xy 18.870385 -415.716844) (xy 18.885058 -415.66564) (xy 18.906711 -415.616976) (xy 18.934923 -415.571797)
			(xy 18.969145 -415.530983) (xy 19.008713 -415.495325) (xy 19.052857 -415.465519) (xy 19.100717 -415.442144)
			(xy 19.151365 -415.425654) (xy 19.177508 -415.420556) (xy 19.19605 -415.417254) (xy 19.219672 -415.389314)
			(xy 19.219672 -414.453832) (xy 19.220254 -414.428847) (xy 19.230006 -414.379837) (xy 19.249121 -414.333668)
			(xy 19.276869 -414.292109) (xy 19.294094 -414.274) (xy 19.652488 -413.915606) (xy 19.659217 -413.908153)
			(xy 19.666785 -413.889572) (xy 19.66722 -413.879538) (xy 19.66722 -408.034236) (xy 19.666879 -408.024187)
			(xy 19.659272 -408.00559) (xy 19.652488 -407.998168) (xy 18.563844 -406.909524) (xy 18.556376 -406.902813)
			(xy 18.537807 -406.895234) (xy 18.527776 -406.894792) (xy 16.969232 -406.894792) (xy 16.959183 -406.895128)
			(xy 16.940586 -406.902738) (xy 16.933164 -406.909524) (xy 16.431768 -407.41092) (xy 16.413683 -407.428188)
			(xy 16.372134 -407.455995) (xy 16.32596 -407.475164) (xy 16.276933 -407.484961) (xy 16.251936 -407.485596)
			(xy 14.278864 -407.485596) (xy 14.25387 -407.484916) (xy 14.20485 -407.475124) (xy 14.15868 -407.455964)
			(xy 14.117131 -407.428169) (xy 14.099032 -407.41092) (xy 13.352018 -406.663906) (xy 13.334779 -406.645811)
			(xy 13.307042 -406.604246) (xy 13.28794 -406.558071) (xy 13.278204 -406.509059) (xy 13.277596 -406.484074)
			(xy 13.277596 -402.487892) (xy 13.277202 -402.477819) (xy 13.269463 -402.459219) (xy 13.26261 -402.451824)
			(xy 10.209784 -399.398998) (xy 10.192531 -399.380899) (xy 10.164721 -399.339355) (xy 10.145547 -399.293185)
			(xy 10.135746 -399.244162) (xy 10.135108 -399.219166) (xy 10.135108 -383.966466) (xy 10.134755 -383.956418)
			(xy 10.127157 -383.937821) (xy 10.120376 -383.930398) (xy 7.61111 -381.421132) (xy 7.603653 -381.414407)
			(xy 7.585075 -381.406836) (xy 7.575042 -381.4064) (xy 7.320534 -381.4064) (xy 7.291578 -381.432308)
			(xy 7.2898 -381.45212) (xy 7.28642 -381.479994) (xy 7.272686 -381.534432) (xy 7.251121 -381.586269)
			(xy 7.222193 -381.634386) (xy 7.186525 -381.677744) (xy 7.144889 -381.715407) (xy 7.098182 -381.746562)
			(xy 7.047414 -381.770535) (xy 6.99368 -381.786809) (xy 6.938142 -381.795033) (xy 6.91007 -381.795528)
			(xy 6.882819 -381.79505) (xy 6.828872 -381.78729) (xy 6.776578 -381.771932) (xy 6.727002 -381.749289)
			(xy 6.681153 -381.719821) (xy 6.639964 -381.684129) (xy 6.604273 -381.642939) (xy 6.574806 -381.597089)
			(xy 6.552164 -381.547512) (xy 6.536808 -381.495218) (xy 6.529049 -381.441271) (xy 6.528562 -381.41402)
			(xy 4.461256 -381.41402) (xy 4.461256 -382.580642) (xy 4.461803 -382.590625) (xy 4.469533 -382.609041)
			(xy 4.476242 -382.616456) (xy 4.540504 -382.680718) (xy 4.547347 -382.688118) (xy 4.555074 -382.706716)
			(xy 4.55549 -382.716786) (xy 4.55549 -395.730984) (xy 4.555928 -395.741048) (xy 4.563663 -395.759631)
			(xy 4.570476 -395.767052) (xy 11.203686 -402.400516) (xy 11.210531 -402.407915) (xy 11.218262 -402.426513)
			(xy 11.218672 -402.436584) (xy 11.218672 -402.48332) (xy 11.219212 -402.493306) (xy 11.226928 -402.511736)
			(xy 11.233658 -402.519134) (xy 11.275222 -402.56079) (xy 11.742672 -402.56079) (xy 11.746743 -402.505168)
			(xy 11.758869 -402.450731) (xy 11.778792 -402.39864) (xy 11.806088 -402.350005) (xy 11.840174 -402.305862)
			(xy 11.880323 -402.267153) (xy 11.925681 -402.234702) (xy 11.975281 -402.209201) (xy 12.028065 -402.191194)
			(xy 12.082908 -402.181064) (xy 12.138642 -402.179027) (xy 12.194079 -402.185127) (xy 12.248036 -402.199233)
			(xy 12.299365 -402.221045) (xy 12.346971 -402.250099) (xy 12.389839 -402.285774) (xy 12.427056 -402.327311)
			(xy 12.457829 -402.373824) (xy 12.481501 -402.424321) (xy 12.497569 -402.477728) (xy 12.505689 -402.532904)
			(xy 12.506198 -402.56079) (xy 12.505689 -402.588676) (xy 12.497569 -402.643852) (xy 12.481501 -402.697259)
			(xy 12.457829 -402.747756) (xy 12.427056 -402.794269) (xy 12.389839 -402.835806) (xy 12.346971 -402.871481)
			(xy 12.299365 -402.900535) (xy 12.248036 -402.922347) (xy 12.194079 -402.936453) (xy 12.138642 -402.942553)
			(xy 12.082908 -402.940516) (xy 12.028065 -402.930386) (xy 11.975281 -402.912379) (xy 11.925681 -402.886878)
			(xy 11.880323 -402.854427) (xy 11.840174 -402.815718) (xy 11.806088 -402.771575) (xy 11.778792 -402.72294)
			(xy 11.758869 -402.670849) (xy 11.746743 -402.616412) (xy 11.742672 -402.56079) (xy 11.275222 -402.56079)
			(xy 11.347958 -402.633688) (xy 11.370635 -402.656999) (xy 11.411197 -402.707836) (xy 11.445817 -402.762892)
			(xy 11.474059 -402.821476) (xy 11.495569 -402.882852) (xy 11.510077 -402.94625) (xy 11.517399 -403.010872)
			(xy 11.517884 -403.04339) (xy 11.517884 -403.855174) (xy 11.803124 -403.855174) (xy 11.807195 -403.799552)
			(xy 11.819321 -403.745115) (xy 11.839244 -403.693024) (xy 11.86654 -403.644389) (xy 11.900626 -403.600246)
			(xy 11.940775 -403.561537) (xy 11.986133 -403.529086) (xy 12.035733 -403.503585) (xy 12.088517 -403.485578)
			(xy 12.14336 -403.475448) (xy 12.199094 -403.473411) (xy 12.254531 -403.479511) (xy 12.308488 -403.493617)
			(xy 12.359817 -403.515429) (xy 12.407423 -403.544483) (xy 12.450291 -403.580158) (xy 12.487508 -403.621695)
			(xy 12.518281 -403.668208) (xy 12.541953 -403.718705) (xy 12.558021 -403.772112) (xy 12.566141 -403.827288)
			(xy 12.56665 -403.855174) (xy 12.566141 -403.88306) (xy 12.558021 -403.938236) (xy 12.541953 -403.991643)
			(xy 12.518281 -404.04214) (xy 12.487508 -404.088653) (xy 12.450291 -404.13019) (xy 12.407423 -404.165865)
			(xy 12.359817 -404.194919) (xy 12.308488 -404.216731) (xy 12.254531 -404.230837) (xy 12.199094 -404.236937)
			(xy 12.14336 -404.2349) (xy 12.088517 -404.22477) (xy 12.035733 -404.206763) (xy 11.986133 -404.181262)
			(xy 11.940775 -404.148811) (xy 11.900626 -404.110102) (xy 11.86654 -404.065959) (xy 11.839244 -404.017324)
			(xy 11.819321 -403.965233) (xy 11.807195 -403.910796) (xy 11.803124 -403.855174) (xy 11.517884 -403.855174)
			(xy 11.517884 -406.568148) (xy 11.51743 -406.600668) (xy 11.514385 -406.627584) (xy 11.716764 -406.627584)
			(xy 11.720835 -406.571962) (xy 11.732961 -406.517525) (xy 11.752884 -406.465434) (xy 11.78018 -406.416799)
			(xy 11.814266 -406.372656) (xy 11.854415 -406.333947) (xy 11.899773 -406.301496) (xy 11.949373 -406.275995)
			(xy 12.002157 -406.257988) (xy 12.057 -406.247858) (xy 12.112734 -406.245821) (xy 12.168171 -406.251921)
			(xy 12.222128 -406.266027) (xy 12.273457 -406.287839) (xy 12.321063 -406.316893) (xy 12.363931 -406.352568)
			(xy 12.401148 -406.394105) (xy 12.431921 -406.440618) (xy 12.455593 -406.491115) (xy 12.471661 -406.544522)
			(xy 12.479781 -406.599698) (xy 12.48029 -406.627584) (xy 12.479781 -406.65547) (xy 12.471661 -406.710646)
			(xy 12.455593 -406.764053) (xy 12.431921 -406.81455) (xy 12.401148 -406.861063) (xy 12.363931 -406.9026)
			(xy 12.321063 -406.938275) (xy 12.273457 -406.967329) (xy 12.222128 -406.989141) (xy 12.168171 -407.003247)
			(xy 12.112734 -407.009347) (xy 12.057 -407.00731) (xy 12.002157 -406.99718) (xy 11.949373 -406.979173)
			(xy 11.899773 -406.953672) (xy 11.854415 -406.921221) (xy 11.814266 -406.882512) (xy 11.78018 -406.838369)
			(xy 11.752884 -406.789734) (xy 11.732961 -406.737643) (xy 11.720835 -406.683206) (xy 11.716764 -406.627584)
			(xy 11.514385 -406.627584) (xy 11.510119 -406.665295) (xy 11.495616 -406.728698) (xy 11.474104 -406.790077)
			(xy 11.445853 -406.848661) (xy 11.41122 -406.903713) (xy 11.370639 -406.95454) (xy 11.347958 -406.97785)
			(xy 10.817098 -407.50871) (xy 18.001232 -407.50871) (xy 18.005303 -407.453088) (xy 18.017429 -407.398651)
			(xy 18.037352 -407.34656) (xy 18.064648 -407.297925) (xy 18.098734 -407.253782) (xy 18.138883 -407.215073)
			(xy 18.184241 -407.182622) (xy 18.233841 -407.157121) (xy 18.286625 -407.139114) (xy 18.341468 -407.128984)
			(xy 18.397202 -407.126947) (xy 18.452639 -407.133047) (xy 18.506596 -407.147153) (xy 18.557925 -407.168965)
			(xy 18.605531 -407.198019) (xy 18.648399 -407.233694) (xy 18.685616 -407.275231) (xy 18.716389 -407.321744)
			(xy 18.740061 -407.372241) (xy 18.756129 -407.425648) (xy 18.764249 -407.480824) (xy 18.764758 -407.50871)
			(xy 18.764249 -407.536596) (xy 18.756129 -407.591772) (xy 18.740061 -407.645179) (xy 18.716389 -407.695676)
			(xy 18.685616 -407.742189) (xy 18.648399 -407.783726) (xy 18.605531 -407.819401) (xy 18.557925 -407.848455)
			(xy 18.506596 -407.870267) (xy 18.452639 -407.884373) (xy 18.397202 -407.890473) (xy 18.341468 -407.888436)
			(xy 18.286625 -407.878306) (xy 18.233841 -407.860299) (xy 18.184241 -407.834798) (xy 18.138883 -407.802347)
			(xy 18.098734 -407.763638) (xy 18.064648 -407.719495) (xy 18.037352 -407.67086) (xy 18.017429 -407.618769)
			(xy 18.005303 -407.564332) (xy 18.001232 -407.50871) (xy 10.817098 -407.50871) (xy 10.686034 -407.639774)
			(xy 10.679195 -407.647175) (xy 10.671483 -407.665774) (xy 10.671048 -407.675842) (xy 10.671048 -407.780998)
			(xy 10.671528 -407.790628) (xy 10.678727 -407.808498) (xy 10.691974 -407.822488) (xy 10.700512 -407.826972)
			(xy 10.797286 -407.872438) (xy 10.826496 -407.868374) (xy 10.837926 -407.858976) (xy 10.858624 -407.842271)
			(xy 10.903769 -407.814148) (xy 10.95238 -407.792561) (xy 11.003516 -407.777928) (xy 11.056188 -407.770531)
			(xy 11.082782 -407.770076) (xy 11.110037 -407.770538) (xy 11.163992 -407.778293) (xy 11.216294 -407.793648)
			(xy 11.265879 -407.81629) (xy 11.311736 -407.845759) (xy 11.352933 -407.881454) (xy 11.38863 -407.922649)
			(xy 11.418101 -407.968505) (xy 11.440746 -408.018089) (xy 11.456103 -408.07039) (xy 11.463861 -408.124345)
			(xy 11.463861 -408.178855) (xy 11.456103 -408.23281) (xy 11.440746 -408.285111) (xy 11.418101 -408.334695)
			(xy 11.38863 -408.380551) (xy 11.352933 -408.421746) (xy 11.311736 -408.457441) (xy 11.265879 -408.48691)
			(xy 11.216294 -408.509552) (xy 11.163992 -408.524907) (xy 11.110037 -408.532662) (xy 11.082782 -408.533092)
			(xy 11.056186 -408.532637) (xy 11.003507 -408.52526) (xy 10.952364 -408.510639) (xy 10.903747 -408.489056)
			(xy 10.858599 -408.46093) (xy 10.837926 -408.444192) (xy 10.826496 -408.434794) (xy 10.797286 -408.43073)
			(xy 10.700512 -408.476196) (xy 10.691924 -408.48061) (xy 10.678637 -408.494599) (xy 10.671496 -408.512523)
			(xy 10.671048 -408.52217) (xy 10.671048 -409.167584) (xy 18.447764 -409.167584) (xy 18.451835 -409.111962)
			(xy 18.463961 -409.057525) (xy 18.483884 -409.005434) (xy 18.51118 -408.956799) (xy 18.545266 -408.912656)
			(xy 18.585415 -408.873947) (xy 18.630773 -408.841496) (xy 18.680373 -408.815995) (xy 18.733157 -408.797988)
			(xy 18.788 -408.787858) (xy 18.843734 -408.785821) (xy 18.899171 -408.791921) (xy 18.953128 -408.806027)
			(xy 19.004457 -408.827839) (xy 19.052063 -408.856893) (xy 19.094931 -408.892568) (xy 19.132148 -408.934105)
			(xy 19.162921 -408.980618) (xy 19.186593 -409.031115) (xy 19.202661 -409.084522) (xy 19.210781 -409.139698)
			(xy 19.21129 -409.167584) (xy 19.210781 -409.19547) (xy 19.202661 -409.250646) (xy 19.186593 -409.304053)
			(xy 19.162921 -409.35455) (xy 19.132148 -409.401063) (xy 19.094931 -409.4426) (xy 19.052063 -409.478275)
			(xy 19.004457 -409.507329) (xy 18.953128 -409.529141) (xy 18.899171 -409.543247) (xy 18.843734 -409.549347)
			(xy 18.788 -409.54731) (xy 18.733157 -409.53718) (xy 18.680373 -409.519173) (xy 18.630773 -409.493672)
			(xy 18.585415 -409.461221) (xy 18.545266 -409.422512) (xy 18.51118 -409.378369) (xy 18.483884 -409.329734)
			(xy 18.463961 -409.277643) (xy 18.451835 -409.223206) (xy 18.447764 -409.167584) (xy 10.671048 -409.167584)
			(xy 10.671048 -409.528772) (xy 10.670589 -409.561283) (xy 10.663303 -409.625895) (xy 10.648831 -409.689286)
			(xy 10.627354 -409.750658) (xy 10.599144 -409.809241) (xy 10.564553 -409.864298) (xy 10.524017 -409.915138)
			(xy 10.502784 -409.937023) (xy 10.777937 -409.937023) (xy 10.777937 -409.882517) (xy 10.785694 -409.828566)
			(xy 10.80105 -409.776269) (xy 10.823693 -409.726689) (xy 10.853161 -409.680836) (xy 10.888855 -409.639643)
			(xy 10.930047 -409.60395) (xy 10.9759 -409.574482) (xy 11.025481 -409.55184) (xy 11.077778 -409.536484)
			(xy 11.131729 -409.528727) (xy 11.158982 -409.528264) (xy 11.186427 -409.528721) (xy 11.24075 -409.536598)
			(xy 11.293379 -409.552193) (xy 11.343224 -409.575181) (xy 11.3665 -409.589732) (xy 11.37867 -409.597011)
			(xy 11.40576 -409.605338) (xy 11.434095 -409.605891) (xy 11.461489 -409.598628) (xy 11.485829 -409.584109)
			(xy 11.505235 -409.563455) (xy 11.51821 -409.538259) (xy 11.52144 -409.524454) (xy 11.527693 -409.496008)
			(xy 11.54769 -409.441309) (xy 11.575765 -409.390283) (xy 11.611268 -409.344116) (xy 11.653373 -409.303879)
			(xy 11.701103 -409.270507) (xy 11.753349 -409.244774) (xy 11.808899 -409.227279) (xy 11.866462 -409.218427)
			(xy 11.895582 -409.217876) (xy 11.922835 -409.21837) (xy 11.976785 -409.226125) (xy 12.029083 -409.241478)
			(xy 12.078663 -409.264119) (xy 12.124517 -409.293585) (xy 12.16571 -409.329277) (xy 12.201404 -409.370469)
			(xy 12.230872 -409.416321) (xy 12.253515 -409.4659) (xy 12.268872 -409.518197) (xy 12.276629 -409.572147)
			(xy 12.276629 -409.626653) (xy 12.268872 -409.680603) (xy 12.253515 -409.7329) (xy 12.230872 -409.782479)
			(xy 12.201404 -409.828331) (xy 12.16571 -409.869523) (xy 12.124517 -409.905215) (xy 12.078663 -409.934681)
			(xy 12.029083 -409.957322) (xy 11.976785 -409.972675) (xy 11.922835 -409.98043) (xy 11.895582 -409.980892)
			(xy 11.868137 -409.980412) (xy 11.813815 -409.972542) (xy 11.761186 -409.956955) (xy 11.71134 -409.933973)
			(xy 11.688064 -409.919424) (xy 11.675937 -409.912065) (xy 11.648831 -409.903736) (xy 11.62048 -409.903187)
			(xy 11.593073 -409.910461) (xy 11.568725 -409.924997) (xy 11.549317 -409.945671) (xy 11.536348 -409.970887)
			(xy 11.533124 -409.984702) (xy 11.526851 -410.013142) (xy 11.506851 -410.067836) (xy 11.478775 -410.118858)
			(xy 11.443273 -410.165022) (xy 11.401171 -410.205257) (xy 11.353445 -410.23863) (xy 11.301204 -410.264365)
			(xy 11.245659 -410.281865) (xy 11.1881 -410.290725) (xy 11.158982 -410.29128) (xy 11.131729 -410.290813)
			(xy 11.077778 -410.283056) (xy 11.025481 -410.2677) (xy 10.9759 -410.245058) (xy 10.930047 -410.21559)
			(xy 10.888855 -410.179897) (xy 10.853161 -410.138704) (xy 10.823693 -410.092851) (xy 10.80105 -410.043271)
			(xy 10.785694 -409.990974) (xy 10.777937 -409.937023) (xy 10.502784 -409.937023) (xy 10.501376 -409.938474)
			(xy 10.39241 -410.047694) (xy 10.385597 -410.055038) (xy 10.377861 -410.073501) (xy 10.377424 -410.083508)
			(xy 10.377424 -410.64942) (xy 17.970752 -410.64942) (xy 17.974823 -410.593798) (xy 17.986949 -410.539361)
			(xy 18.006872 -410.48727) (xy 18.034168 -410.438635) (xy 18.068254 -410.394492) (xy 18.108403 -410.355783)
			(xy 18.153761 -410.323332) (xy 18.203361 -410.297831) (xy 18.256145 -410.279824) (xy 18.310988 -410.269694)
			(xy 18.366722 -410.267657) (xy 18.422159 -410.273757) (xy 18.476116 -410.287863) (xy 18.527445 -410.309675)
			(xy 18.575051 -410.338729) (xy 18.617919 -410.374404) (xy 18.655136 -410.415941) (xy 18.685909 -410.462454)
			(xy 18.709581 -410.512951) (xy 18.725649 -410.566358) (xy 18.733769 -410.621534) (xy 18.734278 -410.64942)
			(xy 18.733769 -410.677306) (xy 18.725649 -410.732482) (xy 18.709581 -410.785889) (xy 18.685909 -410.836386)
			(xy 18.655136 -410.882899) (xy 18.617919 -410.924436) (xy 18.575051 -410.960111) (xy 18.527445 -410.989165)
			(xy 18.476116 -411.010977) (xy 18.422159 -411.025083) (xy 18.366722 -411.031183) (xy 18.310988 -411.029146)
			(xy 18.256145 -411.019016) (xy 18.203361 -411.001009) (xy 18.153761 -410.975508) (xy 18.108403 -410.943057)
			(xy 18.068254 -410.904348) (xy 18.034168 -410.860205) (xy 18.006872 -410.81157) (xy 17.986949 -410.759479)
			(xy 17.974823 -410.705042) (xy 17.970752 -410.64942) (xy 10.377424 -410.64942) (xy 10.377424 -410.956506)
			(xy 10.377849 -410.966575) (xy 10.385567 -410.985176) (xy 10.39241 -410.992574) (xy 10.464546 -411.06471)
			(xy 10.48131 -411.07233) (xy 10.490708 -411.072838) (xy 10.518208 -411.075053) (xy 10.572198 -411.086405)
			(xy 10.62399 -411.105416) (xy 10.672503 -411.131688) (xy 10.716726 -411.164675) (xy 10.755736 -411.203687)
			(xy 10.788721 -411.247911) (xy 10.814991 -411.296426) (xy 10.833999 -411.348218) (xy 10.845349 -411.402208)
			(xy 10.847578 -411.429708) (xy 10.848086 -411.439106) (xy 10.855706 -411.45587) (xy 11.23442 -411.834584)
			(xy 18.448018 -411.834584) (xy 18.452089 -411.778962) (xy 18.464215 -411.724525) (xy 18.484138 -411.672434)
			(xy 18.511434 -411.623799) (xy 18.54552 -411.579656) (xy 18.585669 -411.540947) (xy 18.631027 -411.508496)
			(xy 18.680627 -411.482995) (xy 18.733411 -411.464988) (xy 18.788254 -411.454858) (xy 18.843988 -411.452821)
			(xy 18.899425 -411.458921) (xy 18.953382 -411.473027) (xy 19.004711 -411.494839) (xy 19.052317 -411.523893)
			(xy 19.095185 -411.559568) (xy 19.132402 -411.601105) (xy 19.163175 -411.647618) (xy 19.186847 -411.698115)
			(xy 19.202915 -411.751522) (xy 19.211035 -411.806698) (xy 19.211544 -411.834584) (xy 19.211035 -411.86247)
			(xy 19.202915 -411.917646) (xy 19.186847 -411.971053) (xy 19.163175 -412.02155) (xy 19.132402 -412.068063)
			(xy 19.095185 -412.1096) (xy 19.052317 -412.145275) (xy 19.004711 -412.174329) (xy 18.953382 -412.196141)
			(xy 18.899425 -412.210247) (xy 18.843988 -412.216347) (xy 18.788254 -412.21431) (xy 18.733411 -412.20418)
			(xy 18.680627 -412.186173) (xy 18.631027 -412.160672) (xy 18.585669 -412.128221) (xy 18.54552 -412.089512)
			(xy 18.511434 -412.045369) (xy 18.484138 -411.996734) (xy 18.464215 -411.944643) (xy 18.452089 -411.890206)
			(xy 18.448018 -411.834584) (xy 11.23442 -411.834584) (xy 11.693398 -412.293562) (xy 11.700235 -412.300964)
			(xy 11.707947 -412.319562) (xy 11.708384 -412.32963) (xy 11.708384 -412.857442) (xy 11.708929 -412.867426)
			(xy 11.716651 -412.885849) (xy 11.72337 -412.893256) (xy 11.733274 -412.903162) (xy 17.542 -412.903162)
			(xy 17.546071 -412.84754) (xy 17.558197 -412.793103) (xy 17.57812 -412.741012) (xy 17.605416 -412.692377)
			(xy 17.639502 -412.648234) (xy 17.679651 -412.609525) (xy 17.725009 -412.577074) (xy 17.774609 -412.551573)
			(xy 17.827393 -412.533566) (xy 17.882236 -412.523436) (xy 17.93797 -412.521399) (xy 17.993407 -412.527499)
			(xy 18.047364 -412.541605) (xy 18.098693 -412.563417) (xy 18.146299 -412.592471) (xy 18.189167 -412.628146)
			(xy 18.226384 -412.669683) (xy 18.257157 -412.716196) (xy 18.280829 -412.766693) (xy 18.296897 -412.8201)
			(xy 18.305017 -412.875276) (xy 18.305526 -412.903162) (xy 18.305017 -412.931048) (xy 18.296897 -412.986224)
			(xy 18.280829 -413.039631) (xy 18.257157 -413.090128) (xy 18.226384 -413.136641) (xy 18.189167 -413.178178)
			(xy 18.146299 -413.213853) (xy 18.098693 -413.242907) (xy 18.047364 -413.264719) (xy 17.993407 -413.278825)
			(xy 17.93797 -413.284925) (xy 17.882236 -413.282888) (xy 17.827393 -413.272758) (xy 17.774609 -413.254751)
			(xy 17.725009 -413.22925) (xy 17.679651 -413.196799) (xy 17.639502 -413.15809) (xy 17.605416 -413.113947)
			(xy 17.57812 -413.065312) (xy 17.558197 -413.013221) (xy 17.546071 -412.958784) (xy 17.542 -412.903162)
			(xy 11.733274 -412.903162) (xy 12.315569 -413.485584) (xy 15.907764 -413.485584) (xy 15.911835 -413.429962)
			(xy 15.923961 -413.375525) (xy 15.943884 -413.323434) (xy 15.97118 -413.274799) (xy 16.005266 -413.230656)
			(xy 16.045415 -413.191947) (xy 16.090773 -413.159496) (xy 16.140373 -413.133995) (xy 16.193157 -413.115988)
			(xy 16.248 -413.105858) (xy 16.303734 -413.103821) (xy 16.359171 -413.109921) (xy 16.413128 -413.124027)
			(xy 16.464457 -413.145839) (xy 16.512063 -413.174893) (xy 16.554931 -413.210568) (xy 16.592148 -413.252105)
			(xy 16.622921 -413.298618) (xy 16.646593 -413.349115) (xy 16.662661 -413.402522) (xy 16.664643 -413.415988)
			(xy 18.764502 -413.415988) (xy 18.768573 -413.360366) (xy 18.780699 -413.305929) (xy 18.800622 -413.253838)
			(xy 18.827918 -413.205203) (xy 18.862004 -413.16106) (xy 18.902153 -413.122351) (xy 18.947511 -413.0899)
			(xy 18.997111 -413.064399) (xy 19.049895 -413.046392) (xy 19.104738 -413.036262) (xy 19.160472 -413.034225)
			(xy 19.215909 -413.040325) (xy 19.269866 -413.054431) (xy 19.321195 -413.076243) (xy 19.368801 -413.105297)
			(xy 19.411669 -413.140972) (xy 19.448886 -413.182509) (xy 19.479659 -413.229022) (xy 19.503331 -413.279519)
			(xy 19.519399 -413.332926) (xy 19.527519 -413.388102) (xy 19.528028 -413.415988) (xy 19.527519 -413.443874)
			(xy 19.519399 -413.49905) (xy 19.503331 -413.552457) (xy 19.479659 -413.602954) (xy 19.448886 -413.649467)
			(xy 19.411669 -413.691004) (xy 19.368801 -413.726679) (xy 19.321195 -413.755733) (xy 19.269866 -413.777545)
			(xy 19.215909 -413.791651) (xy 19.160472 -413.797751) (xy 19.104738 -413.795714) (xy 19.049895 -413.785584)
			(xy 18.997111 -413.767577) (xy 18.947511 -413.742076) (xy 18.902153 -413.709625) (xy 18.862004 -413.670916)
			(xy 18.827918 -413.626773) (xy 18.800622 -413.578138) (xy 18.780699 -413.526047) (xy 18.768573 -413.47161)
			(xy 18.764502 -413.415988) (xy 16.664643 -413.415988) (xy 16.670781 -413.457698) (xy 16.67129 -413.485584)
			(xy 16.670781 -413.51347) (xy 16.662661 -413.568646) (xy 16.646593 -413.622053) (xy 16.622921 -413.67255)
			(xy 16.592148 -413.719063) (xy 16.554931 -413.7606) (xy 16.512063 -413.796275) (xy 16.464457 -413.825329)
			(xy 16.413128 -413.847141) (xy 16.359171 -413.861247) (xy 16.303734 -413.867347) (xy 16.248 -413.86531)
			(xy 16.193157 -413.85518) (xy 16.140373 -413.837173) (xy 16.090773 -413.811672) (xy 16.045415 -413.779221)
			(xy 16.005266 -413.740512) (xy 15.97118 -413.696369) (xy 15.943884 -413.647734) (xy 15.923961 -413.595643)
			(xy 15.911835 -413.541206) (xy 15.907764 -413.485584) (xy 12.315569 -413.485584) (xy 12.823459 -413.993584)
			(xy 13.240764 -413.993584) (xy 13.244835 -413.937962) (xy 13.256961 -413.883525) (xy 13.276884 -413.831434)
			(xy 13.30418 -413.782799) (xy 13.338266 -413.738656) (xy 13.378415 -413.699947) (xy 13.423773 -413.667496)
			(xy 13.473373 -413.641995) (xy 13.526157 -413.623988) (xy 13.581 -413.613858) (xy 13.636734 -413.611821)
			(xy 13.692171 -413.617921) (xy 13.746128 -413.632027) (xy 13.797457 -413.653839) (xy 13.845063 -413.682893)
			(xy 13.887931 -413.718568) (xy 13.925148 -413.760105) (xy 13.955921 -413.806618) (xy 13.979593 -413.857115)
			(xy 13.995661 -413.910522) (xy 14.003781 -413.965698) (xy 14.00429 -413.993584) (xy 14.510764 -413.993584)
			(xy 14.514835 -413.937962) (xy 14.526961 -413.883525) (xy 14.546884 -413.831434) (xy 14.57418 -413.782799)
			(xy 14.608266 -413.738656) (xy 14.648415 -413.699947) (xy 14.693773 -413.667496) (xy 14.743373 -413.641995)
			(xy 14.796157 -413.623988) (xy 14.851 -413.613858) (xy 14.906734 -413.611821) (xy 14.962171 -413.617921)
			(xy 15.016128 -413.632027) (xy 15.067457 -413.653839) (xy 15.115063 -413.682893) (xy 15.157931 -413.718568)
			(xy 15.195148 -413.760105) (xy 15.225921 -413.806618) (xy 15.249593 -413.857115) (xy 15.265661 -413.910522)
			(xy 15.273781 -413.965698) (xy 15.27429 -413.993584) (xy 15.273781 -414.02147) (xy 15.265661 -414.076646)
			(xy 15.249593 -414.130053) (xy 15.225921 -414.18055) (xy 15.195148 -414.227063) (xy 15.157931 -414.2686)
			(xy 15.115063 -414.304275) (xy 15.067457 -414.333329) (xy 15.016128 -414.355141) (xy 14.962171 -414.369247)
			(xy 14.906734 -414.375347) (xy 14.851 -414.37331) (xy 14.796157 -414.36318) (xy 14.743373 -414.345173)
			(xy 14.693773 -414.319672) (xy 14.648415 -414.287221) (xy 14.608266 -414.248512) (xy 14.57418 -414.204369)
			(xy 14.546884 -414.155734) (xy 14.526961 -414.103643) (xy 14.514835 -414.049206) (xy 14.510764 -413.993584)
			(xy 14.00429 -413.993584) (xy 14.003781 -414.02147) (xy 13.995661 -414.076646) (xy 13.979593 -414.130053)
			(xy 13.955921 -414.18055) (xy 13.925148 -414.227063) (xy 13.887931 -414.2686) (xy 13.845063 -414.304275)
			(xy 13.797457 -414.333329) (xy 13.746128 -414.355141) (xy 13.692171 -414.369247) (xy 13.636734 -414.375347)
			(xy 13.581 -414.37331) (xy 13.526157 -414.36318) (xy 13.473373 -414.345173) (xy 13.423773 -414.319672)
			(xy 13.378415 -414.287221) (xy 13.338266 -414.248512) (xy 13.30418 -414.204369) (xy 13.276884 -414.155734)
			(xy 13.256961 -414.103643) (xy 13.244835 -414.049206) (xy 13.240764 -413.993584) (xy 12.823459 -413.993584)
			(xy 12.891516 -414.061656) (xy 12.908771 -414.079753) (xy 12.936578 -414.121299) (xy 12.955753 -414.167469)
			(xy 12.965559 -414.216492) (xy 12.966192 -414.241488) (xy 12.966192 -414.253172) (xy 12.966679 -414.263134)
			(xy 12.974267 -414.281557) (xy 12.980924 -414.288986) (xy 13.447522 -414.755584) (xy 16.034764 -414.755584)
			(xy 16.038835 -414.699962) (xy 16.050961 -414.645525) (xy 16.070884 -414.593434) (xy 16.09818 -414.544799)
			(xy 16.132266 -414.500656) (xy 16.172415 -414.461947) (xy 16.217773 -414.429496) (xy 16.267373 -414.403995)
			(xy 16.320157 -414.385988) (xy 16.375 -414.375858) (xy 16.430734 -414.373821) (xy 16.486171 -414.379921)
			(xy 16.540128 -414.394027) (xy 16.591457 -414.415839) (xy 16.639063 -414.444893) (xy 16.681931 -414.480568)
			(xy 16.719148 -414.522105) (xy 16.749921 -414.568618) (xy 16.773593 -414.619115) (xy 16.789661 -414.672522)
			(xy 16.797781 -414.727698) (xy 16.79829 -414.755584) (xy 16.797781 -414.78347) (xy 16.789661 -414.838646)
			(xy 16.773593 -414.892053) (xy 16.749921 -414.94255) (xy 16.719148 -414.989063) (xy 16.681931 -415.0306)
			(xy 16.639063 -415.066275) (xy 16.591457 -415.095329) (xy 16.540128 -415.117141) (xy 16.486171 -415.131247)
			(xy 16.430734 -415.137347) (xy 16.375 -415.13531) (xy 16.320157 -415.12518) (xy 16.267373 -415.107173)
			(xy 16.217773 -415.081672) (xy 16.172415 -415.049221) (xy 16.132266 -415.010512) (xy 16.09818 -414.966369)
			(xy 16.070884 -414.917734) (xy 16.050961 -414.865643) (xy 16.038835 -414.811206) (xy 16.034764 -414.755584)
			(xy 13.447522 -414.755584) (xy 14.411706 -415.719768) (xy 14.419103 -415.726617) (xy 14.437702 -415.734354)
			(xy 14.447774 -415.734754) (xy 17.010634 -415.734754) (xy 17.0207 -415.735185) (xy 17.039291 -415.742914)
			(xy 17.046702 -415.74974) (xy 18.090896 -416.793934) (xy 18.098238 -416.800752) (xy 18.116701 -416.808497)
			(xy 18.12671 -416.80892)
		)
		(stroke
			(width 0)
			(type solid)
		)
		(fill yes)
		(layer "In2.Cu")
		(net "GND")
	)
	(gr_poly
		(pts
			(xy 413.863536 -368.0968) (xy 413.873539 -368.096306) (xy 413.892018 -368.08864) (xy 413.90616 -368.074488)
			(xy 413.913813 -368.056003) (xy 413.914336 -368.046) (xy 413.914336 -364.040928) (xy 413.913805 -364.030937)
			(xy 413.906102 -364.012495) (xy 413.89935 -364.005114) (xy 413.04337 -363.149134) (xy 413.022575 -363.12754)
			(xy 412.987357 -363.07903) (xy 412.960171 -363.025603) (xy 412.941688 -362.968577) (xy 412.932363 -362.90936)
			(xy 412.931864 -362.879386) (xy 412.931864 -362.872528) (xy 412.93161 -362.804964) (xy 412.932099 -362.777715)
			(xy 412.93986 -362.723772) (xy 412.955218 -362.671483) (xy 412.977861 -362.621911) (xy 413.007329 -362.576067)
			(xy 413.043021 -362.534882) (xy 413.08421 -362.499196) (xy 413.130059 -362.469735) (xy 413.179633 -362.447099)
			(xy 413.231925 -362.431748) (xy 413.285869 -362.423995) (xy 413.313118 -362.423456) (xy 413.34817 -362.42498)
			(xy 413.357822 -362.42625) (xy 413.385381 -362.430012) (xy 413.439085 -362.444488) (xy 413.490116 -362.466612)
			(xy 413.537392 -362.495915) (xy 413.579911 -362.531773) (xy 413.616769 -362.573428) (xy 413.647187 -362.619994)
			(xy 413.670517 -362.670485) (xy 413.678878 -362.697014) (xy 413.68091 -362.703364) (xy 413.687006 -362.714032)
			(xy 414.292288 -363.319314) (xy 414.329152 -363.356144) (xy 415.065208 -363.356144) (xy 415.069279 -363.300522)
			(xy 415.081405 -363.246085) (xy 415.101328 -363.193994) (xy 415.128624 -363.145359) (xy 415.16271 -363.101216)
			(xy 415.202859 -363.062507) (xy 415.248217 -363.030056) (xy 415.297817 -363.004555) (xy 415.350601 -362.986548)
			(xy 415.405444 -362.976418) (xy 415.461178 -362.974381) (xy 415.516615 -362.980481) (xy 415.570572 -362.994587)
			(xy 415.621901 -363.016399) (xy 415.669507 -363.045453) (xy 415.712375 -363.081128) (xy 415.749592 -363.122665)
			(xy 415.780365 -363.169178) (xy 415.804037 -363.219675) (xy 415.820105 -363.273082) (xy 415.828225 -363.328258)
			(xy 415.828734 -363.356144) (xy 415.828225 -363.38403) (xy 415.820105 -363.439206) (xy 415.804037 -363.492613)
			(xy 415.780365 -363.54311) (xy 415.749592 -363.589623) (xy 415.712375 -363.63116) (xy 415.669507 -363.666835)
			(xy 415.621901 -363.695889) (xy 415.570572 -363.717701) (xy 415.516615 -363.731807) (xy 415.461178 -363.737907)
			(xy 415.405444 -363.73587) (xy 415.350601 -363.72574) (xy 415.297817 -363.707733) (xy 415.248217 -363.682232)
			(xy 415.202859 -363.649781) (xy 415.16271 -363.611072) (xy 415.128624 -363.566929) (xy 415.101328 -363.518294)
			(xy 415.081405 -363.466203) (xy 415.069279 -363.411766) (xy 415.065208 -363.356144) (xy 414.329152 -363.356144)
			(xy 414.565592 -363.592364) (xy 414.586371 -363.613978) (xy 414.62161 -363.662484) (xy 414.64883 -363.715902)
			(xy 414.667363 -363.772921) (xy 414.676751 -363.832135) (xy 414.677352 -363.862112) (xy 414.677352 -363.954314)
			(xy 425.230796 -363.954314) (xy 425.234867 -363.898692) (xy 425.246993 -363.844255) (xy 425.266916 -363.792164)
			(xy 425.294212 -363.743529) (xy 425.328298 -363.699386) (xy 425.368447 -363.660677) (xy 425.413805 -363.628226)
			(xy 425.463405 -363.602725) (xy 425.516189 -363.584718) (xy 425.571032 -363.574588) (xy 425.626766 -363.572551)
			(xy 425.682203 -363.578651) (xy 425.73616 -363.592757) (xy 425.787489 -363.614569) (xy 425.835095 -363.643623)
			(xy 425.877963 -363.679298) (xy 425.91518 -363.720835) (xy 425.945953 -363.767348) (xy 425.969625 -363.817845)
			(xy 425.985693 -363.871252) (xy 425.993813 -363.926428) (xy 425.994322 -363.954314) (xy 425.993813 -363.9822)
			(xy 425.985693 -364.037376) (xy 425.969625 -364.090783) (xy 425.945953 -364.14128) (xy 425.91518 -364.187793)
			(xy 425.877963 -364.22933) (xy 425.835095 -364.265005) (xy 425.787489 -364.294059) (xy 425.73616 -364.315871)
			(xy 425.682203 -364.329977) (xy 425.626766 -364.336077) (xy 425.571032 -364.33404) (xy 425.516189 -364.32391)
			(xy 425.463405 -364.305903) (xy 425.413805 -364.280402) (xy 425.368447 -364.247951) (xy 425.328298 -364.209242)
			(xy 425.294212 -364.165099) (xy 425.266916 -364.116464) (xy 425.246993 -364.064373) (xy 425.234867 -364.009936)
			(xy 425.230796 -363.954314) (xy 414.677352 -363.954314) (xy 414.677352 -364.357412) (xy 416.135818 -364.357412)
			(xy 416.139889 -364.30179) (xy 416.152015 -364.247353) (xy 416.171938 -364.195262) (xy 416.199234 -364.146627)
			(xy 416.23332 -364.102484) (xy 416.273469 -364.063775) (xy 416.318827 -364.031324) (xy 416.368427 -364.005823)
			(xy 416.421211 -363.987816) (xy 416.476054 -363.977686) (xy 416.531788 -363.975649) (xy 416.587225 -363.981749)
			(xy 416.641182 -363.995855) (xy 416.692511 -364.017667) (xy 416.740117 -364.046721) (xy 416.782985 -364.082396)
			(xy 416.820202 -364.123933) (xy 416.850975 -364.170446) (xy 416.874647 -364.220943) (xy 416.890715 -364.27435)
			(xy 416.898835 -364.329526) (xy 416.899344 -364.357412) (xy 416.898835 -364.385298) (xy 416.890715 -364.440474)
			(xy 416.874647 -364.493881) (xy 416.86825 -364.507526) (xy 424.072048 -364.507526) (xy 424.076119 -364.451904)
			(xy 424.088245 -364.397467) (xy 424.108168 -364.345376) (xy 424.135464 -364.296741) (xy 424.16955 -364.252598)
			(xy 424.209699 -364.213889) (xy 424.255057 -364.181438) (xy 424.304657 -364.155937) (xy 424.357441 -364.13793)
			(xy 424.412284 -364.1278) (xy 424.468018 -364.125763) (xy 424.523455 -364.131863) (xy 424.577412 -364.145969)
			(xy 424.628741 -364.167781) (xy 424.676347 -364.196835) (xy 424.719215 -364.23251) (xy 424.756432 -364.274047)
			(xy 424.787205 -364.32056) (xy 424.81052 -364.370296) (xy 431.124356 -364.370296) (xy 431.124356 -364.2856)
			(xy 431.132407 -364.201286) (xy 431.148436 -364.11812) (xy 431.172297 -364.036853) (xy 431.203776 -363.958223)
			(xy 431.242587 -363.882942) (xy 431.288377 -363.81169) (xy 431.340733 -363.745114) (xy 431.399181 -363.683816)
			(xy 431.463191 -363.628351) (xy 431.532183 -363.579222) (xy 431.605533 -363.536873) (xy 431.682576 -363.501689)
			(xy 431.762615 -363.473987) (xy 431.844924 -363.454019) (xy 431.928759 -363.441966) (xy 432.01336 -363.437936)
			(xy 432.097961 -363.441966) (xy 432.181796 -363.454019) (xy 432.264105 -363.473987) (xy 432.344144 -363.501689)
			(xy 432.421187 -363.536873) (xy 432.494537 -363.579222) (xy 432.563529 -363.628351) (xy 432.627539 -363.683816)
			(xy 432.685987 -363.745114) (xy 432.738343 -363.81169) (xy 432.784133 -363.882942) (xy 432.822944 -363.958223)
			(xy 432.854423 -364.036853) (xy 432.878284 -364.11812) (xy 432.894313 -364.201286) (xy 432.902364 -364.2856)
			(xy 432.902868 -364.327948) (xy 432.902364 -364.370296) (xy 432.894313 -364.45461) (xy 432.878284 -364.537776)
			(xy 432.854423 -364.619043) (xy 432.822944 -364.697673) (xy 432.784133 -364.772954) (xy 432.738343 -364.844206)
			(xy 432.685987 -364.910782) (xy 432.627539 -364.97208) (xy 432.563529 -365.027545) (xy 432.494537 -365.076674)
			(xy 432.421187 -365.119023) (xy 432.344144 -365.154207) (xy 432.264105 -365.181909) (xy 432.181796 -365.201877)
			(xy 432.097961 -365.21393) (xy 432.01336 -365.217961) (xy 431.928759 -365.21393) (xy 431.844924 -365.201877)
			(xy 431.762615 -365.181909) (xy 431.682576 -365.154207) (xy 431.605533 -365.119023) (xy 431.532183 -365.076674)
			(xy 431.463191 -365.027545) (xy 431.399181 -364.97208) (xy 431.340733 -364.910782) (xy 431.288377 -364.844206)
			(xy 431.242587 -364.772954) (xy 431.203776 -364.697673) (xy 431.172297 -364.619043) (xy 431.148436 -364.537776)
			(xy 431.132407 -364.45461) (xy 431.124356 -364.370296) (xy 424.81052 -364.370296) (xy 424.810877 -364.371057)
			(xy 424.826945 -364.424464) (xy 424.835065 -364.47964) (xy 424.835574 -364.507526) (xy 424.835065 -364.535412)
			(xy 424.826945 -364.590588) (xy 424.810877 -364.643995) (xy 424.787205 -364.694492) (xy 424.756432 -364.741005)
			(xy 424.719215 -364.782542) (xy 424.676347 -364.818217) (xy 424.628741 -364.847271) (xy 424.577412 -364.869083)
			(xy 424.523455 -364.883189) (xy 424.468018 -364.889289) (xy 424.412284 -364.887252) (xy 424.357441 -364.877122)
			(xy 424.304657 -364.859115) (xy 424.255057 -364.833614) (xy 424.209699 -364.801163) (xy 424.16955 -364.762454)
			(xy 424.135464 -364.718311) (xy 424.108168 -364.669676) (xy 424.088245 -364.617585) (xy 424.076119 -364.563148)
			(xy 424.072048 -364.507526) (xy 416.86825 -364.507526) (xy 416.850975 -364.544378) (xy 416.820202 -364.590891)
			(xy 416.782985 -364.632428) (xy 416.740117 -364.668103) (xy 416.692511 -364.697157) (xy 416.641182 -364.718969)
			(xy 416.587225 -364.733075) (xy 416.531788 -364.739175) (xy 416.476054 -364.737138) (xy 416.421211 -364.727008)
			(xy 416.368427 -364.709001) (xy 416.318827 -364.6835) (xy 416.273469 -364.651049) (xy 416.23332 -364.61234)
			(xy 416.199234 -364.568197) (xy 416.171938 -364.519562) (xy 416.152015 -364.467471) (xy 416.139889 -364.413034)
			(xy 416.135818 -364.357412) (xy 414.677352 -364.357412) (xy 414.677352 -364.878112) (xy 414.96564 -364.878112)
			(xy 414.969711 -364.82249) (xy 414.981837 -364.768053) (xy 415.00176 -364.715962) (xy 415.029056 -364.667327)
			(xy 415.063142 -364.623184) (xy 415.103291 -364.584475) (xy 415.148649 -364.552024) (xy 415.198249 -364.526523)
			(xy 415.251033 -364.508516) (xy 415.305876 -364.498386) (xy 415.36161 -364.496349) (xy 415.417047 -364.502449)
			(xy 415.471004 -364.516555) (xy 415.522333 -364.538367) (xy 415.569939 -364.567421) (xy 415.612807 -364.603096)
			(xy 415.650024 -364.644633) (xy 415.680797 -364.691146) (xy 415.704469 -364.741643) (xy 415.720537 -364.79505)
			(xy 415.728657 -364.850226) (xy 415.729166 -364.878112) (xy 415.728657 -364.905998) (xy 415.720537 -364.961174)
			(xy 415.704469 -365.014581) (xy 415.680797 -365.065078) (xy 415.650024 -365.111591) (xy 415.612807 -365.153128)
			(xy 415.569939 -365.188803) (xy 415.522333 -365.217857) (xy 415.471872 -365.2393) (xy 417.696648 -365.2393)
			(xy 417.700719 -365.183678) (xy 417.712845 -365.129241) (xy 417.732768 -365.07715) (xy 417.760064 -365.028515)
			(xy 417.79415 -364.984372) (xy 417.834299 -364.945663) (xy 417.879657 -364.913212) (xy 417.929257 -364.887711)
			(xy 417.982041 -364.869704) (xy 418.036884 -364.859574) (xy 418.092618 -364.857537) (xy 418.148055 -364.863637)
			(xy 418.202012 -364.877743) (xy 418.253341 -364.899555) (xy 418.300947 -364.928609) (xy 418.343815 -364.964284)
			(xy 418.381032 -365.005821) (xy 418.411805 -365.052334) (xy 418.435477 -365.102831) (xy 418.451545 -365.156238)
			(xy 418.458909 -365.20628) (xy 418.819582 -365.20628) (xy 418.823653 -365.150658) (xy 418.835779 -365.096221)
			(xy 418.855702 -365.04413) (xy 418.882998 -364.995495) (xy 418.917084 -364.951352) (xy 418.957233 -364.912643)
			(xy 419.002591 -364.880192) (xy 419.052191 -364.854691) (xy 419.104975 -364.836684) (xy 419.159818 -364.826554)
			(xy 419.215552 -364.824517) (xy 419.270989 -364.830617) (xy 419.324946 -364.844723) (xy 419.376275 -364.866535)
			(xy 419.423881 -364.895589) (xy 419.466749 -364.931264) (xy 419.503966 -364.972801) (xy 419.534739 -365.019314)
			(xy 419.558411 -365.069811) (xy 419.570736 -365.110776) (xy 420.772588 -365.110776) (xy 420.776659 -365.055154)
			(xy 420.788785 -365.000717) (xy 420.808708 -364.948626) (xy 420.836004 -364.899991) (xy 420.87009 -364.855848)
			(xy 420.910239 -364.817139) (xy 420.955597 -364.784688) (xy 421.005197 -364.759187) (xy 421.057981 -364.74118)
			(xy 421.112824 -364.73105) (xy 421.168558 -364.729013) (xy 421.223995 -364.735113) (xy 421.277952 -364.749219)
			(xy 421.329281 -364.771031) (xy 421.376887 -364.800085) (xy 421.419755 -364.83576) (xy 421.456972 -364.877297)
			(xy 421.487745 -364.92381) (xy 421.511417 -364.974307) (xy 421.527485 -365.027714) (xy 421.535605 -365.08289)
			(xy 421.536114 -365.110776) (xy 421.535605 -365.138662) (xy 421.527485 -365.193838) (xy 421.511417 -365.247245)
			(xy 421.487745 -365.297742) (xy 421.456972 -365.344255) (xy 421.419755 -365.385792) (xy 421.376887 -365.421467)
			(xy 421.329281 -365.450521) (xy 421.277952 -365.472333) (xy 421.223995 -365.486439) (xy 421.168558 -365.492539)
			(xy 421.112824 -365.490502) (xy 421.057981 -365.480372) (xy 421.005197 -365.462365) (xy 420.955597 -365.436864)
			(xy 420.910239 -365.404413) (xy 420.87009 -365.365704) (xy 420.836004 -365.321561) (xy 420.808708 -365.272926)
			(xy 420.788785 -365.220835) (xy 420.776659 -365.166398) (xy 420.772588 -365.110776) (xy 419.570736 -365.110776)
			(xy 419.574479 -365.123218) (xy 419.582599 -365.178394) (xy 419.583108 -365.20628) (xy 419.582599 -365.234166)
			(xy 419.574479 -365.289342) (xy 419.558411 -365.342749) (xy 419.534739 -365.393246) (xy 419.503966 -365.439759)
			(xy 419.466749 -365.481296) (xy 419.423881 -365.516971) (xy 419.376275 -365.546025) (xy 419.324946 -365.567837)
			(xy 419.270989 -365.581943) (xy 419.215552 -365.588043) (xy 419.159818 -365.586006) (xy 419.104975 -365.575876)
			(xy 419.052191 -365.557869) (xy 419.002591 -365.532368) (xy 418.957233 -365.499917) (xy 418.917084 -365.461208)
			(xy 418.882998 -365.417065) (xy 418.855702 -365.36843) (xy 418.835779 -365.316339) (xy 418.823653 -365.261902)
			(xy 418.819582 -365.20628) (xy 418.458909 -365.20628) (xy 418.459665 -365.211414) (xy 418.460174 -365.2393)
			(xy 418.459665 -365.267186) (xy 418.451545 -365.322362) (xy 418.435477 -365.375769) (xy 418.411805 -365.426266)
			(xy 418.381032 -365.472779) (xy 418.343815 -365.514316) (xy 418.300947 -365.549991) (xy 418.253341 -365.579045)
			(xy 418.202012 -365.600857) (xy 418.148055 -365.614963) (xy 418.092618 -365.621063) (xy 418.036884 -365.619026)
			(xy 417.982041 -365.608896) (xy 417.929257 -365.590889) (xy 417.879657 -365.565388) (xy 417.834299 -365.532937)
			(xy 417.79415 -365.494228) (xy 417.760064 -365.450085) (xy 417.732768 -365.40145) (xy 417.712845 -365.349359)
			(xy 417.700719 -365.294922) (xy 417.696648 -365.2393) (xy 415.471872 -365.2393) (xy 415.471004 -365.239669)
			(xy 415.417047 -365.253775) (xy 415.36161 -365.259875) (xy 415.305876 -365.257838) (xy 415.251033 -365.247708)
			(xy 415.198249 -365.229701) (xy 415.148649 -365.2042) (xy 415.103291 -365.171749) (xy 415.063142 -365.13304)
			(xy 415.029056 -365.088897) (xy 415.00176 -365.040262) (xy 414.981837 -364.988171) (xy 414.969711 -364.933734)
			(xy 414.96564 -364.878112) (xy 414.677352 -364.878112) (xy 414.677352 -365.677196) (xy 416.787582 -365.677196)
			(xy 416.791653 -365.621574) (xy 416.803779 -365.567137) (xy 416.823702 -365.515046) (xy 416.850998 -365.466411)
			(xy 416.885084 -365.422268) (xy 416.925233 -365.383559) (xy 416.970591 -365.351108) (xy 417.020191 -365.325607)
			(xy 417.072975 -365.3076) (xy 417.127818 -365.29747) (xy 417.183552 -365.295433) (xy 417.238989 -365.301533)
			(xy 417.292946 -365.315639) (xy 417.344275 -365.337451) (xy 417.391881 -365.366505) (xy 417.434749 -365.40218)
			(xy 417.471966 -365.443717) (xy 417.502739 -365.49023) (xy 417.526411 -365.540727) (xy 417.542479 -365.594134)
			(xy 417.550599 -365.64931) (xy 417.551108 -365.677196) (xy 417.550599 -365.705082) (xy 417.542479 -365.760258)
			(xy 417.526411 -365.813665) (xy 417.502739 -365.864162) (xy 417.471966 -365.910675) (xy 417.434749 -365.952212)
			(xy 417.391881 -365.987887) (xy 417.344275 -366.016941) (xy 417.292946 -366.038753) (xy 417.238989 -366.052859)
			(xy 417.183552 -366.058959) (xy 417.127818 -366.056922) (xy 417.072975 -366.046792) (xy 417.020191 -366.028785)
			(xy 416.970591 -366.003284) (xy 416.925233 -365.970833) (xy 416.885084 -365.932124) (xy 416.850998 -365.887981)
			(xy 416.823702 -365.839346) (xy 416.803779 -365.787255) (xy 416.791653 -365.732818) (xy 416.787582 -365.677196)
			(xy 414.677352 -365.677196) (xy 414.677352 -366.854994) (xy 423.83532 -366.854994) (xy 423.839391 -366.799372)
			(xy 423.851517 -366.744935) (xy 423.87144 -366.692844) (xy 423.898736 -366.644209) (xy 423.932822 -366.600066)
			(xy 423.972971 -366.561357) (xy 424.018329 -366.528906) (xy 424.067929 -366.503405) (xy 424.120713 -366.485398)
			(xy 424.175556 -366.475268) (xy 424.23129 -366.473231) (xy 424.286727 -366.479331) (xy 424.340684 -366.493437)
			(xy 424.392013 -366.515249) (xy 424.439619 -366.544303) (xy 424.482487 -366.579978) (xy 424.519704 -366.621515)
			(xy 424.550477 -366.668028) (xy 424.574149 -366.718525) (xy 424.590217 -366.771932) (xy 424.598337 -366.827108)
			(xy 424.598846 -366.854994) (xy 424.598337 -366.88288) (xy 424.590217 -366.938056) (xy 424.574149 -366.991463)
			(xy 424.550477 -367.04196) (xy 424.519704 -367.088473) (xy 424.482487 -367.13001) (xy 424.439619 -367.165685)
			(xy 424.392013 -367.194739) (xy 424.340684 -367.216551) (xy 424.286727 -367.230657) (xy 424.23129 -367.236757)
			(xy 424.175556 -367.23472) (xy 424.120713 -367.22459) (xy 424.067929 -367.206583) (xy 424.018329 -367.181082)
			(xy 423.972971 -367.148631) (xy 423.932822 -367.109922) (xy 423.898736 -367.065779) (xy 423.87144 -367.017144)
			(xy 423.851517 -366.965053) (xy 423.839391 -366.910616) (xy 423.83532 -366.854994) (xy 414.677352 -366.854994)
			(xy 414.677352 -367.473484) (xy 415.2044 -367.473484) (xy 415.208471 -367.417862) (xy 415.220597 -367.363425)
			(xy 415.24052 -367.311334) (xy 415.267816 -367.262699) (xy 415.301902 -367.218556) (xy 415.342051 -367.179847)
			(xy 415.387409 -367.147396) (xy 415.437009 -367.121895) (xy 415.489793 -367.103888) (xy 415.544636 -367.093758)
			(xy 415.60037 -367.091721) (xy 415.655807 -367.097821) (xy 415.709764 -367.111927) (xy 415.761093 -367.133739)
			(xy 415.808699 -367.162793) (xy 415.851567 -367.198468) (xy 415.888784 -367.240005) (xy 415.919557 -367.286518)
			(xy 415.943229 -367.337015) (xy 415.959297 -367.390422) (xy 415.967417 -367.445598) (xy 415.967926 -367.473484)
			(xy 416.4744 -367.473484) (xy 416.478471 -367.417862) (xy 416.490597 -367.363425) (xy 416.51052 -367.311334)
			(xy 416.537816 -367.262699) (xy 416.571902 -367.218556) (xy 416.612051 -367.179847) (xy 416.657409 -367.147396)
			(xy 416.707009 -367.121895) (xy 416.759793 -367.103888) (xy 416.814636 -367.093758) (xy 416.87037 -367.091721)
			(xy 416.925807 -367.097821) (xy 416.979764 -367.111927) (xy 417.031093 -367.133739) (xy 417.078699 -367.162793)
			(xy 417.121567 -367.198468) (xy 417.158784 -367.240005) (xy 417.189557 -367.286518) (xy 417.213229 -367.337015)
			(xy 417.229297 -367.390422) (xy 417.237417 -367.445598) (xy 417.237773 -367.465102) (xy 418.560502 -367.465102)
			(xy 418.564573 -367.40948) (xy 418.576699 -367.355043) (xy 418.596622 -367.302952) (xy 418.623918 -367.254317)
			(xy 418.658004 -367.210174) (xy 418.698153 -367.171465) (xy 418.743511 -367.139014) (xy 418.793111 -367.113513)
			(xy 418.845895 -367.095506) (xy 418.900738 -367.085376) (xy 418.956472 -367.083339) (xy 419.011909 -367.089439)
			(xy 419.065866 -367.103545) (xy 419.117195 -367.125357) (xy 419.164801 -367.154411) (xy 419.207669 -367.190086)
			(xy 419.244886 -367.231623) (xy 419.275659 -367.278136) (xy 419.299331 -367.328633) (xy 419.315399 -367.38204)
			(xy 419.323519 -367.437216) (xy 419.324028 -367.465102) (xy 419.323519 -367.492988) (xy 419.315399 -367.548164)
			(xy 419.299331 -367.601571) (xy 419.275659 -367.652068) (xy 419.244886 -367.698581) (xy 419.207669 -367.740118)
			(xy 419.164801 -367.775793) (xy 419.117195 -367.804847) (xy 419.065866 -367.826659) (xy 419.011909 -367.840765)
			(xy 418.956472 -367.846865) (xy 418.900738 -367.844828) (xy 418.845895 -367.834698) (xy 418.793111 -367.816691)
			(xy 418.743511 -367.79119) (xy 418.698153 -367.758739) (xy 418.658004 -367.72003) (xy 418.623918 -367.675887)
			(xy 418.596622 -367.627252) (xy 418.576699 -367.575161) (xy 418.564573 -367.520724) (xy 418.560502 -367.465102)
			(xy 417.237773 -367.465102) (xy 417.237926 -367.473484) (xy 417.237417 -367.50137) (xy 417.229297 -367.556546)
			(xy 417.213229 -367.609953) (xy 417.189557 -367.66045) (xy 417.158784 -367.706963) (xy 417.121567 -367.7485)
			(xy 417.078699 -367.784175) (xy 417.031093 -367.813229) (xy 416.979764 -367.835041) (xy 416.925807 -367.849147)
			(xy 416.87037 -367.855247) (xy 416.814636 -367.85321) (xy 416.759793 -367.84308) (xy 416.707009 -367.825073)
			(xy 416.657409 -367.799572) (xy 416.612051 -367.767121) (xy 416.571902 -367.728412) (xy 416.537816 -367.684269)
			(xy 416.51052 -367.635634) (xy 416.490597 -367.583543) (xy 416.478471 -367.529106) (xy 416.4744 -367.473484)
			(xy 415.967926 -367.473484) (xy 415.967417 -367.50137) (xy 415.959297 -367.556546) (xy 415.943229 -367.609953)
			(xy 415.919557 -367.66045) (xy 415.888784 -367.706963) (xy 415.851567 -367.7485) (xy 415.808699 -367.784175)
			(xy 415.761093 -367.813229) (xy 415.709764 -367.835041) (xy 415.655807 -367.849147) (xy 415.60037 -367.855247)
			(xy 415.544636 -367.85321) (xy 415.489793 -367.84308) (xy 415.437009 -367.825073) (xy 415.387409 -367.799572)
			(xy 415.342051 -367.767121) (xy 415.301902 -367.728412) (xy 415.267816 -367.684269) (xy 415.24052 -367.635634)
			(xy 415.220597 -367.583543) (xy 415.208471 -367.529106) (xy 415.2044 -367.473484) (xy 414.677352 -367.473484)
			(xy 414.677352 -368.046) (xy 414.677839 -368.056011) (xy 414.685497 -368.074511) (xy 414.699648 -368.088676)
			(xy 414.718141 -368.096351) (xy 414.728152 -368.0968) (xy 424.550078 -368.0968) (xy 424.55995 -368.096329)
			(xy 424.578233 -368.088871) (xy 424.585638 -368.082322) (xy 424.585892 -368.082068) (xy 426.263054 -366.404906)
			(xy 426.270455 -366.398067) (xy 426.289053 -366.390352) (xy 426.299122 -366.38992) (xy 427.302422 -366.38992)
			(xy 427.326298 -366.375442) (xy 427.332902 -366.362742) (xy 427.346231 -366.33857) (xy 427.37879 -366.293998)
			(xy 427.417431 -366.254583) (xy 427.461349 -366.221147) (xy 427.509627 -366.194388) (xy 427.561257 -366.174866)
			(xy 427.615161 -366.162987) (xy 427.670214 -366.159) (xy 427.725267 -366.162987) (xy 427.779171 -366.174866)
			(xy 427.830801 -366.194388) (xy 427.879079 -366.221147) (xy 427.922997 -366.254583) (xy 427.961638 -366.293998)
			(xy 427.994197 -366.33857) (xy 428.007526 -366.362742) (xy 428.01413 -366.375442) (xy 428.038006 -366.38992)
			(xy 434.5305 -366.38992) (xy 434.540379 -366.389464) (xy 434.558684 -366.382027) (xy 434.56606 -366.375442)
			(xy 434.566314 -366.375188) (xy 436.801514 -364.139988) (xy 436.808909 -364.133134) (xy 436.827508 -364.125391)
			(xy 436.837582 -364.125002) (xy 444.529464 -364.125002) (xy 444.539302 -364.124467) (xy 444.557465 -364.116882)
			(xy 444.56477 -364.11027) (xy 445.972946 -362.702094) (xy 445.979656 -362.694855) (xy 445.987247 -362.67665)
			(xy 445.987678 -362.666788) (xy 445.987678 -330.08316) (xy 445.987247 -330.073093) (xy 445.97952 -330.054502)
			(xy 445.972692 -330.047092) (xy 444.972186 -329.046586) (xy 444.965074 -329.03922) (xy 444.946278 -329.0316)
			(xy 414.853882 -329.0316) (xy 414.843896 -329.032141) (xy 414.825469 -329.039859) (xy 414.818068 -329.046586)
			(xy 410.84754 -333.017114) (xy 412.707074 -333.017114) (xy 412.707574 -332.988196) (xy 412.716303 -332.931023)
			(xy 412.733563 -332.875822) (xy 412.758958 -332.82386) (xy 412.791906 -332.776327) (xy 412.831652 -332.734312)
			(xy 412.85414 -332.716124) (xy 412.862893 -332.708554) (xy 412.87308 -332.687801) (xy 412.873698 -332.676246)
			(xy 412.873698 -332.595982) (xy 412.873138 -332.584413) (xy 412.862936 -332.563642) (xy 412.85414 -332.556104)
			(xy 412.831667 -332.537901) (xy 412.791929 -332.495885) (xy 412.758988 -332.448353) (xy 412.733597 -332.396394)
			(xy 412.716339 -332.341198) (xy 412.707609 -332.284029) (xy 412.707074 -332.255114) (xy 412.70756 -332.227863)
			(xy 412.715316 -332.173915) (xy 412.730671 -332.12162) (xy 412.753313 -332.072043) (xy 412.782779 -332.026193)
			(xy 412.81847 -331.985002) (xy 412.859661 -331.949311) (xy 412.905511 -331.919845) (xy 412.955088 -331.897203)
			(xy 413.007383 -331.881848) (xy 413.061331 -331.874092) (xy 413.115833 -331.874092) (xy 413.169781 -331.881848)
			(xy 413.222076 -331.897203) (xy 413.271653 -331.919845) (xy 413.317503 -331.949311) (xy 413.358694 -331.985002)
			(xy 413.394385 -332.026193) (xy 413.423851 -332.072043) (xy 413.446493 -332.12162) (xy 413.461848 -332.173915)
			(xy 413.469604 -332.227863) (xy 413.47009 -332.255114) (xy 413.469514 -332.284029) (xy 413.460797 -332.341198)
			(xy 413.443551 -332.396395) (xy 413.41817 -332.448357) (xy 413.385237 -332.495893) (xy 413.345505 -332.537912)
			(xy 413.323024 -332.556104) (xy 413.314252 -332.563656) (xy 413.304077 -332.584423) (xy 413.303466 -332.595982)
			(xy 413.303466 -332.676246) (xy 413.304045 -332.687813) (xy 413.314231 -332.708586) (xy 413.323024 -332.716124)
			(xy 413.345524 -332.734295) (xy 413.385257 -332.77632) (xy 413.418193 -332.823859) (xy 413.443579 -332.875824)
			(xy 413.460832 -332.931025) (xy 413.469557 -332.988197) (xy 413.47009 -333.017114) (xy 413.469604 -333.044365)
			(xy 413.461848 -333.098313) (xy 413.446493 -333.150608) (xy 413.423851 -333.200185) (xy 413.394385 -333.246035)
			(xy 413.358694 -333.287226) (xy 413.317503 -333.322917) (xy 413.271653 -333.352383) (xy 413.222076 -333.375025)
			(xy 413.169781 -333.39038) (xy 413.115833 -333.398136) (xy 413.061331 -333.398136) (xy 413.007383 -333.39038)
			(xy 412.955088 -333.375025) (xy 412.905511 -333.352383) (xy 412.859661 -333.322917) (xy 412.81847 -333.287226)
			(xy 412.782779 -333.246035) (xy 412.753313 -333.200185) (xy 412.730671 -333.150608) (xy 412.715316 -333.098313)
			(xy 412.70756 -333.044365) (xy 412.707074 -333.017114) (xy 410.84754 -333.017114) (xy 409.186634 -334.67802)
			(xy 409.168944 -334.695018) (xy 409.12925 -334.723846) (xy 409.085539 -334.746118) (xy 409.038886 -334.761288)
			(xy 408.990436 -334.768984) (xy 408.965908 -334.76946) (xy 407.65095 -334.76946) (xy 407.640946 -334.769956)
			(xy 407.622464 -334.777623) (xy 407.608317 -334.791773) (xy 407.600654 -334.810256) (xy 407.60015 -334.82026)
			(xy 407.60015 -335.314799) (xy 418.990283 -335.314799) (xy 418.994013 -335.261548) (xy 419.005129 -335.209336)
			(xy 419.023415 -335.159184) (xy 419.048513 -335.11207) (xy 419.079934 -335.068915) (xy 419.117063 -335.030562)
			(xy 419.137846 -335.013808) (xy 419.146607 -335.006246) (xy 419.156789 -334.985487) (xy 419.157404 -334.97393)
			(xy 419.157404 -334.893666) (xy 419.156794 -334.882103) (xy 419.146627 -334.861332) (xy 419.137846 -334.853788)
			(xy 419.117062 -334.837037) (xy 419.079932 -334.798683) (xy 419.048512 -334.755527) (xy 419.023414 -334.708414)
			(xy 419.005128 -334.658262) (xy 418.994012 -334.60605) (xy 418.990283 -334.552799) (xy 418.994013 -334.499548)
			(xy 419.005129 -334.447336) (xy 419.023415 -334.397184) (xy 419.048513 -334.35007) (xy 419.079934 -334.306915)
			(xy 419.117063 -334.268562) (xy 419.137846 -334.251808) (xy 419.146607 -334.244246) (xy 419.156789 -334.223487)
			(xy 419.157404 -334.21193) (xy 419.157404 -334.131666) (xy 419.156794 -334.120103) (xy 419.146627 -334.099332)
			(xy 419.137846 -334.091788) (xy 419.115346 -334.073617) (xy 419.075614 -334.031592) (xy 419.042678 -333.984052)
			(xy 419.017293 -333.932087) (xy 419.00004 -333.876887) (xy 418.991314 -333.819715) (xy 418.99078 -333.790798)
			(xy 418.991266 -333.763547) (xy 418.999022 -333.709599) (xy 419.014377 -333.657304) (xy 419.037019 -333.607727)
			(xy 419.066485 -333.561877) (xy 419.102176 -333.520686) (xy 419.143367 -333.484995) (xy 419.189217 -333.455529)
			(xy 419.238794 -333.432887) (xy 419.291089 -333.417532) (xy 419.345037 -333.409776) (xy 419.399539 -333.409776)
			(xy 419.453487 -333.417532) (xy 419.505782 -333.432887) (xy 419.555359 -333.455529) (xy 419.601209 -333.484995)
			(xy 419.6424 -333.520686) (xy 419.678091 -333.561877) (xy 419.707557 -333.607727) (xy 419.730199 -333.657304)
			(xy 419.745554 -333.709599) (xy 419.75331 -333.763547) (xy 419.753796 -333.790798) (xy 419.753278 -333.819715)
			(xy 419.744549 -333.876886) (xy 419.727291 -333.932085) (xy 419.701899 -333.984047) (xy 419.668956 -334.031581)
			(xy 419.629215 -334.073598) (xy 419.60673 -334.091788) (xy 419.597966 -334.099347) (xy 419.587787 -334.120109)
			(xy 419.587172 -334.131666) (xy 419.587172 -334.21193) (xy 419.587757 -334.223497) (xy 419.597939 -334.24427)
			(xy 419.60673 -334.251808) (xy 419.627512 -334.268563) (xy 419.664643 -334.306916) (xy 419.696065 -334.35007)
			(xy 419.721165 -334.397183) (xy 419.739452 -334.447335) (xy 419.750569 -334.499547) (xy 419.754299 -334.552799)
			(xy 419.750569 -334.60605) (xy 419.739453 -334.658262) (xy 419.721166 -334.708414) (xy 419.696067 -334.755528)
			(xy 419.664645 -334.798682) (xy 419.627513 -334.837035) (xy 419.60673 -334.853788) (xy 419.597966 -334.861347)
			(xy 419.587787 -334.882109) (xy 419.587172 -334.893666) (xy 419.587172 -334.97393) (xy 419.587757 -334.985497)
			(xy 419.597939 -335.00627) (xy 419.60673 -335.013808) (xy 419.627512 -335.030563) (xy 419.664643 -335.068916)
			(xy 419.696065 -335.11207) (xy 419.721165 -335.159183) (xy 419.739452 -335.209335) (xy 419.745683 -335.238599)
			(xy 421.403283 -335.238599) (xy 421.407013 -335.185348) (xy 421.418129 -335.133136) (xy 421.436415 -335.082984)
			(xy 421.461513 -335.03587) (xy 421.492934 -334.992715) (xy 421.530063 -334.954362) (xy 421.550846 -334.937608)
			(xy 421.559607 -334.930046) (xy 421.569789 -334.909287) (xy 421.570404 -334.89773) (xy 421.570404 -334.817466)
			(xy 421.569794 -334.805903) (xy 421.559627 -334.785132) (xy 421.550846 -334.777588) (xy 421.530062 -334.760837)
			(xy 421.492932 -334.722483) (xy 421.461512 -334.679327) (xy 421.436414 -334.632214) (xy 421.418128 -334.582062)
			(xy 421.407012 -334.52985) (xy 421.403283 -334.476599) (xy 421.407013 -334.423348) (xy 421.418129 -334.371136)
			(xy 421.436415 -334.320984) (xy 421.461513 -334.27387) (xy 421.492934 -334.230715) (xy 421.530063 -334.192362)
			(xy 421.550846 -334.175608) (xy 421.559607 -334.168046) (xy 421.569789 -334.147287) (xy 421.570404 -334.13573)
			(xy 421.570404 -334.055466) (xy 421.569794 -334.043903) (xy 421.559627 -334.023132) (xy 421.550846 -334.015588)
			(xy 421.528346 -333.997417) (xy 421.488614 -333.955392) (xy 421.455678 -333.907852) (xy 421.430293 -333.855887)
			(xy 421.41304 -333.800687) (xy 421.404314 -333.743515) (xy 421.40378 -333.714598) (xy 421.404266 -333.687347)
			(xy 421.412022 -333.633399) (xy 421.427377 -333.581104) (xy 421.450019 -333.531527) (xy 421.479485 -333.485677)
			(xy 421.515176 -333.444486) (xy 421.556367 -333.408795) (xy 421.602217 -333.379329) (xy 421.651794 -333.356687)
			(xy 421.704089 -333.341332) (xy 421.758037 -333.333576) (xy 421.812539 -333.333576) (xy 421.866487 -333.341332)
			(xy 421.918782 -333.356687) (xy 421.968359 -333.379329) (xy 422.014209 -333.408795) (xy 422.0554 -333.444486)
			(xy 422.091091 -333.485677) (xy 422.120557 -333.531527) (xy 422.143199 -333.581104) (xy 422.158554 -333.633399)
			(xy 422.16631 -333.687347) (xy 422.166796 -333.714598) (xy 422.166278 -333.743515) (xy 422.157549 -333.800686)
			(xy 422.140291 -333.855885) (xy 422.114899 -333.907847) (xy 422.081956 -333.955381) (xy 422.042215 -333.997398)
			(xy 422.01973 -334.015588) (xy 422.010966 -334.023147) (xy 422.000787 -334.043909) (xy 422.000172 -334.055466)
			(xy 422.000172 -334.13573) (xy 422.000757 -334.147297) (xy 422.010939 -334.16807) (xy 422.01973 -334.175608)
			(xy 422.040512 -334.192363) (xy 422.077643 -334.230716) (xy 422.109065 -334.27387) (xy 422.134165 -334.320983)
			(xy 422.152452 -334.371135) (xy 422.163569 -334.423347) (xy 422.167299 -334.476599) (xy 422.163569 -334.52985)
			(xy 422.152453 -334.582062) (xy 422.134166 -334.632214) (xy 422.109067 -334.679328) (xy 422.077645 -334.722482)
			(xy 422.040513 -334.760835) (xy 422.01973 -334.777588) (xy 422.010966 -334.785147) (xy 422.000787 -334.805909)
			(xy 422.000172 -334.817466) (xy 422.000172 -334.89773) (xy 422.000757 -334.909297) (xy 422.010939 -334.93007)
			(xy 422.01973 -334.937608) (xy 422.040512 -334.954363) (xy 422.077643 -334.992716) (xy 422.109065 -335.03587)
			(xy 422.134165 -335.082983) (xy 422.152452 -335.133135) (xy 422.163569 -335.185347) (xy 422.167299 -335.238599)
			(xy 425.060883 -335.238599) (xy 425.064613 -335.185348) (xy 425.075729 -335.133136) (xy 425.094015 -335.082984)
			(xy 425.119113 -335.03587) (xy 425.150534 -334.992715) (xy 425.187663 -334.954362) (xy 425.208446 -334.937608)
			(xy 425.217207 -334.930046) (xy 425.227389 -334.909287) (xy 425.228004 -334.89773) (xy 425.228004 -334.817466)
			(xy 425.227394 -334.805903) (xy 425.217227 -334.785132) (xy 425.208446 -334.777588) (xy 425.187662 -334.760837)
			(xy 425.150532 -334.722483) (xy 425.119112 -334.679327) (xy 425.094014 -334.632214) (xy 425.075728 -334.582062)
			(xy 425.064612 -334.52985) (xy 425.060883 -334.476599) (xy 425.064613 -334.423348) (xy 425.075729 -334.371136)
			(xy 425.094015 -334.320984) (xy 425.119113 -334.27387) (xy 425.150534 -334.230715) (xy 425.187663 -334.192362)
			(xy 425.208446 -334.175608) (xy 425.217207 -334.168046) (xy 425.227389 -334.147287) (xy 425.228004 -334.13573)
			(xy 425.228004 -334.055466) (xy 425.227394 -334.043903) (xy 425.217227 -334.023132) (xy 425.208446 -334.015588)
			(xy 425.185946 -333.997417) (xy 425.146214 -333.955392) (xy 425.113278 -333.907852) (xy 425.087893 -333.855887)
			(xy 425.07064 -333.800687) (xy 425.061914 -333.743515) (xy 425.06138 -333.714598) (xy 425.061866 -333.687347)
			(xy 425.069622 -333.633399) (xy 425.084977 -333.581104) (xy 425.107619 -333.531527) (xy 425.137085 -333.485677)
			(xy 425.172776 -333.444486) (xy 425.213967 -333.408795) (xy 425.259817 -333.379329) (xy 425.309394 -333.356687)
			(xy 425.361689 -333.341332) (xy 425.415637 -333.333576) (xy 425.470139 -333.333576) (xy 425.524087 -333.341332)
			(xy 425.576382 -333.356687) (xy 425.625959 -333.379329) (xy 425.671809 -333.408795) (xy 425.713 -333.444486)
			(xy 425.748691 -333.485677) (xy 425.778157 -333.531527) (xy 425.800799 -333.581104) (xy 425.816154 -333.633399)
			(xy 425.82391 -333.687347) (xy 425.824396 -333.714598) (xy 425.823878 -333.743515) (xy 425.815149 -333.800686)
			(xy 425.797891 -333.855885) (xy 425.772499 -333.907847) (xy 425.739556 -333.955381) (xy 425.699815 -333.997398)
			(xy 425.67733 -334.015588) (xy 425.668566 -334.023147) (xy 425.658387 -334.043909) (xy 425.657772 -334.055466)
			(xy 425.657772 -334.13573) (xy 425.658357 -334.147297) (xy 425.668539 -334.16807) (xy 425.67733 -334.175608)
			(xy 425.698112 -334.192363) (xy 425.735243 -334.230716) (xy 425.766665 -334.27387) (xy 425.791765 -334.320983)
			(xy 425.810052 -334.371135) (xy 425.821169 -334.423347) (xy 425.824899 -334.476599) (xy 425.821169 -334.52985)
			(xy 425.810053 -334.582062) (xy 425.791766 -334.632214) (xy 425.766667 -334.679328) (xy 425.735245 -334.722482)
			(xy 425.698113 -334.760835) (xy 425.67733 -334.777588) (xy 425.668566 -334.785147) (xy 425.658387 -334.805909)
			(xy 425.657772 -334.817466) (xy 425.657772 -334.89773) (xy 425.658357 -334.909297) (xy 425.668539 -334.93007)
			(xy 425.67733 -334.937608) (xy 425.698112 -334.954363) (xy 425.735243 -334.992716) (xy 425.766665 -335.03587)
			(xy 425.791765 -335.082983) (xy 425.810052 -335.133135) (xy 425.821169 -335.185347) (xy 425.824899 -335.238599)
			(xy 427.524683 -335.238599) (xy 427.528413 -335.185348) (xy 427.539529 -335.133136) (xy 427.557815 -335.082984)
			(xy 427.582913 -335.03587) (xy 427.614334 -334.992715) (xy 427.651463 -334.954362) (xy 427.672246 -334.937608)
			(xy 427.681007 -334.930046) (xy 427.691189 -334.909287) (xy 427.691804 -334.89773) (xy 427.691804 -334.817466)
			(xy 427.691194 -334.805903) (xy 427.681027 -334.785132) (xy 427.672246 -334.777588) (xy 427.651462 -334.760837)
			(xy 427.614332 -334.722483) (xy 427.582912 -334.679327) (xy 427.557814 -334.632214) (xy 427.539528 -334.582062)
			(xy 427.528412 -334.52985) (xy 427.524683 -334.476599) (xy 427.528413 -334.423348) (xy 427.539529 -334.371136)
			(xy 427.557815 -334.320984) (xy 427.582913 -334.27387) (xy 427.614334 -334.230715) (xy 427.651463 -334.192362)
			(xy 427.672246 -334.175608) (xy 427.681007 -334.168046) (xy 427.691189 -334.147287) (xy 427.691804 -334.13573)
			(xy 427.691804 -334.055466) (xy 427.691194 -334.043903) (xy 427.681027 -334.023132) (xy 427.672246 -334.015588)
			(xy 427.649746 -333.997417) (xy 427.610014 -333.955392) (xy 427.577078 -333.907852) (xy 427.551693 -333.855887)
			(xy 427.53444 -333.800687) (xy 427.525714 -333.743515) (xy 427.52518 -333.714598) (xy 427.525666 -333.687347)
			(xy 427.533422 -333.633399) (xy 427.548777 -333.581104) (xy 427.571419 -333.531527) (xy 427.600885 -333.485677)
			(xy 427.636576 -333.444486) (xy 427.677767 -333.408795) (xy 427.723617 -333.379329) (xy 427.773194 -333.356687)
			(xy 427.825489 -333.341332) (xy 427.879437 -333.333576) (xy 427.933939 -333.333576) (xy 427.987887 -333.341332)
			(xy 428.040182 -333.356687) (xy 428.089759 -333.379329) (xy 428.135609 -333.408795) (xy 428.1768 -333.444486)
			(xy 428.212491 -333.485677) (xy 428.241957 -333.531527) (xy 428.264599 -333.581104) (xy 428.279954 -333.633399)
			(xy 428.28771 -333.687347) (xy 428.288196 -333.714598) (xy 428.287678 -333.743515) (xy 428.278949 -333.800686)
			(xy 428.261691 -333.855885) (xy 428.236299 -333.907847) (xy 428.203356 -333.955381) (xy 428.163615 -333.997398)
			(xy 428.14113 -334.015588) (xy 428.132366 -334.023147) (xy 428.122187 -334.043909) (xy 428.121572 -334.055466)
			(xy 428.121572 -334.13573) (xy 428.122157 -334.147297) (xy 428.132339 -334.16807) (xy 428.14113 -334.175608)
			(xy 428.161912 -334.192363) (xy 428.199043 -334.230716) (xy 428.230465 -334.27387) (xy 428.255565 -334.320983)
			(xy 428.273852 -334.371135) (xy 428.284969 -334.423347) (xy 428.288699 -334.476599) (xy 428.284969 -334.52985)
			(xy 428.273853 -334.582062) (xy 428.255566 -334.632214) (xy 428.230467 -334.679328) (xy 428.199045 -334.722482)
			(xy 428.161913 -334.760835) (xy 428.14113 -334.777588) (xy 428.132366 -334.785147) (xy 428.122187 -334.805909)
			(xy 428.121572 -334.817466) (xy 428.121572 -334.89773) (xy 428.122157 -334.909297) (xy 428.132339 -334.93007)
			(xy 428.14113 -334.937608) (xy 428.161912 -334.954363) (xy 428.199043 -334.992716) (xy 428.230465 -335.03587)
			(xy 428.255565 -335.082983) (xy 428.273852 -335.133135) (xy 428.284969 -335.185347) (xy 428.28692 -335.213199)
			(xy 431.182283 -335.213199) (xy 431.186013 -335.159948) (xy 431.197129 -335.107736) (xy 431.215415 -335.057584)
			(xy 431.240513 -335.01047) (xy 431.271934 -334.967315) (xy 431.309063 -334.928962) (xy 431.329846 -334.912208)
			(xy 431.338607 -334.904646) (xy 431.348789 -334.883887) (xy 431.349404 -334.87233) (xy 431.349404 -334.792066)
			(xy 431.348794 -334.780503) (xy 431.338627 -334.759732) (xy 431.329846 -334.752188) (xy 431.309062 -334.735437)
			(xy 431.271932 -334.697083) (xy 431.240512 -334.653927) (xy 431.215414 -334.606814) (xy 431.197128 -334.556662)
			(xy 431.186012 -334.50445) (xy 431.182283 -334.451199) (xy 431.186013 -334.397948) (xy 431.197129 -334.345736)
			(xy 431.215415 -334.295584) (xy 431.240513 -334.24847) (xy 431.271934 -334.205315) (xy 431.309063 -334.166962)
			(xy 431.329846 -334.150208) (xy 431.338607 -334.142646) (xy 431.348789 -334.121887) (xy 431.349404 -334.11033)
			(xy 431.349404 -334.030066) (xy 431.348794 -334.018503) (xy 431.338627 -333.997732) (xy 431.329846 -333.990188)
			(xy 431.307346 -333.972017) (xy 431.267614 -333.929992) (xy 431.234678 -333.882452) (xy 431.209293 -333.830487)
			(xy 431.19204 -333.775287) (xy 431.183314 -333.718115) (xy 431.18278 -333.689198) (xy 431.183266 -333.661947)
			(xy 431.191022 -333.607999) (xy 431.206377 -333.555704) (xy 431.229019 -333.506127) (xy 431.258485 -333.460277)
			(xy 431.294176 -333.419086) (xy 431.335367 -333.383395) (xy 431.381217 -333.353929) (xy 431.430794 -333.331287)
			(xy 431.483089 -333.315932) (xy 431.537037 -333.308176) (xy 431.591539 -333.308176) (xy 431.645487 -333.315932)
			(xy 431.697782 -333.331287) (xy 431.747359 -333.353929) (xy 431.793209 -333.383395) (xy 431.8344 -333.419086)
			(xy 431.870091 -333.460277) (xy 431.899557 -333.506127) (xy 431.922199 -333.555704) (xy 431.937554 -333.607999)
			(xy 431.94531 -333.661947) (xy 431.945796 -333.689198) (xy 431.945278 -333.718115) (xy 431.936549 -333.775286)
			(xy 431.919291 -333.830485) (xy 431.893899 -333.882447) (xy 431.860956 -333.929981) (xy 431.821215 -333.971998)
			(xy 431.79873 -333.990188) (xy 431.789966 -333.997747) (xy 431.779787 -334.018509) (xy 431.779172 -334.030066)
			(xy 431.779172 -334.11033) (xy 431.779757 -334.121897) (xy 431.789939 -334.14267) (xy 431.79873 -334.150208)
			(xy 431.819512 -334.166963) (xy 431.856643 -334.205316) (xy 431.888065 -334.24847) (xy 431.913165 -334.295583)
			(xy 431.931452 -334.345735) (xy 431.942569 -334.397947) (xy 431.946299 -334.451199) (xy 431.942569 -334.50445)
			(xy 431.931453 -334.556662) (xy 431.913166 -334.606814) (xy 431.888067 -334.653928) (xy 431.856645 -334.697082)
			(xy 431.819513 -334.735435) (xy 431.79873 -334.752188) (xy 431.789966 -334.759747) (xy 431.779787 -334.780509)
			(xy 431.779172 -334.792066) (xy 431.779172 -334.87233) (xy 431.779757 -334.883897) (xy 431.789939 -334.90467)
			(xy 431.79873 -334.912208) (xy 431.819512 -334.928963) (xy 431.856643 -334.967316) (xy 431.888065 -335.01047)
			(xy 431.913165 -335.057583) (xy 431.931452 -335.107735) (xy 431.942569 -335.159947) (xy 431.946299 -335.213199)
			(xy 433.620683 -335.213199) (xy 433.624413 -335.159948) (xy 433.635529 -335.107736) (xy 433.653815 -335.057584)
			(xy 433.678913 -335.01047) (xy 433.710334 -334.967315) (xy 433.747463 -334.928962) (xy 433.768246 -334.912208)
			(xy 433.777007 -334.904646) (xy 433.787189 -334.883887) (xy 433.787804 -334.87233) (xy 433.787804 -334.792066)
			(xy 433.787194 -334.780503) (xy 433.777027 -334.759732) (xy 433.768246 -334.752188) (xy 433.747462 -334.735437)
			(xy 433.710332 -334.697083) (xy 433.678912 -334.653927) (xy 433.653814 -334.606814) (xy 433.635528 -334.556662)
			(xy 433.624412 -334.50445) (xy 433.620683 -334.451199) (xy 433.624413 -334.397948) (xy 433.635529 -334.345736)
			(xy 433.653815 -334.295584) (xy 433.678913 -334.24847) (xy 433.710334 -334.205315) (xy 433.747463 -334.166962)
			(xy 433.768246 -334.150208) (xy 433.777007 -334.142646) (xy 433.787189 -334.121887) (xy 433.787804 -334.11033)
			(xy 433.787804 -334.030066) (xy 433.787194 -334.018503) (xy 433.777027 -333.997732) (xy 433.768246 -333.990188)
			(xy 433.745746 -333.972017) (xy 433.706014 -333.929992) (xy 433.673078 -333.882452) (xy 433.647693 -333.830487)
			(xy 433.63044 -333.775287) (xy 433.621714 -333.718115) (xy 433.62118 -333.689198) (xy 433.621666 -333.661947)
			(xy 433.629422 -333.607999) (xy 433.644777 -333.555704) (xy 433.667419 -333.506127) (xy 433.696885 -333.460277)
			(xy 433.732576 -333.419086) (xy 433.773767 -333.383395) (xy 433.819617 -333.353929) (xy 433.869194 -333.331287)
			(xy 433.921489 -333.315932) (xy 433.975437 -333.308176) (xy 434.029939 -333.308176) (xy 434.083887 -333.315932)
			(xy 434.136182 -333.331287) (xy 434.185759 -333.353929) (xy 434.231609 -333.383395) (xy 434.2728 -333.419086)
			(xy 434.308491 -333.460277) (xy 434.337957 -333.506127) (xy 434.360599 -333.555704) (xy 434.375954 -333.607999)
			(xy 434.38371 -333.661947) (xy 434.384196 -333.689198) (xy 434.383678 -333.718115) (xy 434.374949 -333.775286)
			(xy 434.357691 -333.830485) (xy 434.332299 -333.882447) (xy 434.299356 -333.929981) (xy 434.259615 -333.971998)
			(xy 434.23713 -333.990188) (xy 434.228366 -333.997747) (xy 434.218187 -334.018509) (xy 434.217572 -334.030066)
			(xy 434.217572 -334.11033) (xy 434.218157 -334.121897) (xy 434.228339 -334.14267) (xy 434.23713 -334.150208)
			(xy 434.257912 -334.166963) (xy 434.295043 -334.205316) (xy 434.326465 -334.24847) (xy 434.351565 -334.295583)
			(xy 434.369852 -334.345735) (xy 434.380969 -334.397947) (xy 434.384699 -334.451199) (xy 434.380969 -334.50445)
			(xy 434.369853 -334.556662) (xy 434.351566 -334.606814) (xy 434.326467 -334.653928) (xy 434.295045 -334.697082)
			(xy 434.257913 -334.735435) (xy 434.23713 -334.752188) (xy 434.228366 -334.759747) (xy 434.218187 -334.780509)
			(xy 434.217572 -334.792066) (xy 434.217572 -334.87233) (xy 434.218157 -334.883897) (xy 434.228339 -334.90467)
			(xy 434.23713 -334.912208) (xy 434.257912 -334.928963) (xy 434.295043 -334.967316) (xy 434.326465 -335.01047)
			(xy 434.351565 -335.057583) (xy 434.361999 -335.086199) (xy 437.176683 -335.086199) (xy 437.180413 -335.032948)
			(xy 437.191529 -334.980736) (xy 437.209815 -334.930584) (xy 437.234913 -334.88347) (xy 437.266334 -334.840315)
			(xy 437.303463 -334.801962) (xy 437.324246 -334.785208) (xy 437.333007 -334.777646) (xy 437.343189 -334.756887)
			(xy 437.343804 -334.74533) (xy 437.343804 -334.665066) (xy 437.343194 -334.653503) (xy 437.333027 -334.632732)
			(xy 437.324246 -334.625188) (xy 437.303462 -334.608437) (xy 437.266332 -334.570083) (xy 437.234912 -334.526927)
			(xy 437.209814 -334.479814) (xy 437.191528 -334.429662) (xy 437.180412 -334.37745) (xy 437.176683 -334.324199)
			(xy 437.180413 -334.270948) (xy 437.191529 -334.218736) (xy 437.209815 -334.168584) (xy 437.234913 -334.12147)
			(xy 437.266334 -334.078315) (xy 437.303463 -334.039962) (xy 437.324246 -334.023208) (xy 437.333007 -334.015646)
			(xy 437.343189 -333.994887) (xy 437.343804 -333.98333) (xy 437.343804 -333.903066) (xy 437.343194 -333.891503)
			(xy 437.333027 -333.870732) (xy 437.324246 -333.863188) (xy 437.301746 -333.845017) (xy 437.262014 -333.802992)
			(xy 437.229078 -333.755452) (xy 437.203693 -333.703487) (xy 437.18644 -333.648287) (xy 437.177714 -333.591115)
			(xy 437.17718 -333.562198) (xy 437.177666 -333.534947) (xy 437.185422 -333.480999) (xy 437.200777 -333.428704)
			(xy 437.223419 -333.379127) (xy 437.252885 -333.333277) (xy 437.288576 -333.292086) (xy 437.329767 -333.256395)
			(xy 437.375617 -333.226929) (xy 437.425194 -333.204287) (xy 437.477489 -333.188932) (xy 437.531437 -333.181176)
			(xy 437.585939 -333.181176) (xy 437.639887 -333.188932) (xy 437.692182 -333.204287) (xy 437.741759 -333.226929)
			(xy 437.787609 -333.256395) (xy 437.8288 -333.292086) (xy 437.864491 -333.333277) (xy 437.893957 -333.379127)
			(xy 437.916599 -333.428704) (xy 437.931954 -333.480999) (xy 437.93971 -333.534947) (xy 437.940196 -333.562198)
			(xy 437.939678 -333.591115) (xy 437.930949 -333.648286) (xy 437.913691 -333.703485) (xy 437.888299 -333.755447)
			(xy 437.855356 -333.802981) (xy 437.815615 -333.844998) (xy 437.79313 -333.863188) (xy 437.784366 -333.870747)
			(xy 437.774187 -333.891509) (xy 437.773572 -333.903066) (xy 437.773572 -333.98333) (xy 437.774157 -333.994897)
			(xy 437.784339 -334.01567) (xy 437.79313 -334.023208) (xy 437.813912 -334.039963) (xy 437.851043 -334.078316)
			(xy 437.882465 -334.12147) (xy 437.907565 -334.168583) (xy 437.925852 -334.218735) (xy 437.936969 -334.270947)
			(xy 437.940699 -334.324199) (xy 437.936969 -334.37745) (xy 437.925853 -334.429662) (xy 437.907566 -334.479814)
			(xy 437.882467 -334.526928) (xy 437.851045 -334.570082) (xy 437.813913 -334.608435) (xy 437.79313 -334.625188)
			(xy 437.784366 -334.632747) (xy 437.774187 -334.653509) (xy 437.773572 -334.665066) (xy 437.773572 -334.74533)
			(xy 437.774157 -334.756897) (xy 437.784339 -334.77767) (xy 437.79313 -334.785208) (xy 437.813912 -334.801963)
			(xy 437.851043 -334.840316) (xy 437.882465 -334.88347) (xy 437.907565 -334.930583) (xy 437.925852 -334.980735)
			(xy 437.93587 -335.027786) (xy 439.724279 -335.027786) (xy 439.728011 -334.974532) (xy 439.739131 -334.922319)
			(xy 439.75742 -334.872165) (xy 439.782522 -334.82505) (xy 439.813947 -334.781895) (xy 439.851081 -334.743541)
			(xy 439.871866 -334.726788) (xy 439.88064 -334.719238) (xy 439.890814 -334.69847) (xy 439.891424 -334.68691)
			(xy 439.891424 -334.606646) (xy 439.890853 -334.595077) (xy 439.880662 -334.574305) (xy 439.871866 -334.566768)
			(xy 439.851061 -334.550041) (xy 439.81393 -334.511685) (xy 439.782508 -334.468527) (xy 439.757409 -334.421411)
			(xy 439.739123 -334.371255) (xy 439.728008 -334.319041) (xy 439.724279 -334.265786) (xy 439.728011 -334.212532)
			(xy 439.739131 -334.160319) (xy 439.75742 -334.110165) (xy 439.782522 -334.06305) (xy 439.813947 -334.019895)
			(xy 439.851081 -333.981541) (xy 439.871866 -333.964788) (xy 439.88064 -333.957238) (xy 439.890814 -333.93647)
			(xy 439.891424 -333.92491) (xy 439.891424 -333.844646) (xy 439.890853 -333.833077) (xy 439.880662 -333.812305)
			(xy 439.871866 -333.804768) (xy 439.84936 -333.786604) (xy 439.809628 -333.744577) (xy 439.776692 -333.697037)
			(xy 439.751308 -333.64507) (xy 439.734057 -333.589868) (xy 439.725332 -333.532695) (xy 439.7248 -333.503778)
			(xy 439.725286 -333.476527) (xy 439.733042 -333.422579) (xy 439.748397 -333.370284) (xy 439.771039 -333.320707)
			(xy 439.800505 -333.274857) (xy 439.836196 -333.233666) (xy 439.877387 -333.197975) (xy 439.923237 -333.168509)
			(xy 439.972814 -333.145867) (xy 440.025109 -333.130512) (xy 440.079057 -333.122756) (xy 440.133559 -333.122756)
			(xy 440.187507 -333.130512) (xy 440.239802 -333.145867) (xy 440.289379 -333.168509) (xy 440.335229 -333.197975)
			(xy 440.37642 -333.233666) (xy 440.412111 -333.274857) (xy 440.441577 -333.320707) (xy 440.464219 -333.370284)
			(xy 440.479574 -333.422579) (xy 440.48733 -333.476527) (xy 440.487816 -333.503778) (xy 440.487314 -333.532696)
			(xy 440.478586 -333.589869) (xy 440.461327 -333.64507) (xy 440.435932 -333.697032) (xy 440.402984 -333.744565)
			(xy 440.363238 -333.78658) (xy 440.34075 -333.804768) (xy 440.331998 -333.812339) (xy 440.321811 -333.833091)
			(xy 440.321192 -333.844646) (xy 440.321192 -333.92491) (xy 440.32176 -333.936478) (xy 440.331957 -333.957249)
			(xy 440.34075 -333.964788) (xy 440.361511 -333.981567) (xy 440.39864 -334.019918) (xy 440.430061 -334.06307)
			(xy 440.45516 -334.11018) (xy 440.473447 -334.160329) (xy 440.484564 -334.212538) (xy 440.488296 -334.265786)
			(xy 440.484568 -334.319035) (xy 440.473454 -334.371245) (xy 440.455171 -334.421395) (xy 440.430075 -334.468507)
			(xy 440.398658 -334.511661) (xy 440.361531 -334.550014) (xy 440.34075 -334.566768) (xy 440.331998 -334.574339)
			(xy 440.321811 -334.595091) (xy 440.321192 -334.606646) (xy 440.321192 -334.68691) (xy 440.32176 -334.698478)
			(xy 440.331957 -334.719249) (xy 440.34075 -334.726788) (xy 440.361511 -334.743567) (xy 440.39864 -334.781918)
			(xy 440.430061 -334.82507) (xy 440.45516 -334.87218) (xy 440.473447 -334.922329) (xy 440.484564 -334.974538)
			(xy 440.488296 -335.027786) (xy 440.484568 -335.081035) (xy 440.473454 -335.133245) (xy 440.455171 -335.183395)
			(xy 440.430075 -335.230507) (xy 440.398658 -335.273661) (xy 440.361531 -335.312014) (xy 440.34075 -335.328768)
			(xy 440.331998 -335.336339) (xy 440.321811 -335.357091) (xy 440.321192 -335.368646) (xy 440.321192 -335.44891)
			(xy 440.32176 -335.460478) (xy 440.331957 -335.481249) (xy 440.34075 -335.488788) (xy 440.363238 -335.506973)
			(xy 440.402971 -335.548996) (xy 440.435908 -335.596532) (xy 440.461295 -335.648494) (xy 440.478551 -335.703692)
			(xy 440.48728 -335.760862) (xy 440.487816 -335.789778) (xy 440.48733 -335.817029) (xy 440.479574 -335.870977)
			(xy 440.464219 -335.923272) (xy 440.441577 -335.972849) (xy 440.412111 -336.018699) (xy 440.37642 -336.05989)
			(xy 440.335229 -336.095581) (xy 440.289379 -336.125047) (xy 440.239802 -336.147689) (xy 440.187507 -336.163044)
			(xy 440.133559 -336.1708) (xy 440.079057 -336.1708) (xy 440.025109 -336.163044) (xy 439.972814 -336.147689)
			(xy 439.923237 -336.125047) (xy 439.877387 -336.095581) (xy 439.836196 -336.05989) (xy 439.800505 -336.018699)
			(xy 439.771039 -335.972849) (xy 439.748397 -335.923272) (xy 439.733042 -335.870977) (xy 439.725286 -335.817029)
			(xy 439.7248 -335.789778) (xy 439.725374 -335.760863) (xy 439.734092 -335.703695) (xy 439.751338 -335.648497)
			(xy 439.77672 -335.596535) (xy 439.809653 -335.548999) (xy 439.849385 -335.50698) (xy 439.871866 -335.488788)
			(xy 439.88064 -335.481238) (xy 439.890814 -335.46047) (xy 439.891424 -335.44891) (xy 439.891424 -335.368646)
			(xy 439.890853 -335.357077) (xy 439.880662 -335.336305) (xy 439.871866 -335.328768) (xy 439.851061 -335.312041)
			(xy 439.81393 -335.273685) (xy 439.782508 -335.230527) (xy 439.757409 -335.183411) (xy 439.739123 -335.133255)
			(xy 439.728008 -335.081041) (xy 439.724279 -335.027786) (xy 437.93587 -335.027786) (xy 437.936969 -335.032947)
			(xy 437.940699 -335.086199) (xy 437.936969 -335.13945) (xy 437.925853 -335.191662) (xy 437.907566 -335.241814)
			(xy 437.882467 -335.288928) (xy 437.851045 -335.332082) (xy 437.813913 -335.370435) (xy 437.79313 -335.387188)
			(xy 437.784366 -335.394747) (xy 437.774187 -335.415509) (xy 437.773572 -335.427066) (xy 437.773572 -335.50733)
			(xy 437.774157 -335.518897) (xy 437.784339 -335.53967) (xy 437.79313 -335.547208) (xy 437.815624 -335.565387)
			(xy 437.855357 -335.60741) (xy 437.888294 -335.654948) (xy 437.91368 -335.706911) (xy 437.930934 -335.762111)
			(xy 437.939662 -335.819281) (xy 437.940196 -335.848198) (xy 437.93971 -335.875449) (xy 437.931954 -335.929397)
			(xy 437.916599 -335.981692) (xy 437.893957 -336.031269) (xy 437.864491 -336.077119) (xy 437.8288 -336.11831)
			(xy 437.787609 -336.154001) (xy 437.741759 -336.183467) (xy 437.692182 -336.206109) (xy 437.639887 -336.221464)
			(xy 437.585939 -336.22922) (xy 437.531437 -336.22922) (xy 437.477489 -336.221464) (xy 437.425194 -336.206109)
			(xy 437.375617 -336.183467) (xy 437.329767 -336.154001) (xy 437.288576 -336.11831) (xy 437.252885 -336.077119)
			(xy 437.223419 -336.031269) (xy 437.200777 -335.981692) (xy 437.185422 -335.929397) (xy 437.177666 -335.875449)
			(xy 437.17718 -335.848198) (xy 437.177667 -335.81928) (xy 437.186398 -335.762105) (xy 437.20366 -335.706905)
			(xy 437.229058 -335.654942) (xy 437.262008 -335.60741) (xy 437.301757 -335.565396) (xy 437.324246 -335.547208)
			(xy 437.333007 -335.539646) (xy 437.343189 -335.518887) (xy 437.343804 -335.50733) (xy 437.343804 -335.427066)
			(xy 437.343194 -335.415503) (xy 437.333027 -335.394732) (xy 437.324246 -335.387188) (xy 437.303462 -335.370437)
			(xy 437.266332 -335.332083) (xy 437.234912 -335.288927) (xy 437.209814 -335.241814) (xy 437.191528 -335.191662)
			(xy 437.180412 -335.13945) (xy 437.176683 -335.086199) (xy 434.361999 -335.086199) (xy 434.369852 -335.107735)
			(xy 434.380969 -335.159947) (xy 434.384699 -335.213199) (xy 434.380969 -335.26645) (xy 434.369853 -335.318662)
			(xy 434.351566 -335.368814) (xy 434.326467 -335.415928) (xy 434.295045 -335.459082) (xy 434.257913 -335.497435)
			(xy 434.23713 -335.514188) (xy 434.228366 -335.521747) (xy 434.218187 -335.542509) (xy 434.217572 -335.554066)
			(xy 434.217572 -335.63433) (xy 434.218157 -335.645897) (xy 434.228339 -335.66667) (xy 434.23713 -335.674208)
			(xy 434.259624 -335.692387) (xy 434.299357 -335.73441) (xy 434.332294 -335.781948) (xy 434.35768 -335.833911)
			(xy 434.374934 -335.889111) (xy 434.383662 -335.946281) (xy 434.384196 -335.975198) (xy 434.38371 -336.002449)
			(xy 434.375954 -336.056397) (xy 434.360599 -336.108692) (xy 434.337957 -336.158269) (xy 434.308491 -336.204119)
			(xy 434.2728 -336.24531) (xy 434.231609 -336.281001) (xy 434.185759 -336.310467) (xy 434.136182 -336.333109)
			(xy 434.083887 -336.348464) (xy 434.029939 -336.35622) (xy 433.975437 -336.35622) (xy 433.921489 -336.348464)
			(xy 433.869194 -336.333109) (xy 433.819617 -336.310467) (xy 433.773767 -336.281001) (xy 433.732576 -336.24531)
			(xy 433.696885 -336.204119) (xy 433.667419 -336.158269) (xy 433.644777 -336.108692) (xy 433.629422 -336.056397)
			(xy 433.621666 -336.002449) (xy 433.62118 -335.975198) (xy 433.621667 -335.94628) (xy 433.630398 -335.889105)
			(xy 433.64766 -335.833905) (xy 433.673058 -335.781942) (xy 433.706008 -335.73441) (xy 433.745757 -335.692396)
			(xy 433.768246 -335.674208) (xy 433.777007 -335.666646) (xy 433.787189 -335.645887) (xy 433.787804 -335.63433)
			(xy 433.787804 -335.554066) (xy 433.787194 -335.542503) (xy 433.777027 -335.521732) (xy 433.768246 -335.514188)
			(xy 433.747462 -335.497437) (xy 433.710332 -335.459083) (xy 433.678912 -335.415927) (xy 433.653814 -335.368814)
			(xy 433.635528 -335.318662) (xy 433.624412 -335.26645) (xy 433.620683 -335.213199) (xy 431.946299 -335.213199)
			(xy 431.942569 -335.26645) (xy 431.931453 -335.318662) (xy 431.913166 -335.368814) (xy 431.888067 -335.415928)
			(xy 431.856645 -335.459082) (xy 431.819513 -335.497435) (xy 431.79873 -335.514188) (xy 431.789966 -335.521747)
			(xy 431.779787 -335.542509) (xy 431.779172 -335.554066) (xy 431.779172 -335.63433) (xy 431.779757 -335.645897)
			(xy 431.789939 -335.66667) (xy 431.79873 -335.674208) (xy 431.821224 -335.692387) (xy 431.860957 -335.73441)
			(xy 431.893894 -335.781948) (xy 431.91928 -335.833911) (xy 431.936534 -335.889111) (xy 431.945262 -335.946281)
			(xy 431.945796 -335.975198) (xy 431.94531 -336.002449) (xy 431.937554 -336.056397) (xy 431.922199 -336.108692)
			(xy 431.899557 -336.158269) (xy 431.870091 -336.204119) (xy 431.8344 -336.24531) (xy 431.793209 -336.281001)
			(xy 431.747359 -336.310467) (xy 431.697782 -336.333109) (xy 431.645487 -336.348464) (xy 431.591539 -336.35622)
			(xy 431.537037 -336.35622) (xy 431.483089 -336.348464) (xy 431.430794 -336.333109) (xy 431.381217 -336.310467)
			(xy 431.335367 -336.281001) (xy 431.294176 -336.24531) (xy 431.258485 -336.204119) (xy 431.229019 -336.158269)
			(xy 431.206377 -336.108692) (xy 431.191022 -336.056397) (xy 431.183266 -336.002449) (xy 431.18278 -335.975198)
			(xy 431.183267 -335.94628) (xy 431.191998 -335.889105) (xy 431.20926 -335.833905) (xy 431.234658 -335.781942)
			(xy 431.267608 -335.73441) (xy 431.307357 -335.692396) (xy 431.329846 -335.674208) (xy 431.338607 -335.666646)
			(xy 431.348789 -335.645887) (xy 431.349404 -335.63433) (xy 431.349404 -335.554066) (xy 431.348794 -335.542503)
			(xy 431.338627 -335.521732) (xy 431.329846 -335.514188) (xy 431.309062 -335.497437) (xy 431.271932 -335.459083)
			(xy 431.240512 -335.415927) (xy 431.215414 -335.368814) (xy 431.197128 -335.318662) (xy 431.186012 -335.26645)
			(xy 431.182283 -335.213199) (xy 428.28692 -335.213199) (xy 428.288699 -335.238599) (xy 428.284969 -335.29185)
			(xy 428.273853 -335.344062) (xy 428.255566 -335.394214) (xy 428.230467 -335.441328) (xy 428.199045 -335.484482)
			(xy 428.161913 -335.522835) (xy 428.14113 -335.539588) (xy 428.132366 -335.547147) (xy 428.122187 -335.567909)
			(xy 428.121572 -335.579466) (xy 428.121572 -335.65973) (xy 428.122157 -335.671297) (xy 428.132339 -335.69207)
			(xy 428.14113 -335.699608) (xy 428.163624 -335.717787) (xy 428.203357 -335.75981) (xy 428.236294 -335.807348)
			(xy 428.26168 -335.859311) (xy 428.278934 -335.914511) (xy 428.287662 -335.971681) (xy 428.288196 -336.000598)
			(xy 428.28771 -336.027849) (xy 428.279954 -336.081797) (xy 428.264599 -336.134092) (xy 428.241957 -336.183669)
			(xy 428.212491 -336.229519) (xy 428.1768 -336.27071) (xy 428.135609 -336.306401) (xy 428.089759 -336.335867)
			(xy 428.040182 -336.358509) (xy 427.987887 -336.373864) (xy 427.933939 -336.38162) (xy 427.879437 -336.38162)
			(xy 427.825489 -336.373864) (xy 427.773194 -336.358509) (xy 427.723617 -336.335867) (xy 427.677767 -336.306401)
			(xy 427.636576 -336.27071) (xy 427.600885 -336.229519) (xy 427.571419 -336.183669) (xy 427.548777 -336.134092)
			(xy 427.533422 -336.081797) (xy 427.525666 -336.027849) (xy 427.52518 -336.000598) (xy 427.525667 -335.97168)
			(xy 427.534398 -335.914505) (xy 427.55166 -335.859305) (xy 427.577058 -335.807342) (xy 427.610008 -335.75981)
			(xy 427.649757 -335.717796) (xy 427.672246 -335.699608) (xy 427.681007 -335.692046) (xy 427.691189 -335.671287)
			(xy 427.691804 -335.65973) (xy 427.691804 -335.579466) (xy 427.691194 -335.567903) (xy 427.681027 -335.547132)
			(xy 427.672246 -335.539588) (xy 427.651462 -335.522837) (xy 427.614332 -335.484483) (xy 427.582912 -335.441327)
			(xy 427.557814 -335.394214) (xy 427.539528 -335.344062) (xy 427.528412 -335.29185) (xy 427.524683 -335.238599)
			(xy 425.824899 -335.238599) (xy 425.821169 -335.29185) (xy 425.810053 -335.344062) (xy 425.791766 -335.394214)
			(xy 425.766667 -335.441328) (xy 425.735245 -335.484482) (xy 425.698113 -335.522835) (xy 425.67733 -335.539588)
			(xy 425.668566 -335.547147) (xy 425.658387 -335.567909) (xy 425.657772 -335.579466) (xy 425.657772 -335.65973)
			(xy 425.658357 -335.671297) (xy 425.668539 -335.69207) (xy 425.67733 -335.699608) (xy 425.699824 -335.717787)
			(xy 425.739557 -335.75981) (xy 425.772494 -335.807348) (xy 425.79788 -335.859311) (xy 425.815134 -335.914511)
			(xy 425.823862 -335.971681) (xy 425.824396 -336.000598) (xy 425.82391 -336.027849) (xy 425.816154 -336.081797)
			(xy 425.800799 -336.134092) (xy 425.778157 -336.183669) (xy 425.748691 -336.229519) (xy 425.713 -336.27071)
			(xy 425.671809 -336.306401) (xy 425.625959 -336.335867) (xy 425.576382 -336.358509) (xy 425.524087 -336.373864)
			(xy 425.470139 -336.38162) (xy 425.415637 -336.38162) (xy 425.361689 -336.373864) (xy 425.309394 -336.358509)
			(xy 425.259817 -336.335867) (xy 425.213967 -336.306401) (xy 425.172776 -336.27071) (xy 425.137085 -336.229519)
			(xy 425.107619 -336.183669) (xy 425.084977 -336.134092) (xy 425.069622 -336.081797) (xy 425.061866 -336.027849)
			(xy 425.06138 -336.000598) (xy 425.061867 -335.97168) (xy 425.070598 -335.914505) (xy 425.08786 -335.859305)
			(xy 425.113258 -335.807342) (xy 425.146208 -335.75981) (xy 425.185957 -335.717796) (xy 425.208446 -335.699608)
			(xy 425.217207 -335.692046) (xy 425.227389 -335.671287) (xy 425.228004 -335.65973) (xy 425.228004 -335.579466)
			(xy 425.227394 -335.567903) (xy 425.217227 -335.547132) (xy 425.208446 -335.539588) (xy 425.187662 -335.522837)
			(xy 425.150532 -335.484483) (xy 425.119112 -335.441327) (xy 425.094014 -335.394214) (xy 425.075728 -335.344062)
			(xy 425.064612 -335.29185) (xy 425.060883 -335.238599) (xy 422.167299 -335.238599) (xy 422.163569 -335.29185)
			(xy 422.152453 -335.344062) (xy 422.134166 -335.394214) (xy 422.109067 -335.441328) (xy 422.077645 -335.484482)
			(xy 422.040513 -335.522835) (xy 422.01973 -335.539588) (xy 422.010966 -335.547147) (xy 422.000787 -335.567909)
			(xy 422.000172 -335.579466) (xy 422.000172 -335.65973) (xy 422.000757 -335.671297) (xy 422.010939 -335.69207)
			(xy 422.01973 -335.699608) (xy 422.042224 -335.717787) (xy 422.081957 -335.75981) (xy 422.114894 -335.807348)
			(xy 422.14028 -335.859311) (xy 422.157534 -335.914511) (xy 422.166262 -335.971681) (xy 422.166796 -336.000598)
			(xy 422.16631 -336.027849) (xy 422.158554 -336.081797) (xy 422.143199 -336.134092) (xy 422.120557 -336.183669)
			(xy 422.091091 -336.229519) (xy 422.0554 -336.27071) (xy 422.014209 -336.306401) (xy 421.968359 -336.335867)
			(xy 421.918782 -336.358509) (xy 421.866487 -336.373864) (xy 421.812539 -336.38162) (xy 421.758037 -336.38162)
			(xy 421.704089 -336.373864) (xy 421.651794 -336.358509) (xy 421.602217 -336.335867) (xy 421.556367 -336.306401)
			(xy 421.515176 -336.27071) (xy 421.479485 -336.229519) (xy 421.450019 -336.183669) (xy 421.427377 -336.134092)
			(xy 421.412022 -336.081797) (xy 421.404266 -336.027849) (xy 421.40378 -336.000598) (xy 421.404267 -335.97168)
			(xy 421.412998 -335.914505) (xy 421.43026 -335.859305) (xy 421.455658 -335.807342) (xy 421.488608 -335.75981)
			(xy 421.528357 -335.717796) (xy 421.550846 -335.699608) (xy 421.559607 -335.692046) (xy 421.569789 -335.671287)
			(xy 421.570404 -335.65973) (xy 421.570404 -335.579466) (xy 421.569794 -335.567903) (xy 421.559627 -335.547132)
			(xy 421.550846 -335.539588) (xy 421.530062 -335.522837) (xy 421.492932 -335.484483) (xy 421.461512 -335.441327)
			(xy 421.436414 -335.394214) (xy 421.418128 -335.344062) (xy 421.407012 -335.29185) (xy 421.403283 -335.238599)
			(xy 419.745683 -335.238599) (xy 419.750569 -335.261547) (xy 419.754299 -335.314799) (xy 419.750569 -335.36805)
			(xy 419.739453 -335.420262) (xy 419.721166 -335.470414) (xy 419.696067 -335.517528) (xy 419.664645 -335.560682)
			(xy 419.627513 -335.599035) (xy 419.60673 -335.615788) (xy 419.597966 -335.623347) (xy 419.587787 -335.644109)
			(xy 419.587172 -335.655666) (xy 419.587172 -335.73593) (xy 419.587757 -335.747497) (xy 419.597939 -335.76827)
			(xy 419.60673 -335.775808) (xy 419.629224 -335.793987) (xy 419.668957 -335.83601) (xy 419.701894 -335.883548)
			(xy 419.72728 -335.935511) (xy 419.744534 -335.990711) (xy 419.753262 -336.047881) (xy 419.753796 -336.076798)
			(xy 419.75331 -336.104049) (xy 419.745554 -336.157997) (xy 419.730199 -336.210292) (xy 419.707557 -336.259869)
			(xy 419.678091 -336.305719) (xy 419.6424 -336.34691) (xy 419.601209 -336.382601) (xy 419.555359 -336.412067)
			(xy 419.505782 -336.434709) (xy 419.453487 -336.450064) (xy 419.399539 -336.45782) (xy 419.345037 -336.45782)
			(xy 419.291089 -336.450064) (xy 419.238794 -336.434709) (xy 419.189217 -336.412067) (xy 419.143367 -336.382601)
			(xy 419.102176 -336.34691) (xy 419.066485 -336.305719) (xy 419.037019 -336.259869) (xy 419.014377 -336.210292)
			(xy 418.999022 -336.157997) (xy 418.991266 -336.104049) (xy 418.99078 -336.076798) (xy 418.991267 -336.04788)
			(xy 418.999998 -335.990705) (xy 419.01726 -335.935505) (xy 419.042658 -335.883542) (xy 419.075608 -335.83601)
			(xy 419.115357 -335.793996) (xy 419.137846 -335.775808) (xy 419.146607 -335.768246) (xy 419.156789 -335.747487)
			(xy 419.157404 -335.73593) (xy 419.157404 -335.655666) (xy 419.156794 -335.644103) (xy 419.146627 -335.623332)
			(xy 419.137846 -335.615788) (xy 419.117062 -335.599037) (xy 419.079932 -335.560683) (xy 419.048512 -335.517527)
			(xy 419.023414 -335.470414) (xy 419.005128 -335.420262) (xy 418.994012 -335.36805) (xy 418.990283 -335.314799)
			(xy 407.60015 -335.314799) (xy 407.60015 -338.731606) (xy 408.156664 -338.731606) (xy 408.157118 -338.704235)
			(xy 408.164936 -338.650055) (xy 408.180427 -338.597551) (xy 408.203272 -338.547804) (xy 408.233001 -338.501839)
			(xy 408.250644 -338.480908) (xy 408.25674 -338.473796) (xy 408.26309 -338.456778) (xy 408.26309 -338.371434)
			(xy 408.25674 -338.354416) (xy 408.250644 -338.347304) (xy 408.233 -338.326376) (xy 408.203288 -338.280402)
			(xy 408.180452 -338.230654) (xy 408.164962 -338.178152) (xy 408.157136 -338.123976) (xy 408.156664 -338.096606)
			(xy 408.15715 -338.069355) (xy 408.164906 -338.015407) (xy 408.180261 -337.963112) (xy 408.202903 -337.913535)
			(xy 408.232369 -337.867685) (xy 408.26806 -337.826494) (xy 408.309251 -337.790803) (xy 408.355101 -337.761337)
			(xy 408.404678 -337.738695) (xy 408.456973 -337.72334) (xy 408.510921 -337.715584) (xy 408.565423 -337.715584)
			(xy 408.619371 -337.72334) (xy 408.671666 -337.738695) (xy 408.721243 -337.761337) (xy 408.767093 -337.790803)
			(xy 408.808284 -337.826494) (xy 408.843975 -337.867685) (xy 408.873441 -337.913535) (xy 408.896083 -337.963112)
			(xy 408.911438 -338.015407) (xy 408.919194 -338.069355) (xy 408.91968 -338.096606) (xy 408.919222 -338.123977)
			(xy 408.911403 -338.178156) (xy 408.895912 -338.23066) (xy 408.873069 -338.280406) (xy 408.843342 -338.326373)
			(xy 408.8257 -338.347304) (xy 408.819604 -338.354416) (xy 408.813254 -338.371434) (xy 408.813254 -338.456778)
			(xy 408.819604 -338.473796) (xy 408.8257 -338.480908) (xy 408.843356 -338.501826) (xy 408.873066 -338.547803)
			(xy 408.895898 -338.597554) (xy 408.911385 -338.650058) (xy 408.919209 -338.704236) (xy 408.91968 -338.731606)
			(xy 408.919194 -338.758857) (xy 408.911438 -338.812805) (xy 408.896083 -338.8651) (xy 408.873441 -338.914677)
			(xy 408.843975 -338.960527) (xy 408.808284 -339.001718) (xy 408.767093 -339.037409) (xy 408.721243 -339.066875)
			(xy 408.671666 -339.089517) (xy 408.619371 -339.104872) (xy 408.565423 -339.112628) (xy 408.510921 -339.112628)
			(xy 408.456973 -339.104872) (xy 408.404678 -339.089517) (xy 408.355101 -339.066875) (xy 408.309251 -339.037409)
			(xy 408.26806 -339.001718) (xy 408.232369 -338.960527) (xy 408.202903 -338.914677) (xy 408.180261 -338.8651)
			(xy 408.164906 -338.812805) (xy 408.15715 -338.758857) (xy 408.156664 -338.731606) (xy 407.60015 -338.731606)
			(xy 407.60015 -341.499952) (xy 416.60445 -341.499952) (xy 416.604987 -341.471036) (xy 416.613709 -341.413864)
			(xy 416.630962 -341.358665) (xy 416.65635 -341.306703) (xy 416.689292 -341.259169) (xy 416.729031 -341.217152)
			(xy 416.751516 -341.198962) (xy 416.760293 -341.191415) (xy 416.770468 -341.170645) (xy 416.771074 -341.159084)
			(xy 416.771074 -341.07882) (xy 416.770501 -341.067252) (xy 416.760309 -341.046481) (xy 416.751516 -341.038942)
			(xy 416.729056 -341.020723) (xy 416.689319 -340.97871) (xy 416.656376 -340.931181) (xy 416.630984 -340.879225)
			(xy 416.613723 -340.824032) (xy 416.604988 -340.766866) (xy 416.60445 -340.737952) (xy 416.604936 -340.710701)
			(xy 416.612692 -340.656753) (xy 416.628047 -340.604458) (xy 416.650689 -340.554881) (xy 416.680155 -340.509031)
			(xy 416.715846 -340.46784) (xy 416.757037 -340.432149) (xy 416.802887 -340.402683) (xy 416.852464 -340.380041)
			(xy 416.904759 -340.364686) (xy 416.958707 -340.35693) (xy 417.013209 -340.35693) (xy 417.067157 -340.364686)
			(xy 417.119452 -340.380041) (xy 417.169029 -340.402683) (xy 417.214879 -340.432149) (xy 417.25607 -340.46784)
			(xy 417.291761 -340.509031) (xy 417.321227 -340.554881) (xy 417.343869 -340.604458) (xy 417.359224 -340.656753)
			(xy 417.36698 -340.710701) (xy 417.367466 -340.737952) (xy 417.366926 -340.766868) (xy 417.358203 -340.824039)
			(xy 417.340951 -340.879238) (xy 417.315563 -340.9312) (xy 417.282623 -340.978734) (xy 417.242884 -341.020752)
			(xy 417.2204 -341.038942) (xy 417.211624 -341.04649) (xy 417.201448 -341.067259) (xy 417.200842 -341.07882)
			(xy 417.200842 -341.159084) (xy 417.201407 -341.170653) (xy 417.211604 -341.191425) (xy 417.2204 -341.198962)
			(xy 417.242865 -341.217174) (xy 417.282602 -341.25919) (xy 417.315543 -341.30672) (xy 417.340934 -341.358677)
			(xy 417.358195 -341.413871) (xy 417.366928 -341.471037) (xy 417.367466 -341.499952) (xy 418.76345 -341.499952)
			(xy 418.763987 -341.471036) (xy 418.772709 -341.413864) (xy 418.789962 -341.358665) (xy 418.81535 -341.306703)
			(xy 418.848292 -341.259169) (xy 418.888031 -341.217152) (xy 418.910516 -341.198962) (xy 418.919293 -341.191415)
			(xy 418.929468 -341.170645) (xy 418.930074 -341.159084) (xy 418.930074 -341.07882) (xy 418.929501 -341.067252)
			(xy 418.919309 -341.046481) (xy 418.910516 -341.038942) (xy 418.888056 -341.020723) (xy 418.848319 -340.97871)
			(xy 418.815376 -340.931181) (xy 418.789984 -340.879225) (xy 418.772723 -340.824032) (xy 418.763988 -340.766866)
			(xy 418.76345 -340.737952) (xy 418.763936 -340.710701) (xy 418.771692 -340.656753) (xy 418.787047 -340.604458)
			(xy 418.809689 -340.554881) (xy 418.839155 -340.509031) (xy 418.874846 -340.46784) (xy 418.916037 -340.432149)
			(xy 418.961887 -340.402683) (xy 419.011464 -340.380041) (xy 419.063759 -340.364686) (xy 419.117707 -340.35693)
			(xy 419.172209 -340.35693) (xy 419.226157 -340.364686) (xy 419.278452 -340.380041) (xy 419.328029 -340.402683)
			(xy 419.373879 -340.432149) (xy 419.41507 -340.46784) (xy 419.450761 -340.509031) (xy 419.480227 -340.554881)
			(xy 419.502869 -340.604458) (xy 419.518224 -340.656753) (xy 419.52598 -340.710701) (xy 419.526466 -340.737952)
			(xy 419.525926 -340.766868) (xy 419.517203 -340.824039) (xy 419.499951 -340.879238) (xy 419.474563 -340.9312)
			(xy 419.441623 -340.978734) (xy 419.401884 -341.020752) (xy 419.3794 -341.038942) (xy 419.370624 -341.04649)
			(xy 419.360448 -341.067259) (xy 419.359842 -341.07882) (xy 419.359842 -341.159084) (xy 419.360407 -341.170653)
			(xy 419.370604 -341.191425) (xy 419.3794 -341.198962) (xy 419.401865 -341.217174) (xy 419.441602 -341.25919)
			(xy 419.474543 -341.30672) (xy 419.499934 -341.358677) (xy 419.517195 -341.413871) (xy 419.525928 -341.471037)
			(xy 419.526466 -341.499952) (xy 419.52598 -341.527203) (xy 419.518224 -341.581151) (xy 419.502869 -341.633446)
			(xy 419.480227 -341.683023) (xy 419.450761 -341.728873) (xy 419.41507 -341.770064) (xy 419.373879 -341.805755)
			(xy 419.328029 -341.835221) (xy 419.278452 -341.857863) (xy 419.226157 -341.873218) (xy 419.172209 -341.880974)
			(xy 419.117707 -341.880974) (xy 419.063759 -341.873218) (xy 419.011464 -341.857863) (xy 418.961887 -341.835221)
			(xy 418.916037 -341.805755) (xy 418.874846 -341.770064) (xy 418.839155 -341.728873) (xy 418.809689 -341.683023)
			(xy 418.787047 -341.633446) (xy 418.771692 -341.581151) (xy 418.763936 -341.527203) (xy 418.76345 -341.499952)
			(xy 417.367466 -341.499952) (xy 417.36698 -341.527203) (xy 417.359224 -341.581151) (xy 417.343869 -341.633446)
			(xy 417.321227 -341.683023) (xy 417.291761 -341.728873) (xy 417.25607 -341.770064) (xy 417.214879 -341.805755)
			(xy 417.169029 -341.835221) (xy 417.119452 -341.857863) (xy 417.067157 -341.873218) (xy 417.013209 -341.880974)
			(xy 416.958707 -341.880974) (xy 416.904759 -341.873218) (xy 416.852464 -341.857863) (xy 416.802887 -341.835221)
			(xy 416.757037 -341.805755) (xy 416.715846 -341.770064) (xy 416.680155 -341.728873) (xy 416.650689 -341.683023)
			(xy 416.628047 -341.633446) (xy 416.612692 -341.581151) (xy 416.604936 -341.527203) (xy 416.60445 -341.499952)
			(xy 407.60015 -341.499952) (xy 407.60015 -352.769678) (xy 419.579552 -352.769678) (xy 419.580041 -352.741767)
			(xy 419.588178 -352.686542) (xy 419.604275 -352.633091) (xy 419.627988 -352.582556) (xy 419.658812 -352.536016)
			(xy 419.677088 -352.514916) (xy 419.683438 -352.507804) (xy 419.690042 -352.490532) (xy 419.690042 -352.40341)
			(xy 419.683438 -352.386138) (xy 419.677088 -352.379026) (xy 419.658799 -352.357936) (xy 419.627973 -352.311395)
			(xy 419.604261 -352.260858) (xy 419.588167 -352.207404) (xy 419.580036 -352.152176) (xy 419.579552 -352.124264)
			(xy 419.580044 -352.097014) (xy 419.587805 -352.043068) (xy 419.603162 -351.990776) (xy 419.625805 -351.941201)
			(xy 419.655271 -351.895353) (xy 419.690962 -351.854164) (xy 419.73215 -351.818473) (xy 419.777998 -351.789007)
			(xy 419.827572 -351.766364) (xy 419.879864 -351.751005) (xy 419.93381 -351.743244) (xy 419.96106 -351.742756)
			(xy 419.98889 -351.743273) (xy 420.043958 -351.751363) (xy 420.097269 -351.767362) (xy 420.147692 -351.790932)
			(xy 420.194158 -351.821573) (xy 420.235683 -351.858636) (xy 420.253922 -351.879662) (xy 420.264082 -351.891854)
			(xy 420.29507 -351.900236) (xy 420.399972 -351.862136) (xy 420.40958 -351.858116) (xy 420.424744 -351.843877)
			(xy 420.433004 -351.824785) (xy 420.4335 -351.814384) (xy 420.4335 -342.052656) (xy 420.433983 -342.027681)
			(xy 420.441771 -341.978343) (xy 420.457179 -341.93083) (xy 420.479829 -341.886312) (xy 420.509163 -341.845883)
			(xy 420.526464 -341.827866) (xy 420.924736 -341.429594) (xy 420.93134 -341.417656) (xy 420.933118 -341.410798)
			(xy 420.939026 -341.387667) (xy 420.955863 -341.342992) (xy 420.978149 -341.30077) (xy 420.991538 -341.281004)
			(xy 420.997126 -341.272876) (xy 421.001698 -341.25408) (xy 420.987982 -341.164926) (xy 420.978076 -341.148416)
			(xy 420.970202 -341.14232) (xy 420.947409 -341.12413) (xy 420.907079 -341.082012) (xy 420.873626 -341.034249)
			(xy 420.847827 -340.981953) (xy 420.830285 -340.926342) (xy 420.821406 -340.868708) (xy 420.82085 -340.839552)
			(xy 420.821456 -340.809358) (xy 420.830974 -340.749724) (xy 420.849765 -340.692334) (xy 420.87736 -340.638619)
			(xy 420.91307 -340.589921) (xy 420.934134 -340.56828) (xy 420.942262 -340.560152) (xy 420.950136 -340.53907)
			(xy 420.940992 -340.437978) (xy 420.929562 -340.418674) (xy 420.920164 -340.41207) (xy 420.898585 -340.396775)
			(xy 420.859502 -340.361135) (xy 420.825718 -340.320437) (xy 420.797879 -340.275462) (xy 420.776521 -340.227073)
			(xy 420.762052 -340.176197) (xy 420.75475 -340.123811) (xy 420.754302 -340.097364) (xy 420.754746 -340.069993)
			(xy 420.762569 -340.015813) (xy 420.778064 -339.96331) (xy 420.80091 -339.913563) (xy 420.830639 -339.867597)
			(xy 420.848282 -339.846666) (xy 420.854378 -339.839554) (xy 420.860728 -339.822536) (xy 420.860728 -339.737192)
			(xy 420.854378 -339.720174) (xy 420.848282 -339.713062) (xy 420.830608 -339.692157) (xy 420.800888 -339.646183)
			(xy 420.778048 -339.596432) (xy 420.762556 -339.543926) (xy 420.754732 -339.489745) (xy 420.754736 -339.435001)
			(xy 420.762568 -339.380821) (xy 420.778067 -339.328317) (xy 420.800914 -339.278569) (xy 420.830641 -339.2326)
			(xy 420.848282 -339.211666) (xy 420.854378 -339.204554) (xy 420.860728 -339.187536) (xy 420.860728 -339.102192)
			(xy 420.854378 -339.085174) (xy 420.848282 -339.078062) (xy 420.830608 -339.057157) (xy 420.800888 -339.011183)
			(xy 420.778048 -338.961432) (xy 420.762556 -338.908926) (xy 420.754732 -338.854745) (xy 420.754736 -338.800001)
			(xy 420.762568 -338.745821) (xy 420.778067 -338.693317) (xy 420.800914 -338.643569) (xy 420.830641 -338.5976)
			(xy 420.848282 -338.576666) (xy 420.854378 -338.569554) (xy 420.860728 -338.552536) (xy 420.860728 -338.467192)
			(xy 420.854378 -338.450174) (xy 420.848282 -338.443062) (xy 420.830608 -338.422157) (xy 420.800888 -338.376183)
			(xy 420.778048 -338.326432) (xy 420.762556 -338.273926) (xy 420.754732 -338.219745) (xy 420.754736 -338.165001)
			(xy 420.762568 -338.110821) (xy 420.778067 -338.058317) (xy 420.800914 -338.008569) (xy 420.830641 -337.9626)
			(xy 420.848282 -337.941666) (xy 420.854378 -337.934554) (xy 420.860728 -337.917536) (xy 420.860728 -337.832192)
			(xy 420.854378 -337.815174) (xy 420.848282 -337.808062) (xy 420.830656 -337.78712) (xy 420.800943 -337.741149)
			(xy 420.778104 -337.691404) (xy 420.76261 -337.638906) (xy 420.754778 -337.584732) (xy 420.754302 -337.557364)
			(xy 420.754851 -337.528447) (xy 420.763578 -337.471276) (xy 420.780841 -337.41608) (xy 420.806244 -337.364124)
			(xy 420.839205 -337.316603) (xy 420.858696 -337.295236) (xy 420.865046 -337.288378) (xy 420.872158 -337.271614)
			(xy 420.875714 -337.186016) (xy 420.869872 -337.168998) (xy 420.86403 -337.161632) (xy 420.848161 -337.141195)
			(xy 420.821462 -337.096874) (xy 420.800995 -337.049352) (xy 420.787135 -336.999501) (xy 420.780137 -336.948235)
			(xy 420.779702 -336.922364) (xy 420.780144 -336.895111) (xy 420.787906 -336.841162) (xy 420.803266 -336.788865)
			(xy 420.825912 -336.739287) (xy 420.855383 -336.693437) (xy 420.891079 -336.652247) (xy 420.932274 -336.616556)
			(xy 420.978128 -336.58709) (xy 421.027709 -336.56445) (xy 421.080007 -336.549096) (xy 421.133957 -336.541341)
			(xy 421.16121 -336.540856) (xy 421.188847 -336.54137) (xy 421.243542 -336.549358) (xy 421.296512 -336.565151)
			(xy 421.346651 -336.588419) (xy 421.39291 -336.618675) (xy 421.41394 -336.636614) (xy 421.421052 -336.64271)
			(xy 421.438324 -336.649314) (xy 421.524176 -336.649314) (xy 421.541448 -336.64271) (xy 421.54856 -336.636614)
			(xy 421.56957 -336.618647) (xy 421.615825 -336.588375) (xy 421.665968 -336.565101) (xy 421.718946 -336.549313)
			(xy 421.773649 -336.541341) (xy 421.80129 -336.540856) (xy 421.828311 -336.541308) (xy 421.881813 -336.548922)
			(xy 421.933705 -336.564012) (xy 421.982947 -336.586278) (xy 422.028552 -336.615272) (xy 422.069607 -336.650414)
			(xy 422.087802 -336.670396) (xy 422.094914 -336.678778) (xy 422.113964 -336.687414) (xy 422.210738 -336.689446)
			(xy 422.230042 -336.681572) (xy 422.237408 -336.673698) (xy 422.255473 -336.655456) (xy 422.295643 -336.623484)
			(xy 422.339736 -336.597186) (xy 422.386956 -336.577035) (xy 422.436451 -336.563395) (xy 422.487328 -336.556513)
			(xy 422.512998 -336.556096) (xy 422.540251 -336.556557) (xy 422.594202 -336.564314) (xy 422.6465 -336.57967)
			(xy 422.696081 -336.602313) (xy 422.741934 -336.631781) (xy 422.783127 -336.667475) (xy 422.81882 -336.708668)
			(xy 422.848288 -336.754521) (xy 422.870931 -336.804102) (xy 422.886286 -336.8564) (xy 422.894043 -336.910351)
			(xy 422.894506 -336.937604) (xy 422.894051 -336.964863) (xy 422.886283 -337.018824) (xy 422.870918 -337.071132)
			(xy 422.84827 -337.120723) (xy 422.818798 -337.166588) (xy 422.783103 -337.207795) (xy 422.74191 -337.243507)
			(xy 422.719246 -337.25866) (xy 422.71228 -337.263513) (xy 422.701759 -337.276822) (xy 422.696195 -337.292849)
			(xy 422.695878 -337.301332) (xy 422.695878 -337.386676) (xy 422.696243 -337.395151) (xy 422.701814 -337.411163)
			(xy 422.712292 -337.424491) (xy 422.719246 -337.429348) (xy 422.741892 -337.444527) (xy 422.78309 -337.480228)
			(xy 422.818788 -337.521429) (xy 422.84826 -337.567291) (xy 422.870905 -337.61688) (xy 422.886263 -337.669187)
			(xy 422.89402 -337.723147) (xy 422.894506 -337.750404) (xy 422.894041 -337.777774) (xy 422.886223 -337.831953)
			(xy 422.870733 -337.884456) (xy 422.847891 -337.934203) (xy 422.818167 -337.98017) (xy 422.800526 -338.001102)
			(xy 422.79443 -338.008214) (xy 422.78808 -338.025232) (xy 422.78808 -338.110576) (xy 422.79443 -338.127594)
			(xy 422.800526 -338.134706) (xy 422.818173 -338.155635) (xy 422.847901 -338.201602) (xy 422.870749 -338.251349)
			(xy 422.886247 -338.303852) (xy 422.894076 -338.358032) (xy 422.894076 -338.412774) (xy 422.886245 -338.466954)
			(xy 422.870747 -338.519457) (xy 422.847898 -338.569203) (xy 422.818169 -338.61517) (xy 422.800526 -338.636102)
			(xy 422.79443 -338.643214) (xy 422.78808 -338.660232) (xy 422.78808 -338.745576) (xy 422.79443 -338.762594)
			(xy 422.800526 -338.769706) (xy 422.818185 -338.790622) (xy 422.847893 -338.836599) (xy 422.870725 -338.886351)
			(xy 422.886211 -338.938855) (xy 422.894035 -338.993034) (xy 422.894287 -339.007704) (xy 424.464734 -339.007704)
			(xy 424.465194 -338.980333) (xy 424.473012 -338.926154) (xy 424.488502 -338.87365) (xy 424.511345 -338.823903)
			(xy 424.541072 -338.777937) (xy 424.558714 -338.757006) (xy 424.56481 -338.749894) (xy 424.57116 -338.732876)
			(xy 424.57116 -338.647532) (xy 424.56481 -338.630514) (xy 424.558714 -338.623402) (xy 424.541078 -338.602466)
			(xy 424.511354 -338.556498) (xy 424.488509 -338.506753) (xy 424.473013 -338.454251) (xy 424.465184 -338.400073)
			(xy 424.465184 -338.345333) (xy 424.473012 -338.291155) (xy 424.488507 -338.238653) (xy 424.511351 -338.188907)
			(xy 424.541074 -338.142939) (xy 424.558714 -338.122006) (xy 424.56481 -338.114894) (xy 424.57116 -338.097876)
			(xy 424.57116 -338.012532) (xy 424.56481 -337.995514) (xy 424.558714 -337.988402) (xy 424.541065 -337.967478)
			(xy 424.511354 -337.921503) (xy 424.48852 -337.871754) (xy 424.473031 -337.819251) (xy 424.465206 -337.765074)
			(xy 424.464734 -337.737704) (xy 424.465222 -337.710447) (xy 424.472988 -337.656488) (xy 424.488349 -337.604182)
			(xy 424.510993 -337.554593) (xy 424.540458 -337.508727) (xy 424.576147 -337.467518) (xy 424.617333 -337.431803)
			(xy 424.639994 -337.416648) (xy 424.64699 -337.411832) (xy 424.65751 -337.398509) (xy 424.663058 -337.382465)
			(xy 424.663362 -337.373976) (xy 424.663362 -337.288632) (xy 424.662974 -337.280159) (xy 424.65741 -337.26415)
			(xy 424.646942 -337.250821) (xy 424.639994 -337.24596) (xy 424.617338 -337.230795) (xy 424.576143 -337.19509)
			(xy 424.540447 -337.153885) (xy 424.510978 -337.108021) (xy 424.488335 -337.058431) (xy 424.472978 -337.006123)
			(xy 424.46522 -336.952162) (xy 424.464734 -336.924904) (xy 424.465159 -336.897649) (xy 424.472917 -336.843695)
			(xy 424.488274 -336.791394) (xy 424.510919 -336.741811) (xy 424.540391 -336.695956) (xy 424.576089 -336.654762)
			(xy 424.617286 -336.619068) (xy 424.663144 -336.589601) (xy 424.712729 -336.566961) (xy 424.765032 -336.551609)
			(xy 424.818987 -336.543856) (xy 424.846242 -336.543396) (xy 424.875756 -336.543918) (xy 424.934079 -336.553016)
			(xy 424.990305 -336.570987) (xy 425.043092 -336.597403) (xy 425.091181 -336.631634) (xy 425.112688 -336.651854)
			(xy 425.119546 -336.658712) (xy 425.13758 -336.666078) (xy 425.226734 -336.667602) (xy 425.245022 -336.660744)
			(xy 425.252134 -336.65414) (xy 425.273317 -336.635437) (xy 425.320209 -336.603906) (xy 425.37124 -336.579635)
			(xy 425.425291 -336.563155) (xy 425.481182 -336.554826) (xy 425.509436 -336.554318) (xy 425.537075 -336.554801)
			(xy 425.591771 -336.562795) (xy 425.644742 -336.578594) (xy 425.694881 -336.601869) (xy 425.741138 -336.632133)
			(xy 425.762166 -336.650076) (xy 425.769278 -336.656172) (xy 425.78655 -336.662776) (xy 425.872402 -336.662776)
			(xy 425.889674 -336.656172) (xy 425.896786 -336.650076) (xy 425.917819 -336.632138) (xy 425.964069 -336.601863)
			(xy 426.014206 -336.578584) (xy 426.067179 -336.562789) (xy 426.121877 -336.554809) (xy 426.149516 -336.554318)
			(xy 426.17677 -336.55474) (xy 426.230724 -336.5625) (xy 426.283025 -336.577859) (xy 426.332607 -336.600506)
			(xy 426.378461 -336.629978) (xy 426.419654 -336.665676) (xy 426.455348 -336.706873) (xy 426.484815 -336.75273)
			(xy 426.507455 -336.802315) (xy 426.522809 -336.854617) (xy 426.530563 -336.908571) (xy 426.531024 -336.935826)
			(xy 426.530592 -336.963198) (xy 426.522769 -337.017379) (xy 426.507273 -337.069883) (xy 426.484423 -337.11963)
			(xy 426.45469 -337.165594) (xy 426.437044 -337.186524) (xy 426.430948 -337.193636) (xy 426.424598 -337.210654)
			(xy 426.424598 -337.295998) (xy 426.430948 -337.313016) (xy 426.437044 -337.320128) (xy 426.454711 -337.34104)
			(xy 426.484437 -337.38701) (xy 426.507283 -337.43676) (xy 426.522778 -337.489265) (xy 426.530605 -337.543447)
			(xy 426.530602 -337.598192) (xy 426.52277 -337.652373) (xy 426.507269 -337.704877) (xy 426.484418 -337.754624)
			(xy 426.454688 -337.800592) (xy 426.437044 -337.821524) (xy 426.430948 -337.828636) (xy 426.424598 -337.845654)
			(xy 426.424598 -337.930998) (xy 426.430948 -337.948016) (xy 426.437044 -337.955128) (xy 426.454711 -337.97604)
			(xy 426.484437 -338.02201) (xy 426.507283 -338.07176) (xy 426.522778 -338.124265) (xy 426.530605 -338.178447)
			(xy 426.530602 -338.233192) (xy 426.52277 -338.287373) (xy 426.507269 -338.339877) (xy 426.484418 -338.389624)
			(xy 426.454688 -338.435592) (xy 426.437044 -338.456524) (xy 426.430948 -338.463636) (xy 426.424598 -338.480654)
			(xy 426.424598 -338.565998) (xy 426.430948 -338.583016) (xy 426.437044 -338.590128) (xy 426.454711 -338.61104)
			(xy 426.484437 -338.65701) (xy 426.507283 -338.70676) (xy 426.522778 -338.759265) (xy 426.530605 -338.813447)
			(xy 426.530602 -338.868192) (xy 426.52277 -338.922373) (xy 426.507269 -338.974877) (xy 426.484418 -339.024624)
			(xy 426.454688 -339.070592) (xy 426.437044 -339.091524) (xy 426.430948 -339.098636) (xy 426.424598 -339.115654)
			(xy 426.424598 -339.200998) (xy 426.430948 -339.218016) (xy 426.437044 -339.225128) (xy 426.454711 -339.24604)
			(xy 426.484437 -339.29201) (xy 426.507283 -339.34176) (xy 426.522778 -339.394265) (xy 426.530605 -339.448447)
			(xy 426.530602 -339.503192) (xy 426.52277 -339.557373) (xy 426.507269 -339.609877) (xy 426.484418 -339.659624)
			(xy 426.454688 -339.705592) (xy 426.437044 -339.726524) (xy 426.430948 -339.733636) (xy 426.424598 -339.750654)
			(xy 426.424598 -339.835998) (xy 426.430948 -339.853016) (xy 426.437044 -339.860128) (xy 426.45467 -339.88107)
			(xy 426.484382 -339.927041) (xy 426.50722 -339.976786) (xy 426.522715 -340.029284) (xy 426.530548 -340.083458)
			(xy 426.531024 -340.110826) (xy 426.530452 -340.140666) (xy 426.521195 -340.199624) (xy 426.50285 -340.256414)
			(xy 426.489876 -340.283292) (xy 426.484542 -340.293706) (xy 426.484034 -340.317074) (xy 426.52823 -340.411054)
			(xy 426.546264 -340.425532) (xy 426.557948 -340.428326) (xy 426.585683 -340.43513) (xy 426.638853 -340.45597)
			(xy 426.688319 -340.484506) (xy 426.732978 -340.520099) (xy 426.771829 -340.561954) (xy 426.804004 -340.609135)
			(xy 426.828784 -340.660586) (xy 426.845614 -340.715157) (xy 426.854118 -340.771628) (xy 426.85462 -340.800182)
			(xy 426.854163 -340.827553) (xy 426.846346 -340.881733) (xy 426.830856 -340.934237) (xy 426.808012 -340.983984)
			(xy 426.778283 -341.029949) (xy 426.76064 -341.05088) (xy 426.754544 -341.057992) (xy 426.748194 -341.07501)
			(xy 426.748194 -341.160354) (xy 426.754544 -341.177372) (xy 426.76064 -341.184484) (xy 426.778292 -341.205406)
			(xy 426.808 -341.251382) (xy 426.830833 -341.301132) (xy 426.846322 -341.353635) (xy 426.850763 -341.384382)
			(xy 428.175928 -341.384382) (xy 428.176377 -341.357011) (xy 428.184198 -341.302831) (xy 428.19969 -341.250327)
			(xy 428.222536 -341.200581) (xy 428.252265 -341.154615) (xy 428.269908 -341.133684) (xy 428.276004 -341.126572)
			(xy 428.282354 -341.109554) (xy 428.282354 -341.02421) (xy 428.276004 -341.007192) (xy 428.269908 -341.00008)
			(xy 428.252294 -340.979128) (xy 428.222578 -340.93316) (xy 428.199737 -340.883418) (xy 428.18424 -340.830922)
			(xy 428.176406 -340.77675) (xy 428.175928 -340.749382) (xy 428.176414 -340.722131) (xy 428.18417 -340.668183)
			(xy 428.199525 -340.615888) (xy 428.222167 -340.566311) (xy 428.251633 -340.520461) (xy 428.287324 -340.47927)
			(xy 428.328515 -340.443579) (xy 428.374365 -340.414113) (xy 428.423942 -340.391471) (xy 428.476237 -340.376116)
			(xy 428.530185 -340.36836) (xy 428.584687 -340.36836) (xy 428.638635 -340.376116) (xy 428.69093 -340.391471)
			(xy 428.740507 -340.414113) (xy 428.786357 -340.443579) (xy 428.827548 -340.47927) (xy 428.863239 -340.520461)
			(xy 428.892705 -340.566311) (xy 428.915347 -340.615888) (xy 428.930702 -340.668183) (xy 428.938458 -340.722131)
			(xy 428.938944 -340.749382) (xy 428.938481 -340.776752) (xy 428.930665 -340.830932) (xy 428.915176 -340.883436)
			(xy 428.892333 -340.933183) (xy 428.862606 -340.979149) (xy 428.844964 -341.00008) (xy 428.838868 -341.007192)
			(xy 428.832518 -341.02421) (xy 428.832518 -341.109554) (xy 428.838868 -341.126572) (xy 428.844964 -341.133684)
			(xy 428.862603 -341.154616) (xy 428.892316 -341.200588) (xy 428.915153 -341.250336) (xy 428.930644 -341.302837)
			(xy 428.938471 -341.357013) (xy 428.938944 -341.384382) (xy 428.938458 -341.411633) (xy 428.930702 -341.465581)
			(xy 428.915347 -341.517876) (xy 428.892705 -341.567453) (xy 428.863239 -341.613303) (xy 428.827548 -341.654494)
			(xy 428.786357 -341.690185) (xy 428.740507 -341.719651) (xy 428.69093 -341.742293) (xy 428.638635 -341.757648)
			(xy 428.584687 -341.765404) (xy 428.530185 -341.765404) (xy 428.476237 -341.757648) (xy 428.423942 -341.742293)
			(xy 428.374365 -341.719651) (xy 428.328515 -341.690185) (xy 428.287324 -341.654494) (xy 428.251633 -341.613303)
			(xy 428.222167 -341.567453) (xy 428.199525 -341.517876) (xy 428.18417 -341.465581) (xy 428.176414 -341.411633)
			(xy 428.175928 -341.384382) (xy 426.850763 -341.384382) (xy 426.854148 -341.407812) (xy 426.85462 -341.435182)
			(xy 426.854134 -341.462433) (xy 426.846378 -341.516381) (xy 426.831023 -341.568676) (xy 426.808381 -341.618253)
			(xy 426.778915 -341.664103) (xy 426.743224 -341.705294) (xy 426.702033 -341.740985) (xy 426.656183 -341.770451)
			(xy 426.606606 -341.793093) (xy 426.554311 -341.808448) (xy 426.500363 -341.816204) (xy 426.445861 -341.816204)
			(xy 426.391913 -341.808448) (xy 426.339618 -341.793093) (xy 426.290041 -341.770451) (xy 426.244191 -341.740985)
			(xy 426.203 -341.705294) (xy 426.167309 -341.664103) (xy 426.137843 -341.618253) (xy 426.115201 -341.568676)
			(xy 426.099846 -341.516381) (xy 426.09209 -341.462433) (xy 426.091604 -341.435182) (xy 426.092059 -341.407811)
			(xy 426.099879 -341.353632) (xy 426.115371 -341.301128) (xy 426.138215 -341.251382) (xy 426.167942 -341.205415)
			(xy 426.185584 -341.184484) (xy 426.19168 -341.177372) (xy 426.19803 -341.160354) (xy 426.19803 -341.07501)
			(xy 426.19168 -341.057992) (xy 426.185584 -341.05088) (xy 426.167966 -341.029931) (xy 426.138252 -340.983962)
			(xy 426.115412 -340.934219) (xy 426.099916 -340.881722) (xy 426.092082 -340.82755) (xy 426.091604 -340.800182)
			(xy 426.092176 -340.770342) (xy 426.101432 -340.711384) (xy 426.119778 -340.654594) (xy 426.132752 -340.627716)
			(xy 426.138086 -340.617302) (xy 426.138594 -340.593934) (xy 426.094398 -340.499954) (xy 426.076364 -340.485476)
			(xy 426.06468 -340.482682) (xy 426.036135 -340.475641) (xy 425.981486 -340.453963) (xy 425.930807 -340.424163)
			(xy 425.907708 -340.405974) (xy 425.900088 -340.399624) (xy 425.881546 -340.393782) (xy 425.791884 -340.40064)
			(xy 425.774358 -340.409276) (xy 425.767754 -340.416642) (xy 425.749607 -340.436197) (xy 425.708769 -340.470525)
			(xy 425.663546 -340.498826) (xy 425.614819 -340.520548) (xy 425.56354 -340.535266) (xy 425.510711 -340.542693)
			(xy 425.484036 -340.543134) (xy 425.456785 -340.542611) (xy 425.402838 -340.53486) (xy 425.350543 -340.51951)
			(xy 425.300964 -340.496873) (xy 425.255112 -340.467411) (xy 425.21392 -340.431724) (xy 425.178226 -340.390537)
			(xy 425.148756 -340.34469) (xy 425.126112 -340.295116) (xy 425.110753 -340.242823) (xy 425.102993 -340.188877)
			(xy 425.102528 -340.161626) (xy 425.103002 -340.134256) (xy 425.110817 -340.080077) (xy 425.126304 -340.027574)
			(xy 425.149144 -339.977827) (xy 425.178867 -339.93186) (xy 425.196508 -339.910928) (xy 425.202604 -339.903816)
			(xy 425.208954 -339.886798) (xy 425.208954 -339.801454) (xy 425.202604 -339.784436) (xy 425.196508 -339.777324)
			(xy 425.178868 -339.756393) (xy 425.149156 -339.71042) (xy 425.12632 -339.660672) (xy 425.110829 -339.608171)
			(xy 425.103002 -339.553995) (xy 425.102528 -339.526626) (xy 425.102647 -339.514206) (xy 425.1043 -339.489422)
			(xy 425.10583 -339.477096) (xy 425.107608 -339.463888) (xy 425.097702 -339.439504) (xy 425.010072 -339.36813)
			(xy 424.984164 -339.363558) (xy 424.971718 -339.36813) (xy 424.941292 -339.377996) (xy 424.878221 -339.388602)
			(xy 424.846242 -339.389212) (xy 424.81899 -339.388706) (xy 424.765041 -339.380954) (xy 424.712744 -339.365604)
			(xy 424.663165 -339.342967) (xy 424.617312 -339.313503) (xy 424.576118 -339.277814) (xy 424.540424 -339.236625)
			(xy 424.510955 -339.190776) (xy 424.488312 -339.141199) (xy 424.472955 -339.088904) (xy 424.465198 -339.034956)
			(xy 424.464734 -339.007704) (xy 422.894287 -339.007704) (xy 422.894506 -339.020404) (xy 422.894026 -339.047655)
			(xy 422.886269 -339.101603) (xy 422.870913 -339.153898) (xy 422.848271 -339.203476) (xy 422.818804 -339.249326)
			(xy 422.783112 -339.290517) (xy 422.741922 -339.326208) (xy 422.696071 -339.355674) (xy 422.646493 -339.378315)
			(xy 422.594198 -339.39367) (xy 422.540249 -339.401426) (xy 422.512998 -339.401912) (xy 422.486081 -339.4015)
			(xy 422.432782 -339.393939) (xy 422.381077 -339.378954) (xy 422.331995 -339.356843) (xy 422.286512 -339.328046)
			(xy 422.245533 -339.293135) (xy 422.209874 -339.252807) (xy 422.180244 -339.207861) (xy 422.16832 -339.183726)
			(xy 422.162646 -339.173243) (xy 422.143819 -339.15867) (xy 422.132252 -339.155786) (xy 422.074594 -339.144356)
			(xy 422.068084 -339.15171) (xy 422.060625 -339.169856) (xy 422.060116 -339.179662) (xy 422.060116 -339.211666)
			(xy 422.060573 -339.221484) (xy 422.068038 -339.239648) (xy 422.074594 -339.246972) (xy 422.094761 -339.268477)
			(xy 422.128905 -339.316536) (xy 422.155252 -339.369274) (xy 422.173175 -339.425437) (xy 422.182247 -339.483687)
			(xy 422.182798 -339.513164) (xy 422.182311 -339.540533) (xy 422.174499 -339.594712) (xy 422.159014 -339.647215)
			(xy 422.136177 -339.696962) (xy 422.106457 -339.74293) (xy 422.088818 -339.763862) (xy 422.082722 -339.770974)
			(xy 422.076372 -339.787992) (xy 422.076372 -339.873336) (xy 422.082722 -339.890354) (xy 422.088818 -339.897466)
			(xy 422.106457 -339.918398) (xy 422.136169 -339.964371) (xy 422.159004 -340.014119) (xy 422.174495 -340.066619)
			(xy 422.182324 -340.120795) (xy 422.182798 -340.148164) (xy 422.182311 -340.175416) (xy 422.174559 -340.229367)
			(xy 422.159207 -340.281665) (xy 422.136568 -340.331246) (xy 422.107103 -340.3771) (xy 422.071411 -340.418293)
			(xy 422.03022 -340.453987) (xy 421.984369 -340.483455) (xy 421.934789 -340.506098) (xy 421.882492 -340.521453)
			(xy 421.828542 -340.529209) (xy 421.80129 -340.529672) (xy 421.772613 -340.529168) (xy 421.715904 -340.520594)
			(xy 421.661119 -340.503624) (xy 421.609492 -340.478642) (xy 421.562188 -340.446211) (xy 421.520273 -340.407063)
			(xy 421.502078 -340.384892) (xy 421.495134 -340.377042) (xy 421.476655 -340.367203) (xy 421.466264 -340.365842)
			(xy 421.410892 -340.361524) (xy 421.404034 -340.368636) (xy 421.395906 -340.376764) (xy 421.388032 -340.397846)
			(xy 421.397176 -340.498938) (xy 421.408606 -340.518242) (xy 421.418004 -340.524846) (xy 421.439584 -340.540141)
			(xy 421.478668 -340.57578) (xy 421.512453 -340.616477) (xy 421.540292 -340.661452) (xy 421.56165 -340.709842)
			(xy 421.576118 -340.760718) (xy 421.583419 -340.813105) (xy 421.583866 -340.839552) (xy 421.583323 -340.868717)
			(xy 421.574438 -340.926367) (xy 421.556882 -340.981993) (xy 421.531064 -341.034299) (xy 421.514778 -341.0585)
			(xy 421.50919 -341.066628) (xy 421.504618 -341.085424) (xy 421.518334 -341.174578) (xy 421.52824 -341.191088)
			(xy 421.536114 -341.197184) (xy 421.558892 -341.215394) (xy 421.599226 -341.257505) (xy 421.632684 -341.305263)
			(xy 421.658486 -341.357555) (xy 421.67603 -341.413165) (xy 421.68491 -341.470796) (xy 421.685466 -341.499952)
			(xy 421.684977 -341.528259) (xy 421.676625 -341.584253) (xy 421.660084 -341.638395) (xy 421.635717 -341.689496)
			(xy 421.604059 -341.736431) (xy 421.565809 -341.778167) (xy 421.521805 -341.813787) (xy 421.473018 -341.842506)
			(xy 421.420519 -341.863695) (xy 421.393112 -341.870792) (xy 421.386254 -341.87257) (xy 421.374316 -341.879174)
			(xy 421.083994 -342.169496) (xy 421.077256 -342.176888) (xy 421.069544 -342.195322) (xy 421.069008 -342.20531)
			(xy 421.069008 -353.063302) (xy 421.068559 -353.088278) (xy 421.066201 -353.1032) (xy 423.961713 -353.1032)
			(xy 423.965882 -353.047576) (xy 423.978295 -352.993194) (xy 423.998676 -352.94127) (xy 424.026567 -352.892964)
			(xy 424.061348 -352.849355) (xy 424.10224 -352.811417) (xy 424.14833 -352.779998) (xy 424.198588 -352.755799)
			(xy 424.251892 -352.739362) (xy 424.30705 -352.731054) (xy 424.33494 -352.730562) (xy 424.361362 -352.731005)
			(xy 424.413678 -352.73846) (xy 424.464416 -352.753229) (xy 424.51256 -352.775016) (xy 424.557145 -352.803384)
			(xy 424.57751 -352.820224) (xy 424.584368 -352.82632) (xy 424.601386 -352.832416) (xy 424.685714 -352.832416)
			(xy 424.702732 -352.82632) (xy 424.70959 -352.820224) (xy 424.729956 -352.803385) (xy 424.774542 -352.77502)
			(xy 424.822686 -352.753233) (xy 424.873423 -352.738462) (xy 424.925738 -352.731002) (xy 424.978582 -352.731002)
			(xy 425.030897 -352.738462) (xy 425.081634 -352.753233) (xy 425.129778 -352.77502) (xy 425.174364 -352.803385)
			(xy 425.19473 -352.820224) (xy 425.201588 -352.82632) (xy 425.218606 -352.832416) (xy 425.302934 -352.832416)
			(xy 425.319952 -352.82632) (xy 425.32681 -352.820224) (xy 425.340704 -352.80864) (xy 425.370347 -352.787903)
			(xy 425.385992 -352.778822) (xy 425.396406 -352.77298) (xy 425.409614 -352.753676) (xy 425.424854 -352.65106)
			(xy 425.417996 -352.628962) (xy 425.409868 -352.620326) (xy 425.390283 -352.598948) (xy 425.357166 -352.55136)
			(xy 425.331637 -352.499306) (xy 425.314283 -352.443987) (xy 425.305506 -352.386678) (xy 425.304966 -352.35769)
			(xy 425.305471 -352.330117) (xy 425.313412 -352.275545) (xy 425.329128 -352.222684) (xy 425.352291 -352.172638)
			(xy 425.382418 -352.126448) (xy 425.418881 -352.085076) (xy 425.439586 -352.06686) (xy 425.447716 -352.059268)
			(xy 425.457064 -352.039109) (xy 425.45762 -352.027998) (xy 425.45762 -351.950782) (xy 425.457104 -351.939665)
			(xy 425.447731 -351.919505) (xy 425.439586 -351.91192) (xy 425.418879 -351.893705) (xy 425.382409 -351.852337)
			(xy 425.352276 -351.806147) (xy 425.32911 -351.7561) (xy 425.313393 -351.703239) (xy 425.305452 -351.648664)
			(xy 425.304966 -351.62109) (xy 425.305452 -351.593839) (xy 425.313208 -351.539891) (xy 425.328563 -351.487596)
			(xy 425.351205 -351.438019) (xy 425.380671 -351.392169) (xy 425.416362 -351.350978) (xy 425.457553 -351.315287)
			(xy 425.503403 -351.285821) (xy 425.55298 -351.263179) (xy 425.605275 -351.247824) (xy 425.659223 -351.240068)
			(xy 425.713725 -351.240068) (xy 425.767673 -351.247824) (xy 425.819968 -351.263179) (xy 425.869545 -351.285821)
			(xy 425.915395 -351.315287) (xy 425.956586 -351.350978) (xy 425.992277 -351.392169) (xy 426.021743 -351.438019)
			(xy 426.044385 -351.487596) (xy 426.05974 -351.539891) (xy 426.067496 -351.593839) (xy 426.067982 -351.62109)
			(xy 426.067516 -351.648665) (xy 426.059564 -351.703238) (xy 426.04384 -351.756098) (xy 426.02067 -351.806144)
			(xy 425.990537 -351.852333) (xy 425.954069 -351.893704) (xy 425.933362 -351.91192) (xy 425.925233 -351.919513)
			(xy 425.915886 -351.939672) (xy 425.915328 -351.950782) (xy 425.915328 -352.027998) (xy 425.915872 -352.039111)
			(xy 425.925227 -352.05927) (xy 425.933362 -352.06686) (xy 425.954049 -352.085097) (xy 425.990523 -352.126459)
			(xy 426.020659 -352.172644) (xy 426.043829 -352.222687) (xy 426.05955 -352.275545) (xy 426.067495 -352.330117)
			(xy 426.067982 -352.35769) (xy 426.06742 -352.386882) (xy 426.058512 -352.444583) (xy 426.040918 -352.500254)
			(xy 426.015049 -352.552595) (xy 425.981509 -352.600384) (xy 425.94108 -352.642507) (xy 425.894706 -352.677978)
			(xy 425.869354 -352.692462) (xy 425.85894 -352.698304) (xy 425.845478 -352.7171) (xy 425.832707 -352.795078)
			(xy 427.90618 -352.795078) (xy 427.906662 -352.767167) (xy 427.914799 -352.711941) (xy 427.930898 -352.65849)
			(xy 427.954613 -352.607955) (xy 427.985438 -352.561416) (xy 428.003716 -352.540316) (xy 428.010066 -352.533204)
			(xy 428.01667 -352.515932) (xy 428.01667 -352.42881) (xy 428.010066 -352.411538) (xy 428.003716 -352.404426)
			(xy 427.985431 -352.383332) (xy 427.954604 -352.336792) (xy 427.93089 -352.286256) (xy 427.914795 -352.232804)
			(xy 427.906664 -352.177576) (xy 427.90618 -352.149664) (xy 427.906666 -352.122413) (xy 427.914422 -352.068465)
			(xy 427.929777 -352.01617) (xy 427.952419 -351.966593) (xy 427.981885 -351.920743) (xy 428.017576 -351.879552)
			(xy 428.058767 -351.843861) (xy 428.104617 -351.814395) (xy 428.154194 -351.791753) (xy 428.206489 -351.776398)
			(xy 428.260437 -351.768642) (xy 428.314939 -351.768642) (xy 428.368887 -351.776398) (xy 428.421182 -351.791753)
			(xy 428.470759 -351.814395) (xy 428.516609 -351.843861) (xy 428.5578 -351.879552) (xy 428.593491 -351.920743)
			(xy 428.622957 -351.966593) (xy 428.645599 -352.01617) (xy 428.660954 -352.068465) (xy 428.66871 -352.122413)
			(xy 428.669196 -352.149664) (xy 428.66872 -352.177575) (xy 428.660578 -352.232801) (xy 428.644477 -352.286251)
			(xy 428.620762 -352.336785) (xy 428.589937 -352.383325) (xy 428.57166 -352.404426) (xy 428.56531 -352.411538)
			(xy 428.558706 -352.42881) (xy 428.558706 -352.515932) (xy 428.56531 -352.533204) (xy 428.57166 -352.540316)
			(xy 428.591324 -352.563089) (xy 428.623969 -352.613628) (xy 428.648262 -352.66867) (xy 428.663599 -352.726848)
			(xy 428.667164 -352.756724) (xy 428.668688 -352.771456) (xy 428.686722 -352.79457) (xy 428.787306 -352.830384)
			(xy 428.79646 -352.83313) (xy 428.815544 -352.832452) (xy 428.833074 -352.824882) (xy 428.840138 -352.818446)
			(xy 428.936404 -352.72218) (xy 428.943067 -352.714757) (xy 428.950651 -352.696329) (xy 428.951136 -352.686366)
			(xy 428.951136 -342.164924) (xy 428.951647 -342.139939) (xy 428.959476 -342.090585) (xy 428.97493 -342.043064)
			(xy 428.997628 -341.998545) (xy 429.02701 -341.958125) (xy 429.044354 -341.940134) (xy 429.795178 -341.18931)
			(xy 429.80191 -341.181913) (xy 429.809626 -341.163483) (xy 429.810164 -341.153496) (xy 429.810164 -340.522306)
			(xy 429.809708 -340.513122) (xy 429.803134 -340.495965) (xy 429.790934 -340.482225) (xy 429.782986 -340.477602)
			(xy 429.691038 -340.428834) (xy 429.663098 -340.430358) (xy 429.651414 -340.438486) (xy 429.627552 -340.454014)
			(xy 429.576222 -340.478629) (xy 429.521802 -340.495336) (xy 429.465502 -340.503763) (xy 429.437038 -340.504272)
			(xy 429.409784 -340.503809) (xy 429.355832 -340.496057) (xy 429.303532 -340.480703) (xy 429.253949 -340.458063)
			(xy 429.208094 -340.428595) (xy 429.1669 -340.392901) (xy 429.131206 -340.351707) (xy 429.101738 -340.305853)
			(xy 429.079097 -340.25627) (xy 429.063744 -340.20397) (xy 429.055991 -340.150018) (xy 429.05553 -340.122764)
			(xy 429.055968 -340.095393) (xy 429.063791 -340.041212) (xy 429.079287 -339.988708) (xy 429.102135 -339.938962)
			(xy 429.131866 -339.892997) (xy 429.14951 -339.872066) (xy 429.155606 -339.864954) (xy 429.161956 -339.847936)
			(xy 429.161956 -339.762592) (xy 429.155606 -339.745574) (xy 429.14951 -339.738462) (xy 429.131835 -339.717557)
			(xy 429.102113 -339.671584) (xy 429.07927 -339.621833) (xy 429.063778 -339.569327) (xy 429.055953 -339.515145)
			(xy 429.055957 -339.460401) (xy 429.063789 -339.40622) (xy 429.07929 -339.353716) (xy 429.102139 -339.303968)
			(xy 429.131867 -339.257999) (xy 429.14951 -339.237066) (xy 429.155606 -339.229954) (xy 429.161956 -339.212936)
			(xy 429.161956 -339.127592) (xy 429.155606 -339.110574) (xy 429.14951 -339.103462) (xy 429.131835 -339.082557)
			(xy 429.102113 -339.036584) (xy 429.07927 -338.986833) (xy 429.063778 -338.934327) (xy 429.055953 -338.880145)
			(xy 429.055957 -338.825401) (xy 429.063789 -338.77122) (xy 429.07929 -338.718716) (xy 429.102139 -338.668968)
			(xy 429.131867 -338.622999) (xy 429.14951 -338.602066) (xy 429.155606 -338.594954) (xy 429.161956 -338.577936)
			(xy 429.161956 -338.492592) (xy 429.155606 -338.475574) (xy 429.14951 -338.468462) (xy 429.131835 -338.447557)
			(xy 429.102113 -338.401584) (xy 429.07927 -338.351833) (xy 429.063778 -338.299327) (xy 429.055953 -338.245145)
			(xy 429.055957 -338.190401) (xy 429.063789 -338.13622) (xy 429.07929 -338.083716) (xy 429.102139 -338.033968)
			(xy 429.131867 -337.987999) (xy 429.14951 -337.967066) (xy 429.155606 -337.959954) (xy 429.161956 -337.942936)
			(xy 429.161956 -337.857592) (xy 429.155606 -337.840574) (xy 429.14951 -337.833462) (xy 429.131835 -337.812557)
			(xy 429.102113 -337.766584) (xy 429.07927 -337.716833) (xy 429.063778 -337.664327) (xy 429.055953 -337.610145)
			(xy 429.055957 -337.555401) (xy 429.063789 -337.50122) (xy 429.07929 -337.448716) (xy 429.102139 -337.398968)
			(xy 429.131867 -337.352999) (xy 429.14951 -337.332066) (xy 429.155606 -337.324954) (xy 429.161956 -337.307936)
			(xy 429.161956 -337.222592) (xy 429.155606 -337.205574) (xy 429.14951 -337.198462) (xy 429.131888 -337.177516)
			(xy 429.102173 -337.131547) (xy 429.079334 -337.081803) (xy 429.063839 -337.029306) (xy 429.056006 -336.975132)
			(xy 429.05553 -336.947764) (xy 429.055922 -336.920508) (xy 429.063684 -336.866553) (xy 429.079047 -336.814251)
			(xy 429.101696 -336.764669) (xy 429.131172 -336.718814) (xy 429.166873 -336.67762) (xy 429.208073 -336.641927)
			(xy 429.253934 -336.612461) (xy 429.303521 -336.589821) (xy 429.355825 -336.574469) (xy 429.409782 -336.566716)
			(xy 429.437038 -336.566256) (xy 429.464676 -336.566754) (xy 429.519371 -336.574746) (xy 429.572342 -336.590543)
			(xy 429.62248 -336.613814) (xy 429.668738 -336.644074) (xy 429.689768 -336.662014) (xy 429.69688 -336.66811)
			(xy 429.714152 -336.674714) (xy 429.800004 -336.674714) (xy 429.817276 -336.66811) (xy 429.824388 -336.662014)
			(xy 429.845425 -336.644081) (xy 429.891673 -336.613804) (xy 429.941809 -336.590523) (xy 429.994781 -336.574727)
			(xy 430.049479 -336.566747) (xy 430.077118 -336.566256) (xy 430.103911 -336.56672) (xy 430.15697 -336.574227)
			(xy 430.208459 -336.589076) (xy 430.257366 -336.610977) (xy 430.302732 -336.639499) (xy 430.343666 -336.674082)
			(xy 430.361852 -336.693764) (xy 430.369218 -336.702146) (xy 430.388522 -336.710782) (xy 430.486058 -336.711036)
			(xy 430.505616 -336.7024) (xy 430.512982 -336.694272) (xy 430.531135 -336.674865) (xy 430.571932 -336.640812)
			(xy 430.617058 -336.612745) (xy 430.665639 -336.591208) (xy 430.716738 -336.576616) (xy 430.769367 -336.569252)
			(xy 430.795938 -336.568796) (xy 430.82319 -336.569242) (xy 430.87714 -336.577004) (xy 430.929435 -336.592364)
			(xy 430.979013 -336.61501) (xy 431.024863 -336.644481) (xy 431.066053 -336.680176) (xy 431.101744 -336.72137)
			(xy 431.13121 -336.767224) (xy 431.15385 -336.816804) (xy 431.169205 -336.869101) (xy 431.176961 -336.923052)
			(xy 431.177446 -336.950304) (xy 431.177009 -336.97628) (xy 431.169965 -337.027751) (xy 431.155996 -337.077789)
			(xy 431.135359 -337.125465) (xy 431.108438 -337.169896) (xy 431.075731 -337.210259) (xy 431.037845 -337.245806)
			(xy 431.016918 -337.2612) (xy 431.007401 -337.268805) (xy 430.996271 -337.290438) (xy 430.995582 -337.302602)
			(xy 430.995582 -337.385406) (xy 430.996285 -337.397567) (xy 431.007414 -337.41919) (xy 431.016918 -337.426808)
			(xy 431.037848 -337.442196) (xy 431.075726 -337.47775) (xy 431.108427 -337.518117) (xy 431.135345 -337.562549)
			(xy 431.155982 -337.610224) (xy 431.169955 -337.66026) (xy 431.177007 -337.711729) (xy 431.177446 -337.737704)
			(xy 431.176995 -337.765075) (xy 431.169176 -337.819255) (xy 431.153684 -337.871759) (xy 431.130838 -337.921506)
			(xy 431.10111 -337.967471) (xy 431.083466 -337.988402) (xy 431.07737 -337.995514) (xy 431.07102 -338.012532)
			(xy 431.07102 -338.097876) (xy 431.07737 -338.114894) (xy 431.083466 -338.122006) (xy 431.101111 -338.142935)
			(xy 431.130836 -338.188904) (xy 431.153682 -338.23865) (xy 431.169178 -338.291153) (xy 431.177006 -338.345332)
			(xy 431.177006 -338.400074) (xy 431.169177 -338.454253) (xy 431.15368 -338.506755) (xy 431.130833 -338.556502)
			(xy 431.101107 -338.602469) (xy 431.083466 -338.623402) (xy 431.07737 -338.630514) (xy 431.07102 -338.647532)
			(xy 431.07102 -338.732876) (xy 431.07737 -338.749894) (xy 431.083466 -338.757006) (xy 431.101116 -338.777929)
			(xy 431.130827 -338.823904) (xy 431.153662 -338.873654) (xy 431.16915 -338.926156) (xy 431.176974 -338.980334)
			(xy 431.177446 -339.007704) (xy 432.785774 -339.007704) (xy 432.786224 -338.980333) (xy 432.794043 -338.926153)
			(xy 432.809535 -338.873649) (xy 432.832381 -338.823902) (xy 432.86211 -338.777936) (xy 432.879754 -338.757006)
			(xy 432.88585 -338.749894) (xy 432.8922 -338.732876) (xy 432.8922 -338.647532) (xy 432.88585 -338.630514)
			(xy 432.879754 -338.623402) (xy 432.862116 -338.602467) (xy 432.832389 -338.5565) (xy 432.809542 -338.506754)
			(xy 432.794044 -338.454252) (xy 432.786215 -338.400074) (xy 432.786214 -338.345332) (xy 432.794043 -338.291153)
			(xy 432.80954 -338.238651) (xy 432.832386 -338.188905) (xy 432.862112 -338.142938) (xy 432.879754 -338.122006)
			(xy 432.88585 -338.114894) (xy 432.8922 -338.097876) (xy 432.8922 -338.012532) (xy 432.88585 -337.995514)
			(xy 432.879754 -337.988402) (xy 432.862111 -337.967473) (xy 432.832398 -337.9215) (xy 432.809562 -337.871752)
			(xy 432.794072 -337.81925) (xy 432.786246 -337.765074) (xy 432.785774 -337.737704) (xy 432.786209 -337.711728)
			(xy 432.793252 -337.660256) (xy 432.807221 -337.610218) (xy 432.827858 -337.562542) (xy 432.85478 -337.51811)
			(xy 432.887487 -337.477747) (xy 432.925374 -337.442202) (xy 432.946302 -337.426808) (xy 432.955801 -337.419184)
			(xy 432.966944 -337.397566) (xy 432.967638 -337.385406) (xy 432.967638 -337.302602) (xy 432.966982 -337.290435)
			(xy 432.955818 -337.268813) (xy 432.946302 -337.2612) (xy 432.925358 -337.24583) (xy 432.887484 -337.210271)
			(xy 432.854787 -337.1699) (xy 432.827872 -337.125464) (xy 432.807238 -337.077787) (xy 432.793265 -337.02775)
			(xy 432.786213 -336.97628) (xy 432.785774 -336.950304) (xy 432.786281 -336.923054) (xy 432.794037 -336.869108)
			(xy 432.809391 -336.816814) (xy 432.83203 -336.767238) (xy 432.861494 -336.721389) (xy 432.897183 -336.680199)
			(xy 432.938371 -336.644507) (xy 432.984219 -336.615041) (xy 433.033794 -336.592398) (xy 433.086086 -336.577042)
			(xy 433.140032 -336.569283) (xy 433.167282 -336.568796) (xy 433.197081 -336.569368) (xy 433.255951 -336.578646)
			(xy 433.312664 -336.596962) (xy 433.36584 -336.623873) (xy 433.414186 -336.658722) (xy 433.43576 -336.679286)
			(xy 433.442872 -336.686398) (xy 433.460652 -336.693764) (xy 433.551076 -336.695288) (xy 433.56911 -336.68843)
			(xy 433.576476 -336.681572) (xy 433.597798 -336.662565) (xy 433.64499 -336.630391) (xy 433.69645 -336.605608)
			(xy 433.751028 -336.588771) (xy 433.807506 -336.580254) (xy 433.836064 -336.579718) (xy 433.863703 -336.580185)
			(xy 433.9184 -336.588182) (xy 433.971372 -336.603985) (xy 434.02151 -336.627264) (xy 434.067766 -336.657532)
			(xy 434.088794 -336.675476) (xy 434.095906 -336.681572) (xy 434.113178 -336.688176) (xy 434.19903 -336.688176)
			(xy 434.216302 -336.681572) (xy 434.223414 -336.675476) (xy 434.244436 -336.657525) (xy 434.290689 -336.627252)
			(xy 434.340829 -336.603975) (xy 434.393804 -336.588183) (xy 434.448504 -336.580207) (xy 434.476144 -336.579718)
			(xy 434.503398 -336.580137) (xy 434.557349 -336.5879) (xy 434.609647 -336.603262) (xy 434.659226 -336.62591)
			(xy 434.705077 -336.655384) (xy 434.746268 -336.691082) (xy 434.781958 -336.732279) (xy 434.811423 -336.778136)
			(xy 434.834062 -336.827719) (xy 434.849415 -336.88002) (xy 434.857168 -336.933972) (xy 434.857652 -336.961226)
			(xy 434.857213 -336.988597) (xy 434.84939 -337.042778) (xy 434.833896 -337.095282) (xy 434.811048 -337.145028)
			(xy 434.781317 -337.190994) (xy 434.763672 -337.211924) (xy 434.757576 -337.219036) (xy 434.751226 -337.236054)
			(xy 434.751226 -337.321398) (xy 434.757576 -337.338416) (xy 434.763672 -337.345528) (xy 434.781338 -337.36644)
			(xy 434.811062 -337.412411) (xy 434.833906 -337.462161) (xy 434.8494 -337.514666) (xy 434.857226 -337.568848)
			(xy 434.857224 -337.623591) (xy 434.849392 -337.677772) (xy 434.833892 -337.730276) (xy 434.811043 -337.780023)
			(xy 434.781315 -337.825991) (xy 434.763672 -337.846924) (xy 434.757576 -337.854036) (xy 434.751226 -337.871054)
			(xy 434.751226 -337.956398) (xy 434.757576 -337.973416) (xy 434.763672 -337.980528) (xy 434.781338 -338.00144)
			(xy 434.811062 -338.047411) (xy 434.833906 -338.097161) (xy 434.8494 -338.149666) (xy 434.857226 -338.203848)
			(xy 434.857224 -338.258591) (xy 434.849392 -338.312772) (xy 434.833892 -338.365276) (xy 434.811043 -338.415023)
			(xy 434.781315 -338.460991) (xy 434.763672 -338.481924) (xy 434.757576 -338.489036) (xy 434.751226 -338.506054)
			(xy 434.751226 -338.591398) (xy 434.757576 -338.608416) (xy 434.763672 -338.615528) (xy 434.781338 -338.63644)
			(xy 434.811062 -338.682411) (xy 434.833906 -338.732161) (xy 434.8494 -338.784666) (xy 434.857226 -338.838848)
			(xy 434.857224 -338.893591) (xy 434.849392 -338.947772) (xy 434.833892 -339.000276) (xy 434.811043 -339.050023)
			(xy 434.781315 -339.095991) (xy 434.763672 -339.116924) (xy 434.757576 -339.124036) (xy 434.751226 -339.141054)
			(xy 434.751226 -339.226398) (xy 434.757576 -339.243416) (xy 434.763672 -339.250528) (xy 434.781338 -339.27144)
			(xy 434.811062 -339.317411) (xy 434.833906 -339.367161) (xy 434.8494 -339.419666) (xy 434.857226 -339.473848)
			(xy 434.857224 -339.528591) (xy 434.849392 -339.582772) (xy 434.833892 -339.635276) (xy 434.811043 -339.685023)
			(xy 434.781315 -339.730991) (xy 434.763672 -339.751924) (xy 434.757576 -339.759036) (xy 434.751226 -339.776054)
			(xy 434.751226 -339.861398) (xy 434.757576 -339.878416) (xy 434.763672 -339.885528) (xy 434.781286 -339.90648)
			(xy 434.811003 -339.952447) (xy 434.833844 -340.002189) (xy 434.849341 -340.054686) (xy 434.857175 -340.108858)
			(xy 434.857386 -340.120986) (xy 435.837076 -340.120986) (xy 435.837515 -340.093615) (xy 435.845337 -340.039434)
			(xy 435.860831 -339.98693) (xy 435.883679 -339.937183) (xy 435.913411 -339.891218) (xy 435.931056 -339.870288)
			(xy 435.937152 -339.863176) (xy 435.943502 -339.846158) (xy 435.943502 -339.760814) (xy 435.937152 -339.743796)
			(xy 435.931056 -339.736684) (xy 435.9134 -339.715763) (xy 435.883674 -339.669794) (xy 435.860828 -339.620046)
			(xy 435.845331 -339.567542) (xy 435.837503 -339.513361) (xy 435.837505 -339.458618) (xy 435.845336 -339.404438)
			(xy 435.860835 -339.351934) (xy 435.883684 -339.302188) (xy 435.913413 -339.25622) (xy 435.931056 -339.235288)
			(xy 435.937152 -339.228176) (xy 435.943502 -339.211158) (xy 435.943502 -339.125814) (xy 435.937152 -339.108796)
			(xy 435.931056 -339.101684) (xy 435.9134 -339.080763) (xy 435.883674 -339.034794) (xy 435.860828 -338.985046)
			(xy 435.845331 -338.932542) (xy 435.837503 -338.878361) (xy 435.837505 -338.823618) (xy 435.845336 -338.769438)
			(xy 435.860835 -338.716934) (xy 435.883684 -338.667188) (xy 435.913413 -338.62122) (xy 435.931056 -338.600288)
			(xy 435.937152 -338.593176) (xy 435.943502 -338.576158) (xy 435.943502 -338.490814) (xy 435.937152 -338.473796)
			(xy 435.931056 -338.466684) (xy 435.9134 -338.445763) (xy 435.883674 -338.399794) (xy 435.860828 -338.350046)
			(xy 435.845331 -338.297542) (xy 435.837503 -338.243361) (xy 435.837505 -338.188618) (xy 435.845336 -338.134438)
			(xy 435.860835 -338.081934) (xy 435.883684 -338.032188) (xy 435.913413 -337.98622) (xy 435.931056 -337.965288)
			(xy 435.937152 -337.958176) (xy 435.943502 -337.941158) (xy 435.943502 -337.855814) (xy 435.937152 -337.838796)
			(xy 435.931056 -337.831684) (xy 435.9134 -337.810763) (xy 435.883674 -337.764794) (xy 435.860828 -337.715046)
			(xy 435.845331 -337.662542) (xy 435.837503 -337.608361) (xy 435.837505 -337.553618) (xy 435.845336 -337.499438)
			(xy 435.860835 -337.446934) (xy 435.883684 -337.397188) (xy 435.913413 -337.35122) (xy 435.931056 -337.330288)
			(xy 435.937152 -337.323176) (xy 435.943502 -337.306158) (xy 435.943502 -337.220814) (xy 435.937152 -337.203796)
			(xy 435.931056 -337.196684) (xy 435.913436 -337.175737) (xy 435.883722 -337.129768) (xy 435.860883 -337.080024)
			(xy 435.845388 -337.027527) (xy 435.837553 -336.973354) (xy 435.837076 -336.945986) (xy 435.837565 -336.918735)
			(xy 435.845323 -336.864788) (xy 435.860679 -336.812495) (xy 435.88332 -336.762918) (xy 435.912787 -336.717069)
			(xy 435.948478 -336.675879) (xy 435.989667 -336.640188) (xy 436.035517 -336.610721) (xy 436.085093 -336.58808)
			(xy 436.137386 -336.572723) (xy 436.191333 -336.564965) (xy 436.218584 -336.564478) (xy 436.246221 -336.565002)
			(xy 436.300915 -336.572987) (xy 436.353886 -336.588777) (xy 436.404025 -336.612043) (xy 436.450284 -336.642298)
			(xy 436.471314 -336.660236) (xy 436.478426 -336.666332) (xy 436.495698 -336.672936) (xy 436.58155 -336.672936)
			(xy 436.598822 -336.666332) (xy 436.605934 -336.660236) (xy 436.626943 -336.642269) (xy 436.6732 -336.612)
			(xy 436.723343 -336.588727) (xy 436.776321 -336.572938) (xy 436.831024 -336.564965) (xy 436.858664 -336.564478)
			(xy 436.885915 -336.564989) (xy 436.939864 -336.57274) (xy 436.99216 -336.588091) (xy 437.041739 -336.610729)
			(xy 437.087592 -336.640191) (xy 437.128784 -336.67588) (xy 437.164479 -336.717068) (xy 437.193947 -336.762917)
			(xy 437.216591 -336.812493) (xy 437.231949 -336.864787) (xy 437.239708 -336.918735) (xy 437.240172 -336.945986)
			(xy 437.239705 -336.973356) (xy 437.231888 -337.027536) (xy 437.2164 -337.080039) (xy 437.193558 -337.129786)
			(xy 437.163833 -337.175752) (xy 437.146192 -337.196684) (xy 437.140096 -337.203796) (xy 437.133746 -337.220814)
			(xy 437.133746 -337.306158) (xy 437.140096 -337.323176) (xy 437.146192 -337.330288) (xy 437.163818 -337.351232)
			(xy 437.193542 -337.397198) (xy 437.216387 -337.446943) (xy 437.231884 -337.499443) (xy 437.239713 -337.55362)
			(xy 437.239715 -337.608359) (xy 437.231888 -337.662536) (xy 437.216395 -337.715037) (xy 437.193552 -337.764783)
			(xy 437.163831 -337.810751) (xy 437.146192 -337.831684) (xy 437.140096 -337.838796) (xy 437.133746 -337.855814)
			(xy 437.133746 -337.941158) (xy 437.140096 -337.958176) (xy 437.146192 -337.965288) (xy 437.163818 -337.986232)
			(xy 437.193542 -338.032198) (xy 437.216387 -338.081943) (xy 437.231884 -338.134443) (xy 437.239713 -338.18862)
			(xy 437.239715 -338.243359) (xy 437.231888 -338.297536) (xy 437.216395 -338.350037) (xy 437.193552 -338.399783)
			(xy 437.163831 -338.445751) (xy 437.146192 -338.466684) (xy 437.140096 -338.473796) (xy 437.133746 -338.490814)
			(xy 437.133746 -338.576158) (xy 437.140096 -338.593176) (xy 437.146192 -338.600288) (xy 437.163818 -338.621232)
			(xy 437.193542 -338.667198) (xy 437.216387 -338.716943) (xy 437.231884 -338.769443) (xy 437.239713 -338.82362)
			(xy 437.239715 -338.878359) (xy 437.231888 -338.932536) (xy 437.216395 -338.985037) (xy 437.193552 -339.034783)
			(xy 437.163831 -339.080751) (xy 437.146192 -339.101684) (xy 437.140096 -339.108796) (xy 437.133746 -339.125814)
			(xy 437.133746 -339.211158) (xy 437.140096 -339.228176) (xy 437.146192 -339.235288) (xy 437.163818 -339.256232)
			(xy 437.193542 -339.302198) (xy 437.216387 -339.351943) (xy 437.231884 -339.404443) (xy 437.239713 -339.45862)
			(xy 437.239715 -339.513359) (xy 437.231888 -339.567536) (xy 437.216395 -339.620037) (xy 437.193552 -339.669783)
			(xy 437.163831 -339.715751) (xy 437.146192 -339.736684) (xy 437.140096 -339.743796) (xy 437.133746 -339.760814)
			(xy 437.133746 -339.846158) (xy 437.140096 -339.863176) (xy 437.146192 -339.870288) (xy 437.163838 -339.891215)
			(xy 437.193549 -339.937189) (xy 437.216384 -339.986938) (xy 437.231873 -340.03944) (xy 437.239699 -340.093616)
			(xy 437.240172 -340.120986) (xy 437.239659 -340.148188) (xy 437.231907 -340.202038) (xy 437.216586 -340.254242)
			(xy 437.194007 -340.30374) (xy 437.164628 -340.349531) (xy 437.129044 -340.390686) (xy 437.087977 -340.42637)
			(xy 437.042258 -340.455861) (xy 436.992814 -340.47856) (xy 436.966868 -340.486746) (xy 436.9562 -340.490048)
			(xy 436.939944 -340.503764) (xy 436.898288 -340.592664) (xy 436.89778 -340.614) (xy 436.902352 -340.62416)
			(xy 436.91203 -340.647897) (xy 436.925611 -340.697328) (xy 436.932439 -340.748134) (xy 436.932832 -340.773766)
			(xy 436.932363 -340.801136) (xy 436.924548 -340.855316) (xy 436.909061 -340.90782) (xy 436.886219 -340.957567)
			(xy 436.856494 -341.003533) (xy 436.838852 -341.024464) (xy 436.832756 -341.031576) (xy 436.826406 -341.048594)
			(xy 436.826406 -341.133938) (xy 436.832756 -341.150956) (xy 436.838852 -341.158068) (xy 436.856482 -341.179007)
			(xy 436.886197 -341.224977) (xy 436.909035 -341.274723) (xy 436.924528 -341.327222) (xy 436.932358 -341.381397)
			(xy 436.932832 -341.408766) (xy 436.932346 -341.436017) (xy 436.92459 -341.489965) (xy 436.909235 -341.54226)
			(xy 436.886593 -341.591837) (xy 436.857127 -341.637687) (xy 436.821436 -341.678878) (xy 436.780245 -341.714569)
			(xy 436.734395 -341.744035) (xy 436.684818 -341.766677) (xy 436.632523 -341.782032) (xy 436.578575 -341.789788)
			(xy 436.524073 -341.789788) (xy 436.470125 -341.782032) (xy 436.41783 -341.766677) (xy 436.368253 -341.744035)
			(xy 436.322403 -341.714569) (xy 436.281212 -341.678878) (xy 436.245521 -341.637687) (xy 436.216055 -341.591837)
			(xy 436.193413 -341.54226) (xy 436.178058 -341.489965) (xy 436.170302 -341.436017) (xy 436.169816 -341.408766)
			(xy 436.170258 -341.381395) (xy 436.178081 -341.327215) (xy 436.193576 -341.274711) (xy 436.216423 -341.224965)
			(xy 436.246152 -341.178999) (xy 436.263796 -341.158068) (xy 436.269892 -341.150956) (xy 436.276242 -341.133938)
			(xy 436.276242 -341.048594) (xy 436.269892 -341.031576) (xy 436.263796 -341.024464) (xy 436.246173 -341.003519)
			(xy 436.216459 -340.95755) (xy 436.19362 -340.907806) (xy 436.178125 -340.855308) (xy 436.170292 -340.801134)
			(xy 436.169816 -340.773766) (xy 436.170198 -340.74901) (xy 436.176577 -340.69991) (xy 436.189251 -340.652046)
			(xy 436.198264 -340.628986) (xy 436.202582 -340.618572) (xy 436.201566 -340.596474) (xy 436.156608 -340.508082)
			(xy 436.139082 -340.494366) (xy 436.128414 -340.491572) (xy 436.1011 -340.484369) (xy 436.04878 -340.463081)
			(xy 436.000172 -340.434309) (xy 435.956338 -340.398684) (xy 435.918238 -340.356983) (xy 435.886704 -340.31012)
			(xy 435.862426 -340.259118) (xy 435.845936 -340.205094) (xy 435.837593 -340.149228) (xy 435.837076 -340.120986)
			(xy 434.857386 -340.120986) (xy 434.857652 -340.136226) (xy 434.857149 -340.164182) (xy 434.848973 -340.219492)
			(xy 434.832815 -340.273018) (xy 434.80902 -340.323614) (xy 434.778097 -340.370196) (xy 434.740709 -340.411768)
			(xy 434.697655 -340.44744) (xy 434.67401 -340.462362) (xy 434.66385 -340.468458) (xy 434.65115 -340.488016)
			(xy 434.638958 -340.590632) (xy 434.646324 -340.61273) (xy 434.654706 -340.621112) (xy 434.675432 -340.642729)
			(xy 434.710608 -340.691193) (xy 434.737775 -340.744559) (xy 434.756266 -340.801517) (xy 434.765626 -340.860664)
			(xy 434.766212 -340.890606) (xy 434.765747 -340.917976) (xy 434.757928 -340.972155) (xy 434.742439 -341.024658)
			(xy 434.719597 -341.074405) (xy 434.689873 -341.120372) (xy 434.672232 -341.141304) (xy 434.666136 -341.148416)
			(xy 434.659786 -341.165434) (xy 434.659786 -341.250778) (xy 434.666136 -341.267796) (xy 434.672232 -341.274908)
			(xy 434.689893 -341.295822) (xy 434.719601 -341.3418) (xy 434.742432 -341.391552) (xy 434.757918 -341.444057)
			(xy 434.765741 -341.498236) (xy 434.766212 -341.525606) (xy 434.765726 -341.552857) (xy 434.75797 -341.606805)
			(xy 434.742615 -341.6591) (xy 434.719973 -341.708677) (xy 434.690507 -341.754527) (xy 434.654816 -341.795718)
			(xy 434.613625 -341.831409) (xy 434.567775 -341.860875) (xy 434.518198 -341.883517) (xy 434.465903 -341.898872)
			(xy 434.411955 -341.906628) (xy 434.357453 -341.906628) (xy 434.303505 -341.898872) (xy 434.25121 -341.883517)
			(xy 434.201633 -341.860875) (xy 434.155783 -341.831409) (xy 434.114592 -341.795718) (xy 434.078901 -341.754527)
			(xy 434.049435 -341.708677) (xy 434.026793 -341.6591) (xy 434.011438 -341.606805) (xy 434.003682 -341.552857)
			(xy 434.003196 -341.525606) (xy 434.003667 -341.498236) (xy 434.011483 -341.444057) (xy 434.026972 -341.391554)
			(xy 434.049812 -341.341807) (xy 434.079535 -341.29584) (xy 434.097176 -341.274908) (xy 434.103272 -341.267796)
			(xy 434.109622 -341.250778) (xy 434.109622 -341.165434) (xy 434.103272 -341.148416) (xy 434.097176 -341.141304)
			(xy 434.079522 -341.120384) (xy 434.049813 -341.074408) (xy 434.02698 -341.024657) (xy 434.011493 -340.972154)
			(xy 434.003668 -340.917976) (xy 434.003196 -340.890606) (xy 434.0037 -340.863827) (xy 434.011197 -340.810795)
			(xy 434.026031 -340.759332) (xy 434.04791 -340.710446) (xy 434.076406 -340.665097) (xy 434.11096 -340.624175)
			(xy 434.150892 -340.588483) (xy 434.195421 -340.558721) (xy 434.21935 -340.54669) (xy 434.226894 -340.542743)
			(xy 434.238981 -340.530762) (xy 434.246458 -340.515475) (xy 434.247798 -340.507066) (xy 434.255164 -340.447122)
			(xy 434.234336 -340.431374) (xy 434.226716 -340.425024) (xy 434.208174 -340.419182) (xy 434.118512 -340.42604)
			(xy 434.100986 -340.434676) (xy 434.094382 -340.442042) (xy 434.076221 -340.461583) (xy 434.035386 -340.495913)
			(xy 433.990166 -340.524215) (xy 433.941442 -340.545939) (xy 433.890165 -340.56066) (xy 433.837338 -340.568091)
			(xy 433.810664 -340.568534) (xy 433.783413 -340.568056) (xy 433.729466 -340.560295) (xy 433.677173 -340.544937)
			(xy 433.627597 -340.522293) (xy 433.581749 -340.492826) (xy 433.540559 -340.457134) (xy 433.504868 -340.415943)
			(xy 433.475402 -340.370094) (xy 433.45276 -340.320517) (xy 433.437403 -340.268224) (xy 433.429644 -340.214277)
			(xy 433.429156 -340.187026) (xy 433.429624 -340.159656) (xy 433.437439 -340.105476) (xy 433.452927 -340.052972)
			(xy 433.475769 -340.003226) (xy 433.505494 -339.957259) (xy 433.523136 -339.936328) (xy 433.529232 -339.929216)
			(xy 433.535582 -339.912198) (xy 433.535582 -339.826854) (xy 433.529232 -339.809836) (xy 433.523136 -339.802724)
			(xy 433.5055 -339.781789) (xy 433.475787 -339.735818) (xy 433.45295 -339.686071) (xy 433.437458 -339.633571)
			(xy 433.42963 -339.579395) (xy 433.429156 -339.552026) (xy 433.429345 -339.533816) (xy 433.432778 -339.497558)
			(xy 433.436014 -339.479636) (xy 433.438808 -339.46592) (xy 433.429664 -339.440266) (xy 433.340764 -339.364828)
			(xy 433.31384 -339.360256) (xy 433.300886 -339.365082) (xy 433.268631 -339.376312) (xy 433.201427 -339.388452)
			(xy 433.167282 -339.389212) (xy 433.14003 -339.388739) (xy 433.086083 -339.38098) (xy 433.033788 -339.365623)
			(xy 432.984211 -339.34298) (xy 432.938361 -339.313512) (xy 432.897171 -339.277819) (xy 432.861479 -339.236628)
			(xy 432.832013 -339.190777) (xy 432.809372 -339.141199) (xy 432.794017 -339.088904) (xy 432.78626 -339.034956)
			(xy 432.785774 -339.007704) (xy 431.177446 -339.007704) (xy 431.176926 -339.034954) (xy 431.16917 -339.088898)
			(xy 431.153816 -339.14119) (xy 431.131177 -339.190765) (xy 431.101714 -339.236613) (xy 431.066026 -339.277802)
			(xy 431.02484 -339.313494) (xy 430.978995 -339.342961) (xy 430.929422 -339.365604) (xy 430.877131 -339.380963)
			(xy 430.823188 -339.388724) (xy 430.795938 -339.389212) (xy 430.769797 -339.388796) (xy 430.718005 -339.381658)
			(xy 430.667673 -339.367512) (xy 430.643538 -339.357462) (xy 430.63033 -339.35162) (xy 430.602898 -339.35543)
			(xy 430.510188 -339.428836) (xy 430.500536 -339.454998) (xy 430.503076 -339.468968) (xy 430.506064 -339.486211)
			(xy 430.509241 -339.521065) (xy 430.509426 -339.538564) (xy 430.508957 -339.565934) (xy 430.501143 -339.620114)
			(xy 430.485655 -339.672618) (xy 430.462814 -339.722365) (xy 430.433088 -339.768331) (xy 430.415446 -339.789262)
			(xy 430.40935 -339.796374) (xy 430.403 -339.813392) (xy 430.403 -339.898736) (xy 430.40935 -339.915754)
			(xy 430.415446 -339.922866) (xy 430.433074 -339.943807) (xy 430.46279 -339.989777) (xy 430.485628 -340.039522)
			(xy 430.501122 -340.092021) (xy 430.508952 -340.146195) (xy 430.509426 -340.173564) (xy 430.508984 -340.199766)
			(xy 430.501811 -340.251675) (xy 430.487595 -340.302113) (xy 430.466606 -340.350129) (xy 430.453292 -340.3727)
			(xy 430.449765 -340.378796) (xy 430.445897 -340.392331) (xy 430.445672 -340.39937) (xy 430.445672 -341.30615)
			(xy 430.445172 -341.331124) (xy 430.437385 -341.38046) (xy 430.421979 -341.427972) (xy 430.399334 -341.472491)
			(xy 430.370006 -341.512921) (xy 430.352708 -341.53094) (xy 429.601884 -342.281764) (xy 429.595214 -342.289182)
			(xy 429.587632 -342.307613) (xy 429.587152 -342.317578) (xy 429.587152 -352.83902) (xy 429.586672 -352.864007)
			(xy 429.578836 -352.913362) (xy 429.563375 -352.960884) (xy 429.54067 -353.005402) (xy 429.511281 -353.04582)
			(xy 429.493934 -353.06381) (xy 429.429144 -353.1286) (xy 432.288439 -353.1286) (xy 432.292607 -353.072986)
			(xy 432.305016 -353.018615) (xy 432.32539 -352.9667) (xy 432.353273 -352.918401) (xy 432.388044 -352.874798)
			(xy 432.428924 -352.836863) (xy 432.475001 -352.805444) (xy 432.525246 -352.781244) (xy 432.578537 -352.764802)
			(xy 432.633683 -352.756485) (xy 432.661568 -352.755962) (xy 432.687991 -352.756389) (xy 432.740307 -352.763848)
			(xy 432.791046 -352.778621) (xy 432.83919 -352.800411) (xy 432.883773 -352.828782) (xy 432.904138 -352.845624)
			(xy 432.910996 -352.85172) (xy 432.928014 -352.857816) (xy 433.012342 -352.857816) (xy 433.02936 -352.85172)
			(xy 433.036218 -352.845624) (xy 433.056584 -352.828785) (xy 433.10117 -352.80042) (xy 433.149314 -352.778633)
			(xy 433.200051 -352.763862) (xy 433.252366 -352.756402) (xy 433.30521 -352.756402) (xy 433.357525 -352.763862)
			(xy 433.408262 -352.778633) (xy 433.456406 -352.80042) (xy 433.500992 -352.828785) (xy 433.521358 -352.845624)
			(xy 433.528216 -352.85172) (xy 433.545234 -352.857816) (xy 433.629562 -352.857816) (xy 433.64658 -352.85172)
			(xy 433.653438 -352.845624) (xy 433.66733 -352.834037) (xy 433.696974 -352.813302) (xy 433.71262 -352.804222)
			(xy 433.723034 -352.79838) (xy 433.736242 -352.779076) (xy 433.751482 -352.67646) (xy 433.744624 -352.654362)
			(xy 433.736496 -352.645726) (xy 433.716915 -352.624343) (xy 433.683797 -352.576757) (xy 433.658266 -352.524705)
			(xy 433.640912 -352.469387) (xy 433.632134 -352.412078) (xy 433.631594 -352.38309) (xy 433.632124 -352.355518)
			(xy 433.640063 -352.300948) (xy 433.655776 -352.248089) (xy 433.678934 -352.198043) (xy 433.709055 -352.151852)
			(xy 433.745512 -352.110478) (xy 433.766214 -352.09226) (xy 433.774348 -352.084672) (xy 433.783693 -352.064509)
			(xy 433.784248 -352.053398) (xy 433.784248 -351.976182) (xy 433.783723 -351.965067) (xy 433.774356 -351.944907)
			(xy 433.766214 -351.93732) (xy 433.745512 -351.919099) (xy 433.709041 -351.877732) (xy 433.678907 -351.831545)
			(xy 433.655739 -351.781499) (xy 433.640021 -351.728638) (xy 433.63208 -351.674064) (xy 433.631594 -351.64649)
			(xy 433.63208 -351.619239) (xy 433.639836 -351.565291) (xy 433.655191 -351.512996) (xy 433.677833 -351.463419)
			(xy 433.707299 -351.417569) (xy 433.74299 -351.376378) (xy 433.784181 -351.340687) (xy 433.830031 -351.311221)
			(xy 433.879608 -351.288579) (xy 433.931903 -351.273224) (xy 433.985851 -351.265468) (xy 434.040353 -351.265468)
			(xy 434.094301 -351.273224) (xy 434.146596 -351.288579) (xy 434.196173 -351.311221) (xy 434.242023 -351.340687)
			(xy 434.283214 -351.376378) (xy 434.318905 -351.417569) (xy 434.348371 -351.463419) (xy 434.371013 -351.512996)
			(xy 434.386368 -351.565291) (xy 434.394124 -351.619239) (xy 434.39461 -351.64649) (xy 434.394134 -351.674064)
			(xy 434.386183 -351.728636) (xy 434.37046 -351.781496) (xy 434.347292 -351.831542) (xy 434.317161 -351.877732)
			(xy 434.280696 -351.919104) (xy 434.25999 -351.93732) (xy 434.251865 -351.944917) (xy 434.242515 -351.965073)
			(xy 434.241956 -351.976182) (xy 434.241956 -352.053398) (xy 434.242491 -352.064512) (xy 434.251851 -352.084672)
			(xy 434.25999 -352.09226) (xy 434.280683 -352.110491) (xy 434.317155 -352.151855) (xy 434.34729 -352.198041)
			(xy 434.370459 -352.248085) (xy 434.386179 -352.300944) (xy 434.394123 -352.355516) (xy 434.39461 -352.38309)
			(xy 434.394033 -352.412282) (xy 434.385126 -352.469981) (xy 434.367534 -352.525651) (xy 434.341667 -352.577991)
			(xy 434.308129 -352.625781) (xy 434.267703 -352.667904) (xy 434.221332 -352.703377) (xy 434.195982 -352.717862)
			(xy 434.185568 -352.723704) (xy 434.172106 -352.7425) (xy 434.155342 -352.844862) (xy 434.161946 -352.867214)
			(xy 434.16982 -352.87585) (xy 434.18828 -352.896625) (xy 434.219491 -352.942607) (xy 434.243527 -352.992715)
			(xy 434.259854 -353.045836) (xy 434.268111 -353.100793) (xy 434.268626 -353.12858) (xy 434.268147 -353.155197)
			(xy 434.260574 -353.207889) (xy 434.245579 -353.258968) (xy 434.223467 -353.307392) (xy 434.194688 -353.352176)
			(xy 434.159829 -353.392409) (xy 434.119599 -353.427271) (xy 434.074817 -353.456053) (xy 434.026394 -353.478169)
			(xy 433.975317 -353.493168) (xy 433.922625 -353.500745) (xy 433.896008 -353.501198) (xy 433.869586 -353.500736)
			(xy 433.817271 -353.493287) (xy 433.766532 -353.478523) (xy 433.718388 -353.45674) (xy 433.673803 -353.428375)
			(xy 433.653438 -353.411536) (xy 433.64658 -353.40544) (xy 433.629562 -353.399344) (xy 433.545234 -353.399344)
			(xy 433.528216 -353.40544) (xy 433.521358 -353.411536) (xy 433.500992 -353.428375) (xy 433.456406 -353.45674)
			(xy 433.408262 -353.478527) (xy 433.357525 -353.493298) (xy 433.30521 -353.500758) (xy 433.252366 -353.500758)
			(xy 433.200051 -353.493298) (xy 433.149314 -353.478527) (xy 433.10117 -353.45674) (xy 433.056584 -353.428375)
			(xy 433.036218 -353.411536) (xy 433.02936 -353.40544) (xy 433.012342 -353.399344) (xy 432.928014 -353.399344)
			(xy 432.910996 -353.40544) (xy 432.904138 -353.411536) (xy 432.883751 -353.428346) (xy 432.839168 -353.456708)
			(xy 432.791029 -353.478494) (xy 432.740297 -353.493268) (xy 432.687988 -353.500734) (xy 432.661568 -353.501198)
			(xy 432.633683 -353.500715) (xy 432.578537 -353.492398) (xy 432.525246 -353.475956) (xy 432.475001 -353.451756)
			(xy 432.428924 -353.420337) (xy 432.388044 -353.382402) (xy 432.353273 -353.338799) (xy 432.32539 -353.2905)
			(xy 432.305016 -353.238585) (xy 432.292607 -353.184214) (xy 432.288439 -353.1286) (xy 429.429144 -353.1286)
			(xy 428.786798 -353.770946) (xy 428.780082 -353.778356) (xy 428.772357 -353.796776) (xy 428.771812 -353.80676)
			(xy 428.771812 -353.93884) (xy 428.772256 -353.948852) (xy 428.779931 -353.967347) (xy 428.794097 -353.981499)
			(xy 428.8126 -353.989155) (xy 428.822612 -353.98964) (xy 428.8409 -353.98964) (xy 428.86884 -353.967034)
			(xy 428.872396 -353.949254) (xy 428.878819 -353.920994) (xy 428.899049 -353.86669) (xy 428.927256 -353.816068)
			(xy 428.962791 -353.770292) (xy 429.004838 -353.730413) (xy 429.05243 -353.697349) (xy 429.104474 -353.67186)
			(xy 429.159772 -353.65453) (xy 429.217055 -353.64576) (xy 429.24603 -353.645216) (xy 429.273282 -353.645656)
			(xy 429.327229 -353.653416) (xy 429.379524 -353.668775) (xy 429.4291 -353.691419) (xy 429.47495 -353.720888)
			(xy 429.516139 -353.756582) (xy 429.55183 -353.797774) (xy 429.581295 -353.843626) (xy 429.603935 -353.893204)
			(xy 429.61929 -353.9455) (xy 429.627046 -353.999448) (xy 429.627046 -354.053952) (xy 429.61929 -354.1079)
			(xy 429.603935 -354.160196) (xy 429.581295 -354.209774) (xy 429.55183 -354.255626) (xy 429.516139 -354.296818)
			(xy 429.47495 -354.332512) (xy 429.4291 -354.361981) (xy 429.379524 -354.384625) (xy 429.327229 -354.399984)
			(xy 429.273282 -354.407744) (xy 429.24603 -354.408232) (xy 429.21802 -354.407724) (xy 429.162604 -354.39953)
			(xy 429.108983 -354.383314) (xy 429.058313 -354.359426) (xy 429.011684 -354.328379) (xy 428.970101 -354.290842)
			(xy 428.951898 -354.269548) (xy 428.941484 -354.257102) (xy 428.91075 -354.24872) (xy 428.805594 -354.286566)
			(xy 428.795958 -354.290564) (xy 428.780742 -354.304809) (xy 428.772378 -354.3239) (xy 428.771812 -354.334318)
			(xy 428.771812 -354.534724) (xy 428.789592 -354.560632) (xy 428.804324 -354.56622) (xy 428.830918 -354.57698)
			(xy 428.88074 -354.60542) (xy 428.925742 -354.641) (xy 428.964907 -354.68292) (xy 428.997352 -354.730231)
			(xy 429.022347 -354.781869) (xy 429.039325 -354.836667) (xy 429.047906 -354.89339) (xy 429.048418 -354.922074)
			(xy 429.047921 -354.949326) (xy 429.040167 -355.003275) (xy 429.024815 -355.055572) (xy 429.002176 -355.105151)
			(xy 428.972712 -355.151004) (xy 428.937022 -355.192196) (xy 428.895833 -355.22789) (xy 428.849983 -355.257359)
			(xy 428.800405 -355.280003) (xy 428.74811 -355.29536) (xy 428.694162 -355.303118) (xy 428.66691 -355.303582)
			(xy 428.638602 -355.303101) (xy 428.582605 -355.294757) (xy 428.528458 -355.278219) (xy 428.477354 -355.253853)
			(xy 428.430417 -355.222195) (xy 428.38868 -355.183941) (xy 428.353061 -355.139934) (xy 428.324345 -355.091142)
			(xy 428.303163 -355.038638) (xy 428.29607 -355.011228) (xy 428.294292 -355.00437) (xy 428.287688 -354.992432)
			(xy 428.229268 -354.934012) (xy 428.211955 -354.916002) (xy 428.182601 -354.875581) (xy 428.159939 -354.831063)
			(xy 428.144528 -354.783545) (xy 428.136748 -354.7342) (xy 428.136304 -354.709222) (xy 428.136304 -353.654106)
			(xy 428.136755 -353.62913) (xy 428.14455 -353.57979) (xy 428.159966 -353.532277) (xy 428.182623 -353.487759)
			(xy 428.211963 -353.447332) (xy 428.229268 -353.429316) (xy 428.311056 -353.347528) (xy 428.31755 -353.340497)
			(xy 428.325176 -353.322956) (xy 428.325823 -353.30384) (xy 428.322994 -353.294696) (xy 428.28718 -353.194112)
			(xy 428.264066 -353.176078) (xy 428.249334 -353.174554) (xy 428.221462 -353.171301) (xy 428.167056 -353.157562)
			(xy 428.115251 -353.135998) (xy 428.067165 -353.107074) (xy 428.023837 -353.071415) (xy 427.986204 -353.029792)
			(xy 427.955076 -352.983103) (xy 427.931128 -352.932355) (xy 427.914875 -352.878646) (xy 427.906669 -352.823135)
			(xy 427.90618 -352.795078) (xy 425.832707 -352.795078) (xy 425.828714 -352.819462) (xy 425.835318 -352.841814)
			(xy 425.843192 -352.85045) (xy 425.861647 -352.871229) (xy 425.89286 -352.91721) (xy 425.916897 -352.967316)
			(xy 425.933226 -353.020437) (xy 425.941483 -353.075393) (xy 425.941998 -353.10318) (xy 425.941547 -353.129798)
			(xy 425.933973 -353.182493) (xy 425.918976 -353.233574) (xy 425.896862 -353.282) (xy 425.868081 -353.326785)
			(xy 425.833219 -353.367019) (xy 425.792985 -353.401881) (xy 425.7482 -353.430662) (xy 425.699774 -353.452776)
			(xy 425.648693 -353.467773) (xy 425.595998 -353.475347) (xy 425.56938 -353.475798) (xy 425.542958 -353.475352)
			(xy 425.490642 -353.4679) (xy 425.439903 -353.453132) (xy 425.391759 -353.431345) (xy 425.347175 -353.402977)
			(xy 425.32681 -353.386136) (xy 425.319952 -353.38004) (xy 425.302934 -353.373944) (xy 425.218606 -353.373944)
			(xy 425.201588 -353.38004) (xy 425.19473 -353.386136) (xy 425.174364 -353.402975) (xy 425.129778 -353.43134)
			(xy 425.081634 -353.453127) (xy 425.030897 -353.467898) (xy 424.978582 -353.475358) (xy 424.925738 -353.475358)
			(xy 424.873423 -353.467898) (xy 424.822686 -353.453127) (xy 424.774542 -353.43134) (xy 424.729956 -353.402975)
			(xy 424.70959 -353.386136) (xy 424.702732 -353.38004) (xy 424.685714 -353.373944) (xy 424.601386 -353.373944)
			(xy 424.584368 -353.38004) (xy 424.57751 -353.386136) (xy 424.557133 -353.40296) (xy 424.512547 -353.431319)
			(xy 424.464405 -353.453102) (xy 424.413671 -353.467873) (xy 424.36136 -353.475336) (xy 424.33494 -353.475798)
			(xy 424.30705 -353.475346) (xy 424.251892 -353.467038) (xy 424.198588 -353.450601) (xy 424.14833 -353.426402)
			(xy 424.10224 -353.394983) (xy 424.061348 -353.357045) (xy 424.026567 -353.313436) (xy 423.998676 -353.26513)
			(xy 423.978295 -353.213206) (xy 423.965882 -353.158824) (xy 423.961713 -353.1032) (xy 421.066201 -353.1032)
			(xy 421.060762 -353.137618) (xy 421.045346 -353.185131) (xy 421.022689 -353.229649) (xy 420.993348 -353.270076)
			(xy 420.976044 -353.288092) (xy 420.816786 -353.44735) (xy 420.809872 -353.454987) (xy 420.802201 -353.474085)
			(xy 420.802597 -353.494662) (xy 420.806372 -353.504246) (xy 420.852092 -353.605592) (xy 420.879016 -353.621594)
			(xy 420.895018 -353.620578) (xy 420.919402 -353.619816) (xy 420.946653 -353.62028) (xy 421.000599 -353.628036)
			(xy 421.052893 -353.643391) (xy 421.102469 -353.666032) (xy 421.148319 -353.695498) (xy 421.189509 -353.731188)
			(xy 421.2252 -353.772377) (xy 421.254666 -353.818227) (xy 421.277307 -353.867803) (xy 421.292663 -353.920096)
			(xy 421.30042 -353.974043) (xy 421.300421 -354.028544) (xy 421.292665 -354.082491) (xy 421.277312 -354.134785)
			(xy 421.254672 -354.184362) (xy 421.225208 -354.230212) (xy 421.189518 -354.271402) (xy 421.14833 -354.307094)
			(xy 421.102481 -354.336562) (xy 421.052906 -354.359204) (xy 421.000612 -354.374561) (xy 420.946666 -354.382319)
			(xy 420.892165 -354.382321) (xy 420.838218 -354.374567) (xy 420.785923 -354.359215) (xy 420.736346 -354.336576)
			(xy 420.690495 -354.307113) (xy 420.649304 -354.271424) (xy 420.613611 -354.230237) (xy 420.584143 -354.184389)
			(xy 420.561499 -354.134814) (xy 420.546141 -354.082521) (xy 420.538381 -354.028575) (xy 420.537894 -354.001324)
			(xy 420.538656 -353.97694) (xy 420.539672 -353.960938) (xy 420.52367 -353.934014) (xy 420.422324 -353.888294)
			(xy 420.412739 -353.884473) (xy 420.392133 -353.884004) (xy 420.373023 -353.891725) (xy 420.365428 -353.898708)
			(xy 420.275258 -353.988878) (xy 420.268522 -353.996272) (xy 420.26081 -354.014705) (xy 420.260272 -354.024692)
			(xy 420.260272 -354.346256) (xy 420.260715 -354.356263) (xy 420.268446 -354.374726) (xy 420.275258 -354.38207)
			(xy 420.41064 -354.517452) (xy 420.422578 -354.524056) (xy 420.429436 -354.525834) (xy 420.456851 -354.532888)
			(xy 420.509333 -354.554106) (xy 420.558104 -354.582846) (xy 420.602093 -354.618477) (xy 420.640332 -354.660218)
			(xy 420.671984 -354.707152) (xy 420.696353 -354.758247) (xy 420.712904 -354.812383) (xy 420.721273 -354.86837)
			(xy 420.72179 -354.896674) (xy 420.72132 -354.923927) (xy 420.713567 -354.977879) (xy 420.698213 -355.030178)
			(xy 420.675572 -355.079759) (xy 420.646105 -355.125613) (xy 420.610412 -355.166806) (xy 420.569219 -355.2025)
			(xy 420.523366 -355.231968) (xy 420.473785 -355.25461) (xy 420.421486 -355.269965) (xy 420.367535 -355.27772)
			(xy 420.340282 -355.278182) (xy 420.311973 -355.277727) (xy 420.255975 -355.269378) (xy 420.201828 -355.252837)
			(xy 420.150723 -355.228467) (xy 420.103786 -355.196806) (xy 420.06205 -355.158549) (xy 420.026432 -355.114539)
			(xy 419.997716 -355.065745) (xy 419.976535 -355.013239) (xy 419.969442 -354.985828) (xy 419.967664 -354.97897)
			(xy 419.96106 -354.967032) (xy 419.717728 -354.7237) (xy 419.700402 -354.705702) (xy 419.671051 -354.665277)
			(xy 419.648392 -354.620756) (xy 419.632984 -354.573235) (xy 419.625207 -354.523888) (xy 419.624764 -354.49891)
			(xy 419.624764 -353.872038) (xy 419.625246 -353.847063) (xy 419.633036 -353.797726) (xy 419.648445 -353.750213)
			(xy 419.671095 -353.705695) (xy 419.700427 -353.665266) (xy 419.717728 -353.647248) (xy 420.040562 -353.324668)
			(xy 420.047354 -353.317169) (xy 420.054993 -353.298457) (xy 420.054813 -353.278247) (xy 420.05123 -353.268788)
			(xy 420.008558 -353.167696) (xy 419.98265 -353.150932) (xy 419.966902 -353.151186) (xy 419.96106 -353.151186)
			(xy 419.933807 -353.150759) (xy 419.879856 -353.142997) (xy 419.827559 -353.127635) (xy 419.77798 -353.104988)
			(xy 419.732128 -353.075516) (xy 419.690938 -353.039818) (xy 419.655247 -352.998622) (xy 419.625782 -352.952766)
			(xy 419.603143 -352.903183) (xy 419.58779 -352.850884) (xy 419.580036 -352.796931) (xy 419.579552 -352.769678)
			(xy 407.60015 -352.769678) (xy 407.60015 -363.390688) (xy 407.600621 -363.400561) (xy 407.608077 -363.418846)
			(xy 407.614628 -363.426248) (xy 407.614882 -363.426502) (xy 410.100272 -365.911892) (xy 410.10765 -365.918705)
			(xy 410.12618 -365.926407) (xy 410.146246 -365.926407) (xy 410.164776 -365.918705) (xy 410.172154 -365.911892)
			(xy 411.180788 -364.903258) (xy 411.187576 -364.895837) (xy 411.195193 -364.87724) (xy 411.19552 -364.86719)
			(xy 411.19552 -359.188004) (xy 411.196055 -359.154716) (xy 411.204774 -359.088713) (xy 411.222037 -359.024413)
			(xy 411.247549 -358.962919) (xy 411.280873 -358.905282) (xy 411.321438 -358.852491) (xy 411.344618 -358.828594)
			(xy 415.116518 -355.056694) (xy 415.140433 -355.033535) (xy 415.193232 -354.992991) (xy 415.250869 -354.959678)
			(xy 415.312358 -354.934166) (xy 415.376648 -354.916891) (xy 415.442643 -354.908148) (xy 415.475928 -354.907596)
			(xy 415.510866 -354.908216) (xy 415.580074 -354.917858) (xy 415.647313 -354.936875) (xy 415.71132 -354.964909)
			(xy 415.770891 -355.001434) (xy 415.798254 -355.023166) (xy 415.805274 -355.028394) (xy 415.821766 -355.034227)
			(xy 415.830512 -355.034596) (xy 416.473386 -355.034596) (xy 416.4831 -355.034168) (xy 416.501136 -355.026948)
			(xy 416.515193 -355.013538) (xy 416.519614 -355.004878) (xy 416.557714 -354.92055) (xy 416.560513 -354.91374)
			(xy 416.562567 -354.899169) (xy 416.561778 -354.891848) (xy 416.560397 -354.884859) (xy 416.554342 -354.87197)
			(xy 416.54984 -354.866448) (xy 416.549586 -354.86594) (xy 416.531777 -354.844938) (xy 416.501755 -354.798778)
			(xy 416.478673 -354.748785) (xy 416.46301 -354.695996) (xy 416.455092 -354.641504) (xy 416.45459 -354.613972)
			(xy 416.455076 -354.586721) (xy 416.462832 -354.532773) (xy 416.478187 -354.480478) (xy 416.500829 -354.430901)
			(xy 416.530295 -354.385051) (xy 416.565986 -354.34386) (xy 416.607177 -354.308169) (xy 416.653027 -354.278703)
			(xy 416.702604 -354.256061) (xy 416.754899 -354.240706) (xy 416.808847 -354.23295) (xy 416.863349 -354.23295)
			(xy 416.917297 -354.240706) (xy 416.969592 -354.256061) (xy 417.019169 -354.278703) (xy 417.065019 -354.308169)
			(xy 417.10621 -354.34386) (xy 417.141901 -354.385051) (xy 417.171367 -354.430901) (xy 417.194009 -354.480478)
			(xy 417.209364 -354.532773) (xy 417.21712 -354.586721) (xy 417.217606 -354.613972) (xy 417.21786 -354.613972)
			(xy 417.217379 -354.641505) (xy 417.209467 -354.696001) (xy 417.193803 -354.748793) (xy 417.170713 -354.798785)
			(xy 417.140677 -354.844939) (xy 417.122864 -354.86594) (xy 417.12261 -354.866194) (xy 417.116499 -354.873817)
			(xy 417.110015 -354.892229) (xy 417.110858 -354.911731) (xy 417.114482 -354.920804) (xy 417.152582 -355.004878)
			(xy 417.157004 -355.013537) (xy 417.171061 -355.026948) (xy 417.189096 -355.034169) (xy 417.19881 -355.034596)
			(xy 417.535106 -355.034596) (xy 417.545093 -355.034057) (xy 417.563523 -355.026342) (xy 417.57092 -355.01961)
			(xy 418.087556 -354.502974) (xy 418.109152 -354.482183) (xy 418.157664 -354.446972) (xy 418.211092 -354.419791)
			(xy 418.268117 -354.401312) (xy 418.327331 -354.391988) (xy 418.357304 -354.391468) (xy 418.896038 -354.391468)
			(xy 418.923268 -354.391956) (xy 418.977172 -354.399711) (xy 419.029425 -354.415059) (xy 419.078961 -354.437686)
			(xy 419.124774 -354.467132) (xy 419.16593 -354.502797) (xy 419.201591 -354.543957) (xy 419.231033 -354.589772)
			(xy 419.253655 -354.639311) (xy 419.268997 -354.691565) (xy 419.276747 -354.74547) (xy 419.276747 -354.79993)
			(xy 419.268997 -354.853835) (xy 419.253655 -354.906089) (xy 419.231033 -354.955628) (xy 419.201591 -355.001443)
			(xy 419.16593 -355.042603) (xy 419.124774 -355.078268) (xy 419.078961 -355.107714) (xy 419.029425 -355.130341)
			(xy 418.977172 -355.145689) (xy 418.923268 -355.153444) (xy 418.896038 -355.153976) (xy 418.532818 -355.153976)
			(xy 418.524397 -355.154869) (xy 418.508817 -355.161478) (xy 418.502338 -355.16693) (xy 418.144198 -355.52507)
			(xy 418.097029 -355.572314) (xy 421.2971 -355.572314) (xy 421.297595 -355.54484) (xy 421.305484 -355.49046)
			(xy 421.321103 -355.437778) (xy 421.344125 -355.387885) (xy 421.374075 -355.341816) (xy 421.391842 -355.320854)
			(xy 421.397938 -355.313742) (xy 421.404288 -355.296724) (xy 421.404288 -355.210872) (xy 421.397938 -355.193854)
			(xy 421.391842 -355.186742) (xy 421.374108 -355.165756) (xy 421.34418 -355.11968) (xy 421.321163 -355.069792)
			(xy 421.30553 -355.01712) (xy 421.297604 -354.962753) (xy 421.2971 -354.935282) (xy 421.297586 -354.908031)
			(xy 421.305342 -354.854083) (xy 421.320697 -354.801788) (xy 421.343339 -354.752211) (xy 421.372805 -354.706361)
			(xy 421.408496 -354.66517) (xy 421.449687 -354.629479) (xy 421.495537 -354.600013) (xy 421.545114 -354.577371)
			(xy 421.597409 -354.562016) (xy 421.651357 -354.55426) (xy 421.705859 -354.55426) (xy 421.759807 -354.562016)
			(xy 421.812102 -354.577371) (xy 421.861679 -354.600013) (xy 421.907529 -354.629479) (xy 421.94872 -354.66517)
			(xy 421.984411 -354.706361) (xy 422.013877 -354.752211) (xy 422.036519 -354.801788) (xy 422.051874 -354.854083)
			(xy 422.05963 -354.908031) (xy 422.060116 -354.935282) (xy 422.059615 -354.962756) (xy 422.051726 -355.017135)
			(xy 422.036109 -355.069817) (xy 422.013088 -355.11971) (xy 421.98314 -355.165779) (xy 421.965374 -355.186742)
			(xy 421.959278 -355.193854) (xy 421.952928 -355.210872) (xy 421.952928 -355.296724) (xy 421.959278 -355.313742)
			(xy 421.965374 -355.320854) (xy 421.983109 -355.341839) (xy 422.013036 -355.387916) (xy 422.036053 -355.437804)
			(xy 422.051686 -355.490476) (xy 422.059612 -355.544843) (xy 422.060116 -355.572314) (xy 422.05963 -355.599565)
			(xy 422.051874 -355.653513) (xy 422.036519 -355.705808) (xy 422.013877 -355.755385) (xy 421.984411 -355.801235)
			(xy 421.94872 -355.842426) (xy 421.907529 -355.878117) (xy 421.861679 -355.907583) (xy 421.812102 -355.930225)
			(xy 421.759807 -355.94558) (xy 421.705859 -355.953336) (xy 421.651357 -355.953336) (xy 421.597409 -355.94558)
			(xy 421.545114 -355.930225) (xy 421.495537 -355.907583) (xy 421.449687 -355.878117) (xy 421.408496 -355.842426)
			(xy 421.372805 -355.801235) (xy 421.343339 -355.755385) (xy 421.320697 -355.705808) (xy 421.305342 -355.653513)
			(xy 421.297586 -355.599565) (xy 421.2971 -355.572314) (xy 418.097029 -355.572314) (xy 417.98367 -355.685852)
			(xy 417.962057 -355.706635) (xy 417.913554 -355.741882) (xy 417.860136 -355.76911) (xy 417.803117 -355.787649)
			(xy 417.7439 -355.797044) (xy 417.713922 -355.797612) (xy 415.834322 -355.797612) (xy 415.824333 -355.798146)
			(xy 415.805896 -355.805855) (xy 415.798508 -355.812598) (xy 414.387184 -357.223822) (xy 416.449002 -357.223822)
			(xy 416.449535 -357.194906) (xy 416.458261 -357.137735) (xy 416.475516 -357.082537) (xy 416.500905 -357.030575)
			(xy 416.533846 -356.983041) (xy 416.573584 -356.941023) (xy 416.596068 -356.922832) (xy 416.604822 -356.915264)
			(xy 416.615007 -356.894509) (xy 416.615626 -356.882954) (xy 416.615626 -356.80269) (xy 416.615087 -356.791117)
			(xy 416.604873 -356.770345) (xy 416.596068 -356.762812) (xy 416.573584 -356.744622) (xy 416.53385 -356.702601)
			(xy 416.500912 -356.655066) (xy 416.475524 -356.603104) (xy 416.458268 -356.547907) (xy 416.449538 -356.490738)
			(xy 416.449002 -356.461822) (xy 416.449488 -356.434571) (xy 416.457244 -356.380623) (xy 416.472599 -356.328328)
			(xy 416.495241 -356.278751) (xy 416.524707 -356.232901) (xy 416.560398 -356.19171) (xy 416.601589 -356.156019)
			(xy 416.647439 -356.126553) (xy 416.697016 -356.103911) (xy 416.749311 -356.088556) (xy 416.803259 -356.0808)
			(xy 416.857761 -356.0808) (xy 416.911709 -356.088556) (xy 416.964004 -356.103911) (xy 417.013581 -356.126553)
			(xy 417.059431 -356.156019) (xy 417.100622 -356.19171) (xy 417.136313 -356.232901) (xy 417.165779 -356.278751)
			(xy 417.188421 -356.328328) (xy 417.203776 -356.380623) (xy 417.211532 -356.434571) (xy 417.212018 -356.461822)
			(xy 417.211475 -356.490738) (xy 417.202755 -356.54791) (xy 417.185504 -356.603109) (xy 417.160117 -356.655072)
			(xy 417.127177 -356.702606) (xy 417.087437 -356.744622) (xy 417.064952 -356.762812) (xy 417.056181 -356.770365)
			(xy 417.046005 -356.791131) (xy 417.045394 -356.80269) (xy 417.045394 -356.882954) (xy 417.045993 -356.894518)
			(xy 417.056168 -356.915289) (xy 417.064952 -356.922832) (xy 417.087462 -356.940992) (xy 417.127193 -356.98302)
			(xy 417.160127 -357.030561) (xy 417.185511 -357.082529) (xy 417.202762 -357.137731) (xy 417.211486 -357.194904)
			(xy 417.212018 -357.223822) (xy 417.211764 -357.240078) (xy 417.211002 -357.254556) (xy 417.224718 -357.279194)
			(xy 417.328096 -357.338122) (xy 417.35629 -357.33736) (xy 417.368482 -357.329486) (xy 417.391804 -357.314957)
			(xy 417.441716 -357.291983) (xy 417.494404 -357.276392) (xy 417.548781 -357.268504) (xy 417.576254 -357.268018)
			(xy 417.603511 -357.268406) (xy 417.65747 -357.276157) (xy 417.709776 -357.291509) (xy 417.759365 -357.314149)
			(xy 417.805228 -357.343616) (xy 417.84643 -357.379309) (xy 417.882133 -357.420504) (xy 417.91161 -357.46636)
			(xy 417.934261 -357.515944) (xy 417.949625 -357.568247) (xy 417.957388 -357.622204) (xy 417.957394 -357.676717)
			(xy 417.949641 -357.730676) (xy 417.934288 -357.782982) (xy 417.911648 -357.832571) (xy 417.88218 -357.878433)
			(xy 417.846486 -357.919635) (xy 417.805291 -357.955337) (xy 417.759435 -357.984813) (xy 417.70985 -358.007463)
			(xy 417.657547 -358.022826) (xy 417.603589 -358.030589) (xy 417.549076 -358.030593) (xy 417.495117 -358.02284)
			(xy 417.442811 -358.007486) (xy 417.393223 -357.984845) (xy 417.347361 -357.955376) (xy 417.30616 -357.919681)
			(xy 417.270459 -357.878486) (xy 417.240984 -357.832629) (xy 417.218334 -357.783044) (xy 417.202973 -357.73074)
			(xy 417.195211 -357.676782) (xy 417.194746 -357.649526) (xy 417.195 -357.63327) (xy 417.195762 -357.618792)
			(xy 417.182046 -357.594154) (xy 417.078668 -357.535226) (xy 417.050474 -357.535988) (xy 417.038282 -357.543862)
			(xy 417.014965 -357.5584) (xy 416.965051 -357.581373) (xy 416.912362 -357.596962) (xy 416.857983 -357.604846)
			(xy 416.83051 -357.60533) (xy 416.80326 -357.604812) (xy 416.749315 -357.597058) (xy 416.697022 -357.581705)
			(xy 416.647446 -357.559067) (xy 416.601597 -357.529604) (xy 416.560407 -357.493916) (xy 416.524716 -357.452729)
			(xy 416.495249 -357.406882) (xy 416.472606 -357.357308) (xy 416.457249 -357.305017) (xy 416.44949 -357.251072)
			(xy 416.449002 -357.223822) (xy 414.387184 -357.223822) (xy 412.774677 -358.836214) (xy 417.824664 -358.836214)
			(xy 417.828735 -358.780592) (xy 417.840861 -358.726155) (xy 417.860784 -358.674064) (xy 417.88808 -358.625429)
			(xy 417.922166 -358.581286) (xy 417.962315 -358.542577) (xy 418.007673 -358.510126) (xy 418.057273 -358.484625)
			(xy 418.110057 -358.466618) (xy 418.1649 -358.456488) (xy 418.220634 -358.454451) (xy 418.276071 -358.460551)
			(xy 418.330028 -358.474657) (xy 418.381357 -358.496469) (xy 418.428963 -358.525523) (xy 418.471831 -358.561198)
			(xy 418.509048 -358.602735) (xy 418.539821 -358.649248) (xy 418.563493 -358.699745) (xy 418.579561 -358.753152)
			(xy 418.587681 -358.808328) (xy 418.58819 -358.836214) (xy 418.587681 -358.8641) (xy 418.579561 -358.919276)
			(xy 418.563493 -358.972683) (xy 418.539821 -359.02318) (xy 418.509048 -359.069693) (xy 418.471831 -359.11123)
			(xy 418.428963 -359.146905) (xy 418.381357 -359.175959) (xy 418.330028 -359.197771) (xy 418.276071 -359.211877)
			(xy 418.220634 -359.217977) (xy 418.1649 -359.21594) (xy 418.110057 -359.20581) (xy 418.057273 -359.187803)
			(xy 418.007673 -359.162302) (xy 417.962315 -359.129851) (xy 417.922166 -359.091142) (xy 417.88808 -359.046999)
			(xy 417.860784 -358.998364) (xy 417.840861 -358.946273) (xy 417.828735 -358.891836) (xy 417.824664 -358.836214)
			(xy 412.774677 -358.836214) (xy 412.227268 -359.383584) (xy 412.220491 -359.391009) (xy 412.212897 -359.409606)
			(xy 412.212536 -359.419652) (xy 412.212536 -360.7943) (xy 412.920178 -360.7943) (xy 412.924249 -360.738678)
			(xy 412.936375 -360.684241) (xy 412.956298 -360.63215) (xy 412.983594 -360.583515) (xy 413.01768 -360.539372)
			(xy 413.057829 -360.500663) (xy 413.103187 -360.468212) (xy 413.152787 -360.442711) (xy 413.205571 -360.424704)
			(xy 413.260414 -360.414574) (xy 413.316148 -360.412537) (xy 413.371585 -360.418637) (xy 413.425542 -360.432743)
			(xy 413.476871 -360.454555) (xy 413.524477 -360.483609) (xy 413.567345 -360.519284) (xy 413.604562 -360.560821)
			(xy 413.635335 -360.607334) (xy 413.659007 -360.657831) (xy 413.675075 -360.711238) (xy 413.683195 -360.766414)
			(xy 413.683704 -360.7943) (xy 413.683195 -360.822186) (xy 413.675075 -360.877362) (xy 413.659007 -360.930769)
			(xy 413.635335 -360.981266) (xy 413.604562 -361.027779) (xy 413.567345 -361.069316) (xy 413.524477 -361.104991)
			(xy 413.476871 -361.134045) (xy 413.425542 -361.155857) (xy 413.371585 -361.169963) (xy 413.316148 -361.176063)
			(xy 413.260414 -361.174026) (xy 413.205571 -361.163896) (xy 413.152787 -361.145889) (xy 413.103187 -361.120388)
			(xy 413.057829 -361.087937) (xy 413.01768 -361.049228) (xy 412.983594 -361.005085) (xy 412.956298 -360.95645)
			(xy 412.936375 -360.904359) (xy 412.924249 -360.849922) (xy 412.920178 -360.7943) (xy 412.212536 -360.7943)
			(xy 412.212536 -361.3023) (xy 414.979356 -361.3023) (xy 414.983427 -361.246678) (xy 414.995553 -361.192241)
			(xy 415.015476 -361.14015) (xy 415.042772 -361.091515) (xy 415.076858 -361.047372) (xy 415.117007 -361.008663)
			(xy 415.162365 -360.976212) (xy 415.211965 -360.950711) (xy 415.264749 -360.932704) (xy 415.319592 -360.922574)
			(xy 415.375326 -360.920537) (xy 415.430763 -360.926637) (xy 415.48472 -360.940743) (xy 415.536049 -360.962555)
			(xy 415.583655 -360.991609) (xy 415.626523 -361.027284) (xy 415.66374 -361.068821) (xy 415.694513 -361.115334)
			(xy 415.718185 -361.165831) (xy 415.734253 -361.219238) (xy 415.742373 -361.274414) (xy 415.742882 -361.3023)
			(xy 415.742373 -361.330186) (xy 415.734253 -361.385362) (xy 415.723326 -361.42168) (xy 420.925244 -361.42168)
			(xy 420.925244 -359.310432) (xy 420.925893 -359.285437) (xy 420.935693 -359.236414) (xy 420.954862 -359.190243)
			(xy 420.982666 -359.148697) (xy 420.99992 -359.1306) (xy 422.413684 -357.716836) (xy 422.420399 -357.709372)
			(xy 422.427975 -357.690799) (xy 422.428416 -357.680768) (xy 422.428416 -355.354382) (xy 422.427971 -355.344411)
			(xy 422.420375 -355.325975) (xy 422.413684 -355.318568) (xy 422.392818 -355.296934) (xy 422.3574 -355.248376)
			(xy 422.330039 -355.194863) (xy 422.311412 -355.137721) (xy 422.301981 -355.078363) (xy 422.301416 -355.048312)
			(xy 422.301867 -355.021058) (xy 422.309623 -354.967106) (xy 422.324978 -354.914806) (xy 422.347621 -354.865224)
			(xy 422.37709 -354.81937) (xy 422.412785 -354.778177) (xy 422.45398 -354.742483) (xy 422.499835 -354.713015)
			(xy 422.549417 -354.690374) (xy 422.601717 -354.67502) (xy 422.65567 -354.667266) (xy 422.682924 -354.666804)
			(xy 422.70816 -354.66719) (xy 422.758194 -354.673811) (xy 422.806914 -354.686987) (xy 422.853466 -354.706488)
			(xy 422.875456 -354.718874) (xy 422.885108 -354.724716) (xy 422.907206 -354.726748) (xy 423.001694 -354.69322)
			(xy 423.017696 -354.677726) (xy 423.02176 -354.667312) (xy 423.032479 -354.640545) (xy 423.060763 -354.590304)
			(xy 423.096289 -354.544893) (xy 423.138247 -354.50535) (xy 423.185681 -354.472575) (xy 423.23751 -354.447315)
			(xy 423.29255 -354.430147) (xy 423.349548 -354.421463) (xy 423.378376 -354.420932) (xy 423.40563 -354.421378)
			(xy 423.459584 -354.429133) (xy 423.511884 -354.444488) (xy 423.561467 -354.46713) (xy 423.607322 -354.496599)
			(xy 423.648516 -354.532295) (xy 423.68421 -354.573491) (xy 423.713678 -354.619347) (xy 423.736318 -354.668931)
			(xy 423.74904 -354.71227) (xy 425.889928 -354.71227) (xy 425.890432 -354.684697) (xy 425.898375 -354.630125)
			(xy 425.914092 -354.577266) (xy 425.937255 -354.527219) (xy 425.967381 -354.481029) (xy 426.003843 -354.439656)
			(xy 426.024548 -354.42144) (xy 426.032651 -354.413824) (xy 426.042012 -354.393683) (xy 426.042582 -354.382578)
			(xy 426.042582 -354.305362) (xy 426.042057 -354.294247) (xy 426.032689 -354.274088) (xy 426.024548 -354.2665)
			(xy 426.003843 -354.248282) (xy 425.96737 -354.206916) (xy 425.937236 -354.160728) (xy 425.914069 -354.110681)
			(xy 425.898352 -354.057819) (xy 425.890413 -354.003245) (xy 425.889928 -353.97567) (xy 425.890327 -353.948415)
			(xy 425.898089 -353.89446) (xy 425.913451 -353.842158) (xy 425.936099 -353.792576) (xy 425.965574 -353.746721)
			(xy 426.001274 -353.705528) (xy 426.042474 -353.669834) (xy 426.088334 -353.640368) (xy 426.13792 -353.617728)
			(xy 426.190224 -353.602375) (xy 426.244181 -353.594622) (xy 426.271436 -353.594162) (xy 426.305726 -353.595686)
			(xy 426.315886 -353.596702) (xy 426.33519 -353.590606) (xy 426.405802 -353.531424) (xy 426.4152 -353.51339)
			(xy 426.416216 -353.50323) (xy 426.419119 -353.475051) (xy 426.432297 -353.419956) (xy 426.453481 -353.367416)
			(xy 426.482204 -353.318589) (xy 426.517834 -353.274547) (xy 426.559587 -353.236261) (xy 426.606544 -353.204572)
			(xy 426.657673 -353.180179) (xy 426.711847 -353.163617) (xy 426.767875 -353.155252) (xy 426.7962 -353.154742)
			(xy 426.814219 -353.154968) (xy 426.850094 -353.158399) (xy 426.867828 -353.1616) (xy 426.877226 -353.163378)
			(xy 426.896276 -353.159568) (xy 426.97146 -353.111816) (xy 426.98289 -353.096068) (xy 426.985176 -353.08667)
			(xy 426.99262 -353.05964) (xy 427.014245 -353.007915) (xy 427.043203 -352.959911) (xy 427.078873 -352.91666)
			(xy 427.120486 -352.879092) (xy 427.167147 -352.848016) (xy 427.217853 -352.8241) (xy 427.271512 -352.80786)
			(xy 427.326969 -352.799644) (xy 427.355 -352.799142) (xy 427.382255 -352.799555) (xy 427.43621 -352.807314)
			(xy 427.488512 -352.822672) (xy 427.538096 -352.845318) (xy 427.583951 -352.874791) (xy 427.625145 -352.91049)
			(xy 427.660839 -352.951689) (xy 427.690306 -352.997548) (xy 427.712945 -353.047135) (xy 427.728297 -353.099438)
			(xy 427.736048 -353.153395) (xy 427.736508 -353.18065) (xy 427.736005 -353.208223) (xy 427.72806 -353.262794)
			(xy 427.712342 -353.315653) (xy 427.689179 -353.365699) (xy 427.659053 -353.41189) (xy 427.622592 -353.453263)
			(xy 427.601888 -353.47148) (xy 427.593781 -353.479093) (xy 427.584421 -353.499237) (xy 427.583854 -353.510342)
			(xy 427.583854 -353.587558) (xy 427.584412 -353.59867) (xy 427.593756 -353.618829) (xy 427.601888 -353.62642)
			(xy 427.622644 -353.644581) (xy 427.659109 -353.685959) (xy 427.689236 -353.732156) (xy 427.712397 -353.78221)
			(xy 427.728109 -353.835077) (xy 427.736046 -353.889656) (xy 427.736041 -353.944809) (xy 427.728095 -353.999386)
			(xy 427.712374 -354.052251) (xy 427.689204 -354.102301) (xy 427.65907 -354.148493) (xy 427.622598 -354.189865)
			(xy 427.601888 -354.20808) (xy 427.593781 -354.215693) (xy 427.584421 -354.235837) (xy 427.583854 -354.246942)
			(xy 427.583854 -354.324158) (xy 427.584412 -354.33527) (xy 427.593756 -354.355429) (xy 427.601888 -354.36302)
			(xy 427.62261 -354.38122) (xy 427.65908 -354.422591) (xy 427.689211 -354.468783) (xy 427.712375 -354.518833)
			(xy 427.728089 -354.571698) (xy 427.736025 -354.626275) (xy 427.736508 -354.65385) (xy 427.735998 -354.681102)
			(xy 427.728248 -354.735051) (xy 427.712898 -354.787348) (xy 427.690262 -354.836928) (xy 427.660799 -354.882781)
			(xy 427.62511 -354.923974) (xy 427.583921 -354.959669) (xy 427.538072 -354.989138) (xy 427.488495 -355.011781)
			(xy 427.4362 -355.027137) (xy 427.382252 -355.034895) (xy 427.355 -355.035358) (xy 427.327143 -355.034866)
			(xy 427.272025 -355.026741) (xy 427.218672 -355.010694) (xy 427.168218 -354.987064) (xy 427.121732 -354.956353)
			(xy 427.080203 -354.919213) (xy 427.044511 -354.876433) (xy 427.015414 -354.828921) (xy 426.99353 -354.777685)
			(xy 426.985938 -354.750878) (xy 426.983652 -354.741988) (xy 426.972984 -354.726748) (xy 426.901102 -354.678996)
			(xy 426.883068 -354.674932) (xy 426.873924 -354.676202) (xy 426.860907 -354.677867) (xy 426.834723 -354.67965)
			(xy 426.8216 -354.679758) (xy 426.807451 -354.679665) (xy 426.779228 -354.67763) (xy 426.765212 -354.675694)
			(xy 426.755052 -354.67417) (xy 426.735494 -354.678996) (xy 426.661072 -354.734876) (xy 426.650912 -354.752402)
			(xy 426.649642 -354.762562) (xy 426.645543 -354.789713) (xy 426.630569 -354.842542) (xy 426.608178 -354.892679)
			(xy 426.578831 -354.939088) (xy 426.543134 -354.980811) (xy 426.501826 -355.016988) (xy 426.455759 -355.046869)
			(xy 426.405885 -355.069839) (xy 426.353233 -355.085422) (xy 426.298891 -355.093298) (xy 426.271436 -355.093778)
			(xy 426.244183 -355.093311) (xy 426.19023 -355.085558) (xy 426.137931 -355.070205) (xy 426.088349 -355.047565)
			(xy 426.042494 -355.018098) (xy 426.0013 -354.982404) (xy 425.965606 -354.941211) (xy 425.936138 -354.895357)
			(xy 425.913497 -354.845775) (xy 425.898143 -354.793476) (xy 425.890389 -354.739523) (xy 425.889928 -354.71227)
			(xy 423.74904 -354.71227) (xy 423.751671 -354.721232) (xy 423.759423 -354.775186) (xy 423.759884 -354.80244)
			(xy 423.759227 -354.834003) (xy 423.748839 -354.896268) (xy 423.728352 -354.955977) (xy 423.71391 -354.98405)
			(xy 423.709084 -354.99294) (xy 423.707052 -355.012498) (xy 423.732706 -355.100636) (xy 423.745152 -355.11613)
			(xy 423.754042 -355.12121) (xy 423.779119 -355.135799) (xy 423.825003 -355.171294) (xy 423.864982 -355.21333)
			(xy 423.898131 -355.260936) (xy 423.923686 -355.313015) (xy 423.941057 -355.368365) (xy 423.949843 -355.425706)
			(xy 423.950384 -355.454712) (xy 423.949898 -355.481963) (xy 423.942142 -355.535911) (xy 423.926787 -355.588206)
			(xy 423.922445 -355.597714) (xy 429.623728 -355.597714) (xy 429.624216 -355.570239) (xy 429.632106 -355.51586)
			(xy 429.647726 -355.463177) (xy 429.67075 -355.413284) (xy 429.700702 -355.367216) (xy 429.71847 -355.346254)
			(xy 429.724566 -355.339142) (xy 429.730916 -355.322124) (xy 429.730916 -355.236272) (xy 429.724566 -355.219254)
			(xy 429.71847 -355.212142) (xy 429.70074 -355.191152) (xy 429.670811 -355.145078) (xy 429.647792 -355.09519)
			(xy 429.632158 -355.04252) (xy 429.624232 -354.988152) (xy 429.623728 -354.960682) (xy 429.624214 -354.933431)
			(xy 429.63197 -354.879483) (xy 429.647325 -354.827188) (xy 429.669967 -354.777611) (xy 429.699433 -354.731761)
			(xy 429.735124 -354.69057) (xy 429.776315 -354.654879) (xy 429.822165 -354.625413) (xy 429.871742 -354.602771)
			(xy 429.924037 -354.587416) (xy 429.977985 -354.57966) (xy 430.032487 -354.57966) (xy 430.086435 -354.587416)
			(xy 430.13873 -354.602771) (xy 430.188307 -354.625413) (xy 430.234157 -354.654879) (xy 430.275348 -354.69057)
			(xy 430.311039 -354.731761) (xy 430.340505 -354.777611) (xy 430.363147 -354.827188) (xy 430.378502 -354.879483)
			(xy 430.386258 -354.933431) (xy 430.386744 -354.960682) (xy 430.386261 -354.988157) (xy 430.37837 -355.042537)
			(xy 430.36275 -355.09522) (xy 430.339724 -355.145113) (xy 430.309771 -355.191181) (xy 430.292002 -355.212142)
			(xy 430.285906 -355.219254) (xy 430.279556 -355.236272) (xy 430.279556 -355.322124) (xy 430.285906 -355.339142)
			(xy 430.292002 -355.346254) (xy 430.309726 -355.367249) (xy 430.339657 -355.413322) (xy 430.362677 -355.463208)
			(xy 430.378312 -355.515877) (xy 430.386239 -355.570244) (xy 430.386744 -355.597714) (xy 430.386258 -355.624965)
			(xy 430.378502 -355.678913) (xy 430.363147 -355.731208) (xy 430.340505 -355.780785) (xy 430.311039 -355.826635)
			(xy 430.275348 -355.867826) (xy 430.234157 -355.903517) (xy 430.188307 -355.932983) (xy 430.13873 -355.955625)
			(xy 430.086435 -355.97098) (xy 430.032487 -355.978736) (xy 429.977985 -355.978736) (xy 429.924037 -355.97098)
			(xy 429.871742 -355.955625) (xy 429.822165 -355.932983) (xy 429.776315 -355.903517) (xy 429.735124 -355.867826)
			(xy 429.699433 -355.826635) (xy 429.669967 -355.780785) (xy 429.647325 -355.731208) (xy 429.63197 -355.678913)
			(xy 429.624214 -355.624965) (xy 429.623728 -355.597714) (xy 423.922445 -355.597714) (xy 423.904145 -355.637783)
			(xy 423.874679 -355.683633) (xy 423.838988 -355.724824) (xy 423.797797 -355.760515) (xy 423.751947 -355.789981)
			(xy 423.70237 -355.812623) (xy 423.650075 -355.827978) (xy 423.596127 -355.835734) (xy 423.541625 -355.835734)
			(xy 423.487677 -355.827978) (xy 423.435382 -355.812623) (xy 423.385805 -355.789981) (xy 423.339955 -355.760515)
			(xy 423.298764 -355.724824) (xy 423.263073 -355.683633) (xy 423.233607 -355.637783) (xy 423.210965 -355.588206)
			(xy 423.19561 -355.535911) (xy 423.187854 -355.481963) (xy 423.187368 -355.454712) (xy 423.188012 -355.423149)
			(xy 423.198407 -355.360883) (xy 423.218898 -355.301174) (xy 423.233342 -355.273102) (xy 423.238168 -355.264212)
			(xy 423.2402 -355.244654) (xy 423.214546 -355.156516) (xy 423.2021 -355.141022) (xy 423.19321 -355.135942)
			(xy 423.185844 -355.131878) (xy 423.176192 -355.126036) (xy 423.154094 -355.124004) (xy 423.059606 -355.157532)
			(xy 423.043604 -355.173026) (xy 423.03954 -355.18344) (xy 423.029549 -355.208564) (xy 423.003467 -355.255927)
			(xy 422.970967 -355.299138) (xy 422.952164 -355.318568) (xy 422.945489 -355.325983) (xy 422.93791 -355.344417)
			(xy 422.937432 -355.354382) (xy 422.937432 -357.680768) (xy 422.937783 -357.690815) (xy 422.945385 -357.709412)
			(xy 422.952164 -357.716836) (xy 423.18686 -357.951532) (xy 423.194331 -357.958238) (xy 423.212898 -357.965821)
			(xy 423.222928 -357.966264) (xy 429.1203 -357.966264) (xy 429.130344 -357.965878) (xy 429.14894 -357.958301)
			(xy 429.156368 -357.951532) (xy 430.667414 -356.440486) (xy 430.674254 -356.433086) (xy 430.681973 -356.414487)
			(xy 430.6824 -356.404418) (xy 430.6824 -355.283262) (xy 430.682176 -355.276805) (xy 430.678829 -355.26433)
			(xy 430.675796 -355.258624) (xy 430.660805 -355.23013) (xy 430.639522 -355.169369) (xy 430.628718 -355.105902)
			(xy 430.628044 -355.073712) (xy 430.628589 -355.046463) (xy 430.636343 -354.99252) (xy 430.651694 -354.94023)
			(xy 430.67433 -354.890656) (xy 430.703791 -354.844808) (xy 430.739476 -354.803618) (xy 430.780659 -354.767927)
			(xy 430.826503 -354.738459) (xy 430.876073 -354.715815) (xy 430.928362 -354.700456) (xy 430.982303 -354.692694)
			(xy 431.009552 -354.692204) (xy 431.034788 -354.692578) (xy 431.084823 -354.699203) (xy 431.133543 -354.712382)
			(xy 431.180094 -354.731886) (xy 431.202084 -354.744274) (xy 431.211736 -354.750116) (xy 431.233834 -354.752148)
			(xy 431.328322 -354.71862) (xy 431.344324 -354.703126) (xy 431.348388 -354.692712) (xy 431.359084 -354.665935)
			(xy 431.38737 -354.615692) (xy 431.422899 -354.570282) (xy 431.464861 -354.530738) (xy 431.512299 -354.497964)
			(xy 431.56413 -354.472707) (xy 431.619174 -354.455542) (xy 431.676175 -354.446861) (xy 431.705004 -354.446332)
			(xy 431.732259 -354.446752) (xy 431.786213 -354.45451) (xy 431.838514 -354.469869) (xy 431.888097 -354.492515)
			(xy 431.933952 -354.521987) (xy 431.975146 -354.557685) (xy 432.01084 -354.598883) (xy 432.040306 -354.644741)
			(xy 432.062947 -354.694327) (xy 432.075669 -354.73767) (xy 434.216556 -354.73767) (xy 434.21705 -354.710096)
			(xy 434.224994 -354.655524) (xy 434.240712 -354.602664) (xy 434.263877 -354.552617) (xy 434.294005 -354.506427)
			(xy 434.33047 -354.465056) (xy 434.351176 -354.44684) (xy 434.359284 -354.439229) (xy 434.368641 -354.419083)
			(xy 434.36921 -354.407978) (xy 434.36921 -354.330762) (xy 434.368708 -354.319643) (xy 434.359326 -354.299484)
			(xy 434.351176 -354.2919) (xy 434.330457 -354.273698) (xy 434.293988 -354.232326) (xy 434.263858 -354.186135)
			(xy 434.240693 -354.136085) (xy 434.224979 -354.083221) (xy 434.217041 -354.028645) (xy 434.216556 -354.00107)
			(xy 434.21705 -353.97382) (xy 434.224809 -353.919874) (xy 434.240167 -353.867582) (xy 434.262809 -353.818007)
			(xy 434.292275 -353.772158) (xy 434.327965 -353.730969) (xy 434.369153 -353.695278) (xy 434.415001 -353.665811)
			(xy 434.464576 -353.643169) (xy 434.516868 -353.627811) (xy 434.570814 -353.62005) (xy 434.598064 -353.619562)
			(xy 434.632354 -353.621086) (xy 434.642514 -353.622102) (xy 434.661818 -353.616006) (xy 434.73243 -353.556824)
			(xy 434.741828 -353.53879) (xy 434.742844 -353.52863) (xy 434.745817 -353.50046) (xy 434.758992 -353.445371)
			(xy 434.780171 -353.392837) (xy 434.808887 -353.344013) (xy 434.844509 -353.299973) (xy 434.886254 -353.261687)
			(xy 434.933202 -353.229997) (xy 434.984321 -353.205599) (xy 435.038486 -353.189031) (xy 435.094507 -353.180657)
			(xy 435.122828 -353.180142) (xy 435.140847 -353.180364) (xy 435.176722 -353.183798) (xy 435.194456 -353.187)
			(xy 435.203854 -353.188778) (xy 435.222904 -353.184968) (xy 435.298088 -353.137216) (xy 435.309518 -353.121468)
			(xy 435.311804 -353.11207) (xy 435.319223 -353.085032) (xy 435.340849 -353.033306) (xy 435.369811 -352.985301)
			(xy 435.405483 -352.942049) (xy 435.4471 -352.904481) (xy 435.493765 -352.873406) (xy 435.544474 -352.849492)
			(xy 435.598136 -352.833254) (xy 435.653596 -352.825042) (xy 435.681628 -352.824542) (xy 435.708884 -352.824929)
			(xy 435.76284 -352.832691) (xy 435.815143 -352.848053) (xy 435.864726 -352.870703) (xy 435.910582 -352.900178)
			(xy 435.951775 -352.93588) (xy 435.987469 -352.977081) (xy 436.016935 -353.022942) (xy 436.039574 -353.072531)
			(xy 436.054926 -353.124836) (xy 436.062677 -353.178794) (xy 436.063136 -353.20605) (xy 436.062658 -353.233624)
			(xy 436.054711 -353.288198) (xy 436.03899 -353.341058) (xy 436.015823 -353.391105) (xy 435.985691 -353.437295)
			(xy 435.949223 -353.478665) (xy 435.928516 -353.49688) (xy 435.920414 -353.504497) (xy 435.91105 -353.524637)
			(xy 435.910482 -353.535742) (xy 435.910482 -353.612958) (xy 435.911031 -353.624071) (xy 435.92038 -353.644231)
			(xy 435.928516 -353.65182) (xy 435.949271 -353.669981) (xy 435.985733 -353.711361) (xy 436.015858 -353.757558)
			(xy 436.039017 -353.807612) (xy 436.054728 -353.860479) (xy 436.062664 -353.915056) (xy 436.062659 -353.970208)
			(xy 436.054714 -354.024785) (xy 436.038994 -354.077649) (xy 436.015826 -354.127698) (xy 435.985694 -354.173891)
			(xy 435.949225 -354.215264) (xy 435.928516 -354.23348) (xy 435.920414 -354.241097) (xy 435.91105 -354.261237)
			(xy 435.910482 -354.272342) (xy 435.910482 -354.349558) (xy 435.911031 -354.360671) (xy 435.92038 -354.380831)
			(xy 435.928516 -354.38842) (xy 435.949243 -354.406614) (xy 435.985712 -354.447986) (xy 436.015841 -354.49418)
			(xy 436.039004 -354.544232) (xy 436.054717 -354.597097) (xy 436.062653 -354.651674) (xy 436.063136 -354.67925)
			(xy 436.062598 -354.7065) (xy 436.054849 -354.760447) (xy 436.039501 -354.812742) (xy 436.016866 -354.86232)
			(xy 435.987406 -354.908172) (xy 435.95172 -354.949365) (xy 435.910535 -354.985059) (xy 435.864689 -355.014528)
			(xy 435.815115 -355.037173) (xy 435.762823 -355.052532) (xy 435.708878 -355.060293) (xy 435.681628 -355.060758)
			(xy 435.653772 -355.060241) (xy 435.598655 -355.05212) (xy 435.545303 -355.036076) (xy 435.494848 -355.01245)
			(xy 435.448363 -354.981742) (xy 435.406833 -354.944606) (xy 435.37114 -354.901828) (xy 435.342043 -354.854318)
			(xy 435.320158 -354.803084) (xy 435.312566 -354.776278) (xy 435.31028 -354.767388) (xy 435.299612 -354.752148)
			(xy 435.22773 -354.704396) (xy 435.209696 -354.700332) (xy 435.200552 -354.701602) (xy 435.187536 -354.703274)
			(xy 435.161351 -354.705052) (xy 435.148228 -354.705158) (xy 435.134079 -354.705062) (xy 435.105856 -354.703029)
			(xy 435.09184 -354.701094) (xy 435.08168 -354.69957) (xy 435.062122 -354.704396) (xy 434.9877 -354.760276)
			(xy 434.97754 -354.777802) (xy 434.97627 -354.787962) (xy 434.972144 -354.815109) (xy 434.957172 -354.867935)
			(xy 434.934782 -354.91807) (xy 434.905438 -354.964478) (xy 434.869745 -355.006201) (xy 434.82844 -355.042377)
			(xy 434.782376 -355.07226) (xy 434.732505 -355.095231) (xy 434.679857 -355.110817) (xy 434.625518 -355.118696)
			(xy 434.598064 -355.119178) (xy 434.57081 -355.118756) (xy 434.516859 -355.110993) (xy 434.464561 -355.095632)
			(xy 434.414982 -355.072985) (xy 434.36913 -355.043512) (xy 434.32794 -355.007814) (xy 434.292249 -354.966617)
			(xy 434.262784 -354.92076) (xy 434.240145 -354.871177) (xy 434.224793 -354.818876) (xy 434.21704 -354.764924)
			(xy 434.216556 -354.73767) (xy 432.075669 -354.73767) (xy 432.078299 -354.74663) (xy 432.086051 -354.800585)
			(xy 432.086512 -354.82784) (xy 432.085851 -354.859403) (xy 432.075464 -354.921668) (xy 432.054979 -354.981377)
			(xy 432.040538 -355.00945) (xy 432.035712 -355.01834) (xy 432.03368 -355.037898) (xy 432.059334 -355.126036)
			(xy 432.07178 -355.14153) (xy 432.08067 -355.14661) (xy 432.105753 -355.161188) (xy 432.151636 -355.196686)
			(xy 432.191613 -355.238724) (xy 432.224761 -355.286333) (xy 432.250315 -355.338413) (xy 432.267685 -355.393763)
			(xy 432.276471 -355.451106) (xy 432.277012 -355.480112) (xy 432.276526 -355.507363) (xy 432.26877 -355.561311)
			(xy 432.253415 -355.613606) (xy 432.230773 -355.663183) (xy 432.201307 -355.709033) (xy 432.165616 -355.750224)
			(xy 432.124425 -355.785915) (xy 432.078575 -355.815381) (xy 432.028998 -355.838023) (xy 431.976703 -355.853378)
			(xy 431.922755 -355.861134) (xy 431.868253 -355.861134) (xy 431.814305 -355.853378) (xy 431.76201 -355.838023)
			(xy 431.712433 -355.815381) (xy 431.666583 -355.785915) (xy 431.625392 -355.750224) (xy 431.589701 -355.709033)
			(xy 431.560235 -355.663183) (xy 431.537593 -355.613606) (xy 431.522238 -355.561311) (xy 431.514482 -355.507363)
			(xy 431.513996 -355.480112) (xy 431.514637 -355.448548) (xy 431.525032 -355.386283) (xy 431.545525 -355.326574)
			(xy 431.55997 -355.298502) (xy 431.564796 -355.289612) (xy 431.566828 -355.270054) (xy 431.541174 -355.181916)
			(xy 431.528728 -355.166422) (xy 431.519838 -355.161342) (xy 431.512472 -355.157278) (xy 431.50282 -355.151436)
			(xy 431.480722 -355.149404) (xy 431.386234 -355.182932) (xy 431.370232 -355.198426) (xy 431.366168 -355.20884)
			(xy 431.354789 -355.237254) (xy 431.324269 -355.290308) (xy 431.285677 -355.337814) (xy 431.24 -355.378554)
			(xy 431.21453 -355.39553) (xy 431.20754 -355.400382) (xy 431.196939 -355.413673) (xy 431.191277 -355.429703)
			(xy 431.190908 -355.438202) (xy 431.190908 -356.53091) (xy 431.190296 -356.555894) (xy 431.180555 -356.604902)
			(xy 431.161448 -356.651072) (xy 431.133708 -356.692632) (xy 431.116486 -356.710742) (xy 429.426624 -358.400604)
			(xy 429.408513 -358.417842) (xy 429.366973 -358.445656) (xy 429.320807 -358.464833) (xy 429.271787 -358.474639)
			(xy 429.246792 -358.47528) (xy 423.096436 -358.47528) (xy 423.071441 -358.474621) (xy 423.02242 -358.464824)
			(xy 422.976249 -358.445657) (xy 422.934701 -358.417856) (xy 422.916604 -358.400604) (xy 422.718738 -358.202992)
			(xy 422.711377 -358.196223) (xy 422.692915 -358.188576) (xy 422.672933 -358.188576) (xy 422.654471 -358.196223)
			(xy 422.64711 -358.202992) (xy 421.448992 -359.400856) (xy 421.44229 -359.408331) (xy 421.434704 -359.426895)
			(xy 421.43426 -359.436924) (xy 421.43426 -359.904792) (xy 421.71696 -359.904792) (xy 421.721031 -359.84917)
			(xy 421.733157 -359.794733) (xy 421.75308 -359.742642) (xy 421.780376 -359.694007) (xy 421.814462 -359.649864)
			(xy 421.854611 -359.611155) (xy 421.899969 -359.578704) (xy 421.949569 -359.553203) (xy 422.002353 -359.535196)
			(xy 422.057196 -359.525066) (xy 422.11293 -359.523029) (xy 422.168367 -359.529129) (xy 422.222324 -359.543235)
			(xy 422.273653 -359.565047) (xy 422.321259 -359.594101) (xy 422.364127 -359.629776) (xy 422.401344 -359.671313)
			(xy 422.432117 -359.717826) (xy 422.455789 -359.768323) (xy 422.471857 -359.82173) (xy 422.473988 -359.836212)
			(xy 424.433236 -359.836212) (xy 424.437307 -359.78059) (xy 424.449433 -359.726153) (xy 424.469356 -359.674062)
			(xy 424.496652 -359.625427) (xy 424.530738 -359.581284) (xy 424.570887 -359.542575) (xy 424.616245 -359.510124)
			(xy 424.665845 -359.484623) (xy 424.718629 -359.466616) (xy 424.773472 -359.456486) (xy 424.829206 -359.454449)
			(xy 424.884643 -359.460549) (xy 424.9386 -359.474655) (xy 424.989929 -359.496467) (xy 425.037535 -359.525521)
			(xy 425.080403 -359.561196) (xy 425.11762 -359.602733) (xy 425.148393 -359.649246) (xy 425.172065 -359.699743)
			(xy 425.188133 -359.75315) (xy 425.196253 -359.808326) (xy 425.196762 -359.836212) (xy 425.196253 -359.864098)
			(xy 425.188133 -359.919274) (xy 425.172065 -359.972681) (xy 425.148393 -360.023178) (xy 425.11762 -360.069691)
			(xy 425.080403 -360.111228) (xy 425.037535 -360.146903) (xy 424.989929 -360.175957) (xy 424.9386 -360.197769)
			(xy 424.884643 -360.211875) (xy 424.829206 -360.217975) (xy 424.773472 -360.215938) (xy 424.718629 -360.205808)
			(xy 424.665845 -360.187801) (xy 424.616245 -360.1623) (xy 424.570887 -360.129849) (xy 424.530738 -360.09114)
			(xy 424.496652 -360.046997) (xy 424.469356 -359.998362) (xy 424.449433 -359.946271) (xy 424.437307 -359.891834)
			(xy 424.433236 -359.836212) (xy 422.473988 -359.836212) (xy 422.479977 -359.876906) (xy 422.480486 -359.904792)
			(xy 422.479977 -359.932678) (xy 422.471857 -359.987854) (xy 422.455789 -360.041261) (xy 422.432117 -360.091758)
			(xy 422.401344 -360.138271) (xy 422.364127 -360.179808) (xy 422.321259 -360.215483) (xy 422.273653 -360.244537)
			(xy 422.222324 -360.266349) (xy 422.168367 -360.280455) (xy 422.11293 -360.286555) (xy 422.057196 -360.284518)
			(xy 422.002353 -360.274388) (xy 421.949569 -360.256381) (xy 421.899969 -360.23088) (xy 421.854611 -360.198429)
			(xy 421.814462 -360.15972) (xy 421.780376 -360.115577) (xy 421.75308 -360.066942) (xy 421.733157 -360.014851)
			(xy 421.721031 -359.960414) (xy 421.71696 -359.904792) (xy 421.43426 -359.904792) (xy 421.43426 -361.295188)
			(xy 421.434594 -361.305237) (xy 421.442206 -361.323834) (xy 421.448992 -361.331256) (xy 421.751252 -361.633516)
			(xy 421.760657 -361.642037) (xy 421.784926 -361.649358) (xy 421.79748 -361.647486) (xy 421.893238 -361.627674)
			(xy 421.912796 -361.611418) (xy 421.917622 -361.59948) (xy 421.927603 -361.575576) (xy 421.953149 -361.530513)
			(xy 421.984566 -361.489327) (xy 422.021274 -361.452777) (xy 422.062596 -361.421539) (xy 422.10777 -361.396189)
			(xy 422.155962 -361.377194) (xy 422.18102 -361.370626) (xy 422.192196 -361.367832) (xy 422.209214 -361.354116)
			(xy 422.253918 -361.263946) (xy 422.254426 -361.241848) (xy 422.249854 -361.23118) (xy 422.239727 -361.206976)
			(xy 422.225476 -361.156479) (xy 422.218285 -361.104506) (xy 422.21785 -361.078272) (xy 422.218336 -361.051021)
			(xy 422.226092 -360.997073) (xy 422.241447 -360.944778) (xy 422.264089 -360.895201) (xy 422.293555 -360.849351)
			(xy 422.329246 -360.80816) (xy 422.370437 -360.772469) (xy 422.416287 -360.743003) (xy 422.465864 -360.720361)
			(xy 422.518159 -360.705006) (xy 422.572107 -360.69725) (xy 422.626609 -360.69725) (xy 422.680557 -360.705006)
			(xy 422.732852 -360.720361) (xy 422.762937 -360.734101) (xy 435.087517 -360.734101) (xy 435.091247 -360.680849)
			(xy 435.102365 -360.628636) (xy 435.120653 -360.578484) (xy 435.145754 -360.53137) (xy 435.177178 -360.488216)
			(xy 435.214312 -360.449865) (xy 435.235096 -360.433112) (xy 435.243847 -360.42554) (xy 435.254037 -360.404789)
			(xy 435.254654 -360.393234) (xy 435.254654 -360.31297) (xy 435.254059 -360.301405) (xy 435.243883 -360.280633)
			(xy 435.235096 -360.273092) (xy 435.212608 -360.254907) (xy 435.172873 -360.212885) (xy 435.139935 -360.165349)
			(xy 435.114547 -360.113387) (xy 435.097292 -360.058189) (xy 435.088564 -360.001018) (xy 435.08803 -359.972102)
			(xy 435.088457 -359.944847) (xy 435.096215 -359.890893) (xy 435.111573 -359.838592) (xy 435.134218 -359.78901)
			(xy 435.163689 -359.743155) (xy 435.199387 -359.701961) (xy 435.240584 -359.666267) (xy 435.286441 -359.6368)
			(xy 435.336026 -359.61416) (xy 435.388329 -359.598807) (xy 435.442283 -359.591055) (xy 435.469538 -359.590594)
			(xy 435.498455 -359.591121) (xy 435.555627 -359.599844) (xy 435.610828 -359.617097) (xy 435.66279 -359.642487)
			(xy 435.710324 -359.675431) (xy 435.752339 -359.715174) (xy 435.770528 -359.73766) (xy 435.778072 -359.74644)
			(xy 435.798845 -359.756611) (xy 435.810406 -359.757218) (xy 435.89067 -359.757218) (xy 435.902235 -359.756624)
			(xy 435.923005 -359.746445) (xy 435.930548 -359.73766) (xy 435.948758 -359.715193) (xy 435.990775 -359.675459)
			(xy 436.038307 -359.642519) (xy 436.090264 -359.617128) (xy 436.145457 -359.599868) (xy 436.202623 -359.591133)
			(xy 436.231538 -359.590594) (xy 436.25879 -359.591042) (xy 436.312739 -359.598804) (xy 436.365035 -359.614164)
			(xy 436.414612 -359.63681) (xy 436.460463 -359.66628) (xy 436.501653 -359.701976) (xy 436.537344 -359.743169)
			(xy 436.566809 -359.789023) (xy 436.58945 -359.838603) (xy 436.604804 -359.8909) (xy 436.61256 -359.94485)
			(xy 436.613046 -359.972102) (xy 436.61255 -360.00102) (xy 436.603819 -360.058193) (xy 436.586558 -360.113393)
			(xy 436.561162 -360.165355) (xy 436.528214 -360.212888) (xy 436.488468 -360.254903) (xy 436.46598 -360.273092)
			(xy 436.457223 -360.280658) (xy 436.447037 -360.301414) (xy 436.446422 -360.31297) (xy 436.446422 -360.393234)
			(xy 436.447023 -360.404798) (xy 436.457195 -360.42557) (xy 436.46598 -360.433112) (xy 436.486763 -360.449864)
			(xy 436.52389 -360.488219) (xy 436.555308 -360.531375) (xy 436.580404 -360.578488) (xy 436.598689 -360.62864)
			(xy 436.609804 -360.680851) (xy 436.613533 -360.734101) (xy 436.609804 -360.787352) (xy 436.598688 -360.839562)
			(xy 436.580403 -360.889714) (xy 436.555307 -360.936827) (xy 436.523888 -360.979983) (xy 436.486761 -361.018338)
			(xy 436.46598 -361.035092) (xy 436.457223 -361.042658) (xy 436.447037 -361.063414) (xy 436.446422 -361.07497)
			(xy 436.446422 -361.155234) (xy 436.447023 -361.166798) (xy 436.457195 -361.18757) (xy 436.46598 -361.195112)
			(xy 436.488465 -361.213301) (xy 436.528201 -361.255321) (xy 436.56114 -361.302856) (xy 436.586529 -361.354818)
			(xy 436.603784 -361.410016) (xy 436.612512 -361.467186) (xy 436.613046 -361.496102) (xy 436.612524 -361.523352)
			(xy 436.604768 -361.577296) (xy 436.589415 -361.629588) (xy 436.566776 -361.679162) (xy 436.537313 -361.725011)
			(xy 436.501626 -361.7662) (xy 436.46044 -361.801892) (xy 436.414594 -361.831359) (xy 436.365022 -361.854002)
			(xy 436.312731 -361.869361) (xy 436.258788 -361.877122) (xy 436.231538 -361.87761) (xy 436.20262 -361.877098)
			(xy 436.145447 -361.868373) (xy 436.090247 -361.851116) (xy 436.038285 -361.825723) (xy 435.990751 -361.792776)
			(xy 435.948737 -361.753031) (xy 435.930548 -361.730544) (xy 435.922971 -361.721799) (xy 435.902223 -361.711608)
			(xy 435.89067 -361.710986) (xy 435.810406 -361.710986) (xy 435.798839 -361.711565) (xy 435.778069 -361.721754)
			(xy 435.770528 -361.730544) (xy 435.752332 -361.753023) (xy 435.710312 -361.792757) (xy 435.662778 -361.825695)
			(xy 435.610818 -361.851084) (xy 435.555622 -361.868341) (xy 435.498454 -361.877073) (xy 435.469538 -361.87761)
			(xy 435.442286 -361.877109) (xy 435.388337 -361.869358) (xy 435.33604 -361.854006) (xy 435.28646 -361.831369)
			(xy 435.240607 -361.801905) (xy 435.199414 -361.766215) (xy 435.163719 -361.725025) (xy 435.134251 -361.679175)
			(xy 435.111608 -361.629598) (xy 435.096251 -361.577302) (xy 435.088494 -361.523354) (xy 435.08803 -361.496102)
			(xy 435.088539 -361.467185) (xy 435.097268 -361.410012) (xy 435.114527 -361.354813) (xy 435.139921 -361.302851)
			(xy 435.172866 -361.255317) (xy 435.212609 -361.213301) (xy 435.235096 -361.195112) (xy 435.243847 -361.18754)
			(xy 435.254037 -361.166789) (xy 435.254654 -361.155234) (xy 435.254654 -361.07497) (xy 435.254059 -361.063405)
			(xy 435.243883 -361.042633) (xy 435.235096 -361.035092) (xy 435.214314 -361.018337) (xy 435.17718 -360.979986)
			(xy 435.145755 -360.936832) (xy 435.120654 -360.889719) (xy 435.102366 -360.839566) (xy 435.091248 -360.787354)
			(xy 435.087517 -360.734101) (xy 422.762937 -360.734101) (xy 422.782429 -360.743003) (xy 422.828279 -360.772469)
			(xy 422.86947 -360.80816) (xy 422.905161 -360.849351) (xy 422.934627 -360.895201) (xy 422.957269 -360.944778)
			(xy 422.972624 -360.997073) (xy 422.98038 -361.051021) (xy 422.980866 -361.078272) (xy 422.980375 -361.106494)
			(xy 422.972062 -361.162322) (xy 422.955613 -361.216317) (xy 422.931389 -361.267298) (xy 422.899916 -361.314153)
			(xy 422.861883 -361.355859) (xy 422.81812 -361.391506) (xy 422.769582 -361.420316) (xy 422.717329 -361.441658)
			(xy 422.690036 -361.448858) (xy 422.67886 -361.451652) (xy 422.661842 -361.465368) (xy 422.627464 -361.53471)
			(xy 424.407836 -361.53471) (xy 424.411907 -361.479088) (xy 424.424033 -361.424651) (xy 424.443956 -361.37256)
			(xy 424.471252 -361.323925) (xy 424.505338 -361.279782) (xy 424.545487 -361.241073) (xy 424.590845 -361.208622)
			(xy 424.640445 -361.183121) (xy 424.693229 -361.165114) (xy 424.748072 -361.154984) (xy 424.803806 -361.152947)
			(xy 424.859243 -361.159047) (xy 424.9132 -361.173153) (xy 424.964529 -361.194965) (xy 425.012135 -361.224019)
			(xy 425.055003 -361.259694) (xy 425.09222 -361.301231) (xy 425.122993 -361.347744) (xy 425.146665 -361.398241)
			(xy 425.162733 -361.451648) (xy 425.170853 -361.506824) (xy 425.171362 -361.53471) (xy 425.170853 -361.562596)
			(xy 425.162733 -361.617772) (xy 425.146665 -361.671179) (xy 425.122993 -361.721676) (xy 425.09222 -361.768189)
			(xy 425.055003 -361.809726) (xy 425.012135 -361.845401) (xy 424.971544 -361.870174) (xy 431.124356 -361.870174)
			(xy 431.124356 -361.785478) (xy 431.132407 -361.701164) (xy 431.148436 -361.617998) (xy 431.172297 -361.536731)
			(xy 431.203776 -361.458101) (xy 431.242587 -361.38282) (xy 431.288377 -361.311568) (xy 431.340733 -361.244992)
			(xy 431.399181 -361.183694) (xy 431.463191 -361.128229) (xy 431.532183 -361.0791) (xy 431.605533 -361.036751)
			(xy 431.682576 -361.001567) (xy 431.762615 -360.973865) (xy 431.844924 -360.953897) (xy 431.928759 -360.941844)
			(xy 432.01336 -360.937814) (xy 432.097961 -360.941844) (xy 432.181796 -360.953897) (xy 432.264105 -360.973865)
			(xy 432.344144 -361.001567) (xy 432.421187 -361.036751) (xy 432.494537 -361.0791) (xy 432.563529 -361.128229)
			(xy 432.627539 -361.183694) (xy 432.685987 -361.244992) (xy 432.738343 -361.311568) (xy 432.784133 -361.38282)
			(xy 432.822944 -361.458101) (xy 432.854423 -361.536731) (xy 432.878284 -361.617998) (xy 432.894313 -361.701164)
			(xy 432.902364 -361.785478) (xy 432.902868 -361.827826) (xy 432.902364 -361.870174) (xy 432.894313 -361.954488)
			(xy 432.878284 -362.037654) (xy 432.854423 -362.118921) (xy 432.822944 -362.197551) (xy 432.784133 -362.272832)
			(xy 432.738343 -362.344084) (xy 432.685987 -362.41066) (xy 432.627539 -362.471958) (xy 432.563529 -362.527423)
			(xy 432.494537 -362.576552) (xy 432.421187 -362.618901) (xy 432.344144 -362.654085) (xy 432.264105 -362.681787)
			(xy 432.181796 -362.701755) (xy 432.097961 -362.713808) (xy 432.01336 -362.717839) (xy 431.928759 -362.713808)
			(xy 431.844924 -362.701755) (xy 431.762615 -362.681787) (xy 431.682576 -362.654085) (xy 431.605533 -362.618901)
			(xy 431.532183 -362.576552) (xy 431.463191 -362.527423) (xy 431.399181 -362.471958) (xy 431.340733 -362.41066)
			(xy 431.288377 -362.344084) (xy 431.242587 -362.272832) (xy 431.203776 -362.197551) (xy 431.172297 -362.118921)
			(xy 431.148436 -362.037654) (xy 431.132407 -361.954488) (xy 431.124356 -361.870174) (xy 424.971544 -361.870174)
			(xy 424.964529 -361.874455) (xy 424.9132 -361.896267) (xy 424.859243 -361.910373) (xy 424.803806 -361.916473)
			(xy 424.748072 -361.914436) (xy 424.693229 -361.904306) (xy 424.640445 -361.886299) (xy 424.590845 -361.860798)
			(xy 424.545487 -361.828347) (xy 424.505338 -361.789638) (xy 424.471252 -361.745495) (xy 424.443956 -361.69686)
			(xy 424.424033 -361.644769) (xy 424.411907 -361.590332) (xy 424.407836 -361.53471) (xy 422.627464 -361.53471)
			(xy 422.617138 -361.555538) (xy 422.61663 -361.577636) (xy 422.621202 -361.588304) (xy 422.631327 -361.612509)
			(xy 422.645578 -361.663005) (xy 422.65277 -361.714978) (xy 422.653206 -361.741212) (xy 422.653111 -361.751457)
			(xy 422.651969 -361.771915) (xy 422.65092 -361.782106) (xy 422.649904 -361.792266) (xy 422.656 -361.812078)
			(xy 422.715944 -361.88396) (xy 422.734232 -361.893358) (xy 422.744392 -361.89412) (xy 422.772852 -361.89667)
			(xy 422.828568 -361.909356) (xy 422.88177 -361.930208) (xy 422.931268 -361.95876) (xy 422.975955 -361.994372)
			(xy 423.014833 -362.03625) (xy 423.047032 -362.083456) (xy 423.071833 -362.134936) (xy 423.088681 -362.189537)
			(xy 423.097199 -362.246041) (xy 423.097706 -362.274612) (xy 423.097235 -362.301594) (xy 423.089605 -362.355016)
			(xy 423.074527 -362.406832) (xy 423.052302 -362.456007) (xy 423.023372 -362.501561) (xy 422.988314 -362.542588)
			(xy 422.947828 -362.578267) (xy 422.902721 -362.607889) (xy 422.878504 -362.619798) (xy 422.870122 -362.623862)
			(xy 422.857168 -362.63707) (xy 422.823132 -362.716064) (xy 422.82237 -362.734606) (xy 422.825164 -362.743496)
			(xy 422.834042 -362.77241) (xy 422.843614 -362.832128) (xy 422.844214 -362.862368) (xy 422.843728 -362.889619)
			(xy 422.837786 -362.930948) (xy 439.741056 -362.930948) (xy 439.741537 -362.903578) (xy 439.749349 -362.849399)
			(xy 439.764834 -362.796896) (xy 439.787673 -362.747148) (xy 439.817395 -362.701182) (xy 439.835036 -362.68025)
			(xy 439.841132 -362.673138) (xy 439.847482 -362.65612) (xy 439.847482 -362.570776) (xy 439.841132 -362.553758)
			(xy 439.835036 -362.546646) (xy 439.817411 -362.525703) (xy 439.787695 -362.479734) (xy 439.764856 -362.429989)
			(xy 439.749362 -362.377491) (xy 439.741531 -362.323317) (xy 439.741056 -362.295948) (xy 439.7416 -362.268698)
			(xy 439.749349 -362.214752) (xy 439.764697 -362.162458) (xy 439.787332 -362.11288) (xy 439.816791 -362.067028)
			(xy 439.852477 -362.025836) (xy 439.893661 -361.990142) (xy 439.939506 -361.960672) (xy 439.989079 -361.938027)
			(xy 440.04137 -361.922667) (xy 440.095314 -361.914906) (xy 440.122564 -361.91444) (xy 440.149934 -361.914917)
			(xy 440.204113 -361.922731) (xy 440.256616 -361.938217) (xy 440.306363 -361.961056) (xy 440.35233 -361.990779)
			(xy 440.373262 -362.00842) (xy 440.380374 -362.014516) (xy 440.397392 -362.020866) (xy 440.482736 -362.020866)
			(xy 440.499754 -362.014516) (xy 440.506866 -362.00842) (xy 440.527799 -361.990779) (xy 440.573767 -361.961055)
			(xy 440.623513 -361.938209) (xy 440.676015 -361.922713) (xy 440.730193 -361.914884) (xy 440.784935 -361.914884)
			(xy 440.839113 -361.922713) (xy 440.891615 -361.938209) (xy 440.941361 -361.961055) (xy 440.987329 -361.990779)
			(xy 441.008262 -362.00842) (xy 441.015374 -362.014516) (xy 441.032392 -362.020866) (xy 441.117736 -362.020866)
			(xy 441.134754 -362.014516) (xy 441.141866 -362.00842) (xy 441.162799 -361.990779) (xy 441.208767 -361.961055)
			(xy 441.258513 -361.938209) (xy 441.311015 -361.922713) (xy 441.365193 -361.914884) (xy 441.419935 -361.914884)
			(xy 441.474113 -361.922713) (xy 441.526615 -361.938209) (xy 441.576361 -361.961055) (xy 441.622329 -361.990779)
			(xy 441.643262 -362.00842) (xy 441.650374 -362.014516) (xy 441.667392 -362.020866) (xy 441.752736 -362.020866)
			(xy 441.769754 -362.014516) (xy 441.776866 -362.00842) (xy 441.780676 -362.005118) (xy 441.788794 -361.997516)
			(xy 441.798146 -361.977364) (xy 441.79871 -361.966256) (xy 441.79871 -361.88904) (xy 441.798164 -361.877927)
			(xy 441.788813 -361.857766) (xy 441.780676 -361.850178) (xy 441.759946 -361.831987) (xy 441.723478 -361.790614)
			(xy 441.693349 -361.744419) (xy 441.670187 -361.694367) (xy 441.654474 -361.641501) (xy 441.646539 -361.586924)
			(xy 441.646056 -361.559348) (xy 441.646537 -361.531978) (xy 441.654349 -361.477799) (xy 441.669834 -361.425296)
			(xy 441.692673 -361.375548) (xy 441.722395 -361.329582) (xy 441.740036 -361.30865) (xy 441.746132 -361.301538)
			(xy 441.752482 -361.28452) (xy 441.752482 -361.199176) (xy 441.746132 -361.182158) (xy 441.740036 -361.175046)
			(xy 441.722442 -361.154075) (xy 441.692715 -361.108114) (xy 441.669866 -361.058374) (xy 441.654365 -361.005878)
			(xy 441.646532 -360.951705) (xy 441.646527 -360.896968) (xy 441.65435 -360.842793) (xy 441.66984 -360.790293)
			(xy 441.69268 -360.740549) (xy 441.722398 -360.694582) (xy 441.740036 -360.67365) (xy 441.746132 -360.666538)
			(xy 441.752482 -360.64952) (xy 441.752482 -360.564176) (xy 441.746132 -360.547158) (xy 441.740036 -360.540046)
			(xy 441.722442 -360.519075) (xy 441.692715 -360.473114) (xy 441.669866 -360.423374) (xy 441.654365 -360.370878)
			(xy 441.646532 -360.316705) (xy 441.646527 -360.261968) (xy 441.65435 -360.207793) (xy 441.66984 -360.155293)
			(xy 441.69268 -360.105549) (xy 441.722398 -360.059582) (xy 441.740036 -360.03865) (xy 441.746132 -360.031538)
			(xy 441.752482 -360.01452) (xy 441.752482 -359.929176) (xy 441.746132 -359.912158) (xy 441.740036 -359.905046)
			(xy 441.722411 -359.884103) (xy 441.692695 -359.838134) (xy 441.669856 -359.788389) (xy 441.654362 -359.735891)
			(xy 441.646531 -359.681717) (xy 441.646056 -359.654348) (xy 441.646535 -359.626774) (xy 441.654482 -359.572201)
			(xy 441.670203 -359.51934) (xy 441.693371 -359.469294) (xy 441.723502 -359.423104) (xy 441.759969 -359.381733)
			(xy 441.780676 -359.363518) (xy 441.788794 -359.355916) (xy 441.798146 -359.335764) (xy 441.79871 -359.324656)
			(xy 441.79871 -359.24744) (xy 441.798164 -359.236327) (xy 441.788813 -359.216166) (xy 441.780676 -359.208578)
			(xy 441.776866 -359.205276) (xy 441.769754 -359.19918) (xy 441.752736 -359.19283) (xy 441.667392 -359.19283)
			(xy 441.650374 -359.19918) (xy 441.643262 -359.205276) (xy 441.622329 -359.222917) (xy 441.576361 -359.252641)
			(xy 441.526615 -359.275487) (xy 441.474113 -359.290983) (xy 441.419935 -359.298812) (xy 441.365193 -359.298812)
			(xy 441.311015 -359.290983) (xy 441.258513 -359.275487) (xy 441.208767 -359.252641) (xy 441.162799 -359.222917)
			(xy 441.141866 -359.205276) (xy 441.134754 -359.19918) (xy 441.117736 -359.19283) (xy 441.032392 -359.19283)
			(xy 441.015374 -359.19918) (xy 441.008262 -359.205276) (xy 440.987329 -359.222917) (xy 440.941361 -359.252641)
			(xy 440.891615 -359.275487) (xy 440.839113 -359.290983) (xy 440.784935 -359.298812) (xy 440.730193 -359.298812)
			(xy 440.676015 -359.290983) (xy 440.623513 -359.275487) (xy 440.573767 -359.252641) (xy 440.527799 -359.222917)
			(xy 440.506866 -359.205276) (xy 440.499754 -359.19918) (xy 440.482736 -359.19283) (xy 440.397392 -359.19283)
			(xy 440.380374 -359.19918) (xy 440.373262 -359.205276) (xy 440.352314 -359.222896) (xy 440.306346 -359.252611)
			(xy 440.256603 -359.275451) (xy 440.204105 -359.290947) (xy 440.149932 -359.29878) (xy 440.122564 -359.299256)
			(xy 440.095314 -359.298756) (xy 440.041369 -359.290996) (xy 439.989078 -359.275638) (xy 439.939504 -359.252997)
			(xy 439.893656 -359.223531) (xy 439.852467 -359.187841) (xy 439.816776 -359.146654) (xy 439.787309 -359.100807)
			(xy 439.764666 -359.051233) (xy 439.749307 -358.998942) (xy 439.741545 -358.944998) (xy 439.741056 -358.917748)
			(xy 439.741537 -358.890378) (xy 439.749349 -358.836199) (xy 439.764834 -358.783696) (xy 439.787673 -358.733948)
			(xy 439.817395 -358.687982) (xy 439.835036 -358.66705) (xy 439.841132 -358.659938) (xy 439.847482 -358.64292)
			(xy 439.847482 -358.557576) (xy 439.841132 -358.540558) (xy 439.835036 -358.533446) (xy 439.817411 -358.512503)
			(xy 439.787695 -358.466534) (xy 439.764856 -358.416789) (xy 439.749362 -358.364291) (xy 439.741531 -358.310117)
			(xy 439.741056 -358.282748) (xy 439.7416 -358.255498) (xy 439.749349 -358.201552) (xy 439.764697 -358.149258)
			(xy 439.787332 -358.09968) (xy 439.816791 -358.053828) (xy 439.852477 -358.012636) (xy 439.893661 -357.976942)
			(xy 439.939506 -357.947472) (xy 439.989079 -357.924827) (xy 440.04137 -357.909467) (xy 440.095314 -357.901706)
			(xy 440.122564 -357.90124) (xy 440.149934 -357.901717) (xy 440.204113 -357.909531) (xy 440.256616 -357.925017)
			(xy 440.306363 -357.947856) (xy 440.35233 -357.977579) (xy 440.373262 -357.99522) (xy 440.380374 -358.001316)
			(xy 440.397392 -358.007666) (xy 440.482736 -358.007666) (xy 440.499754 -358.001316) (xy 440.506866 -357.99522)
			(xy 440.527799 -357.977579) (xy 440.573767 -357.947855) (xy 440.623513 -357.925009) (xy 440.676015 -357.909513)
			(xy 440.730193 -357.901684) (xy 440.784935 -357.901684) (xy 440.839113 -357.909513) (xy 440.891615 -357.925009)
			(xy 440.941361 -357.947855) (xy 440.987329 -357.977579) (xy 441.008262 -357.99522) (xy 441.015374 -358.001316)
			(xy 441.032392 -358.007666) (xy 441.117736 -358.007666) (xy 441.134754 -358.001316) (xy 441.141866 -357.99522)
			(xy 441.162799 -357.977579) (xy 441.208767 -357.947855) (xy 441.258513 -357.925009) (xy 441.311015 -357.909513)
			(xy 441.365193 -357.901684) (xy 441.419935 -357.901684) (xy 441.474113 -357.909513) (xy 441.526615 -357.925009)
			(xy 441.576361 -357.947855) (xy 441.622329 -357.977579) (xy 441.643262 -357.99522) (xy 441.650374 -358.001316)
			(xy 441.667392 -358.007666) (xy 441.752736 -358.007666) (xy 441.769754 -358.001316) (xy 441.776866 -357.99522)
			(xy 441.797799 -357.977579) (xy 441.843767 -357.947855) (xy 441.893513 -357.925009) (xy 441.946015 -357.909513)
			(xy 442.000193 -357.901684) (xy 442.054935 -357.901684) (xy 442.109113 -357.909513) (xy 442.161615 -357.925009)
			(xy 442.211361 -357.947855) (xy 442.257329 -357.977579) (xy 442.278262 -357.99522) (xy 442.285374 -358.001316)
			(xy 442.302392 -358.007666) (xy 442.387736 -358.007666) (xy 442.404754 -358.001316) (xy 442.411866 -357.99522)
			(xy 442.432803 -357.977586) (xy 442.478774 -357.947873) (xy 442.52852 -357.925036) (xy 442.58102 -357.909543)
			(xy 442.635195 -357.901714) (xy 442.662564 -357.90124) (xy 442.689818 -357.901689) (xy 442.743772 -357.909442)
			(xy 442.796073 -357.924796) (xy 442.845656 -357.947438) (xy 442.891512 -357.976907) (xy 442.932706 -358.012602)
			(xy 442.968401 -358.053798) (xy 442.997868 -358.099654) (xy 443.020508 -358.149238) (xy 443.03586 -358.20154)
			(xy 443.043612 -358.255494) (xy 443.044072 -358.282748) (xy 443.043582 -358.310117) (xy 443.035771 -358.364296)
			(xy 443.020288 -358.416799) (xy 442.997451 -358.466546) (xy 442.967731 -358.512514) (xy 442.950092 -358.533446)
			(xy 442.943996 -358.540558) (xy 442.937646 -358.557576) (xy 442.937646 -358.64292) (xy 442.943996 -358.659938)
			(xy 442.950092 -358.66705) (xy 442.96772 -358.687991) (xy 442.997434 -358.733961) (xy 443.020272 -358.783707)
			(xy 443.035766 -358.836205) (xy 443.043597 -358.890379) (xy 443.044072 -358.917748) (xy 443.04358 -358.945322)
			(xy 443.035634 -358.999894) (xy 443.019915 -359.052754) (xy 442.99675 -359.1028) (xy 442.966622 -359.14899)
			(xy 442.930158 -359.190362) (xy 442.909452 -359.208578) (xy 442.90134 -359.216186) (xy 442.891984 -359.236334)
			(xy 442.891418 -359.24744) (xy 442.891418 -359.324656) (xy 442.891989 -359.335766) (xy 442.901325 -359.355925)
			(xy 442.909452 -359.363518) (xy 442.930165 -359.381727) (xy 442.966638 -359.423095) (xy 442.996771 -359.469285)
			(xy 443.019936 -359.519334) (xy 443.035652 -359.572197) (xy 443.043589 -359.626773) (xy 443.044072 -359.654348)
			(xy 443.043582 -359.681717) (xy 443.035771 -359.735896) (xy 443.020288 -359.788399) (xy 442.997451 -359.838146)
			(xy 442.967731 -359.884114) (xy 442.950092 -359.905046) (xy 442.943996 -359.912158) (xy 442.937646 -359.929176)
			(xy 442.937646 -360.01452) (xy 442.943996 -360.031538) (xy 442.950092 -360.03865) (xy 442.967779 -360.059545)
			(xy 442.9975 -360.10552) (xy 443.020342 -360.155272) (xy 443.035833 -360.20778) (xy 443.043657 -360.261963)
			(xy 443.043652 -360.316709) (xy 443.035818 -360.370891) (xy 443.020316 -360.423395) (xy 442.997465 -360.473144)
			(xy 442.967735 -360.519113) (xy 442.950092 -360.540046) (xy 442.943996 -360.547158) (xy 442.937646 -360.564176)
			(xy 442.937646 -360.64952) (xy 442.943996 -360.666538) (xy 442.950092 -360.67365) (xy 442.967779 -360.694545)
			(xy 442.9975 -360.74052) (xy 443.020342 -360.790272) (xy 443.035833 -360.84278) (xy 443.043657 -360.896963)
			(xy 443.043652 -360.951709) (xy 443.035818 -361.005891) (xy 443.020316 -361.058395) (xy 442.997465 -361.108144)
			(xy 442.967735 -361.154113) (xy 442.950092 -361.175046) (xy 442.943996 -361.182158) (xy 442.937646 -361.199176)
			(xy 442.937646 -361.28452) (xy 442.943996 -361.301538) (xy 442.950092 -361.30865) (xy 442.96772 -361.329591)
			(xy 442.997434 -361.375561) (xy 443.020272 -361.425307) (xy 443.035766 -361.477805) (xy 443.043597 -361.531979)
			(xy 443.044072 -361.559348) (xy 443.043667 -361.586602) (xy 443.035903 -361.640555) (xy 443.02054 -361.692853)
			(xy 442.99789 -361.742433) (xy 442.968416 -361.788285) (xy 442.932716 -361.829475) (xy 442.891517 -361.865166)
			(xy 442.845659 -361.894631) (xy 442.796074 -361.917269) (xy 442.743772 -361.932621) (xy 442.689818 -361.940373)
			(xy 442.662564 -361.940856) (xy 442.635192 -361.940422) (xy 442.581012 -361.932598) (xy 442.528508 -361.917102)
			(xy 442.478761 -361.894253) (xy 442.432796 -361.864521) (xy 442.411866 -361.846876) (xy 442.404754 -361.84078)
			(xy 442.387736 -361.83443) (xy 442.302392 -361.83443) (xy 442.285374 -361.84078) (xy 442.278262 -361.846876)
			(xy 442.274452 -361.850178) (xy 442.26634 -361.857786) (xy 442.256984 -361.877934) (xy 442.256418 -361.88904)
			(xy 442.256418 -361.966256) (xy 442.256989 -361.977366) (xy 442.266325 -361.997525) (xy 442.274452 -362.005118)
			(xy 442.295165 -362.023327) (xy 442.331638 -362.064695) (xy 442.361771 -362.110885) (xy 442.384936 -362.160934)
			(xy 442.400652 -362.213797) (xy 442.408589 -362.268373) (xy 442.409072 -362.295948) (xy 442.408667 -362.323202)
			(xy 442.400903 -362.377155) (xy 442.38554 -362.429453) (xy 442.36289 -362.479033) (xy 442.333416 -362.524885)
			(xy 442.297716 -362.566075) (xy 442.256517 -362.601766) (xy 442.210659 -362.631231) (xy 442.161074 -362.653869)
			(xy 442.108772 -362.669221) (xy 442.054818 -362.676973) (xy 442.027564 -362.677456) (xy 441.998087 -362.676888)
			(xy 441.939835 -362.667827) (xy 441.88367 -362.649912) (xy 441.83093 -362.623569) (xy 441.782872 -362.589424)
			(xy 441.761372 -362.569252) (xy 441.754047 -362.562706) (xy 441.735879 -362.555269) (xy 441.726066 -362.554774)
			(xy 441.672726 -362.554774) (xy 441.665868 -362.56214) (xy 441.659319 -362.569463) (xy 441.651883 -362.587632)
			(xy 441.65139 -362.597446) (xy 441.65139 -362.62945) (xy 441.651862 -362.639266) (xy 441.659317 -362.65743)
			(xy 441.665868 -362.664756) (xy 441.686023 -362.686272) (xy 441.72017 -362.734327) (xy 441.746519 -362.787062)
			(xy 441.764445 -362.843223) (xy 441.77352 -362.901472) (xy 441.774072 -362.930948) (xy 441.773667 -362.958202)
			(xy 441.765903 -363.012155) (xy 441.75054 -363.064453) (xy 441.72789 -363.114033) (xy 441.698416 -363.159885)
			(xy 441.662716 -363.201075) (xy 441.621517 -363.236766) (xy 441.575659 -363.266231) (xy 441.526074 -363.288869)
			(xy 441.473772 -363.304221) (xy 441.419818 -363.311973) (xy 441.392564 -363.312456) (xy 441.365192 -363.312022)
			(xy 441.311012 -363.304198) (xy 441.258508 -363.288702) (xy 441.208761 -363.265853) (xy 441.162796 -363.236121)
			(xy 441.141866 -363.218476) (xy 441.134754 -363.21238) (xy 441.117736 -363.20603) (xy 441.032392 -363.20603)
			(xy 441.015374 -363.21238) (xy 441.008262 -363.218476) (xy 440.987329 -363.236117) (xy 440.941361 -363.265841)
			(xy 440.891615 -363.288687) (xy 440.839113 -363.304183) (xy 440.784935 -363.312012) (xy 440.730193 -363.312012)
			(xy 440.676015 -363.304183) (xy 440.623513 -363.288687) (xy 440.573767 -363.265841) (xy 440.527799 -363.236117)
			(xy 440.506866 -363.218476) (xy 440.499754 -363.21238) (xy 440.482736 -363.20603) (xy 440.397392 -363.20603)
			(xy 440.380374 -363.21238) (xy 440.373262 -363.218476) (xy 440.352314 -363.236096) (xy 440.306346 -363.265811)
			(xy 440.256603 -363.288651) (xy 440.204105 -363.304147) (xy 440.149932 -363.31198) (xy 440.122564 -363.312456)
			(xy 440.095314 -363.311956) (xy 440.041369 -363.304196) (xy 439.989078 -363.288838) (xy 439.939504 -363.266197)
			(xy 439.893656 -363.236731) (xy 439.852467 -363.201041) (xy 439.816776 -363.159854) (xy 439.787309 -363.114007)
			(xy 439.764666 -363.064433) (xy 439.749307 -363.012142) (xy 439.741545 -362.958198) (xy 439.741056 -362.930948)
			(xy 422.837786 -362.930948) (xy 422.835972 -362.943567) (xy 422.820617 -362.995862) (xy 422.797975 -363.045439)
			(xy 422.768509 -363.091289) (xy 422.732818 -363.13248) (xy 422.691627 -363.168171) (xy 422.645777 -363.197637)
			(xy 422.5962 -363.220279) (xy 422.543905 -363.235634) (xy 422.489957 -363.24339) (xy 422.435455 -363.24339)
			(xy 422.381507 -363.235634) (xy 422.329212 -363.220279) (xy 422.279635 -363.197637) (xy 422.233785 -363.168171)
			(xy 422.192594 -363.13248) (xy 422.156903 -363.091289) (xy 422.127437 -363.045439) (xy 422.104795 -362.995862)
			(xy 422.08944 -362.943567) (xy 422.081684 -362.889619) (xy 422.081198 -362.862368) (xy 422.081813 -362.830515)
			(xy 422.092383 -362.767693) (xy 422.113225 -362.707494) (xy 422.127934 -362.679234) (xy 422.134538 -362.667296)
			(xy 422.13403 -362.64088) (xy 422.082468 -362.553758) (xy 422.077656 -362.546415) (xy 422.064091 -362.535291)
			(xy 422.047554 -362.529437) (xy 422.03878 -362.52912) (xy 422.032684 -362.52912) (xy 422.007686 -362.52851)
			(xy 421.958662 -362.5187) (xy 421.912491 -362.499519) (xy 421.870946 -362.471703) (xy 421.852852 -362.454444)
			(xy 420.99992 -361.601512) (xy 420.98268 -361.583402) (xy 420.954866 -361.541862) (xy 420.935688 -361.495696)
			(xy 420.925884 -361.446675) (xy 420.925244 -361.42168) (xy 415.723326 -361.42168) (xy 415.718185 -361.438769)
			(xy 415.694513 -361.489266) (xy 415.66374 -361.535779) (xy 415.626523 -361.577316) (xy 415.583655 -361.612991)
			(xy 415.536049 -361.642045) (xy 415.48472 -361.663857) (xy 415.430763 -361.677963) (xy 415.375326 -361.684063)
			(xy 415.319592 -361.682026) (xy 415.264749 -361.671896) (xy 415.211965 -361.653889) (xy 415.162365 -361.628388)
			(xy 415.117007 -361.595937) (xy 415.076858 -361.557228) (xy 415.042772 -361.513085) (xy 415.015476 -361.46445)
			(xy 414.995553 -361.412359) (xy 414.983427 -361.357922) (xy 414.979356 -361.3023) (xy 412.212536 -361.3023)
			(xy 412.212536 -364.079536) (xy 412.440372 -364.079536) (xy 412.444443 -364.023914) (xy 412.456569 -363.969477)
			(xy 412.476492 -363.917386) (xy 412.503788 -363.868751) (xy 412.537874 -363.824608) (xy 412.578023 -363.785899)
			(xy 412.623381 -363.753448) (xy 412.672981 -363.727947) (xy 412.725765 -363.70994) (xy 412.780608 -363.69981)
			(xy 412.836342 -363.697773) (xy 412.891779 -363.703873) (xy 412.945736 -363.717979) (xy 412.997065 -363.739791)
			(xy 413.044671 -363.768845) (xy 413.087539 -363.80452) (xy 413.124756 -363.846057) (xy 413.155529 -363.89257)
			(xy 413.179201 -363.943067) (xy 413.195269 -363.996474) (xy 413.203389 -364.05165) (xy 413.203898 -364.079536)
			(xy 413.203389 -364.107422) (xy 413.195269 -364.162598) (xy 413.179201 -364.216005) (xy 413.155529 -364.266502)
			(xy 413.124756 -364.313015) (xy 413.087539 -364.354552) (xy 413.044671 -364.390227) (xy 412.997065 -364.419281)
			(xy 412.945736 -364.441093) (xy 412.891779 -364.455199) (xy 412.836342 -364.461299) (xy 412.780608 -364.459262)
			(xy 412.725765 -364.449132) (xy 412.672981 -364.431125) (xy 412.623381 -364.405624) (xy 412.578023 -364.373173)
			(xy 412.537874 -364.334464) (xy 412.503788 -364.290321) (xy 412.476492 -364.241686) (xy 412.456569 -364.189595)
			(xy 412.444443 -364.135158) (xy 412.440372 -364.079536) (xy 412.212536 -364.079536) (xy 412.212536 -365.098838)
			(xy 412.211933 -365.133801) (xy 412.202312 -365.203062) (xy 412.183297 -365.270353) (xy 412.155247 -365.334407)
			(xy 412.11869 -365.394017) (xy 412.096966 -365.421418) (xy 412.091378 -365.428276) (xy 412.085536 -365.444532)
			(xy 412.085536 -365.479838) (xy 412.085964 -365.489537) (xy 412.093144 -365.507557) (xy 412.099506 -365.51489)
			(xy 412.154878 -365.572802) (xy 412.172658 -365.58093) (xy 412.182564 -365.581438) (xy 412.210214 -365.583209)
			(xy 412.264608 -365.593743) (xy 412.316905 -365.612036) (xy 412.366005 -365.637705) (xy 412.410874 -365.670208)
			(xy 412.450567 -365.708862) (xy 412.484249 -365.752853) (xy 412.511211 -365.801254) (xy 412.530885 -365.853048)
			(xy 412.542858 -365.907143) (xy 412.546877 -365.962402) (xy 412.542857 -366.01766) (xy 412.530884 -366.071756)
			(xy 412.511209 -366.123549) (xy 412.484247 -366.17195) (xy 412.450564 -366.215941) (xy 412.410871 -366.254594)
			(xy 412.366002 -366.287097) (xy 412.316902 -366.312765) (xy 412.264605 -366.331058) (xy 412.210211 -366.341591)
			(xy 412.182564 -366.343438) (xy 412.172658 -366.343946) (xy 412.154878 -366.352074) (xy 412.099506 -366.409986)
			(xy 412.093122 -366.417307) (xy 412.085931 -366.435333) (xy 412.085536 -366.445038) (xy 412.085536 -366.780064)
			(xy 412.411162 -366.780064) (xy 412.415233 -366.724442) (xy 412.427359 -366.670005) (xy 412.447282 -366.617914)
			(xy 412.474578 -366.569279) (xy 412.508664 -366.525136) (xy 412.548813 -366.486427) (xy 412.594171 -366.453976)
			(xy 412.643771 -366.428475) (xy 412.696555 -366.410468) (xy 412.751398 -366.400338) (xy 412.807132 -366.398301)
			(xy 412.862569 -366.404401) (xy 412.916526 -366.418507) (xy 412.967855 -366.440319) (xy 413.015461 -366.469373)
			(xy 413.058329 -366.505048) (xy 413.095546 -366.546585) (xy 413.126319 -366.593098) (xy 413.149991 -366.643595)
			(xy 413.166059 -366.697002) (xy 413.174179 -366.752178) (xy 413.174688 -366.780064) (xy 413.174179 -366.80795)
			(xy 413.166059 -366.863126) (xy 413.149991 -366.916533) (xy 413.126319 -366.96703) (xy 413.095546 -367.013543)
			(xy 413.058329 -367.05508) (xy 413.015461 -367.090755) (xy 412.967855 -367.119809) (xy 412.916526 -367.141621)
			(xy 412.862569 -367.155727) (xy 412.807132 -367.161827) (xy 412.751398 -367.15979) (xy 412.696555 -367.14966)
			(xy 412.643771 -367.131653) (xy 412.594171 -367.106152) (xy 412.548813 -367.073701) (xy 412.508664 -367.034992)
			(xy 412.474578 -366.990849) (xy 412.447282 -366.942214) (xy 412.427359 -366.890123) (xy 412.415233 -366.835686)
			(xy 412.411162 -366.780064) (xy 412.085536 -366.780064) (xy 412.085536 -367.876074) (xy 412.085973 -367.886137)
			(xy 412.093711 -367.904719) (xy 412.100522 -367.912142) (xy 412.270194 -368.081814) (xy 412.270702 -368.082322)
			(xy 412.278084 -368.0889) (xy 412.296384 -368.096338) (xy 412.306262 -368.0968)
		)
		(stroke
			(width 0)
			(type solid)
		)
		(fill yes)
		(layer "In2.Cu")
		(net "GND")
	)
	(gr_poly
		(pts
			(xy 114.333528 -392.588242) (xy 114.343595 -392.587812) (xy 114.362186 -392.580084) (xy 114.369596 -392.573256)
			(xy 114.5286 -392.414252) (xy 114.535966 -392.398758) (xy 114.536728 -392.389868) (xy 114.540095 -392.362387)
			(xy 114.553737 -392.30873) (xy 114.57498 -392.257603) (xy 114.603378 -392.210076) (xy 114.638337 -392.167145)
			(xy 114.658394 -392.14806) (xy 114.665506 -392.14171) (xy 114.673634 -392.124946) (xy 114.682016 -392.038332)
			(xy 114.676936 -392.020552) (xy 114.671348 -392.012678) (xy 114.657191 -391.992833) (xy 114.634705 -391.949585)
			(xy 114.619387 -391.90331) (xy 114.611628 -391.855186) (xy 114.61115 -391.830814) (xy 114.611672 -391.805559)
			(xy 114.619985 -391.755737) (xy 114.636386 -391.707963) (xy 114.660427 -391.66354) (xy 114.691451 -391.62368)
			(xy 114.728613 -391.58947) (xy 114.770899 -391.561844) (xy 114.817155 -391.541554) (xy 114.86612 -391.529154)
			(xy 114.916458 -391.524983) (xy 114.966796 -391.529154) (xy 115.015761 -391.541554) (xy 115.062017 -391.561844)
			(xy 115.104303 -391.58947) (xy 115.141465 -391.62368) (xy 115.172489 -391.66354) (xy 115.19653 -391.707963)
			(xy 115.212931 -391.755737) (xy 115.221244 -391.805559) (xy 115.221766 -391.830814) (xy 115.221268 -391.855184)
			(xy 115.213488 -391.9033) (xy 115.198177 -391.949573) (xy 115.175721 -391.992833) (xy 115.161568 -392.012678)
			(xy 115.15598 -392.020552) (xy 115.1509 -392.038332) (xy 115.159282 -392.124946) (xy 115.16741 -392.14171)
			(xy 115.174522 -392.14806) (xy 115.1965 -392.169063) (xy 115.23415 -392.216788) (xy 115.249452 -392.243056)
			(xy 115.254193 -392.250743) (xy 115.267939 -392.262438) (xy 115.284878 -392.268669) (xy 115.293902 -392.268964)
			(xy 115.73891 -392.268964) (xy 115.747937 -392.268649) (xy 115.764892 -392.262459) (xy 115.77863 -392.250751)
			(xy 115.78336 -392.243056) (xy 115.798682 -392.216801) (xy 115.836323 -392.169072) (xy 115.85829 -392.14806)
			(xy 115.865402 -392.141456) (xy 115.873784 -392.124946) (xy 115.881912 -392.038078) (xy 115.877086 -392.020298)
			(xy 115.871244 -392.012678) (xy 115.857139 -391.992813) (xy 115.834748 -391.949546) (xy 115.819502 -391.903276)
			(xy 115.811788 -391.855173) (xy 115.8113 -391.830814) (xy 115.811822 -391.805559) (xy 115.820135 -391.755737)
			(xy 115.836536 -391.707963) (xy 115.860577 -391.66354) (xy 115.891601 -391.62368) (xy 115.928763 -391.58947)
			(xy 115.971049 -391.561844) (xy 116.017305 -391.541554) (xy 116.06627 -391.529154) (xy 116.116608 -391.524983)
			(xy 116.166946 -391.529154) (xy 116.215911 -391.541554) (xy 116.262167 -391.561844) (xy 116.304453 -391.58947)
			(xy 116.341615 -391.62368) (xy 116.372639 -391.66354) (xy 116.39668 -391.707963) (xy 116.413081 -391.755737)
			(xy 116.421394 -391.805559) (xy 116.421916 -391.830814) (xy 116.421438 -391.855216) (xy 116.413679 -391.903399)
			(xy 116.398362 -391.949737) (xy 116.375876 -391.993051) (xy 116.361718 -392.012932) (xy 116.35613 -392.020552)
			(xy 116.35105 -392.038332) (xy 116.359178 -392.1252) (xy 116.36756 -392.14171) (xy 116.374672 -392.148314)
			(xy 116.396569 -392.169271) (xy 116.434094 -392.216865) (xy 116.449348 -392.243056) (xy 116.454089 -392.250743)
			(xy 116.467835 -392.26244) (xy 116.484774 -392.268672) (xy 116.493798 -392.268964) (xy 116.93906 -392.268964)
			(xy 116.948091 -392.268657) (xy 116.96506 -392.262478) (xy 116.978811 -392.250774) (xy 116.98351 -392.243056)
			(xy 116.998834 -392.216803) (xy 117.036478 -392.169077) (xy 117.05844 -392.14806) (xy 117.065552 -392.14171)
			(xy 117.07368 -392.124946) (xy 117.082062 -392.038332) (xy 117.076982 -392.020552) (xy 117.071394 -392.012678)
			(xy 117.057235 -391.992834) (xy 117.034745 -391.949586) (xy 117.019425 -391.903311) (xy 117.011665 -391.855187)
			(xy 117.011196 -391.830814) (xy 117.011718 -391.805559) (xy 117.020031 -391.755737) (xy 117.036432 -391.707963)
			(xy 117.060473 -391.66354) (xy 117.091497 -391.62368) (xy 117.128659 -391.58947) (xy 117.170945 -391.561844)
			(xy 117.217201 -391.541554) (xy 117.266166 -391.529154) (xy 117.316504 -391.524983) (xy 117.366842 -391.529154)
			(xy 117.415807 -391.541554) (xy 117.462063 -391.561844) (xy 117.504349 -391.58947) (xy 117.541511 -391.62368)
			(xy 117.572535 -391.66354) (xy 117.596576 -391.707963) (xy 117.612977 -391.755737) (xy 117.62129 -391.805559)
			(xy 117.621812 -391.830814) (xy 117.621313 -391.855184) (xy 117.613533 -391.903299) (xy 117.598219 -391.949571)
			(xy 117.57576 -391.992828) (xy 117.561614 -392.012678) (xy 117.556026 -392.020552) (xy 117.550946 -392.038332)
			(xy 117.559328 -392.124946) (xy 117.567456 -392.14171) (xy 117.574568 -392.14806) (xy 117.596544 -392.169065)
			(xy 117.63419 -392.216792) (xy 117.649498 -392.243056) (xy 117.654241 -392.250737) (xy 117.667989 -392.262421)
			(xy 117.684927 -392.268636) (xy 117.693948 -392.268964) (xy 118.138956 -392.268964) (xy 118.147988 -392.268658)
			(xy 118.164957 -392.26248) (xy 118.17871 -392.250775) (xy 118.183406 -392.243056) (xy 118.198729 -392.216803)
			(xy 118.236373 -392.169076) (xy 118.258336 -392.14806) (xy 118.265448 -392.14171) (xy 118.273576 -392.124946)
			(xy 118.281958 -392.038332) (xy 118.276878 -392.020552) (xy 118.27129 -392.012678) (xy 118.257131 -391.992834)
			(xy 118.234642 -391.949586) (xy 118.219322 -391.903311) (xy 118.211562 -391.855187) (xy 118.211092 -391.830814)
			(xy 118.211614 -391.805559) (xy 118.219927 -391.755737) (xy 118.236328 -391.707963) (xy 118.260369 -391.66354)
			(xy 118.291393 -391.62368) (xy 118.328555 -391.58947) (xy 118.370841 -391.561844) (xy 118.417097 -391.541554)
			(xy 118.466062 -391.529154) (xy 118.5164 -391.524983) (xy 118.566738 -391.529154) (xy 118.615703 -391.541554)
			(xy 118.661959 -391.561844) (xy 118.704245 -391.58947) (xy 118.741407 -391.62368) (xy 118.772431 -391.66354)
			(xy 118.796472 -391.707963) (xy 118.812873 -391.755737) (xy 118.821186 -391.805559) (xy 118.821708 -391.830814)
			(xy 118.821209 -391.855184) (xy 118.813429 -391.903299) (xy 118.798115 -391.949571) (xy 118.775655 -391.992828)
			(xy 118.76151 -392.012678) (xy 118.755922 -392.020552) (xy 118.750842 -392.038332) (xy 118.759224 -392.124946)
			(xy 118.767352 -392.14171) (xy 118.774464 -392.14806) (xy 118.79644 -392.169065) (xy 118.834087 -392.216792)
			(xy 118.849394 -392.243056) (xy 118.854137 -392.250738) (xy 118.867885 -392.262422) (xy 118.884823 -392.268639)
			(xy 118.893844 -392.268964) (xy 119.339106 -392.268964) (xy 119.348133 -392.26865) (xy 119.36509 -392.262461)
			(xy 119.378828 -392.250753) (xy 119.383556 -392.243056) (xy 119.398878 -392.216801) (xy 119.436518 -392.169071)
			(xy 119.458486 -392.14806) (xy 119.465598 -392.14171) (xy 119.473726 -392.124946) (xy 119.482108 -392.038332)
			(xy 119.477028 -392.020552) (xy 119.47144 -392.012678) (xy 119.457283 -391.992833) (xy 119.434798 -391.949585)
			(xy 119.41948 -391.903309) (xy 119.411722 -391.855186) (xy 119.411242 -391.830814) (xy 119.411764 -391.805559)
			(xy 119.420077 -391.755737) (xy 119.436478 -391.707963) (xy 119.460519 -391.66354) (xy 119.491543 -391.62368)
			(xy 119.528705 -391.58947) (xy 119.570991 -391.561844) (xy 119.617247 -391.541554) (xy 119.666212 -391.529154)
			(xy 119.71655 -391.524983) (xy 119.766888 -391.529154) (xy 119.815853 -391.541554) (xy 119.862109 -391.561844)
			(xy 119.904395 -391.58947) (xy 119.941557 -391.62368) (xy 119.972581 -391.66354) (xy 119.996622 -391.707963)
			(xy 120.013023 -391.755737) (xy 120.021336 -391.805559) (xy 120.021858 -391.830814) (xy 120.02136 -391.855184)
			(xy 120.01358 -391.9033) (xy 119.998268 -391.949573) (xy 119.975812 -391.992832) (xy 119.96166 -392.012678)
			(xy 119.956072 -392.020552) (xy 119.950992 -392.038332) (xy 119.959374 -392.124946) (xy 119.967502 -392.14171)
			(xy 119.974614 -392.14806) (xy 119.996592 -392.169063) (xy 120.034243 -392.216787) (xy 120.049544 -392.243056)
			(xy 120.05429 -392.250732) (xy 120.06804 -392.262403) (xy 120.084976 -392.268604) (xy 120.093994 -392.268964)
			(xy 120.539002 -392.268964) (xy 120.54803 -392.26865) (xy 120.564987 -392.262462) (xy 120.578727 -392.250755)
			(xy 120.583452 -392.243056) (xy 120.598774 -392.216801) (xy 120.636414 -392.169071) (xy 120.658382 -392.14806)
			(xy 120.665494 -392.14171) (xy 120.673622 -392.124946) (xy 120.682004 -392.038332) (xy 120.676924 -392.020552)
			(xy 120.671336 -392.012678) (xy 120.657179 -391.992833) (xy 120.634694 -391.949585) (xy 120.619377 -391.903309)
			(xy 120.611619 -391.855186) (xy 120.611138 -391.830814) (xy 120.61166 -391.805559) (xy 120.619973 -391.755737)
			(xy 120.636374 -391.707963) (xy 120.660415 -391.66354) (xy 120.691439 -391.62368) (xy 120.728601 -391.58947)
			(xy 120.770887 -391.561844) (xy 120.817143 -391.541554) (xy 120.866108 -391.529154) (xy 120.916446 -391.524983)
			(xy 120.966784 -391.529154) (xy 121.015749 -391.541554) (xy 121.062005 -391.561844) (xy 121.104291 -391.58947)
			(xy 121.141453 -391.62368) (xy 121.172477 -391.66354) (xy 121.196518 -391.707963) (xy 121.212919 -391.755737)
			(xy 121.221232 -391.805559) (xy 121.221754 -391.830814) (xy 121.221256 -391.855184) (xy 121.213476 -391.9033)
			(xy 121.198164 -391.949573) (xy 121.175707 -391.992832) (xy 121.161556 -392.012678) (xy 121.155968 -392.020552)
			(xy 121.150888 -392.038332) (xy 121.15927 -392.124946) (xy 121.167398 -392.14171) (xy 121.17451 -392.14806)
			(xy 121.196488 -392.169063) (xy 121.23414 -392.216787) (xy 121.24944 -392.243056) (xy 121.254185 -392.250733)
			(xy 121.267935 -392.262405) (xy 121.284871 -392.268607) (xy 121.29389 -392.268964) (xy 121.739152 -392.268964)
			(xy 121.748184 -392.268658) (xy 121.765155 -392.262481) (xy 121.778909 -392.250777) (xy 121.783602 -392.243056)
			(xy 121.798925 -392.216802) (xy 121.836569 -392.169076) (xy 121.858532 -392.14806) (xy 121.865644 -392.14171)
			(xy 121.873772 -392.124946) (xy 121.882154 -392.038332) (xy 121.877074 -392.020552) (xy 121.871486 -392.012678)
			(xy 121.857327 -391.992834) (xy 121.834838 -391.949586) (xy 121.819519 -391.903311) (xy 121.811759 -391.855187)
			(xy 121.811288 -391.830814) (xy 121.81181 -391.805559) (xy 121.820123 -391.755737) (xy 121.836524 -391.707963)
			(xy 121.860565 -391.66354) (xy 121.891589 -391.62368) (xy 121.928751 -391.58947) (xy 121.971037 -391.561844)
			(xy 122.017293 -391.541554) (xy 122.066258 -391.529154) (xy 122.116596 -391.524983) (xy 122.166934 -391.529154)
			(xy 122.215899 -391.541554) (xy 122.262155 -391.561844) (xy 122.304441 -391.58947) (xy 122.341603 -391.62368)
			(xy 122.372627 -391.66354) (xy 122.396668 -391.707963) (xy 122.413069 -391.755737) (xy 122.421382 -391.805559)
			(xy 122.421904 -391.830814) (xy 122.421405 -391.855184) (xy 122.413625 -391.903299) (xy 122.398311 -391.949571)
			(xy 122.375851 -391.992828) (xy 122.361706 -392.012678) (xy 122.356118 -392.020552) (xy 122.351038 -392.038332)
			(xy 122.35942 -392.124946) (xy 122.367548 -392.14171) (xy 122.37466 -392.14806) (xy 122.396636 -392.169065)
			(xy 122.434283 -392.216791) (xy 122.44959 -392.243056) (xy 122.454333 -392.250738) (xy 122.468081 -392.262424)
			(xy 122.485018 -392.268642) (xy 122.49404 -392.268964) (xy 122.939048 -392.268964) (xy 122.948081 -392.268659)
			(xy 122.965052 -392.262483) (xy 122.978807 -392.250779) (xy 122.983498 -392.243056) (xy 122.998821 -392.216802)
			(xy 123.036464 -392.169075) (xy 123.058428 -392.14806) (xy 123.06554 -392.14171) (xy 123.073668 -392.124946)
			(xy 123.08205 -392.038332) (xy 123.07697 -392.020552) (xy 123.071382 -392.012678) (xy 123.057224 -391.992834)
			(xy 123.034735 -391.949586) (xy 123.019415 -391.90331) (xy 123.011656 -391.855187) (xy 123.011184 -391.830814)
			(xy 123.011706 -391.805559) (xy 123.020019 -391.755737) (xy 123.03642 -391.707963) (xy 123.060461 -391.66354)
			(xy 123.091485 -391.62368) (xy 123.128647 -391.58947) (xy 123.170933 -391.561844) (xy 123.217189 -391.541554)
			(xy 123.266154 -391.529154) (xy 123.316492 -391.524983) (xy 123.36683 -391.529154) (xy 123.415795 -391.541554)
			(xy 123.462051 -391.561844) (xy 123.504337 -391.58947) (xy 123.541499 -391.62368) (xy 123.572523 -391.66354)
			(xy 123.596564 -391.707963) (xy 123.612965 -391.755737) (xy 123.621278 -391.805559) (xy 123.6218 -391.830814)
			(xy 123.621301 -391.855184) (xy 123.613521 -391.903299) (xy 123.598206 -391.94957) (xy 123.575746 -391.992827)
			(xy 123.561602 -392.012678) (xy 123.556014 -392.020552) (xy 123.550934 -392.038332) (xy 123.559316 -392.124946)
			(xy 123.567444 -392.14171) (xy 123.574556 -392.14806) (xy 123.596532 -392.169065) (xy 123.63418 -392.216791)
			(xy 123.649486 -392.243056) (xy 123.654229 -392.250739) (xy 123.667976 -392.262425) (xy 123.684914 -392.268645)
			(xy 123.693936 -392.268964) (xy 124.139198 -392.268964) (xy 124.148226 -392.268651) (xy 124.165184 -392.262464)
			(xy 124.178925 -392.250757) (xy 124.183648 -392.243056) (xy 124.198921 -392.216877) (xy 124.236435 -392.169278)
			(xy 124.258324 -392.148314) (xy 124.265436 -392.14171) (xy 124.273818 -392.1252) (xy 124.281946 -392.038332)
			(xy 124.276866 -392.020552) (xy 124.271278 -392.012932) (xy 124.257115 -391.993054) (xy 124.234621 -391.94974)
			(xy 124.219299 -391.903402) (xy 124.211538 -391.855217) (xy 124.21108 -391.830814) (xy 124.211602 -391.805559)
			(xy 124.219915 -391.755737) (xy 124.236316 -391.707963) (xy 124.260357 -391.66354) (xy 124.291381 -391.62368)
			(xy 124.328543 -391.58947) (xy 124.370829 -391.561844) (xy 124.417085 -391.541554) (xy 124.46605 -391.529154)
			(xy 124.516388 -391.524983) (xy 124.566726 -391.529154) (xy 124.615691 -391.541554) (xy 124.661947 -391.561844)
			(xy 124.704233 -391.58947) (xy 124.741395 -391.62368) (xy 124.772419 -391.66354) (xy 124.79646 -391.707963)
			(xy 124.812861 -391.755737) (xy 124.821174 -391.805559) (xy 124.821696 -391.830814) (xy 124.821242 -391.855175)
			(xy 124.813539 -391.903285) (xy 124.798283 -391.949556) (xy 124.775862 -391.992813) (xy 124.761752 -392.012678)
			(xy 124.75591 -392.020298) (xy 124.751084 -392.038078) (xy 124.759212 -392.124946) (xy 124.767594 -392.141456)
			(xy 124.774706 -392.14806) (xy 124.796684 -392.169063) (xy 124.834336 -392.216787) (xy 124.849636 -392.243056)
			(xy 124.854381 -392.250733) (xy 124.868131 -392.262406) (xy 124.885067 -392.26861) (xy 124.894086 -392.268964)
			(xy 125.339094 -392.268964) (xy 125.348122 -392.268652) (xy 125.365082 -392.262465) (xy 125.378824 -392.250758)
			(xy 125.383544 -392.243056) (xy 125.398865 -392.216801) (xy 125.436505 -392.16907) (xy 125.458474 -392.14806)
			(xy 125.465586 -392.14171) (xy 125.473714 -392.124946) (xy 125.482096 -392.038332) (xy 125.477016 -392.020552)
			(xy 125.471428 -392.012678) (xy 125.457272 -391.992833) (xy 125.434787 -391.949584) (xy 125.41947 -391.903309)
			(xy 125.411712 -391.855186) (xy 125.41123 -391.830814) (xy 125.411752 -391.805559) (xy 125.420065 -391.755737)
			(xy 125.436466 -391.707963) (xy 125.460507 -391.66354) (xy 125.491531 -391.62368) (xy 125.528693 -391.58947)
			(xy 125.570979 -391.561844) (xy 125.617235 -391.541554) (xy 125.6662 -391.529154) (xy 125.716538 -391.524983)
			(xy 125.766876 -391.529154) (xy 125.815841 -391.541554) (xy 125.862097 -391.561844) (xy 125.904383 -391.58947)
			(xy 125.941545 -391.62368) (xy 125.972569 -391.66354) (xy 125.99661 -391.707963) (xy 126.013011 -391.755737)
			(xy 126.021324 -391.805559) (xy 126.021846 -391.830814) (xy 126.021348 -391.855184) (xy 126.013568 -391.9033)
			(xy 125.998256 -391.949572) (xy 125.975798 -391.992831) (xy 125.961648 -392.012678) (xy 125.95606 -392.020552)
			(xy 125.95098 -392.038332) (xy 125.959362 -392.124946) (xy 125.96749 -392.14171) (xy 125.974602 -392.14806)
			(xy 125.99658 -392.169063) (xy 126.034233 -392.216786) (xy 126.049532 -392.243056) (xy 126.054277 -392.250734)
			(xy 126.068026 -392.262408) (xy 126.084963 -392.268613) (xy 126.093982 -392.268964) (xy 126.539244 -392.268964)
			(xy 126.548277 -392.26866) (xy 126.56525 -392.262484) (xy 126.579006 -392.250781) (xy 126.583694 -392.243056)
			(xy 126.598968 -392.216878) (xy 126.636486 -392.169282) (xy 126.65837 -392.148314) (xy 126.665482 -392.14171)
			(xy 126.673864 -392.1252) (xy 126.681992 -392.038332) (xy 126.676912 -392.020552) (xy 126.671324 -392.012932)
			(xy 126.657163 -391.993053) (xy 126.634673 -391.949739) (xy 126.619354 -391.9034) (xy 126.611595 -391.855216)
			(xy 126.611126 -391.830814) (xy 126.611648 -391.805559) (xy 126.619961 -391.755737) (xy 126.636362 -391.707963)
			(xy 126.660403 -391.66354) (xy 126.691427 -391.62368) (xy 126.728589 -391.58947) (xy 126.770875 -391.561844)
			(xy 126.817131 -391.541554) (xy 126.866096 -391.529154) (xy 126.916434 -391.524983) (xy 126.966772 -391.529154)
			(xy 127.015737 -391.541554) (xy 127.061993 -391.561844) (xy 127.104279 -391.58947) (xy 127.141441 -391.62368)
			(xy 127.172465 -391.66354) (xy 127.196506 -391.707963) (xy 127.212907 -391.755737) (xy 127.22122 -391.805559)
			(xy 127.221742 -391.830814) (xy 127.221288 -391.855175) (xy 127.213583 -391.903284) (xy 127.198325 -391.949554)
			(xy 127.175901 -391.992809) (xy 127.161798 -392.012678) (xy 127.155956 -392.020298) (xy 127.15113 -392.038078)
			(xy 127.159258 -392.124946) (xy 127.16764 -392.141456) (xy 127.174752 -392.14806) (xy 127.196728 -392.169064)
			(xy 127.234376 -392.216791) (xy 127.249682 -392.243056) (xy 127.254425 -392.250739) (xy 127.268172 -392.262427)
			(xy 127.28511 -392.268647) (xy 127.294132 -392.268964) (xy 127.73914 -392.268964) (xy 127.748173 -392.26866)
			(xy 127.765147 -392.262486) (xy 127.778904 -392.250783) (xy 127.78359 -392.243056) (xy 127.798913 -392.216802)
			(xy 127.836556 -392.169075) (xy 127.85852 -392.14806) (xy 127.865632 -392.14171) (xy 127.87376 -392.124946)
			(xy 127.882142 -392.038332) (xy 127.877062 -392.020552) (xy 127.871474 -392.012678) (xy 127.857316 -391.992834)
			(xy 127.834828 -391.949586) (xy 127.819509 -391.90331) (xy 127.811749 -391.855187) (xy 127.811276 -391.830814)
			(xy 127.811798 -391.805559) (xy 127.820111 -391.755737) (xy 127.836512 -391.707963) (xy 127.860553 -391.66354)
			(xy 127.891577 -391.62368) (xy 127.928739 -391.58947) (xy 127.971025 -391.561844) (xy 128.017281 -391.541554)
			(xy 128.066246 -391.529154) (xy 128.116584 -391.524983) (xy 128.166922 -391.529154) (xy 128.215887 -391.541554)
			(xy 128.262143 -391.561844) (xy 128.304429 -391.58947) (xy 128.341591 -391.62368) (xy 128.372615 -391.66354)
			(xy 128.396656 -391.707963) (xy 128.413057 -391.755737) (xy 128.42137 -391.805559) (xy 128.421892 -391.830814)
			(xy 128.421393 -391.855184) (xy 128.413613 -391.903299) (xy 128.398298 -391.94957) (xy 128.375837 -391.992826)
			(xy 128.361694 -392.012678) (xy 128.356106 -392.020552) (xy 128.351026 -392.038332) (xy 128.359408 -392.124946)
			(xy 128.367536 -392.14171) (xy 128.374648 -392.14806) (xy 128.396624 -392.169064) (xy 128.434273 -392.21679)
			(xy 128.449578 -392.243056) (xy 128.45432 -392.25074) (xy 128.468068 -392.262428) (xy 128.485006 -392.26865)
			(xy 128.494028 -392.268964) (xy 128.939036 -392.268964) (xy 128.94807 -392.268661) (xy 128.965044 -392.262487)
			(xy 128.978803 -392.250785) (xy 128.983486 -392.243056) (xy 128.998809 -392.216802) (xy 129.036451 -392.169074)
			(xy 129.058416 -392.14806) (xy 129.065528 -392.14171) (xy 129.073656 -392.124946) (xy 129.082038 -392.038332)
			(xy 129.076958 -392.020552) (xy 129.07137 -392.012678) (xy 129.057212 -391.992834) (xy 129.034724 -391.949586)
			(xy 129.019405 -391.90331) (xy 129.011646 -391.855187) (xy 129.011172 -391.830814) (xy 129.011694 -391.805559)
			(xy 129.020007 -391.755737) (xy 129.036408 -391.707963) (xy 129.060449 -391.66354) (xy 129.091473 -391.62368)
			(xy 129.128635 -391.58947) (xy 129.170921 -391.561844) (xy 129.217177 -391.541554) (xy 129.266142 -391.529154)
			(xy 129.31648 -391.524983) (xy 129.366818 -391.529154) (xy 129.415783 -391.541554) (xy 129.462039 -391.561844)
			(xy 129.504325 -391.58947) (xy 129.541487 -391.62368) (xy 129.572511 -391.66354) (xy 129.596552 -391.707963)
			(xy 129.612953 -391.755737) (xy 129.621266 -391.805559) (xy 129.621788 -391.830814) (xy 129.621289 -391.855184)
			(xy 129.613508 -391.903298) (xy 129.598194 -391.94957) (xy 129.575733 -391.992826) (xy 129.56159 -392.012678)
			(xy 129.556002 -392.020552) (xy 129.550922 -392.038332) (xy 129.559304 -392.124946) (xy 129.567432 -392.14171)
			(xy 129.574544 -392.14806) (xy 129.596521 -392.169064) (xy 129.634169 -392.21679) (xy 129.649474 -392.243056)
			(xy 129.654216 -392.25074) (xy 129.667963 -392.26243) (xy 129.684901 -392.268653) (xy 129.693924 -392.268964)
			(xy 130.138932 -392.268964) (xy 130.147966 -392.268662) (xy 130.164942 -392.262489) (xy 130.178701 -392.250786)
			(xy 130.183382 -392.243056) (xy 130.198705 -392.216802) (xy 130.236347 -392.169074) (xy 130.258312 -392.14806)
			(xy 130.265424 -392.14171) (xy 130.273552 -392.124946) (xy 130.281934 -392.038332) (xy 130.276854 -392.020552)
			(xy 130.271266 -392.012678) (xy 130.257108 -391.992833) (xy 130.234621 -391.949585) (xy 130.219302 -391.90331)
			(xy 130.211543 -391.855186) (xy 130.211068 -391.830814) (xy 130.21159 -391.805559) (xy 130.219903 -391.755737)
			(xy 130.236304 -391.707963) (xy 130.260345 -391.66354) (xy 130.291369 -391.62368) (xy 130.328531 -391.58947)
			(xy 130.370817 -391.561844) (xy 130.417073 -391.541554) (xy 130.466038 -391.529154) (xy 130.516376 -391.524983)
			(xy 130.566714 -391.529154) (xy 130.615679 -391.541554) (xy 130.661935 -391.561844) (xy 130.704221 -391.58947)
			(xy 130.741383 -391.62368) (xy 130.772407 -391.66354) (xy 130.796448 -391.707963) (xy 130.812849 -391.755737)
			(xy 130.821162 -391.805559) (xy 130.821684 -391.830814) (xy 130.821186 -391.855184) (xy 130.813407 -391.9033)
			(xy 130.798096 -391.949574) (xy 130.775641 -391.992834) (xy 130.761486 -392.012678) (xy 130.755898 -392.020552)
			(xy 130.750818 -392.038332) (xy 130.7592 -392.124946) (xy 130.767328 -392.14171) (xy 130.77444 -392.14806)
			(xy 130.796417 -392.169064) (xy 130.834066 -392.21679) (xy 130.84937 -392.243056) (xy 130.854112 -392.250741)
			(xy 130.867859 -392.262432) (xy 130.884797 -392.268656) (xy 130.89382 -392.268964) (xy 131.339082 -392.268964)
			(xy 131.348111 -392.268654) (xy 131.365074 -392.26247) (xy 131.378819 -392.250764) (xy 131.383532 -392.243056)
			(xy 131.398853 -392.216801) (xy 131.436492 -392.169069) (xy 131.458462 -392.14806) (xy 131.465574 -392.14171)
			(xy 131.473702 -392.124946) (xy 131.482084 -392.038332) (xy 131.477004 -392.020552) (xy 131.471416 -392.012678)
			(xy 131.457256 -391.992834) (xy 131.434765 -391.949587) (xy 131.419444 -391.903311) (xy 131.411683 -391.855187)
			(xy 131.411218 -391.830814) (xy 131.41174 -391.805559) (xy 131.420053 -391.755737) (xy 131.436454 -391.707963)
			(xy 131.460495 -391.66354) (xy 131.491519 -391.62368) (xy 131.528681 -391.58947) (xy 131.570967 -391.561844)
			(xy 131.617223 -391.541554) (xy 131.666188 -391.529154) (xy 131.716526 -391.524983) (xy 131.766864 -391.529154)
			(xy 131.815829 -391.541554) (xy 131.862085 -391.561844) (xy 131.904371 -391.58947) (xy 131.941533 -391.62368)
			(xy 131.972557 -391.66354) (xy 131.996598 -391.707963) (xy 132.012999 -391.755737) (xy 132.021312 -391.805559)
			(xy 132.021834 -391.830814) (xy 132.021336 -391.855184) (xy 132.013556 -391.903299) (xy 131.998243 -391.949572)
			(xy 131.975785 -391.99283) (xy 131.961636 -392.012678) (xy 131.956048 -392.020552) (xy 131.950968 -392.038332)
			(xy 131.95935 -392.124946) (xy 131.967478 -392.14171) (xy 131.97459 -392.14806) (xy 131.996565 -392.169066)
			(xy 132.034209 -392.216794) (xy 132.04952 -392.243056) (xy 132.054264 -392.250735) (xy 132.068013 -392.262412)
			(xy 132.08495 -392.268621) (xy 132.09397 -392.268964) (xy 132.538978 -392.268964) (xy 132.548008 -392.268654)
			(xy 132.564971 -392.262471) (xy 132.578718 -392.250766) (xy 132.583428 -392.243056) (xy 132.598749 -392.2168)
			(xy 132.636387 -392.169069) (xy 132.658358 -392.14806) (xy 132.66547 -392.14171) (xy 132.673598 -392.124946)
			(xy 132.68198 -392.038332) (xy 132.6769 -392.020552) (xy 132.671312 -392.012678) (xy 132.657152 -391.992834)
			(xy 132.634661 -391.949587) (xy 132.61934 -391.903311) (xy 132.61158 -391.855187) (xy 132.611114 -391.830814)
			(xy 132.611636 -391.805559) (xy 132.619949 -391.755737) (xy 132.63635 -391.707963) (xy 132.660391 -391.66354)
			(xy 132.691415 -391.62368) (xy 132.728577 -391.58947) (xy 132.770863 -391.561844) (xy 132.817119 -391.541554)
			(xy 132.866084 -391.529154) (xy 132.916422 -391.524983) (xy 132.96676 -391.529154) (xy 133.015725 -391.541554)
			(xy 133.061981 -391.561844) (xy 133.104267 -391.58947) (xy 133.141429 -391.62368) (xy 133.172453 -391.66354)
			(xy 133.196494 -391.707963) (xy 133.212895 -391.755737) (xy 133.221208 -391.805559) (xy 133.22173 -391.830814)
			(xy 133.221232 -391.855184) (xy 133.213452 -391.903299) (xy 133.198138 -391.949572) (xy 133.17568 -391.99283)
			(xy 133.161532 -392.012678) (xy 133.155944 -392.020552) (xy 133.150864 -392.038332) (xy 133.159246 -392.124946)
			(xy 133.167374 -392.14171) (xy 133.174486 -392.14806) (xy 133.196461 -392.169066) (xy 133.234106 -392.216793)
			(xy 133.249416 -392.243056) (xy 133.25416 -392.250736) (xy 133.267909 -392.262414) (xy 133.284846 -392.268624)
			(xy 133.293866 -392.268964) (xy 134.492492 -392.268964) (xy 134.502562 -392.268542) (xy 134.521165 -392.260825)
			(xy 134.52856 -392.253978) (xy 135.223758 -391.55878) (xy 135.230606 -391.551382) (xy 135.23834 -391.532784)
			(xy 135.238744 -391.522712) (xy 135.238744 -390.70788) (xy 135.238322 -390.698178) (xy 135.231154 -390.680147)
			(xy 135.224774 -390.672828) (xy 135.203946 -390.650984) (xy 135.197493 -390.644712) (xy 135.181357 -390.636771)
			(xy 135.17245 -390.63549) (xy 135.145682 -390.632166) (xy 135.093653 -390.617947) (xy 135.044621 -390.595472)
			(xy 134.999887 -390.565337) (xy 134.960637 -390.528342) (xy 134.927911 -390.485467) (xy 134.902578 -390.43785)
			(xy 134.885309 -390.386752) (xy 134.876561 -390.333529) (xy 134.876032 -390.30656) (xy 134.876439 -390.28372)
			(xy 134.882764 -390.238478) (xy 134.895247 -390.194535) (xy 134.913652 -390.152725) (xy 134.925308 -390.133078)
			(xy 134.929806 -390.124884) (xy 134.933208 -390.10652) (xy 134.931912 -390.097264) (xy 134.926324 -390.066276)
			(xy 134.924221 -390.05712) (xy 134.914457 -390.041088) (xy 134.907274 -390.035034) (xy 134.88761 -390.01927)
			(xy 134.852836 -389.982795) (xy 134.823996 -389.941467) (xy 134.801758 -389.896243) (xy 134.786638 -389.848169)
			(xy 134.778985 -389.798358) (xy 134.778496 -389.77316) (xy 134.778974 -389.747931) (xy 134.786643 -389.698059)
			(xy 134.801797 -389.64993) (xy 134.824084 -389.604661) (xy 134.852987 -389.563302) (xy 134.887836 -389.526811)
			(xy 134.907528 -389.511032) (xy 134.91845 -389.50265) (xy 134.92861 -389.477758) (xy 134.91337 -389.363204)
			(xy 134.897114 -389.341868) (xy 134.88416 -389.336788) (xy 134.861788 -389.327063) (xy 134.819935 -389.302001)
			(xy 134.782214 -389.271069) (xy 134.749441 -389.234936) (xy 134.722325 -389.194385) (xy 134.701455 -389.150293)
			(xy 134.687281 -389.103615) (xy 134.680111 -389.055363) (xy 134.67969 -389.030972) (xy 134.680167 -389.005347)
			(xy 134.688066 -388.954711) (xy 134.703687 -388.9059) (xy 134.726656 -388.860086) (xy 134.75642 -388.818366)
			(xy 134.792268 -388.78174) (xy 134.812532 -388.76605) (xy 134.823454 -388.757922) (xy 134.834122 -388.73303)
			(xy 134.821422 -388.618984) (xy 134.80542 -388.59714) (xy 134.792974 -388.591552) (xy 134.768254 -388.58002)
			(xy 134.722658 -388.550084) (xy 134.682597 -388.513066) (xy 134.64916 -388.469972) (xy 134.623254 -388.421972)
			(xy 134.605583 -388.370369) (xy 134.596627 -388.316564) (xy 134.596124 -388.289292) (xy 134.596608 -388.263304)
			(xy 134.60474 -388.211968) (xy 134.620804 -388.162537) (xy 134.644402 -388.116227) (xy 134.674955 -388.074179)
			(xy 134.71171 -388.037429) (xy 134.753761 -388.006881) (xy 134.800074 -387.983288) (xy 134.849507 -387.967231)
			(xy 134.900844 -387.959105) (xy 134.926832 -387.958584) (xy 134.951774 -387.959042) (xy 135.00109 -387.966545)
			(xy 135.048717 -387.981376) (xy 135.093574 -388.003199) (xy 135.134641 -388.031516) (xy 135.153146 -388.048246)
			(xy 135.160258 -388.05485) (xy 135.178292 -388.061962) (xy 135.187944 -388.061962) (xy 135.197943 -388.061466)
			(xy 135.216413 -388.053797) (xy 135.230543 -388.039644) (xy 135.238182 -388.021162) (xy 135.238744 -388.011162)
			(xy 135.238744 -387.9723) (xy 135.238205 -387.962314) (xy 135.230485 -387.943887) (xy 135.223758 -387.936486)
			(xy 133.965188 -386.677662) (xy 133.924294 -386.6769) (xy 133.909054 -386.691124) (xy 133.890596 -386.707692)
			(xy 133.849648 -386.735676) (xy 133.80498 -386.757235) (xy 133.757596 -386.771884) (xy 133.708555 -386.779296)
			(xy 133.683756 -386.77977) (xy 133.657772 -386.779257) (xy 133.606445 -386.77112) (xy 133.557023 -386.755055)
			(xy 133.510723 -386.731456) (xy 133.468684 -386.700905) (xy 133.431942 -386.664154) (xy 133.401401 -386.622107)
			(xy 133.377814 -386.575801) (xy 133.36176 -386.526375) (xy 133.353637 -386.475046) (xy 133.353048 -386.449062)
			(xy 133.353302 -386.437378) (xy 133.353556 -386.427472) (xy 133.347206 -386.409438) (xy 133.288024 -386.342382)
			(xy 133.270752 -386.333492) (xy 133.2611 -386.33273) (xy 133.236904 -386.330089) (xy 133.189605 -386.318606)
			(xy 133.144503 -386.300308) (xy 133.102574 -386.275591) (xy 133.064725 -386.24499) (xy 133.031774 -386.209168)
			(xy 133.004436 -386.168899) (xy 132.983301 -386.125054) (xy 132.968828 -386.078584) (xy 132.964682 -386.0546)
			(xy 132.963158 -386.045202) (xy 132.690362 -385.57327) (xy 132.682996 -385.567428) (xy 132.664219 -385.551623)
			(xy 132.63109 -385.515415) (xy 132.603673 -385.47471) (xy 132.582571 -385.430401) (xy 132.568246 -385.38346)
			(xy 132.561014 -385.334919) (xy 132.560568 -385.31038) (xy 132.561079 -385.284393) (xy 132.569212 -385.23306)
			(xy 132.585274 -385.18363) (xy 132.608871 -385.137322) (xy 132.639421 -385.095274) (xy 132.676171 -385.058523)
			(xy 132.718218 -385.027973) (xy 132.764527 -385.004376) (xy 132.813956 -384.988313) (xy 132.865289 -384.980179)
			(xy 132.891276 -384.979672) (xy 132.917288 -384.980155) (xy 132.96867 -384.988299) (xy 133.018144 -385.004389)
			(xy 133.064486 -385.028028) (xy 133.106555 -385.058633) (xy 133.143312 -385.095449) (xy 133.17385 -385.137567)
			(xy 133.197415 -385.183948) (xy 133.213425 -385.233447) (xy 133.21792 -385.259072) (xy 133.219444 -385.26847)
			(xy 133.49224 -385.740402) (xy 133.499606 -385.746244) (xy 133.518384 -385.762048) (xy 133.551516 -385.798256)
			(xy 133.578936 -385.838961) (xy 133.600042 -385.883269) (xy 133.61437 -385.93021) (xy 133.621607 -385.978752)
			(xy 133.622034 -386.003292) (xy 133.620256 -386.037836) (xy 133.61967 -386.048377) (xy 133.626102 -386.068459)
			(xy 133.632702 -386.076698) (xy 133.669532 -386.118608) (xy 133.680962 -386.118354) (xy 133.716776 -386.08254)
			(xy 133.723469 -386.075134) (xy 133.731069 -386.056697) (xy 133.731508 -386.046726) (xy 133.731508 -385.03479)
			(xy 133.732069 -385.006227) (xy 133.741004 -384.949805) (xy 133.758653 -384.895475) (xy 133.784581 -384.844573)
			(xy 133.818151 -384.798352) (xy 133.837934 -384.777742) (xy 134.298182 -384.317494) (xy 134.318785 -384.297704)
			(xy 134.365013 -384.264146) (xy 134.415917 -384.238226) (xy 134.470248 -384.220579) (xy 134.526668 -384.211641)
			(xy 134.55523 -384.211068) (xy 134.874254 -384.211068) (xy 134.896576 -384.211346) (xy 134.940898 -384.216697)
			(xy 134.962646 -384.221736) (xy 134.975346 -384.225038) (xy 135.000238 -384.218434) (xy 135.081518 -384.142234)
			(xy 135.089646 -384.11785) (xy 135.08736 -384.104896) (xy 135.084405 -384.087841) (xy 135.081224 -384.05337)
			(xy 135.08101 -384.036062) (xy 135.081504 -384.007989) (xy 135.089726 -383.952449) (xy 135.106003 -383.898715)
			(xy 135.129981 -383.847947) (xy 135.161143 -383.801244) (xy 135.198816 -383.759613) (xy 135.220202 -383.741422)
			(xy 135.228556 -383.733795) (xy 135.238163 -383.713351) (xy 135.238744 -383.702052) (xy 135.238744 -382.921256)
			(xy 135.238311 -382.911191) (xy 135.230579 -382.892603) (xy 135.223758 -382.885188) (xy 134.818628 -382.480058)
			(xy 134.811229 -382.473216) (xy 134.79263 -382.465499) (xy 134.78256 -382.465072) (xy 133.240272 -382.465072)
			(xy 133.230525 -382.465503) (xy 133.212444 -382.472787) (xy 133.198414 -382.486321) (xy 133.194044 -382.495044)
			(xy 133.149848 -382.593088) (xy 133.154166 -382.622552) (xy 133.164326 -382.633982) (xy 133.179842 -382.652213)
			(xy 133.206007 -382.692301) (xy 133.226126 -382.73574) (xy 133.23978 -382.781623) (xy 133.246684 -382.828994)
			(xy 133.24713 -382.85293) (xy 133.24662 -382.878917) (xy 133.23849 -382.930252) (xy 133.222429 -382.979682)
			(xy 133.198833 -383.025992) (xy 133.168283 -383.06804) (xy 133.131532 -383.104791) (xy 133.089484 -383.135341)
			(xy 133.043174 -383.158937) (xy 132.993744 -383.174998) (xy 132.942409 -383.183128) (xy 132.890435 -383.183128)
			(xy 132.8391 -383.174998) (xy 132.78967 -383.158937) (xy 132.74336 -383.135341) (xy 132.701312 -383.104791)
			(xy 132.664561 -383.06804) (xy 132.634011 -383.025992) (xy 132.610415 -382.979682) (xy 132.594354 -382.930252)
			(xy 132.586224 -382.878917) (xy 132.585714 -382.85293) (xy 132.586135 -382.828992) (xy 132.593033 -382.781617)
			(xy 132.606688 -382.73573) (xy 132.626815 -382.692292) (xy 132.652994 -382.652208) (xy 132.668518 -382.633982)
			(xy 132.678678 -382.622552) (xy 132.682996 -382.593088) (xy 132.6388 -382.495044) (xy 132.634394 -382.486351)
			(xy 132.620352 -382.472857) (xy 132.602307 -382.465536) (xy 132.592572 -382.465072) (xy 132.040376 -382.465072)
			(xy 132.030628 -382.465502) (xy 132.012546 -382.472786) (xy 131.998515 -382.486319) (xy 131.994148 -382.495044)
			(xy 131.949952 -382.593088) (xy 131.95427 -382.622552) (xy 131.96443 -382.633982) (xy 131.979946 -382.652213)
			(xy 132.006111 -382.692301) (xy 132.02623 -382.73574) (xy 132.039883 -382.781623) (xy 132.046787 -382.828994)
			(xy 132.047234 -382.85293) (xy 132.046724 -382.878917) (xy 132.038594 -382.930252) (xy 132.022533 -382.979682)
			(xy 131.998937 -383.025992) (xy 131.968387 -383.06804) (xy 131.931636 -383.104791) (xy 131.889588 -383.135341)
			(xy 131.843278 -383.158937) (xy 131.793848 -383.174998) (xy 131.742513 -383.183128) (xy 131.690539 -383.183128)
			(xy 131.639204 -383.174998) (xy 131.589774 -383.158937) (xy 131.543464 -383.135341) (xy 131.501416 -383.104791)
			(xy 131.464665 -383.06804) (xy 131.434115 -383.025992) (xy 131.410519 -382.979682) (xy 131.394458 -382.930252)
			(xy 131.386328 -382.878917) (xy 131.385818 -382.85293) (xy 131.386239 -382.828992) (xy 131.393137 -382.781617)
			(xy 131.406792 -382.735731) (xy 131.42692 -382.692292) (xy 131.453099 -382.652209) (xy 131.468622 -382.633982)
			(xy 131.478782 -382.622552) (xy 131.4831 -382.593088) (xy 131.438904 -382.495044) (xy 131.434498 -382.48635)
			(xy 131.420457 -382.472855) (xy 131.402411 -382.465533) (xy 131.392676 -382.465072) (xy 130.840226 -382.465072)
			(xy 130.830473 -382.465493) (xy 130.812376 -382.472766) (xy 130.79833 -382.486298) (xy 130.793998 -382.495044)
			(xy 130.749802 -382.593088) (xy 130.75412 -382.622552) (xy 130.76428 -382.633982) (xy 130.779798 -382.652212)
			(xy 130.805967 -382.692299) (xy 130.826089 -382.735738) (xy 130.839744 -382.781622) (xy 130.846649 -382.828994)
			(xy 130.847084 -382.85293) (xy 130.846574 -382.878917) (xy 130.838444 -382.930252) (xy 130.822383 -382.979682)
			(xy 130.798787 -383.025992) (xy 130.768237 -383.06804) (xy 130.731486 -383.104791) (xy 130.689438 -383.135341)
			(xy 130.643128 -383.158937) (xy 130.593698 -383.174998) (xy 130.542363 -383.183128) (xy 130.490389 -383.183128)
			(xy 130.439054 -383.174998) (xy 130.389624 -383.158937) (xy 130.343314 -383.135341) (xy 130.301266 -383.104791)
			(xy 130.264515 -383.06804) (xy 130.233965 -383.025992) (xy 130.210369 -382.979682) (xy 130.194308 -382.930252)
			(xy 130.186178 -382.878917) (xy 130.185668 -382.85293) (xy 130.186089 -382.828992) (xy 130.192986 -382.781616)
			(xy 130.206639 -382.735728) (xy 130.226765 -382.692288) (xy 130.252941 -382.652202) (xy 130.268472 -382.633982)
			(xy 130.278632 -382.622552) (xy 130.28295 -382.593088) (xy 130.238754 -382.495044) (xy 130.234345 -382.486356)
			(xy 130.220302 -382.472875) (xy 130.202257 -382.465569) (xy 130.192526 -382.465072) (xy 129.64033 -382.465072)
			(xy 129.630577 -382.465493) (xy 129.612478 -382.472765) (xy 129.598431 -382.486296) (xy 129.594102 -382.495044)
			(xy 129.549906 -382.593088) (xy 129.554224 -382.622552) (xy 129.564384 -382.633982) (xy 129.579902 -382.652212)
			(xy 129.60607 -382.692299) (xy 129.626192 -382.735738) (xy 129.639848 -382.781622) (xy 129.646752 -382.828994)
			(xy 129.647188 -382.85293) (xy 129.646678 -382.878917) (xy 129.638548 -382.930252) (xy 129.622487 -382.979682)
			(xy 129.598891 -383.025992) (xy 129.568341 -383.06804) (xy 129.53159 -383.104791) (xy 129.489542 -383.135341)
			(xy 129.443232 -383.158937) (xy 129.393802 -383.174998) (xy 129.342467 -383.183128) (xy 129.290493 -383.183128)
			(xy 129.239158 -383.174998) (xy 129.189728 -383.158937) (xy 129.143418 -383.135341) (xy 129.10137 -383.104791)
			(xy 129.064619 -383.06804) (xy 129.034069 -383.025992) (xy 129.010473 -382.979682) (xy 128.994412 -382.930252)
			(xy 128.986282 -382.878917) (xy 128.985772 -382.85293) (xy 128.986193 -382.828992) (xy 128.99309 -382.781616)
			(xy 129.006744 -382.735729) (xy 129.026869 -382.692288) (xy 129.053046 -382.652203) (xy 129.068576 -382.633982)
			(xy 129.078736 -382.622552) (xy 129.083054 -382.593088) (xy 129.038858 -382.495044) (xy 129.034449 -382.486355)
			(xy 129.020406 -382.472873) (xy 129.002362 -382.465566) (xy 128.99263 -382.465072) (xy 128.440434 -382.465072)
			(xy 128.43068 -382.465492) (xy 128.412581 -382.472763) (xy 128.398532 -382.486295) (xy 128.394206 -382.495044)
			(xy 128.35001 -382.593088) (xy 128.354328 -382.622552) (xy 128.364488 -382.633982) (xy 128.380006 -382.652212)
			(xy 128.406174 -382.6923) (xy 128.426295 -382.735738) (xy 128.439951 -382.781622) (xy 128.446855 -382.828994)
			(xy 128.447292 -382.85293) (xy 128.446782 -382.878917) (xy 128.438652 -382.930252) (xy 128.422591 -382.979682)
			(xy 128.398995 -383.025992) (xy 128.368445 -383.06804) (xy 128.331694 -383.104791) (xy 128.289646 -383.135341)
			(xy 128.243336 -383.158937) (xy 128.193906 -383.174998) (xy 128.142571 -383.183128) (xy 128.090597 -383.183128)
			(xy 128.039262 -383.174998) (xy 127.989832 -383.158937) (xy 127.943522 -383.135341) (xy 127.901474 -383.104791)
			(xy 127.864723 -383.06804) (xy 127.834173 -383.025992) (xy 127.810577 -382.979682) (xy 127.794516 -382.930252)
			(xy 127.786386 -382.878917) (xy 127.785876 -382.85293) (xy 127.786297 -382.828992) (xy 127.793194 -382.781616)
			(xy 127.806848 -382.735729) (xy 127.826973 -382.692289) (xy 127.85315 -382.652203) (xy 127.86868 -382.633982)
			(xy 127.87884 -382.622552) (xy 127.883158 -382.593088) (xy 127.838962 -382.495044) (xy 127.834554 -382.486355)
			(xy 127.82051 -382.472872) (xy 127.802466 -382.465563) (xy 127.792734 -382.465072) (xy 127.240284 -382.465072)
			(xy 127.230535 -382.465501) (xy 127.212451 -382.472783) (xy 127.198417 -382.486316) (xy 127.194056 -382.495044)
			(xy 127.14986 -382.593088) (xy 127.154178 -382.622552) (xy 127.164338 -382.633982) (xy 127.179854 -382.652213)
			(xy 127.206018 -382.692302) (xy 127.226136 -382.73574) (xy 127.239789 -382.781623) (xy 127.246693 -382.828994)
			(xy 127.247142 -382.85293) (xy 127.246632 -382.878917) (xy 127.238502 -382.930252) (xy 127.222441 -382.979682)
			(xy 127.198845 -383.025992) (xy 127.168295 -383.06804) (xy 127.131544 -383.104791) (xy 127.089496 -383.135341)
			(xy 127.043186 -383.158937) (xy 126.993756 -383.174998) (xy 126.942421 -383.183128) (xy 126.890447 -383.183128)
			(xy 126.839112 -383.174998) (xy 126.789682 -383.158937) (xy 126.743372 -383.135341) (xy 126.701324 -383.104791)
			(xy 126.664573 -383.06804) (xy 126.634023 -383.025992) (xy 126.610427 -382.979682) (xy 126.594366 -382.930252)
			(xy 126.586236 -382.878917) (xy 126.585726 -382.85293) (xy 126.586147 -382.828992) (xy 126.593045 -382.781617)
			(xy 126.6067 -382.735731) (xy 126.626828 -382.692293) (xy 126.653008 -382.65221) (xy 126.66853 -382.633982)
			(xy 126.67869 -382.622552) (xy 126.683008 -382.593088) (xy 126.638812 -382.495044) (xy 126.634406 -382.486349)
			(xy 126.620365 -382.472852) (xy 126.60232 -382.465527) (xy 126.592584 -382.465072) (xy 126.040388 -382.465072)
			(xy 126.030639 -382.4655) (xy 126.012553 -382.472781) (xy 125.998519 -382.486314) (xy 125.99416 -382.495044)
			(xy 125.949964 -382.593088) (xy 125.954282 -382.622552) (xy 125.964442 -382.633982) (xy 125.979957 -382.652213)
			(xy 126.006121 -382.692302) (xy 126.026239 -382.735741) (xy 126.039893 -382.781624) (xy 126.046796 -382.828994)
			(xy 126.047246 -382.85293) (xy 126.046736 -382.878917) (xy 126.038606 -382.930252) (xy 126.022545 -382.979682)
			(xy 125.998949 -383.025992) (xy 125.968399 -383.06804) (xy 125.931648 -383.104791) (xy 125.8896 -383.135341)
			(xy 125.84329 -383.158937) (xy 125.79386 -383.174998) (xy 125.742525 -383.183128) (xy 125.690551 -383.183128)
			(xy 125.639216 -383.174998) (xy 125.589786 -383.158937) (xy 125.543476 -383.135341) (xy 125.501428 -383.104791)
			(xy 125.464677 -383.06804) (xy 125.434127 -383.025992) (xy 125.410531 -382.979682) (xy 125.39447 -382.930252)
			(xy 125.38634 -382.878917) (xy 125.38583 -382.85293) (xy 125.386251 -382.828993) (xy 125.393149 -382.781617)
			(xy 125.406805 -382.735731) (xy 125.426933 -382.692293) (xy 125.453113 -382.652211) (xy 125.468634 -382.633982)
			(xy 125.478794 -382.622552) (xy 125.483112 -382.593088) (xy 125.438916 -382.495044) (xy 125.434506 -382.48636)
			(xy 125.42046 -382.472889) (xy 125.402417 -382.465596) (xy 125.392688 -382.465072) (xy 124.840238 -382.465072)
			(xy 124.830484 -382.465491) (xy 124.812383 -382.472762) (xy 124.798333 -382.486293) (xy 124.79401 -382.495044)
			(xy 124.749814 -382.593088) (xy 124.754132 -382.622552) (xy 124.764292 -382.633982) (xy 124.77981 -382.652212)
			(xy 124.805977 -382.6923) (xy 124.826098 -382.735738) (xy 124.839754 -382.781622) (xy 124.846659 -382.828994)
			(xy 124.847096 -382.85293) (xy 124.846586 -382.878917) (xy 124.838456 -382.930252) (xy 124.822395 -382.979682)
			(xy 124.798799 -383.025992) (xy 124.768249 -383.06804) (xy 124.731498 -383.104791) (xy 124.68945 -383.135341)
			(xy 124.64314 -383.158937) (xy 124.59371 -383.174998) (xy 124.542375 -383.183128) (xy 124.490401 -383.183128)
			(xy 124.439066 -383.174998) (xy 124.389636 -383.158937) (xy 124.343326 -383.135341) (xy 124.301278 -383.104791)
			(xy 124.264527 -383.06804) (xy 124.233977 -383.025992) (xy 124.210381 -382.979682) (xy 124.19432 -382.930252)
			(xy 124.18619 -382.878917) (xy 124.18568 -382.85293) (xy 124.186101 -382.828992) (xy 124.192998 -382.781616)
			(xy 124.206652 -382.735729) (xy 124.226778 -382.692289) (xy 124.252955 -382.652204) (xy 124.268484 -382.633982)
			(xy 124.278644 -382.622552) (xy 124.282962 -382.593088) (xy 124.238766 -382.495044) (xy 124.234358 -382.486354)
			(xy 124.220315 -382.47287) (xy 124.20227 -382.46556) (xy 124.192538 -382.465072) (xy 123.640342 -382.465072)
			(xy 123.630598 -382.465508) (xy 123.612526 -382.472799) (xy 123.598505 -382.486333) (xy 123.594114 -382.495044)
			(xy 123.549918 -382.593088) (xy 123.554236 -382.622552) (xy 123.564396 -382.633982) (xy 123.579913 -382.652212)
			(xy 123.606081 -382.6923) (xy 123.626202 -382.735738) (xy 123.639857 -382.781622) (xy 123.646762 -382.828994)
			(xy 123.6472 -382.85293) (xy 123.64669 -382.878917) (xy 123.63856 -382.930252) (xy 123.622499 -382.979682)
			(xy 123.598903 -383.025992) (xy 123.568353 -383.06804) (xy 123.531602 -383.104791) (xy 123.489554 -383.135341)
			(xy 123.443244 -383.158937) (xy 123.393814 -383.174998) (xy 123.342479 -383.183128) (xy 123.290505 -383.183128)
			(xy 123.23917 -383.174998) (xy 123.18974 -383.158937) (xy 123.14343 -383.135341) (xy 123.101382 -383.104791)
			(xy 123.064631 -383.06804) (xy 123.034081 -383.025992) (xy 123.010485 -382.979682) (xy 122.994424 -382.930252)
			(xy 122.986294 -382.878917) (xy 122.985784 -382.85293) (xy 122.986205 -382.828992) (xy 122.993102 -382.781616)
			(xy 123.006756 -382.735729) (xy 123.026882 -382.692289) (xy 123.05306 -382.652204) (xy 123.068588 -382.633982)
			(xy 123.078748 -382.622552) (xy 123.083066 -382.593088) (xy 123.03887 -382.495044) (xy 123.034462 -382.486354)
			(xy 123.020419 -382.472869) (xy 123.002375 -382.465558) (xy 122.992642 -382.465072) (xy 122.440446 -382.465072)
			(xy 122.430702 -382.465507) (xy 122.412628 -382.472797) (xy 122.398606 -382.486332) (xy 122.394218 -382.495044)
			(xy 122.350022 -382.593088) (xy 122.35434 -382.622552) (xy 122.3645 -382.633982) (xy 122.380017 -382.652212)
			(xy 122.406184 -382.6923) (xy 122.426305 -382.735739) (xy 122.43996 -382.781622) (xy 122.446865 -382.828994)
			(xy 122.447304 -382.85293) (xy 122.446794 -382.878917) (xy 122.438664 -382.930252) (xy 122.422603 -382.979682)
			(xy 122.399007 -383.025992) (xy 122.368457 -383.06804) (xy 122.331706 -383.104791) (xy 122.289658 -383.135341)
			(xy 122.243348 -383.158937) (xy 122.193918 -383.174998) (xy 122.142583 -383.183128) (xy 122.090609 -383.183128)
			(xy 122.039274 -383.174998) (xy 121.989844 -383.158937) (xy 121.943534 -383.135341) (xy 121.901486 -383.104791)
			(xy 121.864735 -383.06804) (xy 121.834185 -383.025992) (xy 121.810589 -382.979682) (xy 121.794528 -382.930252)
			(xy 121.786398 -382.878917) (xy 121.785888 -382.85293) (xy 121.786309 -382.828992) (xy 121.793206 -382.781616)
			(xy 121.80686 -382.735729) (xy 121.826987 -382.69229) (xy 121.853164 -382.652205) (xy 121.868692 -382.633982)
			(xy 121.878852 -382.622552) (xy 121.88317 -382.593088) (xy 121.838974 -382.495044) (xy 121.834566 -382.486353)
			(xy 121.820524 -382.472867) (xy 121.802479 -382.465554) (xy 121.792746 -382.465072) (xy 121.240296 -382.465072)
			(xy 121.230546 -382.465499) (xy 121.212458 -382.472778) (xy 121.198421 -382.486311) (xy 121.194068 -382.495044)
			(xy 121.149872 -382.593088) (xy 121.15419 -382.622552) (xy 121.16435 -382.633982) (xy 121.179865 -382.652213)
			(xy 121.206028 -382.692302) (xy 121.226146 -382.735741) (xy 121.239799 -382.781624) (xy 121.246702 -382.828995)
			(xy 121.247154 -382.85293) (xy 121.246644 -382.878917) (xy 121.238514 -382.930252) (xy 121.222453 -382.979682)
			(xy 121.198857 -383.025992) (xy 121.168307 -383.06804) (xy 121.131556 -383.104791) (xy 121.089508 -383.135341)
			(xy 121.043198 -383.158937) (xy 120.993768 -383.174998) (xy 120.942433 -383.183128) (xy 120.890459 -383.183128)
			(xy 120.839124 -383.174998) (xy 120.789694 -383.158937) (xy 120.743384 -383.135341) (xy 120.701336 -383.104791)
			(xy 120.664585 -383.06804) (xy 120.634035 -383.025992) (xy 120.610439 -382.979682) (xy 120.594378 -382.930252)
			(xy 120.586248 -382.878917) (xy 120.585738 -382.85293) (xy 120.586159 -382.828993) (xy 120.593057 -382.781617)
			(xy 120.606713 -382.735731) (xy 120.626842 -382.692294) (xy 120.653022 -382.652212) (xy 120.668542 -382.633982)
			(xy 120.678702 -382.622552) (xy 120.68302 -382.593088) (xy 120.638824 -382.495044) (xy 120.634414 -382.486359)
			(xy 120.620369 -382.472886) (xy 120.602325 -382.465591) (xy 120.592596 -382.465072) (xy 120.0404 -382.465072)
			(xy 120.03065 -382.465498) (xy 120.01256 -382.472776) (xy 119.998522 -382.486309) (xy 119.994172 -382.495044)
			(xy 119.949976 -382.593088) (xy 119.954294 -382.622552) (xy 119.964454 -382.633982) (xy 119.979969 -382.652213)
			(xy 120.006132 -382.692302) (xy 120.026249 -382.735741) (xy 120.039902 -382.781624) (xy 120.046805 -382.828995)
			(xy 120.047258 -382.85293) (xy 120.046748 -382.878917) (xy 120.038618 -382.930252) (xy 120.022557 -382.979682)
			(xy 119.998961 -383.025992) (xy 119.968411 -383.06804) (xy 119.93166 -383.104791) (xy 119.889612 -383.135341)
			(xy 119.843302 -383.158937) (xy 119.793872 -383.174998) (xy 119.742537 -383.183128) (xy 119.690563 -383.183128)
			(xy 119.639228 -383.174998) (xy 119.589798 -383.158937) (xy 119.543488 -383.135341) (xy 119.50144 -383.104791)
			(xy 119.464689 -383.06804) (xy 119.434139 -383.025992) (xy 119.410543 -382.979682) (xy 119.394482 -382.930252)
			(xy 119.386352 -382.878917) (xy 119.385842 -382.85293) (xy 119.386263 -382.828993) (xy 119.393161 -382.781617)
			(xy 119.406817 -382.735732) (xy 119.426946 -382.692294) (xy 119.453127 -382.652212) (xy 119.468646 -382.633982)
			(xy 119.478806 -382.622552) (xy 119.483124 -382.593088) (xy 119.438928 -382.495044) (xy 119.434518 -382.486358)
			(xy 119.420473 -382.472884) (xy 119.40243 -382.465588) (xy 119.3927 -382.465072) (xy 118.84025 -382.465072)
			(xy 118.830505 -382.465507) (xy 118.812431 -382.472796) (xy 118.798408 -382.48633) (xy 118.794022 -382.495044)
			(xy 118.749826 -382.593088) (xy 118.754144 -382.622552) (xy 118.764304 -382.633982) (xy 118.779821 -382.652212)
			(xy 118.805988 -382.6923) (xy 118.826108 -382.735739) (xy 118.839763 -382.781622) (xy 118.846668 -382.828994)
			(xy 118.847108 -382.85293) (xy 118.846598 -382.878917) (xy 118.838468 -382.930252) (xy 118.822407 -382.979682)
			(xy 118.798811 -383.025992) (xy 118.768261 -383.06804) (xy 118.73151 -383.104791) (xy 118.689462 -383.135341)
			(xy 118.643152 -383.158937) (xy 118.593722 -383.174998) (xy 118.542387 -383.183128) (xy 118.490413 -383.183128)
			(xy 118.439078 -383.174998) (xy 118.389648 -383.158937) (xy 118.343338 -383.135341) (xy 118.30129 -383.104791)
			(xy 118.264539 -383.06804) (xy 118.233989 -383.025992) (xy 118.210393 -382.979682) (xy 118.194332 -382.930252)
			(xy 118.186202 -382.878917) (xy 118.185692 -382.85293) (xy 118.186113 -382.828992) (xy 118.19301 -382.781616)
			(xy 118.206665 -382.735729) (xy 118.226791 -382.69229) (xy 118.252969 -382.652206) (xy 118.268496 -382.633982)
			(xy 118.278656 -382.622552) (xy 118.282974 -382.593088) (xy 118.238778 -382.495044) (xy 118.234371 -382.486353)
			(xy 118.220328 -382.472865) (xy 118.202283 -382.465551) (xy 118.19255 -382.465072) (xy 117.640354 -382.465072)
			(xy 117.630609 -382.465506) (xy 117.612533 -382.472794) (xy 117.598509 -382.486328) (xy 117.594126 -382.495044)
			(xy 117.54993 -382.593088) (xy 117.554248 -382.622552) (xy 117.564408 -382.633982) (xy 117.579925 -382.652212)
			(xy 117.606091 -382.6923) (xy 117.626212 -382.735739) (xy 117.639866 -382.781622) (xy 117.646771 -382.828994)
			(xy 117.647212 -382.85293) (xy 117.646702 -382.878917) (xy 117.638572 -382.930252) (xy 117.622511 -382.979682)
			(xy 117.598915 -383.025992) (xy 117.568365 -383.06804) (xy 117.531614 -383.104791) (xy 117.489566 -383.135341)
			(xy 117.443256 -383.158937) (xy 117.393826 -383.174998) (xy 117.342491 -383.183128) (xy 117.290517 -383.183128)
			(xy 117.239182 -383.174998) (xy 117.189752 -383.158937) (xy 117.143442 -383.135341) (xy 117.101394 -383.104791)
			(xy 117.064643 -383.06804) (xy 117.034093 -383.025992) (xy 117.010497 -382.979682) (xy 116.994436 -382.930252)
			(xy 116.986306 -382.878917) (xy 116.985796 -382.85293) (xy 116.986217 -382.828992) (xy 116.993114 -382.781616)
			(xy 117.006769 -382.73573) (xy 117.026895 -382.69229) (xy 117.053074 -382.652206) (xy 117.0686 -382.633982)
			(xy 117.07876 -382.622552) (xy 117.083078 -382.593088) (xy 117.038882 -382.495044) (xy 117.034475 -382.486352)
			(xy 117.020433 -382.472864) (xy 117.002387 -382.465548) (xy 116.992654 -382.465072) (xy 116.440458 -382.465072)
			(xy 116.430712 -382.465505) (xy 116.412635 -382.472793) (xy 116.39861 -382.486327) (xy 116.39423 -382.495044)
			(xy 116.350034 -382.593088) (xy 116.354352 -382.622552) (xy 116.364512 -382.633982) (xy 116.380029 -382.652212)
			(xy 116.406195 -382.692301) (xy 116.426315 -382.735739) (xy 116.439969 -382.781623) (xy 116.446874 -382.828994)
			(xy 116.447316 -382.85293) (xy 116.446806 -382.878917) (xy 116.438676 -382.930252) (xy 116.422615 -382.979682)
			(xy 116.399019 -383.025992) (xy 116.368469 -383.06804) (xy 116.331718 -383.104791) (xy 116.28967 -383.135341)
			(xy 116.24336 -383.158937) (xy 116.19393 -383.174998) (xy 116.142595 -383.183128) (xy 116.090621 -383.183128)
			(xy 116.039286 -383.174998) (xy 115.989856 -383.158937) (xy 115.943546 -383.135341) (xy 115.901498 -383.104791)
			(xy 115.864747 -383.06804) (xy 115.834197 -383.025992) (xy 115.810601 -382.979682) (xy 115.79454 -382.930252)
			(xy 115.78641 -382.878917) (xy 115.7859 -382.85293) (xy 115.786321 -382.828992) (xy 115.793219 -382.781617)
			(xy 115.806873 -382.73573) (xy 115.827 -382.692291) (xy 115.853178 -382.652207) (xy 115.868704 -382.633982)
			(xy 115.878864 -382.622552) (xy 115.883182 -382.593088) (xy 115.838986 -382.495044) (xy 115.834579 -382.486352)
			(xy 115.820537 -382.472862) (xy 115.802492 -382.465546) (xy 115.792758 -382.465072) (xy 115.240308 -382.465072)
			(xy 115.230557 -382.465496) (xy 115.212465 -382.472773) (xy 115.198424 -382.486306) (xy 115.19408 -382.495044)
			(xy 115.149884 -382.593088) (xy 115.154202 -382.622552) (xy 115.164362 -382.633982) (xy 115.179881 -382.652211)
			(xy 115.206051 -382.692298) (xy 115.226174 -382.735737) (xy 115.239831 -382.781621) (xy 115.246736 -382.828993)
			(xy 115.247166 -382.85293) (xy 115.246656 -382.878917) (xy 115.238526 -382.930252) (xy 115.222465 -382.979682)
			(xy 115.198869 -383.025992) (xy 115.168319 -383.06804) (xy 115.131568 -383.104791) (xy 115.08952 -383.135341)
			(xy 115.04321 -383.158937) (xy 114.99378 -383.174998) (xy 114.942445 -383.183128) (xy 114.890471 -383.183128)
			(xy 114.839136 -383.174998) (xy 114.789706 -383.158937) (xy 114.743396 -383.135341) (xy 114.701348 -383.104791)
			(xy 114.664597 -383.06804) (xy 114.634047 -383.025992) (xy 114.610451 -382.979682) (xy 114.59439 -382.930252)
			(xy 114.58626 -382.878917) (xy 114.58575 -382.85293) (xy 114.586172 -382.828993) (xy 114.59307 -382.781618)
			(xy 114.606726 -382.735732) (xy 114.626855 -382.692295) (xy 114.653036 -382.652213) (xy 114.668554 -382.633982)
			(xy 114.678714 -382.622552) (xy 114.683032 -382.593088) (xy 114.638836 -382.495044) (xy 114.634427 -382.486358)
			(xy 114.620382 -382.472881) (xy 114.602338 -382.465582) (xy 114.592608 -382.465072) (xy 112.548162 -382.465072)
			(xy 112.538094 -382.465501) (xy 112.519497 -382.473222) (xy 112.512094 -382.480058) (xy 112.058117 -382.934035)
			(xy 113.238282 -382.934035) (xy 113.238282 -382.882061) (xy 113.246412 -382.830726) (xy 113.262473 -382.781296)
			(xy 113.286069 -382.734986) (xy 113.316619 -382.692938) (xy 113.35337 -382.656187) (xy 113.395418 -382.625637)
			(xy 113.441728 -382.602041) (xy 113.491158 -382.58598) (xy 113.542493 -382.57785) (xy 113.594467 -382.57785)
			(xy 113.645802 -382.58598) (xy 113.695232 -382.602041) (xy 113.741542 -382.625637) (xy 113.78359 -382.656187)
			(xy 113.820341 -382.692938) (xy 113.850891 -382.734986) (xy 113.874487 -382.781296) (xy 113.890548 -382.830726)
			(xy 113.898678 -382.882061) (xy 113.899188 -382.908048) (xy 113.898678 -382.934035) (xy 113.890548 -382.98537)
			(xy 113.874487 -383.0348) (xy 113.850891 -383.08111) (xy 113.820341 -383.123158) (xy 113.78359 -383.159909)
			(xy 113.741542 -383.190459) (xy 113.695232 -383.214055) (xy 113.645802 -383.230116) (xy 113.594467 -383.238246)
			(xy 113.542493 -383.238246) (xy 113.491158 -383.230116) (xy 113.441728 -383.214055) (xy 113.395418 -383.190459)
			(xy 113.35337 -383.159909) (xy 113.316619 -383.123158) (xy 113.286069 -383.08111) (xy 113.262473 -383.0348)
			(xy 113.246412 -382.98537) (xy 113.238282 -382.934035) (xy 112.058117 -382.934035) (xy 112.020096 -382.972056)
			(xy 112.013259 -382.979458) (xy 112.005545 -382.998056) (xy 112.00511 -383.008124) (xy 112.00511 -384.383359)
			(xy 112.170974 -384.383359) (xy 112.170974 -384.331385) (xy 112.179104 -384.28005) (xy 112.195165 -384.23062)
			(xy 112.218761 -384.18431) (xy 112.249311 -384.142262) (xy 112.286062 -384.105511) (xy 112.32811 -384.074961)
			(xy 112.37442 -384.051365) (xy 112.42385 -384.035304) (xy 112.475185 -384.027174) (xy 112.527159 -384.027174)
			(xy 112.578494 -384.035304) (xy 112.627924 -384.051365) (xy 112.674234 -384.074961) (xy 112.716282 -384.105511)
			(xy 112.753033 -384.142262) (xy 112.783583 -384.18431) (xy 112.807179 -384.23062) (xy 112.82324 -384.28005)
			(xy 112.83137 -384.331385) (xy 112.83188 -384.357372) (xy 112.83137 -384.383359) (xy 112.82324 -384.434694)
			(xy 112.807179 -384.484124) (xy 112.783583 -384.530434) (xy 112.753033 -384.572482) (xy 112.716282 -384.609233)
			(xy 112.674234 -384.639783) (xy 112.666529 -384.643709) (xy 114.232184 -384.643709) (xy 114.232184 -384.591735)
			(xy 114.240314 -384.5404) (xy 114.256375 -384.49097) (xy 114.279971 -384.44466) (xy 114.310521 -384.402612)
			(xy 114.347272 -384.365861) (xy 114.38932 -384.335311) (xy 114.43563 -384.311715) (xy 114.48506 -384.295654)
			(xy 114.536395 -384.287524) (xy 114.588369 -384.287524) (xy 114.639704 -384.295654) (xy 114.689134 -384.311715)
			(xy 114.735444 -384.335311) (xy 114.777492 -384.365861) (xy 114.814243 -384.402612) (xy 114.844793 -384.44466)
			(xy 114.868389 -384.49097) (xy 114.88445 -384.5404) (xy 114.89258 -384.591735) (xy 114.89309 -384.617722)
			(xy 114.89258 -384.643709) (xy 115.43208 -384.643709) (xy 115.43208 -384.591735) (xy 115.44021 -384.5404)
			(xy 115.456271 -384.49097) (xy 115.479867 -384.44466) (xy 115.510417 -384.402612) (xy 115.547168 -384.365861)
			(xy 115.589216 -384.335311) (xy 115.635526 -384.311715) (xy 115.684956 -384.295654) (xy 115.736291 -384.287524)
			(xy 115.788265 -384.287524) (xy 115.8396 -384.295654) (xy 115.88903 -384.311715) (xy 115.93534 -384.335311)
			(xy 115.977388 -384.365861) (xy 116.014139 -384.402612) (xy 116.044689 -384.44466) (xy 116.068285 -384.49097)
			(xy 116.084346 -384.5404) (xy 116.092476 -384.591735) (xy 116.092986 -384.617722) (xy 116.092476 -384.643709)
			(xy 116.63223 -384.643709) (xy 116.63223 -384.591735) (xy 116.64036 -384.5404) (xy 116.656421 -384.49097)
			(xy 116.680017 -384.44466) (xy 116.710567 -384.402612) (xy 116.747318 -384.365861) (xy 116.789366 -384.335311)
			(xy 116.835676 -384.311715) (xy 116.885106 -384.295654) (xy 116.936441 -384.287524) (xy 116.988415 -384.287524)
			(xy 117.03975 -384.295654) (xy 117.08918 -384.311715) (xy 117.13549 -384.335311) (xy 117.177538 -384.365861)
			(xy 117.214289 -384.402612) (xy 117.244839 -384.44466) (xy 117.268435 -384.49097) (xy 117.284496 -384.5404)
			(xy 117.292626 -384.591735) (xy 117.293136 -384.617722) (xy 117.292626 -384.643709) (xy 117.832126 -384.643709)
			(xy 117.832126 -384.591735) (xy 117.840256 -384.5404) (xy 117.856317 -384.49097) (xy 117.879913 -384.44466)
			(xy 117.910463 -384.402612) (xy 117.947214 -384.365861) (xy 117.989262 -384.335311) (xy 118.035572 -384.311715)
			(xy 118.085002 -384.295654) (xy 118.136337 -384.287524) (xy 118.188311 -384.287524) (xy 118.239646 -384.295654)
			(xy 118.289076 -384.311715) (xy 118.335386 -384.335311) (xy 118.377434 -384.365861) (xy 118.414185 -384.402612)
			(xy 118.444735 -384.44466) (xy 118.468331 -384.49097) (xy 118.484392 -384.5404) (xy 118.492522 -384.591735)
			(xy 118.493032 -384.617722) (xy 118.492522 -384.643709) (xy 119.032276 -384.643709) (xy 119.032276 -384.591735)
			(xy 119.040406 -384.5404) (xy 119.056467 -384.49097) (xy 119.080063 -384.44466) (xy 119.110613 -384.402612)
			(xy 119.147364 -384.365861) (xy 119.189412 -384.335311) (xy 119.235722 -384.311715) (xy 119.285152 -384.295654)
			(xy 119.336487 -384.287524) (xy 119.388461 -384.287524) (xy 119.439796 -384.295654) (xy 119.489226 -384.311715)
			(xy 119.535536 -384.335311) (xy 119.577584 -384.365861) (xy 119.614335 -384.402612) (xy 119.644885 -384.44466)
			(xy 119.668481 -384.49097) (xy 119.684542 -384.5404) (xy 119.692672 -384.591735) (xy 119.693182 -384.617722)
			(xy 119.692672 -384.643709) (xy 120.232172 -384.643709) (xy 120.232172 -384.591735) (xy 120.240302 -384.5404)
			(xy 120.256363 -384.49097) (xy 120.279959 -384.44466) (xy 120.310509 -384.402612) (xy 120.34726 -384.365861)
			(xy 120.389308 -384.335311) (xy 120.435618 -384.311715) (xy 120.485048 -384.295654) (xy 120.536383 -384.287524)
			(xy 120.588357 -384.287524) (xy 120.639692 -384.295654) (xy 120.689122 -384.311715) (xy 120.735432 -384.335311)
			(xy 120.77748 -384.365861) (xy 120.814231 -384.402612) (xy 120.844781 -384.44466) (xy 120.868377 -384.49097)
			(xy 120.884438 -384.5404) (xy 120.892568 -384.591735) (xy 120.893078 -384.617722) (xy 120.892568 -384.643709)
			(xy 121.432068 -384.643709) (xy 121.432068 -384.591735) (xy 121.440198 -384.5404) (xy 121.456259 -384.49097)
			(xy 121.479855 -384.44466) (xy 121.510405 -384.402612) (xy 121.547156 -384.365861) (xy 121.589204 -384.335311)
			(xy 121.635514 -384.311715) (xy 121.684944 -384.295654) (xy 121.736279 -384.287524) (xy 121.788253 -384.287524)
			(xy 121.839588 -384.295654) (xy 121.889018 -384.311715) (xy 121.935328 -384.335311) (xy 121.977376 -384.365861)
			(xy 122.014127 -384.402612) (xy 122.044677 -384.44466) (xy 122.068273 -384.49097) (xy 122.084334 -384.5404)
			(xy 122.092464 -384.591735) (xy 122.092974 -384.617722) (xy 122.092464 -384.643709) (xy 122.632218 -384.643709)
			(xy 122.632218 -384.591735) (xy 122.640348 -384.5404) (xy 122.656409 -384.49097) (xy 122.680005 -384.44466)
			(xy 122.710555 -384.402612) (xy 122.747306 -384.365861) (xy 122.789354 -384.335311) (xy 122.835664 -384.311715)
			(xy 122.885094 -384.295654) (xy 122.936429 -384.287524) (xy 122.988403 -384.287524) (xy 123.039738 -384.295654)
			(xy 123.089168 -384.311715) (xy 123.135478 -384.335311) (xy 123.177526 -384.365861) (xy 123.214277 -384.402612)
			(xy 123.244827 -384.44466) (xy 123.268423 -384.49097) (xy 123.284484 -384.5404) (xy 123.292614 -384.591735)
			(xy 123.293124 -384.617722) (xy 123.292614 -384.643709) (xy 123.832114 -384.643709) (xy 123.832114 -384.591735)
			(xy 123.840244 -384.5404) (xy 123.856305 -384.49097) (xy 123.879901 -384.44466) (xy 123.910451 -384.402612)
			(xy 123.947202 -384.365861) (xy 123.98925 -384.335311) (xy 124.03556 -384.311715) (xy 124.08499 -384.295654)
			(xy 124.136325 -384.287524) (xy 124.188299 -384.287524) (xy 124.239634 -384.295654) (xy 124.289064 -384.311715)
			(xy 124.335374 -384.335311) (xy 124.377422 -384.365861) (xy 124.414173 -384.402612) (xy 124.444723 -384.44466)
			(xy 124.468319 -384.49097) (xy 124.48438 -384.5404) (xy 124.49251 -384.591735) (xy 124.49302 -384.617722)
			(xy 124.49251 -384.643709) (xy 125.032264 -384.643709) (xy 125.032264 -384.591735) (xy 125.040394 -384.5404)
			(xy 125.056455 -384.49097) (xy 125.080051 -384.44466) (xy 125.110601 -384.402612) (xy 125.147352 -384.365861)
			(xy 125.1894 -384.335311) (xy 125.23571 -384.311715) (xy 125.28514 -384.295654) (xy 125.336475 -384.287524)
			(xy 125.388449 -384.287524) (xy 125.439784 -384.295654) (xy 125.489214 -384.311715) (xy 125.535524 -384.335311)
			(xy 125.577572 -384.365861) (xy 125.614323 -384.402612) (xy 125.644873 -384.44466) (xy 125.668469 -384.49097)
			(xy 125.68453 -384.5404) (xy 125.69266 -384.591735) (xy 125.69317 -384.617722) (xy 125.69266 -384.643709)
			(xy 126.23216 -384.643709) (xy 126.23216 -384.591735) (xy 126.24029 -384.5404) (xy 126.256351 -384.49097)
			(xy 126.279947 -384.44466) (xy 126.310497 -384.402612) (xy 126.347248 -384.365861) (xy 126.389296 -384.335311)
			(xy 126.435606 -384.311715) (xy 126.485036 -384.295654) (xy 126.536371 -384.287524) (xy 126.588345 -384.287524)
			(xy 126.63968 -384.295654) (xy 126.68911 -384.311715) (xy 126.73542 -384.335311) (xy 126.777468 -384.365861)
			(xy 126.814219 -384.402612) (xy 126.844769 -384.44466) (xy 126.868365 -384.49097) (xy 126.884426 -384.5404)
			(xy 126.892556 -384.591735) (xy 126.893066 -384.617722) (xy 126.892556 -384.643709) (xy 127.432056 -384.643709)
			(xy 127.432056 -384.591735) (xy 127.440186 -384.5404) (xy 127.456247 -384.49097) (xy 127.479843 -384.44466)
			(xy 127.510393 -384.402612) (xy 127.547144 -384.365861) (xy 127.589192 -384.335311) (xy 127.635502 -384.311715)
			(xy 127.684932 -384.295654) (xy 127.736267 -384.287524) (xy 127.788241 -384.287524) (xy 127.839576 -384.295654)
			(xy 127.889006 -384.311715) (xy 127.935316 -384.335311) (xy 127.977364 -384.365861) (xy 128.014115 -384.402612)
			(xy 128.044665 -384.44466) (xy 128.068261 -384.49097) (xy 128.084322 -384.5404) (xy 128.092452 -384.591735)
			(xy 128.092962 -384.617722) (xy 128.092452 -384.643709) (xy 128.632206 -384.643709) (xy 128.632206 -384.591735)
			(xy 128.640336 -384.5404) (xy 128.656397 -384.49097) (xy 128.679993 -384.44466) (xy 128.710543 -384.402612)
			(xy 128.747294 -384.365861) (xy 128.789342 -384.335311) (xy 128.835652 -384.311715) (xy 128.885082 -384.295654)
			(xy 128.936417 -384.287524) (xy 128.988391 -384.287524) (xy 129.039726 -384.295654) (xy 129.089156 -384.311715)
			(xy 129.135466 -384.335311) (xy 129.177514 -384.365861) (xy 129.214265 -384.402612) (xy 129.244815 -384.44466)
			(xy 129.268411 -384.49097) (xy 129.284472 -384.5404) (xy 129.292602 -384.591735) (xy 129.293112 -384.617722)
			(xy 129.292602 -384.643709) (xy 129.832102 -384.643709) (xy 129.832102 -384.591735) (xy 129.840232 -384.5404)
			(xy 129.856293 -384.49097) (xy 129.879889 -384.44466) (xy 129.910439 -384.402612) (xy 129.94719 -384.365861)
			(xy 129.989238 -384.335311) (xy 130.035548 -384.311715) (xy 130.084978 -384.295654) (xy 130.136313 -384.287524)
			(xy 130.188287 -384.287524) (xy 130.239622 -384.295654) (xy 130.289052 -384.311715) (xy 130.335362 -384.335311)
			(xy 130.37741 -384.365861) (xy 130.414161 -384.402612) (xy 130.444711 -384.44466) (xy 130.468307 -384.49097)
			(xy 130.484368 -384.5404) (xy 130.492498 -384.591735) (xy 130.493008 -384.617722) (xy 130.492498 -384.643709)
			(xy 131.032252 -384.643709) (xy 131.032252 -384.591735) (xy 131.040382 -384.5404) (xy 131.056443 -384.49097)
			(xy 131.080039 -384.44466) (xy 131.110589 -384.402612) (xy 131.14734 -384.365861) (xy 131.189388 -384.335311)
			(xy 131.235698 -384.311715) (xy 131.285128 -384.295654) (xy 131.336463 -384.287524) (xy 131.388437 -384.287524)
			(xy 131.439772 -384.295654) (xy 131.489202 -384.311715) (xy 131.535512 -384.335311) (xy 131.57756 -384.365861)
			(xy 131.614311 -384.402612) (xy 131.644861 -384.44466) (xy 131.668457 -384.49097) (xy 131.684518 -384.5404)
			(xy 131.692648 -384.591735) (xy 131.693158 -384.617722) (xy 131.692648 -384.643709) (xy 132.232148 -384.643709)
			(xy 132.232148 -384.591735) (xy 132.240278 -384.5404) (xy 132.256339 -384.49097) (xy 132.279935 -384.44466)
			(xy 132.310485 -384.402612) (xy 132.347236 -384.365861) (xy 132.389284 -384.335311) (xy 132.435594 -384.311715)
			(xy 132.485024 -384.295654) (xy 132.536359 -384.287524) (xy 132.588333 -384.287524) (xy 132.639668 -384.295654)
			(xy 132.689098 -384.311715) (xy 132.735408 -384.335311) (xy 132.777456 -384.365861) (xy 132.814207 -384.402612)
			(xy 132.844757 -384.44466) (xy 132.868353 -384.49097) (xy 132.884414 -384.5404) (xy 132.892544 -384.591735)
			(xy 132.893054 -384.617722) (xy 132.892544 -384.643709) (xy 132.884414 -384.695044) (xy 132.868353 -384.744474)
			(xy 132.844757 -384.790784) (xy 132.814207 -384.832832) (xy 132.777456 -384.869583) (xy 132.735408 -384.900133)
			(xy 132.689098 -384.923729) (xy 132.639668 -384.93979) (xy 132.588333 -384.94792) (xy 132.536359 -384.94792)
			(xy 132.485024 -384.93979) (xy 132.435594 -384.923729) (xy 132.389284 -384.900133) (xy 132.347236 -384.869583)
			(xy 132.310485 -384.832832) (xy 132.279935 -384.790784) (xy 132.256339 -384.744474) (xy 132.240278 -384.695044)
			(xy 132.232148 -384.643709) (xy 131.692648 -384.643709) (xy 131.684518 -384.695044) (xy 131.668457 -384.744474)
			(xy 131.644861 -384.790784) (xy 131.614311 -384.832832) (xy 131.57756 -384.869583) (xy 131.535512 -384.900133)
			(xy 131.489202 -384.923729) (xy 131.439772 -384.93979) (xy 131.388437 -384.94792) (xy 131.336463 -384.94792)
			(xy 131.285128 -384.93979) (xy 131.235698 -384.923729) (xy 131.189388 -384.900133) (xy 131.14734 -384.869583)
			(xy 131.110589 -384.832832) (xy 131.080039 -384.790784) (xy 131.056443 -384.744474) (xy 131.040382 -384.695044)
			(xy 131.032252 -384.643709) (xy 130.492498 -384.643709) (xy 130.484368 -384.695044) (xy 130.468307 -384.744474)
			(xy 130.444711 -384.790784) (xy 130.414161 -384.832832) (xy 130.37741 -384.869583) (xy 130.335362 -384.900133)
			(xy 130.289052 -384.923729) (xy 130.239622 -384.93979) (xy 130.188287 -384.94792) (xy 130.136313 -384.94792)
			(xy 130.084978 -384.93979) (xy 130.035548 -384.923729) (xy 129.989238 -384.900133) (xy 129.94719 -384.869583)
			(xy 129.910439 -384.832832) (xy 129.879889 -384.790784) (xy 129.856293 -384.744474) (xy 129.840232 -384.695044)
			(xy 129.832102 -384.643709) (xy 129.292602 -384.643709) (xy 129.284472 -384.695044) (xy 129.268411 -384.744474)
			(xy 129.244815 -384.790784) (xy 129.214265 -384.832832) (xy 129.177514 -384.869583) (xy 129.135466 -384.900133)
			(xy 129.089156 -384.923729) (xy 129.039726 -384.93979) (xy 128.988391 -384.94792) (xy 128.936417 -384.94792)
			(xy 128.885082 -384.93979) (xy 128.835652 -384.923729) (xy 128.789342 -384.900133) (xy 128.747294 -384.869583)
			(xy 128.710543 -384.832832) (xy 128.679993 -384.790784) (xy 128.656397 -384.744474) (xy 128.640336 -384.695044)
			(xy 128.632206 -384.643709) (xy 128.092452 -384.643709) (xy 128.084322 -384.695044) (xy 128.068261 -384.744474)
			(xy 128.044665 -384.790784) (xy 128.014115 -384.832832) (xy 127.977364 -384.869583) (xy 127.935316 -384.900133)
			(xy 127.889006 -384.923729) (xy 127.839576 -384.93979) (xy 127.788241 -384.94792) (xy 127.736267 -384.94792)
			(xy 127.684932 -384.93979) (xy 127.635502 -384.923729) (xy 127.589192 -384.900133) (xy 127.547144 -384.869583)
			(xy 127.510393 -384.832832) (xy 127.479843 -384.790784) (xy 127.456247 -384.744474) (xy 127.440186 -384.695044)
			(xy 127.432056 -384.643709) (xy 126.892556 -384.643709) (xy 126.884426 -384.695044) (xy 126.868365 -384.744474)
			(xy 126.844769 -384.790784) (xy 126.814219 -384.832832) (xy 126.777468 -384.869583) (xy 126.73542 -384.900133)
			(xy 126.68911 -384.923729) (xy 126.63968 -384.93979) (xy 126.588345 -384.94792) (xy 126.536371 -384.94792)
			(xy 126.485036 -384.93979) (xy 126.435606 -384.923729) (xy 126.389296 -384.900133) (xy 126.347248 -384.869583)
			(xy 126.310497 -384.832832) (xy 126.279947 -384.790784) (xy 126.256351 -384.744474) (xy 126.24029 -384.695044)
			(xy 126.23216 -384.643709) (xy 125.69266 -384.643709) (xy 125.68453 -384.695044) (xy 125.668469 -384.744474)
			(xy 125.644873 -384.790784) (xy 125.614323 -384.832832) (xy 125.577572 -384.869583) (xy 125.535524 -384.900133)
			(xy 125.489214 -384.923729) (xy 125.439784 -384.93979) (xy 125.388449 -384.94792) (xy 125.336475 -384.94792)
			(xy 125.28514 -384.93979) (xy 125.23571 -384.923729) (xy 125.1894 -384.900133) (xy 125.147352 -384.869583)
			(xy 125.110601 -384.832832) (xy 125.080051 -384.790784) (xy 125.056455 -384.744474) (xy 125.040394 -384.695044)
			(xy 125.032264 -384.643709) (xy 124.49251 -384.643709) (xy 124.48438 -384.695044) (xy 124.468319 -384.744474)
			(xy 124.444723 -384.790784) (xy 124.414173 -384.832832) (xy 124.377422 -384.869583) (xy 124.335374 -384.900133)
			(xy 124.289064 -384.923729) (xy 124.239634 -384.93979) (xy 124.188299 -384.94792) (xy 124.136325 -384.94792)
			(xy 124.08499 -384.93979) (xy 124.03556 -384.923729) (xy 123.98925 -384.900133) (xy 123.947202 -384.869583)
			(xy 123.910451 -384.832832) (xy 123.879901 -384.790784) (xy 123.856305 -384.744474) (xy 123.840244 -384.695044)
			(xy 123.832114 -384.643709) (xy 123.292614 -384.643709) (xy 123.284484 -384.695044) (xy 123.268423 -384.744474)
			(xy 123.244827 -384.790784) (xy 123.214277 -384.832832) (xy 123.177526 -384.869583) (xy 123.135478 -384.900133)
			(xy 123.089168 -384.923729) (xy 123.039738 -384.93979) (xy 122.988403 -384.94792) (xy 122.936429 -384.94792)
			(xy 122.885094 -384.93979) (xy 122.835664 -384.923729) (xy 122.789354 -384.900133) (xy 122.747306 -384.869583)
			(xy 122.710555 -384.832832) (xy 122.680005 -384.790784) (xy 122.656409 -384.744474) (xy 122.640348 -384.695044)
			(xy 122.632218 -384.643709) (xy 122.092464 -384.643709) (xy 122.084334 -384.695044) (xy 122.068273 -384.744474)
			(xy 122.044677 -384.790784) (xy 122.014127 -384.832832) (xy 121.977376 -384.869583) (xy 121.935328 -384.900133)
			(xy 121.889018 -384.923729) (xy 121.839588 -384.93979) (xy 121.788253 -384.94792) (xy 121.736279 -384.94792)
			(xy 121.684944 -384.93979) (xy 121.635514 -384.923729) (xy 121.589204 -384.900133) (xy 121.547156 -384.869583)
			(xy 121.510405 -384.832832) (xy 121.479855 -384.790784) (xy 121.456259 -384.744474) (xy 121.440198 -384.695044)
			(xy 121.432068 -384.643709) (xy 120.892568 -384.643709) (xy 120.884438 -384.695044) (xy 120.868377 -384.744474)
			(xy 120.844781 -384.790784) (xy 120.814231 -384.832832) (xy 120.77748 -384.869583) (xy 120.735432 -384.900133)
			(xy 120.689122 -384.923729) (xy 120.639692 -384.93979) (xy 120.588357 -384.94792) (xy 120.536383 -384.94792)
			(xy 120.485048 -384.93979) (xy 120.435618 -384.923729) (xy 120.389308 -384.900133) (xy 120.34726 -384.869583)
			(xy 120.310509 -384.832832) (xy 120.279959 -384.790784) (xy 120.256363 -384.744474) (xy 120.240302 -384.695044)
			(xy 120.232172 -384.643709) (xy 119.692672 -384.643709) (xy 119.684542 -384.695044) (xy 119.668481 -384.744474)
			(xy 119.644885 -384.790784) (xy 119.614335 -384.832832) (xy 119.577584 -384.869583) (xy 119.535536 -384.900133)
			(xy 119.489226 -384.923729) (xy 119.439796 -384.93979) (xy 119.388461 -384.94792) (xy 119.336487 -384.94792)
			(xy 119.285152 -384.93979) (xy 119.235722 -384.923729) (xy 119.189412 -384.900133) (xy 119.147364 -384.869583)
			(xy 119.110613 -384.832832) (xy 119.080063 -384.790784) (xy 119.056467 -384.744474) (xy 119.040406 -384.695044)
			(xy 119.032276 -384.643709) (xy 118.492522 -384.643709) (xy 118.484392 -384.695044) (xy 118.468331 -384.744474)
			(xy 118.444735 -384.790784) (xy 118.414185 -384.832832) (xy 118.377434 -384.869583) (xy 118.335386 -384.900133)
			(xy 118.289076 -384.923729) (xy 118.239646 -384.93979) (xy 118.188311 -384.94792) (xy 118.136337 -384.94792)
			(xy 118.085002 -384.93979) (xy 118.035572 -384.923729) (xy 117.989262 -384.900133) (xy 117.947214 -384.869583)
			(xy 117.910463 -384.832832) (xy 117.879913 -384.790784) (xy 117.856317 -384.744474) (xy 117.840256 -384.695044)
			(xy 117.832126 -384.643709) (xy 117.292626 -384.643709) (xy 117.284496 -384.695044) (xy 117.268435 -384.744474)
			(xy 117.244839 -384.790784) (xy 117.214289 -384.832832) (xy 117.177538 -384.869583) (xy 117.13549 -384.900133)
			(xy 117.08918 -384.923729) (xy 117.03975 -384.93979) (xy 116.988415 -384.94792) (xy 116.936441 -384.94792)
			(xy 116.885106 -384.93979) (xy 116.835676 -384.923729) (xy 116.789366 -384.900133) (xy 116.747318 -384.869583)
			(xy 116.710567 -384.832832) (xy 116.680017 -384.790784) (xy 116.656421 -384.744474) (xy 116.64036 -384.695044)
			(xy 116.63223 -384.643709) (xy 116.092476 -384.643709) (xy 116.084346 -384.695044) (xy 116.068285 -384.744474)
			(xy 116.044689 -384.790784) (xy 116.014139 -384.832832) (xy 115.977388 -384.869583) (xy 115.93534 -384.900133)
			(xy 115.88903 -384.923729) (xy 115.8396 -384.93979) (xy 115.788265 -384.94792) (xy 115.736291 -384.94792)
			(xy 115.684956 -384.93979) (xy 115.635526 -384.923729) (xy 115.589216 -384.900133) (xy 115.547168 -384.869583)
			(xy 115.510417 -384.832832) (xy 115.479867 -384.790784) (xy 115.456271 -384.744474) (xy 115.44021 -384.695044)
			(xy 115.43208 -384.643709) (xy 114.89258 -384.643709) (xy 114.88445 -384.695044) (xy 114.868389 -384.744474)
			(xy 114.844793 -384.790784) (xy 114.814243 -384.832832) (xy 114.777492 -384.869583) (xy 114.735444 -384.900133)
			(xy 114.689134 -384.923729) (xy 114.639704 -384.93979) (xy 114.588369 -384.94792) (xy 114.536395 -384.94792)
			(xy 114.48506 -384.93979) (xy 114.43563 -384.923729) (xy 114.38932 -384.900133) (xy 114.347272 -384.869583)
			(xy 114.310521 -384.832832) (xy 114.279971 -384.790784) (xy 114.256375 -384.744474) (xy 114.240314 -384.695044)
			(xy 114.232184 -384.643709) (xy 112.666529 -384.643709) (xy 112.627924 -384.663379) (xy 112.578494 -384.67944)
			(xy 112.527159 -384.68757) (xy 112.475185 -384.68757) (xy 112.42385 -384.67944) (xy 112.37442 -384.663379)
			(xy 112.32811 -384.639783) (xy 112.286062 -384.609233) (xy 112.249311 -384.572482) (xy 112.218761 -384.530434)
			(xy 112.195165 -384.484124) (xy 112.179104 -384.434694) (xy 112.170974 -384.383359) (xy 112.00511 -384.383359)
			(xy 112.00511 -385.171188) (xy 112.005526 -385.180796) (xy 112.012577 -385.198674) (xy 112.018826 -385.205986)
			(xy 112.073182 -385.263898) (xy 112.090708 -385.272026) (xy 112.10036 -385.272788) (xy 112.126549 -385.274912)
			(xy 112.177816 -385.286403) (xy 112.22662 -385.305859) (xy 112.234193 -385.31038) (xy 114.560604 -385.31038)
			(xy 114.561083 -385.284392) (xy 114.569217 -385.233055) (xy 114.585282 -385.183623) (xy 114.608881 -385.137313)
			(xy 114.639434 -385.095265) (xy 114.676189 -385.058513) (xy 114.71824 -385.027964) (xy 114.764553 -385.004369)
			(xy 114.813987 -384.98831) (xy 114.865324 -384.980181) (xy 114.891312 -384.979672) (xy 114.917322 -384.980131)
			(xy 114.9687 -384.988291) (xy 115.018166 -385.004394) (xy 115.064502 -385.028041) (xy 115.106565 -385.05865)
			(xy 115.143318 -385.095466) (xy 115.173855 -385.137581) (xy 115.197423 -385.183958) (xy 115.213441 -385.233452)
			(xy 115.217956 -385.259072) (xy 115.21948 -385.26847) (xy 115.243706 -385.31038) (xy 115.7605 -385.31038)
			(xy 115.760983 -385.284392) (xy 115.769117 -385.233056) (xy 115.785181 -385.183624) (xy 115.80878 -385.137314)
			(xy 115.839333 -385.095266) (xy 115.876087 -385.058515) (xy 115.918138 -385.027966) (xy 115.96445 -385.00437)
			(xy 116.013883 -384.98831) (xy 116.06522 -384.980181) (xy 116.091208 -384.979672) (xy 116.117218 -384.980134)
			(xy 116.168595 -384.988294) (xy 116.218062 -385.004396) (xy 116.264398 -385.028043) (xy 116.306461 -385.058651)
			(xy 116.343214 -385.095467) (xy 116.373751 -385.137582) (xy 116.397319 -385.183958) (xy 116.413337 -385.233452)
			(xy 116.417852 -385.259072) (xy 116.419376 -385.26847) (xy 116.443602 -385.31038) (xy 116.96065 -385.31038)
			(xy 116.961183 -385.284394) (xy 116.969315 -385.233063) (xy 116.985376 -385.183636) (xy 117.008971 -385.137329)
			(xy 117.039518 -385.095283) (xy 117.076266 -385.058533) (xy 117.11831 -385.027983) (xy 117.164616 -385.004385)
			(xy 117.214042 -384.98832) (xy 117.265372 -384.980185) (xy 117.291358 -384.979672) (xy 117.317401 -384.980171)
			(xy 117.36884 -384.988353) (xy 117.418363 -385.004489) (xy 117.464748 -385.028181) (xy 117.506851 -385.058846)
			(xy 117.543631 -385.095725) (xy 117.574183 -385.13791) (xy 117.597751 -385.184358) (xy 117.613754 -385.233925)
			(xy 117.618256 -385.25958) (xy 117.619526 -385.268978) (xy 117.643462 -385.31038) (xy 118.160546 -385.31038)
			(xy 118.161083 -385.284395) (xy 118.169215 -385.233064) (xy 118.185276 -385.183637) (xy 118.20887 -385.13733)
			(xy 118.239417 -385.095285) (xy 118.276165 -385.058534) (xy 118.318208 -385.027984) (xy 118.364513 -385.004386)
			(xy 118.413939 -384.988321) (xy 118.465269 -384.980185) (xy 118.491254 -384.979672) (xy 118.517266 -384.980092)
			(xy 118.568645 -384.988259) (xy 118.618112 -385.004368) (xy 118.664448 -385.02802) (xy 118.706511 -385.058634)
			(xy 118.743263 -385.095455) (xy 118.773799 -385.137574) (xy 118.797366 -385.183953) (xy 118.813383 -385.23345)
			(xy 118.817898 -385.259072) (xy 118.819422 -385.26847) (xy 118.843648 -385.31038) (xy 119.360442 -385.31038)
			(xy 119.360857 -385.284388) (xy 119.368993 -385.233044) (xy 119.385061 -385.183605) (xy 119.408665 -385.137288)
			(xy 119.439225 -385.095234) (xy 119.475988 -385.05848) (xy 119.518048 -385.027929) (xy 119.564369 -385.004334)
			(xy 119.613812 -384.988276) (xy 119.665158 -384.980151) (xy 119.69115 -384.979672) (xy 119.717162 -384.980096)
			(xy 119.76854 -384.988262) (xy 119.818007 -385.00437) (xy 119.864343 -385.028022) (xy 119.906406 -385.058636)
			(xy 119.943159 -385.095456) (xy 119.973695 -385.137574) (xy 119.997262 -385.183954) (xy 120.013279 -385.23345)
			(xy 120.017794 -385.259072) (xy 120.019318 -385.26847) (xy 120.043544 -385.31038) (xy 120.560592 -385.31038)
			(xy 120.561083 -385.284392) (xy 120.569217 -385.233057) (xy 120.58528 -385.183626) (xy 120.608879 -385.137317)
			(xy 120.639431 -385.095269) (xy 120.676184 -385.058518) (xy 120.718234 -385.027968) (xy 120.764545 -385.004373)
			(xy 120.813977 -384.988312) (xy 120.865312 -384.980182) (xy 120.8913 -384.979672) (xy 120.91731 -384.980142)
			(xy 120.968687 -384.9883) (xy 121.018153 -385.004401) (xy 121.064489 -385.028047) (xy 121.106552 -385.058654)
			(xy 121.143305 -385.095469) (xy 121.173843 -385.137584) (xy 121.197411 -385.183959) (xy 121.213429 -385.233452)
			(xy 121.217944 -385.259072) (xy 121.219468 -385.26847) (xy 121.243694 -385.31038) (xy 121.760488 -385.31038)
			(xy 121.760983 -385.284392) (xy 121.769117 -385.233058) (xy 121.78518 -385.183627) (xy 121.808778 -385.137318)
			(xy 121.839329 -385.09527) (xy 121.876082 -385.058519) (xy 121.918132 -385.02797) (xy 121.964442 -385.004374)
			(xy 122.013873 -384.988313) (xy 122.065208 -384.980182) (xy 122.091196 -384.979672) (xy 122.117206 -384.980145)
			(xy 122.168583 -384.988303) (xy 122.218049 -385.004404) (xy 122.264385 -385.028049) (xy 122.306448 -385.058656)
			(xy 122.343201 -385.09547) (xy 122.373738 -385.137584) (xy 122.397307 -385.183959) (xy 122.413325 -385.233452)
			(xy 122.41784 -385.259072) (xy 122.419364 -385.26847) (xy 122.44359 -385.31038) (xy 122.960638 -385.31038)
			(xy 122.961057 -385.284388) (xy 122.969192 -385.233044) (xy 122.98526 -385.183605) (xy 123.008865 -385.137289)
			(xy 123.039424 -385.095236) (xy 123.076186 -385.058481) (xy 123.118246 -385.02793) (xy 123.164567 -385.004335)
			(xy 123.214008 -384.988277) (xy 123.265354 -384.980152) (xy 123.291346 -384.979672) (xy 123.317388 -384.980182)
			(xy 123.368827 -384.988362) (xy 123.41835 -385.004496) (xy 123.464735 -385.028187) (xy 123.506838 -385.05885)
			(xy 123.543619 -385.095729) (xy 123.57417 -385.137912) (xy 123.597739 -385.18436) (xy 123.613742 -385.233925)
			(xy 123.618244 -385.25958) (xy 123.619514 -385.268978) (xy 123.64345 -385.31038) (xy 124.160534 -385.31038)
			(xy 124.160957 -385.284388) (xy 124.169092 -385.233045) (xy 124.18516 -385.183606) (xy 124.208764 -385.13729)
			(xy 124.239323 -385.095237) (xy 124.276084 -385.058482) (xy 124.318143 -385.027931) (xy 124.364464 -385.004336)
			(xy 124.413905 -384.988278) (xy 124.46525 -384.980152) (xy 124.491242 -384.979672) (xy 124.517253 -384.980103)
			(xy 124.568632 -384.988268) (xy 124.618099 -385.004375) (xy 124.664435 -385.028026) (xy 124.706498 -385.058639)
			(xy 124.74325 -385.095458) (xy 124.773787 -385.137576) (xy 124.797354 -385.183955) (xy 124.813371 -385.233451)
			(xy 124.817886 -385.259072) (xy 124.81941 -385.26847) (xy 124.843636 -385.31038) (xy 125.36043 -385.31038)
			(xy 125.360857 -385.284388) (xy 125.368992 -385.233045) (xy 125.38506 -385.183607) (xy 125.408663 -385.137292)
			(xy 125.439222 -385.095239) (xy 125.475983 -385.058484) (xy 125.518041 -385.027933) (xy 125.564361 -385.004337)
			(xy 125.613802 -384.988279) (xy 125.665146 -384.980152) (xy 125.691138 -384.979672) (xy 125.717149 -384.980107)
			(xy 125.768527 -384.988272) (xy 125.817994 -385.004378) (xy 125.86433 -385.028028) (xy 125.906393 -385.05864)
			(xy 125.943146 -385.095459) (xy 125.973682 -385.137577) (xy 125.99725 -385.183955) (xy 126.013267 -385.233451)
			(xy 126.017782 -385.259072) (xy 126.019306 -385.26847) (xy 126.043532 -385.31038) (xy 126.56058 -385.31038)
			(xy 126.561083 -385.284393) (xy 126.569216 -385.233059) (xy 126.585279 -385.183629) (xy 126.608877 -385.13732)
			(xy 126.639427 -385.095273) (xy 126.676179 -385.058522) (xy 126.718227 -385.027972) (xy 126.764536 -385.004376)
			(xy 126.813967 -384.988314) (xy 126.865301 -384.980182) (xy 126.891288 -384.979672) (xy 126.917298 -384.980152)
			(xy 126.968674 -384.988309) (xy 127.01814 -385.004409) (xy 127.064476 -385.028053) (xy 127.106539 -385.058659)
			(xy 127.143293 -385.095473) (xy 127.17383 -385.137586) (xy 127.197398 -385.18396) (xy 127.213417 -385.233452)
			(xy 127.217932 -385.259072) (xy 127.219456 -385.26847) (xy 127.243682 -385.31038) (xy 127.760476 -385.31038)
			(xy 127.760983 -385.284393) (xy 127.769116 -385.233059) (xy 127.785179 -385.18363) (xy 127.808776 -385.137322)
			(xy 127.839326 -385.095274) (xy 127.876077 -385.058523) (xy 127.918125 -385.027974) (xy 127.964434 -385.004377)
			(xy 128.013863 -384.988315) (xy 128.065197 -384.980183) (xy 128.091184 -384.979672) (xy 128.117194 -384.980156)
			(xy 128.16857 -384.988313) (xy 128.218036 -385.004411) (xy 128.264372 -385.028055) (xy 128.306435 -385.05866)
			(xy 128.343188 -385.095474) (xy 128.373726 -385.137587) (xy 128.397294 -385.183961) (xy 128.413313 -385.233453)
			(xy 128.417828 -385.259072) (xy 128.419352 -385.26847) (xy 128.443578 -385.31038) (xy 128.960626 -385.31038)
			(xy 128.961057 -385.284388) (xy 128.969192 -385.233046) (xy 128.985259 -385.183608) (xy 129.008862 -385.137293)
			(xy 129.03942 -385.09524) (xy 129.076181 -385.058485) (xy 129.118239 -385.027934) (xy 129.164558 -385.004338)
			(xy 129.213999 -384.988279) (xy 129.265342 -384.980153) (xy 129.291334 -384.979672) (xy 129.317379 -384.980102)
			(xy 129.368821 -384.988295) (xy 129.418346 -385.004442) (xy 129.464731 -385.028144) (xy 129.506833 -385.058817)
			(xy 129.543612 -385.095705) (xy 129.574162 -385.137896) (xy 129.597729 -385.18435) (xy 129.613731 -385.233922)
			(xy 129.618232 -385.25958) (xy 129.619502 -385.268978) (xy 129.643438 -385.31038) (xy 130.160522 -385.31038)
			(xy 130.160957 -385.284389) (xy 130.169092 -385.233047) (xy 130.185159 -385.183609) (xy 130.208762 -385.137294)
			(xy 130.239319 -385.095241) (xy 130.276079 -385.058487) (xy 130.318137 -385.027935) (xy 130.364455 -385.00434)
			(xy 130.413895 -384.98828) (xy 130.465239 -384.980153) (xy 130.49123 -384.979672) (xy 130.517241 -384.980114)
			(xy 130.568619 -384.988278) (xy 130.618086 -385.004383) (xy 130.664422 -385.028032) (xy 130.706485 -385.058643)
			(xy 130.743237 -385.095461) (xy 130.773774 -385.137578) (xy 130.797342 -385.183956) (xy 130.813359 -385.233451)
			(xy 130.817874 -385.259072) (xy 130.819398 -385.26847) (xy 130.843624 -385.31038) (xy 131.360672 -385.31038)
			(xy 131.361183 -385.284393) (xy 131.369316 -385.23306) (xy 131.385378 -385.183631) (xy 131.408975 -385.137323)
			(xy 131.439525 -385.095276) (xy 131.476276 -385.058525) (xy 131.518323 -385.027975) (xy 131.564631 -385.004378)
			(xy 131.61406 -384.988316) (xy 131.665393 -384.980183) (xy 131.69138 -384.979672) (xy 131.717423 -384.980151)
			(xy 131.768863 -384.988336) (xy 131.818387 -385.004475) (xy 131.864772 -385.028171) (xy 131.906874 -385.058838)
			(xy 131.943655 -385.095719) (xy 131.974206 -385.137906) (xy 131.997773 -385.184356) (xy 132.013776 -385.233924)
			(xy 132.018278 -385.25958) (xy 132.019548 -385.268978) (xy 132.29209 -385.740402) (xy 132.299456 -385.746244)
			(xy 132.318249 -385.762028) (xy 132.351363 -385.79825) (xy 132.378769 -385.838963) (xy 132.399867 -385.883274)
			(xy 132.414195 -385.930213) (xy 132.421439 -385.978753) (xy 132.421884 -386.003292) (xy 132.42163 -386.015484)
			(xy 132.421376 -386.025136) (xy 132.427472 -386.04317) (xy 132.486146 -386.11048) (xy 132.50291 -386.119116)
			(xy 132.512816 -386.120132) (xy 132.53958 -386.123479) (xy 132.591603 -386.137703) (xy 132.640628 -386.160181)
			(xy 132.685358 -386.190314) (xy 132.724605 -386.227306) (xy 132.75733 -386.270176) (xy 132.782666 -386.317787)
			(xy 132.799941 -386.368879) (xy 132.808698 -386.422096) (xy 132.809234 -386.449062) (xy 132.808692 -386.476347)
			(xy 132.799738 -386.530176) (xy 132.782067 -386.581805) (xy 132.756159 -386.629832) (xy 132.722717 -386.672953)
			(xy 132.703062 -386.691886) (xy 132.695674 -386.699419) (xy 132.68714 -386.71869) (xy 132.686552 -386.729224)
			(xy 132.686552 -386.8039) (xy 132.687082 -386.814449) (xy 132.695618 -386.833744) (xy 132.703062 -386.841238)
			(xy 132.722707 -386.860179) (xy 132.756139 -386.903303) (xy 132.782042 -386.951329) (xy 132.799713 -387.002954)
			(xy 132.808673 -387.056779) (xy 132.809234 -387.084062) (xy 132.808787 -387.108178) (xy 132.80179 -387.155901)
			(xy 132.78794 -387.202102) (xy 132.767529 -387.245803) (xy 132.754624 -387.26618) (xy 132.748782 -387.27507)
			(xy 132.745226 -387.295136) (xy 132.766308 -387.387338) (xy 132.7785 -387.404102) (xy 132.78739 -387.409436)
			(xy 132.808181 -387.422307) (xy 132.846089 -387.453192) (xy 132.879033 -387.489324) (xy 132.906297 -387.529915)
			(xy 132.927284 -387.574078) (xy 132.941537 -387.620851) (xy 132.948745 -387.669214) (xy 132.949188 -387.693662)
			(xy 132.948771 -387.718035) (xy 132.941625 -387.766255) (xy 132.927482 -387.812905) (xy 132.906648 -387.856975)
			(xy 132.879574 -387.897512) (xy 132.846846 -387.933638) (xy 132.828284 -387.94944) (xy 132.819394 -387.956552)
			(xy 132.809996 -387.97611) (xy 132.807202 -388.075424) (xy 132.815838 -388.09549) (xy 132.82422 -388.10311)
			(xy 132.842662 -388.120579) (xy 132.874011 -388.160547) (xy 132.89831 -388.205154) (xy 132.914888 -388.253168)
			(xy 132.923288 -388.303264) (xy 132.923788 -388.328662) (xy 132.923684 -388.339943) (xy 132.922033 -388.362445)
			(xy 132.920486 -388.37362) (xy 132.919216 -388.38251) (xy 132.922772 -388.400036) (xy 132.966206 -388.470902)
			(xy 132.979922 -388.482078) (xy 132.988558 -388.484872) (xy 133.010804 -388.492806) (xy 133.052725 -388.514557)
			(xy 133.090798 -388.542502) (xy 133.124116 -388.575975) (xy 133.151885 -388.614177) (xy 133.163056 -388.634986)
			(xy 133.163564 -388.636002) (xy 133.555994 -389.314944) (xy 133.568805 -389.338283) (xy 133.587029 -389.388303)
			(xy 133.596295 -389.440726) (xy 133.596888 -389.467344) (xy 133.596501 -389.491352) (xy 133.58898 -389.538775)
			(xy 133.574128 -389.584437) (xy 133.552314 -389.627212) (xy 133.524073 -389.666045) (xy 133.490103 -389.69998)
			(xy 133.45124 -389.72818) (xy 133.408443 -389.74995) (xy 133.362766 -389.764754) (xy 133.315334 -389.772226)
			(xy 133.291326 -389.772652) (xy 133.267793 -389.772228) (xy 133.221285 -389.765017) (xy 133.176436 -389.750745)
			(xy 133.134312 -389.729752) (xy 133.095914 -389.702537) (xy 133.062153 -389.669746) (xy 133.03383 -389.632157)
			(xy 133.02234 -389.611616) (xy 133.022086 -389.611108) (xy 133.021578 -389.610346) (xy 132.623814 -388.922006)
			(xy 132.611935 -388.899331) (xy 132.595086 -388.850997) (xy 132.586514 -388.800533) (xy 132.585968 -388.77494)
			(xy 132.585968 -388.774432) (xy 132.58606 -388.763087) (xy 132.587714 -388.740458) (xy 132.58927 -388.72922)
			(xy 132.59054 -388.72033) (xy 132.586984 -388.703058) (xy 132.54355 -388.631938) (xy 132.52958 -388.621016)
			(xy 132.521198 -388.617968) (xy 132.498786 -388.609961) (xy 132.456569 -388.587996) (xy 132.418274 -388.559743)
			(xy 132.384829 -388.525887) (xy 132.357047 -388.48725) (xy 132.335599 -388.444767) (xy 132.321007 -388.39947)
			(xy 132.313625 -388.352457) (xy 132.313172 -388.328662) (xy 132.313707 -388.303268) (xy 132.322115 -388.253179)
			(xy 132.338694 -388.205172) (xy 132.362986 -388.160569) (xy 132.394321 -388.1206) (xy 132.41274 -388.10311)
			(xy 132.421122 -388.09549) (xy 132.429758 -388.075424) (xy 132.426964 -387.97611) (xy 132.417566 -387.956552)
			(xy 132.408676 -387.94944) (xy 132.390144 -387.933607) (xy 132.357421 -387.897483) (xy 132.33035 -387.856951)
			(xy 132.309515 -387.812888) (xy 132.295366 -387.766245) (xy 132.28821 -387.718032) (xy 132.287772 -387.693662)
			(xy 132.288182 -387.669544) (xy 132.29519 -387.621821) (xy 132.309051 -387.57562) (xy 132.329472 -387.53192)
			(xy 132.342382 -387.511544) (xy 132.348224 -387.502654) (xy 132.35178 -387.482588) (xy 132.330698 -387.390386)
			(xy 132.318506 -387.373622) (xy 132.309616 -387.368288) (xy 132.288837 -387.355398) (xy 132.250929 -387.324517)
			(xy 132.217984 -387.288388) (xy 132.190719 -387.247801) (xy 132.16973 -387.20364) (xy 132.155474 -387.156869)
			(xy 132.148263 -387.108509) (xy 132.147818 -387.084062) (xy 132.148359 -387.056777) (xy 132.157311 -387.002946)
			(xy 132.174981 -386.951317) (xy 132.20089 -386.90329) (xy 132.234334 -386.86017) (xy 132.25399 -386.841238)
			(xy 132.261375 -386.833703) (xy 132.269909 -386.814433) (xy 132.2705 -386.8039) (xy 132.2705 -386.729224)
			(xy 132.269971 -386.718674) (xy 132.261436 -386.699379) (xy 132.25399 -386.691886) (xy 132.234366 -386.672924)
			(xy 132.200929 -386.629807) (xy 132.175021 -386.581786) (xy 132.157346 -386.530165) (xy 132.148381 -386.476344)
			(xy 132.147818 -386.449062) (xy 132.148072 -386.43687) (xy 132.148326 -386.427218) (xy 132.14223 -386.409184)
			(xy 132.083556 -386.341874) (xy 132.066792 -386.333238) (xy 132.056886 -386.332222) (xy 132.029982 -386.32883)
			(xy 131.977697 -386.31447) (xy 131.928453 -386.291775) (xy 131.88357 -386.261353) (xy 131.84425 -386.224019)
			(xy 131.811544 -386.180771) (xy 131.78633 -386.132769) (xy 131.769282 -386.081297) (xy 131.764532 -386.0546)
			(xy 131.763008 -386.045202) (xy 131.489958 -385.572762) (xy 131.482846 -385.56692) (xy 131.464103 -385.551152)
			(xy 131.431051 -385.515007) (xy 131.403697 -385.474378) (xy 131.38264 -385.430157) (xy 131.368342 -385.383312)
			(xy 131.361114 -385.334869) (xy 131.360672 -385.31038) (xy 130.843624 -385.31038) (xy 131.092194 -385.740402)
			(xy 131.09956 -385.746244) (xy 131.118354 -385.762027) (xy 131.151468 -385.79825) (xy 131.178874 -385.838962)
			(xy 131.199972 -385.883274) (xy 131.214299 -385.930213) (xy 131.221543 -385.978753) (xy 131.221988 -386.003292)
			(xy 131.221734 -386.015484) (xy 131.22148 -386.025136) (xy 131.227576 -386.04317) (xy 131.28625 -386.11048)
			(xy 131.303014 -386.119116) (xy 131.31292 -386.120132) (xy 131.339684 -386.123475) (xy 131.391707 -386.1377)
			(xy 131.440733 -386.160178) (xy 131.485462 -386.190312) (xy 131.52471 -386.227305) (xy 131.557435 -386.270175)
			(xy 131.582771 -386.317787) (xy 131.600046 -386.368878) (xy 131.608803 -386.422096) (xy 131.609338 -386.449062)
			(xy 131.608795 -386.476347) (xy 131.599841 -386.530176) (xy 131.58217 -386.581805) (xy 131.556263 -386.629832)
			(xy 131.522821 -386.672953) (xy 131.503166 -386.691886) (xy 131.495778 -386.69942) (xy 131.487244 -386.71869)
			(xy 131.486656 -386.729224) (xy 131.486656 -386.8039) (xy 131.487185 -386.814449) (xy 131.495722 -386.833744)
			(xy 131.503166 -386.841238) (xy 131.522812 -386.860178) (xy 131.556244 -386.903303) (xy 131.582146 -386.951329)
			(xy 131.599817 -387.002954) (xy 131.608777 -387.056779) (xy 131.609338 -387.084062) (xy 131.60889 -387.108178)
			(xy 131.601894 -387.1559) (xy 131.588043 -387.202101) (xy 131.567633 -387.245802) (xy 131.554728 -387.26618)
			(xy 131.548886 -387.27507) (xy 131.54533 -387.295136) (xy 131.566412 -387.387338) (xy 131.578604 -387.404102)
			(xy 131.587494 -387.409436) (xy 131.608286 -387.422306) (xy 131.646193 -387.453191) (xy 131.679138 -387.489323)
			(xy 131.706401 -387.529914) (xy 131.727388 -387.574078) (xy 131.741641 -387.620851) (xy 131.748849 -387.669214)
			(xy 131.749292 -387.693662) (xy 131.748874 -387.718035) (xy 131.741728 -387.766255) (xy 131.727585 -387.812905)
			(xy 131.706751 -387.856975) (xy 131.679678 -387.897512) (xy 131.64695 -387.933638) (xy 131.628388 -387.94944)
			(xy 131.619498 -387.956552) (xy 131.6101 -387.97611) (xy 131.607306 -388.075424) (xy 131.615942 -388.09549)
			(xy 131.624324 -388.10311) (xy 131.642767 -388.120578) (xy 131.674116 -388.160547) (xy 131.698414 -388.205153)
			(xy 131.714992 -388.253168) (xy 131.723392 -388.303264) (xy 131.723892 -388.328662) (xy 131.723788 -388.339943)
			(xy 131.722137 -388.362445) (xy 131.72059 -388.37362) (xy 131.71932 -388.382764) (xy 131.722622 -388.400036)
			(xy 131.76631 -388.471156) (xy 131.780026 -388.482078) (xy 131.788662 -388.484872) (xy 131.816825 -388.495074)
			(xy 131.868772 -388.524882) (xy 131.891786 -388.544054) (xy 131.913269 -388.563637) (xy 131.949083 -388.609414)
			(xy 131.962906 -388.634986) (xy 131.963668 -388.636256) (xy 132.355844 -389.314944) (xy 132.36858 -389.338308)
			(xy 132.386693 -389.388337) (xy 132.395902 -389.440741) (xy 132.396484 -389.467344) (xy 132.396078 -389.491338)
			(xy 132.388564 -389.538733) (xy 132.37373 -389.58437) (xy 132.351938 -389.627124) (xy 132.323728 -389.665943)
			(xy 132.289792 -389.699872) (xy 132.250966 -389.728074) (xy 132.208207 -389.749856) (xy 132.162567 -389.76468)
			(xy 132.11517 -389.772183) (xy 132.091176 -389.772652) (xy 132.067645 -389.772188) (xy 132.021138 -389.764984)
			(xy 131.97629 -389.750719) (xy 131.934166 -389.729734) (xy 131.895767 -389.702525) (xy 131.862005 -389.669739)
			(xy 131.833681 -389.632155) (xy 131.82219 -389.611616) (xy 131.821936 -389.611108) (xy 131.821428 -389.610346)
			(xy 131.423918 -388.921752) (xy 131.413346 -388.901825) (xy 131.397543 -388.859576) (xy 131.388135 -388.815459)
			(xy 131.386326 -388.792974) (xy 131.385818 -388.781798) (xy 131.385564 -388.774432) (xy 131.385722 -388.763083)
			(xy 131.387498 -388.740454) (xy 131.38912 -388.72922) (xy 131.39039 -388.72033) (xy 131.386834 -388.703058)
			(xy 131.3434 -388.631938) (xy 131.329684 -388.620762) (xy 131.321048 -388.617968) (xy 131.298641 -388.609985)
			(xy 131.256471 -388.587978) (xy 131.218224 -388.559699) (xy 131.184825 -388.52583) (xy 131.157082 -388.487191)
			(xy 131.135667 -388.444718) (xy 131.121098 -388.399438) (xy 131.113727 -388.352445) (xy 131.113276 -388.328662)
			(xy 131.11381 -388.303268) (xy 131.122218 -388.253179) (xy 131.138797 -388.205172) (xy 131.163089 -388.160569)
			(xy 131.194425 -388.1206) (xy 131.212844 -388.10311) (xy 131.221226 -388.09549) (xy 131.229862 -388.075424)
			(xy 131.227068 -387.97611) (xy 131.21767 -387.956552) (xy 131.20878 -387.94944) (xy 131.190248 -387.933606)
			(xy 131.157526 -387.897482) (xy 131.130454 -387.85695) (xy 131.109619 -387.812887) (xy 131.09547 -387.766245)
			(xy 131.088314 -387.718032) (xy 131.087876 -387.693662) (xy 131.088286 -387.669544) (xy 131.095293 -387.62182)
			(xy 131.109155 -387.575619) (xy 131.129576 -387.53192) (xy 131.142486 -387.511544) (xy 131.148328 -387.502654)
			(xy 131.151884 -387.482588) (xy 131.130802 -387.390386) (xy 131.11861 -387.373622) (xy 131.10972 -387.368288)
			(xy 131.088942 -387.355397) (xy 131.051034 -387.324515) (xy 131.018088 -387.288387) (xy 130.990823 -387.2478)
			(xy 130.969834 -387.20364) (xy 130.955578 -387.156869) (xy 130.948367 -387.108509) (xy 130.947922 -387.084062)
			(xy 130.948462 -387.056777) (xy 130.957413 -387.002946) (xy 130.975084 -386.951317) (xy 131.000993 -386.90329)
			(xy 131.034438 -386.86017) (xy 131.054094 -386.841238) (xy 131.06148 -386.833703) (xy 131.070013 -386.814433)
			(xy 131.070604 -386.8039) (xy 131.070604 -386.729224) (xy 131.070074 -386.718674) (xy 131.061539 -386.699379)
			(xy 131.054094 -386.691886) (xy 131.034471 -386.672923) (xy 131.001034 -386.629806) (xy 130.975126 -386.581786)
			(xy 130.95745 -386.530165) (xy 130.948485 -386.476344) (xy 130.947922 -386.449062) (xy 130.948176 -386.43687)
			(xy 130.94843 -386.427218) (xy 130.942334 -386.409184) (xy 130.88366 -386.341874) (xy 130.866896 -386.333238)
			(xy 130.85699 -386.332222) (xy 130.830087 -386.328827) (xy 130.777801 -386.314467) (xy 130.728558 -386.291773)
			(xy 130.683675 -386.261352) (xy 130.644354 -386.224017) (xy 130.611649 -386.18077) (xy 130.586434 -386.132768)
			(xy 130.569386 -386.081297) (xy 130.564636 -386.0546) (xy 130.563112 -386.045202) (xy 130.290316 -385.57327)
			(xy 130.28295 -385.567428) (xy 130.264193 -385.551603) (xy 130.231076 -385.51539) (xy 130.203665 -385.474686)
			(xy 130.182561 -385.430383) (xy 130.168225 -385.38345) (xy 130.160972 -385.334916) (xy 130.160522 -385.31038)
			(xy 129.643438 -385.31038) (xy 129.892044 -385.740402) (xy 129.89941 -385.746244) (xy 129.918194 -385.762039)
			(xy 129.951311 -385.798258) (xy 129.978719 -385.838967) (xy 129.999819 -385.883277) (xy 130.014148 -385.930215)
			(xy 130.021393 -385.978754) (xy 130.021838 -386.003292) (xy 130.021584 -386.015484) (xy 130.02133 -386.025136)
			(xy 130.027426 -386.04317) (xy 130.0861 -386.11048) (xy 130.102864 -386.119116) (xy 130.11277 -386.120132)
			(xy 130.139529 -386.123516) (xy 130.191551 -386.137734) (xy 130.240577 -386.160205) (xy 130.285307 -386.190333)
			(xy 130.324555 -386.22732) (xy 130.357282 -386.270186) (xy 130.382619 -386.317794) (xy 130.399895 -386.368882)
			(xy 130.408652 -386.422097) (xy 130.409188 -386.449062) (xy 130.408661 -386.476348) (xy 130.399706 -386.530179)
			(xy 130.382032 -386.581808) (xy 130.35612 -386.629835) (xy 130.322673 -386.672954) (xy 130.303016 -386.691886)
			(xy 130.295621 -386.699413) (xy 130.287092 -386.718689) (xy 130.286506 -386.729224) (xy 130.286506 -386.8039)
			(xy 130.28702 -386.814451) (xy 130.295566 -386.833747) (xy 130.303016 -386.841238) (xy 130.322652 -386.860187)
			(xy 130.356088 -386.903308) (xy 130.381993 -386.951332) (xy 130.399666 -387.002955) (xy 130.408627 -387.05678)
			(xy 130.409188 -387.084062) (xy 130.408732 -387.108178) (xy 130.401737 -387.155899) (xy 130.387888 -387.2021)
			(xy 130.367481 -387.245802) (xy 130.354578 -387.26618) (xy 130.348736 -387.27507) (xy 130.34518 -387.295136)
			(xy 130.366262 -387.387338) (xy 130.378454 -387.404102) (xy 130.387344 -387.409436) (xy 130.408147 -387.422287)
			(xy 130.446052 -387.453178) (xy 130.478994 -387.489314) (xy 130.506255 -387.529908) (xy 130.52724 -387.574074)
			(xy 130.541492 -387.620849) (xy 130.548699 -387.669213) (xy 130.549142 -387.693662) (xy 130.548706 -387.718034)
			(xy 130.541561 -387.766253) (xy 130.52742 -387.812901) (xy 130.50659 -387.856971) (xy 130.47952 -387.897508)
			(xy 130.446797 -387.933636) (xy 130.428238 -387.94944) (xy 130.419348 -387.956552) (xy 130.40995 -387.97611)
			(xy 130.407156 -388.075424) (xy 130.415792 -388.09549) (xy 130.424174 -388.10311) (xy 130.442627 -388.120568)
			(xy 130.473972 -388.16054) (xy 130.498268 -388.20515) (xy 130.514844 -388.253166) (xy 130.523243 -388.303264)
			(xy 130.523742 -388.328662) (xy 130.523639 -388.339943) (xy 130.521987 -388.362445) (xy 130.52044 -388.37362)
			(xy 130.51917 -388.38251) (xy 130.522726 -388.400036) (xy 130.56616 -388.470902) (xy 130.579876 -388.482078)
			(xy 130.588512 -388.484872) (xy 130.610767 -388.492781) (xy 130.652687 -388.514539) (xy 130.690759 -388.54249)
			(xy 130.724075 -388.575968) (xy 130.751841 -388.614174) (xy 130.76301 -388.634986) (xy 130.763518 -388.636002)
			(xy 131.155948 -389.314944) (xy 131.168684 -389.338308) (xy 131.186797 -389.388337) (xy 131.196006 -389.440741)
			(xy 131.196588 -389.467344) (xy 131.196178 -389.491337) (xy 131.188665 -389.538733) (xy 131.17383 -389.584369)
			(xy 131.152039 -389.627123) (xy 131.123829 -389.665942) (xy 131.089893 -389.69987) (xy 131.051068 -389.728073)
			(xy 131.00831 -389.749854) (xy 130.96267 -389.76468) (xy 130.915274 -389.772183) (xy 130.89128 -389.772652)
			(xy 130.867749 -389.772185) (xy 130.821242 -389.764981) (xy 130.776394 -389.750717) (xy 130.734271 -389.729732)
			(xy 130.695872 -389.702524) (xy 130.662109 -389.669738) (xy 130.633785 -389.632155) (xy 130.622294 -389.611616)
			(xy 130.62204 -389.611108) (xy 130.621532 -389.610346) (xy 130.223768 -388.922006) (xy 130.211858 -388.899335)
			(xy 130.194918 -388.851011) (xy 130.186256 -388.800542) (xy 130.185668 -388.77494) (xy 130.185668 -388.774432)
			(xy 130.185826 -388.763083) (xy 130.187602 -388.740454) (xy 130.189224 -388.72922) (xy 130.190494 -388.72033)
			(xy 130.186938 -388.703058) (xy 130.143504 -388.631938) (xy 130.129534 -388.621016) (xy 130.121152 -388.617968)
			(xy 130.098752 -388.60993) (xy 130.056533 -388.587972) (xy 130.018236 -388.559725) (xy 129.98479 -388.525874)
			(xy 129.957005 -388.487241) (xy 129.935556 -388.444761) (xy 129.920963 -388.399467) (xy 129.913579 -388.352456)
			(xy 129.913126 -388.328662) (xy 129.913643 -388.303267) (xy 129.922053 -388.253177) (xy 129.938635 -388.205169)
			(xy 129.962931 -388.160566) (xy 129.994273 -388.120598) (xy 130.012694 -388.10311) (xy 130.021076 -388.09549)
			(xy 130.029712 -388.075424) (xy 130.026918 -387.97611) (xy 130.01752 -387.956552) (xy 130.00863 -387.94944)
			(xy 129.990088 -387.933617) (xy 129.957369 -387.89749) (xy 129.9303 -387.856955) (xy 129.909466 -387.81289)
			(xy 129.895319 -387.766247) (xy 129.888164 -387.718033) (xy 129.887726 -387.693662) (xy 129.888144 -387.669545)
			(xy 129.89515 -387.621822) (xy 129.909009 -387.575621) (xy 129.929428 -387.531921) (xy 129.942336 -387.511544)
			(xy 129.948178 -387.502654) (xy 129.951734 -387.482588) (xy 129.930652 -387.390386) (xy 129.91846 -387.373622)
			(xy 129.90957 -387.368288) (xy 129.888781 -387.355415) (xy 129.850875 -387.324529) (xy 129.817932 -387.288396)
			(xy 129.790669 -387.247806) (xy 129.769682 -387.203643) (xy 129.755427 -387.156871) (xy 129.748217 -387.10851)
			(xy 129.747772 -387.084062) (xy 129.748328 -387.056778) (xy 129.757278 -387.002949) (xy 129.774945 -386.95132)
			(xy 129.800851 -386.903293) (xy 129.83429 -386.860171) (xy 129.853944 -386.841238) (xy 129.861323 -386.833697)
			(xy 129.869862 -386.814432) (xy 129.870454 -386.8039) (xy 129.870454 -386.729224) (xy 129.869939 -386.718672)
			(xy 129.861395 -386.699376) (xy 129.853944 -386.691886) (xy 129.834312 -386.672933) (xy 129.800878 -386.629812)
			(xy 129.774973 -386.581789) (xy 129.757299 -386.530167) (xy 129.748335 -386.476344) (xy 129.747772 -386.449062)
			(xy 129.748026 -386.43687) (xy 129.74828 -386.427218) (xy 129.742184 -386.409184) (xy 129.68351 -386.341874)
			(xy 129.666746 -386.333238) (xy 129.65684 -386.332222) (xy 129.629931 -386.328867) (xy 129.577645 -386.314499)
			(xy 129.528401 -386.291798) (xy 129.483519 -386.26137) (xy 129.4442 -386.224031) (xy 129.411496 -386.180779)
			(xy 129.386283 -386.132773) (xy 129.369236 -386.081298) (xy 129.364486 -386.0546) (xy 129.362962 -386.045202)
			(xy 129.089912 -385.572762) (xy 129.0828 -385.56692) (xy 129.064069 -385.551139) (xy 129.031014 -385.514998)
			(xy 129.003657 -385.474373) (xy 128.982597 -385.430154) (xy 128.968297 -385.38331) (xy 128.961069 -385.334869)
			(xy 128.960626 -385.31038) (xy 128.443578 -385.31038) (xy 128.692148 -385.740402) (xy 128.699514 -385.746244)
			(xy 128.718298 -385.762038) (xy 128.751415 -385.798257) (xy 128.778823 -385.838967) (xy 128.799923 -385.883276)
			(xy 128.814252 -385.930215) (xy 128.821497 -385.978754) (xy 128.821942 -386.003292) (xy 128.821688 -386.015484)
			(xy 128.821434 -386.025136) (xy 128.82753 -386.04317) (xy 128.886204 -386.11048) (xy 128.902968 -386.119116)
			(xy 128.912874 -386.120132) (xy 128.939633 -386.123513) (xy 128.991656 -386.137731) (xy 129.040682 -386.160202)
			(xy 129.085411 -386.190331) (xy 129.12466 -386.227319) (xy 129.157386 -386.270185) (xy 129.182723 -386.317793)
			(xy 129.199999 -386.368882) (xy 129.208756 -386.422097) (xy 129.209292 -386.449062) (xy 129.208763 -386.476347)
			(xy 129.199808 -386.530178) (xy 129.182135 -386.581808) (xy 129.156223 -386.629835) (xy 129.122777 -386.672954)
			(xy 129.10312 -386.691886) (xy 129.095725 -386.699414) (xy 129.087196 -386.718689) (xy 129.08661 -386.729224)
			(xy 129.08661 -386.8039) (xy 129.087123 -386.814452) (xy 129.095669 -386.833747) (xy 129.10312 -386.841238)
			(xy 129.122757 -386.860187) (xy 129.156192 -386.903308) (xy 129.182097 -386.951331) (xy 129.19977 -387.002955)
			(xy 129.208731 -387.05678) (xy 129.209292 -387.084062) (xy 129.208835 -387.108178) (xy 129.20184 -387.155899)
			(xy 129.187992 -387.2021) (xy 129.167585 -387.245802) (xy 129.154682 -387.26618) (xy 129.14884 -387.27507)
			(xy 129.145284 -387.295136) (xy 129.166366 -387.387338) (xy 129.178558 -387.404102) (xy 129.187448 -387.409436)
			(xy 129.208252 -387.422286) (xy 129.246157 -387.453177) (xy 129.279099 -387.489313) (xy 129.30636 -387.529908)
			(xy 129.327344 -387.574074) (xy 129.341596 -387.620849) (xy 129.348803 -387.669213) (xy 129.349246 -387.693662)
			(xy 129.348845 -387.718036) (xy 129.341698 -387.766257) (xy 129.327552 -387.812908) (xy 129.306716 -387.856979)
			(xy 129.279638 -387.897515) (xy 129.246906 -387.933639) (xy 129.228342 -387.94944) (xy 129.219452 -387.956552)
			(xy 129.210054 -387.97611) (xy 129.20726 -388.075424) (xy 129.215896 -388.09549) (xy 129.224278 -388.10311)
			(xy 129.242731 -388.120567) (xy 129.274076 -388.16054) (xy 129.298372 -388.20515) (xy 129.314948 -388.253166)
			(xy 129.323347 -388.303264) (xy 129.323846 -388.328662) (xy 129.323743 -388.339943) (xy 129.322091 -388.362445)
			(xy 129.320544 -388.37362) (xy 129.319274 -388.382764) (xy 129.322576 -388.400036) (xy 129.366264 -388.471156)
			(xy 129.37998 -388.482078) (xy 129.388616 -388.484872) (xy 129.416784 -388.495061) (xy 129.468728 -388.524878)
			(xy 129.49174 -388.544054) (xy 129.513229 -388.56363) (xy 129.549039 -388.609413) (xy 129.56286 -388.634986)
			(xy 129.563622 -388.636256) (xy 129.955798 -389.314944) (xy 129.968601 -389.338288) (xy 129.98683 -389.388305)
			(xy 129.996099 -389.440727) (xy 129.996692 -389.467344) (xy 129.996301 -389.491352) (xy 129.98878 -389.538775)
			(xy 129.973929 -389.584436) (xy 129.952114 -389.627211) (xy 129.923874 -389.666044) (xy 129.889905 -389.699979)
			(xy 129.851042 -389.728179) (xy 129.808246 -389.749949) (xy 129.762569 -389.764753) (xy 129.715138 -389.772226)
			(xy 129.69113 -389.772652) (xy 129.667598 -389.772225) (xy 129.621089 -389.765014) (xy 129.57624 -389.750743)
			(xy 129.534116 -389.729751) (xy 129.495718 -389.702536) (xy 129.461957 -389.669746) (xy 129.433634 -389.632157)
			(xy 129.422144 -389.611616) (xy 129.42189 -389.611108) (xy 129.421382 -389.610346) (xy 129.023872 -388.921752)
			(xy 129.013296 -388.901827) (xy 128.997495 -388.859576) (xy 128.988089 -388.815459) (xy 128.98628 -388.792974)
			(xy 128.985772 -388.781798) (xy 128.985772 -388.774432) (xy 128.985864 -388.763087) (xy 128.987518 -388.740458)
			(xy 128.989074 -388.72922) (xy 128.990344 -388.72033) (xy 128.986788 -388.703058) (xy 128.943354 -388.631938)
			(xy 128.929638 -388.620762) (xy 128.921002 -388.617968) (xy 128.898606 -388.609954) (xy 128.856435 -388.587955)
			(xy 128.818186 -388.559681) (xy 128.784784 -388.525817) (xy 128.75704 -388.487183) (xy 128.735623 -388.444712)
			(xy 128.721053 -388.399434) (xy 128.713681 -388.352444) (xy 128.71323 -388.328662) (xy 128.713746 -388.303267)
			(xy 128.722156 -388.253177) (xy 128.738738 -388.205169) (xy 128.763035 -388.160566) (xy 128.794376 -388.120598)
			(xy 128.812798 -388.10311) (xy 128.82118 -388.09549) (xy 128.829816 -388.075424) (xy 128.827022 -387.97611)
			(xy 128.817624 -387.956552) (xy 128.808734 -387.94944) (xy 128.790193 -387.933617) (xy 128.757473 -387.897489)
			(xy 128.730404 -387.856955) (xy 128.709571 -387.81289) (xy 128.695423 -387.766247) (xy 128.688268 -387.718033)
			(xy 128.68783 -387.693662) (xy 128.688247 -387.669545) (xy 128.695254 -387.621821) (xy 128.709113 -387.575621)
			(xy 128.729532 -387.531921) (xy 128.74244 -387.511544) (xy 128.748282 -387.502654) (xy 128.751838 -387.482588)
			(xy 128.730756 -387.390386) (xy 128.718564 -387.373622) (xy 128.709674 -387.368288) (xy 128.688886 -387.355414)
			(xy 128.65098 -387.324527) (xy 128.618036 -387.288395) (xy 128.590773 -387.247806) (xy 128.569786 -387.203643)
			(xy 128.555531 -387.156871) (xy 128.548321 -387.10851) (xy 128.547876 -387.084062) (xy 128.54843 -387.056778)
			(xy 128.557381 -387.002948) (xy 128.575048 -386.95132) (xy 128.600954 -386.903292) (xy 128.634394 -386.860171)
			(xy 128.654048 -386.841238) (xy 128.661427 -386.833697) (xy 128.669966 -386.814432) (xy 128.670558 -386.8039)
			(xy 128.670558 -386.729224) (xy 128.670042 -386.718673) (xy 128.661499 -386.699377) (xy 128.654048 -386.691886)
			(xy 128.634416 -386.672932) (xy 128.600982 -386.629811) (xy 128.575077 -386.581789) (xy 128.557403 -386.530167)
			(xy 128.548439 -386.476344) (xy 128.547876 -386.449062) (xy 128.54813 -386.43687) (xy 128.548384 -386.427218)
			(xy 128.542288 -386.409184) (xy 128.483614 -386.341874) (xy 128.46685 -386.333238) (xy 128.456944 -386.332222)
			(xy 128.430035 -386.328863) (xy 128.377749 -386.314497) (xy 128.328506 -386.291796) (xy 128.283624 -386.261369)
			(xy 128.244304 -386.22403) (xy 128.2116 -386.180778) (xy 128.186387 -386.132773) (xy 128.16934 -386.081298)
			(xy 128.16459 -386.0546) (xy 128.163066 -386.045202) (xy 127.89027 -385.57327) (xy 127.882904 -385.567428)
			(xy 127.864158 -385.55159) (xy 127.831038 -385.515381) (xy 127.803625 -385.47468) (xy 127.782518 -385.430379)
			(xy 127.768181 -385.383449) (xy 127.760927 -385.334916) (xy 127.760476 -385.31038) (xy 127.243682 -385.31038)
			(xy 127.492252 -385.740402) (xy 127.499618 -385.746244) (xy 127.518403 -385.762037) (xy 127.55152 -385.798256)
			(xy 127.578928 -385.838967) (xy 127.600027 -385.883276) (xy 127.614356 -385.930214) (xy 127.621601 -385.978754)
			(xy 127.622046 -386.003292) (xy 127.621792 -386.015484) (xy 127.621538 -386.025136) (xy 127.627634 -386.04317)
			(xy 127.686308 -386.11048) (xy 127.703072 -386.119116) (xy 127.712724 -386.120132) (xy 127.739489 -386.123472)
			(xy 127.791512 -386.137698) (xy 127.840538 -386.160176) (xy 127.885267 -386.190311) (xy 127.924514 -386.227304)
			(xy 127.957239 -386.270174) (xy 127.982575 -386.317786) (xy 127.99985 -386.368878) (xy 128.008607 -386.422095)
			(xy 128.009142 -386.449062) (xy 128.008598 -386.476347) (xy 127.999644 -386.530176) (xy 127.981974 -386.581805)
			(xy 127.956066 -386.629832) (xy 127.922624 -386.672953) (xy 127.90297 -386.691886) (xy 127.895583 -386.69942)
			(xy 127.887048 -386.71869) (xy 127.88646 -386.729224) (xy 127.88646 -386.8039) (xy 127.886988 -386.81445)
			(xy 127.895525 -386.833744) (xy 127.90297 -386.841238) (xy 127.922616 -386.860177) (xy 127.956048 -386.903302)
			(xy 127.98195 -386.951328) (xy 127.999621 -387.002954) (xy 128.008581 -387.056779) (xy 128.009142 -387.084062)
			(xy 128.008693 -387.108178) (xy 128.001697 -387.1559) (xy 127.987847 -387.202101) (xy 127.967437 -387.245802)
			(xy 127.954532 -387.26618) (xy 127.94869 -387.27507) (xy 127.945134 -387.295136) (xy 127.966216 -387.387338)
			(xy 127.978408 -387.404102) (xy 127.987298 -387.409436) (xy 128.008091 -387.422304) (xy 128.045998 -387.45319)
			(xy 128.078942 -387.489323) (xy 128.106205 -387.529914) (xy 128.127192 -387.574078) (xy 128.141445 -387.620851)
			(xy 128.148653 -387.669214) (xy 128.149096 -387.693662) (xy 128.148676 -387.718035) (xy 128.141531 -387.766255)
			(xy 128.127388 -387.812905) (xy 128.106554 -387.856975) (xy 128.079481 -387.897511) (xy 128.046754 -387.933638)
			(xy 128.028192 -387.94944) (xy 128.019302 -387.956552) (xy 128.009904 -387.97611) (xy 128.00711 -388.075424)
			(xy 128.015746 -388.09549) (xy 128.024128 -388.10311) (xy 128.042572 -388.120577) (xy 128.07392 -388.160546)
			(xy 128.098218 -388.205153) (xy 128.114796 -388.253168) (xy 128.123196 -388.303264) (xy 128.123696 -388.328662)
			(xy 128.123592 -388.339943) (xy 128.121941 -388.362445) (xy 128.120394 -388.37362) (xy 128.119124 -388.38251)
			(xy 128.12268 -388.400036) (xy 128.166114 -388.470902) (xy 128.17983 -388.482078) (xy 128.188466 -388.484872)
			(xy 128.210713 -388.492803) (xy 128.252634 -388.514555) (xy 128.290707 -388.5425) (xy 128.324025 -388.575974)
			(xy 128.351793 -388.614176) (xy 128.362964 -388.634986) (xy 128.363472 -388.636002) (xy 128.755902 -389.314944)
			(xy 128.768705 -389.338288) (xy 128.786934 -389.388305) (xy 128.796203 -389.440727) (xy 128.796796 -389.467344)
			(xy 128.796401 -389.491352) (xy 128.78888 -389.538774) (xy 128.774029 -389.584435) (xy 128.752215 -389.627209)
			(xy 128.723975 -389.666042) (xy 128.690006 -389.699977) (xy 128.651145 -389.728177) (xy 128.608348 -389.749948)
			(xy 128.562672 -389.764752) (xy 128.515242 -389.772226) (xy 128.491234 -389.772652) (xy 128.467702 -389.772222)
			(xy 128.421193 -389.765011) (xy 128.376344 -389.750741) (xy 128.334221 -389.729749) (xy 128.295822 -389.702535)
			(xy 128.262061 -389.669745) (xy 128.233738 -389.632157) (xy 128.222248 -389.611616) (xy 128.221994 -389.611108)
			(xy 128.221486 -389.610346) (xy 127.823722 -388.922006) (xy 127.811843 -388.899331) (xy 127.794994 -388.850996)
			(xy 127.786422 -388.800533) (xy 127.785876 -388.77494) (xy 127.785876 -388.774432) (xy 127.785968 -388.763087)
			(xy 127.787622 -388.740458) (xy 127.789178 -388.72922) (xy 127.790448 -388.72033) (xy 127.786892 -388.703058)
			(xy 127.743458 -388.631938) (xy 127.729488 -388.621016) (xy 127.721106 -388.617968) (xy 127.698696 -388.609956)
			(xy 127.656479 -388.587992) (xy 127.618183 -388.55974) (xy 127.584739 -388.525885) (xy 127.556956 -388.487248)
			(xy 127.535508 -388.444766) (xy 127.520916 -388.399469) (xy 127.513533 -388.352457) (xy 127.51308 -388.328662)
			(xy 127.513612 -388.303267) (xy 127.522021 -388.253179) (xy 127.5386 -388.205172) (xy 127.562892 -388.160569)
			(xy 127.594229 -388.120599) (xy 127.612648 -388.10311) (xy 127.62103 -388.09549) (xy 127.629666 -388.075424)
			(xy 127.626872 -387.97611) (xy 127.617474 -387.956552) (xy 127.608584 -387.94944) (xy 127.590053 -387.933605)
			(xy 127.55733 -387.897481) (xy 127.530259 -387.85695) (xy 127.509423 -387.812887) (xy 127.495274 -387.766245)
			(xy 127.488118 -387.718032) (xy 127.48768 -387.693662) (xy 127.488089 -387.669544) (xy 127.495097 -387.62182)
			(xy 127.508958 -387.575619) (xy 127.52938 -387.53192) (xy 127.54229 -387.511544) (xy 127.548132 -387.502654)
			(xy 127.551688 -387.482588) (xy 127.530606 -387.390386) (xy 127.518414 -387.373622) (xy 127.509524 -387.368288)
			(xy 127.488724 -387.355432) (xy 127.450821 -387.324541) (xy 127.41788 -387.288405) (xy 127.390619 -387.247812)
			(xy 127.369634 -387.203647) (xy 127.355381 -387.156873) (xy 127.348171 -387.10851) (xy 127.347726 -387.084062)
			(xy 127.348265 -387.056777) (xy 127.357216 -387.002946) (xy 127.374887 -386.951316) (xy 127.400796 -386.903289)
			(xy 127.434242 -386.86017) (xy 127.453898 -386.841238) (xy 127.461284 -386.833704) (xy 127.469817 -386.814433)
			(xy 127.470408 -386.8039) (xy 127.470408 -386.729224) (xy 127.469877 -386.718675) (xy 127.461343 -386.699379)
			(xy 127.453898 -386.691886) (xy 127.434276 -386.672923) (xy 127.400838 -386.629806) (xy 127.37493 -386.581786)
			(xy 127.357254 -386.530165) (xy 127.348289 -386.476343) (xy 127.347726 -386.449062) (xy 127.34798 -386.43687)
			(xy 127.348234 -386.427218) (xy 127.342138 -386.409184) (xy 127.283464 -386.341874) (xy 127.2667 -386.333238)
			(xy 127.257048 -386.332222) (xy 127.23014 -386.32886) (xy 127.177854 -386.314494) (xy 127.12861 -386.291794)
			(xy 127.083728 -386.261367) (xy 127.044408 -386.224029) (xy 127.011704 -386.180778) (xy 126.986491 -386.132772)
			(xy 126.969444 -386.081298) (xy 126.964694 -386.0546) (xy 126.96317 -386.045202) (xy 126.690374 -385.57327)
			(xy 126.683008 -385.567428) (xy 126.664263 -385.551589) (xy 126.631143 -385.51538) (xy 126.603729 -385.47468)
			(xy 126.582622 -385.430379) (xy 126.568285 -385.383448) (xy 126.561031 -385.334916) (xy 126.56058 -385.31038)
			(xy 126.043532 -385.31038) (xy 126.292102 -385.740402) (xy 126.299468 -385.746244) (xy 126.318263 -385.762025)
			(xy 126.351377 -385.798248) (xy 126.378783 -385.838961) (xy 126.39988 -385.883273) (xy 126.414207 -385.930213)
			(xy 126.421451 -385.978753) (xy 126.421896 -386.003292) (xy 126.421642 -386.015484) (xy 126.421388 -386.025136)
			(xy 126.427484 -386.04317) (xy 126.486158 -386.11048) (xy 126.502922 -386.119116) (xy 126.512828 -386.120132)
			(xy 126.539593 -386.123468) (xy 126.591616 -386.137695) (xy 126.640642 -386.160174) (xy 126.685371 -386.190309)
			(xy 126.724618 -386.227302) (xy 126.757343 -386.270173) (xy 126.782679 -386.317785) (xy 126.799954 -386.368877)
			(xy 126.808711 -386.422095) (xy 126.809246 -386.449062) (xy 126.8087 -386.476347) (xy 126.799747 -386.530176)
			(xy 126.782077 -386.581805) (xy 126.756169 -386.629831) (xy 126.722728 -386.672953) (xy 126.703074 -386.691886)
			(xy 126.695687 -386.699421) (xy 126.687152 -386.71869) (xy 126.686564 -386.729224) (xy 126.686564 -386.8039)
			(xy 126.68709 -386.81445) (xy 126.695629 -386.833744) (xy 126.703074 -386.841238) (xy 126.722721 -386.860176)
			(xy 126.756153 -386.903302) (xy 126.782055 -386.951328) (xy 126.799725 -387.002954) (xy 126.808685 -387.056779)
			(xy 126.809246 -387.084062) (xy 126.808797 -387.108178) (xy 126.8018 -387.1559) (xy 126.787951 -387.202101)
			(xy 126.767541 -387.245802) (xy 126.754636 -387.26618) (xy 126.748794 -387.27507) (xy 126.745238 -387.295136)
			(xy 126.76632 -387.387338) (xy 126.778512 -387.404102) (xy 126.787402 -387.409436) (xy 126.808196 -387.422303)
			(xy 126.846103 -387.453189) (xy 126.879047 -387.489322) (xy 126.90631 -387.529913) (xy 126.927296 -387.574077)
			(xy 126.941549 -387.620851) (xy 126.948757 -387.669214) (xy 126.9492 -387.693662) (xy 126.948779 -387.718035)
			(xy 126.941633 -387.766255) (xy 126.927491 -387.812904) (xy 126.906658 -387.856974) (xy 126.879584 -387.897511)
			(xy 126.846857 -387.933638) (xy 126.828296 -387.94944) (xy 126.819406 -387.956552) (xy 126.810008 -387.97611)
			(xy 126.807214 -388.075424) (xy 126.81585 -388.09549) (xy 126.824232 -388.10311) (xy 126.842676 -388.120577)
			(xy 126.874025 -388.160546) (xy 126.898323 -388.205153) (xy 126.9149 -388.253167) (xy 126.9233 -388.303264)
			(xy 126.9238 -388.328662) (xy 126.923696 -388.339943) (xy 126.922045 -388.362445) (xy 126.920498 -388.37362)
			(xy 126.919228 -388.38251) (xy 126.922784 -388.400036) (xy 126.966218 -388.470902) (xy 126.979934 -388.482078)
			(xy 126.98857 -388.484872) (xy 127.010818 -388.492801) (xy 127.052739 -388.514553) (xy 127.090812 -388.5425)
			(xy 127.124129 -388.575973) (xy 127.151897 -388.614176) (xy 127.163068 -388.634986) (xy 127.163576 -388.636002)
			(xy 127.556006 -389.314944) (xy 127.56881 -389.338287) (xy 127.587038 -389.388304) (xy 127.596307 -389.440727)
			(xy 127.5969 -389.467344) (xy 127.596501 -389.491351) (xy 127.58898 -389.538774) (xy 127.57413 -389.584434)
			(xy 127.552316 -389.627208) (xy 127.524077 -389.666041) (xy 127.490108 -389.699976) (xy 127.451247 -389.728176)
			(xy 127.408451 -389.749947) (xy 127.362776 -389.764752) (xy 127.315346 -389.772225) (xy 127.291338 -389.772652)
			(xy 127.267806 -389.772219) (xy 127.221297 -389.765009) (xy 127.176449 -389.750739) (xy 127.134325 -389.729748)
			(xy 127.095927 -389.702534) (xy 127.062165 -389.669744) (xy 127.033842 -389.632157) (xy 127.022352 -389.611616)
			(xy 127.022098 -389.611108) (xy 127.02159 -389.610346) (xy 126.623826 -388.922006) (xy 126.611947 -388.89933)
			(xy 126.595098 -388.850996) (xy 126.586526 -388.800533) (xy 126.58598 -388.77494) (xy 126.58598 -388.774432)
			(xy 126.586072 -388.763087) (xy 126.587726 -388.740458) (xy 126.589282 -388.72922) (xy 126.590552 -388.72033)
			(xy 126.586996 -388.703058) (xy 126.543562 -388.631938) (xy 126.529592 -388.621016) (xy 126.52121 -388.617968)
			(xy 126.498801 -388.609954) (xy 126.456584 -388.58799) (xy 126.418288 -388.559739) (xy 126.384843 -388.525884)
			(xy 126.35706 -388.487247) (xy 126.335612 -388.444766) (xy 126.32102 -388.399469) (xy 126.313637 -388.352456)
			(xy 126.313184 -388.328662) (xy 126.313715 -388.303267) (xy 126.322124 -388.253179) (xy 126.338703 -388.205172)
			(xy 126.362996 -388.160569) (xy 126.394333 -388.120599) (xy 126.412752 -388.10311) (xy 126.421134 -388.09549)
			(xy 126.42977 -388.075424) (xy 126.426976 -387.97611) (xy 126.417578 -387.956552) (xy 126.408688 -387.94944)
			(xy 126.390158 -387.933604) (xy 126.357435 -387.897481) (xy 126.330363 -387.85695) (xy 126.309527 -387.812887)
			(xy 126.295378 -387.766245) (xy 126.288222 -387.718032) (xy 126.287784 -387.693662) (xy 126.288192 -387.669544)
			(xy 126.2952 -387.62182) (xy 126.309062 -387.575619) (xy 126.329484 -387.53192) (xy 126.342394 -387.511544)
			(xy 126.348236 -387.502654) (xy 126.351792 -387.482588) (xy 126.33071 -387.390386) (xy 126.318518 -387.373622)
			(xy 126.309628 -387.368288) (xy 126.288829 -387.35543) (xy 126.250926 -387.32454) (xy 126.217984 -387.288404)
			(xy 126.190724 -387.247811) (xy 126.169738 -387.203646) (xy 126.155485 -387.156873) (xy 126.148275 -387.10851)
			(xy 126.14783 -387.084062) (xy 126.148367 -387.056777) (xy 126.157319 -387.002946) (xy 126.17499 -386.951316)
			(xy 126.2009 -386.903289) (xy 126.234345 -386.86017) (xy 126.254002 -386.841238) (xy 126.261389 -386.833704)
			(xy 126.269922 -386.814433) (xy 126.270512 -386.8039) (xy 126.270512 -386.729224) (xy 126.26998 -386.718675)
			(xy 126.261446 -386.69938) (xy 126.254002 -386.691886) (xy 126.23438 -386.672922) (xy 126.200943 -386.629805)
			(xy 126.175034 -386.581786) (xy 126.157358 -386.530165) (xy 126.148393 -386.476343) (xy 126.14783 -386.449062)
			(xy 126.148084 -386.43687) (xy 126.148338 -386.427218) (xy 126.142242 -386.409184) (xy 126.083568 -386.341874)
			(xy 126.066804 -386.333238) (xy 126.056898 -386.332222) (xy 126.029995 -386.32882) (xy 125.97771 -386.314462)
			(xy 125.928467 -386.291769) (xy 125.883583 -386.261349) (xy 125.844263 -386.224015) (xy 125.811557 -386.180769)
			(xy 125.786342 -386.132768) (xy 125.769294 -386.081297) (xy 125.764544 -386.0546) (xy 125.76302 -386.045202)
			(xy 125.490224 -385.57327) (xy 125.482858 -385.567428) (xy 125.464102 -385.551601) (xy 125.430985 -385.515388)
			(xy 125.403574 -385.474685) (xy 125.382469 -385.430382) (xy 125.368134 -385.38345) (xy 125.36088 -385.334916)
			(xy 125.36043 -385.31038) (xy 124.843636 -385.31038) (xy 125.092206 -385.740402) (xy 125.099572 -385.746244)
			(xy 125.118368 -385.762024) (xy 125.151482 -385.798248) (xy 125.178887 -385.838961) (xy 125.199984 -385.883273)
			(xy 125.214311 -385.930213) (xy 125.221555 -385.978753) (xy 125.222 -386.003292) (xy 125.221746 -386.015484)
			(xy 125.221492 -386.025136) (xy 125.227588 -386.04317) (xy 125.286262 -386.11048) (xy 125.303026 -386.119116)
			(xy 125.312678 -386.120132) (xy 125.339437 -386.123509) (xy 125.39146 -386.137728) (xy 125.440486 -386.1602)
			(xy 125.485216 -386.19033) (xy 125.524464 -386.227318) (xy 125.55719 -386.270184) (xy 125.582527 -386.317793)
			(xy 125.599803 -386.368882) (xy 125.60856 -386.422097) (xy 125.609096 -386.449062) (xy 125.608566 -386.476347)
			(xy 125.599611 -386.530178) (xy 125.581938 -386.581808) (xy 125.556027 -386.629834) (xy 125.522581 -386.672954)
			(xy 125.502924 -386.691886) (xy 125.49553 -386.699414) (xy 125.487 -386.718689) (xy 125.486414 -386.729224)
			(xy 125.486414 -386.8039) (xy 125.486926 -386.814452) (xy 125.495473 -386.833747) (xy 125.502924 -386.841238)
			(xy 125.522562 -386.860186) (xy 125.555997 -386.903307) (xy 125.581902 -386.951331) (xy 125.599574 -387.002955)
			(xy 125.608535 -387.05678) (xy 125.609096 -387.084062) (xy 125.608655 -387.108179) (xy 125.601657 -387.155901)
			(xy 125.587805 -387.202103) (xy 125.567392 -387.245803) (xy 125.554486 -387.26618) (xy 125.548644 -387.27507)
			(xy 125.545088 -387.295136) (xy 125.56617 -387.387338) (xy 125.578362 -387.404102) (xy 125.587252 -387.409436)
			(xy 125.608057 -387.422285) (xy 125.645962 -387.453176) (xy 125.678903 -387.489313) (xy 125.706164 -387.529907)
			(xy 125.727149 -387.574073) (xy 125.7414 -387.620849) (xy 125.748607 -387.669213) (xy 125.74905 -387.693662)
			(xy 125.748647 -387.718036) (xy 125.7415 -387.766257) (xy 125.727355 -387.812908) (xy 125.706519 -387.856978)
			(xy 125.679442 -387.897515) (xy 125.64671 -387.933639) (xy 125.628146 -387.94944) (xy 125.619256 -387.956552)
			(xy 125.609858 -387.97611) (xy 125.607064 -388.075424) (xy 125.6157 -388.09549) (xy 125.624082 -388.10311)
			(xy 125.642536 -388.120567) (xy 125.673881 -388.160539) (xy 125.698176 -388.205149) (xy 125.714752 -388.253166)
			(xy 125.723151 -388.303263) (xy 125.72365 -388.328662) (xy 125.723547 -388.339943) (xy 125.721895 -388.362445)
			(xy 125.720348 -388.37362) (xy 125.719078 -388.38251) (xy 125.722634 -388.400036) (xy 125.766068 -388.470902)
			(xy 125.779784 -388.482078) (xy 125.78842 -388.484872) (xy 125.810677 -388.492777) (xy 125.852596 -388.514536)
			(xy 125.890668 -388.542488) (xy 125.923983 -388.575967) (xy 125.951749 -388.614174) (xy 125.962918 -388.634986)
			(xy 125.963426 -388.636002) (xy 126.355856 -389.314944) (xy 126.368593 -389.338307) (xy 126.386706 -389.388337)
			(xy 126.395914 -389.440741) (xy 126.396496 -389.467344) (xy 126.396078 -389.491337) (xy 126.388565 -389.538731)
			(xy 126.373731 -389.584367) (xy 126.351941 -389.627121) (xy 126.323731 -389.665939) (xy 126.289797 -389.699868)
			(xy 126.250973 -389.72807) (xy 126.208215 -389.749852) (xy 126.162577 -389.764678) (xy 126.115181 -389.772182)
			(xy 126.091188 -389.772652) (xy 126.067657 -389.772178) (xy 126.021151 -389.764976) (xy 125.976303 -389.750713)
			(xy 125.934179 -389.729729) (xy 125.89578 -389.702522) (xy 125.862018 -389.669737) (xy 125.833693 -389.632154)
			(xy 125.822202 -389.611616) (xy 125.821948 -389.611108) (xy 125.82144 -389.610346) (xy 125.423676 -388.922006)
			(xy 125.411759 -388.899339) (xy 125.394823 -388.851013) (xy 125.386163 -388.800542) (xy 125.385576 -388.77494)
			(xy 125.385576 -388.774432) (xy 125.385734 -388.763083) (xy 125.38751 -388.740454) (xy 125.389132 -388.72922)
			(xy 125.390402 -388.72033) (xy 125.386846 -388.703058) (xy 125.343412 -388.631938) (xy 125.329442 -388.621016)
			(xy 125.32106 -388.617968) (xy 125.298661 -388.609925) (xy 125.256443 -388.587968) (xy 125.218145 -388.559722)
			(xy 125.184698 -388.525872) (xy 125.156913 -388.487239) (xy 125.135464 -388.44476) (xy 125.120871 -388.399466)
			(xy 125.113487 -388.352456) (xy 125.113034 -388.328662) (xy 125.113549 -388.303266) (xy 125.121959 -388.253176)
			(xy 125.138541 -388.205168) (xy 125.162838 -388.160566) (xy 125.19418 -388.120598) (xy 125.212602 -388.10311)
			(xy 125.220984 -388.09549) (xy 125.22962 -388.075424) (xy 125.226826 -387.97611) (xy 125.217428 -387.956552)
			(xy 125.208538 -387.94944) (xy 125.189998 -387.933616) (xy 125.157278 -387.897489) (xy 125.130208 -387.856955)
			(xy 125.109375 -387.81289) (xy 125.095227 -387.766246) (xy 125.088072 -387.718033) (xy 125.087634 -387.693662)
			(xy 125.08805 -387.669545) (xy 125.095057 -387.621821) (xy 125.108917 -387.575621) (xy 125.129335 -387.531921)
			(xy 125.142244 -387.511544) (xy 125.148086 -387.502654) (xy 125.151642 -387.482588) (xy 125.13056 -387.390386)
			(xy 125.118368 -387.373622) (xy 125.109478 -387.368288) (xy 125.088691 -387.355412) (xy 125.050784 -387.324526)
			(xy 125.017841 -387.288395) (xy 124.990578 -387.247805) (xy 124.96959 -387.203643) (xy 124.955335 -387.156871)
			(xy 124.948125 -387.10851) (xy 124.94768 -387.084062) (xy 124.948233 -387.056778) (xy 124.957183 -387.002948)
			(xy 124.974851 -386.951319) (xy 125.000757 -386.903292) (xy 125.034198 -386.860171) (xy 125.053852 -386.841238)
			(xy 125.061232 -386.833698) (xy 125.06977 -386.814432) (xy 125.070362 -386.8039) (xy 125.070362 -386.729224)
			(xy 125.069845 -386.718673) (xy 125.061303 -386.699377) (xy 125.053852 -386.691886) (xy 125.034221 -386.672931)
			(xy 125.000787 -386.629811) (xy 124.974881 -386.581789) (xy 124.957207 -386.530167) (xy 124.948243 -386.476344)
			(xy 124.94768 -386.449062) (xy 124.947934 -386.43687) (xy 124.948188 -386.427218) (xy 124.942092 -386.409184)
			(xy 124.883418 -386.341874) (xy 124.866654 -386.333238) (xy 124.857002 -386.332222) (xy 124.8301 -386.328817)
			(xy 124.777815 -386.31446) (xy 124.728571 -386.291767) (xy 124.683688 -386.261347) (xy 124.644367 -386.224014)
			(xy 124.611661 -386.180768) (xy 124.586447 -386.132767) (xy 124.569398 -386.081296) (xy 124.564648 -386.0546)
			(xy 124.563124 -386.045202) (xy 124.290328 -385.57327) (xy 124.282962 -385.567428) (xy 124.264207 -385.5516)
			(xy 124.23109 -385.515388) (xy 124.203678 -385.474685) (xy 124.182574 -385.430382) (xy 124.168238 -385.38345)
			(xy 124.160984 -385.334916) (xy 124.160534 -385.31038) (xy 123.64345 -385.31038) (xy 123.892056 -385.740402)
			(xy 123.899422 -385.746244) (xy 123.918208 -385.762036) (xy 123.951324 -385.798256) (xy 123.978732 -385.838966)
			(xy 123.999832 -385.883276) (xy 124.01416 -385.930214) (xy 124.021405 -385.978754) (xy 124.02185 -386.003292)
			(xy 124.021596 -386.015484) (xy 124.021342 -386.025136) (xy 124.027438 -386.04317) (xy 124.086112 -386.11048)
			(xy 124.102876 -386.119116) (xy 124.112782 -386.120132) (xy 124.139542 -386.123506) (xy 124.191565 -386.137726)
			(xy 124.24059 -386.160198) (xy 124.28532 -386.190328) (xy 124.324568 -386.227317) (xy 124.357294 -386.270183)
			(xy 124.382631 -386.317792) (xy 124.399907 -386.368881) (xy 124.408664 -386.422097) (xy 124.4092 -386.449062)
			(xy 124.408669 -386.476347) (xy 124.399714 -386.530178) (xy 124.382041 -386.581808) (xy 124.35613 -386.629834)
			(xy 124.322685 -386.672954) (xy 124.303028 -386.691886) (xy 124.295635 -386.699415) (xy 124.287104 -386.718689)
			(xy 124.286518 -386.729224) (xy 124.286518 -386.8039) (xy 124.287028 -386.814452) (xy 124.295576 -386.833747)
			(xy 124.303028 -386.841238) (xy 124.322667 -386.860185) (xy 124.356101 -386.903307) (xy 124.382006 -386.951331)
			(xy 124.399678 -387.002955) (xy 124.408639 -387.056779) (xy 124.4092 -387.084062) (xy 124.408758 -387.108179)
			(xy 124.401761 -387.155901) (xy 124.387909 -387.202102) (xy 124.367496 -387.245803) (xy 124.35459 -387.26618)
			(xy 124.348748 -387.27507) (xy 124.345192 -387.295136) (xy 124.366274 -387.387338) (xy 124.378466 -387.404102)
			(xy 124.387356 -387.409436) (xy 124.408162 -387.422283) (xy 124.446066 -387.453175) (xy 124.479008 -387.489312)
			(xy 124.506268 -387.529907) (xy 124.527253 -387.574073) (xy 124.541504 -387.620849) (xy 124.548711 -387.669213)
			(xy 124.549154 -387.693662) (xy 124.54875 -387.718036) (xy 124.541603 -387.766257) (xy 124.527458 -387.812908)
			(xy 124.506622 -387.856978) (xy 124.479545 -387.897514) (xy 124.446814 -387.933639) (xy 124.42825 -387.94944)
			(xy 124.41936 -387.956552) (xy 124.409962 -387.97611) (xy 124.407168 -388.075424) (xy 124.415804 -388.09549)
			(xy 124.424186 -388.10311) (xy 124.442641 -388.120566) (xy 124.473985 -388.160539) (xy 124.498281 -388.205149)
			(xy 124.514856 -388.253166) (xy 124.523255 -388.303263) (xy 124.523754 -388.328662) (xy 124.523651 -388.339943)
			(xy 124.521999 -388.362445) (xy 124.520452 -388.37362) (xy 124.519182 -388.38251) (xy 124.522738 -388.400036)
			(xy 124.566172 -388.470902) (xy 124.579888 -388.482078) (xy 124.588524 -388.484872) (xy 124.610781 -388.492775)
			(xy 124.652701 -388.514535) (xy 124.690772 -388.542488) (xy 124.724087 -388.575967) (xy 124.751853 -388.614174)
			(xy 124.763022 -388.634986) (xy 124.76353 -388.636002) (xy 125.15596 -389.314944) (xy 125.168697 -389.338307)
			(xy 125.18681 -389.388337) (xy 125.196018 -389.440741) (xy 125.1966 -389.467344) (xy 125.196178 -389.491337)
			(xy 125.188665 -389.538731) (xy 125.173831 -389.584366) (xy 125.152041 -389.627119) (xy 125.123832 -389.665938)
			(xy 125.089898 -389.699866) (xy 125.051075 -389.728069) (xy 125.008318 -389.749851) (xy 124.96268 -389.764677)
			(xy 124.915285 -389.772182) (xy 124.891292 -389.772652) (xy 124.867761 -389.772175) (xy 124.821255 -389.764973)
			(xy 124.776407 -389.750711) (xy 124.734284 -389.729728) (xy 124.695885 -389.702521) (xy 124.662122 -389.669737)
			(xy 124.633797 -389.632154) (xy 124.622306 -389.611616) (xy 124.622052 -389.611108) (xy 124.621544 -389.610346)
			(xy 124.22378 -388.922006) (xy 124.211863 -388.899339) (xy 124.194927 -388.851013) (xy 124.186267 -388.800542)
			(xy 124.18568 -388.77494) (xy 124.18568 -388.774432) (xy 124.185838 -388.763083) (xy 124.187614 -388.740454)
			(xy 124.189236 -388.72922) (xy 124.190506 -388.72033) (xy 124.18695 -388.703058) (xy 124.143516 -388.631938)
			(xy 124.129546 -388.621016) (xy 124.121164 -388.617968) (xy 124.098766 -388.609923) (xy 124.056547 -388.587967)
			(xy 124.01825 -388.559721) (xy 123.984803 -388.525871) (xy 123.957018 -388.487239) (xy 123.935568 -388.44476)
			(xy 123.920975 -388.399466) (xy 123.913591 -388.352455) (xy 123.913138 -388.328662) (xy 123.913652 -388.303266)
			(xy 123.922062 -388.253176) (xy 123.938644 -388.205168) (xy 123.962941 -388.160565) (xy 123.994284 -388.120598)
			(xy 124.012706 -388.10311) (xy 124.021088 -388.09549) (xy 124.029724 -388.075424) (xy 124.02693 -387.97611)
			(xy 124.017532 -387.956552) (xy 124.008642 -387.94944) (xy 123.990103 -387.933615) (xy 123.957382 -387.897488)
			(xy 123.930313 -387.856954) (xy 123.909479 -387.81289) (xy 123.895331 -387.766246) (xy 123.888176 -387.718033)
			(xy 123.887738 -387.693662) (xy 123.888154 -387.669545) (xy 123.895161 -387.621821) (xy 123.90902 -387.57562)
			(xy 123.929439 -387.531921) (xy 123.942348 -387.511544) (xy 123.94819 -387.502654) (xy 123.951746 -387.482588)
			(xy 123.930664 -387.390386) (xy 123.918472 -387.373622) (xy 123.909582 -387.368288) (xy 123.888795 -387.355411)
			(xy 123.850889 -387.324525) (xy 123.817945 -387.288394) (xy 123.790682 -387.247805) (xy 123.769694 -387.203642)
			(xy 123.755439 -387.156871) (xy 123.748229 -387.10851) (xy 123.747784 -387.084062) (xy 123.748336 -387.056778)
			(xy 123.757286 -387.002948) (xy 123.774955 -386.951319) (xy 123.800861 -386.903292) (xy 123.834302 -386.860171)
			(xy 123.853956 -386.841238) (xy 123.861336 -386.833698) (xy 123.869874 -386.814432) (xy 123.870466 -386.8039)
			(xy 123.870466 -386.729224) (xy 123.869948 -386.718673) (xy 123.861406 -386.699377) (xy 123.853956 -386.691886)
			(xy 123.834326 -386.672931) (xy 123.800891 -386.629811) (xy 123.774985 -386.581789) (xy 123.757311 -386.530166)
			(xy 123.748347 -386.476344) (xy 123.747784 -386.449062) (xy 123.748038 -386.43687) (xy 123.748292 -386.427218)
			(xy 123.742196 -386.409184) (xy 123.683522 -386.341874) (xy 123.666758 -386.333238) (xy 123.656852 -386.332222)
			(xy 123.629944 -386.328857) (xy 123.577658 -386.314492) (xy 123.528415 -386.291792) (xy 123.483532 -386.261366)
			(xy 123.444213 -386.224028) (xy 123.411508 -386.180777) (xy 123.386295 -386.132772) (xy 123.369248 -386.081298)
			(xy 123.364498 -386.0546) (xy 123.362974 -386.045202) (xy 123.089924 -385.572762) (xy 123.082812 -385.56692)
			(xy 123.064083 -385.551136) (xy 123.031028 -385.514996) (xy 123.00367 -385.474371) (xy 122.98261 -385.430153)
			(xy 122.968309 -385.38331) (xy 122.961081 -385.334869) (xy 122.960638 -385.31038) (xy 122.44359 -385.31038)
			(xy 122.69216 -385.740402) (xy 122.699526 -385.746244) (xy 122.718313 -385.762035) (xy 122.751429 -385.798255)
			(xy 122.778837 -385.838966) (xy 122.799936 -385.883276) (xy 122.814265 -385.930214) (xy 122.821509 -385.978754)
			(xy 122.821954 -386.003292) (xy 122.8217 -386.015484) (xy 122.821446 -386.025136) (xy 122.827542 -386.04317)
			(xy 122.886216 -386.11048) (xy 122.90298 -386.119116) (xy 122.912886 -386.120132) (xy 122.939646 -386.123503)
			(xy 122.991669 -386.137723) (xy 123.040695 -386.160196) (xy 123.085425 -386.190326) (xy 123.124673 -386.227315)
			(xy 123.157399 -386.270182) (xy 123.182735 -386.317792) (xy 123.200011 -386.368881) (xy 123.208768 -386.422096)
			(xy 123.209304 -386.449062) (xy 123.208772 -386.476347) (xy 123.199817 -386.530178) (xy 123.182144 -386.581807)
			(xy 123.156234 -386.629834) (xy 123.122788 -386.672954) (xy 123.103132 -386.691886) (xy 123.095739 -386.699415)
			(xy 123.087209 -386.718689) (xy 123.086622 -386.729224) (xy 123.086622 -386.8039) (xy 123.087131 -386.814452)
			(xy 123.09568 -386.833748) (xy 123.103132 -386.841238) (xy 123.122771 -386.860184) (xy 123.156206 -386.903306)
			(xy 123.18211 -386.951331) (xy 123.199782 -387.002955) (xy 123.208743 -387.056779) (xy 123.209304 -387.084062)
			(xy 123.208861 -387.108179) (xy 123.201864 -387.155901) (xy 123.188013 -387.202102) (xy 123.1676 -387.245803)
			(xy 123.154694 -387.26618) (xy 123.148852 -387.27507) (xy 123.145296 -387.295136) (xy 123.166378 -387.387338)
			(xy 123.17857 -387.404102) (xy 123.18746 -387.409436) (xy 123.208267 -387.422282) (xy 123.246171 -387.453174)
			(xy 123.279112 -387.489311) (xy 123.306372 -387.529906) (xy 123.327357 -387.574073) (xy 123.341608 -387.620849)
			(xy 123.348815 -387.669213) (xy 123.349258 -387.693662) (xy 123.348852 -387.718036) (xy 123.341705 -387.766257)
			(xy 123.327561 -387.812907) (xy 123.306725 -387.856978) (xy 123.279648 -387.897514) (xy 123.246917 -387.933639)
			(xy 123.228354 -387.94944) (xy 123.219464 -387.956552) (xy 123.210066 -387.97611) (xy 123.207272 -388.075424)
			(xy 123.215908 -388.09549) (xy 123.22429 -388.10311) (xy 123.242746 -388.120565) (xy 123.27409 -388.160539)
			(xy 123.298385 -388.205149) (xy 123.31496 -388.253165) (xy 123.323359 -388.303263) (xy 123.323858 -388.328662)
			(xy 123.323755 -388.339943) (xy 123.322103 -388.362445) (xy 123.320556 -388.37362) (xy 123.319286 -388.382764)
			(xy 123.322588 -388.400036) (xy 123.366276 -388.471156) (xy 123.379992 -388.482078) (xy 123.388628 -388.484872)
			(xy 123.416797 -388.495059) (xy 123.46874 -388.524877) (xy 123.491752 -388.544054) (xy 123.513243 -388.563629)
			(xy 123.549052 -388.609412) (xy 123.562872 -388.634986) (xy 123.563634 -388.636256) (xy 123.95581 -389.314944)
			(xy 123.968614 -389.338287) (xy 123.986843 -389.388304) (xy 123.996111 -389.440727) (xy 123.996704 -389.467344)
			(xy 123.996301 -389.491351) (xy 123.98878 -389.538773) (xy 123.97393 -389.584433) (xy 123.952117 -389.627207)
			(xy 123.923878 -389.66604) (xy 123.88991 -389.699974) (xy 123.851049 -389.728175) (xy 123.808254 -389.749946)
			(xy 123.762579 -389.764751) (xy 123.71515 -389.772225) (xy 123.691142 -389.772652) (xy 123.66761 -389.772215)
			(xy 123.621102 -389.765006) (xy 123.576253 -389.750737) (xy 123.534129 -389.729746) (xy 123.495731 -389.702533)
			(xy 123.461969 -389.669744) (xy 123.433647 -389.632156) (xy 123.422156 -389.611616) (xy 123.421902 -389.611108)
			(xy 123.421394 -389.610346) (xy 123.023884 -388.921752) (xy 123.013309 -388.901826) (xy 122.997507 -388.859576)
			(xy 122.988101 -388.815459) (xy 122.986292 -388.792974) (xy 122.985784 -388.781798) (xy 122.985784 -388.774432)
			(xy 122.985875 -388.763087) (xy 122.98753 -388.740458) (xy 122.989086 -388.72922) (xy 122.990356 -388.72033)
			(xy 122.9868 -388.703058) (xy 122.943366 -388.631938) (xy 122.92965 -388.620762) (xy 122.921014 -388.617968)
			(xy 122.898621 -388.609947) (xy 122.856449 -388.587949) (xy 122.818199 -388.559677) (xy 122.784798 -388.525814)
			(xy 122.757053 -388.487181) (xy 122.735636 -388.444711) (xy 122.721065 -388.399434) (xy 122.713693 -388.352444)
			(xy 122.713242 -388.328662) (xy 122.713754 -388.303266) (xy 122.722165 -388.253176) (xy 122.738747 -388.205168)
			(xy 122.763045 -388.160565) (xy 122.794388 -388.120598) (xy 122.81281 -388.10311) (xy 122.821192 -388.09549)
			(xy 122.829828 -388.075424) (xy 122.827034 -387.97611) (xy 122.817636 -387.956552) (xy 122.808746 -387.94944)
			(xy 122.790207 -387.933614) (xy 122.757487 -387.897487) (xy 122.730417 -387.856954) (xy 122.709583 -387.812889)
			(xy 122.695435 -387.766246) (xy 122.68828 -387.718033) (xy 122.687842 -387.693662) (xy 122.688257 -387.669545)
			(xy 122.695264 -387.621821) (xy 122.709124 -387.57562) (xy 122.729543 -387.531921) (xy 122.742452 -387.511544)
			(xy 122.748294 -387.502654) (xy 122.75185 -387.482588) (xy 122.730768 -387.390386) (xy 122.718576 -387.373622)
			(xy 122.709686 -387.368288) (xy 122.6889 -387.355409) (xy 122.650994 -387.324524) (xy 122.61805 -387.288393)
			(xy 122.590786 -387.247804) (xy 122.569798 -387.203642) (xy 122.555544 -387.156871) (xy 122.548333 -387.10851)
			(xy 122.547888 -387.084062) (xy 122.548439 -387.056778) (xy 122.557389 -387.002948) (xy 122.575058 -386.951319)
			(xy 122.600964 -386.903292) (xy 122.634406 -386.860171) (xy 122.65406 -386.841238) (xy 122.661441 -386.833699)
			(xy 122.669978 -386.814432) (xy 122.67057 -386.8039) (xy 122.67057 -386.729224) (xy 122.67005 -386.718673)
			(xy 122.66151 -386.699377) (xy 122.65406 -386.691886) (xy 122.634431 -386.67293) (xy 122.600996 -386.62981)
			(xy 122.57509 -386.581788) (xy 122.557415 -386.530166) (xy 122.548451 -386.476344) (xy 122.547888 -386.449062)
			(xy 122.548142 -386.43687) (xy 122.548396 -386.427218) (xy 122.5423 -386.409184) (xy 122.483626 -386.341874)
			(xy 122.466862 -386.333238) (xy 122.456956 -386.332222) (xy 122.430049 -386.328854) (xy 122.377763 -386.314489)
			(xy 122.328519 -386.29179) (xy 122.283637 -386.261364) (xy 122.244317 -386.224027) (xy 122.211613 -386.180776)
			(xy 122.186399 -386.132772) (xy 122.169352 -386.081298) (xy 122.164602 -386.0546) (xy 122.163078 -386.045202)
			(xy 121.890282 -385.57327) (xy 121.882916 -385.567428) (xy 121.864173 -385.551587) (xy 121.831052 -385.515379)
			(xy 121.803638 -385.474679) (xy 121.782531 -385.430379) (xy 121.768193 -385.383448) (xy 121.760939 -385.334916)
			(xy 121.760488 -385.31038) (xy 121.243694 -385.31038) (xy 121.492264 -385.740402) (xy 121.49963 -385.746244)
			(xy 121.518418 -385.762034) (xy 121.551533 -385.798254) (xy 121.578941 -385.838965) (xy 121.60004 -385.883275)
			(xy 121.614369 -385.930214) (xy 121.621613 -385.978754) (xy 121.622058 -386.003292) (xy 121.621804 -386.015484)
			(xy 121.62155 -386.025136) (xy 121.627646 -386.04317) (xy 121.68632 -386.11048) (xy 121.703084 -386.119116)
			(xy 121.712736 -386.120132) (xy 121.739502 -386.123462) (xy 121.791525 -386.13769) (xy 121.840551 -386.16017)
			(xy 121.88528 -386.190306) (xy 121.924527 -386.2273) (xy 121.957252 -386.270171) (xy 121.982587 -386.317784)
			(xy 121.999862 -386.368877) (xy 122.008619 -386.422095) (xy 122.009154 -386.449062) (xy 122.008606 -386.476346)
			(xy 121.999653 -386.530175) (xy 121.981983 -386.581804) (xy 121.956076 -386.629831) (xy 121.922636 -386.672952)
			(xy 121.902982 -386.691886) (xy 121.895582 -386.699408) (xy 121.887057 -386.718688) (xy 121.886472 -386.729224)
			(xy 121.886472 -386.8039) (xy 121.886996 -386.81445) (xy 121.895536 -386.833745) (xy 121.902982 -386.841238)
			(xy 121.922631 -386.860175) (xy 121.956062 -386.903301) (xy 121.981963 -386.951328) (xy 121.999633 -387.002953)
			(xy 122.008593 -387.056779) (xy 122.009154 -387.084062) (xy 122.008703 -387.108178) (xy 122.001707 -387.1559)
			(xy 121.987858 -387.202101) (xy 121.967448 -387.245802) (xy 121.954544 -387.26618) (xy 121.948702 -387.27507)
			(xy 121.945146 -387.295136) (xy 121.966228 -387.387338) (xy 121.97842 -387.404102) (xy 121.98731 -387.409436)
			(xy 122.008105 -387.4223) (xy 122.046012 -387.453187) (xy 122.078956 -387.48932) (xy 122.106218 -387.529912)
			(xy 122.127205 -387.574077) (xy 122.141457 -387.620851) (xy 122.148665 -387.669213) (xy 122.149108 -387.693662)
			(xy 122.148684 -387.718035) (xy 122.141539 -387.766254) (xy 122.127396 -387.812904) (xy 122.106564 -387.856974)
			(xy 122.079491 -387.897511) (xy 122.046765 -387.933637) (xy 122.028204 -387.94944) (xy 122.019314 -387.956552)
			(xy 122.009916 -387.97611) (xy 122.007122 -388.075424) (xy 122.015758 -388.09549) (xy 122.02414 -388.10311)
			(xy 122.042586 -388.120575) (xy 122.073933 -388.160545) (xy 122.098231 -388.205152) (xy 122.114809 -388.253167)
			(xy 122.123208 -388.303264) (xy 122.123708 -388.328662) (xy 122.123604 -388.339943) (xy 122.121953 -388.362445)
			(xy 122.120406 -388.37362) (xy 122.119136 -388.38251) (xy 122.122692 -388.400036) (xy 122.166126 -388.470902)
			(xy 122.179842 -388.482078) (xy 122.188478 -388.484872) (xy 122.210727 -388.492796) (xy 122.252648 -388.51455)
			(xy 122.290721 -388.542497) (xy 122.324038 -388.575972) (xy 122.351806 -388.614176) (xy 122.362976 -388.634986)
			(xy 122.363484 -388.636002) (xy 122.755914 -389.314944) (xy 122.768718 -389.338287) (xy 122.786947 -389.388304)
			(xy 122.796215 -389.440727) (xy 122.796808 -389.467344) (xy 122.796401 -389.491351) (xy 122.78888 -389.538772)
			(xy 122.77403 -389.584432) (xy 122.752217 -389.627206) (xy 122.723979 -389.666038) (xy 122.690011 -389.699973)
			(xy 122.651151 -389.728173) (xy 122.608357 -389.749944) (xy 122.562682 -389.76475) (xy 122.515253 -389.772225)
			(xy 122.491246 -389.772652) (xy 122.467714 -389.772212) (xy 122.421206 -389.765003) (xy 122.376357 -389.750735)
			(xy 122.334234 -389.729745) (xy 122.295835 -389.702532) (xy 122.262074 -389.669743) (xy 122.233751 -389.632156)
			(xy 122.22226 -389.611616) (xy 122.222006 -389.611108) (xy 122.221498 -389.610346) (xy 121.823734 -388.922006)
			(xy 121.811856 -388.89933) (xy 121.795006 -388.850996) (xy 121.786434 -388.800533) (xy 121.785888 -388.77494)
			(xy 121.785888 -388.774432) (xy 121.785979 -388.763087) (xy 121.787634 -388.740458) (xy 121.78919 -388.72922)
			(xy 121.79046 -388.72033) (xy 121.786904 -388.703058) (xy 121.74347 -388.631938) (xy 121.7295 -388.621016)
			(xy 121.721118 -388.617968) (xy 121.698711 -388.609949) (xy 121.656493 -388.587987) (xy 121.618197 -388.559736)
			(xy 121.584752 -388.525882) (xy 121.556968 -388.487246) (xy 121.53552 -388.444765) (xy 121.520928 -388.399469)
			(xy 121.513545 -388.352456) (xy 121.513092 -388.328662) (xy 121.51362 -388.303267) (xy 121.522029 -388.253178)
			(xy 121.538609 -388.205171) (xy 121.562902 -388.160568) (xy 121.59424 -388.120599) (xy 121.61266 -388.10311)
			(xy 121.621042 -388.09549) (xy 121.629678 -388.075424) (xy 121.626884 -387.97611) (xy 121.617486 -387.956552)
			(xy 121.608596 -387.94944) (xy 121.590068 -387.933602) (xy 121.557344 -387.89748) (xy 121.530272 -387.856949)
			(xy 121.509436 -387.812886) (xy 121.495286 -387.766245) (xy 121.48813 -387.718032) (xy 121.487692 -387.693662)
			(xy 121.488099 -387.669544) (xy 121.495107 -387.62182) (xy 121.508969 -387.575619) (xy 121.529391 -387.53192)
			(xy 121.542302 -387.511544) (xy 121.548144 -387.502654) (xy 121.5517 -387.482588) (xy 121.530618 -387.390386)
			(xy 121.518426 -387.373622) (xy 121.509536 -387.368288) (xy 121.488739 -387.355427) (xy 121.450835 -387.324537)
			(xy 121.417893 -387.288402) (xy 121.390632 -387.24781) (xy 121.369646 -387.203646) (xy 121.355393 -387.156873)
			(xy 121.348183 -387.10851) (xy 121.347738 -387.084062) (xy 121.348304 -387.056778) (xy 121.357254 -387.00295)
			(xy 121.374919 -386.951322) (xy 121.400822 -386.903295) (xy 121.434258 -386.860172) (xy 121.45391 -386.841238)
			(xy 121.461299 -386.833706) (xy 121.46983 -386.814434) (xy 121.47042 -386.8039) (xy 121.47042 -386.729224)
			(xy 121.469885 -386.718675) (xy 121.461353 -386.69938) (xy 121.45391 -386.691886) (xy 121.434271 -386.672939)
			(xy 121.40084 -386.629816) (xy 121.374936 -386.581791) (xy 121.357264 -386.530168) (xy 121.348301 -386.476344)
			(xy 121.347738 -386.449062) (xy 121.347992 -386.43687) (xy 121.348246 -386.427218) (xy 121.34215 -386.409184)
			(xy 121.283476 -386.341874) (xy 121.266712 -386.333238) (xy 121.25706 -386.332222) (xy 121.230153 -386.328851)
			(xy 121.177867 -386.314487) (xy 121.128624 -386.291788) (xy 121.083741 -386.261363) (xy 121.044421 -386.224025)
			(xy 121.011717 -386.180776) (xy 120.986503 -386.132771) (xy 120.969456 -386.081298) (xy 120.964706 -386.0546)
			(xy 120.963182 -386.045202) (xy 120.690386 -385.57327) (xy 120.68302 -385.567428) (xy 120.664278 -385.551586)
			(xy 120.631156 -385.515378) (xy 120.603742 -385.474678) (xy 120.582635 -385.430378) (xy 120.568297 -385.383448)
			(xy 120.561043 -385.334916) (xy 120.560592 -385.31038) (xy 120.043544 -385.31038) (xy 120.292114 -385.740402)
			(xy 120.29948 -385.746244) (xy 120.318257 -385.762047) (xy 120.351376 -385.798263) (xy 120.378786 -385.838971)
			(xy 120.399887 -385.883279) (xy 120.414217 -385.930216) (xy 120.421462 -385.978754) (xy 120.421908 -386.003292)
			(xy 120.421654 -386.015484) (xy 120.4214 -386.025136) (xy 120.427496 -386.04317) (xy 120.48617 -386.11048)
			(xy 120.502934 -386.119116) (xy 120.51284 -386.120132) (xy 120.539606 -386.123459) (xy 120.59163 -386.137687)
			(xy 120.640655 -386.160168) (xy 120.685384 -386.190304) (xy 120.724631 -386.227299) (xy 120.757356 -386.270171)
			(xy 120.782691 -386.317784) (xy 120.799966 -386.368876) (xy 120.808723 -386.422095) (xy 120.809258 -386.449062)
			(xy 120.808708 -386.476346) (xy 120.799755 -386.530175) (xy 120.782086 -386.581804) (xy 120.75618 -386.629831)
			(xy 120.722739 -386.672952) (xy 120.703086 -386.691886) (xy 120.695686 -386.699409) (xy 120.687161 -386.718688)
			(xy 120.686576 -386.729224) (xy 120.686576 -386.8039) (xy 120.687099 -386.81445) (xy 120.695639 -386.833745)
			(xy 120.703086 -386.841238) (xy 120.722735 -386.860174) (xy 120.756166 -386.9033) (xy 120.782067 -386.951327)
			(xy 120.799737 -387.002953) (xy 120.808697 -387.056779) (xy 120.809258 -387.084062) (xy 120.808807 -387.108178)
			(xy 120.801811 -387.1559) (xy 120.787961 -387.202101) (xy 120.767552 -387.245802) (xy 120.754648 -387.26618)
			(xy 120.748806 -387.27507) (xy 120.74525 -387.295136) (xy 120.766332 -387.387338) (xy 120.778524 -387.404102)
			(xy 120.787414 -387.409436) (xy 120.80821 -387.422298) (xy 120.846117 -387.453186) (xy 120.87906 -387.48932)
			(xy 120.906323 -387.529912) (xy 120.927309 -387.574076) (xy 120.941561 -387.62085) (xy 120.948769 -387.669213)
			(xy 120.949212 -387.693662) (xy 120.948787 -387.718035) (xy 120.941641 -387.766254) (xy 120.927499 -387.812903)
			(xy 120.906667 -387.856973) (xy 120.879595 -387.89751) (xy 120.846869 -387.933637) (xy 120.828308 -387.94944)
			(xy 120.819418 -387.956552) (xy 120.81002 -387.97611) (xy 120.807226 -388.075424) (xy 120.815862 -388.09549)
			(xy 120.824244 -388.10311) (xy 120.842691 -388.120574) (xy 120.874038 -388.160544) (xy 120.898336 -388.205152)
			(xy 120.914913 -388.253167) (xy 120.923312 -388.303264) (xy 120.923812 -388.328662) (xy 120.923708 -388.339943)
			(xy 120.922057 -388.362445) (xy 120.92051 -388.37362) (xy 120.91924 -388.38251) (xy 120.922796 -388.400036)
			(xy 120.96623 -388.470902) (xy 120.979946 -388.482078) (xy 120.988582 -388.484872) (xy 121.010832 -388.492795)
			(xy 121.052753 -388.514549) (xy 121.090825 -388.542497) (xy 121.124142 -388.575971) (xy 121.15191 -388.614176)
			(xy 121.16308 -388.634986) (xy 121.163588 -388.636002) (xy 121.556018 -389.314944) (xy 121.568823 -389.338287)
			(xy 121.587051 -389.388304) (xy 121.596319 -389.440727) (xy 121.596912 -389.467344) (xy 121.596502 -389.491351)
			(xy 121.58898 -389.538772) (xy 121.574131 -389.584432) (xy 121.552318 -389.627205) (xy 121.52408 -389.666037)
			(xy 121.490113 -389.699971) (xy 121.451253 -389.728172) (xy 121.408459 -389.749943) (xy 121.362786 -389.764749)
			(xy 121.315357 -389.772225) (xy 121.29135 -389.772652) (xy 121.267818 -389.772209) (xy 121.22131 -389.765001)
			(xy 121.176462 -389.750733) (xy 121.134338 -389.729743) (xy 121.09594 -389.702531) (xy 121.062178 -389.669743)
			(xy 121.033855 -389.632156) (xy 121.022364 -389.611616) (xy 121.02211 -389.611108) (xy 121.021602 -389.610346)
			(xy 120.623838 -388.922006) (xy 120.61196 -388.89933) (xy 120.595111 -388.850996) (xy 120.586538 -388.800533)
			(xy 120.585992 -388.77494) (xy 120.585992 -388.774432) (xy 120.586083 -388.763087) (xy 120.587738 -388.740458)
			(xy 120.589294 -388.72922) (xy 120.590564 -388.72033) (xy 120.587008 -388.703058) (xy 120.543574 -388.631938)
			(xy 120.529604 -388.621016) (xy 120.521222 -388.617968) (xy 120.498815 -388.609947) (xy 120.456598 -388.587985)
			(xy 120.418302 -388.559735) (xy 120.384856 -388.525881) (xy 120.357073 -388.487245) (xy 120.335625 -388.444764)
			(xy 120.321032 -388.399469) (xy 120.313649 -388.352456) (xy 120.313196 -388.328662) (xy 120.313723 -388.303267)
			(xy 120.322132 -388.253178) (xy 120.338712 -388.205171) (xy 120.363006 -388.160568) (xy 120.394344 -388.120599)
			(xy 120.412764 -388.10311) (xy 120.421146 -388.09549) (xy 120.429782 -388.075424) (xy 120.426988 -387.97611)
			(xy 120.41759 -387.956552) (xy 120.4087 -387.94944) (xy 120.390172 -387.933601) (xy 120.357449 -387.897479)
			(xy 120.330376 -387.856948) (xy 120.30954 -387.812886) (xy 120.29539 -387.766245) (xy 120.288234 -387.718032)
			(xy 120.287796 -387.693662) (xy 120.288202 -387.669544) (xy 120.29521 -387.62182) (xy 120.309073 -387.575619)
			(xy 120.329495 -387.53192) (xy 120.342406 -387.511544) (xy 120.348248 -387.502654) (xy 120.351804 -387.482588)
			(xy 120.330722 -387.390386) (xy 120.31853 -387.373622) (xy 120.30964 -387.368288) (xy 120.288844 -387.355426)
			(xy 120.25094 -387.324536) (xy 120.217998 -387.288402) (xy 120.190736 -387.24781) (xy 120.16975 -387.203646)
			(xy 120.155497 -387.156872) (xy 120.148287 -387.10851) (xy 120.147842 -387.084062) (xy 120.148407 -387.056778)
			(xy 120.157356 -387.00295) (xy 120.175022 -386.951322) (xy 120.200925 -386.903295) (xy 120.234362 -386.860172)
			(xy 120.254014 -386.841238) (xy 120.261403 -386.833706) (xy 120.269934 -386.814434) (xy 120.270524 -386.8039)
			(xy 120.270524 -386.729224) (xy 120.269988 -386.718675) (xy 120.261457 -386.69938) (xy 120.254014 -386.691886)
			(xy 120.234376 -386.672938) (xy 120.200944 -386.629815) (xy 120.175041 -386.581791) (xy 120.157368 -386.530168)
			(xy 120.148405 -386.476344) (xy 120.147842 -386.449062) (xy 120.148096 -386.43687) (xy 120.14835 -386.427218)
			(xy 120.142254 -386.409184) (xy 120.08358 -386.341874) (xy 120.066816 -386.333238) (xy 120.05691 -386.332222)
			(xy 120.030009 -386.328811) (xy 119.977724 -386.314455) (xy 119.92848 -386.291763) (xy 119.883597 -386.261344)
			(xy 119.844276 -386.224012) (xy 119.81157 -386.180767) (xy 119.786355 -386.132766) (xy 119.769306 -386.081296)
			(xy 119.764556 -386.0546) (xy 119.763032 -386.045202) (xy 119.490236 -385.57327) (xy 119.48287 -385.567428)
			(xy 119.464117 -385.551598) (xy 119.430999 -385.515387) (xy 119.403587 -385.474684) (xy 119.382482 -385.430381)
			(xy 119.368146 -385.38345) (xy 119.360892 -385.334916) (xy 119.360442 -385.31038) (xy 118.843648 -385.31038)
			(xy 119.092218 -385.740402) (xy 119.099584 -385.746244) (xy 119.118362 -385.762046) (xy 119.15148 -385.798262)
			(xy 119.17889 -385.83897) (xy 119.199991 -385.883278) (xy 119.214321 -385.930216) (xy 119.221566 -385.978754)
			(xy 119.222012 -386.003292) (xy 119.221758 -386.015484) (xy 119.221504 -386.025136) (xy 119.2276 -386.04317)
			(xy 119.286274 -386.11048) (xy 119.303038 -386.119116) (xy 119.31269 -386.120132) (xy 119.339451 -386.1235)
			(xy 119.391474 -386.137721) (xy 119.440499 -386.160194) (xy 119.485229 -386.190325) (xy 119.524477 -386.227314)
			(xy 119.557203 -386.270182) (xy 119.582539 -386.317791) (xy 119.599815 -386.368881) (xy 119.608572 -386.422096)
			(xy 119.609108 -386.449062) (xy 119.608574 -386.476347) (xy 119.59962 -386.530178) (xy 119.581947 -386.581807)
			(xy 119.556037 -386.629834) (xy 119.522592 -386.672954) (xy 119.502936 -386.691886) (xy 119.495544 -386.699416)
			(xy 119.487013 -386.718689) (xy 119.486426 -386.729224) (xy 119.486426 -386.8039) (xy 119.486934 -386.814452)
			(xy 119.495483 -386.833748) (xy 119.502936 -386.841238) (xy 119.522576 -386.860184) (xy 119.55601 -386.903306)
			(xy 119.581914 -386.95133) (xy 119.599586 -387.002955) (xy 119.608547 -387.056779) (xy 119.609108 -387.084062)
			(xy 119.608665 -387.108178) (xy 119.601668 -387.155901) (xy 119.587816 -387.202102) (xy 119.567404 -387.245803)
			(xy 119.554498 -387.26618) (xy 119.548656 -387.27507) (xy 119.5451 -387.295136) (xy 119.566182 -387.387338)
			(xy 119.578374 -387.404102) (xy 119.587264 -387.409436) (xy 119.608072 -387.42228) (xy 119.645976 -387.453173)
			(xy 119.678917 -387.489311) (xy 119.706177 -387.529906) (xy 119.727161 -387.574073) (xy 119.741412 -387.620848)
			(xy 119.748619 -387.669213) (xy 119.749062 -387.693662) (xy 119.748655 -387.718036) (xy 119.741508 -387.766257)
			(xy 119.727364 -387.812907) (xy 119.706528 -387.856977) (xy 119.679452 -387.897514) (xy 119.646721 -387.933639)
			(xy 119.628158 -387.94944) (xy 119.619268 -387.956552) (xy 119.60987 -387.97611) (xy 119.607076 -388.075424)
			(xy 119.615712 -388.09549) (xy 119.624094 -388.10311) (xy 119.642531 -388.120584) (xy 119.673882 -388.16055)
			(xy 119.698182 -388.205155) (xy 119.714761 -388.253169) (xy 119.723162 -388.303264) (xy 119.723662 -388.328662)
			(xy 119.723559 -388.339943) (xy 119.721907 -388.362445) (xy 119.72036 -388.37362) (xy 119.71909 -388.38251)
			(xy 119.722646 -388.400036) (xy 119.76608 -388.470902) (xy 119.779796 -388.482078) (xy 119.788432 -388.484872)
			(xy 119.810673 -388.492818) (xy 119.852595 -388.514566) (xy 119.890669 -388.542508) (xy 119.923989 -388.575978)
			(xy 119.951759 -388.614178) (xy 119.96293 -388.634986) (xy 119.963438 -388.636002) (xy 120.355868 -389.314944)
			(xy 120.368606 -389.338307) (xy 120.386718 -389.388336) (xy 120.395926 -389.440741) (xy 120.396508 -389.467344)
			(xy 120.396078 -389.491336) (xy 120.388565 -389.53873) (xy 120.373732 -389.584364) (xy 120.351943 -389.627117)
			(xy 120.323735 -389.665935) (xy 120.289802 -389.699863) (xy 120.250979 -389.728066) (xy 120.208224 -389.749849)
			(xy 120.162587 -389.764676) (xy 120.115192 -389.772181) (xy 120.0912 -389.772652) (xy 120.06767 -389.772169)
			(xy 120.021163 -389.764968) (xy 119.976316 -389.750707) (xy 119.934192 -389.729725) (xy 119.895793 -389.702519)
			(xy 119.86203 -389.669735) (xy 119.833706 -389.632154) (xy 119.822214 -389.611616) (xy 119.82196 -389.611108)
			(xy 119.821452 -389.610346) (xy 119.423688 -388.922006) (xy 119.411772 -388.899338) (xy 119.394835 -388.851013)
			(xy 119.386175 -388.800542) (xy 119.385588 -388.77494) (xy 119.385588 -388.774432) (xy 119.385745 -388.763083)
			(xy 119.387522 -388.740454) (xy 119.389144 -388.72922) (xy 119.390414 -388.72033) (xy 119.386858 -388.703058)
			(xy 119.343424 -388.631938) (xy 119.329454 -388.621016) (xy 119.321072 -388.617968) (xy 119.298676 -388.609918)
			(xy 119.256457 -388.587963) (xy 119.218159 -388.559718) (xy 119.184712 -388.525869) (xy 119.156926 -388.487237)
			(xy 119.135476 -388.444759) (xy 119.120883 -388.399466) (xy 119.113499 -388.352455) (xy 119.113046 -388.328662)
			(xy 119.113557 -388.303266) (xy 119.121967 -388.253176) (xy 119.13855 -388.205167) (xy 119.162848 -388.160565)
			(xy 119.194191 -388.120597) (xy 119.212614 -388.10311) (xy 119.220996 -388.09549) (xy 119.229632 -388.075424)
			(xy 119.226838 -387.97611) (xy 119.21744 -387.956552) (xy 119.20855 -387.94944) (xy 119.190012 -387.933613)
			(xy 119.157292 -387.897487) (xy 119.130222 -387.856953) (xy 119.109387 -387.812889) (xy 119.095239 -387.766246)
			(xy 119.088084 -387.718033) (xy 119.087646 -387.693662) (xy 119.08806 -387.669545) (xy 119.095067 -387.621821)
			(xy 119.108927 -387.57562) (xy 119.129347 -387.531921) (xy 119.142256 -387.511544) (xy 119.148098 -387.502654)
			(xy 119.151654 -387.482588) (xy 119.130572 -387.390386) (xy 119.11838 -387.373622) (xy 119.10949 -387.368288)
			(xy 119.088705 -387.355408) (xy 119.050799 -387.324523) (xy 119.017854 -387.288393) (xy 118.990591 -387.247804)
			(xy 118.969602 -387.203642) (xy 118.955348 -387.15687) (xy 118.948137 -387.10851) (xy 118.947692 -387.084062)
			(xy 118.948241 -387.056777) (xy 118.957192 -387.002948) (xy 118.974861 -386.951318) (xy 119.000768 -386.903292)
			(xy 119.034209 -386.860171) (xy 119.053864 -386.841238) (xy 119.061246 -386.833699) (xy 119.069783 -386.814433)
			(xy 119.070374 -386.8039) (xy 119.070374 -386.729224) (xy 119.069853 -386.718673) (xy 119.061313 -386.699377)
			(xy 119.053864 -386.691886) (xy 119.034235 -386.672929) (xy 119.0008 -386.62981) (xy 118.974894 -386.581788)
			(xy 118.957219 -386.530166) (xy 118.948255 -386.476344) (xy 118.947692 -386.449062) (xy 118.947946 -386.43687)
			(xy 118.9482 -386.427218) (xy 118.942104 -386.409184) (xy 118.88343 -386.341874) (xy 118.866666 -386.333238)
			(xy 118.857014 -386.332222) (xy 118.830113 -386.328808) (xy 118.777828 -386.314452) (xy 118.728585 -386.291761)
			(xy 118.683701 -386.261343) (xy 118.64438 -386.224011) (xy 118.611674 -386.180766) (xy 118.586459 -386.132766)
			(xy 118.56941 -386.081296) (xy 118.56466 -386.0546) (xy 118.563136 -386.045202) (xy 118.29034 -385.57327)
			(xy 118.282974 -385.567428) (xy 118.264222 -385.551598) (xy 118.231103 -385.515386) (xy 118.203691 -385.474683)
			(xy 118.182586 -385.430381) (xy 118.16825 -385.38345) (xy 118.160996 -385.334916) (xy 118.160546 -385.31038)
			(xy 117.643462 -385.31038) (xy 117.892068 -385.740402) (xy 117.899434 -385.746244) (xy 117.918223 -385.762033)
			(xy 117.951338 -385.798254) (xy 117.978745 -385.838965) (xy 117.999844 -385.883275) (xy 118.014173 -385.930214)
			(xy 118.021417 -385.978753) (xy 118.021862 -386.003292) (xy 118.021608 -386.015484) (xy 118.021354 -386.025136)
			(xy 118.02745 -386.04317) (xy 118.086124 -386.11048) (xy 118.102888 -386.119116) (xy 118.112794 -386.120132)
			(xy 118.139555 -386.123496) (xy 118.191578 -386.137718) (xy 118.240604 -386.160192) (xy 118.285333 -386.190323)
			(xy 118.324581 -386.227313) (xy 118.357307 -386.270181) (xy 118.382643 -386.31779) (xy 118.399919 -386.36888)
			(xy 118.408676 -386.422096) (xy 118.409212 -386.449062) (xy 118.408677 -386.476347) (xy 118.399723 -386.530177)
			(xy 118.38205 -386.581807) (xy 118.35614 -386.629833) (xy 118.322696 -386.672954) (xy 118.30304 -386.691886)
			(xy 118.295649 -386.699416) (xy 118.287117 -386.71869) (xy 118.28653 -386.729224) (xy 118.28653 -386.8039)
			(xy 118.287037 -386.814453) (xy 118.295587 -386.833748) (xy 118.30304 -386.841238) (xy 118.322681 -386.860183)
			(xy 118.356115 -386.903306) (xy 118.382019 -386.95133) (xy 118.39969 -387.002955) (xy 118.408651 -387.056779)
			(xy 118.409212 -387.084062) (xy 118.408768 -387.108178) (xy 118.401771 -387.155901) (xy 118.38792 -387.202102)
			(xy 118.367508 -387.245803) (xy 118.354602 -387.26618) (xy 118.34876 -387.27507) (xy 118.345204 -387.295136)
			(xy 118.366286 -387.387338) (xy 118.378478 -387.404102) (xy 118.387368 -387.409436) (xy 118.408177 -387.422279)
			(xy 118.44608 -387.453172) (xy 118.479021 -387.48931) (xy 118.506281 -387.529905) (xy 118.527265 -387.574072)
			(xy 118.541516 -387.620848) (xy 118.548723 -387.669213) (xy 118.549166 -387.693662) (xy 118.548757 -387.718036)
			(xy 118.541611 -387.766256) (xy 118.527467 -387.812907) (xy 118.506631 -387.856977) (xy 118.479555 -387.897513)
			(xy 118.446825 -387.933639) (xy 118.428262 -387.94944) (xy 118.419372 -387.956552) (xy 118.409974 -387.97611)
			(xy 118.40718 -388.075424) (xy 118.415816 -388.09549) (xy 118.424198 -388.10311) (xy 118.442636 -388.120583)
			(xy 118.473986 -388.16055) (xy 118.498287 -388.205155) (xy 118.514866 -388.253169) (xy 118.523266 -388.303264)
			(xy 118.523766 -388.328662) (xy 118.523663 -388.339943) (xy 118.522011 -388.362445) (xy 118.520464 -388.37362)
			(xy 118.519194 -388.38251) (xy 118.52275 -388.400036) (xy 118.566184 -388.470902) (xy 118.5799 -388.482078)
			(xy 118.588536 -388.484872) (xy 118.610778 -388.492817) (xy 118.652699 -388.514565) (xy 118.690774 -388.542507)
			(xy 118.724093 -388.575977) (xy 118.751863 -388.614177) (xy 118.763034 -388.634986) (xy 118.763542 -388.636002)
			(xy 119.155972 -389.314944) (xy 119.16871 -389.338307) (xy 119.186822 -389.388336) (xy 119.19603 -389.440741)
			(xy 119.196612 -389.467344) (xy 119.196178 -389.491336) (xy 119.188665 -389.538729) (xy 119.173832 -389.584363)
			(xy 119.152044 -389.627116) (xy 119.123836 -389.665934) (xy 119.089903 -389.699862) (xy 119.051082 -389.728065)
			(xy 119.008326 -389.749848) (xy 118.96269 -389.764675) (xy 118.915296 -389.772181) (xy 118.891304 -389.772652)
			(xy 118.867774 -389.772165) (xy 118.821268 -389.764965) (xy 118.77642 -389.750705) (xy 118.734297 -389.729723)
			(xy 118.695897 -389.702518) (xy 118.662134 -389.669735) (xy 118.63381 -389.632154) (xy 118.622318 -389.611616)
			(xy 118.622064 -389.611108) (xy 118.621556 -389.610346) (xy 118.223792 -388.922006) (xy 118.211876 -388.899338)
			(xy 118.194939 -388.851012) (xy 118.186279 -388.800542) (xy 118.185692 -388.77494) (xy 118.185692 -388.774432)
			(xy 118.185849 -388.763083) (xy 118.187626 -388.740454) (xy 118.189248 -388.72922) (xy 118.190518 -388.72033)
			(xy 118.186962 -388.703058) (xy 118.143528 -388.631938) (xy 118.129558 -388.621016) (xy 118.121176 -388.617968)
			(xy 118.098781 -388.609916) (xy 118.056562 -388.587961) (xy 118.018264 -388.559717) (xy 117.984816 -388.525868)
			(xy 117.95703 -388.487237) (xy 117.935581 -388.444759) (xy 117.920987 -388.399465) (xy 117.913603 -388.352455)
			(xy 117.91315 -388.328662) (xy 117.91366 -388.303266) (xy 117.92207 -388.253176) (xy 117.938653 -388.205167)
			(xy 117.962952 -388.160565) (xy 117.994295 -388.120597) (xy 118.012718 -388.10311) (xy 118.0211 -388.09549)
			(xy 118.029736 -388.075424) (xy 118.026942 -387.97611) (xy 118.017544 -387.956552) (xy 118.008654 -387.94944)
			(xy 117.990117 -387.933612) (xy 117.957396 -387.897486) (xy 117.930326 -387.856953) (xy 117.909492 -387.812889)
			(xy 117.895343 -387.766246) (xy 117.888188 -387.718033) (xy 117.88775 -387.693662) (xy 117.888164 -387.669544)
			(xy 117.895171 -387.621821) (xy 117.909031 -387.57562) (xy 117.929451 -387.53192) (xy 117.94236 -387.511544)
			(xy 117.948202 -387.502654) (xy 117.951758 -387.482588) (xy 117.930676 -387.390386) (xy 117.918484 -387.373622)
			(xy 117.909594 -387.368288) (xy 117.88881 -387.355406) (xy 117.850903 -387.324522) (xy 117.817959 -387.288392)
			(xy 117.790695 -387.247803) (xy 117.769707 -387.203642) (xy 117.755452 -387.15687) (xy 117.748241 -387.10851)
			(xy 117.747796 -387.084062) (xy 117.748344 -387.056777) (xy 117.757295 -387.002948) (xy 117.774964 -386.951318)
			(xy 117.800871 -386.903291) (xy 117.834313 -386.860171) (xy 117.853968 -386.841238) (xy 117.86135 -386.8337)
			(xy 117.869887 -386.814433) (xy 117.870478 -386.8039) (xy 117.870478 -386.729224) (xy 117.869956 -386.718673)
			(xy 117.861417 -386.699378) (xy 117.853968 -386.691886) (xy 117.83434 -386.672928) (xy 117.800904 -386.629809)
			(xy 117.774998 -386.581788) (xy 117.757323 -386.530166) (xy 117.748359 -386.476344) (xy 117.747796 -386.449062)
			(xy 117.74805 -386.43687) (xy 117.748304 -386.427218) (xy 117.742208 -386.409184) (xy 117.683534 -386.341874)
			(xy 117.66677 -386.333238) (xy 117.656864 -386.332222) (xy 117.629958 -386.328847) (xy 117.577672 -386.314484)
			(xy 117.528428 -386.291786) (xy 117.483546 -386.261361) (xy 117.444226 -386.224024) (xy 117.411521 -386.180775)
			(xy 117.386307 -386.132771) (xy 117.36926 -386.081298) (xy 117.36451 -386.0546) (xy 117.362986 -386.045202)
			(xy 117.089936 -385.572762) (xy 117.082824 -385.56692) (xy 117.064077 -385.551158) (xy 117.031026 -385.51501)
			(xy 117.003673 -385.474381) (xy 116.982617 -385.430158) (xy 116.968319 -385.383313) (xy 116.961092 -385.33487)
			(xy 116.96065 -385.31038) (xy 116.443602 -385.31038) (xy 116.692172 -385.740402) (xy 116.699538 -385.746244)
			(xy 116.718327 -385.762032) (xy 116.751443 -385.798253) (xy 116.77885 -385.838965) (xy 116.799948 -385.883275)
			(xy 116.814277 -385.930214) (xy 116.821521 -385.978753) (xy 116.821966 -386.003292) (xy 116.821712 -386.015484)
			(xy 116.821458 -386.025136) (xy 116.827554 -386.04317) (xy 116.886228 -386.11048) (xy 116.902992 -386.119116)
			(xy 116.912898 -386.120132) (xy 116.93966 -386.123493) (xy 116.991683 -386.137715) (xy 117.040708 -386.16019)
			(xy 117.085438 -386.190322) (xy 117.124685 -386.227312) (xy 117.157411 -386.27018) (xy 117.182748 -386.31779)
			(xy 117.200023 -386.36888) (xy 117.20878 -386.422096) (xy 117.209316 -386.449062) (xy 117.20878 -386.476347)
			(xy 117.199825 -386.530177) (xy 117.182154 -386.581807) (xy 117.156244 -386.629833) (xy 117.1228 -386.672954)
			(xy 117.103144 -386.691886) (xy 117.095753 -386.699417) (xy 117.087221 -386.71869) (xy 117.086634 -386.729224)
			(xy 117.086634 -386.8039) (xy 117.08714 -386.814453) (xy 117.09569 -386.833748) (xy 117.103144 -386.841238)
			(xy 117.122786 -386.860182) (xy 117.156219 -386.903305) (xy 117.182123 -386.95133) (xy 117.199794 -387.002955)
			(xy 117.208755 -387.056779) (xy 117.209316 -387.084062) (xy 117.208871 -387.108178) (xy 117.201875 -387.155901)
			(xy 117.188023 -387.202102) (xy 117.167612 -387.245803) (xy 117.154706 -387.26618) (xy 117.148864 -387.27507)
			(xy 117.145308 -387.295136) (xy 117.16639 -387.387338) (xy 117.178582 -387.404102) (xy 117.187472 -387.409436)
			(xy 117.208282 -387.422277) (xy 117.246185 -387.453171) (xy 117.279126 -387.489309) (xy 117.306385 -387.529905)
			(xy 117.327369 -387.574072) (xy 117.34162 -387.620848) (xy 117.348827 -387.669213) (xy 117.34927 -387.693662)
			(xy 117.34886 -387.718036) (xy 117.341713 -387.766256) (xy 117.327569 -387.812906) (xy 117.306734 -387.856977)
			(xy 117.279659 -387.897513) (xy 117.246929 -387.933639) (xy 117.228366 -387.94944) (xy 117.219476 -387.956552)
			(xy 117.210078 -387.97611) (xy 117.207284 -388.075424) (xy 117.21592 -388.09549) (xy 117.224302 -388.10311)
			(xy 117.242741 -388.120582) (xy 117.274091 -388.160549) (xy 117.298391 -388.205155) (xy 117.31497 -388.253168)
			(xy 117.32337 -388.303264) (xy 117.32387 -388.328662) (xy 117.323766 -388.339943) (xy 117.322115 -388.362445)
			(xy 117.320568 -388.37362) (xy 117.319298 -388.382764) (xy 117.3226 -388.400036) (xy 117.366288 -388.471156)
			(xy 117.380004 -388.482078) (xy 117.38864 -388.484872) (xy 117.416801 -388.495079) (xy 117.468749 -388.524883)
			(xy 117.491764 -388.544054) (xy 117.513245 -388.563639) (xy 117.54906 -388.609415) (xy 117.562884 -388.634986)
			(xy 117.563646 -388.636256) (xy 117.955822 -389.314944) (xy 117.968627 -389.338287) (xy 117.986855 -389.388304)
			(xy 117.996123 -389.440727) (xy 117.996716 -389.467344) (xy 117.996302 -389.491351) (xy 117.988781 -389.538771)
			(xy 117.973931 -389.584431) (xy 117.952119 -389.627203) (xy 117.923881 -389.666036) (xy 117.889915 -389.69997)
			(xy 117.851056 -389.728171) (xy 117.808262 -389.749942) (xy 117.762589 -389.764748) (xy 117.715161 -389.772224)
			(xy 117.691154 -389.772652) (xy 117.667622 -389.772206) (xy 117.621114 -389.764998) (xy 117.576266 -389.750731)
			(xy 117.534142 -389.729742) (xy 117.495744 -389.70253) (xy 117.461982 -389.669742) (xy 117.433659 -389.632156)
			(xy 117.422168 -389.611616) (xy 117.421914 -389.611108) (xy 117.421406 -389.610346) (xy 117.023896 -388.921752)
			(xy 117.013322 -388.901826) (xy 116.99752 -388.859576) (xy 116.988113 -388.815459) (xy 116.986304 -388.792974)
			(xy 116.985796 -388.781798) (xy 116.985796 -388.774432) (xy 116.985887 -388.763087) (xy 116.987542 -388.740458)
			(xy 116.989098 -388.72922) (xy 116.990368 -388.72033) (xy 116.986812 -388.703058) (xy 116.943378 -388.631938)
			(xy 116.929662 -388.620762) (xy 116.921026 -388.617968) (xy 116.898614 -388.609997) (xy 116.856445 -388.587988)
			(xy 116.818198 -388.559706) (xy 116.7848 -388.525835) (xy 116.757058 -388.487195) (xy 116.735644 -388.44472)
			(xy 116.721076 -388.399439) (xy 116.713705 -388.352446) (xy 116.713254 -388.328662) (xy 116.713762 -388.303266)
			(xy 116.722173 -388.253175) (xy 116.738756 -388.205167) (xy 116.763055 -388.160564) (xy 116.794399 -388.120597)
			(xy 116.812822 -388.10311) (xy 116.821204 -388.09549) (xy 116.82984 -388.075424) (xy 116.827046 -387.97611)
			(xy 116.817648 -387.956552) (xy 116.808758 -387.94944) (xy 116.790222 -387.933611) (xy 116.757501 -387.897485)
			(xy 116.73043 -387.856953) (xy 116.709596 -387.812889) (xy 116.695448 -387.766246) (xy 116.688292 -387.718033)
			(xy 116.687854 -387.693662) (xy 116.688267 -387.669544) (xy 116.695274 -387.621821) (xy 116.709135 -387.57562)
			(xy 116.729555 -387.53192) (xy 116.742464 -387.511544) (xy 116.748306 -387.502654) (xy 116.751862 -387.482588)
			(xy 116.73078 -387.390386) (xy 116.718588 -387.373622) (xy 116.709698 -387.368288) (xy 116.688915 -387.355405)
			(xy 116.651008 -387.324521) (xy 116.618063 -387.288391) (xy 116.590799 -387.247803) (xy 116.569811 -387.203641)
			(xy 116.555556 -387.15687) (xy 116.548345 -387.10851) (xy 116.5479 -387.084062) (xy 116.548447 -387.056777)
			(xy 116.557398 -387.002947) (xy 116.575067 -386.951318) (xy 116.600974 -386.903291) (xy 116.634417 -386.86017)
			(xy 116.654072 -386.841238) (xy 116.661455 -386.833701) (xy 116.669991 -386.814433) (xy 116.670582 -386.8039)
			(xy 116.670582 -386.729224) (xy 116.670059 -386.718673) (xy 116.66152 -386.699378) (xy 116.654072 -386.691886)
			(xy 116.634445 -386.672928) (xy 116.601009 -386.629809) (xy 116.575102 -386.581788) (xy 116.557427 -386.530166)
			(xy 116.548463 -386.476344) (xy 116.5479 -386.449062) (xy 116.548154 -386.43687) (xy 116.548408 -386.427218)
			(xy 116.542312 -386.409184) (xy 116.483638 -386.341874) (xy 116.466874 -386.333238) (xy 116.456968 -386.332222)
			(xy 116.430062 -386.328844) (xy 116.377776 -386.314481) (xy 116.328533 -386.291784) (xy 116.28365 -386.26136)
			(xy 116.24433 -386.224023) (xy 116.211625 -386.180774) (xy 116.186411 -386.132771) (xy 116.169364 -386.081298)
			(xy 116.164614 -386.0546) (xy 116.16309 -386.045202) (xy 115.890294 -385.57327) (xy 115.882928 -385.567428)
			(xy 115.864166 -385.551608) (xy 115.831051 -385.515393) (xy 115.803641 -385.474688) (xy 115.782538 -385.430384)
			(xy 115.768203 -385.383451) (xy 115.76095 -385.334917) (xy 115.7605 -385.31038) (xy 115.243706 -385.31038)
			(xy 115.492276 -385.740402) (xy 115.499642 -385.746244) (xy 115.518432 -385.762031) (xy 115.551547 -385.798252)
			(xy 115.578954 -385.838964) (xy 115.600053 -385.883275) (xy 115.614381 -385.930214) (xy 115.621625 -385.978753)
			(xy 115.62207 -386.003292) (xy 115.621816 -386.015484) (xy 115.621562 -386.025136) (xy 115.627658 -386.04317)
			(xy 115.686332 -386.11048) (xy 115.703096 -386.119116) (xy 115.712748 -386.120132) (xy 115.739515 -386.123452)
			(xy 115.791539 -386.137682) (xy 115.840564 -386.160164) (xy 115.885293 -386.190301) (xy 115.92454 -386.227296)
			(xy 115.957264 -386.270169) (xy 115.982599 -386.317783) (xy 115.999874 -386.368876) (xy 116.008631 -386.422095)
			(xy 116.009166 -386.449062) (xy 116.008614 -386.476346) (xy 115.999661 -386.530175) (xy 115.981992 -386.581803)
			(xy 115.956086 -386.62983) (xy 115.922647 -386.672952) (xy 115.902994 -386.691886) (xy 115.895596 -386.69941)
			(xy 115.88707 -386.718688) (xy 115.886484 -386.729224) (xy 115.886484 -386.8039) (xy 115.887004 -386.814451)
			(xy 115.895546 -386.833746) (xy 115.902994 -386.841238) (xy 115.922645 -386.860173) (xy 115.956075 -386.903299)
			(xy 115.981976 -386.951327) (xy 115.999646 -387.002953) (xy 116.008605 -387.056779) (xy 116.009166 -387.084062)
			(xy 116.008713 -387.108178) (xy 116.001718 -387.1559) (xy 115.987869 -387.202101) (xy 115.96746 -387.245802)
			(xy 115.954556 -387.26618) (xy 115.948714 -387.27507) (xy 115.945158 -387.295136) (xy 115.96624 -387.387338)
			(xy 115.978432 -387.404102) (xy 115.987322 -387.409436) (xy 116.00812 -387.422295) (xy 116.046026 -387.453184)
			(xy 116.07897 -387.489318) (xy 116.106231 -387.529911) (xy 116.127217 -387.574076) (xy 116.141469 -387.62085)
			(xy 116.148677 -387.669213) (xy 116.14912 -387.693662) (xy 116.148692 -387.718035) (xy 116.141546 -387.766254)
			(xy 116.127405 -387.812903) (xy 116.106573 -387.856973) (xy 116.079502 -387.89751) (xy 116.046776 -387.933637)
			(xy 116.028216 -387.94944) (xy 116.019326 -387.956552) (xy 116.009928 -387.97611) (xy 116.007134 -388.075424)
			(xy 116.01577 -388.09549) (xy 116.024152 -388.10311) (xy 116.042601 -388.120572) (xy 116.073947 -388.160543)
			(xy 116.098244 -388.205151) (xy 116.114821 -388.253167) (xy 116.123221 -388.303264) (xy 116.12372 -388.328662)
			(xy 116.123616 -388.339943) (xy 116.121965 -388.362445) (xy 116.120418 -388.37362) (xy 116.119148 -388.38251)
			(xy 116.122704 -388.400036) (xy 116.166138 -388.470902) (xy 116.179854 -388.482078) (xy 116.18849 -388.484872)
			(xy 116.210741 -388.492791) (xy 116.252662 -388.514546) (xy 116.290734 -388.542495) (xy 116.324051 -388.57597)
			(xy 116.351818 -388.614175) (xy 116.362988 -388.634986) (xy 116.363496 -388.636002) (xy 116.755926 -389.314944)
			(xy 116.768731 -389.338286) (xy 116.786959 -389.388304) (xy 116.796227 -389.440727) (xy 116.79682 -389.467344)
			(xy 116.796402 -389.49135) (xy 116.788881 -389.538771) (xy 116.774031 -389.58443) (xy 116.752219 -389.627202)
			(xy 116.723982 -389.666034) (xy 116.690016 -389.699969) (xy 116.651158 -389.728169) (xy 116.608365 -389.749941)
			(xy 116.562692 -389.764748) (xy 116.515265 -389.772224) (xy 116.491258 -389.772652) (xy 116.467726 -389.772202)
			(xy 116.421219 -389.764996) (xy 116.37637 -389.750729) (xy 116.334247 -389.72974) (xy 116.295848 -389.702529)
			(xy 116.262086 -389.669741) (xy 116.233763 -389.632156) (xy 116.222272 -389.611616) (xy 116.222018 -389.611108)
			(xy 116.22151 -389.610346) (xy 115.823746 -388.922006) (xy 115.811869 -388.89933) (xy 115.795019 -388.850996)
			(xy 115.786446 -388.800533) (xy 115.7859 -388.77494) (xy 115.7859 -388.774432) (xy 115.785991 -388.763087)
			(xy 115.787646 -388.740458) (xy 115.789202 -388.72922) (xy 115.790472 -388.72033) (xy 115.786916 -388.703058)
			(xy 115.743482 -388.631938) (xy 115.729512 -388.621016) (xy 115.72113 -388.617968) (xy 115.698725 -388.609942)
			(xy 115.656507 -388.587982) (xy 115.618211 -388.559732) (xy 115.584765 -388.525879) (xy 115.556981 -388.487244)
			(xy 115.535533 -388.444764) (xy 115.52094 -388.399468) (xy 115.513557 -388.352456) (xy 115.513104 -388.328662)
			(xy 115.513629 -388.303267) (xy 115.522038 -388.253178) (xy 115.538618 -388.20517) (xy 115.562913 -388.160567)
			(xy 115.594252 -388.120599) (xy 115.612672 -388.10311) (xy 115.621054 -388.09549) (xy 115.62969 -388.075424)
			(xy 115.626896 -387.97611) (xy 115.617498 -387.956552) (xy 115.608608 -387.94944) (xy 115.590062 -387.933623)
			(xy 115.557343 -387.897493) (xy 115.530276 -387.856958) (xy 115.509443 -387.812892) (xy 115.495297 -387.766247)
			(xy 115.488141 -387.718033) (xy 115.487704 -387.693662) (xy 115.488109 -387.669544) (xy 115.495117 -387.62182)
			(xy 115.50898 -387.575619) (xy 115.529403 -387.53192) (xy 115.542314 -387.511544) (xy 115.548156 -387.502654)
			(xy 115.551712 -387.482588) (xy 115.53063 -387.390386) (xy 115.518438 -387.373622) (xy 115.509548 -387.368288)
			(xy 115.488754 -387.355423) (xy 115.450849 -387.324534) (xy 115.417907 -387.2884) (xy 115.390645 -387.247809)
			(xy 115.369659 -387.203645) (xy 115.355405 -387.156872) (xy 115.348195 -387.10851) (xy 115.34775 -387.084062)
			(xy 115.348313 -387.056778) (xy 115.357262 -387.00295) (xy 115.374928 -386.951321) (xy 115.400832 -386.903294)
			(xy 115.43427 -386.860172) (xy 115.453922 -386.841238) (xy 115.461312 -386.833707) (xy 115.469842 -386.814434)
			(xy 115.470432 -386.8039) (xy 115.470432 -386.729224) (xy 115.469894 -386.718676) (xy 115.461364 -386.699381)
			(xy 115.453922 -386.691886) (xy 115.434286 -386.672937) (xy 115.400853 -386.629814) (xy 115.374949 -386.581791)
			(xy 115.357276 -386.530168) (xy 115.348313 -386.476344) (xy 115.34775 -386.449062) (xy 115.348004 -386.43687)
			(xy 115.348258 -386.427218) (xy 115.342162 -386.409184) (xy 115.283488 -386.341874) (xy 115.266724 -386.333238)
			(xy 115.257072 -386.332222) (xy 115.230167 -386.328841) (xy 115.177881 -386.314479) (xy 115.128637 -386.291782)
			(xy 115.083755 -386.261358) (xy 115.044434 -386.224022) (xy 115.011729 -386.180774) (xy 114.986516 -386.13277)
			(xy 114.969468 -386.081297) (xy 114.964718 -386.0546) (xy 114.963194 -386.045202) (xy 114.690398 -385.57327)
			(xy 114.683032 -385.567428) (xy 114.664271 -385.551608) (xy 114.631155 -385.515393) (xy 114.603746 -385.474688)
			(xy 114.582642 -385.430384) (xy 114.568307 -385.383451) (xy 114.561054 -385.334917) (xy 114.560604 -385.31038)
			(xy 112.234193 -385.31038) (xy 112.271732 -385.332791) (xy 112.312015 -385.36652) (xy 112.346456 -385.406197)
			(xy 112.374186 -385.450823) (xy 112.394507 -385.499273) (xy 112.406909 -385.550328) (xy 112.411077 -385.602702)
			(xy 112.406908 -385.655076) (xy 112.394506 -385.706131) (xy 112.374184 -385.754581) (xy 112.346453 -385.799206)
			(xy 112.312012 -385.838883) (xy 112.271729 -385.872611) (xy 112.26684 -385.87553) (xy 113.933986 -385.87553)
			(xy 113.934496 -385.849543) (xy 113.942626 -385.798208) (xy 113.958687 -385.748778) (xy 113.982283 -385.702468)
			(xy 114.012833 -385.66042) (xy 114.049584 -385.623669) (xy 114.091632 -385.593119) (xy 114.137942 -385.569523)
			(xy 114.187372 -385.553462) (xy 114.238707 -385.545332) (xy 114.290681 -385.545332) (xy 114.342016 -385.553462)
			(xy 114.391446 -385.569523) (xy 114.437756 -385.593119) (xy 114.479804 -385.623669) (xy 114.516555 -385.66042)
			(xy 114.547105 -385.702468) (xy 114.570701 -385.748778) (xy 114.586762 -385.798208) (xy 114.594892 -385.849543)
			(xy 114.595402 -385.87553) (xy 114.595014 -385.899206) (xy 114.588283 -385.946077) (xy 114.574919 -385.991503)
			(xy 114.56543 -386.013198) (xy 114.561112 -386.022596) (xy 114.56035 -386.042662) (xy 114.592608 -386.129022)
			(xy 114.606324 -386.143754) (xy 114.615722 -386.148072) (xy 114.640084 -386.159776) (xy 114.684956 -386.189899)
			(xy 114.724335 -386.226914) (xy 114.757175 -386.269837) (xy 114.782602 -386.317526) (xy 114.799941 -386.368714)
			(xy 114.80873 -386.42204) (xy 114.80927 -386.449062) (xy 114.808748 -386.476348) (xy 114.799793 -386.530179)
			(xy 114.782118 -386.58181) (xy 114.756205 -386.629836) (xy 114.722756 -386.672955) (xy 114.703098 -386.691886)
			(xy 114.6957 -386.699411) (xy 114.687174 -386.718688) (xy 114.686588 -386.729224) (xy 114.686588 -386.8039)
			(xy 114.687107 -386.814451) (xy 114.69565 -386.833746) (xy 114.703098 -386.841238) (xy 114.722731 -386.860191)
			(xy 114.756168 -386.90331) (xy 114.782074 -386.951333) (xy 114.799747 -387.002956) (xy 114.808709 -387.05678)
			(xy 114.80927 -387.084062) (xy 114.808817 -387.108178) (xy 114.801821 -387.1559) (xy 114.787972 -387.202101)
			(xy 114.767564 -387.245802) (xy 114.75466 -387.26618) (xy 114.748818 -387.27507) (xy 114.745262 -387.295136)
			(xy 114.766344 -387.387338) (xy 114.778536 -387.404102) (xy 114.787426 -387.409436) (xy 114.808225 -387.422294)
			(xy 114.846131 -387.453183) (xy 114.879074 -387.489317) (xy 114.906336 -387.52991) (xy 114.927321 -387.574075)
			(xy 114.941573 -387.62085) (xy 114.948781 -387.669213) (xy 114.949224 -387.693662) (xy 114.948794 -387.718035)
			(xy 114.941649 -387.766254) (xy 114.927508 -387.812903) (xy 114.906676 -387.856972) (xy 114.879605 -387.89751)
			(xy 114.84688 -387.933637) (xy 114.82832 -387.94944) (xy 114.81943 -387.956552) (xy 114.810032 -387.97611)
			(xy 114.807238 -388.075424) (xy 114.815874 -388.09549) (xy 114.824256 -388.10311) (xy 114.842705 -388.120572)
			(xy 114.874052 -388.160542) (xy 114.898349 -388.205151) (xy 114.914925 -388.253167) (xy 114.923325 -388.303264)
			(xy 114.923824 -388.328662) (xy 114.923721 -388.339943) (xy 114.922069 -388.362445) (xy 114.920522 -388.37362)
			(xy 114.919252 -388.38251) (xy 114.922808 -388.400036) (xy 114.966242 -388.470902) (xy 114.979958 -388.482078)
			(xy 114.988594 -388.484872) (xy 115.010846 -388.492789) (xy 115.052766 -388.514545) (xy 115.090839 -388.542494)
			(xy 115.124155 -388.57597) (xy 115.151922 -388.614175) (xy 115.163092 -388.634986) (xy 115.1636 -388.636002)
			(xy 115.55603 -389.314944) (xy 115.568836 -389.338286) (xy 115.587063 -389.388304) (xy 115.596331 -389.440727)
			(xy 115.596924 -389.467344) (xy 115.596502 -389.49135) (xy 115.588981 -389.53877) (xy 115.574132 -389.584429)
			(xy 115.55232 -389.627201) (xy 115.524084 -389.666033) (xy 115.490118 -389.699967) (xy 115.45126 -389.728168)
			(xy 115.408468 -389.74994) (xy 115.362795 -389.764747) (xy 115.315369 -389.772224) (xy 115.291362 -389.772652)
			(xy 115.26783 -389.772199) (xy 115.221323 -389.764993) (xy 115.176475 -389.750727) (xy 115.134351 -389.729739)
			(xy 115.095952 -389.702528) (xy 115.06219 -389.669741) (xy 115.033867 -389.632155) (xy 115.022376 -389.611616)
			(xy 115.022122 -389.611108) (xy 115.021614 -389.610346) (xy 114.62385 -388.922006) (xy 114.611973 -388.899329)
			(xy 114.595123 -388.850996) (xy 114.58655 -388.800533) (xy 114.586004 -388.77494) (xy 114.586004 -388.774432)
			(xy 114.586095 -388.763087) (xy 114.58775 -388.740458) (xy 114.589306 -388.72922) (xy 114.590576 -388.72033)
			(xy 114.58702 -388.703058) (xy 114.543586 -388.631938) (xy 114.529616 -388.621016) (xy 114.521234 -388.617968)
			(xy 114.49883 -388.60994) (xy 114.456612 -388.58798) (xy 114.418316 -388.559731) (xy 114.38487 -388.525878)
			(xy 114.357086 -388.487244) (xy 114.335637 -388.444763) (xy 114.321044 -388.399468) (xy 114.313661 -388.352456)
			(xy 114.313208 -388.328662) (xy 114.313731 -388.303267) (xy 114.322141 -388.253178) (xy 114.338721 -388.20517)
			(xy 114.363016 -388.160567) (xy 114.394355 -388.120599) (xy 114.412776 -388.10311) (xy 114.421158 -388.09549)
			(xy 114.429794 -388.075424) (xy 114.427 -387.97611) (xy 114.417602 -387.956552) (xy 114.408712 -387.94944)
			(xy 114.390167 -387.933622) (xy 114.357448 -387.897493) (xy 114.33038 -387.856957) (xy 114.309547 -387.812891)
			(xy 114.295401 -387.766247) (xy 114.288245 -387.718033) (xy 114.287808 -387.693662) (xy 114.288229 -387.669545)
			(xy 114.295235 -387.621822) (xy 114.309093 -387.575621) (xy 114.32951 -387.531921) (xy 114.342418 -387.511544)
			(xy 114.34826 -387.502654) (xy 114.351816 -387.482588) (xy 114.330734 -387.390386) (xy 114.318542 -387.373622)
			(xy 114.309652 -387.368288) (xy 114.288859 -387.355422) (xy 114.250954 -387.324533) (xy 114.218011 -387.288399)
			(xy 114.190749 -387.247808) (xy 114.169763 -387.203645) (xy 114.155509 -387.156872) (xy 114.148299 -387.10851)
			(xy 114.147854 -387.084062) (xy 114.148415 -387.056778) (xy 114.157365 -387.00295) (xy 114.175031 -386.951321)
			(xy 114.200935 -386.903294) (xy 114.234373 -386.860172) (xy 114.254026 -386.841238) (xy 114.261402 -386.833694)
			(xy 114.269944 -386.814432) (xy 114.270536 -386.8039) (xy 114.270536 -386.729224) (xy 114.269997 -386.718676)
			(xy 114.261468 -386.699381) (xy 114.254026 -386.691886) (xy 114.23439 -386.672936) (xy 114.200958 -386.629814)
			(xy 114.175053 -386.58179) (xy 114.15738 -386.530167) (xy 114.148417 -386.476344) (xy 114.147854 -386.449062)
			(xy 114.148234 -386.425386) (xy 114.154968 -386.378515) (xy 114.168335 -386.333088) (xy 114.177826 -386.311394)
			(xy 114.182144 -386.301996) (xy 114.182906 -386.28193) (xy 114.150648 -386.19557) (xy 114.136932 -386.180838)
			(xy 114.127534 -386.17652) (xy 114.103158 -386.164843) (xy 114.058289 -386.134713) (xy 114.018912 -386.097693)
			(xy 113.986074 -386.054765) (xy 113.960649 -386.007072) (xy 113.943312 -385.955881) (xy 113.934525 -385.902553)
			(xy 113.933986 -385.87553) (xy 112.26684 -385.87553) (xy 112.226617 -385.899543) (xy 112.177812 -385.918999)
			(xy 112.126545 -385.930489) (xy 112.10036 -385.93268) (xy 112.090708 -385.933442) (xy 112.073182 -385.94157)
			(xy 112.018826 -385.999482) (xy 112.012541 -386.006772) (xy 112.005482 -386.024662) (xy 112.00511 -386.03428)
			(xy 112.00511 -386.063744) (xy 112.005673 -386.074852) (xy 112.015024 -386.095005) (xy 112.023144 -386.102606)
			(xy 112.091724 -386.16001) (xy 112.11306 -386.165852) (xy 112.124236 -386.16382) (xy 112.13847 -386.161459)
			(xy 112.167213 -386.158912) (xy 112.18164 -386.15874) (xy 112.207626 -386.159226) (xy 112.258957 -386.167363)
			(xy 112.308383 -386.183429) (xy 112.354687 -386.20703) (xy 112.396729 -386.237583) (xy 112.433474 -386.274338)
			(xy 112.464016 -386.316388) (xy 112.487605 -386.362699) (xy 112.503658 -386.412129) (xy 112.511781 -386.463462)
			(xy 112.512348 -386.489448) (xy 112.511789 -386.516777) (xy 112.502809 -386.570693) (xy 112.485083 -386.622398)
			(xy 112.459095 -386.670483) (xy 112.442752 -386.692394) (xy 112.437164 -386.69976) (xy 112.431576 -386.716524)
			(xy 112.435132 -386.800598) (xy 112.44199 -386.816854) (xy 112.448086 -386.823712) (xy 112.46446 -386.842121)
			(xy 112.492132 -386.882883) (xy 112.513447 -386.9273) (xy 112.527933 -386.974389) (xy 112.535269 -387.023107)
			(xy 112.535716 -387.04774) (xy 112.535203 -387.073725) (xy 112.527068 -387.125055) (xy 112.511004 -387.174481)
			(xy 112.487406 -387.220786) (xy 112.456855 -387.262829) (xy 112.420105 -387.299576) (xy 112.378058 -387.330122)
			(xy 112.331752 -387.353716) (xy 112.282324 -387.369775) (xy 112.230993 -387.377906) (xy 112.205008 -387.378448)
			(xy 112.186042 -387.378173) (xy 112.148358 -387.373847) (xy 112.129824 -387.369812) (xy 112.118394 -387.367018)
			(xy 112.096042 -387.372098) (xy 112.024414 -387.428994) (xy 112.015737 -387.436519) (xy 112.005687 -387.457147)
			(xy 112.00511 -387.468618) (xy 112.00511 -387.875272) (xy 112.005804 -387.886716) (xy 112.015829 -387.907298)
			(xy 112.024414 -387.914896) (xy 112.096042 -387.971792) (xy 112.118394 -387.976872) (xy 112.129824 -387.974078)
			(xy 112.148354 -387.970023) (xy 112.186041 -387.965696) (xy 112.205008 -387.965442) (xy 112.230991 -387.965952)
			(xy 112.282316 -387.974083) (xy 112.331738 -387.990142) (xy 112.37804 -388.013735) (xy 112.42008 -388.04428)
			(xy 112.456825 -388.081026) (xy 112.487369 -388.123067) (xy 112.510961 -388.169369) (xy 112.527019 -388.218791)
			(xy 112.535148 -388.270117) (xy 112.535148 -388.322083) (xy 112.527019 -388.373409) (xy 112.510961 -388.422831)
			(xy 112.487369 -388.469133) (xy 112.456825 -388.511174) (xy 112.42008 -388.54792) (xy 112.37804 -388.578465)
			(xy 112.331738 -388.602058) (xy 112.282316 -388.618117) (xy 112.230991 -388.626248) (xy 112.205008 -388.626858)
			(xy 112.186042 -388.626583) (xy 112.148358 -388.622256) (xy 112.129824 -388.618222) (xy 112.118394 -388.615428)
			(xy 112.096042 -388.620508) (xy 112.024414 -388.677404) (xy 112.015739 -388.68493) (xy 112.005693 -388.705558)
			(xy 112.00511 -388.717028) (xy 112.00511 -388.981696) (xy 112.005547 -388.991391) (xy 112.01274 -389.009399)
			(xy 112.01908 -389.016748) (xy 112.038834 -389.038165) (xy 112.072268 -389.085878) (xy 112.09805 -389.138125)
			(xy 112.115579 -389.193687) (xy 112.124447 -389.251269) (xy 112.124998 -389.2804) (xy 112.124426 -389.309528)
			(xy 112.115533 -389.367101) (xy 112.097999 -389.422656) (xy 112.072231 -389.474904) (xy 112.038826 -389.522632)
			(xy 112.01908 -389.544052) (xy 112.012222 -389.551418) (xy 112.00511 -389.569198) (xy 112.00511 -389.643874)
			(xy 112.005756 -389.655139) (xy 112.015512 -389.675451) (xy 112.023906 -389.68299) (xy 112.093756 -389.74014)
			(xy 112.1156 -389.745728) (xy 112.12703 -389.743188) (xy 112.143426 -389.740075) (xy 112.176636 -389.736771)
			(xy 112.193324 -389.736584) (xy 112.21931 -389.737095) (xy 112.270642 -389.745229) (xy 112.32007 -389.761292)
			(xy 112.366377 -389.784889) (xy 112.408422 -389.815439) (xy 112.445172 -389.85219) (xy 112.47572 -389.894237)
			(xy 112.499314 -389.940545) (xy 112.515375 -389.989973) (xy 112.523506 -390.041306) (xy 112.524032 -390.067292)
			(xy 112.523639 -390.090526) (xy 112.517138 -390.136537) (xy 112.510371 -390.160002) (xy 114.185204 -390.160002)
			(xy 114.189164 -390.110948) (xy 114.200941 -390.063164) (xy 114.220232 -390.017888) (xy 114.246535 -389.976292)
			(xy 114.27917 -389.939455) (xy 114.317291 -389.90833) (xy 114.359912 -389.883723) (xy 114.405928 -389.866271)
			(xy 114.454147 -389.856427) (xy 114.503322 -389.854446) (xy 114.552177 -389.860378) (xy 114.599448 -389.87407)
			(xy 114.64391 -389.895168) (xy 114.684413 -389.923124) (xy 114.719906 -389.957216) (xy 114.749471 -389.99656)
			(xy 114.772342 -390.040137) (xy 114.787926 -390.086818) (xy 114.795821 -390.135395) (xy 114.796316 -390.160002)
			(xy 115.385354 -390.160002) (xy 115.389314 -390.110948) (xy 115.401091 -390.063164) (xy 115.420382 -390.017888)
			(xy 115.446685 -389.976292) (xy 115.47932 -389.939455) (xy 115.517441 -389.90833) (xy 115.560062 -389.883723)
			(xy 115.606078 -389.866271) (xy 115.654297 -389.856427) (xy 115.703472 -389.854446) (xy 115.752327 -389.860378)
			(xy 115.799598 -389.87407) (xy 115.84406 -389.895168) (xy 115.884563 -389.923124) (xy 115.920056 -389.957216)
			(xy 115.949621 -389.99656) (xy 115.972492 -390.040137) (xy 115.988076 -390.086818) (xy 115.995971 -390.135395)
			(xy 115.996466 -390.160002) (xy 116.585504 -390.160002) (xy 116.589464 -390.110948) (xy 116.601241 -390.063164)
			(xy 116.620532 -390.017888) (xy 116.646835 -389.976292) (xy 116.67947 -389.939455) (xy 116.717591 -389.90833)
			(xy 116.760212 -389.883723) (xy 116.806228 -389.866271) (xy 116.854447 -389.856427) (xy 116.903622 -389.854446)
			(xy 116.952477 -389.860378) (xy 116.999748 -389.87407) (xy 117.04421 -389.895168) (xy 117.084713 -389.923124)
			(xy 117.120206 -389.957216) (xy 117.149771 -389.99656) (xy 117.172642 -390.040137) (xy 117.188226 -390.086818)
			(xy 117.196121 -390.135395) (xy 117.196616 -390.160002) (xy 117.7854 -390.160002) (xy 117.78936 -390.110948)
			(xy 117.801137 -390.063164) (xy 117.820428 -390.017888) (xy 117.846731 -389.976292) (xy 117.879366 -389.939455)
			(xy 117.917487 -389.90833) (xy 117.960108 -389.883723) (xy 118.006124 -389.866271) (xy 118.054343 -389.856427)
			(xy 118.103518 -389.854446) (xy 118.152373 -389.860378) (xy 118.199644 -389.87407) (xy 118.244106 -389.895168)
			(xy 118.284609 -389.923124) (xy 118.320102 -389.957216) (xy 118.349667 -389.99656) (xy 118.372538 -390.040137)
			(xy 118.388122 -390.086818) (xy 118.396017 -390.135395) (xy 118.396512 -390.160002) (xy 118.98555 -390.160002)
			(xy 118.98951 -390.110948) (xy 119.001287 -390.063164) (xy 119.020578 -390.017888) (xy 119.046881 -389.976292)
			(xy 119.079516 -389.939455) (xy 119.117637 -389.90833) (xy 119.160258 -389.883723) (xy 119.206274 -389.866271)
			(xy 119.254493 -389.856427) (xy 119.303668 -389.854446) (xy 119.352523 -389.860378) (xy 119.399794 -389.87407)
			(xy 119.444256 -389.895168) (xy 119.484759 -389.923124) (xy 119.520252 -389.957216) (xy 119.549817 -389.99656)
			(xy 119.572688 -390.040137) (xy 119.588272 -390.086818) (xy 119.596167 -390.135395) (xy 119.596662 -390.160002)
			(xy 120.185446 -390.160002) (xy 120.189406 -390.110948) (xy 120.201183 -390.063164) (xy 120.220474 -390.017888)
			(xy 120.246777 -389.976292) (xy 120.279412 -389.939455) (xy 120.317533 -389.90833) (xy 120.360154 -389.883723)
			(xy 120.40617 -389.866271) (xy 120.454389 -389.856427) (xy 120.503564 -389.854446) (xy 120.552419 -389.860378)
			(xy 120.59969 -389.87407) (xy 120.644152 -389.895168) (xy 120.684655 -389.923124) (xy 120.720148 -389.957216)
			(xy 120.749713 -389.99656) (xy 120.772584 -390.040137) (xy 120.788168 -390.086818) (xy 120.796063 -390.135395)
			(xy 120.796558 -390.160002) (xy 121.385342 -390.160002) (xy 121.389302 -390.110948) (xy 121.401079 -390.063164)
			(xy 121.42037 -390.017888) (xy 121.446673 -389.976292) (xy 121.479308 -389.939455) (xy 121.517429 -389.90833)
			(xy 121.56005 -389.883723) (xy 121.606066 -389.866271) (xy 121.654285 -389.856427) (xy 121.70346 -389.854446)
			(xy 121.752315 -389.860378) (xy 121.799586 -389.87407) (xy 121.844048 -389.895168) (xy 121.884551 -389.923124)
			(xy 121.920044 -389.957216) (xy 121.949609 -389.99656) (xy 121.97248 -390.040137) (xy 121.988064 -390.086818)
			(xy 121.995959 -390.135395) (xy 121.996454 -390.160002) (xy 122.585492 -390.160002) (xy 122.589452 -390.110948)
			(xy 122.601229 -390.063164) (xy 122.62052 -390.017888) (xy 122.646823 -389.976292) (xy 122.679458 -389.939455)
			(xy 122.717579 -389.90833) (xy 122.7602 -389.883723) (xy 122.806216 -389.866271) (xy 122.854435 -389.856427)
			(xy 122.90361 -389.854446) (xy 122.952465 -389.860378) (xy 122.999736 -389.87407) (xy 123.044198 -389.895168)
			(xy 123.084701 -389.923124) (xy 123.120194 -389.957216) (xy 123.149759 -389.99656) (xy 123.17263 -390.040137)
			(xy 123.188214 -390.086818) (xy 123.196109 -390.135395) (xy 123.196604 -390.160002) (xy 123.785388 -390.160002)
			(xy 123.789348 -390.110948) (xy 123.801125 -390.063164) (xy 123.820416 -390.017888) (xy 123.846719 -389.976292)
			(xy 123.879354 -389.939455) (xy 123.917475 -389.90833) (xy 123.960096 -389.883723) (xy 124.006112 -389.866271)
			(xy 124.054331 -389.856427) (xy 124.103506 -389.854446) (xy 124.152361 -389.860378) (xy 124.199632 -389.87407)
			(xy 124.244094 -389.895168) (xy 124.284597 -389.923124) (xy 124.32009 -389.957216) (xy 124.349655 -389.99656)
			(xy 124.372526 -390.040137) (xy 124.38811 -390.086818) (xy 124.396005 -390.135395) (xy 124.3965 -390.160002)
			(xy 124.985538 -390.160002) (xy 124.989498 -390.110948) (xy 125.001275 -390.063164) (xy 125.020566 -390.017888)
			(xy 125.046869 -389.976292) (xy 125.079504 -389.939455) (xy 125.117625 -389.90833) (xy 125.160246 -389.883723)
			(xy 125.206262 -389.866271) (xy 125.254481 -389.856427) (xy 125.303656 -389.854446) (xy 125.352511 -389.860378)
			(xy 125.399782 -389.87407) (xy 125.444244 -389.895168) (xy 125.484747 -389.923124) (xy 125.52024 -389.957216)
			(xy 125.549805 -389.99656) (xy 125.572676 -390.040137) (xy 125.58826 -390.086818) (xy 125.596155 -390.135395)
			(xy 125.59665 -390.160002) (xy 126.185434 -390.160002) (xy 126.189394 -390.110948) (xy 126.201171 -390.063164)
			(xy 126.220462 -390.017888) (xy 126.246765 -389.976292) (xy 126.2794 -389.939455) (xy 126.317521 -389.90833)
			(xy 126.360142 -389.883723) (xy 126.406158 -389.866271) (xy 126.454377 -389.856427) (xy 126.503552 -389.854446)
			(xy 126.552407 -389.860378) (xy 126.599678 -389.87407) (xy 126.64414 -389.895168) (xy 126.684643 -389.923124)
			(xy 126.720136 -389.957216) (xy 126.749701 -389.99656) (xy 126.772572 -390.040137) (xy 126.788156 -390.086818)
			(xy 126.796051 -390.135395) (xy 126.796546 -390.160002) (xy 127.38533 -390.160002) (xy 127.38929 -390.110948)
			(xy 127.401067 -390.063164) (xy 127.420358 -390.017888) (xy 127.446661 -389.976292) (xy 127.479296 -389.939455)
			(xy 127.517417 -389.90833) (xy 127.560038 -389.883723) (xy 127.606054 -389.866271) (xy 127.654273 -389.856427)
			(xy 127.703448 -389.854446) (xy 127.752303 -389.860378) (xy 127.799574 -389.87407) (xy 127.844036 -389.895168)
			(xy 127.884539 -389.923124) (xy 127.920032 -389.957216) (xy 127.949597 -389.99656) (xy 127.972468 -390.040137)
			(xy 127.988052 -390.086818) (xy 127.995947 -390.135395) (xy 127.996442 -390.160002) (xy 128.58548 -390.160002)
			(xy 128.58944 -390.110948) (xy 128.601217 -390.063164) (xy 128.620508 -390.017888) (xy 128.646811 -389.976292)
			(xy 128.679446 -389.939455) (xy 128.717567 -389.90833) (xy 128.760188 -389.883723) (xy 128.806204 -389.866271)
			(xy 128.854423 -389.856427) (xy 128.903598 -389.854446) (xy 128.952453 -389.860378) (xy 128.999724 -389.87407)
			(xy 129.044186 -389.895168) (xy 129.084689 -389.923124) (xy 129.120182 -389.957216) (xy 129.149747 -389.99656)
			(xy 129.172618 -390.040137) (xy 129.188202 -390.086818) (xy 129.196097 -390.135395) (xy 129.196592 -390.160002)
			(xy 129.785376 -390.160002) (xy 129.789336 -390.110948) (xy 129.801113 -390.063164) (xy 129.820404 -390.017888)
			(xy 129.846707 -389.976292) (xy 129.879342 -389.939455) (xy 129.917463 -389.90833) (xy 129.960084 -389.883723)
			(xy 130.0061 -389.866271) (xy 130.054319 -389.856427) (xy 130.103494 -389.854446) (xy 130.152349 -389.860378)
			(xy 130.19962 -389.87407) (xy 130.244082 -389.895168) (xy 130.284585 -389.923124) (xy 130.320078 -389.957216)
			(xy 130.349643 -389.99656) (xy 130.372514 -390.040137) (xy 130.388098 -390.086818) (xy 130.395993 -390.135395)
			(xy 130.396488 -390.160002) (xy 130.985526 -390.160002) (xy 130.989486 -390.110948) (xy 131.001263 -390.063164)
			(xy 131.020554 -390.017888) (xy 131.046857 -389.976292) (xy 131.079492 -389.939455) (xy 131.117613 -389.90833)
			(xy 131.160234 -389.883723) (xy 131.20625 -389.866271) (xy 131.254469 -389.856427) (xy 131.303644 -389.854446)
			(xy 131.352499 -389.860378) (xy 131.39977 -389.87407) (xy 131.444232 -389.895168) (xy 131.484735 -389.923124)
			(xy 131.520228 -389.957216) (xy 131.549793 -389.99656) (xy 131.572664 -390.040137) (xy 131.588248 -390.086818)
			(xy 131.596143 -390.135395) (xy 131.596638 -390.160002) (xy 132.185422 -390.160002) (xy 132.189382 -390.110948)
			(xy 132.201159 -390.063164) (xy 132.22045 -390.017888) (xy 132.246753 -389.976292) (xy 132.279388 -389.939455)
			(xy 132.317509 -389.90833) (xy 132.36013 -389.883723) (xy 132.406146 -389.866271) (xy 132.454365 -389.856427)
			(xy 132.50354 -389.854446) (xy 132.552395 -389.860378) (xy 132.599666 -389.87407) (xy 132.644128 -389.895168)
			(xy 132.684631 -389.923124) (xy 132.720124 -389.957216) (xy 132.749689 -389.99656) (xy 132.77256 -390.040137)
			(xy 132.788144 -390.086818) (xy 132.796039 -390.135395) (xy 132.796534 -390.160002) (xy 132.796039 -390.184609)
			(xy 132.795815 -390.185989) (xy 133.515102 -390.185989) (xy 133.515102 -390.134015) (xy 133.523232 -390.08268)
			(xy 133.539293 -390.03325) (xy 133.562889 -389.98694) (xy 133.593439 -389.944892) (xy 133.63019 -389.908141)
			(xy 133.672238 -389.877591) (xy 133.718548 -389.853995) (xy 133.767978 -389.837934) (xy 133.819313 -389.829804)
			(xy 133.871287 -389.829804) (xy 133.922622 -389.837934) (xy 133.972052 -389.853995) (xy 134.018362 -389.877591)
			(xy 134.06041 -389.908141) (xy 134.097161 -389.944892) (xy 134.127711 -389.98694) (xy 134.151307 -390.03325)
			(xy 134.167368 -390.08268) (xy 134.175498 -390.134015) (xy 134.176008 -390.160002) (xy 134.175498 -390.185989)
			(xy 134.167368 -390.237324) (xy 134.151307 -390.286754) (xy 134.127711 -390.333064) (xy 134.097161 -390.375112)
			(xy 134.06041 -390.411863) (xy 134.018362 -390.442413) (xy 133.972052 -390.466009) (xy 133.922622 -390.48207)
			(xy 133.871287 -390.4902) (xy 133.819313 -390.4902) (xy 133.767978 -390.48207) (xy 133.718548 -390.466009)
			(xy 133.672238 -390.442413) (xy 133.63019 -390.411863) (xy 133.593439 -390.375112) (xy 133.562889 -390.333064)
			(xy 133.539293 -390.286754) (xy 133.523232 -390.237324) (xy 133.515102 -390.185989) (xy 132.795815 -390.185989)
			(xy 132.788144 -390.233186) (xy 132.77256 -390.279867) (xy 132.749689 -390.323444) (xy 132.720124 -390.362788)
			(xy 132.684631 -390.39688) (xy 132.644128 -390.424836) (xy 132.599666 -390.445934) (xy 132.552395 -390.459626)
			(xy 132.50354 -390.465558) (xy 132.454365 -390.463577) (xy 132.406146 -390.453733) (xy 132.36013 -390.436281)
			(xy 132.317509 -390.411674) (xy 132.279388 -390.380549) (xy 132.246753 -390.343712) (xy 132.22045 -390.302116)
			(xy 132.201159 -390.25684) (xy 132.189382 -390.209056) (xy 132.185422 -390.160002) (xy 131.596638 -390.160002)
			(xy 131.596143 -390.184609) (xy 131.588248 -390.233186) (xy 131.572664 -390.279867) (xy 131.549793 -390.323444)
			(xy 131.520228 -390.362788) (xy 131.484735 -390.39688) (xy 131.444232 -390.424836) (xy 131.39977 -390.445934)
			(xy 131.352499 -390.459626) (xy 131.303644 -390.465558) (xy 131.254469 -390.463577) (xy 131.20625 -390.453733)
			(xy 131.160234 -390.436281) (xy 131.117613 -390.411674) (xy 131.079492 -390.380549) (xy 131.046857 -390.343712)
			(xy 131.020554 -390.302116) (xy 131.001263 -390.25684) (xy 130.989486 -390.209056) (xy 130.985526 -390.160002)
			(xy 130.396488 -390.160002) (xy 130.395993 -390.184609) (xy 130.388098 -390.233186) (xy 130.372514 -390.279867)
			(xy 130.349643 -390.323444) (xy 130.320078 -390.362788) (xy 130.284585 -390.39688) (xy 130.244082 -390.424836)
			(xy 130.19962 -390.445934) (xy 130.152349 -390.459626) (xy 130.103494 -390.465558) (xy 130.054319 -390.463577)
			(xy 130.0061 -390.453733) (xy 129.960084 -390.436281) (xy 129.917463 -390.411674) (xy 129.879342 -390.380549)
			(xy 129.846707 -390.343712) (xy 129.820404 -390.302116) (xy 129.801113 -390.25684) (xy 129.789336 -390.209056)
			(xy 129.785376 -390.160002) (xy 129.196592 -390.160002) (xy 129.196097 -390.184609) (xy 129.188202 -390.233186)
			(xy 129.172618 -390.279867) (xy 129.149747 -390.323444) (xy 129.120182 -390.362788) (xy 129.084689 -390.39688)
			(xy 129.044186 -390.424836) (xy 128.999724 -390.445934) (xy 128.952453 -390.459626) (xy 128.903598 -390.465558)
			(xy 128.854423 -390.463577) (xy 128.806204 -390.453733) (xy 128.760188 -390.436281) (xy 128.717567 -390.411674)
			(xy 128.679446 -390.380549) (xy 128.646811 -390.343712) (xy 128.620508 -390.302116) (xy 128.601217 -390.25684)
			(xy 128.58944 -390.209056) (xy 128.58548 -390.160002) (xy 127.996442 -390.160002) (xy 127.995947 -390.184609)
			(xy 127.988052 -390.233186) (xy 127.972468 -390.279867) (xy 127.949597 -390.323444) (xy 127.920032 -390.362788)
			(xy 127.884539 -390.39688) (xy 127.844036 -390.424836) (xy 127.799574 -390.445934) (xy 127.752303 -390.459626)
			(xy 127.703448 -390.465558) (xy 127.654273 -390.463577) (xy 127.606054 -390.453733) (xy 127.560038 -390.436281)
			(xy 127.517417 -390.411674) (xy 127.479296 -390.380549) (xy 127.446661 -390.343712) (xy 127.420358 -390.302116)
			(xy 127.401067 -390.25684) (xy 127.38929 -390.209056) (xy 127.38533 -390.160002) (xy 126.796546 -390.160002)
			(xy 126.796051 -390.184609) (xy 126.788156 -390.233186) (xy 126.772572 -390.279867) (xy 126.749701 -390.323444)
			(xy 126.720136 -390.362788) (xy 126.684643 -390.39688) (xy 126.64414 -390.424836) (xy 126.599678 -390.445934)
			(xy 126.552407 -390.459626) (xy 126.503552 -390.465558) (xy 126.454377 -390.463577) (xy 126.406158 -390.453733)
			(xy 126.360142 -390.436281) (xy 126.317521 -390.411674) (xy 126.2794 -390.380549) (xy 126.246765 -390.343712)
			(xy 126.220462 -390.302116) (xy 126.201171 -390.25684) (xy 126.189394 -390.209056) (xy 126.185434 -390.160002)
			(xy 125.59665 -390.160002) (xy 125.596155 -390.184609) (xy 125.58826 -390.233186) (xy 125.572676 -390.279867)
			(xy 125.549805 -390.323444) (xy 125.52024 -390.362788) (xy 125.484747 -390.39688) (xy 125.444244 -390.424836)
			(xy 125.399782 -390.445934) (xy 125.352511 -390.459626) (xy 125.303656 -390.465558) (xy 125.254481 -390.463577)
			(xy 125.206262 -390.453733) (xy 125.160246 -390.436281) (xy 125.117625 -390.411674) (xy 125.079504 -390.380549)
			(xy 125.046869 -390.343712) (xy 125.020566 -390.302116) (xy 125.001275 -390.25684) (xy 124.989498 -390.209056)
			(xy 124.985538 -390.160002) (xy 124.3965 -390.160002) (xy 124.396005 -390.184609) (xy 124.38811 -390.233186)
			(xy 124.372526 -390.279867) (xy 124.349655 -390.323444) (xy 124.32009 -390.362788) (xy 124.284597 -390.39688)
			(xy 124.244094 -390.424836) (xy 124.199632 -390.445934) (xy 124.152361 -390.459626) (xy 124.103506 -390.465558)
			(xy 124.054331 -390.463577) (xy 124.006112 -390.453733) (xy 123.960096 -390.436281) (xy 123.917475 -390.411674)
			(xy 123.879354 -390.380549) (xy 123.846719 -390.343712) (xy 123.820416 -390.302116) (xy 123.801125 -390.25684)
			(xy 123.789348 -390.209056) (xy 123.785388 -390.160002) (xy 123.196604 -390.160002) (xy 123.196109 -390.184609)
			(xy 123.188214 -390.233186) (xy 123.17263 -390.279867) (xy 123.149759 -390.323444) (xy 123.120194 -390.362788)
			(xy 123.084701 -390.39688) (xy 123.044198 -390.424836) (xy 122.999736 -390.445934) (xy 122.952465 -390.459626)
			(xy 122.90361 -390.465558) (xy 122.854435 -390.463577) (xy 122.806216 -390.453733) (xy 122.7602 -390.436281)
			(xy 122.717579 -390.411674) (xy 122.679458 -390.380549) (xy 122.646823 -390.343712) (xy 122.62052 -390.302116)
			(xy 122.601229 -390.25684) (xy 122.589452 -390.209056) (xy 122.585492 -390.160002) (xy 121.996454 -390.160002)
			(xy 121.995959 -390.184609) (xy 121.988064 -390.233186) (xy 121.97248 -390.279867) (xy 121.949609 -390.323444)
			(xy 121.920044 -390.362788) (xy 121.884551 -390.39688) (xy 121.844048 -390.424836) (xy 121.799586 -390.445934)
			(xy 121.752315 -390.459626) (xy 121.70346 -390.465558) (xy 121.654285 -390.463577) (xy 121.606066 -390.453733)
			(xy 121.56005 -390.436281) (xy 121.517429 -390.411674) (xy 121.479308 -390.380549) (xy 121.446673 -390.343712)
			(xy 121.42037 -390.302116) (xy 121.401079 -390.25684) (xy 121.389302 -390.209056) (xy 121.385342 -390.160002)
			(xy 120.796558 -390.160002) (xy 120.796063 -390.184609) (xy 120.788168 -390.233186) (xy 120.772584 -390.279867)
			(xy 120.749713 -390.323444) (xy 120.720148 -390.362788) (xy 120.684655 -390.39688) (xy 120.644152 -390.424836)
			(xy 120.59969 -390.445934) (xy 120.552419 -390.459626) (xy 120.503564 -390.465558) (xy 120.454389 -390.463577)
			(xy 120.40617 -390.453733) (xy 120.360154 -390.436281) (xy 120.317533 -390.411674) (xy 120.279412 -390.380549)
			(xy 120.246777 -390.343712) (xy 120.220474 -390.302116) (xy 120.201183 -390.25684) (xy 120.189406 -390.209056)
			(xy 120.185446 -390.160002) (xy 119.596662 -390.160002) (xy 119.596167 -390.184609) (xy 119.588272 -390.233186)
			(xy 119.572688 -390.279867) (xy 119.549817 -390.323444) (xy 119.520252 -390.362788) (xy 119.484759 -390.39688)
			(xy 119.444256 -390.424836) (xy 119.399794 -390.445934) (xy 119.352523 -390.459626) (xy 119.303668 -390.465558)
			(xy 119.254493 -390.463577) (xy 119.206274 -390.453733) (xy 119.160258 -390.436281) (xy 119.117637 -390.411674)
			(xy 119.079516 -390.380549) (xy 119.046881 -390.343712) (xy 119.020578 -390.302116) (xy 119.001287 -390.25684)
			(xy 118.98951 -390.209056) (xy 118.98555 -390.160002) (xy 118.396512 -390.160002) (xy 118.396017 -390.184609)
			(xy 118.388122 -390.233186) (xy 118.372538 -390.279867) (xy 118.349667 -390.323444) (xy 118.320102 -390.362788)
			(xy 118.284609 -390.39688) (xy 118.244106 -390.424836) (xy 118.199644 -390.445934) (xy 118.152373 -390.459626)
			(xy 118.103518 -390.465558) (xy 118.054343 -390.463577) (xy 118.006124 -390.453733) (xy 117.960108 -390.436281)
			(xy 117.917487 -390.411674) (xy 117.879366 -390.380549) (xy 117.846731 -390.343712) (xy 117.820428 -390.302116)
			(xy 117.801137 -390.25684) (xy 117.78936 -390.209056) (xy 117.7854 -390.160002) (xy 117.196616 -390.160002)
			(xy 117.196121 -390.184609) (xy 117.188226 -390.233186) (xy 117.172642 -390.279867) (xy 117.149771 -390.323444)
			(xy 117.120206 -390.362788) (xy 117.084713 -390.39688) (xy 117.04421 -390.424836) (xy 116.999748 -390.445934)
			(xy 116.952477 -390.459626) (xy 116.903622 -390.465558) (xy 116.854447 -390.463577) (xy 116.806228 -390.453733)
			(xy 116.760212 -390.436281) (xy 116.717591 -390.411674) (xy 116.67947 -390.380549) (xy 116.646835 -390.343712)
			(xy 116.620532 -390.302116) (xy 116.601241 -390.25684) (xy 116.589464 -390.209056) (xy 116.585504 -390.160002)
			(xy 115.996466 -390.160002) (xy 115.995971 -390.184609) (xy 115.988076 -390.233186) (xy 115.972492 -390.279867)
			(xy 115.949621 -390.323444) (xy 115.920056 -390.362788) (xy 115.884563 -390.39688) (xy 115.84406 -390.424836)
			(xy 115.799598 -390.445934) (xy 115.752327 -390.459626) (xy 115.703472 -390.465558) (xy 115.654297 -390.463577)
			(xy 115.606078 -390.453733) (xy 115.560062 -390.436281) (xy 115.517441 -390.411674) (xy 115.47932 -390.380549)
			(xy 115.446685 -390.343712) (xy 115.420382 -390.302116) (xy 115.401091 -390.25684) (xy 115.389314 -390.209056)
			(xy 115.385354 -390.160002) (xy 114.796316 -390.160002) (xy 114.795821 -390.184609) (xy 114.787926 -390.233186)
			(xy 114.772342 -390.279867) (xy 114.749471 -390.323444) (xy 114.719906 -390.362788) (xy 114.684413 -390.39688)
			(xy 114.64391 -390.424836) (xy 114.599448 -390.445934) (xy 114.552177 -390.459626) (xy 114.503322 -390.465558)
			(xy 114.454147 -390.463577) (xy 114.405928 -390.453733) (xy 114.359912 -390.436281) (xy 114.317291 -390.411674)
			(xy 114.27917 -390.380549) (xy 114.246535 -390.343712) (xy 114.220232 -390.302116) (xy 114.200941 -390.25684)
			(xy 114.189164 -390.209056) (xy 114.185204 -390.160002) (xy 112.510371 -390.160002) (xy 112.504262 -390.181186)
			(xy 112.485265 -390.223594) (xy 112.46052 -390.262926) (xy 112.4458 -390.280906) (xy 112.439704 -390.288018)
			(xy 112.433608 -390.304528) (xy 112.433608 -390.388856) (xy 112.439704 -390.405366) (xy 112.4458 -390.412478)
			(xy 112.460504 -390.43047) (xy 112.485251 -390.469797) (xy 112.504248 -390.512202) (xy 112.51712 -390.556849)
			(xy 112.523614 -390.602859) (xy 112.524032 -390.626092) (xy 112.523523 -390.65208) (xy 112.515394 -390.703417)
			(xy 112.499334 -390.75285) (xy 112.475739 -390.799163) (xy 112.445189 -390.841214) (xy 112.408438 -390.877969)
			(xy 112.36639 -390.908522) (xy 112.32008 -390.932121) (xy 112.270648 -390.948186) (xy 112.219312 -390.956321)
			(xy 112.193324 -390.9568) (xy 112.176636 -390.956619) (xy 112.143425 -390.953315) (xy 112.12703 -390.950196)
			(xy 112.1156 -390.947656) (xy 112.093756 -390.953244) (xy 112.023906 -391.010394) (xy 112.015548 -391.017961)
			(xy 112.00579 -391.038256) (xy 112.00511 -391.04951) (xy 112.00511 -391.49401) (xy 112.005535 -391.504079)
			(xy 112.013253 -391.52268) (xy 112.020096 -391.530078) (xy 112.291955 -391.801937) (xy 113.264698 -391.801937)
			(xy 113.264698 -391.749963) (xy 113.272828 -391.698628) (xy 113.288889 -391.649198) (xy 113.312485 -391.602888)
			(xy 113.343035 -391.56084) (xy 113.379786 -391.524089) (xy 113.421834 -391.493539) (xy 113.468144 -391.469943)
			(xy 113.517574 -391.453882) (xy 113.568909 -391.445752) (xy 113.620883 -391.445752) (xy 113.672218 -391.453882)
			(xy 113.721648 -391.469943) (xy 113.767958 -391.493539) (xy 113.810006 -391.524089) (xy 113.846757 -391.56084)
			(xy 113.877307 -391.602888) (xy 113.900903 -391.649198) (xy 113.916964 -391.698628) (xy 113.925094 -391.749963)
			(xy 113.925604 -391.77595) (xy 113.925094 -391.801937) (xy 113.916964 -391.853272) (xy 113.900903 -391.902702)
			(xy 113.877307 -391.949012) (xy 113.846757 -391.99106) (xy 113.810006 -392.027811) (xy 113.767958 -392.058361)
			(xy 113.721648 -392.081957) (xy 113.672218 -392.098018) (xy 113.620883 -392.106148) (xy 113.568909 -392.106148)
			(xy 113.517574 -392.098018) (xy 113.468144 -392.081957) (xy 113.421834 -392.058361) (xy 113.379786 -392.027811)
			(xy 113.343035 -391.99106) (xy 113.312485 -391.949012) (xy 113.288889 -391.902702) (xy 113.272828 -391.853272)
			(xy 113.264698 -391.801937) (xy 112.291955 -391.801937) (xy 113.063274 -392.573256) (xy 113.070674 -392.580096)
			(xy 113.089273 -392.58781) (xy 113.099342 -392.588242)
		)
		(stroke
			(width 0)
			(type solid)
		)
		(fill yes)
		(layer "In2.Cu")
		(net "NCF_CPU1_P3_GND")
	)
	(gr_poly
		(pts
			(xy 352.824034 -403.427184) (xy 352.833998 -403.426703) (xy 352.85243 -403.419122) (xy 352.859848 -403.412452)
			(xy 353.845114 -402.427186) (xy 353.851968 -402.419791) (xy 353.85971 -402.401192) (xy 353.8601 -402.391118)
			(xy 353.8601 -398.864328) (xy 353.840796 -398.837658) (xy 353.824794 -398.832578) (xy 353.802073 -398.824757)
			(xy 353.759236 -398.80299) (xy 353.720336 -398.774784) (xy 353.686332 -398.740835) (xy 353.658064 -398.701979)
			(xy 353.636229 -398.659177) (xy 353.621366 -398.613483) (xy 353.613842 -398.566026) (xy 353.613842 -398.517976)
			(xy 353.621366 -398.470518) (xy 353.636229 -398.424824) (xy 353.658064 -398.382022) (xy 353.686331 -398.343166)
			(xy 353.720335 -398.309217) (xy 353.759235 -398.281011) (xy 353.802072 -398.259244) (xy 353.824794 -398.251426)
			(xy 353.840796 -398.246346) (xy 353.8601 -398.219676) (xy 353.8601 -398.178274) (xy 353.859678 -398.168954)
			(xy 353.852988 -398.151555) (xy 353.840507 -398.13771) (xy 353.832414 -398.133062) (xy 353.738688 -398.08531)
			(xy 353.71024 -398.087596) (xy 353.698556 -398.096232) (xy 353.678846 -398.110011) (xy 353.636003 -398.131851)
			(xy 353.590268 -398.146709) (xy 353.542769 -398.154217) (xy 353.518724 -398.154652) (xy 353.495195 -398.154211)
			(xy 353.448697 -398.146978) (xy 353.403859 -398.132695) (xy 353.361745 -398.111699) (xy 353.323352 -398.08449)
			(xy 353.289589 -398.05171) (xy 353.261256 -398.014138) (xy 353.249738 -397.993616) (xy 353.249484 -397.993108)
			(xy 353.248976 -397.992346) (xy 352.851466 -397.303752) (xy 352.840908 -397.28382) (xy 352.825121 -397.241568)
			(xy 352.815711 -397.197455) (xy 352.813874 -397.174974) (xy 352.813366 -397.163798) (xy 352.813112 -397.156432)
			(xy 352.813263 -397.145083) (xy 352.815044 -397.122453) (xy 352.816668 -397.11122) (xy 352.817938 -397.10233)
			(xy 352.814382 -397.085058) (xy 352.770948 -397.013938) (xy 352.757232 -397.002762) (xy 352.748596 -396.999968)
			(xy 352.726206 -396.991941) (xy 352.684037 -396.969943) (xy 352.64579 -396.94167) (xy 352.612391 -396.907808)
			(xy 352.584648 -396.869175) (xy 352.563233 -396.826707) (xy 352.548663 -396.781431) (xy 352.541292 -396.734443)
			(xy 352.540824 -396.710662) (xy 352.541324 -396.685264) (xy 352.549724 -396.635168) (xy 352.566303 -396.587154)
			(xy 352.590602 -396.542548) (xy 352.621952 -396.502581) (xy 352.640392 -396.48511) (xy 352.648774 -396.47749)
			(xy 352.65741 -396.457424) (xy 352.654616 -396.35811) (xy 352.645218 -396.338552) (xy 352.636328 -396.33144)
			(xy 352.617765 -396.315638) (xy 352.585036 -396.279513) (xy 352.557961 -396.238976) (xy 352.537126 -396.194906)
			(xy 352.522983 -396.148256) (xy 352.515836 -396.100036) (xy 352.515424 -396.075662) (xy 352.515863 -396.051546)
			(xy 352.522869 -396.003826) (xy 352.536727 -395.957628) (xy 352.557144 -395.913931) (xy 352.570034 -395.893544)
			(xy 352.575876 -395.884654) (xy 352.579432 -395.864588) (xy 352.55835 -395.772386) (xy 352.546158 -395.755622)
			(xy 352.537268 -395.750288) (xy 352.516465 -395.737433) (xy 352.478546 -395.706556) (xy 352.445594 -395.670425)
			(xy 352.418329 -395.629832) (xy 352.397346 -395.585662) (xy 352.383104 -395.538881) (xy 352.375915 -395.490512)
			(xy 352.37547 -395.466062) (xy 352.376031 -395.438779) (xy 352.384991 -395.384954) (xy 352.402662 -395.333329)
			(xy 352.428565 -395.285303) (xy 352.461998 -395.242179) (xy 352.481642 -395.223238) (xy 352.489098 -395.215749)
			(xy 352.497651 -395.196453) (xy 352.498152 -395.1859) (xy 352.498152 -395.111224) (xy 352.497565 -395.10069)
			(xy 352.489031 -395.081419) (xy 352.481642 -395.073886) (xy 352.461987 -395.054953) (xy 352.428544 -395.011832)
			(xy 352.402636 -394.963806) (xy 352.384965 -394.912177) (xy 352.376011 -394.858347) (xy 352.37547 -394.831062)
			(xy 352.375724 -394.81887) (xy 352.375978 -394.809218) (xy 352.369882 -394.791184) (xy 352.311208 -394.723874)
			(xy 352.294444 -394.715238) (xy 352.284538 -394.714222) (xy 352.257626 -394.71087) (xy 352.205329 -394.696522)
			(xy 352.156074 -394.673832) (xy 352.111183 -394.643408) (xy 352.07186 -394.606065) (xy 352.039158 -394.562806)
			(xy 352.013954 -394.514789) (xy 351.996924 -394.463303) (xy 351.992184 -394.4366) (xy 351.99066 -394.427202)
			(xy 351.717864 -393.95527) (xy 351.710498 -393.949428) (xy 351.691721 -393.933623) (xy 351.658592 -393.897415)
			(xy 351.631175 -393.85671) (xy 351.610073 -393.812401) (xy 351.595748 -393.765461) (xy 351.588515 -393.716919)
			(xy 351.58807 -393.69238) (xy 351.588581 -393.666393) (xy 351.596714 -393.61506) (xy 351.612776 -393.565631)
			(xy 351.636373 -393.519322) (xy 351.666923 -393.477275) (xy 351.703673 -393.440524) (xy 351.745721 -393.409974)
			(xy 351.792029 -393.386377) (xy 351.841458 -393.370314) (xy 351.892791 -393.362181) (xy 351.918778 -393.361672)
			(xy 351.94479 -393.362155) (xy 351.996172 -393.370299) (xy 352.045645 -393.386389) (xy 352.091988 -393.410029)
			(xy 352.134056 -393.440634) (xy 352.170813 -393.47745) (xy 352.20135 -393.519568) (xy 352.224915 -393.565949)
			(xy 352.240925 -393.615447) (xy 352.245422 -393.641072) (xy 352.246946 -393.65047) (xy 352.519742 -394.122402)
			(xy 352.527108 -394.128244) (xy 352.545886 -394.144048) (xy 352.579018 -394.180256) (xy 352.606438 -394.220961)
			(xy 352.627543 -394.26527) (xy 352.641872 -394.31221) (xy 352.649109 -394.360752) (xy 352.649536 -394.385292)
			(xy 352.649282 -394.397484) (xy 352.649028 -394.407136) (xy 352.655124 -394.42517) (xy 352.713798 -394.49248)
			(xy 352.730562 -394.501116) (xy 352.740468 -394.502132) (xy 352.767238 -394.505456) (xy 352.81927 -394.519676)
			(xy 352.868305 -394.542151) (xy 352.913044 -394.572285) (xy 352.9523 -394.609279) (xy 352.985032 -394.652153)
			(xy 353.010374 -394.699769) (xy 353.027653 -394.750867) (xy 353.036412 -394.804092) (xy 353.036886 -394.831062)
			(xy 353.036323 -394.858344) (xy 353.027358 -394.912166) (xy 353.009683 -394.963787) (xy 352.983775 -395.011807)
			(xy 352.950339 -395.054925) (xy 352.930714 -395.073886) (xy 352.923268 -395.081379) (xy 352.914731 -395.100674)
			(xy 352.914204 -395.111224) (xy 352.914204 -395.1859) (xy 352.914795 -395.196433) (xy 352.923329 -395.215702)
			(xy 352.930714 -395.223238) (xy 352.95037 -395.24217) (xy 352.983814 -395.28529) (xy 353.009722 -395.333317)
			(xy 353.027392 -395.384947) (xy 353.036344 -395.438777) (xy 353.036886 -395.466062) (xy 353.036453 -395.490179)
			(xy 353.029457 -395.537904) (xy 353.015608 -395.584108) (xy 352.995199 -395.627813) (xy 352.982276 -395.64818)
			(xy 352.976434 -395.65707) (xy 352.972878 -395.677136) (xy 352.99396 -395.769338) (xy 353.006152 -395.786102)
			(xy 353.015042 -395.791436) (xy 353.035843 -395.804292) (xy 353.073759 -395.83517) (xy 353.106707 -395.871301)
			(xy 353.133969 -395.911895) (xy 353.154948 -395.956065) (xy 353.169186 -396.002845) (xy 353.176371 -396.051212)
			(xy 353.17684 -396.075662) (xy 353.176402 -396.100033) (xy 353.169246 -396.148246) (xy 353.155098 -396.194888)
			(xy 353.134263 -396.238952) (xy 353.107192 -396.279485) (xy 353.074471 -396.315609) (xy 353.055936 -396.33144)
			(xy 353.047046 -396.338552) (xy 353.037648 -396.35811) (xy 353.034854 -396.457424) (xy 353.04349 -396.47749)
			(xy 353.051872 -396.48511) (xy 353.070295 -396.502597) (xy 353.10164 -396.542564) (xy 353.125939 -396.587167)
			(xy 353.142523 -396.635175) (xy 353.150934 -396.685266) (xy 353.15144 -396.710662) (xy 353.151349 -396.721944)
			(xy 353.149695 -396.744446) (xy 353.148138 -396.75562) (xy 353.146868 -396.764764) (xy 353.15017 -396.782036)
			(xy 353.193858 -396.853156) (xy 353.207574 -396.864078) (xy 353.21621 -396.866872) (xy 353.244339 -396.877147)
			(xy 353.296266 -396.906957) (xy 353.319334 -396.926054) (xy 353.340779 -396.945671) (xy 353.376578 -396.991448)
			(xy 353.390454 -397.016986) (xy 353.391216 -397.018256) (xy 353.765358 -397.665702) (xy 353.771422 -397.675057)
			(xy 353.789672 -397.687814) (xy 353.811606 -397.691657) (xy 353.822508 -397.689324) (xy 353.839272 -397.684752)
			(xy 353.8601 -397.657574) (xy 353.8601 -396.9766) (xy 353.859625 -396.965849) (xy 353.850812 -396.94624)
			(xy 353.843082 -396.938754) (xy 353.824184 -396.921222) (xy 353.791978 -396.880978) (xy 353.766989 -396.835897)
			(xy 353.749925 -396.787259) (xy 353.741273 -396.736447) (xy 353.741277 -396.684903) (xy 353.749938 -396.634092)
			(xy 353.767009 -396.585457) (xy 353.792007 -396.54038) (xy 353.824219 -396.500141) (xy 353.843082 -396.48257)
			(xy 353.850702 -396.475005) (xy 353.859496 -396.455445) (xy 353.8601 -396.444724) (xy 353.8601 -396.374874)
			(xy 353.859552 -396.363341) (xy 353.849502 -396.342579) (xy 353.840796 -396.334996) (xy 353.821585 -396.319222)
			(xy 353.787664 -396.282889) (xy 353.759562 -396.241889) (xy 353.737915 -396.197144) (xy 353.723208 -396.149663)
			(xy 353.715774 -396.100515) (xy 353.71532 -396.075662) (xy 353.715759 -396.051546) (xy 353.722765 -396.003826)
			(xy 353.736623 -395.957628) (xy 353.75704 -395.913931) (xy 353.76993 -395.893544) (xy 353.775772 -395.884654)
			(xy 353.779328 -395.864588) (xy 353.758246 -395.772386) (xy 353.746054 -395.755622) (xy 353.737164 -395.750288)
			(xy 353.716361 -395.737433) (xy 353.678443 -395.706555) (xy 353.645491 -395.670425) (xy 353.618226 -395.629831)
			(xy 353.597244 -395.585662) (xy 353.583002 -395.538881) (xy 353.575813 -395.490512) (xy 353.575366 -395.466062)
			(xy 353.575927 -395.438779) (xy 353.584887 -395.384954) (xy 353.602558 -395.333329) (xy 353.628461 -395.285303)
			(xy 353.661893 -395.242179) (xy 353.681538 -395.223238) (xy 353.688982 -395.215744) (xy 353.697518 -395.196449)
			(xy 353.698048 -395.1859) (xy 353.698048 -395.111224) (xy 353.69746 -395.10069) (xy 353.688926 -395.081419)
			(xy 353.681538 -395.073886) (xy 353.661883 -395.054953) (xy 353.628441 -395.011832) (xy 353.602533 -394.963805)
			(xy 353.584862 -394.912176) (xy 353.575908 -394.858347) (xy 353.575366 -394.831062) (xy 353.57562 -394.81887)
			(xy 353.575874 -394.809218) (xy 353.569778 -394.791184) (xy 353.511104 -394.723874) (xy 353.49434 -394.715238)
			(xy 353.484434 -394.714222) (xy 353.457483 -394.710859) (xy 353.405113 -394.696479) (xy 353.355792 -394.673742)
			(xy 353.310844 -394.64326) (xy 353.271476 -394.605849) (xy 353.238742 -394.562514) (xy 353.213521 -394.514417)
			(xy 353.19649 -394.462847) (xy 353.191826 -394.436092) (xy 353.190556 -394.426694) (xy 352.918014 -393.95527)
			(xy 352.910648 -393.949428) (xy 352.891869 -393.933625) (xy 352.858735 -393.897419) (xy 352.831314 -393.856714)
			(xy 352.810208 -393.812405) (xy 352.795881 -393.765463) (xy 352.788647 -393.71692) (xy 352.78822 -393.69238)
			(xy 352.788441 -393.675884) (xy 352.791753 -393.643058) (xy 352.794824 -393.626848) (xy 352.797364 -393.614402)
			(xy 352.789998 -393.590018) (xy 352.092514 -392.892534) (xy 352.084837 -392.8856) (xy 352.065624 -392.877986)
			(xy 352.044964 -392.878519) (xy 352.035364 -392.882374) (xy 351.934018 -392.929364) (xy 351.918016 -392.956542)
			(xy 351.91954 -392.972798) (xy 351.920556 -392.999722) (xy 351.920071 -393.025715) (xy 351.911935 -393.077062)
			(xy 351.895866 -393.126503) (xy 351.872261 -393.172822) (xy 351.841701 -393.214878) (xy 351.804938 -393.251635)
			(xy 351.762877 -393.282189) (xy 351.716554 -393.305787) (xy 351.66711 -393.321847) (xy 351.615763 -393.329975)
			(xy 351.563776 -393.32997) (xy 351.51243 -393.321833) (xy 351.462989 -393.305763) (xy 351.416671 -393.282157)
			(xy 351.374615 -393.251595) (xy 351.337859 -393.214831) (xy 351.307306 -393.17277) (xy 351.28371 -393.126446)
			(xy 351.267651 -393.077002) (xy 351.259524 -393.025654) (xy 351.25953 -392.973667) (xy 351.267669 -392.922321)
			(xy 351.28374 -392.872881) (xy 351.307348 -392.826563) (xy 351.33791 -392.784509) (xy 351.374675 -392.747753)
			(xy 351.416738 -392.717202) (xy 351.463062 -392.693607) (xy 351.512506 -392.677549) (xy 351.563854 -392.669424)
			(xy 351.589848 -392.669014) (xy 351.616772 -392.67003) (xy 351.633028 -392.671554) (xy 351.660206 -392.655552)
			(xy 351.707196 -392.554206) (xy 351.711101 -392.544614) (xy 351.711666 -392.523932) (xy 351.70401 -392.504712)
			(xy 351.697036 -392.497056) (xy 350.773238 -391.573258) (xy 350.754696 -391.565638) (xy 350.744536 -391.565638)
			(xy 350.719101 -391.565213) (xy 350.66882 -391.557506) (xy 350.620312 -391.542191) (xy 350.57472 -391.519629)
			(xy 350.533121 -391.490353) (xy 350.496494 -391.455053) (xy 350.465705 -391.414561) (xy 350.453198 -391.39241)
			(xy 350.446594 -391.379964) (xy 350.422464 -391.36574) (xy 349.865696 -391.36574) (xy 349.841566 -391.379964)
			(xy 349.834962 -391.39241) (xy 349.822461 -391.414523) (xy 349.791728 -391.454968) (xy 349.755173 -391.490238)
			(xy 349.713655 -391.519505) (xy 349.66815 -391.542079) (xy 349.619729 -391.55743) (xy 349.56953 -391.565196)
			(xy 349.518734 -391.565196) (xy 349.468535 -391.55743) (xy 349.420114 -391.542079) (xy 349.374609 -391.519505)
			(xy 349.333091 -391.490238) (xy 349.296536 -391.454968) (xy 349.265803 -391.414523) (xy 349.253302 -391.39241)
			(xy 349.246698 -391.379964) (xy 349.222568 -391.36574) (xy 348.665546 -391.36574) (xy 348.641416 -391.379964)
			(xy 348.634812 -391.39241) (xy 348.622311 -391.414523) (xy 348.591578 -391.454968) (xy 348.555023 -391.490238)
			(xy 348.513505 -391.519505) (xy 348.468 -391.542079) (xy 348.419579 -391.55743) (xy 348.36938 -391.565196)
			(xy 348.318584 -391.565196) (xy 348.268385 -391.55743) (xy 348.219964 -391.542079) (xy 348.174459 -391.519505)
			(xy 348.132941 -391.490238) (xy 348.096386 -391.454968) (xy 348.065653 -391.414523) (xy 348.053152 -391.39241)
			(xy 348.046548 -391.379964) (xy 348.022418 -391.36574) (xy 347.46565 -391.36574) (xy 347.44152 -391.379964)
			(xy 347.434916 -391.39241) (xy 347.422415 -391.414523) (xy 347.391682 -391.454968) (xy 347.355127 -391.490238)
			(xy 347.313609 -391.519505) (xy 347.268104 -391.542079) (xy 347.219683 -391.55743) (xy 347.169484 -391.565196)
			(xy 347.118688 -391.565196) (xy 347.068489 -391.55743) (xy 347.020068 -391.542079) (xy 346.974563 -391.519505)
			(xy 346.933045 -391.490238) (xy 346.89649 -391.454968) (xy 346.865757 -391.414523) (xy 346.853256 -391.39241)
			(xy 346.846652 -391.379964) (xy 346.822522 -391.36574) (xy 346.2655 -391.36574) (xy 346.24137 -391.379964)
			(xy 346.234766 -391.39241) (xy 346.222265 -391.414523) (xy 346.191532 -391.454968) (xy 346.154977 -391.490238)
			(xy 346.113459 -391.519505) (xy 346.067954 -391.542079) (xy 346.019533 -391.55743) (xy 345.969334 -391.565196)
			(xy 345.918538 -391.565196) (xy 345.868339 -391.55743) (xy 345.819918 -391.542079) (xy 345.774413 -391.519505)
			(xy 345.732895 -391.490238) (xy 345.69634 -391.454968) (xy 345.665607 -391.414523) (xy 345.653106 -391.39241)
			(xy 345.646502 -391.379964) (xy 345.622372 -391.36574) (xy 345.065604 -391.36574) (xy 345.041474 -391.379964)
			(xy 345.03487 -391.39241) (xy 345.022369 -391.414523) (xy 344.991636 -391.454968) (xy 344.955081 -391.490238)
			(xy 344.913563 -391.519505) (xy 344.868058 -391.542079) (xy 344.819637 -391.55743) (xy 344.769438 -391.565196)
			(xy 344.718642 -391.565196) (xy 344.668443 -391.55743) (xy 344.620022 -391.542079) (xy 344.574517 -391.519505)
			(xy 344.532999 -391.490238) (xy 344.496444 -391.454968) (xy 344.465711 -391.414523) (xy 344.45321 -391.39241)
			(xy 344.446606 -391.379964) (xy 344.422476 -391.36574) (xy 343.865708 -391.36574) (xy 343.841578 -391.379964)
			(xy 343.834974 -391.39241) (xy 343.822473 -391.414523) (xy 343.79174 -391.454968) (xy 343.755185 -391.490238)
			(xy 343.713667 -391.519505) (xy 343.668162 -391.542079) (xy 343.619741 -391.55743) (xy 343.569542 -391.565196)
			(xy 343.518746 -391.565196) (xy 343.468547 -391.55743) (xy 343.420126 -391.542079) (xy 343.374621 -391.519505)
			(xy 343.333103 -391.490238) (xy 343.296548 -391.454968) (xy 343.265815 -391.414523) (xy 343.253314 -391.39241)
			(xy 343.24671 -391.379964) (xy 343.22258 -391.36574) (xy 342.665558 -391.36574) (xy 342.641428 -391.379964)
			(xy 342.634824 -391.39241) (xy 342.622323 -391.414523) (xy 342.59159 -391.454968) (xy 342.555035 -391.490238)
			(xy 342.513517 -391.519505) (xy 342.468012 -391.542079) (xy 342.419591 -391.55743) (xy 342.369392 -391.565196)
			(xy 342.318596 -391.565196) (xy 342.268397 -391.55743) (xy 342.219976 -391.542079) (xy 342.174471 -391.519505)
			(xy 342.132953 -391.490238) (xy 342.096398 -391.454968) (xy 342.065665 -391.414523) (xy 342.053164 -391.39241)
			(xy 342.04656 -391.379964) (xy 342.02243 -391.36574) (xy 341.465662 -391.36574) (xy 341.441532 -391.379964)
			(xy 341.434928 -391.39241) (xy 341.422427 -391.414523) (xy 341.391694 -391.454968) (xy 341.355139 -391.490238)
			(xy 341.313621 -391.519505) (xy 341.268116 -391.542079) (xy 341.219695 -391.55743) (xy 341.169496 -391.565196)
			(xy 341.1187 -391.565196) (xy 341.068501 -391.55743) (xy 341.02008 -391.542079) (xy 340.974575 -391.519505)
			(xy 340.933057 -391.490238) (xy 340.896502 -391.454968) (xy 340.865769 -391.414523) (xy 340.853268 -391.39241)
			(xy 340.846664 -391.379964) (xy 340.822534 -391.36574) (xy 340.265512 -391.36574) (xy 340.241382 -391.379964)
			(xy 340.234778 -391.39241) (xy 340.222277 -391.414523) (xy 340.191544 -391.454968) (xy 340.154989 -391.490238)
			(xy 340.113471 -391.519505) (xy 340.067966 -391.542079) (xy 340.019545 -391.55743) (xy 339.969346 -391.565196)
			(xy 339.91855 -391.565196) (xy 339.868351 -391.55743) (xy 339.81993 -391.542079) (xy 339.774425 -391.519505)
			(xy 339.732907 -391.490238) (xy 339.696352 -391.454968) (xy 339.665619 -391.414523) (xy 339.653118 -391.39241)
			(xy 339.646514 -391.379964) (xy 339.622384 -391.36574) (xy 339.065616 -391.36574) (xy 339.041486 -391.379964)
			(xy 339.034882 -391.39241) (xy 339.022381 -391.414523) (xy 338.991648 -391.454968) (xy 338.955093 -391.490238)
			(xy 338.913575 -391.519505) (xy 338.86807 -391.542079) (xy 338.819649 -391.55743) (xy 338.76945 -391.565196)
			(xy 338.718654 -391.565196) (xy 338.668455 -391.55743) (xy 338.620034 -391.542079) (xy 338.574529 -391.519505)
			(xy 338.533011 -391.490238) (xy 338.496456 -391.454968) (xy 338.465723 -391.414523) (xy 338.453222 -391.39241)
			(xy 338.446618 -391.379964) (xy 338.422488 -391.36574) (xy 337.86572 -391.36574) (xy 337.84159 -391.379964)
			(xy 337.834986 -391.39241) (xy 337.822485 -391.414523) (xy 337.791752 -391.454968) (xy 337.755197 -391.490238)
			(xy 337.713679 -391.519505) (xy 337.668174 -391.542079) (xy 337.619753 -391.55743) (xy 337.569554 -391.565196)
			(xy 337.518758 -391.565196) (xy 337.468559 -391.55743) (xy 337.420138 -391.542079) (xy 337.374633 -391.519505)
			(xy 337.333115 -391.490238) (xy 337.29656 -391.454968) (xy 337.265827 -391.414523) (xy 337.253326 -391.39241)
			(xy 337.246722 -391.379964) (xy 337.222592 -391.36574) (xy 336.66557 -391.36574) (xy 336.64144 -391.379964)
			(xy 336.634836 -391.39241) (xy 336.622335 -391.414523) (xy 336.591602 -391.454968) (xy 336.555047 -391.490238)
			(xy 336.513529 -391.519505) (xy 336.468024 -391.542079) (xy 336.419603 -391.55743) (xy 336.369404 -391.565196)
			(xy 336.318608 -391.565196) (xy 336.268409 -391.55743) (xy 336.219988 -391.542079) (xy 336.174483 -391.519505)
			(xy 336.132965 -391.490238) (xy 336.09641 -391.454968) (xy 336.065677 -391.414523) (xy 336.053176 -391.39241)
			(xy 336.046572 -391.379964) (xy 336.022442 -391.36574) (xy 335.339944 -391.36574) (xy 335.313528 -391.384536)
			(xy 335.308194 -391.399776) (xy 335.298917 -391.424699) (xy 335.273556 -391.47144) (xy 335.241039 -391.513516)
			(xy 335.202205 -391.549844) (xy 335.158054 -391.579485) (xy 335.109728 -391.601674) (xy 335.058472 -391.615839)
			(xy 335.032096 -391.619232) (xy 335.02346 -391.620248) (xy 335.007966 -391.627614) (xy 334.195674 -392.439906)
			(xy 334.189183 -392.446925) (xy 334.181497 -392.464415) (xy 334.180688 -392.473942) (xy 334.179672 -392.504168)
			(xy 334.179789 -392.512983) (xy 334.185255 -392.529731) (xy 334.19034 -392.536934) (xy 334.206554 -392.558831)
			(xy 334.232352 -392.60682) (xy 334.249949 -392.658383) (xy 334.25887 -392.712131) (xy 334.259428 -392.739372)
			(xy 334.258944 -392.764966) (xy 334.251049 -392.815541) (xy 334.235458 -392.864297) (xy 334.212543 -392.910069)
			(xy 334.182852 -392.951766) (xy 334.147093 -392.988392) (xy 334.106119 -393.019073) (xy 334.09362 -393.025709)
			(xy 335.659732 -393.025709) (xy 335.659732 -392.973735) (xy 335.667862 -392.9224) (xy 335.683923 -392.87297)
			(xy 335.707519 -392.82666) (xy 335.738069 -392.784612) (xy 335.77482 -392.747861) (xy 335.816868 -392.717311)
			(xy 335.863178 -392.693715) (xy 335.912608 -392.677654) (xy 335.963943 -392.669524) (xy 336.015917 -392.669524)
			(xy 336.067252 -392.677654) (xy 336.116682 -392.693715) (xy 336.162992 -392.717311) (xy 336.20504 -392.747861)
			(xy 336.241791 -392.784612) (xy 336.272341 -392.82666) (xy 336.295937 -392.87297) (xy 336.311998 -392.9224)
			(xy 336.320128 -392.973735) (xy 336.320638 -392.999722) (xy 336.320128 -393.025709) (xy 336.859628 -393.025709)
			(xy 336.859628 -392.973735) (xy 336.867758 -392.9224) (xy 336.883819 -392.87297) (xy 336.907415 -392.82666)
			(xy 336.937965 -392.784612) (xy 336.974716 -392.747861) (xy 337.016764 -392.717311) (xy 337.063074 -392.693715)
			(xy 337.112504 -392.677654) (xy 337.163839 -392.669524) (xy 337.215813 -392.669524) (xy 337.267148 -392.677654)
			(xy 337.316578 -392.693715) (xy 337.362888 -392.717311) (xy 337.404936 -392.747861) (xy 337.441687 -392.784612)
			(xy 337.472237 -392.82666) (xy 337.495833 -392.87297) (xy 337.511894 -392.9224) (xy 337.520024 -392.973735)
			(xy 337.520534 -392.999722) (xy 337.520024 -393.025709) (xy 338.059778 -393.025709) (xy 338.059778 -392.973735)
			(xy 338.067908 -392.9224) (xy 338.083969 -392.87297) (xy 338.107565 -392.82666) (xy 338.138115 -392.784612)
			(xy 338.174866 -392.747861) (xy 338.216914 -392.717311) (xy 338.263224 -392.693715) (xy 338.312654 -392.677654)
			(xy 338.363989 -392.669524) (xy 338.415963 -392.669524) (xy 338.467298 -392.677654) (xy 338.516728 -392.693715)
			(xy 338.563038 -392.717311) (xy 338.605086 -392.747861) (xy 338.641837 -392.784612) (xy 338.672387 -392.82666)
			(xy 338.695983 -392.87297) (xy 338.712044 -392.9224) (xy 338.720174 -392.973735) (xy 338.720684 -392.999722)
			(xy 338.720174 -393.025709) (xy 339.259674 -393.025709) (xy 339.259674 -392.973735) (xy 339.267804 -392.9224)
			(xy 339.283865 -392.87297) (xy 339.307461 -392.82666) (xy 339.338011 -392.784612) (xy 339.374762 -392.747861)
			(xy 339.41681 -392.717311) (xy 339.46312 -392.693715) (xy 339.51255 -392.677654) (xy 339.563885 -392.669524)
			(xy 339.615859 -392.669524) (xy 339.667194 -392.677654) (xy 339.716624 -392.693715) (xy 339.762934 -392.717311)
			(xy 339.804982 -392.747861) (xy 339.841733 -392.784612) (xy 339.872283 -392.82666) (xy 339.895879 -392.87297)
			(xy 339.91194 -392.9224) (xy 339.92007 -392.973735) (xy 339.92058 -392.999722) (xy 339.92007 -393.025709)
			(xy 340.459824 -393.025709) (xy 340.459824 -392.973735) (xy 340.467954 -392.9224) (xy 340.484015 -392.87297)
			(xy 340.507611 -392.82666) (xy 340.538161 -392.784612) (xy 340.574912 -392.747861) (xy 340.61696 -392.717311)
			(xy 340.66327 -392.693715) (xy 340.7127 -392.677654) (xy 340.764035 -392.669524) (xy 340.816009 -392.669524)
			(xy 340.867344 -392.677654) (xy 340.916774 -392.693715) (xy 340.963084 -392.717311) (xy 341.005132 -392.747861)
			(xy 341.041883 -392.784612) (xy 341.072433 -392.82666) (xy 341.096029 -392.87297) (xy 341.11209 -392.9224)
			(xy 341.12022 -392.973735) (xy 341.12073 -392.999722) (xy 341.12022 -393.025709) (xy 341.65972 -393.025709)
			(xy 341.65972 -392.973735) (xy 341.66785 -392.9224) (xy 341.683911 -392.87297) (xy 341.707507 -392.82666)
			(xy 341.738057 -392.784612) (xy 341.774808 -392.747861) (xy 341.816856 -392.717311) (xy 341.863166 -392.693715)
			(xy 341.912596 -392.677654) (xy 341.963931 -392.669524) (xy 342.015905 -392.669524) (xy 342.06724 -392.677654)
			(xy 342.11667 -392.693715) (xy 342.16298 -392.717311) (xy 342.205028 -392.747861) (xy 342.241779 -392.784612)
			(xy 342.272329 -392.82666) (xy 342.295925 -392.87297) (xy 342.311986 -392.9224) (xy 342.320116 -392.973735)
			(xy 342.320626 -392.999722) (xy 342.320116 -393.025709) (xy 342.859616 -393.025709) (xy 342.859616 -392.973735)
			(xy 342.867746 -392.9224) (xy 342.883807 -392.87297) (xy 342.907403 -392.82666) (xy 342.937953 -392.784612)
			(xy 342.974704 -392.747861) (xy 343.016752 -392.717311) (xy 343.063062 -392.693715) (xy 343.112492 -392.677654)
			(xy 343.163827 -392.669524) (xy 343.215801 -392.669524) (xy 343.267136 -392.677654) (xy 343.316566 -392.693715)
			(xy 343.362876 -392.717311) (xy 343.404924 -392.747861) (xy 343.441675 -392.784612) (xy 343.472225 -392.82666)
			(xy 343.495821 -392.87297) (xy 343.511882 -392.9224) (xy 343.520012 -392.973735) (xy 343.520522 -392.999722)
			(xy 343.520012 -393.025709) (xy 344.059766 -393.025709) (xy 344.059766 -392.973735) (xy 344.067896 -392.9224)
			(xy 344.083957 -392.87297) (xy 344.107553 -392.82666) (xy 344.138103 -392.784612) (xy 344.174854 -392.747861)
			(xy 344.216902 -392.717311) (xy 344.263212 -392.693715) (xy 344.312642 -392.677654) (xy 344.363977 -392.669524)
			(xy 344.415951 -392.669524) (xy 344.467286 -392.677654) (xy 344.516716 -392.693715) (xy 344.563026 -392.717311)
			(xy 344.605074 -392.747861) (xy 344.641825 -392.784612) (xy 344.672375 -392.82666) (xy 344.695971 -392.87297)
			(xy 344.712032 -392.9224) (xy 344.720162 -392.973735) (xy 344.720672 -392.999722) (xy 344.720162 -393.025709)
			(xy 345.259662 -393.025709) (xy 345.259662 -392.973735) (xy 345.267792 -392.9224) (xy 345.283853 -392.87297)
			(xy 345.307449 -392.82666) (xy 345.337999 -392.784612) (xy 345.37475 -392.747861) (xy 345.416798 -392.717311)
			(xy 345.463108 -392.693715) (xy 345.512538 -392.677654) (xy 345.563873 -392.669524) (xy 345.615847 -392.669524)
			(xy 345.667182 -392.677654) (xy 345.716612 -392.693715) (xy 345.762922 -392.717311) (xy 345.80497 -392.747861)
			(xy 345.841721 -392.784612) (xy 345.872271 -392.82666) (xy 345.895867 -392.87297) (xy 345.911928 -392.9224)
			(xy 345.920058 -392.973735) (xy 345.920568 -392.999722) (xy 345.920058 -393.025709) (xy 346.459812 -393.025709)
			(xy 346.459812 -392.973735) (xy 346.467942 -392.9224) (xy 346.484003 -392.87297) (xy 346.507599 -392.82666)
			(xy 346.538149 -392.784612) (xy 346.5749 -392.747861) (xy 346.616948 -392.717311) (xy 346.663258 -392.693715)
			(xy 346.712688 -392.677654) (xy 346.764023 -392.669524) (xy 346.815997 -392.669524) (xy 346.867332 -392.677654)
			(xy 346.916762 -392.693715) (xy 346.963072 -392.717311) (xy 347.00512 -392.747861) (xy 347.041871 -392.784612)
			(xy 347.072421 -392.82666) (xy 347.096017 -392.87297) (xy 347.112078 -392.9224) (xy 347.120208 -392.973735)
			(xy 347.120718 -392.999722) (xy 347.120208 -393.025709) (xy 347.659708 -393.025709) (xy 347.659708 -392.973735)
			(xy 347.667838 -392.9224) (xy 347.683899 -392.87297) (xy 347.707495 -392.82666) (xy 347.738045 -392.784612)
			(xy 347.774796 -392.747861) (xy 347.816844 -392.717311) (xy 347.863154 -392.693715) (xy 347.912584 -392.677654)
			(xy 347.963919 -392.669524) (xy 348.015893 -392.669524) (xy 348.067228 -392.677654) (xy 348.116658 -392.693715)
			(xy 348.162968 -392.717311) (xy 348.205016 -392.747861) (xy 348.241767 -392.784612) (xy 348.272317 -392.82666)
			(xy 348.295913 -392.87297) (xy 348.311974 -392.9224) (xy 348.320104 -392.973735) (xy 348.320614 -392.999722)
			(xy 348.320104 -393.025709) (xy 348.859604 -393.025709) (xy 348.859604 -392.973735) (xy 348.867734 -392.9224)
			(xy 348.883795 -392.87297) (xy 348.907391 -392.82666) (xy 348.937941 -392.784612) (xy 348.974692 -392.747861)
			(xy 349.01674 -392.717311) (xy 349.06305 -392.693715) (xy 349.11248 -392.677654) (xy 349.163815 -392.669524)
			(xy 349.215789 -392.669524) (xy 349.267124 -392.677654) (xy 349.316554 -392.693715) (xy 349.362864 -392.717311)
			(xy 349.404912 -392.747861) (xy 349.441663 -392.784612) (xy 349.472213 -392.82666) (xy 349.495809 -392.87297)
			(xy 349.51187 -392.9224) (xy 349.52 -392.973735) (xy 349.52051 -392.999722) (xy 349.52 -393.025709)
			(xy 350.059754 -393.025709) (xy 350.059754 -392.973735) (xy 350.067884 -392.9224) (xy 350.083945 -392.87297)
			(xy 350.107541 -392.82666) (xy 350.138091 -392.784612) (xy 350.174842 -392.747861) (xy 350.21689 -392.717311)
			(xy 350.2632 -392.693715) (xy 350.31263 -392.677654) (xy 350.363965 -392.669524) (xy 350.415939 -392.669524)
			(xy 350.467274 -392.677654) (xy 350.516704 -392.693715) (xy 350.563014 -392.717311) (xy 350.605062 -392.747861)
			(xy 350.641813 -392.784612) (xy 350.672363 -392.82666) (xy 350.695959 -392.87297) (xy 350.71202 -392.9224)
			(xy 350.72015 -392.973735) (xy 350.72066 -392.999722) (xy 350.72015 -393.025709) (xy 350.71202 -393.077044)
			(xy 350.695959 -393.126474) (xy 350.672363 -393.172784) (xy 350.641813 -393.214832) (xy 350.605062 -393.251583)
			(xy 350.563014 -393.282133) (xy 350.516704 -393.305729) (xy 350.467274 -393.32179) (xy 350.415939 -393.32992)
			(xy 350.363965 -393.32992) (xy 350.31263 -393.32179) (xy 350.2632 -393.305729) (xy 350.21689 -393.282133)
			(xy 350.174842 -393.251583) (xy 350.138091 -393.214832) (xy 350.107541 -393.172784) (xy 350.083945 -393.126474)
			(xy 350.067884 -393.077044) (xy 350.059754 -393.025709) (xy 349.52 -393.025709) (xy 349.51187 -393.077044)
			(xy 349.495809 -393.126474) (xy 349.472213 -393.172784) (xy 349.441663 -393.214832) (xy 349.404912 -393.251583)
			(xy 349.362864 -393.282133) (xy 349.316554 -393.305729) (xy 349.267124 -393.32179) (xy 349.215789 -393.32992)
			(xy 349.163815 -393.32992) (xy 349.11248 -393.32179) (xy 349.06305 -393.305729) (xy 349.01674 -393.282133)
			(xy 348.974692 -393.251583) (xy 348.937941 -393.214832) (xy 348.907391 -393.172784) (xy 348.883795 -393.126474)
			(xy 348.867734 -393.077044) (xy 348.859604 -393.025709) (xy 348.320104 -393.025709) (xy 348.311974 -393.077044)
			(xy 348.295913 -393.126474) (xy 348.272317 -393.172784) (xy 348.241767 -393.214832) (xy 348.205016 -393.251583)
			(xy 348.162968 -393.282133) (xy 348.116658 -393.305729) (xy 348.067228 -393.32179) (xy 348.015893 -393.32992)
			(xy 347.963919 -393.32992) (xy 347.912584 -393.32179) (xy 347.863154 -393.305729) (xy 347.816844 -393.282133)
			(xy 347.774796 -393.251583) (xy 347.738045 -393.214832) (xy 347.707495 -393.172784) (xy 347.683899 -393.126474)
			(xy 347.667838 -393.077044) (xy 347.659708 -393.025709) (xy 347.120208 -393.025709) (xy 347.112078 -393.077044)
			(xy 347.096017 -393.126474) (xy 347.072421 -393.172784) (xy 347.041871 -393.214832) (xy 347.00512 -393.251583)
			(xy 346.963072 -393.282133) (xy 346.916762 -393.305729) (xy 346.867332 -393.32179) (xy 346.815997 -393.32992)
			(xy 346.764023 -393.32992) (xy 346.712688 -393.32179) (xy 346.663258 -393.305729) (xy 346.616948 -393.282133)
			(xy 346.5749 -393.251583) (xy 346.538149 -393.214832) (xy 346.507599 -393.172784) (xy 346.484003 -393.126474)
			(xy 346.467942 -393.077044) (xy 346.459812 -393.025709) (xy 345.920058 -393.025709) (xy 345.911928 -393.077044)
			(xy 345.895867 -393.126474) (xy 345.872271 -393.172784) (xy 345.841721 -393.214832) (xy 345.80497 -393.251583)
			(xy 345.762922 -393.282133) (xy 345.716612 -393.305729) (xy 345.667182 -393.32179) (xy 345.615847 -393.32992)
			(xy 345.563873 -393.32992) (xy 345.512538 -393.32179) (xy 345.463108 -393.305729) (xy 345.416798 -393.282133)
			(xy 345.37475 -393.251583) (xy 345.337999 -393.214832) (xy 345.307449 -393.172784) (xy 345.283853 -393.126474)
			(xy 345.267792 -393.077044) (xy 345.259662 -393.025709) (xy 344.720162 -393.025709) (xy 344.712032 -393.077044)
			(xy 344.695971 -393.126474) (xy 344.672375 -393.172784) (xy 344.641825 -393.214832) (xy 344.605074 -393.251583)
			(xy 344.563026 -393.282133) (xy 344.516716 -393.305729) (xy 344.467286 -393.32179) (xy 344.415951 -393.32992)
			(xy 344.363977 -393.32992) (xy 344.312642 -393.32179) (xy 344.263212 -393.305729) (xy 344.216902 -393.282133)
			(xy 344.174854 -393.251583) (xy 344.138103 -393.214832) (xy 344.107553 -393.172784) (xy 344.083957 -393.126474)
			(xy 344.067896 -393.077044) (xy 344.059766 -393.025709) (xy 343.520012 -393.025709) (xy 343.511882 -393.077044)
			(xy 343.495821 -393.126474) (xy 343.472225 -393.172784) (xy 343.441675 -393.214832) (xy 343.404924 -393.251583)
			(xy 343.362876 -393.282133) (xy 343.316566 -393.305729) (xy 343.267136 -393.32179) (xy 343.215801 -393.32992)
			(xy 343.163827 -393.32992) (xy 343.112492 -393.32179) (xy 343.063062 -393.305729) (xy 343.016752 -393.282133)
			(xy 342.974704 -393.251583) (xy 342.937953 -393.214832) (xy 342.907403 -393.172784) (xy 342.883807 -393.126474)
			(xy 342.867746 -393.077044) (xy 342.859616 -393.025709) (xy 342.320116 -393.025709) (xy 342.311986 -393.077044)
			(xy 342.295925 -393.126474) (xy 342.272329 -393.172784) (xy 342.241779 -393.214832) (xy 342.205028 -393.251583)
			(xy 342.16298 -393.282133) (xy 342.11667 -393.305729) (xy 342.06724 -393.32179) (xy 342.015905 -393.32992)
			(xy 341.963931 -393.32992) (xy 341.912596 -393.32179) (xy 341.863166 -393.305729) (xy 341.816856 -393.282133)
			(xy 341.774808 -393.251583) (xy 341.738057 -393.214832) (xy 341.707507 -393.172784) (xy 341.683911 -393.126474)
			(xy 341.66785 -393.077044) (xy 341.65972 -393.025709) (xy 341.12022 -393.025709) (xy 341.11209 -393.077044)
			(xy 341.096029 -393.126474) (xy 341.072433 -393.172784) (xy 341.041883 -393.214832) (xy 341.005132 -393.251583)
			(xy 340.963084 -393.282133) (xy 340.916774 -393.305729) (xy 340.867344 -393.32179) (xy 340.816009 -393.32992)
			(xy 340.764035 -393.32992) (xy 340.7127 -393.32179) (xy 340.66327 -393.305729) (xy 340.61696 -393.282133)
			(xy 340.574912 -393.251583) (xy 340.538161 -393.214832) (xy 340.507611 -393.172784) (xy 340.484015 -393.126474)
			(xy 340.467954 -393.077044) (xy 340.459824 -393.025709) (xy 339.92007 -393.025709) (xy 339.91194 -393.077044)
			(xy 339.895879 -393.126474) (xy 339.872283 -393.172784) (xy 339.841733 -393.214832) (xy 339.804982 -393.251583)
			(xy 339.762934 -393.282133) (xy 339.716624 -393.305729) (xy 339.667194 -393.32179) (xy 339.615859 -393.32992)
			(xy 339.563885 -393.32992) (xy 339.51255 -393.32179) (xy 339.46312 -393.305729) (xy 339.41681 -393.282133)
			(xy 339.374762 -393.251583) (xy 339.338011 -393.214832) (xy 339.307461 -393.172784) (xy 339.283865 -393.126474)
			(xy 339.267804 -393.077044) (xy 339.259674 -393.025709) (xy 338.720174 -393.025709) (xy 338.712044 -393.077044)
			(xy 338.695983 -393.126474) (xy 338.672387 -393.172784) (xy 338.641837 -393.214832) (xy 338.605086 -393.251583)
			(xy 338.563038 -393.282133) (xy 338.516728 -393.305729) (xy 338.467298 -393.32179) (xy 338.415963 -393.32992)
			(xy 338.363989 -393.32992) (xy 338.312654 -393.32179) (xy 338.263224 -393.305729) (xy 338.216914 -393.282133)
			(xy 338.174866 -393.251583) (xy 338.138115 -393.214832) (xy 338.107565 -393.172784) (xy 338.083969 -393.126474)
			(xy 338.067908 -393.077044) (xy 338.059778 -393.025709) (xy 337.520024 -393.025709) (xy 337.511894 -393.077044)
			(xy 337.495833 -393.126474) (xy 337.472237 -393.172784) (xy 337.441687 -393.214832) (xy 337.404936 -393.251583)
			(xy 337.362888 -393.282133) (xy 337.316578 -393.305729) (xy 337.267148 -393.32179) (xy 337.215813 -393.32992)
			(xy 337.163839 -393.32992) (xy 337.112504 -393.32179) (xy 337.063074 -393.305729) (xy 337.016764 -393.282133)
			(xy 336.974716 -393.251583) (xy 336.937965 -393.214832) (xy 336.907415 -393.172784) (xy 336.883819 -393.126474)
			(xy 336.867758 -393.077044) (xy 336.859628 -393.025709) (xy 336.320128 -393.025709) (xy 336.311998 -393.077044)
			(xy 336.295937 -393.126474) (xy 336.272341 -393.172784) (xy 336.241791 -393.214832) (xy 336.20504 -393.251583)
			(xy 336.162992 -393.282133) (xy 336.116682 -393.305729) (xy 336.067252 -393.32179) (xy 336.015917 -393.32992)
			(xy 335.963943 -393.32992) (xy 335.912608 -393.32179) (xy 335.863178 -393.305729) (xy 335.816868 -393.282133)
			(xy 335.77482 -393.251583) (xy 335.738069 -393.214832) (xy 335.707519 -393.172784) (xy 335.683923 -393.126474)
			(xy 335.667862 -393.077044) (xy 335.659732 -393.025709) (xy 334.09362 -393.025709) (xy 334.060908 -393.043077)
			(xy 334.012539 -393.059831) (xy 333.962168 -393.068935) (xy 333.936594 -393.07008) (xy 333.926434 -393.070334)
			(xy 333.9084 -393.078208) (xy 333.851758 -393.13612) (xy 333.845169 -393.143499) (xy 333.837706 -393.161798)
			(xy 333.83728 -393.17168) (xy 333.83728 -393.69238) (xy 335.988152 -393.69238) (xy 335.988683 -393.666394)
			(xy 335.996815 -393.615063) (xy 336.012877 -393.565636) (xy 336.036471 -393.519329) (xy 336.067019 -393.477282)
			(xy 336.103767 -393.440532) (xy 336.145812 -393.409982) (xy 336.192117 -393.386384) (xy 336.241543 -393.37032)
			(xy 336.292874 -393.362185) (xy 336.31886 -393.361672) (xy 336.344872 -393.362087) (xy 336.396251 -393.370255)
			(xy 336.445718 -393.386364) (xy 336.492054 -393.410017) (xy 336.534117 -393.440632) (xy 336.570869 -393.477453)
			(xy 336.601405 -393.519573) (xy 336.624972 -393.565953) (xy 336.640989 -393.61545) (xy 336.645504 -393.641072)
			(xy 336.647028 -393.65047) (xy 336.671254 -393.69238) (xy 337.188048 -393.69238) (xy 337.188583 -393.666394)
			(xy 337.196715 -393.615064) (xy 337.212776 -393.565636) (xy 337.236371 -393.51933) (xy 337.266918 -393.477284)
			(xy 337.303666 -393.440533) (xy 337.345709 -393.409983) (xy 337.392014 -393.386385) (xy 337.44144 -393.370321)
			(xy 337.492771 -393.362185) (xy 337.518756 -393.361672) (xy 337.544768 -393.362091) (xy 337.596147 -393.370258)
			(xy 337.645614 -393.386366) (xy 337.69195 -393.410019) (xy 337.734013 -393.440633) (xy 337.770765 -393.477454)
			(xy 337.801301 -393.519573) (xy 337.824868 -393.565953) (xy 337.840885 -393.61545) (xy 337.8454 -393.641072)
			(xy 337.846924 -393.65047) (xy 337.87115 -393.69238) (xy 338.388198 -393.69238) (xy 338.388683 -393.666392)
			(xy 338.396817 -393.615056) (xy 338.412881 -393.565625) (xy 338.43648 -393.519315) (xy 338.467032 -393.477267)
			(xy 338.503787 -393.440516) (xy 338.545837 -393.409966) (xy 338.592149 -393.386371) (xy 338.641582 -393.370311)
			(xy 338.692918 -393.362181) (xy 338.718906 -393.361672) (xy 338.744916 -393.362136) (xy 338.796293 -393.370296)
			(xy 338.84576 -393.386397) (xy 338.892096 -393.410044) (xy 338.934159 -393.440652) (xy 338.970912 -393.477468)
			(xy 339.001449 -393.519582) (xy 339.025017 -393.565958) (xy 339.041035 -393.615452) (xy 339.04555 -393.641072)
			(xy 339.047074 -393.65047) (xy 339.071296 -393.69238) (xy 339.588094 -393.69238) (xy 339.588583 -393.666392)
			(xy 339.596717 -393.615057) (xy 339.612781 -393.565626) (xy 339.636379 -393.519316) (xy 339.666931 -393.477268)
			(xy 339.703685 -393.440517) (xy 339.745735 -393.409968) (xy 339.792046 -393.386372) (xy 339.841478 -393.370312)
			(xy 339.892814 -393.362181) (xy 339.918802 -393.361672) (xy 339.944812 -393.36214) (xy 339.996189 -393.370299)
			(xy 340.045655 -393.3864) (xy 340.091991 -393.410046) (xy 340.134054 -393.440654) (xy 340.170808 -393.477469)
			(xy 340.201345 -393.519583) (xy 340.224913 -393.565959) (xy 340.240931 -393.615452) (xy 340.245446 -393.641072)
			(xy 340.24697 -393.65047) (xy 340.271196 -393.69238) (xy 340.78799 -393.69238) (xy 340.788483 -393.666392)
			(xy 340.796617 -393.615057) (xy 340.81268 -393.565627) (xy 340.836278 -393.519317) (xy 340.86683 -393.477269)
			(xy 340.903583 -393.440518) (xy 340.945633 -393.409969) (xy 340.991943 -393.386373) (xy 341.041375 -393.370312)
			(xy 341.09271 -393.362182) (xy 341.118698 -393.361672) (xy 341.144708 -393.362143) (xy 341.196085 -393.370302)
			(xy 341.245551 -393.386402) (xy 341.291887 -393.410048) (xy 341.33395 -393.440655) (xy 341.370703 -393.47747)
			(xy 341.401241 -393.519584) (xy 341.424809 -393.565959) (xy 341.440827 -393.615452) (xy 341.445342 -393.641072)
			(xy 341.446866 -393.65047) (xy 341.471092 -393.69238) (xy 341.98814 -393.69238) (xy 341.988557 -393.666388)
			(xy 341.996693 -393.615044) (xy 342.01276 -393.565605) (xy 342.036365 -393.519289) (xy 342.066925 -393.477235)
			(xy 342.103687 -393.44048) (xy 342.145747 -393.409929) (xy 342.192068 -393.386334) (xy 342.24151 -393.370277)
			(xy 342.292856 -393.362152) (xy 342.318848 -393.361672) (xy 342.34486 -393.362098) (xy 342.396238 -393.370264)
			(xy 342.445705 -393.386371) (xy 342.492041 -393.410023) (xy 342.534104 -393.440636) (xy 342.570857 -393.477456)
			(xy 342.601393 -393.519575) (xy 342.62496 -393.565954) (xy 342.640977 -393.61545) (xy 342.645492 -393.641072)
			(xy 342.647016 -393.65047) (xy 342.671242 -393.69238) (xy 343.188036 -393.69238) (xy 343.188457 -393.666388)
			(xy 343.196592 -393.615044) (xy 343.21266 -393.565606) (xy 343.236264 -393.51929) (xy 343.266823 -393.477236)
			(xy 343.303585 -393.440482) (xy 343.345644 -393.409931) (xy 343.391965 -393.386336) (xy 343.441407 -393.370277)
			(xy 343.492752 -393.362152) (xy 343.518744 -393.361672) (xy 343.544755 -393.362102) (xy 343.596134 -393.370267)
			(xy 343.645601 -393.386374) (xy 343.691937 -393.410025) (xy 343.734 -393.440638) (xy 343.770752 -393.477457)
			(xy 343.801289 -393.519576) (xy 343.824856 -393.565954) (xy 343.840873 -393.615451) (xy 343.845388 -393.641072)
			(xy 343.846912 -393.65047) (xy 343.871138 -393.69238) (xy 344.388186 -393.69238) (xy 344.388683 -393.666393)
			(xy 344.396816 -393.615058) (xy 344.41288 -393.565628) (xy 344.436478 -393.519319) (xy 344.467029 -393.477271)
			(xy 344.503781 -393.44052) (xy 344.54583 -393.40997) (xy 344.592141 -393.386374) (xy 344.641572 -393.370313)
			(xy 344.692907 -393.362182) (xy 344.718894 -393.361672) (xy 344.744904 -393.362147) (xy 344.79628 -393.370305)
			(xy 344.845747 -393.386405) (xy 344.892082 -393.41005) (xy 344.934146 -393.440657) (xy 344.970899 -393.477471)
			(xy 345.001436 -393.519585) (xy 345.025005 -393.56596) (xy 345.041023 -393.615452) (xy 345.045538 -393.641072)
			(xy 345.047062 -393.65047) (xy 345.071284 -393.69238) (xy 345.588082 -393.69238) (xy 345.588583 -393.666393)
			(xy 345.596716 -393.615059) (xy 345.612779 -393.565629) (xy 345.636377 -393.51932) (xy 345.666928 -393.477272)
			(xy 345.70368 -393.440521) (xy 345.745728 -393.409972) (xy 345.792038 -393.386376) (xy 345.841468 -393.370314)
			(xy 345.892803 -393.362182) (xy 345.91879 -393.361672) (xy 345.9448 -393.362151) (xy 345.996176 -393.370308)
			(xy 346.045642 -393.386407) (xy 346.091978 -393.410052) (xy 346.134041 -393.440658) (xy 346.170795 -393.477472)
			(xy 346.201332 -393.519585) (xy 346.224901 -393.56596) (xy 346.240919 -393.615452) (xy 346.245434 -393.641072)
			(xy 346.246958 -393.65047) (xy 346.271184 -393.69238) (xy 346.787978 -393.69238) (xy 346.788483 -393.666393)
			(xy 346.796616 -393.615059) (xy 346.812679 -393.565629) (xy 346.836276 -393.519321) (xy 346.866827 -393.477274)
			(xy 346.903578 -393.440523) (xy 346.945626 -393.409973) (xy 346.991935 -393.386377) (xy 347.041365 -393.370315)
			(xy 347.092699 -393.362183) (xy 347.118686 -393.361672) (xy 347.144696 -393.362154) (xy 347.196072 -393.370311)
			(xy 347.245538 -393.38641) (xy 347.291874 -393.410054) (xy 347.333937 -393.44066) (xy 347.370691 -393.477473)
			(xy 347.401228 -393.519586) (xy 347.424796 -393.56596) (xy 347.440815 -393.615453) (xy 347.44533 -393.641072)
			(xy 347.446854 -393.65047) (xy 347.47108 -393.69238) (xy 347.988128 -393.69238) (xy 347.988557 -393.666388)
			(xy 347.996692 -393.615046) (xy 348.012759 -393.565608) (xy 348.036363 -393.519292) (xy 348.066921 -393.477239)
			(xy 348.103682 -393.440485) (xy 348.14574 -393.409933) (xy 348.19206 -393.386338) (xy 348.2415 -393.370279)
			(xy 348.292844 -393.362152) (xy 348.318836 -393.361672) (xy 348.344847 -393.362109) (xy 348.396225 -393.370273)
			(xy 348.445692 -393.386379) (xy 348.492028 -393.410029) (xy 348.534091 -393.440641) (xy 348.570844 -393.477459)
			(xy 348.60138 -393.519577) (xy 348.624948 -393.565955) (xy 348.640965 -393.615451) (xy 348.64548 -393.641072)
			(xy 348.647004 -393.65047) (xy 348.67123 -393.69238) (xy 349.188024 -393.69238) (xy 349.188457 -393.666389)
			(xy 349.196592 -393.615046) (xy 349.212659 -393.565609) (xy 349.236262 -393.519293) (xy 349.26682 -393.477241)
			(xy 349.30358 -393.440486) (xy 349.345638 -393.409935) (xy 349.391957 -393.386339) (xy 349.441397 -393.37028)
			(xy 349.492741 -393.362153) (xy 349.518732 -393.361672) (xy 349.544743 -393.362112) (xy 349.596121 -393.370276)
			(xy 349.645588 -393.386381) (xy 349.691924 -393.410031) (xy 349.733987 -393.440642) (xy 349.77074 -393.477461)
			(xy 349.801276 -393.519578) (xy 349.824844 -393.565956) (xy 349.840861 -393.615451) (xy 349.845376 -393.641072)
			(xy 349.8469 -393.65047) (xy 349.871126 -393.69238) (xy 350.388174 -393.69238) (xy 350.388683 -393.666393)
			(xy 350.396816 -393.61506) (xy 350.412879 -393.56563) (xy 350.436475 -393.519322) (xy 350.467025 -393.477275)
			(xy 350.503776 -393.440524) (xy 350.545824 -393.409974) (xy 350.592132 -393.386378) (xy 350.641562 -393.370316)
			(xy 350.692895 -393.362183) (xy 350.718882 -393.361672) (xy 350.744892 -393.362158) (xy 350.796268 -393.370314)
			(xy 350.845733 -393.386412) (xy 350.892069 -393.410056) (xy 350.934133 -393.440661) (xy 350.970886 -393.477474)
			(xy 351.001424 -393.519587) (xy 351.024992 -393.565961) (xy 351.041011 -393.615453) (xy 351.045526 -393.641072)
			(xy 351.04705 -393.65047) (xy 351.3201 -394.12291) (xy 351.327212 -394.128752) (xy 351.345932 -394.144545)
			(xy 351.378987 -394.180684) (xy 351.406345 -394.221307) (xy 351.427407 -394.265523) (xy 351.44171 -394.312365)
			(xy 351.448941 -394.360804) (xy 351.449386 -394.385292) (xy 351.449132 -394.397484) (xy 351.448878 -394.407136)
			(xy 351.454974 -394.42517) (xy 351.513648 -394.49248) (xy 351.530412 -394.501116) (xy 351.540318 -394.502132)
			(xy 351.567082 -394.505476) (xy 351.619105 -394.519702) (xy 351.668131 -394.542179) (xy 351.71286 -394.572313)
			(xy 351.752107 -394.609305) (xy 351.784833 -394.652175) (xy 351.810169 -394.699787) (xy 351.827444 -394.750878)
			(xy 351.836201 -394.804096) (xy 351.836736 -394.831062) (xy 351.836193 -394.858347) (xy 351.82724 -394.912176)
			(xy 351.809569 -394.963805) (xy 351.783661 -395.011832) (xy 351.750219 -395.054953) (xy 351.730564 -395.073886)
			(xy 351.723176 -395.081419) (xy 351.714642 -395.10069) (xy 351.714054 -395.111224) (xy 351.714054 -395.1859)
			(xy 351.714583 -395.196449) (xy 351.72312 -395.215744) (xy 351.730564 -395.223238) (xy 351.750209 -395.242178)
			(xy 351.783641 -395.285303) (xy 351.809544 -395.333329) (xy 351.827215 -395.384954) (xy 351.836175 -395.438779)
			(xy 351.836736 -395.466062) (xy 351.836288 -395.490178) (xy 351.829292 -395.537901) (xy 351.815442 -395.584102)
			(xy 351.795031 -395.627802) (xy 351.782126 -395.64818) (xy 351.776284 -395.65707) (xy 351.772728 -395.677136)
			(xy 351.79381 -395.769338) (xy 351.806002 -395.786102) (xy 351.814892 -395.791436) (xy 351.835683 -395.804306)
			(xy 351.873591 -395.835192) (xy 351.906536 -395.871324) (xy 351.933799 -395.911914) (xy 351.954786 -395.956078)
			(xy 351.969039 -396.002851) (xy 351.976247 -396.051214) (xy 351.97669 -396.075662) (xy 351.976273 -396.100035)
			(xy 351.969127 -396.148255) (xy 351.954984 -396.194905) (xy 351.93415 -396.238975) (xy 351.907076 -396.279512)
			(xy 351.874348 -396.315638) (xy 351.855786 -396.33144) (xy 351.846896 -396.338552) (xy 351.837498 -396.35811)
			(xy 351.834704 -396.457424) (xy 351.84334 -396.47749) (xy 351.851722 -396.48511) (xy 351.870165 -396.502579)
			(xy 351.901513 -396.542547) (xy 351.925812 -396.587154) (xy 351.94239 -396.635168) (xy 351.95079 -396.685264)
			(xy 351.95129 -396.710662) (xy 351.951186 -396.721943) (xy 351.949535 -396.744445) (xy 351.947988 -396.75562)
			(xy 351.946718 -396.76451) (xy 351.950274 -396.782036) (xy 351.993708 -396.852902) (xy 352.007424 -396.864078)
			(xy 352.01606 -396.866872) (xy 352.038306 -396.874805) (xy 352.080227 -396.896557) (xy 352.1183 -396.924502)
			(xy 352.151619 -396.957974) (xy 352.179387 -396.996177) (xy 352.190558 -397.016986) (xy 352.191066 -397.018002)
			(xy 352.583496 -397.696944) (xy 352.596228 -397.72031) (xy 352.614344 -397.770338) (xy 352.623554 -397.822741)
			(xy 352.624136 -397.849344) (xy 352.623678 -397.873335) (xy 352.616166 -397.920726) (xy 352.601335 -397.966358)
			(xy 352.579548 -398.009109) (xy 352.551343 -398.047926) (xy 352.517413 -398.081853) (xy 352.478595 -398.110056)
			(xy 352.435843 -398.131841) (xy 352.39021 -398.14667) (xy 352.342819 -398.154179) (xy 352.318828 -398.154652)
			(xy 352.295296 -398.154227) (xy 352.248787 -398.147015) (xy 352.203938 -398.132744) (xy 352.161814 -398.111752)
			(xy 352.123416 -398.084537) (xy 352.089655 -398.051746) (xy 352.061332 -398.014157) (xy 352.049842 -397.993616)
			(xy 352.049588 -397.993108) (xy 352.04908 -397.992346) (xy 351.651316 -397.304006) (xy 351.639402 -397.281337)
			(xy 351.622464 -397.233012) (xy 351.613804 -397.182542) (xy 351.613216 -397.15694) (xy 351.613216 -397.156432)
			(xy 351.613373 -397.145083) (xy 351.61515 -397.122453) (xy 351.616772 -397.11122) (xy 351.618042 -397.10233)
			(xy 351.614486 -397.085058) (xy 351.571052 -397.013938) (xy 351.557082 -397.003016) (xy 351.5487 -396.999968)
			(xy 351.526289 -396.99196) (xy 351.484071 -396.969995) (xy 351.445776 -396.941742) (xy 351.412332 -396.907887)
			(xy 351.384549 -396.869249) (xy 351.363101 -396.826767) (xy 351.348509 -396.78147) (xy 351.341127 -396.734457)
			(xy 351.340674 -396.710662) (xy 351.341208 -396.685268) (xy 351.349617 -396.635179) (xy 351.366195 -396.587172)
			(xy 351.390487 -396.542569) (xy 351.421823 -396.5026) (xy 351.440242 -396.48511) (xy 351.448624 -396.47749)
			(xy 351.45726 -396.457424) (xy 351.454466 -396.35811) (xy 351.445068 -396.338552) (xy 351.436178 -396.33144)
			(xy 351.417646 -396.315606) (xy 351.384924 -396.279482) (xy 351.357852 -396.238951) (xy 351.337017 -396.194887)
			(xy 351.322868 -396.148245) (xy 351.315712 -396.100032) (xy 351.315274 -396.075662) (xy 351.315684 -396.051544)
			(xy 351.322691 -396.003821) (xy 351.336553 -395.95762) (xy 351.356974 -395.91392) (xy 351.369884 -395.893544)
			(xy 351.375726 -395.884654) (xy 351.379282 -395.864588) (xy 351.3582 -395.772386) (xy 351.346008 -395.755622)
			(xy 351.337118 -395.750288) (xy 351.31634 -395.737398) (xy 351.278432 -395.706516) (xy 351.245486 -395.670387)
			(xy 351.218221 -395.6298) (xy 351.197232 -395.58564) (xy 351.182976 -395.538869) (xy 351.175765 -395.490509)
			(xy 351.17532 -395.466062) (xy 351.17586 -395.438777) (xy 351.184812 -395.384946) (xy 351.202482 -395.333317)
			(xy 351.228391 -395.28529) (xy 351.261836 -395.24217) (xy 351.281492 -395.223238) (xy 351.288878 -395.215703)
			(xy 351.297411 -395.196433) (xy 351.298002 -395.1859) (xy 351.298002 -395.111224) (xy 351.297473 -395.100674)
			(xy 351.288938 -395.081379) (xy 351.281492 -395.073886) (xy 351.261869 -395.054924) (xy 351.228431 -395.011806)
			(xy 351.202524 -394.963786) (xy 351.184848 -394.912165) (xy 351.175883 -394.858344) (xy 351.17532 -394.831062)
			(xy 351.175574 -394.81887) (xy 351.175828 -394.809218) (xy 351.169732 -394.791184) (xy 351.111058 -394.723874)
			(xy 351.094294 -394.715238) (xy 351.084388 -394.714222) (xy 351.057438 -394.710836) (xy 351.005055 -394.696492)
			(xy 350.955722 -394.673776) (xy 350.910766 -394.643302) (xy 350.871397 -394.605888) (xy 350.838675 -394.562541)
			(xy 350.813479 -394.514427) (xy 350.796487 -394.462842) (xy 350.79178 -394.436092) (xy 350.79051 -394.426694)
			(xy 350.517968 -393.95527) (xy 350.510602 -393.949428) (xy 350.491856 -393.93359) (xy 350.458736 -393.897381)
			(xy 350.431322 -393.85668) (xy 350.410216 -393.812379) (xy 350.395879 -393.765449) (xy 350.388625 -393.716916)
			(xy 350.388174 -393.69238) (xy 349.871126 -393.69238) (xy 350.119696 -394.122402) (xy 350.127062 -394.128244)
			(xy 350.145856 -394.144027) (xy 350.17897 -394.180249) (xy 350.206376 -394.220962) (xy 350.227474 -394.265273)
			(xy 350.241801 -394.312213) (xy 350.249045 -394.360753) (xy 350.24949 -394.385292) (xy 350.249236 -394.397484)
			(xy 350.248982 -394.407136) (xy 350.255078 -394.42517) (xy 350.313752 -394.49248) (xy 350.330516 -394.501116)
			(xy 350.340422 -394.502132) (xy 350.367186 -394.505473) (xy 350.41921 -394.519699) (xy 350.468235 -394.542177)
			(xy 350.512965 -394.572312) (xy 350.552212 -394.609304) (xy 350.584937 -394.652174) (xy 350.610273 -394.699786)
			(xy 350.627548 -394.750878) (xy 350.636305 -394.804095) (xy 350.63684 -394.831062) (xy 350.636296 -394.858347)
			(xy 350.627343 -394.912176) (xy 350.609672 -394.963805) (xy 350.583764 -395.011832) (xy 350.550322 -395.054953)
			(xy 350.530668 -395.073886) (xy 350.523281 -395.08142) (xy 350.514746 -395.10069) (xy 350.514158 -395.111224)
			(xy 350.514158 -395.1859) (xy 350.514686 -395.196449) (xy 350.523223 -395.215744) (xy 350.530668 -395.223238)
			(xy 350.550314 -395.242178) (xy 350.583746 -395.285302) (xy 350.609648 -395.333328) (xy 350.627319 -395.384954)
			(xy 350.636279 -395.438779) (xy 350.63684 -395.466062) (xy 350.636392 -395.490178) (xy 350.629395 -395.5379)
			(xy 350.615545 -395.584101) (xy 350.595135 -395.627802) (xy 350.58223 -395.64818) (xy 350.576388 -395.65707)
			(xy 350.572832 -395.677136) (xy 350.593914 -395.769338) (xy 350.606106 -395.786102) (xy 350.614996 -395.791436)
			(xy 350.635788 -395.804305) (xy 350.673696 -395.835191) (xy 350.70664 -395.871323) (xy 350.733903 -395.911914)
			(xy 350.75489 -395.956078) (xy 350.769143 -396.002851) (xy 350.776351 -396.051214) (xy 350.776794 -396.075662)
			(xy 350.776375 -396.100035) (xy 350.769229 -396.148255) (xy 350.755086 -396.194905) (xy 350.734253 -396.238975)
			(xy 350.707179 -396.279512) (xy 350.674452 -396.315638) (xy 350.65589 -396.33144) (xy 350.647 -396.338552)
			(xy 350.637602 -396.35811) (xy 350.634808 -396.457424) (xy 350.643444 -396.47749) (xy 350.651826 -396.48511)
			(xy 350.670269 -396.502578) (xy 350.701618 -396.542546) (xy 350.725916 -396.587153) (xy 350.742494 -396.635168)
			(xy 350.750894 -396.685264) (xy 350.751394 -396.710662) (xy 350.75129 -396.721943) (xy 350.749639 -396.744445)
			(xy 350.748092 -396.75562) (xy 350.746822 -396.764764) (xy 350.750124 -396.782036) (xy 350.793812 -396.853156)
			(xy 350.807528 -396.864078) (xy 350.816164 -396.866872) (xy 350.844327 -396.877073) (xy 350.896274 -396.906882)
			(xy 350.919288 -396.926054) (xy 350.940771 -396.945636) (xy 350.976585 -396.991414) (xy 350.990408 -397.016986)
			(xy 350.99117 -397.018256) (xy 351.383346 -397.696944) (xy 351.396153 -397.720286) (xy 351.41438 -397.770304)
			(xy 351.423647 -397.822727) (xy 351.42424 -397.849344) (xy 351.423802 -397.873349) (xy 351.416281 -397.920768)
			(xy 351.401433 -397.966425) (xy 351.379623 -398.009196) (xy 351.351388 -398.048027) (xy 351.317425 -398.081961)
			(xy 351.278569 -398.110162) (xy 351.235779 -398.131935) (xy 351.190109 -398.146744) (xy 351.142684 -398.154222)
			(xy 351.118678 -398.154652) (xy 351.095147 -398.154186) (xy 351.04864 -398.146983) (xy 351.003792 -398.132718)
			(xy 350.961669 -398.111733) (xy 350.92327 -398.084524) (xy 350.889507 -398.051739) (xy 350.861183 -398.014155)
			(xy 350.849692 -397.993616) (xy 350.849438 -397.993108) (xy 350.84893 -397.992346) (xy 350.45142 -397.303752)
			(xy 350.440848 -397.283825) (xy 350.425045 -397.241576) (xy 350.415637 -397.197459) (xy 350.413828 -397.174974)
			(xy 350.41332 -397.163798) (xy 350.41332 -397.156432) (xy 350.413411 -397.145087) (xy 350.415066 -397.122458)
			(xy 350.416622 -397.11122) (xy 350.417892 -397.10233) (xy 350.414336 -397.085058) (xy 350.370902 -397.013938)
			(xy 350.357186 -397.002762) (xy 350.34855 -396.999968) (xy 350.326143 -396.991983) (xy 350.283973 -396.969978)
			(xy 350.245726 -396.941698) (xy 350.212327 -396.90783) (xy 350.184584 -396.869191) (xy 350.163169 -396.826718)
			(xy 350.1486 -396.781437) (xy 350.141229 -396.734445) (xy 350.140778 -396.710662) (xy 350.141311 -396.685267)
			(xy 350.149719 -396.635179) (xy 350.166298 -396.587172) (xy 350.190591 -396.542569) (xy 350.221927 -396.502599)
			(xy 350.240346 -396.48511) (xy 350.248728 -396.47749) (xy 350.257364 -396.457424) (xy 350.25457 -396.35811)
			(xy 350.245172 -396.338552) (xy 350.236282 -396.33144) (xy 350.217751 -396.315605) (xy 350.185028 -396.279482)
			(xy 350.157956 -396.23895) (xy 350.137121 -396.194887) (xy 350.122972 -396.148245) (xy 350.115816 -396.100032)
			(xy 350.115378 -396.075662) (xy 350.115787 -396.051544) (xy 350.122795 -396.00382) (xy 350.136656 -395.957619)
			(xy 350.157078 -395.91392) (xy 350.169988 -395.893544) (xy 350.17583 -395.884654) (xy 350.179386 -395.864588)
			(xy 350.158304 -395.772386) (xy 350.146112 -395.755622) (xy 350.137222 -395.750288) (xy 350.116445 -395.737396)
			(xy 350.078536 -395.706515) (xy 350.04559 -395.670387) (xy 350.018325 -395.6298) (xy 349.997336 -395.585639)
			(xy 349.98308 -395.538869) (xy 349.975869 -395.490509) (xy 349.975424 -395.466062) (xy 349.975963 -395.438777)
			(xy 349.984915 -395.384946) (xy 350.002585 -395.333316) (xy 350.028495 -395.28529) (xy 350.06194 -395.24217)
			(xy 350.081596 -395.223238) (xy 350.088982 -395.215704) (xy 350.097515 -395.196433) (xy 350.098106 -395.1859)
			(xy 350.098106 -395.111224) (xy 350.097576 -395.100675) (xy 350.089041 -395.081379) (xy 350.081596 -395.073886)
			(xy 350.061973 -395.054923) (xy 350.028536 -395.011806) (xy 350.002628 -394.963786) (xy 349.984952 -394.912165)
			(xy 349.975987 -394.858343) (xy 349.975424 -394.831062) (xy 349.975678 -394.81887) (xy 349.975932 -394.809218)
			(xy 349.969836 -394.791184) (xy 349.911162 -394.723874) (xy 349.894398 -394.715238) (xy 349.884492 -394.714222)
			(xy 349.857589 -394.710825) (xy 349.805303 -394.696466) (xy 349.75606 -394.673772) (xy 349.711177 -394.643351)
			(xy 349.671856 -394.606017) (xy 349.639151 -394.56277) (xy 349.613936 -394.514768) (xy 349.596888 -394.463297)
			(xy 349.592138 -394.4366) (xy 349.590614 -394.427202) (xy 349.317818 -393.95527) (xy 349.310452 -393.949428)
			(xy 349.291695 -393.933603) (xy 349.258578 -393.897389) (xy 349.231167 -393.856686) (xy 349.210063 -393.812383)
			(xy 349.195727 -393.76545) (xy 349.188474 -393.716916) (xy 349.188024 -393.69238) (xy 348.67123 -393.69238)
			(xy 348.9198 -394.122402) (xy 348.927166 -394.128244) (xy 348.945961 -394.144026) (xy 348.979075 -394.180249)
			(xy 349.00648 -394.220962) (xy 349.027578 -394.265273) (xy 349.041905 -394.312213) (xy 349.049149 -394.360753)
			(xy 349.049594 -394.385292) (xy 349.04934 -394.397484) (xy 349.049086 -394.407136) (xy 349.055182 -394.42517)
			(xy 349.113856 -394.49248) (xy 349.13062 -394.501116) (xy 349.140272 -394.502132) (xy 349.167031 -394.505514)
			(xy 349.219053 -394.519732) (xy 349.268079 -394.542204) (xy 349.312809 -394.572332) (xy 349.352058 -394.60932)
			(xy 349.384784 -394.652185) (xy 349.410121 -394.699794) (xy 349.427397 -394.750882) (xy 349.436154 -394.804097)
			(xy 349.43669 -394.831062) (xy 349.43618 -394.857049) (xy 349.42805 -394.908384) (xy 349.411989 -394.957814)
			(xy 349.388393 -395.004124) (xy 349.357843 -395.046172) (xy 349.321092 -395.082923) (xy 349.279044 -395.113473)
			(xy 349.232734 -395.137069) (xy 349.183304 -395.15313) (xy 349.131969 -395.16126) (xy 349.079995 -395.16126)
			(xy 349.02866 -395.15313) (xy 348.97923 -395.137069) (xy 348.93292 -395.113473) (xy 348.890872 -395.082923)
			(xy 348.854121 -395.046172) (xy 348.823571 -395.004124) (xy 348.799975 -394.957814) (xy 348.783914 -394.908384)
			(xy 348.775784 -394.857049) (xy 348.775274 -394.831062) (xy 348.775528 -394.81887) (xy 348.775782 -394.809218)
			(xy 348.769686 -394.791184) (xy 348.711012 -394.723874) (xy 348.694248 -394.715238) (xy 348.684596 -394.714222)
			(xy 348.657693 -394.710822) (xy 348.605408 -394.696464) (xy 348.556164 -394.67377) (xy 348.511281 -394.643349)
			(xy 348.47196 -394.606016) (xy 348.439255 -394.562769) (xy 348.41404 -394.514768) (xy 348.396992 -394.463297)
			(xy 348.392242 -394.4366) (xy 348.390718 -394.427202) (xy 348.117922 -393.95527) (xy 348.110556 -393.949428)
			(xy 348.0918 -393.933602) (xy 348.058683 -393.897389) (xy 348.031272 -393.856685) (xy 348.010167 -393.812382)
			(xy 347.995832 -393.76545) (xy 347.988578 -393.716916) (xy 347.988128 -393.69238) (xy 347.47108 -393.69238)
			(xy 347.71965 -394.122402) (xy 347.727016 -394.128244) (xy 347.745801 -394.144038) (xy 347.778917 -394.180257)
			(xy 347.806326 -394.220967) (xy 347.827425 -394.265276) (xy 347.841754 -394.312215) (xy 347.848999 -394.360754)
			(xy 347.849444 -394.385292) (xy 347.84919 -394.397484) (xy 347.848936 -394.407136) (xy 347.855032 -394.42517)
			(xy 347.913706 -394.49248) (xy 347.93047 -394.501116) (xy 347.940376 -394.502132) (xy 347.967135 -394.505511)
			(xy 348.019158 -394.51973) (xy 348.068184 -394.542201) (xy 348.112914 -394.572331) (xy 348.152162 -394.609318)
			(xy 348.184888 -394.652185) (xy 348.210225 -394.699793) (xy 348.227501 -394.750882) (xy 348.236258 -394.804097)
			(xy 348.236794 -394.831062) (xy 348.23637 -394.855264) (xy 348.229296 -394.903149) (xy 348.215309 -394.949488)
			(xy 348.194709 -394.99329) (xy 348.181676 -395.013688) (xy 348.176889 -395.021645) (xy 348.172854 -395.039756)
			(xy 348.173802 -395.048994) (xy 348.17812 -395.079982) (xy 348.179796 -395.08928) (xy 348.189081 -395.105721)
			(xy 348.196154 -395.111986) (xy 348.21824 -395.13067) (xy 348.258012 -395.172681) (xy 348.292175 -395.219369)
			(xy 348.320183 -395.269988) (xy 348.34159 -395.323733) (xy 348.356056 -395.379747) (xy 348.363349 -395.437136)
			(xy 348.363794 -395.466062) (xy 348.363199 -395.499383) (xy 348.353538 -395.565321) (xy 348.334414 -395.629161)
			(xy 348.320868 -395.65961) (xy 348.316623 -395.670076) (xy 348.316737 -395.692634) (xy 348.326469 -395.712985)
			(xy 348.334838 -395.72057) (xy 348.357076 -395.739254) (xy 348.397138 -395.781308) (xy 348.431559 -395.828093)
			(xy 348.459784 -395.878857) (xy 348.481361 -395.932783) (xy 348.495943 -395.989005) (xy 348.503295 -396.046621)
			(xy 348.503748 -396.075662) (xy 348.503273 -396.104667) (xy 348.495962 -396.162214) (xy 348.48144 -396.218377)
			(xy 348.459939 -396.272255) (xy 348.431804 -396.322986) (xy 348.397487 -396.369756) (xy 348.357535 -396.411815)
			(xy 348.335346 -396.4305) (xy 348.328234 -396.436088) (xy 348.31909 -396.451328) (xy 348.30385 -396.534132)
			(xy 348.306644 -396.551404) (xy 348.311216 -396.559532) (xy 348.323789 -396.58272) (xy 348.341664 -396.63234)
			(xy 348.350766 -396.684291) (xy 348.351348 -396.710662) (xy 348.940628 -396.710662) (xy 348.94115 -396.685407)
			(xy 348.949463 -396.635585) (xy 348.965864 -396.587811) (xy 348.989905 -396.543388) (xy 349.020929 -396.503528)
			(xy 349.058091 -396.469318) (xy 349.100377 -396.441692) (xy 349.146633 -396.421402) (xy 349.195598 -396.409002)
			(xy 349.245936 -396.404831) (xy 349.296274 -396.409002) (xy 349.345239 -396.421402) (xy 349.391495 -396.441692)
			(xy 349.433781 -396.469318) (xy 349.470943 -396.503528) (xy 349.501967 -396.543388) (xy 349.526008 -396.587811)
			(xy 349.542409 -396.635585) (xy 349.550722 -396.685407) (xy 349.551244 -396.710662) (xy 349.551141 -396.721943)
			(xy 349.549489 -396.744445) (xy 349.547942 -396.75562) (xy 349.546672 -396.76451) (xy 349.550228 -396.782036)
			(xy 349.593662 -396.852902) (xy 349.607378 -396.864078) (xy 349.616014 -396.866872) (xy 349.63827 -396.87478)
			(xy 349.680189 -396.896538) (xy 349.718261 -396.92449) (xy 349.751577 -396.957968) (xy 349.779343 -396.996174)
			(xy 349.790512 -397.016986) (xy 349.79102 -397.018002) (xy 350.18345 -397.696944) (xy 350.196257 -397.720285)
			(xy 350.214484 -397.770304) (xy 350.223751 -397.822726) (xy 350.224344 -397.849344) (xy 350.223902 -397.873349)
			(xy 350.216382 -397.920767) (xy 350.201534 -397.966424) (xy 350.179724 -398.009195) (xy 350.15149 -398.048026)
			(xy 350.117526 -398.08196) (xy 350.078671 -398.110161) (xy 350.035882 -398.131934) (xy 349.990212 -398.146743)
			(xy 349.942788 -398.154222) (xy 349.918782 -398.154652) (xy 349.895251 -398.154183) (xy 349.848744 -398.14698)
			(xy 349.803896 -398.132716) (xy 349.761773 -398.111731) (xy 349.723374 -398.084523) (xy 349.689611 -398.051738)
			(xy 349.661287 -398.014155) (xy 349.649796 -397.993616) (xy 349.649542 -397.993108) (xy 349.649034 -397.992346)
			(xy 349.25127 -397.304006) (xy 349.239395 -397.281329) (xy 349.222543 -397.232996) (xy 349.21397 -397.182533)
			(xy 349.213424 -397.15694) (xy 349.213424 -397.156432) (xy 349.213515 -397.145087) (xy 349.21517 -397.122458)
			(xy 349.216726 -397.11122) (xy 349.217996 -397.10233) (xy 349.21444 -397.085058) (xy 349.171006 -397.013938)
			(xy 349.157036 -397.003016) (xy 349.148654 -396.999968) (xy 349.126254 -396.991929) (xy 349.084036 -396.969971)
			(xy 349.045738 -396.941724) (xy 349.012292 -396.907874) (xy 348.984507 -396.86924) (xy 348.963058 -396.826761)
			(xy 348.948465 -396.781467) (xy 348.941081 -396.734456) (xy 348.940628 -396.710662) (xy 348.351348 -396.710662)
			(xy 348.351245 -396.721943) (xy 348.349593 -396.744445) (xy 348.348046 -396.75562) (xy 348.346776 -396.76451)
			(xy 348.350332 -396.782036) (xy 348.393766 -396.852902) (xy 348.407482 -396.864078) (xy 348.416118 -396.866872)
			(xy 348.438374 -396.874778) (xy 348.480294 -396.896537) (xy 348.518365 -396.924489) (xy 348.551681 -396.957967)
			(xy 348.579447 -396.996174) (xy 348.590616 -397.016986) (xy 348.591124 -397.018002) (xy 348.983554 -397.696944)
			(xy 348.996362 -397.720285) (xy 349.014588 -397.770304) (xy 349.023855 -397.822726) (xy 349.024448 -397.849344)
			(xy 349.024002 -397.873349) (xy 349.016482 -397.920767) (xy 349.001634 -397.966423) (xy 348.979825 -398.009194)
			(xy 348.951591 -398.048025) (xy 348.917628 -398.081959) (xy 348.878773 -398.11016) (xy 348.835984 -398.131933)
			(xy 348.790315 -398.146742) (xy 348.742891 -398.154222) (xy 348.718886 -398.154652) (xy 348.695355 -398.15418)
			(xy 348.648849 -398.146977) (xy 348.604001 -398.132714) (xy 348.561877 -398.11173) (xy 348.523478 -398.084522)
			(xy 348.489716 -398.051737) (xy 348.461391 -398.014154) (xy 348.4499 -397.993616) (xy 348.449646 -397.993108)
			(xy 348.449138 -397.992346) (xy 348.051374 -397.304006) (xy 348.039499 -397.281329) (xy 348.022648 -397.232996)
			(xy 348.014074 -397.182533) (xy 348.013528 -397.15694) (xy 348.013528 -397.156432) (xy 348.013619 -397.145087)
			(xy 348.015274 -397.122458) (xy 348.01683 -397.11122) (xy 348.0181 -397.10233) (xy 348.014544 -397.085058)
			(xy 347.97111 -397.013938) (xy 347.95714 -397.003016) (xy 347.948758 -396.999968) (xy 347.926359 -396.991926)
			(xy 347.88414 -396.969969) (xy 347.845843 -396.941723) (xy 347.812396 -396.907873) (xy 347.784611 -396.86924)
			(xy 347.763162 -396.826761) (xy 347.748569 -396.781466) (xy 347.741185 -396.734456) (xy 347.740732 -396.710662)
			(xy 347.741294 -396.684289) (xy 347.750378 -396.63233) (xy 347.768268 -396.58271) (xy 347.780864 -396.559532)
			(xy 347.785436 -396.551404) (xy 347.78823 -396.534132) (xy 347.77299 -396.451328) (xy 347.763846 -396.436088)
			(xy 347.756734 -396.4305) (xy 347.73457 -396.411786) (xy 347.694622 -396.369727) (xy 347.660303 -396.322961)
			(xy 347.632162 -396.272236) (xy 347.610651 -396.218364) (xy 347.596114 -396.162208) (xy 347.588783 -396.104666)
			(xy 347.588332 -396.075662) (xy 347.588933 -396.042341) (xy 347.598591 -395.976403) (xy 347.617713 -395.912563)
			(xy 347.631258 -395.882114) (xy 347.635504 -395.871647) (xy 347.6354 -395.849087) (xy 347.625662 -395.828735)
			(xy 347.617288 -395.821154) (xy 347.595018 -395.802506) (xy 347.554957 -395.760446) (xy 347.520539 -395.713655)
			(xy 347.492317 -395.662885) (xy 347.470745 -395.608953) (xy 347.45617 -395.552725) (xy 347.448826 -395.495105)
			(xy 347.448378 -395.466062) (xy 347.44882 -395.437135) (xy 347.456104 -395.379742) (xy 347.470564 -395.323725)
			(xy 347.491969 -395.269977) (xy 347.519978 -395.219355) (xy 347.554143 -395.172668) (xy 347.593921 -395.130659)
			(xy 347.616018 -395.111986) (xy 347.622983 -395.105632) (xy 347.632246 -395.089233) (xy 347.634052 -395.079982)
			(xy 347.63837 -395.048994) (xy 347.639271 -395.039757) (xy 347.635248 -395.021658) (xy 347.630496 -395.013688)
			(xy 347.617508 -394.993266) (xy 347.596928 -394.949464) (xy 347.582941 -394.903133) (xy 347.575845 -394.85526)
			(xy 347.575378 -394.831062) (xy 347.575632 -394.81887) (xy 347.575886 -394.809218) (xy 347.56979 -394.791184)
			(xy 347.511116 -394.723874) (xy 347.494352 -394.715238) (xy 347.484446 -394.714222) (xy 347.457538 -394.710862)
			(xy 347.405252 -394.696496) (xy 347.356008 -394.673795) (xy 347.311126 -394.643368) (xy 347.271806 -394.606029)
			(xy 347.239102 -394.562778) (xy 347.213889 -394.514773) (xy 347.196842 -394.463298) (xy 347.192092 -394.4366)
			(xy 347.190568 -394.427202) (xy 346.917772 -393.95527) (xy 346.910406 -393.949428) (xy 346.891661 -393.93359)
			(xy 346.85854 -393.89738) (xy 346.831127 -393.85668) (xy 346.81002 -393.812379) (xy 346.795683 -393.765448)
			(xy 346.788429 -393.716916) (xy 346.787978 -393.69238) (xy 346.271184 -393.69238) (xy 346.519754 -394.122402)
			(xy 346.52712 -394.128244) (xy 346.545906 -394.144037) (xy 346.579022 -394.180256) (xy 346.60643 -394.220966)
			(xy 346.62753 -394.265276) (xy 346.641858 -394.312214) (xy 346.649103 -394.360754) (xy 346.649548 -394.385292)
			(xy 346.649294 -394.397484) (xy 346.64904 -394.407136) (xy 346.655136 -394.42517) (xy 346.71381 -394.49248)
			(xy 346.730574 -394.501116) (xy 346.740226 -394.502132) (xy 346.766991 -394.50547) (xy 346.819014 -394.519696)
			(xy 346.86804 -394.542175) (xy 346.912769 -394.57231) (xy 346.952016 -394.609303) (xy 346.984741 -394.652174)
			(xy 347.010077 -394.699786) (xy 347.027352 -394.750878) (xy 347.036109 -394.804095) (xy 347.036644 -394.831062)
			(xy 347.036099 -394.858347) (xy 347.027145 -394.912176) (xy 347.009475 -394.963805) (xy 346.983568 -395.011832)
			(xy 346.950126 -395.054953) (xy 346.930472 -395.073886) (xy 346.923085 -395.08142) (xy 346.91455 -395.10069)
			(xy 346.913962 -395.111224) (xy 346.913962 -395.1859) (xy 346.914489 -395.19645) (xy 346.923027 -395.215744)
			(xy 346.930472 -395.223238) (xy 346.950119 -395.242177) (xy 346.98355 -395.285302) (xy 347.009453 -395.333328)
			(xy 347.027123 -395.384954) (xy 347.036083 -395.438779) (xy 347.036644 -395.466062) (xy 347.036195 -395.490178)
			(xy 347.029199 -395.5379) (xy 347.015349 -395.584101) (xy 346.994939 -395.627802) (xy 346.982034 -395.64818)
			(xy 346.976192 -395.65707) (xy 346.972636 -395.677136) (xy 346.993718 -395.769338) (xy 347.00591 -395.786102)
			(xy 347.0148 -395.791436) (xy 347.035593 -395.804303) (xy 347.0735 -395.835189) (xy 347.106445 -395.871322)
			(xy 347.133708 -395.911913) (xy 347.154694 -395.956077) (xy 347.168947 -396.002851) (xy 347.176155 -396.051214)
			(xy 347.176598 -396.075662) (xy 347.176178 -396.100035) (xy 347.169032 -396.148255) (xy 347.154889 -396.194904)
			(xy 347.134056 -396.238974) (xy 347.106983 -396.279511) (xy 347.074255 -396.315638) (xy 347.055694 -396.33144)
			(xy 347.046804 -396.338552) (xy 347.037406 -396.35811) (xy 347.034612 -396.457424) (xy 347.043248 -396.47749)
			(xy 347.05163 -396.48511) (xy 347.070074 -396.502577) (xy 347.101422 -396.542546) (xy 347.125721 -396.587153)
			(xy 347.142298 -396.635168) (xy 347.150698 -396.685264) (xy 347.151198 -396.710662) (xy 347.151094 -396.721943)
			(xy 347.149443 -396.744445) (xy 347.147896 -396.75562) (xy 347.146626 -396.76451) (xy 347.150182 -396.782036)
			(xy 347.193616 -396.852902) (xy 347.207332 -396.864078) (xy 347.215968 -396.866872) (xy 347.238215 -396.874802)
			(xy 347.280136 -396.896554) (xy 347.318209 -396.9245) (xy 347.351527 -396.957973) (xy 347.379295 -396.996176)
			(xy 347.390466 -397.016986) (xy 347.390974 -397.018002) (xy 347.783404 -397.696944) (xy 347.796137 -397.72031)
			(xy 347.814252 -397.770337) (xy 347.823462 -397.822741) (xy 347.824044 -397.849344) (xy 347.823578 -397.873335)
			(xy 347.816067 -397.920724) (xy 347.801235 -397.966356) (xy 347.779449 -398.009106) (xy 347.751245 -398.047923)
			(xy 347.717317 -398.08185) (xy 347.678499 -398.110054) (xy 347.635749 -398.131838) (xy 347.590117 -398.146668)
			(xy 347.542727 -398.154179) (xy 347.518736 -398.154652) (xy 347.495204 -398.15422) (xy 347.448695 -398.14701)
			(xy 347.403847 -398.13274) (xy 347.361723 -398.111749) (xy 347.323325 -398.084535) (xy 347.289563 -398.051745)
			(xy 347.26124 -398.014157) (xy 347.24975 -397.993616) (xy 347.249496 -397.993108) (xy 347.248988 -397.992346)
			(xy 346.851224 -397.304006) (xy 346.839311 -397.281337) (xy 346.822372 -397.233012) (xy 346.813712 -397.182542)
			(xy 346.813124 -397.15694) (xy 346.813124 -397.156432) (xy 346.813281 -397.145083) (xy 346.815058 -397.122453)
			(xy 346.81668 -397.11122) (xy 346.81795 -397.10233) (xy 346.814394 -397.085058) (xy 346.77096 -397.013938)
			(xy 346.75699 -397.003016) (xy 346.748608 -396.999968) (xy 346.726199 -396.991955) (xy 346.683981 -396.969991)
			(xy 346.645686 -396.941739) (xy 346.612241 -396.907885) (xy 346.584458 -396.869248) (xy 346.56301 -396.826766)
			(xy 346.548418 -396.781469) (xy 346.541035 -396.734457) (xy 346.540582 -396.710662) (xy 346.541114 -396.685267)
			(xy 346.549522 -396.635179) (xy 346.566101 -396.587172) (xy 346.590394 -396.542569) (xy 346.621731 -396.502599)
			(xy 346.64015 -396.48511) (xy 346.648532 -396.47749) (xy 346.657168 -396.457424) (xy 346.654374 -396.35811)
			(xy 346.644976 -396.338552) (xy 346.636086 -396.33144) (xy 346.617556 -396.315604) (xy 346.584833 -396.279481)
			(xy 346.557761 -396.23895) (xy 346.536925 -396.194887) (xy 346.522776 -396.148245) (xy 346.51562 -396.100032)
			(xy 346.515182 -396.075662) (xy 346.515591 -396.051544) (xy 346.522598 -396.00382) (xy 346.53646 -395.957619)
			(xy 346.556882 -395.91392) (xy 346.569792 -395.893544) (xy 346.575634 -395.884654) (xy 346.57919 -395.864588)
			(xy 346.558108 -395.772386) (xy 346.545916 -395.755622) (xy 346.537026 -395.750288) (xy 346.516227 -395.737431)
			(xy 346.478323 -395.70654) (xy 346.445382 -395.670404) (xy 346.418121 -395.629811) (xy 346.397136 -395.585647)
			(xy 346.382883 -395.538873) (xy 346.375673 -395.49051) (xy 346.375228 -395.466062) (xy 346.375766 -395.438777)
			(xy 346.384718 -395.384946) (xy 346.402388 -395.333316) (xy 346.428298 -395.285289) (xy 346.461743 -395.24217)
			(xy 346.4814 -395.223238) (xy 346.488787 -395.215704) (xy 346.49732 -395.196433) (xy 346.49791 -395.1859)
			(xy 346.49791 -395.111224) (xy 346.497378 -395.100675) (xy 346.488845 -395.08138) (xy 346.4814 -395.073886)
			(xy 346.461778 -395.054922) (xy 346.42834 -395.011806) (xy 346.402432 -394.963786) (xy 346.384756 -394.912165)
			(xy 346.375791 -394.858343) (xy 346.375228 -394.831062) (xy 346.375482 -394.81887) (xy 346.375736 -394.809218)
			(xy 346.36964 -394.791184) (xy 346.310966 -394.723874) (xy 346.294202 -394.715238) (xy 346.28455 -394.714222)
			(xy 346.257642 -394.710859) (xy 346.205356 -394.696493) (xy 346.156113 -394.673793) (xy 346.11123 -394.643367)
			(xy 346.071911 -394.606028) (xy 346.039206 -394.562777) (xy 346.013993 -394.514772) (xy 345.996946 -394.463298)
			(xy 345.992196 -394.4366) (xy 345.990672 -394.427202) (xy 345.717876 -393.95527) (xy 345.71051 -393.949428)
			(xy 345.691765 -393.933589) (xy 345.658645 -393.89738) (xy 345.631231 -393.856679) (xy 345.610124 -393.812379)
			(xy 345.595787 -393.765448) (xy 345.588533 -393.716916) (xy 345.588082 -393.69238) (xy 345.071284 -393.69238)
			(xy 345.320112 -394.12291) (xy 345.327224 -394.128752) (xy 345.345947 -394.144543) (xy 345.379001 -394.180682)
			(xy 345.406359 -394.221306) (xy 345.427419 -394.265523) (xy 345.441722 -394.312364) (xy 345.448953 -394.360804)
			(xy 345.449398 -394.385292) (xy 345.449144 -394.397484) (xy 345.44889 -394.407136) (xy 345.454986 -394.42517)
			(xy 345.51366 -394.49248) (xy 345.530424 -394.501116) (xy 345.54033 -394.502132) (xy 345.567095 -394.505467)
			(xy 345.619119 -394.519694) (xy 345.668144 -394.542173) (xy 345.712873 -394.572308) (xy 345.75212 -394.609302)
			(xy 345.784845 -394.652173) (xy 345.810181 -394.699785) (xy 345.827456 -394.750877) (xy 345.836213 -394.804095)
			(xy 345.836748 -394.831062) (xy 345.836202 -394.858346) (xy 345.827248 -394.912176) (xy 345.809578 -394.963804)
			(xy 345.783671 -395.011831) (xy 345.75023 -395.054953) (xy 345.730576 -395.073886) (xy 345.72319 -395.081421)
			(xy 345.714654 -395.10069) (xy 345.714066 -395.111224) (xy 345.714066 -395.1859) (xy 345.714592 -395.19645)
			(xy 345.72313 -395.215744) (xy 345.730576 -395.223238) (xy 345.750224 -395.242176) (xy 345.783655 -395.285301)
			(xy 345.809557 -395.333328) (xy 345.827227 -395.384954) (xy 345.836187 -395.438779) (xy 345.836748 -395.466062)
			(xy 345.836298 -395.490178) (xy 345.829302 -395.5379) (xy 345.815452 -395.584101) (xy 345.795043 -395.627802)
			(xy 345.782138 -395.64818) (xy 345.776296 -395.65707) (xy 345.77274 -395.677136) (xy 345.793822 -395.769338)
			(xy 345.806014 -395.786102) (xy 345.814904 -395.791436) (xy 345.835698 -395.804302) (xy 345.873605 -395.835188)
			(xy 345.906549 -395.871321) (xy 345.933812 -395.911913) (xy 345.954798 -395.956077) (xy 345.969051 -396.002851)
			(xy 345.976259 -396.051214) (xy 345.976702 -396.075662) (xy 345.97628 -396.100035) (xy 345.969135 -396.148255)
			(xy 345.954992 -396.194904) (xy 345.934159 -396.238974) (xy 345.907086 -396.279511) (xy 345.874359 -396.315638)
			(xy 345.855798 -396.33144) (xy 345.846908 -396.338552) (xy 345.83751 -396.35811) (xy 345.834716 -396.457424)
			(xy 345.843352 -396.47749) (xy 345.851734 -396.48511) (xy 345.870179 -396.502576) (xy 345.901527 -396.542545)
			(xy 345.925825 -396.587153) (xy 345.942402 -396.635167) (xy 345.950802 -396.685264) (xy 345.951302 -396.710662)
			(xy 345.951198 -396.721943) (xy 345.949547 -396.744445) (xy 345.948 -396.75562) (xy 345.94673 -396.76451)
			(xy 345.950286 -396.782036) (xy 345.99372 -396.852902) (xy 346.007436 -396.864078) (xy 346.016072 -396.866872)
			(xy 346.03832 -396.8748) (xy 346.080241 -396.896553) (xy 346.118314 -396.924499) (xy 346.151631 -396.957973)
			(xy 346.179399 -396.996176) (xy 346.19057 -397.016986) (xy 346.191078 -397.018002) (xy 346.583508 -397.696944)
			(xy 346.596241 -397.72031) (xy 346.614356 -397.770337) (xy 346.623566 -397.822741) (xy 346.624148 -397.849344)
			(xy 346.623678 -397.873334) (xy 346.616167 -397.920724) (xy 346.601336 -397.966355) (xy 346.57955 -398.009105)
			(xy 346.551346 -398.047922) (xy 346.517418 -398.081849) (xy 346.478602 -398.110052) (xy 346.435851 -398.131837)
			(xy 346.39022 -398.146668) (xy 346.34283 -398.154178) (xy 346.31884 -398.154652) (xy 346.295308 -398.154217)
			(xy 346.248799 -398.147007) (xy 346.203951 -398.132738) (xy 346.161827 -398.111747) (xy 346.123429 -398.084534)
			(xy 346.089667 -398.051744) (xy 346.061345 -398.014156) (xy 346.049854 -397.993616) (xy 346.0496 -397.993108)
			(xy 346.049092 -397.992346) (xy 345.651328 -397.304006) (xy 345.639415 -397.281337) (xy 345.622476 -397.233012)
			(xy 345.613816 -397.182542) (xy 345.613228 -397.15694) (xy 345.613228 -397.156432) (xy 345.613385 -397.145083)
			(xy 345.615162 -397.122453) (xy 345.616784 -397.11122) (xy 345.618054 -397.10233) (xy 345.614498 -397.085058)
			(xy 345.571064 -397.013938) (xy 345.557094 -397.003016) (xy 345.548712 -396.999968) (xy 345.526303 -396.991953)
			(xy 345.484086 -396.96999) (xy 345.44579 -396.941738) (xy 345.412345 -396.907884) (xy 345.384562 -396.869247)
			(xy 345.363114 -396.826766) (xy 345.348522 -396.781469) (xy 345.341139 -396.734456) (xy 345.340686 -396.710662)
			(xy 345.341216 -396.685267) (xy 345.349625 -396.635179) (xy 345.366204 -396.587171) (xy 345.390497 -396.542569)
			(xy 345.421835 -396.502599) (xy 345.440254 -396.48511) (xy 345.448636 -396.47749) (xy 345.457272 -396.457424)
			(xy 345.454478 -396.35811) (xy 345.44508 -396.338552) (xy 345.43619 -396.33144) (xy 345.41766 -396.315603)
			(xy 345.384937 -396.27948) (xy 345.357865 -396.238949) (xy 345.337029 -396.194887) (xy 345.32288 -396.148245)
			(xy 345.315724 -396.100032) (xy 345.315286 -396.075662) (xy 345.315694 -396.051544) (xy 345.322702 -396.00382)
			(xy 345.336564 -395.957619) (xy 345.356986 -395.91392) (xy 345.369896 -395.893544) (xy 345.375738 -395.884654)
			(xy 345.379294 -395.864588) (xy 345.358212 -395.772386) (xy 345.34602 -395.755622) (xy 345.33713 -395.750288)
			(xy 345.316332 -395.737429) (xy 345.278428 -395.706539) (xy 345.245486 -395.670403) (xy 345.218226 -395.629811)
			(xy 345.19724 -395.585646) (xy 345.182987 -395.538873) (xy 345.175777 -395.49051) (xy 345.175332 -395.466062)
			(xy 345.175869 -395.438777) (xy 345.18482 -395.384946) (xy 345.202491 -395.333316) (xy 345.228402 -395.285289)
			(xy 345.261847 -395.24217) (xy 345.281504 -395.223238) (xy 345.288891 -395.215705) (xy 345.297424 -395.196433)
			(xy 345.298014 -395.1859) (xy 345.298014 -395.111224) (xy 345.297481 -395.100675) (xy 345.288948 -395.08138)
			(xy 345.281504 -395.073886) (xy 345.261864 -395.05494) (xy 345.228433 -395.011816) (xy 345.20253 -394.963792)
			(xy 345.184858 -394.912168) (xy 345.175895 -394.858344) (xy 345.175332 -394.831062) (xy 345.175586 -394.81887)
			(xy 345.17584 -394.809218) (xy 345.169744 -394.791184) (xy 345.11107 -394.723874) (xy 345.094306 -394.715238)
			(xy 345.0844 -394.714222) (xy 345.057451 -394.710827) (xy 345.005068 -394.696484) (xy 344.955735 -394.67377)
			(xy 344.910779 -394.643297) (xy 344.87141 -394.605884) (xy 344.838687 -394.562538) (xy 344.813491 -394.514426)
			(xy 344.796499 -394.462842) (xy 344.791792 -394.436092) (xy 344.790522 -394.426694) (xy 344.51798 -393.95527)
			(xy 344.510614 -393.949428) (xy 344.49187 -393.933588) (xy 344.45875 -393.897379) (xy 344.431336 -393.856679)
			(xy 344.410229 -393.812379) (xy 344.395891 -393.765448) (xy 344.388637 -393.716916) (xy 344.388186 -393.69238)
			(xy 343.871138 -393.69238) (xy 344.119708 -394.122402) (xy 344.127074 -394.128244) (xy 344.145871 -394.144024)
			(xy 344.178984 -394.180247) (xy 344.206389 -394.220961) (xy 344.227486 -394.265273) (xy 344.241813 -394.312213)
			(xy 344.249057 -394.360753) (xy 344.249502 -394.385292) (xy 344.249248 -394.397484) (xy 344.248994 -394.407136)
			(xy 344.25509 -394.42517) (xy 344.313764 -394.49248) (xy 344.330528 -394.501116) (xy 344.340434 -394.502132)
			(xy 344.3672 -394.505464) (xy 344.419223 -394.519691) (xy 344.468249 -394.542171) (xy 344.512978 -394.572307)
			(xy 344.552225 -394.609301) (xy 344.584949 -394.652172) (xy 344.610285 -394.699785) (xy 344.62756 -394.750877)
			(xy 344.636317 -394.804095) (xy 344.636852 -394.831062) (xy 344.636304 -394.858346) (xy 344.627351 -394.912176)
			(xy 344.609681 -394.963804) (xy 344.583774 -395.011831) (xy 344.550334 -395.054953) (xy 344.53068 -395.073886)
			(xy 344.52328 -395.081408) (xy 344.514755 -395.100688) (xy 344.51417 -395.111224) (xy 344.51417 -395.1859)
			(xy 344.514694 -395.19645) (xy 344.523234 -395.215745) (xy 344.53068 -395.223238) (xy 344.550328 -395.242175)
			(xy 344.583759 -395.285301) (xy 344.609661 -395.333328) (xy 344.627331 -395.384953) (xy 344.636291 -395.438779)
			(xy 344.636852 -395.466062) (xy 344.636402 -395.490178) (xy 344.629406 -395.5379) (xy 344.615556 -395.584101)
			(xy 344.595146 -395.627802) (xy 344.582242 -395.64818) (xy 344.5764 -395.65707) (xy 344.572844 -395.677136)
			(xy 344.593926 -395.769338) (xy 344.606118 -395.786102) (xy 344.615008 -395.791436) (xy 344.635803 -395.8043)
			(xy 344.67371 -395.835187) (xy 344.706654 -395.871321) (xy 344.733916 -395.911912) (xy 344.754903 -395.956077)
			(xy 344.769155 -396.002851) (xy 344.776363 -396.051214) (xy 344.776806 -396.075662) (xy 344.776383 -396.100035)
			(xy 344.769237 -396.148254) (xy 344.755095 -396.194904) (xy 344.734262 -396.238974) (xy 344.70719 -396.279511)
			(xy 344.674463 -396.315638) (xy 344.655902 -396.33144) (xy 344.647012 -396.338552) (xy 344.637614 -396.35811)
			(xy 344.63482 -396.457424) (xy 344.643456 -396.47749) (xy 344.651838 -396.48511) (xy 344.670284 -396.502575)
			(xy 344.701631 -396.542545) (xy 344.725929 -396.587153) (xy 344.742507 -396.635167) (xy 344.750906 -396.685264)
			(xy 344.751406 -396.710662) (xy 344.751302 -396.721943) (xy 344.749651 -396.744445) (xy 344.748104 -396.75562)
			(xy 344.746834 -396.764764) (xy 344.750136 -396.782036) (xy 344.793824 -396.853156) (xy 344.80754 -396.864078)
			(xy 344.816176 -396.866872) (xy 344.84434 -396.87707) (xy 344.896287 -396.906881) (xy 344.9193 -396.926054)
			(xy 344.940785 -396.945635) (xy 344.976598 -396.991414) (xy 344.99042 -397.016986) (xy 344.991182 -397.018256)
			(xy 345.383358 -397.696944) (xy 345.396166 -397.720285) (xy 345.414392 -397.770304) (xy 345.423659 -397.822726)
			(xy 345.424252 -397.849344) (xy 345.423802 -397.873349) (xy 345.416282 -397.920766) (xy 345.401434 -397.966422)
			(xy 345.379625 -398.009193) (xy 345.351392 -398.048023) (xy 345.31743 -398.081957) (xy 345.278576 -398.110158)
			(xy 345.235787 -398.131932) (xy 345.190119 -398.146741) (xy 345.142695 -398.154222) (xy 345.11869 -398.154652)
			(xy 345.095159 -398.154177) (xy 345.048653 -398.146975) (xy 345.003805 -398.132712) (xy 344.961682 -398.111728)
			(xy 344.923282 -398.084521) (xy 344.88952 -398.051737) (xy 344.861195 -398.014154) (xy 344.849704 -397.993616)
			(xy 344.84945 -397.993108) (xy 344.848942 -397.992346) (xy 344.451432 -397.303752) (xy 344.440861 -397.283824)
			(xy 344.425057 -397.241575) (xy 344.415649 -397.197459) (xy 344.41384 -397.174974) (xy 344.413332 -397.163798)
			(xy 344.413332 -397.156432) (xy 344.413423 -397.145087) (xy 344.415078 -397.122458) (xy 344.416634 -397.11122)
			(xy 344.417904 -397.10233) (xy 344.414348 -397.085058) (xy 344.370914 -397.013938) (xy 344.357198 -397.002762)
			(xy 344.348562 -396.999968) (xy 344.326158 -396.991977) (xy 344.283987 -396.969972) (xy 344.24574 -396.941694)
			(xy 344.21234 -396.907827) (xy 344.184597 -396.869189) (xy 344.163182 -396.826717) (xy 344.148612 -396.781437)
			(xy 344.141241 -396.734445) (xy 344.14079 -396.710662) (xy 344.141319 -396.685267) (xy 344.149728 -396.635179)
			(xy 344.166307 -396.587171) (xy 344.190601 -396.542568) (xy 344.221938 -396.502599) (xy 344.240358 -396.48511)
			(xy 344.24874 -396.47749) (xy 344.257376 -396.457424) (xy 344.254582 -396.35811) (xy 344.245184 -396.338552)
			(xy 344.236294 -396.33144) (xy 344.217765 -396.315602) (xy 344.185042 -396.27948) (xy 344.15797 -396.238949)
			(xy 344.137134 -396.194886) (xy 344.122984 -396.148245) (xy 344.115828 -396.100032) (xy 344.11539 -396.075662)
			(xy 344.115797 -396.051544) (xy 344.122805 -396.00382) (xy 344.136667 -395.957619) (xy 344.157089 -395.91392)
			(xy 344.17 -395.893544) (xy 344.175842 -395.884654) (xy 344.179398 -395.864588) (xy 344.158316 -395.772386)
			(xy 344.146124 -395.755622) (xy 344.137234 -395.750288) (xy 344.116436 -395.737428) (xy 344.078533 -395.706538)
			(xy 344.045591 -395.670403) (xy 344.01833 -395.62981) (xy 343.997344 -395.585646) (xy 343.983091 -395.538873)
			(xy 343.975881 -395.49051) (xy 343.975436 -395.466062) (xy 343.976003 -395.438778) (xy 343.984952 -395.38495)
			(xy 344.002618 -395.333322) (xy 344.02852 -395.285295) (xy 344.061956 -395.242172) (xy 344.081608 -395.223238)
			(xy 344.088996 -395.215705) (xy 344.097528 -395.196434) (xy 344.098118 -395.1859) (xy 344.098118 -395.111224)
			(xy 344.097584 -395.100675) (xy 344.089052 -395.08138) (xy 344.081608 -395.073886) (xy 344.061969 -395.05494)
			(xy 344.028537 -395.011816) (xy 344.002634 -394.963792) (xy 343.984962 -394.912168) (xy 343.975999 -394.858344)
			(xy 343.975436 -394.831062) (xy 343.97569 -394.81887) (xy 343.975944 -394.809218) (xy 343.969848 -394.791184)
			(xy 343.911174 -394.723874) (xy 343.89441 -394.715238) (xy 343.884504 -394.714222) (xy 343.857602 -394.710816)
			(xy 343.805317 -394.696458) (xy 343.756073 -394.673766) (xy 343.71119 -394.643346) (xy 343.671869 -394.606014)
			(xy 343.639163 -394.562768) (xy 343.613949 -394.514767) (xy 343.5969 -394.463296) (xy 343.59215 -394.4366)
			(xy 343.590626 -394.427202) (xy 343.31783 -393.95527) (xy 343.310464 -393.949428) (xy 343.29171 -393.9336)
			(xy 343.258592 -393.897388) (xy 343.23118 -393.856684) (xy 343.210076 -393.812382) (xy 343.19574 -393.76545)
			(xy 343.188486 -393.716916) (xy 343.188036 -393.69238) (xy 342.671242 -393.69238) (xy 342.919812 -394.122402)
			(xy 342.927178 -394.128244) (xy 342.945955 -394.144047) (xy 342.979073 -394.180263) (xy 343.006484 -394.220971)
			(xy 343.027585 -394.265279) (xy 343.041915 -394.312216) (xy 343.04916 -394.360754) (xy 343.049606 -394.385292)
			(xy 343.049352 -394.397484) (xy 343.049098 -394.407136) (xy 343.055194 -394.42517) (xy 343.113868 -394.49248)
			(xy 343.130632 -394.501116) (xy 343.140284 -394.502132) (xy 343.167044 -394.505504) (xy 343.219067 -394.519724)
			(xy 343.268093 -394.542197) (xy 343.312822 -394.572327) (xy 343.35207 -394.609316) (xy 343.384796 -394.652183)
			(xy 343.410133 -394.699792) (xy 343.427409 -394.750881) (xy 343.436166 -394.804097) (xy 343.436702 -394.831062)
			(xy 343.43617 -394.858347) (xy 343.427215 -394.912178) (xy 343.409543 -394.963807) (xy 343.383632 -395.011834)
			(xy 343.350186 -395.054954) (xy 343.33053 -395.073886) (xy 343.323137 -395.081415) (xy 343.314607 -395.100689)
			(xy 343.31402 -395.111224) (xy 343.31402 -395.1859) (xy 343.31453 -395.196452) (xy 343.323078 -395.215748)
			(xy 343.33053 -395.223238) (xy 343.350169 -395.242185) (xy 343.383603 -395.285307) (xy 343.409508 -395.333331)
			(xy 343.42718 -395.384955) (xy 343.436141 -395.438779) (xy 343.436702 -395.466062) (xy 343.43626 -395.490179)
			(xy 343.429263 -395.537901) (xy 343.415411 -395.584102) (xy 343.394998 -395.627803) (xy 343.382092 -395.64818)
			(xy 343.37625 -395.65707) (xy 343.372694 -395.677136) (xy 343.393776 -395.769338) (xy 343.405968 -395.786102)
			(xy 343.414858 -395.791436) (xy 343.435664 -395.804282) (xy 343.473569 -395.835174) (xy 343.50651 -395.871312)
			(xy 343.53377 -395.911906) (xy 343.554755 -395.956073) (xy 343.569006 -396.002849) (xy 343.576213 -396.051213)
			(xy 343.576656 -396.075662) (xy 343.576251 -396.100036) (xy 343.569104 -396.148257) (xy 343.55496 -396.194907)
			(xy 343.534123 -396.238978) (xy 343.507047 -396.279514) (xy 343.474315 -396.315639) (xy 343.455752 -396.33144)
			(xy 343.446862 -396.338552) (xy 343.437464 -396.35811) (xy 343.43467 -396.457424) (xy 343.443306 -396.47749)
			(xy 343.451688 -396.48511) (xy 343.470143 -396.502566) (xy 343.501488 -396.542539) (xy 343.525783 -396.587149)
			(xy 343.542358 -396.635166) (xy 343.550757 -396.685263) (xy 343.551256 -396.710662) (xy 343.551153 -396.721943)
			(xy 343.549501 -396.744445) (xy 343.547954 -396.75562) (xy 343.546684 -396.76451) (xy 343.55024 -396.782036)
			(xy 343.593674 -396.852902) (xy 343.60739 -396.864078) (xy 343.616026 -396.866872) (xy 343.638266 -396.874821)
			(xy 343.680188 -396.896568) (xy 343.718263 -396.924509) (xy 343.751582 -396.957978) (xy 343.779352 -396.996178)
			(xy 343.790524 -397.016986) (xy 343.791032 -397.018002) (xy 344.183462 -397.696944) (xy 344.19627 -397.720285)
			(xy 344.214496 -397.770304) (xy 344.223763 -397.822726) (xy 344.224356 -397.849344) (xy 344.223902 -397.873349)
			(xy 344.216382 -397.920765) (xy 344.201535 -397.966421) (xy 344.179726 -398.009191) (xy 344.151493 -398.048022)
			(xy 344.117531 -398.081956) (xy 344.078678 -398.110157) (xy 344.03589 -398.131931) (xy 343.990222 -398.14674)
			(xy 343.942799 -398.154221) (xy 343.918794 -398.154652) (xy 343.895263 -398.154173) (xy 343.848757 -398.146972)
			(xy 343.803909 -398.13271) (xy 343.761786 -398.111727) (xy 343.723387 -398.08452) (xy 343.689624 -398.051736)
			(xy 343.661299 -398.014154) (xy 343.649808 -397.993616) (xy 343.649554 -397.993108) (xy 343.649046 -397.992346)
			(xy 343.251282 -397.304006) (xy 343.239408 -397.281328) (xy 343.222556 -397.232996) (xy 343.213982 -397.182533)
			(xy 343.213436 -397.15694) (xy 343.213436 -397.156432) (xy 343.213527 -397.145087) (xy 343.215182 -397.122458)
			(xy 343.216738 -397.11122) (xy 343.218008 -397.10233) (xy 343.214452 -397.085058) (xy 343.171018 -397.013938)
			(xy 343.157048 -397.003016) (xy 343.148666 -396.999968) (xy 343.126269 -396.991922) (xy 343.08405 -396.969966)
			(xy 343.045752 -396.94172) (xy 343.012305 -396.907871) (xy 342.98452 -396.869238) (xy 342.96307 -396.82676)
			(xy 342.948477 -396.781466) (xy 342.941093 -396.734455) (xy 342.94064 -396.710662) (xy 342.941153 -396.685266)
			(xy 342.949563 -396.635176) (xy 342.966146 -396.587168) (xy 342.990443 -396.542565) (xy 343.021786 -396.502598)
			(xy 343.040208 -396.48511) (xy 343.04859 -396.47749) (xy 343.057226 -396.457424) (xy 343.054432 -396.35811)
			(xy 343.045034 -396.338552) (xy 343.036144 -396.33144) (xy 343.017605 -396.315614) (xy 342.984885 -396.279488)
			(xy 342.957815 -396.238954) (xy 342.936981 -396.194889) (xy 342.922833 -396.148246) (xy 342.915678 -396.100033)
			(xy 342.91524 -396.075662) (xy 342.915655 -396.051545) (xy 342.922662 -396.003821) (xy 342.936522 -395.95762)
			(xy 342.956941 -395.913921) (xy 342.96985 -395.893544) (xy 342.975692 -395.884654) (xy 342.979248 -395.864588)
			(xy 342.958166 -395.772386) (xy 342.945974 -395.755622) (xy 342.937084 -395.750288) (xy 342.916298 -395.73741)
			(xy 342.878392 -395.706525) (xy 342.845447 -395.670394) (xy 342.818184 -395.629804) (xy 342.797196 -395.585642)
			(xy 342.782942 -395.538871) (xy 342.775731 -395.49051) (xy 342.775286 -395.466062) (xy 342.775837 -395.438778)
			(xy 342.784788 -395.384948) (xy 342.802456 -395.333319) (xy 342.828362 -395.285292) (xy 342.861804 -395.242171)
			(xy 342.881458 -395.223238) (xy 342.888839 -395.215698) (xy 342.897376 -395.196432) (xy 342.897968 -395.1859)
			(xy 342.897968 -395.111224) (xy 342.897449 -395.100673) (xy 342.888908 -395.081377) (xy 342.881458 -395.073886)
			(xy 342.861828 -395.05493) (xy 342.828393 -395.01181) (xy 342.802487 -394.963788) (xy 342.784813 -394.912166)
			(xy 342.775849 -394.858344) (xy 342.775286 -394.831062) (xy 342.77554 -394.81887) (xy 342.775794 -394.809218)
			(xy 342.769698 -394.791184) (xy 342.711024 -394.723874) (xy 342.69426 -394.715238) (xy 342.684608 -394.714222)
			(xy 342.657707 -394.710812) (xy 342.605421 -394.696456) (xy 342.556178 -394.673764) (xy 342.511295 -394.643345)
			(xy 342.471973 -394.606013) (xy 342.439268 -394.562767) (xy 342.414053 -394.514767) (xy 342.397004 -394.463296)
			(xy 342.392254 -394.4366) (xy 342.39073 -394.427202) (xy 342.117934 -393.95527) (xy 342.110568 -393.949428)
			(xy 342.091815 -393.933599) (xy 342.058696 -393.897387) (xy 342.031285 -393.856684) (xy 342.01018 -393.812382)
			(xy 341.995844 -393.76545) (xy 341.98859 -393.716916) (xy 341.98814 -393.69238) (xy 341.471092 -393.69238)
			(xy 341.719662 -394.122402) (xy 341.727028 -394.128244) (xy 341.745815 -394.144035) (xy 341.778931 -394.180255)
			(xy 341.806339 -394.220966) (xy 341.827438 -394.265276) (xy 341.841767 -394.312214) (xy 341.849011 -394.360754)
			(xy 341.849456 -394.385292) (xy 341.849202 -394.397484) (xy 341.848948 -394.407136) (xy 341.855044 -394.42517)
			(xy 341.913718 -394.49248) (xy 341.930482 -394.501116) (xy 341.940388 -394.502132) (xy 341.967149 -394.505501)
			(xy 342.019171 -394.519722) (xy 342.068197 -394.542195) (xy 342.112927 -394.572326) (xy 342.152175 -394.609315)
			(xy 342.184901 -394.652182) (xy 342.210237 -394.699791) (xy 342.227513 -394.750881) (xy 342.23627 -394.804096)
			(xy 342.236806 -394.831062) (xy 342.23638 -394.855264) (xy 342.229306 -394.903149) (xy 342.21532 -394.949488)
			(xy 342.194721 -394.99329) (xy 342.181688 -395.013688) (xy 342.176901 -395.021645) (xy 342.172866 -395.039756)
			(xy 342.173814 -395.048994) (xy 342.178132 -395.079982) (xy 342.179804 -395.089281) (xy 342.189091 -395.105722)
			(xy 342.196166 -395.111986) (xy 342.218255 -395.130667) (xy 342.258026 -395.172679) (xy 342.292188 -395.219367)
			(xy 342.320196 -395.269987) (xy 342.341603 -395.323732) (xy 342.356068 -395.379746) (xy 342.363361 -395.437136)
			(xy 342.363806 -395.466062) (xy 342.363219 -395.499384) (xy 342.353556 -395.565322) (xy 342.334429 -395.629161)
			(xy 342.32088 -395.65961) (xy 342.316631 -395.670075) (xy 342.316745 -395.692634) (xy 342.32648 -395.712985)
			(xy 342.33485 -395.72057) (xy 342.35707 -395.739275) (xy 342.397137 -395.781324) (xy 342.431561 -395.828104)
			(xy 342.45979 -395.878864) (xy 342.48137 -395.932787) (xy 342.495954 -395.989008) (xy 342.503307 -396.046621)
			(xy 342.50376 -396.075662) (xy 342.50328 -396.104667) (xy 342.49597 -396.162214) (xy 342.481448 -396.218376)
			(xy 342.459948 -396.272254) (xy 342.431814 -396.322985) (xy 342.397497 -396.369755) (xy 342.357547 -396.411815)
			(xy 342.335358 -396.4305) (xy 342.328246 -396.436088) (xy 342.319102 -396.451328) (xy 342.303862 -396.534132)
			(xy 342.306656 -396.551404) (xy 342.311228 -396.559532) (xy 342.323802 -396.582719) (xy 342.341677 -396.63234)
			(xy 342.350778 -396.684291) (xy 342.35136 -396.710662) (xy 342.351257 -396.721943) (xy 342.349605 -396.744445)
			(xy 342.348058 -396.75562) (xy 342.346788 -396.76451) (xy 342.350344 -396.782036) (xy 342.393778 -396.852902)
			(xy 342.407494 -396.864078) (xy 342.41613 -396.866872) (xy 342.438371 -396.874819) (xy 342.480293 -396.896567)
			(xy 342.518367 -396.924508) (xy 342.551686 -396.957978) (xy 342.579456 -396.996178) (xy 342.590628 -397.016986)
			(xy 342.591136 -397.018002) (xy 342.983566 -397.696944) (xy 342.996375 -397.720285) (xy 343.0146 -397.770303)
			(xy 343.023867 -397.822726) (xy 343.02446 -397.849344) (xy 343.024101 -397.873353) (xy 343.016579 -397.92078)
			(xy 343.001726 -397.966444) (xy 342.979909 -398.00922) (xy 342.951665 -398.048055) (xy 342.917691 -398.08199)
			(xy 342.878825 -398.11019) (xy 342.836023 -398.131958) (xy 342.790342 -398.146759) (xy 342.742908 -398.154228)
			(xy 342.718898 -398.154652) (xy 342.695367 -398.15417) (xy 342.648861 -398.146969) (xy 342.604014 -398.132708)
			(xy 342.56189 -398.111725) (xy 342.523491 -398.084519) (xy 342.489728 -398.051736) (xy 342.461404 -398.014154)
			(xy 342.449912 -397.993616) (xy 342.449658 -397.993108) (xy 342.44915 -397.992346) (xy 342.051386 -397.304006)
			(xy 342.039512 -397.281328) (xy 342.02266 -397.232996) (xy 342.014086 -397.182533) (xy 342.01354 -397.15694)
			(xy 342.01354 -397.156432) (xy 342.013631 -397.145087) (xy 342.015286 -397.122458) (xy 342.016842 -397.11122)
			(xy 342.018112 -397.10233) (xy 342.014556 -397.085058) (xy 341.971122 -397.013938) (xy 341.957152 -397.003016)
			(xy 341.94877 -396.999968) (xy 341.926374 -396.991919) (xy 341.884155 -396.969964) (xy 341.845857 -396.941719)
			(xy 341.81241 -396.90787) (xy 341.784624 -396.869238) (xy 341.763174 -396.826759) (xy 341.748581 -396.781466)
			(xy 341.741197 -396.734455) (xy 341.740744 -396.710662) (xy 341.741304 -396.684289) (xy 341.750388 -396.63233)
			(xy 341.76828 -396.58271) (xy 341.780876 -396.559532) (xy 341.785448 -396.551404) (xy 341.788242 -396.534132)
			(xy 341.773002 -396.451328) (xy 341.763858 -396.436088) (xy 341.756746 -396.4305) (xy 341.734564 -396.411807)
			(xy 341.69462 -396.369742) (xy 341.660305 -396.322971) (xy 341.632168 -396.272243) (xy 341.61066 -396.218369)
			(xy 341.596125 -396.16221) (xy 341.588794 -396.104666) (xy 341.588344 -396.075662) (xy 341.588944 -396.042341)
			(xy 341.598602 -395.976403) (xy 341.617724 -395.912563) (xy 341.63127 -395.882114) (xy 341.635512 -395.871646)
			(xy 341.635408 -395.849087) (xy 341.625673 -395.828736) (xy 341.6173 -395.821154) (xy 341.595033 -395.802503)
			(xy 341.554971 -395.760444) (xy 341.520552 -395.713653) (xy 341.49233 -395.662884) (xy 341.470758 -395.608953)
			(xy 341.456182 -395.552725) (xy 341.448838 -395.495105) (xy 341.44839 -395.466062) (xy 341.448828 -395.437135)
			(xy 341.456112 -395.379742) (xy 341.470572 -395.323724) (xy 341.491978 -395.269976) (xy 341.519987 -395.219355)
			(xy 341.554154 -395.172667) (xy 341.593933 -395.130659) (xy 341.61603 -395.111986) (xy 341.622997 -395.105634)
			(xy 341.632258 -395.089234) (xy 341.634064 -395.079982) (xy 341.638382 -395.048994) (xy 341.639281 -395.039757)
			(xy 341.635259 -395.021658) (xy 341.630508 -395.013688) (xy 341.617521 -394.993265) (xy 341.59694 -394.949463)
			(xy 341.582953 -394.903133) (xy 341.575857 -394.85526) (xy 341.57539 -394.831062) (xy 341.575644 -394.81887)
			(xy 341.575898 -394.809218) (xy 341.569802 -394.791184) (xy 341.511128 -394.723874) (xy 341.494364 -394.715238)
			(xy 341.484458 -394.714222) (xy 341.457551 -394.710852) (xy 341.405265 -394.696488) (xy 341.356022 -394.673789)
			(xy 341.311139 -394.643364) (xy 341.271819 -394.606026) (xy 341.239115 -394.562776) (xy 341.213901 -394.514771)
			(xy 341.196854 -394.463298) (xy 341.192104 -394.4366) (xy 341.19058 -394.427202) (xy 340.917784 -393.95527)
			(xy 340.910418 -393.949428) (xy 340.891675 -393.933587) (xy 340.858554 -393.897379) (xy 340.83114 -393.856679)
			(xy 340.810033 -393.812378) (xy 340.795695 -393.765448) (xy 340.788441 -393.716916) (xy 340.78799 -393.69238)
			(xy 340.271196 -393.69238) (xy 340.519766 -394.122402) (xy 340.527132 -394.128244) (xy 340.54592 -394.144034)
			(xy 340.579036 -394.180254) (xy 340.606443 -394.220965) (xy 340.627542 -394.265275) (xy 340.641871 -394.312214)
			(xy 340.649115 -394.360753) (xy 340.64956 -394.385292) (xy 340.649306 -394.397484) (xy 340.649052 -394.407136)
			(xy 340.655148 -394.42517) (xy 340.713822 -394.49248) (xy 340.730586 -394.501116) (xy 340.740238 -394.502132)
			(xy 340.767004 -394.50546) (xy 340.819028 -394.519689) (xy 340.868053 -394.542169) (xy 340.912782 -394.572305)
			(xy 340.952029 -394.609299) (xy 340.984754 -394.652171) (xy 341.010089 -394.699784) (xy 341.027364 -394.750877)
			(xy 341.036121 -394.804095) (xy 341.036656 -394.831062) (xy 341.036146 -394.857049) (xy 341.028016 -394.908384)
			(xy 341.011955 -394.957814) (xy 340.988359 -395.004124) (xy 340.957809 -395.046172) (xy 340.921058 -395.082923)
			(xy 340.87901 -395.113473) (xy 340.8327 -395.137069) (xy 340.78327 -395.15313) (xy 340.731935 -395.16126)
			(xy 340.679961 -395.16126) (xy 340.628626 -395.15313) (xy 340.579196 -395.137069) (xy 340.532886 -395.113473)
			(xy 340.490838 -395.082923) (xy 340.454087 -395.046172) (xy 340.423537 -395.004124) (xy 340.399941 -394.957814)
			(xy 340.38388 -394.908384) (xy 340.37575 -394.857049) (xy 340.37524 -394.831062) (xy 340.375494 -394.81887)
			(xy 340.375748 -394.809218) (xy 340.369652 -394.791184) (xy 340.310978 -394.723874) (xy 340.294214 -394.715238)
			(xy 340.284562 -394.714222) (xy 340.257655 -394.710849) (xy 340.20537 -394.696485) (xy 340.156126 -394.673787)
			(xy 340.111244 -394.643362) (xy 340.071924 -394.606025) (xy 340.039219 -394.562775) (xy 340.014005 -394.514771)
			(xy 339.996958 -394.463298) (xy 339.992208 -394.4366) (xy 339.990684 -394.427202) (xy 339.717888 -393.95527)
			(xy 339.710522 -393.949428) (xy 339.69178 -393.933586) (xy 339.658659 -393.897378) (xy 339.631244 -393.856678)
			(xy 339.610137 -393.812378) (xy 339.595799 -393.765448) (xy 339.588545 -393.716916) (xy 339.588094 -393.69238)
			(xy 339.071296 -393.69238) (xy 339.320124 -394.12291) (xy 339.327236 -394.128752) (xy 339.345961 -394.14454)
			(xy 339.379015 -394.18068) (xy 339.406372 -394.221305) (xy 339.427432 -394.265522) (xy 339.441734 -394.312364)
			(xy 339.448965 -394.360804) (xy 339.44941 -394.385292) (xy 339.449156 -394.397484) (xy 339.448902 -394.407136)
			(xy 339.454998 -394.42517) (xy 339.513672 -394.49248) (xy 339.530436 -394.501116) (xy 339.540342 -394.502132)
			(xy 339.567109 -394.505457) (xy 339.619132 -394.519686) (xy 339.668158 -394.542167) (xy 339.712887 -394.572304)
			(xy 339.752133 -394.609298) (xy 339.784858 -394.65217) (xy 339.810193 -394.699783) (xy 339.827468 -394.750876)
			(xy 339.836225 -394.804095) (xy 339.83676 -394.831062) (xy 339.83621 -394.858346) (xy 339.827257 -394.912175)
			(xy 339.809587 -394.963804) (xy 339.783681 -395.011831) (xy 339.750241 -395.054952) (xy 339.730588 -395.073886)
			(xy 339.723189 -395.081409) (xy 339.714663 -395.100688) (xy 339.714078 -395.111224) (xy 339.714078 -395.1859)
			(xy 339.7146 -395.19645) (xy 339.723141 -395.215745) (xy 339.730588 -395.223238) (xy 339.750238 -395.242174)
			(xy 339.783668 -395.2853) (xy 339.80957 -395.333327) (xy 339.827239 -395.384953) (xy 339.836199 -395.438779)
			(xy 339.83676 -395.466062) (xy 339.836308 -395.490178) (xy 339.829312 -395.5379) (xy 339.815463 -395.584101)
			(xy 339.795054 -395.627802) (xy 339.78215 -395.64818) (xy 339.776308 -395.65707) (xy 339.772752 -395.677136)
			(xy 339.793834 -395.769338) (xy 339.806026 -395.786102) (xy 339.814916 -395.791436) (xy 339.835713 -395.804298)
			(xy 339.873619 -395.835185) (xy 339.906563 -395.871319) (xy 339.933825 -395.911911) (xy 339.954811 -395.956076)
			(xy 339.969063 -396.00285) (xy 339.976271 -396.051213) (xy 339.976714 -396.075662) (xy 339.976288 -396.100035)
			(xy 339.969142 -396.148254) (xy 339.955001 -396.194903) (xy 339.934168 -396.238973) (xy 339.907096 -396.27951)
			(xy 339.874371 -396.315637) (xy 339.85581 -396.33144) (xy 339.84692 -396.338552) (xy 339.837522 -396.35811)
			(xy 339.834728 -396.457424) (xy 339.843364 -396.47749) (xy 339.851746 -396.48511) (xy 339.870193 -396.502574)
			(xy 339.901541 -396.542544) (xy 339.925838 -396.587152) (xy 339.942415 -396.635167) (xy 339.950815 -396.685264)
			(xy 339.951314 -396.710662) (xy 340.540594 -396.710662) (xy 340.541116 -396.685407) (xy 340.549429 -396.635585)
			(xy 340.56583 -396.587811) (xy 340.589871 -396.543388) (xy 340.620895 -396.503528) (xy 340.658057 -396.469318)
			(xy 340.700343 -396.441692) (xy 340.746599 -396.421402) (xy 340.795564 -396.409002) (xy 340.845902 -396.404831)
			(xy 340.89624 -396.409002) (xy 340.945205 -396.421402) (xy 340.991461 -396.441692) (xy 341.033747 -396.469318)
			(xy 341.070909 -396.503528) (xy 341.101933 -396.543388) (xy 341.125974 -396.587811) (xy 341.142375 -396.635585)
			(xy 341.150688 -396.685407) (xy 341.15121 -396.710662) (xy 341.151106 -396.721943) (xy 341.149455 -396.744445)
			(xy 341.147908 -396.75562) (xy 341.146638 -396.76451) (xy 341.150194 -396.782036) (xy 341.193628 -396.852902)
			(xy 341.207344 -396.864078) (xy 341.21598 -396.866872) (xy 341.23823 -396.874796) (xy 341.28015 -396.89655)
			(xy 341.318223 -396.924497) (xy 341.35154 -396.957972) (xy 341.379308 -396.996176) (xy 341.390478 -397.016986)
			(xy 341.390986 -397.018002) (xy 341.783416 -397.696944) (xy 341.79615 -397.720309) (xy 341.814265 -397.770337)
			(xy 341.823474 -397.822741) (xy 341.824056 -397.849344) (xy 341.823578 -397.873334) (xy 341.816067 -397.920723)
			(xy 341.801236 -397.966353) (xy 341.779452 -398.009103) (xy 341.751249 -398.047919) (xy 341.717322 -398.081846)
			(xy 341.678506 -398.11005) (xy 341.635757 -398.131835) (xy 341.590127 -398.146666) (xy 341.542738 -398.154178)
			(xy 341.518748 -398.154652) (xy 341.495216 -398.154211) (xy 341.448708 -398.147002) (xy 341.40386 -398.132734)
			(xy 341.361736 -398.111744) (xy 341.323337 -398.084532) (xy 341.289576 -398.051743) (xy 341.261253 -398.014156)
			(xy 341.249762 -397.993616) (xy 341.249508 -397.993108) (xy 341.249 -397.992346) (xy 340.851236 -397.304006)
			(xy 340.839323 -397.281336) (xy 340.822384 -397.233012) (xy 340.813724 -397.182542) (xy 340.813136 -397.15694)
			(xy 340.813136 -397.156432) (xy 340.813293 -397.145083) (xy 340.81507 -397.122453) (xy 340.816692 -397.11122)
			(xy 340.817962 -397.10233) (xy 340.814406 -397.085058) (xy 340.770972 -397.013938) (xy 340.757002 -397.003016)
			(xy 340.74862 -396.999968) (xy 340.726213 -396.991948) (xy 340.683995 -396.969986) (xy 340.645699 -396.941735)
			(xy 340.612254 -396.907882) (xy 340.584471 -396.869246) (xy 340.563022 -396.826765) (xy 340.54843 -396.781469)
			(xy 340.541047 -396.734456) (xy 340.540594 -396.710662) (xy 339.951314 -396.710662) (xy 339.95121 -396.721943)
			(xy 339.949559 -396.744445) (xy 339.948012 -396.75562) (xy 339.946742 -396.76451) (xy 339.950298 -396.782036)
			(xy 339.993732 -396.852902) (xy 340.007448 -396.864078) (xy 340.016084 -396.866872) (xy 340.038334 -396.874794)
			(xy 340.080255 -396.896548) (xy 340.118327 -396.924496) (xy 340.151645 -396.957971) (xy 340.179412 -396.996175)
			(xy 340.190582 -397.016986) (xy 340.19109 -397.018002) (xy 340.58352 -397.696944) (xy 340.596254 -397.720309)
			(xy 340.614369 -397.770337) (xy 340.623578 -397.822741) (xy 340.62416 -397.849344) (xy 340.623802 -397.873341)
			(xy 340.616287 -397.920742) (xy 340.60145 -397.966385) (xy 340.579655 -398.009144) (xy 340.551439 -398.047968)
			(xy 340.517498 -398.081899) (xy 340.478666 -398.110103) (xy 340.4359 -398.131885) (xy 340.390253 -398.146709)
			(xy 340.342849 -398.154209) (xy 340.318852 -398.154652) (xy 340.29532 -398.154207) (xy 340.248812 -398.147)
			(xy 340.203964 -398.132732) (xy 340.16184 -398.111743) (xy 340.123442 -398.084531) (xy 340.08968 -398.051742)
			(xy 340.061357 -398.014156) (xy 340.049866 -397.993616) (xy 340.049612 -397.993108) (xy 340.049104 -397.992346)
			(xy 339.65134 -397.304006) (xy 339.639428 -397.281336) (xy 339.622488 -397.233012) (xy 339.613828 -397.182542)
			(xy 339.61324 -397.15694) (xy 339.61324 -397.156432) (xy 339.613397 -397.145083) (xy 339.615174 -397.122453)
			(xy 339.616796 -397.11122) (xy 339.618066 -397.10233) (xy 339.61451 -397.085058) (xy 339.571076 -397.013938)
			(xy 339.557106 -397.003016) (xy 339.548724 -396.999968) (xy 339.526318 -396.991946) (xy 339.4841 -396.969984)
			(xy 339.445804 -396.941734) (xy 339.412359 -396.907881) (xy 339.384575 -396.869245) (xy 339.363127 -396.826764)
			(xy 339.348534 -396.781468) (xy 339.341151 -396.734456) (xy 339.340698 -396.710662) (xy 339.341224 -396.685267)
			(xy 339.349634 -396.635178) (xy 339.366214 -396.587171) (xy 339.390508 -396.542568) (xy 339.421846 -396.502599)
			(xy 339.440266 -396.48511) (xy 339.448648 -396.47749) (xy 339.457284 -396.457424) (xy 339.45449 -396.35811)
			(xy 339.445092 -396.338552) (xy 339.436202 -396.33144) (xy 339.417675 -396.315601) (xy 339.384951 -396.279479)
			(xy 339.357878 -396.238948) (xy 339.337042 -396.194886) (xy 339.322892 -396.148244) (xy 339.315736 -396.100032)
			(xy 339.315298 -396.075662) (xy 339.315704 -396.051544) (xy 339.322712 -396.00382) (xy 339.336574 -395.957619)
			(xy 339.356997 -395.91392) (xy 339.369908 -395.893544) (xy 339.37575 -395.884654) (xy 339.379306 -395.864588)
			(xy 339.358224 -395.772386) (xy 339.346032 -395.755622) (xy 339.337142 -395.750288) (xy 339.316346 -395.737425)
			(xy 339.278442 -395.706536) (xy 339.2455 -395.670401) (xy 339.218239 -395.629809) (xy 339.197252 -395.585645)
			(xy 339.182999 -395.538872) (xy 339.175789 -395.49051) (xy 339.175344 -395.466062) (xy 339.175909 -395.438778)
			(xy 339.184858 -395.38495) (xy 339.202524 -395.333322) (xy 339.228427 -395.285294) (xy 339.261864 -395.242172)
			(xy 339.281516 -395.223238) (xy 339.288905 -395.215706) (xy 339.297436 -395.196434) (xy 339.298026 -395.1859)
			(xy 339.298026 -395.111224) (xy 339.29749 -395.100675) (xy 339.288959 -395.08138) (xy 339.281516 -395.073886)
			(xy 339.261879 -395.054938) (xy 339.228446 -395.011815) (xy 339.202543 -394.963791) (xy 339.18487 -394.912168)
			(xy 339.175907 -394.858344) (xy 339.175344 -394.831062) (xy 339.175598 -394.81887) (xy 339.175852 -394.809218)
			(xy 339.169756 -394.791184) (xy 339.111082 -394.723874) (xy 339.094318 -394.715238) (xy 339.084412 -394.714222)
			(xy 339.057453 -394.710897) (xy 339.005069 -394.69654) (xy 338.955736 -394.673814) (xy 338.910782 -394.64333)
			(xy 338.871415 -394.605908) (xy 338.838694 -394.562554) (xy 338.8135 -394.514435) (xy 338.796511 -394.462845)
			(xy 338.791804 -394.436092) (xy 338.790534 -394.426694) (xy 338.517992 -393.95527) (xy 338.510626 -393.949428)
			(xy 338.491864 -393.933609) (xy 338.458748 -393.897394) (xy 338.431339 -393.856688) (xy 338.410236 -393.812384)
			(xy 338.395901 -393.765451) (xy 338.388648 -393.716917) (xy 338.388198 -393.69238) (xy 337.87115 -393.69238)
			(xy 338.11972 -394.122402) (xy 338.127086 -394.128244) (xy 338.145864 -394.144045) (xy 338.178983 -394.180262)
			(xy 338.206392 -394.22097) (xy 338.227493 -394.265278) (xy 338.241823 -394.312216) (xy 338.249068 -394.360754)
			(xy 338.249514 -394.385292) (xy 338.24926 -394.397484) (xy 338.249006 -394.407136) (xy 338.255102 -394.42517)
			(xy 338.313776 -394.49248) (xy 338.33054 -394.501116) (xy 338.340446 -394.502132) (xy 338.367213 -394.505454)
			(xy 338.419237 -394.519683) (xy 338.468262 -394.542165) (xy 338.512991 -394.572302) (xy 338.552238 -394.609297)
			(xy 338.584962 -394.652169) (xy 338.610297 -394.699783) (xy 338.627572 -394.750876) (xy 338.636329 -394.804095)
			(xy 338.636864 -394.831062) (xy 338.636313 -394.858346) (xy 338.62736 -394.912175) (xy 338.60969 -394.963803)
			(xy 338.583785 -395.01183) (xy 338.550345 -395.054952) (xy 338.530692 -395.073886) (xy 338.523294 -395.08141)
			(xy 338.514768 -395.100688) (xy 338.514182 -395.111224) (xy 338.514182 -395.1859) (xy 338.514703 -395.196451)
			(xy 338.523244 -395.215745) (xy 338.530692 -395.223238) (xy 338.550342 -395.242173) (xy 338.583773 -395.2853)
			(xy 338.609674 -395.333327) (xy 338.627344 -395.384953) (xy 338.636303 -395.438779) (xy 338.636864 -395.466062)
			(xy 338.636412 -395.490178) (xy 338.629416 -395.5379) (xy 338.615567 -395.584101) (xy 338.595158 -395.627802)
			(xy 338.582254 -395.64818) (xy 338.576412 -395.65707) (xy 338.572856 -395.677136) (xy 338.593938 -395.769338)
			(xy 338.60613 -395.786102) (xy 338.61502 -395.791436) (xy 338.635818 -395.804296) (xy 338.673724 -395.835184)
			(xy 338.706667 -395.871319) (xy 338.733929 -395.911911) (xy 338.754915 -395.956076) (xy 338.769167 -396.00285)
			(xy 338.776375 -396.051213) (xy 338.776818 -396.075662) (xy 338.77639 -396.100035) (xy 338.769245 -396.148254)
			(xy 338.755103 -396.194903) (xy 338.734271 -396.238973) (xy 338.7072 -396.27951) (xy 338.674474 -396.315637)
			(xy 338.655914 -396.33144) (xy 338.647024 -396.338552) (xy 338.637626 -396.35811) (xy 338.634832 -396.457424)
			(xy 338.643468 -396.47749) (xy 338.65185 -396.48511) (xy 338.670298 -396.502573) (xy 338.701645 -396.542543)
			(xy 338.725942 -396.587152) (xy 338.742519 -396.635167) (xy 338.750919 -396.685264) (xy 338.751418 -396.710662)
			(xy 338.751314 -396.721943) (xy 338.749663 -396.744445) (xy 338.748116 -396.75562) (xy 338.746846 -396.764764)
			(xy 338.750148 -396.782036) (xy 338.793836 -396.853156) (xy 338.807552 -396.864078) (xy 338.816188 -396.866872)
			(xy 338.844353 -396.877068) (xy 338.896299 -396.90688) (xy 338.919312 -396.926054) (xy 338.940798 -396.945633)
			(xy 338.97661 -396.991413) (xy 338.990432 -397.016986) (xy 338.991194 -397.018256) (xy 339.38337 -397.696944)
			(xy 339.396179 -397.720285) (xy 339.414404 -397.770303) (xy 339.423671 -397.822726) (xy 339.424264 -397.849344)
			(xy 339.423901 -397.873353) (xy 339.416379 -397.920779) (xy 339.401526 -397.966443) (xy 339.379709 -398.009219)
			(xy 339.351466 -398.048053) (xy 339.317493 -398.081989) (xy 339.278627 -398.110188) (xy 339.235826 -398.131957)
			(xy 339.190146 -398.146759) (xy 339.142712 -398.154228) (xy 339.118702 -398.154652) (xy 339.095172 -398.154167)
			(xy 339.048666 -398.146967) (xy 339.003818 -398.132706) (xy 338.961695 -398.111724) (xy 338.923295 -398.084518)
			(xy 338.889532 -398.051735) (xy 338.861208 -398.014154) (xy 338.849716 -397.993616) (xy 338.849462 -397.993108)
			(xy 338.848954 -397.992346) (xy 338.451444 -397.303752) (xy 338.440874 -397.283824) (xy 338.425069 -397.241575)
			(xy 338.415661 -397.197459) (xy 338.413852 -397.174974) (xy 338.413344 -397.163798) (xy 338.413344 -397.156432)
			(xy 338.413435 -397.145087) (xy 338.41509 -397.122458) (xy 338.416646 -397.11122) (xy 338.417916 -397.10233)
			(xy 338.41436 -397.085058) (xy 338.370926 -397.013938) (xy 338.35721 -397.002762) (xy 338.348574 -396.999968)
			(xy 338.326172 -396.99197) (xy 338.284002 -396.969967) (xy 338.245753 -396.94169) (xy 338.212353 -396.907824)
			(xy 338.18461 -396.869187) (xy 338.163194 -396.826715) (xy 338.148624 -396.781436) (xy 338.141253 -396.734445)
			(xy 338.140802 -396.710662) (xy 338.141327 -396.685267) (xy 338.149736 -396.635178) (xy 338.166317 -396.58717)
			(xy 338.190611 -396.542568) (xy 338.22195 -396.502599) (xy 338.24037 -396.48511) (xy 338.248752 -396.47749)
			(xy 338.257388 -396.457424) (xy 338.254594 -396.35811) (xy 338.245196 -396.338552) (xy 338.236306 -396.33144)
			(xy 338.217759 -396.315623) (xy 338.185041 -396.279494) (xy 338.157973 -396.238958) (xy 338.137141 -396.194892)
			(xy 338.122995 -396.148247) (xy 338.115839 -396.100033) (xy 338.115402 -396.075662) (xy 338.115807 -396.051544)
			(xy 338.122816 -396.00382) (xy 338.136678 -395.957619) (xy 338.157101 -395.91392) (xy 338.170012 -395.893544)
			(xy 338.175854 -395.884654) (xy 338.17941 -395.864588) (xy 338.158328 -395.772386) (xy 338.146136 -395.755622)
			(xy 338.137246 -395.750288) (xy 338.116451 -395.737424) (xy 338.078547 -395.706535) (xy 338.045605 -395.670401)
			(xy 338.018343 -395.629809) (xy 337.997357 -395.585645) (xy 337.983103 -395.538872) (xy 337.975893 -395.49051)
			(xy 337.975448 -395.466062) (xy 337.976011 -395.438778) (xy 337.984961 -395.38495) (xy 338.002627 -395.333321)
			(xy 338.02853 -395.285294) (xy 338.061968 -395.242172) (xy 338.08162 -395.223238) (xy 338.08901 -395.215707)
			(xy 338.09754 -395.196434) (xy 338.09813 -395.1859) (xy 338.09813 -395.111224) (xy 338.097593 -395.100675)
			(xy 338.089062 -395.081381) (xy 338.08162 -395.073886) (xy 338.061983 -395.054937) (xy 338.028551 -395.011815)
			(xy 338.002647 -394.963791) (xy 337.984974 -394.912168) (xy 337.976011 -394.858344) (xy 337.975448 -394.831062)
			(xy 337.975702 -394.81887) (xy 337.975956 -394.809218) (xy 337.96986 -394.791184) (xy 337.911186 -394.723874)
			(xy 337.894422 -394.715238) (xy 337.884516 -394.714222) (xy 337.857615 -394.710806) (xy 337.80533 -394.696451)
			(xy 337.756087 -394.67376) (xy 337.711203 -394.643342) (xy 337.671882 -394.60601) (xy 337.639176 -394.562766)
			(xy 337.613961 -394.514766) (xy 337.596912 -394.463296) (xy 337.592162 -394.4366) (xy 337.590638 -394.427202)
			(xy 337.317842 -393.95527) (xy 337.310476 -393.949428) (xy 337.291724 -393.933597) (xy 337.258606 -393.897386)
			(xy 337.231194 -393.856683) (xy 337.210088 -393.812381) (xy 337.195752 -393.76545) (xy 337.188498 -393.716916)
			(xy 337.188048 -393.69238) (xy 336.671254 -393.69238) (xy 336.919824 -394.122402) (xy 336.92719 -394.128244)
			(xy 336.945969 -394.144044) (xy 336.979087 -394.180261) (xy 337.006497 -394.22097) (xy 337.027598 -394.265278)
			(xy 337.041927 -394.312215) (xy 337.049172 -394.360754) (xy 337.049618 -394.385292) (xy 337.049364 -394.397484)
			(xy 337.04911 -394.407136) (xy 337.055206 -394.42517) (xy 337.11388 -394.49248) (xy 337.130644 -394.501116)
			(xy 337.140296 -394.502132) (xy 337.167057 -394.505495) (xy 337.21908 -394.519717) (xy 337.268106 -394.542191)
			(xy 337.312836 -394.572322) (xy 337.352083 -394.609312) (xy 337.384809 -394.65218) (xy 337.410146 -394.69979)
			(xy 337.427421 -394.75088) (xy 337.436178 -394.804096) (xy 337.436714 -394.831062) (xy 337.436178 -394.858347)
			(xy 337.427224 -394.912177) (xy 337.409552 -394.963807) (xy 337.383642 -395.011833) (xy 337.350198 -395.054954)
			(xy 337.330542 -395.073886) (xy 337.323151 -395.081417) (xy 337.314619 -395.10069) (xy 337.314032 -395.111224)
			(xy 337.314032 -395.1859) (xy 337.314538 -395.196453) (xy 337.323088 -395.215748) (xy 337.330542 -395.223238)
			(xy 337.350183 -395.242182) (xy 337.383617 -395.285305) (xy 337.409521 -395.33333) (xy 337.427192 -395.384955)
			(xy 337.436153 -395.438779) (xy 337.436714 -395.466062) (xy 337.43627 -395.490178) (xy 337.429273 -395.537901)
			(xy 337.415422 -395.584102) (xy 337.39501 -395.627803) (xy 337.382104 -395.64818) (xy 337.376262 -395.65707)
			(xy 337.372706 -395.677136) (xy 337.393788 -395.769338) (xy 337.40598 -395.786102) (xy 337.41487 -395.791436)
			(xy 337.435679 -395.804278) (xy 337.473583 -395.835171) (xy 337.506524 -395.871309) (xy 337.533783 -395.911905)
			(xy 337.554767 -395.956072) (xy 337.569018 -396.002848) (xy 337.576225 -396.051213) (xy 337.576668 -396.075662)
			(xy 337.576259 -396.100036) (xy 337.569112 -396.148256) (xy 337.554968 -396.194907) (xy 337.534133 -396.238977)
			(xy 337.507057 -396.279513) (xy 337.474327 -396.315639) (xy 337.455764 -396.33144) (xy 337.446874 -396.338552)
			(xy 337.437476 -396.35811) (xy 337.434682 -396.457424) (xy 337.443318 -396.47749) (xy 337.4517 -396.48511)
			(xy 337.470139 -396.502583) (xy 337.501489 -396.542549) (xy 337.525789 -396.587155) (xy 337.542368 -396.635168)
			(xy 337.550768 -396.685264) (xy 337.551268 -396.710662) (xy 337.551164 -396.721943) (xy 337.549513 -396.744445)
			(xy 337.547966 -396.75562) (xy 337.546696 -396.76451) (xy 337.550252 -396.782036) (xy 337.593686 -396.852902)
			(xy 337.607402 -396.864078) (xy 337.616038 -396.866872) (xy 337.63828 -396.874816) (xy 337.680202 -396.896564)
			(xy 337.718276 -396.924506) (xy 337.751595 -396.957977) (xy 337.779365 -396.996177) (xy 337.790536 -397.016986)
			(xy 337.791044 -397.018002) (xy 338.183474 -397.696944) (xy 338.196283 -397.720284) (xy 338.214508 -397.770303)
			(xy 338.223775 -397.822726) (xy 338.224368 -397.849344) (xy 338.224001 -397.873353) (xy 338.216479 -397.920778)
			(xy 338.201626 -397.966442) (xy 338.17981 -398.009218) (xy 338.151567 -398.048052) (xy 338.117595 -398.081987)
			(xy 338.078729 -398.110187) (xy 338.035929 -398.131956) (xy 337.990249 -398.146758) (xy 337.942816 -398.154228)
			(xy 337.918806 -398.154652) (xy 337.895276 -398.154164) (xy 337.84877 -398.146964) (xy 337.803923 -398.132704)
			(xy 337.761799 -398.111722) (xy 337.7234 -398.084517) (xy 337.689637 -398.051735) (xy 337.661312 -398.014154)
			(xy 337.64982 -397.993616) (xy 337.649566 -397.993108) (xy 337.649058 -397.992346) (xy 337.251294 -397.304006)
			(xy 337.239421 -397.281328) (xy 337.222568 -397.232995) (xy 337.213994 -397.182532) (xy 337.213448 -397.15694)
			(xy 337.213448 -397.156432) (xy 337.21354 -397.145087) (xy 337.215194 -397.122458) (xy 337.21675 -397.11122)
			(xy 337.21802 -397.10233) (xy 337.214464 -397.085058) (xy 337.17103 -397.013938) (xy 337.15706 -397.003016)
			(xy 337.148678 -396.999968) (xy 337.126283 -396.991915) (xy 337.084064 -396.96996) (xy 337.045766 -396.941716)
			(xy 337.012318 -396.907868) (xy 336.984533 -396.869236) (xy 336.963083 -396.826759) (xy 336.948489 -396.781465)
			(xy 336.941105 -396.734455) (xy 336.940652 -396.710662) (xy 336.941161 -396.685266) (xy 336.949572 -396.635176)
			(xy 336.966155 -396.587167) (xy 336.990453 -396.542564) (xy 337.021797 -396.502597) (xy 337.04022 -396.48511)
			(xy 337.048602 -396.47749) (xy 337.057238 -396.457424) (xy 337.054444 -396.35811) (xy 337.045046 -396.338552)
			(xy 337.036156 -396.33144) (xy 337.01762 -396.315611) (xy 336.984898 -396.279486) (xy 336.957828 -396.238953)
			(xy 336.936994 -396.194889) (xy 336.922846 -396.148246) (xy 336.91569 -396.100033) (xy 336.915252 -396.075662)
			(xy 336.915665 -396.051544) (xy 336.922673 -396.003821) (xy 336.936533 -395.95762) (xy 336.956953 -395.91392)
			(xy 336.969862 -395.893544) (xy 336.975704 -395.884654) (xy 336.97926 -395.864588) (xy 336.958178 -395.772386)
			(xy 336.945986 -395.755622) (xy 336.937096 -395.750288) (xy 336.916313 -395.737406) (xy 336.878406 -395.706522)
			(xy 336.845461 -395.670391) (xy 336.818197 -395.629803) (xy 336.797209 -395.585641) (xy 336.782954 -395.53887)
			(xy 336.775743 -395.49051) (xy 336.775298 -395.466062) (xy 336.775845 -395.438777) (xy 336.784796 -395.384947)
			(xy 336.802465 -395.333318) (xy 336.828373 -395.285291) (xy 336.861815 -395.242171) (xy 336.88147 -395.223238)
			(xy 336.888853 -395.2157) (xy 336.897389 -395.196433) (xy 336.89798 -395.1859) (xy 336.89798 -395.111224)
			(xy 336.897457 -395.100673) (xy 336.888918 -395.081378) (xy 336.88147 -395.073886) (xy 336.861843 -395.054928)
			(xy 336.828407 -395.011809) (xy 336.8025 -394.963788) (xy 336.784825 -394.912166) (xy 336.775861 -394.858344)
			(xy 336.775298 -394.831062) (xy 336.775552 -394.81887) (xy 336.775806 -394.809218) (xy 336.76971 -394.791184)
			(xy 336.711036 -394.723874) (xy 336.694272 -394.715238) (xy 336.68462 -394.714222) (xy 336.657709 -394.710882)
			(xy 336.605422 -394.696512) (xy 336.556179 -394.673808) (xy 336.511297 -394.643378) (xy 336.471978 -394.606036)
			(xy 336.439274 -394.562783) (xy 336.414062 -394.514775) (xy 336.397015 -394.463299) (xy 336.392266 -394.4366)
			(xy 336.390742 -394.427202) (xy 336.117946 -393.95527) (xy 336.11058 -393.949428) (xy 336.091829 -393.933596)
			(xy 336.05871 -393.897385) (xy 336.031298 -393.856683) (xy 336.010193 -393.812381) (xy 335.995856 -393.765449)
			(xy 335.988602 -393.716916) (xy 335.988152 -393.69238) (xy 333.83728 -393.69238) (xy 333.83728 -393.963906)
			(xy 333.838042 -393.984734) (xy 333.83728 -394.005562) (xy 333.83728 -394.25753) (xy 335.361534 -394.25753)
			(xy 335.362044 -394.231543) (xy 335.370174 -394.180208) (xy 335.386235 -394.130778) (xy 335.409831 -394.084468)
			(xy 335.440381 -394.04242) (xy 335.477132 -394.005669) (xy 335.51918 -393.975119) (xy 335.56549 -393.951523)
			(xy 335.61492 -393.935462) (xy 335.666255 -393.927332) (xy 335.718229 -393.927332) (xy 335.769564 -393.935462)
			(xy 335.818994 -393.951523) (xy 335.865304 -393.975119) (xy 335.907352 -394.005669) (xy 335.944103 -394.04242)
			(xy 335.974653 -394.084468) (xy 335.998249 -394.130778) (xy 336.01431 -394.180208) (xy 336.02244 -394.231543)
			(xy 336.02295 -394.25753) (xy 336.022567 -394.281206) (xy 336.015834 -394.328077) (xy 336.002468 -394.373504)
			(xy 335.992978 -394.395198) (xy 335.98866 -394.404596) (xy 335.987898 -394.424662) (xy 336.020156 -394.511022)
			(xy 336.033872 -394.525754) (xy 336.04327 -394.530072) (xy 336.067643 -394.541753) (xy 336.112512 -394.571883)
			(xy 336.151889 -394.608903) (xy 336.184727 -394.651829) (xy 336.210152 -394.699522) (xy 336.22749 -394.750712)
			(xy 336.236279 -394.804039) (xy 336.236818 -394.831062) (xy 336.236281 -394.858347) (xy 336.227327 -394.912177)
			(xy 336.209655 -394.963806) (xy 336.183746 -395.011833) (xy 336.150302 -395.054954) (xy 336.130646 -395.073886)
			(xy 336.123255 -395.081417) (xy 336.114723 -395.10069) (xy 336.114136 -395.111224) (xy 336.114136 -395.1859)
			(xy 336.114641 -395.196453) (xy 336.123192 -395.215749) (xy 336.130646 -395.223238) (xy 336.150288 -395.242182)
			(xy 336.183721 -395.285305) (xy 336.209625 -395.33333) (xy 336.227296 -395.384955) (xy 336.236257 -395.438779)
			(xy 336.236818 -395.466062) (xy 336.236373 -395.490178) (xy 336.229376 -395.537901) (xy 336.215525 -395.584102)
			(xy 336.195114 -395.627803) (xy 336.182208 -395.64818) (xy 336.176366 -395.65707) (xy 336.17281 -395.677136)
			(xy 336.193892 -395.769338) (xy 336.206084 -395.786102) (xy 336.214974 -395.791436) (xy 336.235784 -395.804277)
			(xy 336.273688 -395.83517) (xy 336.306628 -395.871309) (xy 336.333888 -395.911904) (xy 336.354871 -395.956072)
			(xy 336.369122 -396.002848) (xy 336.376329 -396.051213) (xy 336.376772 -396.075662) (xy 336.376361 -396.100036)
			(xy 336.369215 -396.148256) (xy 336.355071 -396.194906) (xy 336.334236 -396.238977) (xy 336.30716 -396.279513)
			(xy 336.274431 -396.315639) (xy 336.255868 -396.33144) (xy 336.246978 -396.338552) (xy 336.23758 -396.35811)
			(xy 336.234786 -396.457424) (xy 336.243422 -396.47749) (xy 336.251804 -396.48511) (xy 336.270243 -396.502582)
			(xy 336.301593 -396.542549) (xy 336.325893 -396.587155) (xy 336.342472 -396.635168) (xy 336.350872 -396.685264)
			(xy 336.351372 -396.710662) (xy 336.351268 -396.721943) (xy 336.349617 -396.744445) (xy 336.34807 -396.75562)
			(xy 336.3468 -396.76451) (xy 336.350356 -396.782036) (xy 336.39379 -396.852902) (xy 336.407506 -396.864078)
			(xy 336.416142 -396.866872) (xy 336.438385 -396.874814) (xy 336.480306 -396.896563) (xy 336.51838 -396.924506)
			(xy 336.551699 -396.957976) (xy 336.579469 -396.996177) (xy 336.59064 -397.016986) (xy 336.591148 -397.018002)
			(xy 336.983578 -397.696944) (xy 336.996388 -397.720284) (xy 337.014613 -397.770303) (xy 337.023879 -397.822726)
			(xy 337.024472 -397.849344) (xy 337.024101 -397.873353) (xy 337.016579 -397.920778) (xy 337.001727 -397.966441)
			(xy 336.979911 -398.009217) (xy 336.951668 -398.048051) (xy 336.917696 -398.081986) (xy 336.878831 -398.110185)
			(xy 336.836032 -398.131955) (xy 336.790352 -398.146757) (xy 336.742919 -398.154228) (xy 336.71891 -398.154652)
			(xy 336.695377 -398.154241) (xy 336.648867 -398.147027) (xy 336.604018 -398.132753) (xy 336.561895 -398.111759)
			(xy 336.523497 -398.084541) (xy 336.489736 -398.051748) (xy 336.461414 -398.014158) (xy 336.449924 -397.993616)
			(xy 336.44967 -397.993108) (xy 336.449162 -397.992346) (xy 336.051398 -397.304006) (xy 336.039525 -397.281328)
			(xy 336.022672 -397.232995) (xy 336.014098 -397.182532) (xy 336.013552 -397.15694) (xy 336.013552 -397.156432)
			(xy 336.013644 -397.145087) (xy 336.015298 -397.122458) (xy 336.016854 -397.11122) (xy 336.018124 -397.10233)
			(xy 336.014568 -397.085058) (xy 335.971134 -397.013938) (xy 335.957164 -397.003016) (xy 335.948782 -396.999968)
			(xy 335.926388 -396.991913) (xy 335.884169 -396.969959) (xy 335.845871 -396.941715) (xy 335.812423 -396.907867)
			(xy 335.784637 -396.869236) (xy 335.763187 -396.826758) (xy 335.748593 -396.781465) (xy 335.741209 -396.734455)
			(xy 335.740756 -396.710662) (xy 335.741264 -396.685266) (xy 335.749675 -396.635175) (xy 335.766258 -396.587167)
			(xy 335.790557 -396.542564) (xy 335.821901 -396.502597) (xy 335.840324 -396.48511) (xy 335.848706 -396.47749)
			(xy 335.857342 -396.457424) (xy 335.854548 -396.35811) (xy 335.84515 -396.338552) (xy 335.83626 -396.33144)
			(xy 335.817724 -396.31561) (xy 335.785003 -396.279485) (xy 335.757932 -396.238952) (xy 335.737098 -396.194888)
			(xy 335.72295 -396.148246) (xy 335.715794 -396.100033) (xy 335.715356 -396.075662) (xy 335.715769 -396.051544)
			(xy 335.722776 -396.003821) (xy 335.736636 -395.95762) (xy 335.757057 -395.91392) (xy 335.769966 -395.893544)
			(xy 335.775808 -395.884654) (xy 335.779364 -395.864588) (xy 335.758282 -395.772386) (xy 335.74609 -395.755622)
			(xy 335.7372 -395.750288) (xy 335.716418 -395.737404) (xy 335.67851 -395.706521) (xy 335.645565 -395.670391)
			(xy 335.618301 -395.629802) (xy 335.597313 -395.585641) (xy 335.583058 -395.53887) (xy 335.575847 -395.49051)
			(xy 335.575402 -395.466062) (xy 335.575948 -395.438777) (xy 335.584899 -395.384947) (xy 335.602568 -395.333318)
			(xy 335.628476 -395.285291) (xy 335.661919 -395.24217) (xy 335.681574 -395.223238) (xy 335.688957 -395.215701)
			(xy 335.697493 -395.196433) (xy 335.698084 -395.1859) (xy 335.698084 -395.111224) (xy 335.69756 -395.100674)
			(xy 335.689022 -395.081378) (xy 335.681574 -395.073886) (xy 335.661947 -395.054927) (xy 335.628511 -395.011808)
			(xy 335.602604 -394.963787) (xy 335.584929 -394.912166) (xy 335.575965 -394.858344) (xy 335.575402 -394.831062)
			(xy 335.575787 -394.807386) (xy 335.58252 -394.760515) (xy 335.595884 -394.715089) (xy 335.605374 -394.693394)
			(xy 335.609692 -394.683996) (xy 335.610454 -394.66393) (xy 335.578196 -394.57757) (xy 335.56448 -394.562838)
			(xy 335.555082 -394.55852) (xy 335.530717 -394.546821) (xy 335.485846 -394.516697) (xy 335.446466 -394.479681)
			(xy 335.413627 -394.436758) (xy 335.3882 -394.389067) (xy 335.370861 -394.337879) (xy 335.362073 -394.284553)
			(xy 335.361534 -394.25753) (xy 333.83728 -394.25753) (xy 333.83728 -394.611098) (xy 333.837697 -394.620706)
			(xy 333.844748 -394.638584) (xy 333.850996 -394.645896) (xy 333.867615 -394.664356) (xy 333.895692 -394.705329)
			(xy 333.91732 -394.750042) (xy 333.932014 -394.797489) (xy 333.939442 -394.8466) (xy 333.939436 -394.89627)
			(xy 333.931998 -394.945379) (xy 333.917294 -394.992823) (xy 333.895656 -395.037532) (xy 333.867571 -395.078499)
			(xy 333.850996 -395.097) (xy 333.844138 -395.104366) (xy 333.83728 -395.121892) (xy 333.83728 -395.157452)
			(xy 333.845916 -395.176756) (xy 333.854044 -395.184122) (xy 333.872426 -395.201333) (xy 333.904277 -395.240334)
			(xy 333.929847 -395.283714) (xy 333.948545 -395.330468) (xy 333.959937 -395.379518) (xy 333.963762 -395.429727)
			(xy 333.959929 -395.479936) (xy 333.948529 -395.528983) (xy 333.929824 -395.575734) (xy 333.904247 -395.61911)
			(xy 333.872389 -395.658106) (xy 333.854044 -395.675358) (xy 333.846528 -395.6829) (xy 333.837852 -395.702319)
			(xy 333.83728 -395.71295) (xy 333.83728 -396.175738) (xy 333.836849 -396.185805) (xy 333.829123 -396.204397)
			(xy 333.822294 -396.211806) (xy 333.792576 -396.241524) (xy 333.785002 -396.250045) (xy 333.777495 -396.27154)
			(xy 333.778098 -396.282926) (xy 333.788004 -396.37335) (xy 333.800196 -396.392908) (xy 333.809848 -396.399004)
			(xy 333.832938 -396.414338) (xy 333.874113 -396.451436) (xy 333.908529 -396.494879) (xy 333.935223 -396.543451)
			(xy 333.953448 -396.595792) (xy 333.962694 -396.650438) (xy 333.963264 -396.67815) (xy 333.962785 -396.704141)
			(xy 333.954659 -396.755483) (xy 333.938601 -396.804921) (xy 333.915005 -396.851238) (xy 333.884453 -396.893293)
			(xy 333.847697 -396.930049) (xy 333.805643 -396.960602) (xy 333.759327 -396.984199) (xy 333.709888 -397.000258)
			(xy 333.658547 -397.008384) (xy 333.632556 -397.008858) (xy 333.604841 -397.008299) (xy 333.550187 -396.999066)
			(xy 333.497837 -396.980849) (xy 333.449257 -396.954158) (xy 333.405808 -396.91974) (xy 333.368707 -396.878559)
			(xy 333.35341 -396.855442) (xy 333.347314 -396.84579) (xy 333.327756 -396.833598) (xy 333.237332 -396.823692)
			(xy 333.225941 -396.82305) (xy 333.20443 -396.830561) (xy 333.19593 -396.83817) (xy 332.673198 -397.360902)
			(xy 332.666388 -397.368247) (xy 332.658656 -397.38671) (xy 332.658212 -397.396716) (xy 332.658212 -397.503142)
			(xy 332.658757 -397.513126) (xy 332.666483 -397.531546) (xy 332.673198 -397.538956) (xy 333.001874 -397.867632)
			(xy 333.009284 -397.874317) (xy 333.027719 -397.881903) (xy 333.037688 -397.882364) (xy 333.620872 -397.882364)
			(xy 333.655136 -397.882859) (xy 333.723165 -397.891116) (xy 333.789702 -397.907513) (xy 333.853778 -397.931811)
			(xy 333.914458 -397.963655) (xy 333.970857 -398.002581) (xy 334.022152 -398.048022) (xy 334.067596 -398.099315)
			(xy 334.106526 -398.155711) (xy 334.138374 -398.216389) (xy 334.162676 -398.280463) (xy 334.179077 -398.347)
			(xy 334.187339 -398.415028) (xy 334.1878 -398.449292) (xy 334.187305 -398.482582) (xy 334.18027 -398.542002)
			(xy 335.612752 -398.542002) (xy 335.616712 -398.492948) (xy 335.628489 -398.445164) (xy 335.64778 -398.399888)
			(xy 335.674083 -398.358292) (xy 335.706718 -398.321455) (xy 335.744839 -398.29033) (xy 335.78746 -398.265723)
			(xy 335.833476 -398.248271) (xy 335.881695 -398.238427) (xy 335.93087 -398.236446) (xy 335.979725 -398.242378)
			(xy 336.026996 -398.25607) (xy 336.071458 -398.277168) (xy 336.111961 -398.305124) (xy 336.147454 -398.339216)
			(xy 336.177019 -398.37856) (xy 336.19989 -398.422137) (xy 336.215474 -398.468818) (xy 336.223369 -398.517395)
			(xy 336.223864 -398.542002) (xy 336.812902 -398.542002) (xy 336.816862 -398.492948) (xy 336.828639 -398.445164)
			(xy 336.84793 -398.399888) (xy 336.874233 -398.358292) (xy 336.906868 -398.321455) (xy 336.944989 -398.29033)
			(xy 336.98761 -398.265723) (xy 337.033626 -398.248271) (xy 337.081845 -398.238427) (xy 337.13102 -398.236446)
			(xy 337.179875 -398.242378) (xy 337.227146 -398.25607) (xy 337.271608 -398.277168) (xy 337.312111 -398.305124)
			(xy 337.347604 -398.339216) (xy 337.377169 -398.37856) (xy 337.40004 -398.422137) (xy 337.415624 -398.468818)
			(xy 337.423519 -398.517395) (xy 337.424014 -398.542002) (xy 338.013052 -398.542002) (xy 338.017012 -398.492948)
			(xy 338.028789 -398.445164) (xy 338.04808 -398.399888) (xy 338.074383 -398.358292) (xy 338.107018 -398.321455)
			(xy 338.145139 -398.29033) (xy 338.18776 -398.265723) (xy 338.233776 -398.248271) (xy 338.281995 -398.238427)
			(xy 338.33117 -398.236446) (xy 338.380025 -398.242378) (xy 338.427296 -398.25607) (xy 338.471758 -398.277168)
			(xy 338.512261 -398.305124) (xy 338.547754 -398.339216) (xy 338.577319 -398.37856) (xy 338.60019 -398.422137)
			(xy 338.615774 -398.468818) (xy 338.623669 -398.517395) (xy 338.624164 -398.542002) (xy 339.212948 -398.542002)
			(xy 339.216908 -398.492948) (xy 339.228685 -398.445164) (xy 339.247976 -398.399888) (xy 339.274279 -398.358292)
			(xy 339.306914 -398.321455) (xy 339.345035 -398.29033) (xy 339.387656 -398.265723) (xy 339.433672 -398.248271)
			(xy 339.481891 -398.238427) (xy 339.531066 -398.236446) (xy 339.579921 -398.242378) (xy 339.627192 -398.25607)
			(xy 339.671654 -398.277168) (xy 339.712157 -398.305124) (xy 339.74765 -398.339216) (xy 339.777215 -398.37856)
			(xy 339.800086 -398.422137) (xy 339.81567 -398.468818) (xy 339.823565 -398.517395) (xy 339.82406 -398.542002)
			(xy 340.413098 -398.542002) (xy 340.417058 -398.492948) (xy 340.428835 -398.445164) (xy 340.448126 -398.399888)
			(xy 340.474429 -398.358292) (xy 340.507064 -398.321455) (xy 340.545185 -398.29033) (xy 340.587806 -398.265723)
			(xy 340.633822 -398.248271) (xy 340.682041 -398.238427) (xy 340.731216 -398.236446) (xy 340.780071 -398.242378)
			(xy 340.827342 -398.25607) (xy 340.871804 -398.277168) (xy 340.912307 -398.305124) (xy 340.9478 -398.339216)
			(xy 340.977365 -398.37856) (xy 341.000236 -398.422137) (xy 341.01582 -398.468818) (xy 341.023715 -398.517395)
			(xy 341.02421 -398.542002) (xy 341.612994 -398.542002) (xy 341.616954 -398.492948) (xy 341.628731 -398.445164)
			(xy 341.648022 -398.399888) (xy 341.674325 -398.358292) (xy 341.70696 -398.321455) (xy 341.745081 -398.29033)
			(xy 341.787702 -398.265723) (xy 341.833718 -398.248271) (xy 341.881937 -398.238427) (xy 341.931112 -398.236446)
			(xy 341.979967 -398.242378) (xy 342.027238 -398.25607) (xy 342.0717 -398.277168) (xy 342.112203 -398.305124)
			(xy 342.147696 -398.339216) (xy 342.177261 -398.37856) (xy 342.200132 -398.422137) (xy 342.215716 -398.468818)
			(xy 342.223611 -398.517395) (xy 342.224106 -398.542002) (xy 342.81289 -398.542002) (xy 342.81685 -398.492948)
			(xy 342.828627 -398.445164) (xy 342.847918 -398.399888) (xy 342.874221 -398.358292) (xy 342.906856 -398.321455)
			(xy 342.944977 -398.29033) (xy 342.987598 -398.265723) (xy 343.033614 -398.248271) (xy 343.081833 -398.238427)
			(xy 343.131008 -398.236446) (xy 343.179863 -398.242378) (xy 343.227134 -398.25607) (xy 343.271596 -398.277168)
			(xy 343.312099 -398.305124) (xy 343.347592 -398.339216) (xy 343.377157 -398.37856) (xy 343.400028 -398.422137)
			(xy 343.415612 -398.468818) (xy 343.423507 -398.517395) (xy 343.424002 -398.542002) (xy 344.01304 -398.542002)
			(xy 344.017 -398.492948) (xy 344.028777 -398.445164) (xy 344.048068 -398.399888) (xy 344.074371 -398.358292)
			(xy 344.107006 -398.321455) (xy 344.145127 -398.29033) (xy 344.187748 -398.265723) (xy 344.233764 -398.248271)
			(xy 344.281983 -398.238427) (xy 344.331158 -398.236446) (xy 344.380013 -398.242378) (xy 344.427284 -398.25607)
			(xy 344.471746 -398.277168) (xy 344.512249 -398.305124) (xy 344.547742 -398.339216) (xy 344.577307 -398.37856)
			(xy 344.600178 -398.422137) (xy 344.615762 -398.468818) (xy 344.623657 -398.517395) (xy 344.624152 -398.542002)
			(xy 345.212936 -398.542002) (xy 345.216896 -398.492948) (xy 345.228673 -398.445164) (xy 345.247964 -398.399888)
			(xy 345.274267 -398.358292) (xy 345.306902 -398.321455) (xy 345.345023 -398.29033) (xy 345.387644 -398.265723)
			(xy 345.43366 -398.248271) (xy 345.481879 -398.238427) (xy 345.531054 -398.236446) (xy 345.579909 -398.242378)
			(xy 345.62718 -398.25607) (xy 345.671642 -398.277168) (xy 345.712145 -398.305124) (xy 345.747638 -398.339216)
			(xy 345.777203 -398.37856) (xy 345.800074 -398.422137) (xy 345.815658 -398.468818) (xy 345.823553 -398.517395)
			(xy 345.824048 -398.542002) (xy 346.413086 -398.542002) (xy 346.417046 -398.492948) (xy 346.428823 -398.445164)
			(xy 346.448114 -398.399888) (xy 346.474417 -398.358292) (xy 346.507052 -398.321455) (xy 346.545173 -398.29033)
			(xy 346.587794 -398.265723) (xy 346.63381 -398.248271) (xy 346.682029 -398.238427) (xy 346.731204 -398.236446)
			(xy 346.780059 -398.242378) (xy 346.82733 -398.25607) (xy 346.871792 -398.277168) (xy 346.912295 -398.305124)
			(xy 346.947788 -398.339216) (xy 346.977353 -398.37856) (xy 347.000224 -398.422137) (xy 347.015808 -398.468818)
			(xy 347.023703 -398.517395) (xy 347.024198 -398.542002) (xy 347.612982 -398.542002) (xy 347.616942 -398.492948)
			(xy 347.628719 -398.445164) (xy 347.64801 -398.399888) (xy 347.674313 -398.358292) (xy 347.706948 -398.321455)
			(xy 347.745069 -398.29033) (xy 347.78769 -398.265723) (xy 347.833706 -398.248271) (xy 347.881925 -398.238427)
			(xy 347.9311 -398.236446) (xy 347.979955 -398.242378) (xy 348.027226 -398.25607) (xy 348.071688 -398.277168)
			(xy 348.112191 -398.305124) (xy 348.147684 -398.339216) (xy 348.177249 -398.37856) (xy 348.20012 -398.422137)
			(xy 348.215704 -398.468818) (xy 348.223599 -398.517395) (xy 348.224094 -398.542002) (xy 348.812878 -398.542002)
			(xy 348.816838 -398.492948) (xy 348.828615 -398.445164) (xy 348.847906 -398.399888) (xy 348.874209 -398.358292)
			(xy 348.906844 -398.321455) (xy 348.944965 -398.29033) (xy 348.987586 -398.265723) (xy 349.033602 -398.248271)
			(xy 349.081821 -398.238427) (xy 349.130996 -398.236446) (xy 349.179851 -398.242378) (xy 349.227122 -398.25607)
			(xy 349.271584 -398.277168) (xy 349.312087 -398.305124) (xy 349.34758 -398.339216) (xy 349.377145 -398.37856)
			(xy 349.400016 -398.422137) (xy 349.4156 -398.468818) (xy 349.423495 -398.517395) (xy 349.42399 -398.542002)
			(xy 350.013028 -398.542002) (xy 350.016988 -398.492948) (xy 350.028765 -398.445164) (xy 350.048056 -398.399888)
			(xy 350.074359 -398.358292) (xy 350.106994 -398.321455) (xy 350.145115 -398.29033) (xy 350.187736 -398.265723)
			(xy 350.233752 -398.248271) (xy 350.281971 -398.238427) (xy 350.331146 -398.236446) (xy 350.380001 -398.242378)
			(xy 350.427272 -398.25607) (xy 350.471734 -398.277168) (xy 350.512237 -398.305124) (xy 350.54773 -398.339216)
			(xy 350.577295 -398.37856) (xy 350.600166 -398.422137) (xy 350.61575 -398.468818) (xy 350.623645 -398.517395)
			(xy 350.62414 -398.542002) (xy 351.212924 -398.542002) (xy 351.216884 -398.492948) (xy 351.228661 -398.445164)
			(xy 351.247952 -398.399888) (xy 351.274255 -398.358292) (xy 351.30689 -398.321455) (xy 351.345011 -398.29033)
			(xy 351.387632 -398.265723) (xy 351.433648 -398.248271) (xy 351.481867 -398.238427) (xy 351.531042 -398.236446)
			(xy 351.579897 -398.242378) (xy 351.627168 -398.25607) (xy 351.67163 -398.277168) (xy 351.712133 -398.305124)
			(xy 351.747626 -398.339216) (xy 351.777191 -398.37856) (xy 351.800062 -398.422137) (xy 351.815646 -398.468818)
			(xy 351.823541 -398.517395) (xy 351.824036 -398.542002) (xy 352.413074 -398.542002) (xy 352.417034 -398.492948)
			(xy 352.428811 -398.445164) (xy 352.448102 -398.399888) (xy 352.474405 -398.358292) (xy 352.50704 -398.321455)
			(xy 352.545161 -398.29033) (xy 352.587782 -398.265723) (xy 352.633798 -398.248271) (xy 352.682017 -398.238427)
			(xy 352.731192 -398.236446) (xy 352.780047 -398.242378) (xy 352.827318 -398.25607) (xy 352.87178 -398.277168)
			(xy 352.912283 -398.305124) (xy 352.947776 -398.339216) (xy 352.977341 -398.37856) (xy 353.000212 -398.422137)
			(xy 353.015796 -398.468818) (xy 353.023691 -398.517395) (xy 353.024186 -398.542002) (xy 353.023691 -398.566609)
			(xy 353.015796 -398.615186) (xy 353.000212 -398.661867) (xy 352.977341 -398.705444) (xy 352.947776 -398.744788)
			(xy 352.912283 -398.77888) (xy 352.87178 -398.806836) (xy 352.827318 -398.827934) (xy 352.780047 -398.841626)
			(xy 352.731192 -398.847558) (xy 352.682017 -398.845577) (xy 352.633798 -398.835733) (xy 352.587782 -398.818281)
			(xy 352.545161 -398.793674) (xy 352.50704 -398.762549) (xy 352.474405 -398.725712) (xy 352.448102 -398.684116)
			(xy 352.428811 -398.63884) (xy 352.417034 -398.591056) (xy 352.413074 -398.542002) (xy 351.824036 -398.542002)
			(xy 351.823541 -398.566609) (xy 351.815646 -398.615186) (xy 351.800062 -398.661867) (xy 351.777191 -398.705444)
			(xy 351.747626 -398.744788) (xy 351.712133 -398.77888) (xy 351.67163 -398.806836) (xy 351.627168 -398.827934)
			(xy 351.579897 -398.841626) (xy 351.531042 -398.847558) (xy 351.481867 -398.845577) (xy 351.433648 -398.835733)
			(xy 351.387632 -398.818281) (xy 351.345011 -398.793674) (xy 351.30689 -398.762549) (xy 351.274255 -398.725712)
			(xy 351.247952 -398.684116) (xy 351.228661 -398.63884) (xy 351.216884 -398.591056) (xy 351.212924 -398.542002)
			(xy 350.62414 -398.542002) (xy 350.623645 -398.566609) (xy 350.61575 -398.615186) (xy 350.600166 -398.661867)
			(xy 350.577295 -398.705444) (xy 350.54773 -398.744788) (xy 350.512237 -398.77888) (xy 350.471734 -398.806836)
			(xy 350.427272 -398.827934) (xy 350.380001 -398.841626) (xy 350.331146 -398.847558) (xy 350.281971 -398.845577)
			(xy 350.233752 -398.835733) (xy 350.187736 -398.818281) (xy 350.145115 -398.793674) (xy 350.106994 -398.762549)
			(xy 350.074359 -398.725712) (xy 350.048056 -398.684116) (xy 350.028765 -398.63884) (xy 350.016988 -398.591056)
			(xy 350.013028 -398.542002) (xy 349.42399 -398.542002) (xy 349.423495 -398.566609) (xy 349.4156 -398.615186)
			(xy 349.400016 -398.661867) (xy 349.377145 -398.705444) (xy 349.34758 -398.744788) (xy 349.312087 -398.77888)
			(xy 349.271584 -398.806836) (xy 349.227122 -398.827934) (xy 349.179851 -398.841626) (xy 349.130996 -398.847558)
			(xy 349.081821 -398.845577) (xy 349.033602 -398.835733) (xy 348.987586 -398.818281) (xy 348.944965 -398.793674)
			(xy 348.906844 -398.762549) (xy 348.874209 -398.725712) (xy 348.847906 -398.684116) (xy 348.828615 -398.63884)
			(xy 348.816838 -398.591056) (xy 348.812878 -398.542002) (xy 348.224094 -398.542002) (xy 348.223599 -398.566609)
			(xy 348.215704 -398.615186) (xy 348.20012 -398.661867) (xy 348.177249 -398.705444) (xy 348.147684 -398.744788)
			(xy 348.112191 -398.77888) (xy 348.071688 -398.806836) (xy 348.027226 -398.827934) (xy 347.979955 -398.841626)
			(xy 347.9311 -398.847558) (xy 347.881925 -398.845577) (xy 347.833706 -398.835733) (xy 347.78769 -398.818281)
			(xy 347.745069 -398.793674) (xy 347.706948 -398.762549) (xy 347.674313 -398.725712) (xy 347.64801 -398.684116)
			(xy 347.628719 -398.63884) (xy 347.616942 -398.591056) (xy 347.612982 -398.542002) (xy 347.024198 -398.542002)
			(xy 347.023703 -398.566609) (xy 347.015808 -398.615186) (xy 347.000224 -398.661867) (xy 346.977353 -398.705444)
			(xy 346.947788 -398.744788) (xy 346.912295 -398.77888) (xy 346.871792 -398.806836) (xy 346.82733 -398.827934)
			(xy 346.780059 -398.841626) (xy 346.731204 -398.847558) (xy 346.682029 -398.845577) (xy 346.63381 -398.835733)
			(xy 346.587794 -398.818281) (xy 346.545173 -398.793674) (xy 346.507052 -398.762549) (xy 346.474417 -398.725712)
			(xy 346.448114 -398.684116) (xy 346.428823 -398.63884) (xy 346.417046 -398.591056) (xy 346.413086 -398.542002)
			(xy 345.824048 -398.542002) (xy 345.823553 -398.566609) (xy 345.815658 -398.615186) (xy 345.800074 -398.661867)
			(xy 345.777203 -398.705444) (xy 345.747638 -398.744788) (xy 345.712145 -398.77888) (xy 345.671642 -398.806836)
			(xy 345.62718 -398.827934) (xy 345.579909 -398.841626) (xy 345.531054 -398.847558) (xy 345.481879 -398.845577)
			(xy 345.43366 -398.835733) (xy 345.387644 -398.818281) (xy 345.345023 -398.793674) (xy 345.306902 -398.762549)
			(xy 345.274267 -398.725712) (xy 345.247964 -398.684116) (xy 345.228673 -398.63884) (xy 345.216896 -398.591056)
			(xy 345.212936 -398.542002) (xy 344.624152 -398.542002) (xy 344.623657 -398.566609) (xy 344.615762 -398.615186)
			(xy 344.600178 -398.661867) (xy 344.577307 -398.705444) (xy 344.547742 -398.744788) (xy 344.512249 -398.77888)
			(xy 344.471746 -398.806836) (xy 344.427284 -398.827934) (xy 344.380013 -398.841626) (xy 344.331158 -398.847558)
			(xy 344.281983 -398.845577) (xy 344.233764 -398.835733) (xy 344.187748 -398.818281) (xy 344.145127 -398.793674)
			(xy 344.107006 -398.762549) (xy 344.074371 -398.725712) (xy 344.048068 -398.684116) (xy 344.028777 -398.63884)
			(xy 344.017 -398.591056) (xy 344.01304 -398.542002) (xy 343.424002 -398.542002) (xy 343.423507 -398.566609)
			(xy 343.415612 -398.615186) (xy 343.400028 -398.661867) (xy 343.377157 -398.705444) (xy 343.347592 -398.744788)
			(xy 343.312099 -398.77888) (xy 343.271596 -398.806836) (xy 343.227134 -398.827934) (xy 343.179863 -398.841626)
			(xy 343.131008 -398.847558) (xy 343.081833 -398.845577) (xy 343.033614 -398.835733) (xy 342.987598 -398.818281)
			(xy 342.944977 -398.793674) (xy 342.906856 -398.762549) (xy 342.874221 -398.725712) (xy 342.847918 -398.684116)
			(xy 342.828627 -398.63884) (xy 342.81685 -398.591056) (xy 342.81289 -398.542002) (xy 342.224106 -398.542002)
			(xy 342.223611 -398.566609) (xy 342.215716 -398.615186) (xy 342.200132 -398.661867) (xy 342.177261 -398.705444)
			(xy 342.147696 -398.744788) (xy 342.112203 -398.77888) (xy 342.0717 -398.806836) (xy 342.027238 -398.827934)
			(xy 341.979967 -398.841626) (xy 341.931112 -398.847558) (xy 341.881937 -398.845577) (xy 341.833718 -398.835733)
			(xy 341.787702 -398.818281) (xy 341.745081 -398.793674) (xy 341.70696 -398.762549) (xy 341.674325 -398.725712)
			(xy 341.648022 -398.684116) (xy 341.628731 -398.63884) (xy 341.616954 -398.591056) (xy 341.612994 -398.542002)
			(xy 341.02421 -398.542002) (xy 341.023715 -398.566609) (xy 341.01582 -398.615186) (xy 341.000236 -398.661867)
			(xy 340.977365 -398.705444) (xy 340.9478 -398.744788) (xy 340.912307 -398.77888) (xy 340.871804 -398.806836)
			(xy 340.827342 -398.827934) (xy 340.780071 -398.841626) (xy 340.731216 -398.847558) (xy 340.682041 -398.845577)
			(xy 340.633822 -398.835733) (xy 340.587806 -398.818281) (xy 340.545185 -398.793674) (xy 340.507064 -398.762549)
			(xy 340.474429 -398.725712) (xy 340.448126 -398.684116) (xy 340.428835 -398.63884) (xy 340.417058 -398.591056)
			(xy 340.413098 -398.542002) (xy 339.82406 -398.542002) (xy 339.823565 -398.566609) (xy 339.81567 -398.615186)
			(xy 339.800086 -398.661867) (xy 339.777215 -398.705444) (xy 339.74765 -398.744788) (xy 339.712157 -398.77888)
			(xy 339.671654 -398.806836) (xy 339.627192 -398.827934) (xy 339.579921 -398.841626) (xy 339.531066 -398.847558)
			(xy 339.481891 -398.845577) (xy 339.433672 -398.835733) (xy 339.387656 -398.818281) (xy 339.345035 -398.793674)
			(xy 339.306914 -398.762549) (xy 339.274279 -398.725712) (xy 339.247976 -398.684116) (xy 339.228685 -398.63884)
			(xy 339.216908 -398.591056) (xy 339.212948 -398.542002) (xy 338.624164 -398.542002) (xy 338.623669 -398.566609)
			(xy 338.615774 -398.615186) (xy 338.60019 -398.661867) (xy 338.577319 -398.705444) (xy 338.547754 -398.744788)
			(xy 338.512261 -398.77888) (xy 338.471758 -398.806836) (xy 338.427296 -398.827934) (xy 338.380025 -398.841626)
			(xy 338.33117 -398.847558) (xy 338.281995 -398.845577) (xy 338.233776 -398.835733) (xy 338.18776 -398.818281)
			(xy 338.145139 -398.793674) (xy 338.107018 -398.762549) (xy 338.074383 -398.725712) (xy 338.04808 -398.684116)
			(xy 338.028789 -398.63884) (xy 338.017012 -398.591056) (xy 338.013052 -398.542002) (xy 337.424014 -398.542002)
			(xy 337.423519 -398.566609) (xy 337.415624 -398.615186) (xy 337.40004 -398.661867) (xy 337.377169 -398.705444)
			(xy 337.347604 -398.744788) (xy 337.312111 -398.77888) (xy 337.271608 -398.806836) (xy 337.227146 -398.827934)
			(xy 337.179875 -398.841626) (xy 337.13102 -398.847558) (xy 337.081845 -398.845577) (xy 337.033626 -398.835733)
			(xy 336.98761 -398.818281) (xy 336.944989 -398.793674) (xy 336.906868 -398.762549) (xy 336.874233 -398.725712)
			(xy 336.84793 -398.684116) (xy 336.828639 -398.63884) (xy 336.816862 -398.591056) (xy 336.812902 -398.542002)
			(xy 336.223864 -398.542002) (xy 336.223369 -398.566609) (xy 336.215474 -398.615186) (xy 336.19989 -398.661867)
			(xy 336.177019 -398.705444) (xy 336.147454 -398.744788) (xy 336.111961 -398.77888) (xy 336.071458 -398.806836)
			(xy 336.026996 -398.827934) (xy 335.979725 -398.841626) (xy 335.93087 -398.847558) (xy 335.881695 -398.845577)
			(xy 335.833476 -398.835733) (xy 335.78746 -398.818281) (xy 335.744839 -398.793674) (xy 335.706718 -398.762549)
			(xy 335.674083 -398.725712) (xy 335.64778 -398.684116) (xy 335.628489 -398.63884) (xy 335.616712 -398.591056)
			(xy 335.612752 -398.542002) (xy 334.18027 -398.542002) (xy 334.179477 -398.5487) (xy 334.163964 -398.613447)
			(xy 334.140978 -398.675933) (xy 334.126332 -398.705832) (xy 334.121521 -398.716765) (xy 334.121517 -398.740621)
			(xy 334.126332 -398.751552) (xy 334.140986 -398.781448) (xy 334.163984 -398.843931) (xy 334.179499 -398.90868)
			(xy 334.187317 -398.974801) (xy 334.1878 -399.008092) (xy 334.187388 -399.039012) (xy 334.180659 -399.100483)
			(xy 334.167279 -399.160858) (xy 334.147407 -399.219417) (xy 334.134714 -399.247614) (xy 334.131066 -399.256233)
			(xy 334.129772 -399.27489) (xy 334.132174 -399.283936) (xy 334.141318 -399.3134) (xy 334.14432 -399.322001)
			(xy 334.155386 -399.336456) (xy 334.162908 -399.341594) (xy 334.183057 -399.354614) (xy 334.21972 -399.385551)
			(xy 334.251529 -399.42146) (xy 334.277816 -399.461589) (xy 334.298029 -399.505094) (xy 334.311743 -399.551063)
			(xy 334.318672 -399.598532) (xy 334.319118 -399.622518) (xy 334.318607 -399.648505) (xy 334.310474 -399.699837)
			(xy 334.294412 -399.749266) (xy 334.270815 -399.795574) (xy 334.240265 -399.83762) (xy 334.203514 -399.874371)
			(xy 334.161467 -399.904919) (xy 334.115159 -399.928515) (xy 334.06573 -399.944576) (xy 334.014397 -399.952708)
			(xy 333.98841 -399.953226) (xy 333.962561 -399.952728) (xy 333.911493 -399.944686) (xy 333.862299 -399.928795)
			(xy 333.816176 -399.905444) (xy 333.774248 -399.8752) (xy 333.737537 -399.838801) (xy 333.706936 -399.797132)
			(xy 333.683192 -399.75121) (xy 333.666882 -399.702153) (xy 333.658404 -399.651156) (xy 333.657702 -399.625312)
			(xy 333.657448 -399.603976) (xy 333.627984 -399.57502) (xy 332.550262 -399.57502) (xy 332.518449 -399.574593)
			(xy 332.455223 -399.567471) (xy 332.393193 -399.55331) (xy 332.333141 -399.532289) (xy 332.275821 -399.504671)
			(xy 332.221957 -399.470805) (xy 332.172227 -399.431117) (xy 332.14945 -399.408904) (xy 331.131926 -398.39138)
			(xy 331.109758 -398.36857) (xy 331.07011 -398.318829) (xy 331.036281 -398.264962) (xy 331.008696 -398.207645)
			(xy 330.987701 -398.147601) (xy 330.973561 -398.085583) (xy 330.966454 -398.022373) (xy 330.966064 -397.990568)
			(xy 330.966064 -397.732504) (xy 330.965582 -397.722782) (xy 330.958273 -397.704757) (xy 330.95184 -397.697452)
			(xy 330.931012 -397.675608) (xy 330.924332 -397.669225) (xy 330.907665 -397.661283) (xy 330.8985 -397.660114)
			(xy 330.867297 -397.657076) (xy 330.80591 -397.644337) (xy 330.776072 -397.634714) (xy 330.768198 -397.63192)
			(xy 330.434442 -397.63192) (xy 330.410312 -397.646652) (xy 330.403708 -397.659606) (xy 330.391356 -397.682648)
			(xy 330.361297 -397.725423) (xy 330.325684 -397.763699) (xy 330.285183 -397.796759) (xy 330.240551 -397.823985)
			(xy 330.192623 -397.844869) (xy 330.142293 -397.85902) (xy 330.090504 -397.866174) (xy 330.064364 -397.866616)
			(xy 330.033596 -397.866013) (xy 329.97285 -397.856183) (xy 329.94346 -397.847058) (xy 329.92949 -397.842232)
			(xy 329.901804 -397.848836) (xy 329.087988 -398.662652) (xy 329.080888 -398.670562) (xy 329.073264 -398.690378)
			(xy 329.073256 -398.701006) (xy 329.077574 -398.787112) (xy 329.087226 -398.806162) (xy 329.095608 -398.813274)
			(xy 329.120264 -398.834008) (xy 329.16466 -398.88069) (xy 329.202803 -398.932607) (xy 329.234079 -398.988928)
			(xy 329.257988 -399.048749) (xy 329.274147 -399.111112) (xy 329.282296 -399.175017) (xy 329.282806 -399.207228)
			(xy 329.282232 -399.242073) (xy 329.272714 -399.311112) (xy 329.253862 -399.378204) (xy 329.226027 -399.442095)
			(xy 329.208384 -399.47215) (xy 329.203304 -399.480278) (xy 329.200002 -399.498058) (xy 329.21448 -399.582386)
			(xy 329.223624 -399.59788) (xy 329.230736 -399.603976) (xy 329.255394 -399.624709) (xy 329.299797 -399.671388)
			(xy 329.337944 -399.723304) (xy 329.369225 -399.779624) (xy 329.393137 -399.839447) (xy 329.409298 -399.901811)
			(xy 329.417449 -399.965718) (xy 329.417934 -399.99793) (xy 329.417453 -400.028624) (xy 329.410029 -400.089563)
			(xy 329.395328 -400.149167) (xy 329.373564 -400.206569) (xy 329.345053 -400.260936) (xy 329.328018 -400.286474)
			(xy 329.32255 -400.295225) (xy 329.318431 -400.315425) (xy 329.32257 -400.335621) (xy 329.328018 -400.344386)
			(xy 329.345072 -400.369913) (xy 329.3736 -400.424276) (xy 329.395371 -400.48168) (xy 329.410066 -400.541288)
			(xy 329.417471 -400.602233) (xy 329.417934 -400.63293) (xy 329.417468 -400.66366) (xy 329.410057 -400.724673)
			(xy 329.395346 -400.784347) (xy 329.37355 -400.841813) (xy 329.344986 -400.896233) (xy 329.310071 -400.946814)
			(xy 329.269315 -400.992818) (xy 329.223311 -401.033574) (xy 329.17273 -401.068488) (xy 329.118309 -401.097051)
			(xy 329.060843 -401.118847) (xy 329.001169 -401.133558) (xy 328.940156 -401.140968) (xy 328.909426 -401.141438)
			(xy 328.888344 -401.14093) (xy 328.877422 -401.140422) (xy 328.857864 -401.148042) (xy 328.789538 -401.216368)
			(xy 328.781918 -401.235926) (xy 328.782426 -401.246848) (xy 328.782934 -401.26793) (xy 328.782453 -401.298624)
			(xy 328.775029 -401.359563) (xy 328.760328 -401.419167) (xy 328.738564 -401.476569) (xy 328.710053 -401.530936)
			(xy 328.693018 -401.556474) (xy 328.68755 -401.565225) (xy 328.683431 -401.585425) (xy 328.68757 -401.605621)
			(xy 328.693018 -401.614386) (xy 328.710072 -401.639913) (xy 328.7386 -401.694276) (xy 328.760371 -401.75168)
			(xy 328.775066 -401.811288) (xy 328.782471 -401.872233) (xy 328.782934 -401.90293) (xy 329.637898 -401.90293)
			(xy 329.638382 -401.87556) (xy 329.646196 -401.821382) (xy 329.661681 -401.768879) (xy 329.684518 -401.719132)
			(xy 329.714239 -401.673164) (xy 329.731878 -401.652232) (xy 329.737974 -401.64512) (xy 329.744324 -401.628102)
			(xy 329.744324 -401.542758) (xy 329.737974 -401.52574) (xy 329.731878 -401.518628) (xy 329.714269 -401.49767)
			(xy 329.684546 -401.451706) (xy 329.661702 -401.401963) (xy 329.646206 -401.349465) (xy 329.638376 -401.295291)
			(xy 329.638372 -401.240554) (xy 329.646196 -401.186379) (xy 329.661686 -401.133879) (xy 329.684525 -401.084134)
			(xy 329.714241 -401.038166) (xy 329.731878 -401.017232) (xy 329.737974 -401.01012) (xy 329.744324 -400.993102)
			(xy 329.744324 -400.907758) (xy 329.737974 -400.89074) (xy 329.731878 -400.883628) (xy 329.714269 -400.86267)
			(xy 329.684546 -400.816706) (xy 329.661702 -400.766963) (xy 329.646206 -400.714465) (xy 329.638376 -400.660291)
			(xy 329.638372 -400.605554) (xy 329.646196 -400.551379) (xy 329.661686 -400.498879) (xy 329.684525 -400.449134)
			(xy 329.714241 -400.403166) (xy 329.731878 -400.382232) (xy 329.737974 -400.37512) (xy 329.744324 -400.358102)
			(xy 329.744324 -400.272758) (xy 329.737974 -400.25574) (xy 329.731878 -400.248628) (xy 329.714235 -400.227699)
			(xy 329.684525 -400.181725) (xy 329.66169 -400.131977) (xy 329.6462 -400.079475) (xy 329.638372 -400.025299)
			(xy 329.637898 -399.99793) (xy 329.638403 -399.970461) (xy 329.646285 -399.916091) (xy 329.661878 -399.863412)
			(xy 329.684858 -399.813511) (xy 329.714752 -399.767419) (xy 329.750942 -399.726085) (xy 329.771502 -399.707862)
			(xy 329.779122 -399.701258) (xy 329.788266 -399.683478) (xy 329.795378 -399.591276) (xy 329.789028 -399.571972)
			(xy 329.78217 -399.564352) (xy 329.764777 -399.543446) (xy 329.735469 -399.497637) (xy 329.71295 -399.448137)
			(xy 329.697673 -399.395945) (xy 329.689948 -399.342115) (xy 329.68946 -399.314924) (xy 329.689926 -399.287554)
			(xy 329.697741 -399.233374) (xy 329.71323 -399.18087) (xy 329.736072 -399.131123) (xy 329.765798 -399.085157)
			(xy 329.78344 -399.064226) (xy 329.789536 -399.057114) (xy 329.795886 -399.040096) (xy 329.795886 -398.954752)
			(xy 329.789536 -398.937734) (xy 329.78344 -398.930622) (xy 329.765804 -398.909687) (xy 329.73609 -398.863716)
			(xy 329.713253 -398.813969) (xy 329.697761 -398.761469) (xy 329.689934 -398.707293) (xy 329.68946 -398.679924)
			(xy 329.689946 -398.652673) (xy 329.697702 -398.598725) (xy 329.713057 -398.54643) (xy 329.735699 -398.496853)
			(xy 329.765165 -398.451003) (xy 329.800856 -398.409812) (xy 329.842047 -398.374121) (xy 329.887897 -398.344655)
			(xy 329.937474 -398.322013) (xy 329.989769 -398.306658) (xy 330.043717 -398.298902) (xy 330.098219 -398.298902)
			(xy 330.152167 -398.306658) (xy 330.204462 -398.322013) (xy 330.254039 -398.344655) (xy 330.299889 -398.374121)
			(xy 330.34108 -398.409812) (xy 330.376771 -398.451003) (xy 330.406237 -398.496853) (xy 330.428879 -398.54643)
			(xy 330.444234 -398.598725) (xy 330.45199 -398.652673) (xy 330.452476 -398.679924) (xy 330.45203 -398.707295)
			(xy 330.444208 -398.761475) (xy 330.428715 -398.813979) (xy 330.405868 -398.863725) (xy 330.376139 -398.909691)
			(xy 330.358496 -398.930622) (xy 330.3524 -398.937734) (xy 330.34605 -398.954752) (xy 330.34605 -399.040096)
			(xy 330.3524 -399.057114) (xy 330.358496 -399.064226) (xy 330.376113 -399.085176) (xy 330.405829 -399.131144)
			(xy 330.428669 -399.180887) (xy 330.444165 -399.233383) (xy 330.451999 -399.287556) (xy 330.452476 -399.314924)
			(xy 330.451874 -399.344533) (xy 330.442715 -399.403039) (xy 330.424635 -399.459431) (xy 330.398069 -399.512356)
			(xy 330.363652 -399.560547) (xy 330.32221 -399.602848) (xy 330.298806 -399.620994) (xy 330.290368 -399.627915)
			(xy 330.279827 -399.646995) (xy 330.278486 -399.657824) (xy 330.274422 -399.713958) (xy 330.285598 -399.724626)
			(xy 330.292936 -399.731156) (xy 330.311094 -399.738603) (xy 330.320904 -399.739104) (xy 330.352908 -399.739104)
			(xy 330.362722 -399.738612) (xy 330.380886 -399.731171) (xy 330.388214 -399.724626) (xy 330.409704 -399.704442)
			(xy 330.457766 -399.670299) (xy 330.510508 -399.643955) (xy 330.566675 -399.626037) (xy 330.624928 -399.61697)
			(xy 330.654406 -399.616422) (xy 330.681777 -399.616879) (xy 330.735956 -399.624698) (xy 330.78846 -399.640189)
			(xy 330.838206 -399.663033) (xy 330.884173 -399.69276) (xy 330.905104 -399.710402) (xy 330.912216 -399.716498)
			(xy 330.929234 -399.722848) (xy 331.014578 -399.722848) (xy 331.031596 -399.716498) (xy 331.038708 -399.710402)
			(xy 331.059641 -399.692761) (xy 331.105609 -399.663037) (xy 331.155355 -399.640191) (xy 331.207857 -399.624695)
			(xy 331.262035 -399.616866) (xy 331.316777 -399.616866) (xy 331.370955 -399.624695) (xy 331.423457 -399.640191)
			(xy 331.473203 -399.663037) (xy 331.519171 -399.692761) (xy 331.540104 -399.710402) (xy 331.547216 -399.716498)
			(xy 331.564234 -399.722848) (xy 331.649578 -399.722848) (xy 331.666596 -399.716498) (xy 331.673708 -399.710402)
			(xy 331.694626 -399.692746) (xy 331.740603 -399.663037) (xy 331.790354 -399.640204) (xy 331.842858 -399.624717)
			(xy 331.897036 -399.616893) (xy 331.924406 -399.616422) (xy 331.95166 -399.61685) (xy 332.005614 -399.624608)
			(xy 332.057914 -399.639967) (xy 332.107497 -399.662612) (xy 332.153351 -399.692084) (xy 332.194545 -399.727781)
			(xy 332.230238 -399.768978) (xy 332.259705 -399.814835) (xy 332.282346 -399.864419) (xy 332.297699 -399.916721)
			(xy 332.305453 -399.970676) (xy 332.305914 -399.99793) (xy 332.305462 -400.025301) (xy 332.29764 -400.07948)
			(xy 332.282148 -400.131983) (xy 332.259303 -400.18173) (xy 332.229576 -400.227696) (xy 332.211934 -400.248628)
			(xy 332.205838 -400.25574) (xy 332.199488 -400.272758) (xy 332.199488 -400.358102) (xy 332.205838 -400.37512)
			(xy 332.211934 -400.382232) (xy 332.229606 -400.40314) (xy 332.259332 -400.449111) (xy 332.282178 -400.498861)
			(xy 332.297674 -400.551367) (xy 332.305501 -400.60555) (xy 332.305499 -400.633946) (xy 332.590648 -400.633946)
			(xy 332.591134 -400.606695) (xy 332.59889 -400.552747) (xy 332.614245 -400.500452) (xy 332.636887 -400.450875)
			(xy 332.666353 -400.405025) (xy 332.702044 -400.363834) (xy 332.743235 -400.328143) (xy 332.789085 -400.298677)
			(xy 332.838662 -400.276035) (xy 332.890957 -400.26068) (xy 332.944905 -400.252924) (xy 332.999407 -400.252924)
			(xy 333.053355 -400.26068) (xy 333.10565 -400.276035) (xy 333.155227 -400.298677) (xy 333.201077 -400.328143)
			(xy 333.242268 -400.363834) (xy 333.277959 -400.405025) (xy 333.307425 -400.450875) (xy 333.330067 -400.500452)
			(xy 333.345422 -400.552747) (xy 333.353178 -400.606695) (xy 333.353664 -400.633946) (xy 333.353413 -400.653974)
			(xy 333.34921 -400.693808) (xy 333.345282 -400.713448) (xy 333.344685 -400.71675) (xy 334.691736 -400.71675)
			(xy 334.692137 -400.693516) (xy 334.698636 -400.647506) (xy 334.711512 -400.602859) (xy 334.730512 -400.560454)
			(xy 334.755262 -400.521128) (xy 334.769968 -400.503136) (xy 334.776064 -400.496024) (xy 334.78216 -400.479514)
			(xy 334.78216 -400.395186) (xy 334.776064 -400.378676) (xy 334.769968 -400.371564) (xy 334.755285 -400.353555)
			(xy 334.730533 -400.314232) (xy 334.711527 -400.271832) (xy 334.698643 -400.227189) (xy 334.692133 -400.181182)
			(xy 334.691736 -400.15795) (xy 334.692246 -400.131963) (xy 334.700376 -400.080628) (xy 334.716437 -400.031198)
			(xy 334.740033 -399.984888) (xy 334.770583 -399.94284) (xy 334.807334 -399.906089) (xy 334.849382 -399.875539)
			(xy 334.895692 -399.851943) (xy 334.945122 -399.835882) (xy 334.996457 -399.827752) (xy 335.048431 -399.827752)
			(xy 335.099766 -399.835882) (xy 335.149196 -399.851943) (xy 335.195506 -399.875539) (xy 335.237554 -399.906089)
			(xy 335.274305 -399.94284) (xy 335.304855 -399.984888) (xy 335.328451 -400.031198) (xy 335.344512 -400.080628)
			(xy 335.352642 -400.131963) (xy 335.353152 -400.15795) (xy 335.352754 -400.181184) (xy 335.346255 -400.227194)
			(xy 335.333378 -400.271841) (xy 335.314377 -400.314246) (xy 335.289626 -400.353573) (xy 335.27492 -400.371564)
			(xy 335.268824 -400.378676) (xy 335.262728 -400.395186) (xy 335.262728 -400.479514) (xy 335.268824 -400.496024)
			(xy 335.27492 -400.503136) (xy 335.289616 -400.521135) (xy 335.314364 -400.560462) (xy 335.333365 -400.602865)
			(xy 335.346247 -400.647509) (xy 335.352755 -400.693517) (xy 335.353152 -400.71675) (xy 335.352642 -400.742737)
			(xy 335.344512 -400.794072) (xy 335.328451 -400.843502) (xy 335.304855 -400.889812) (xy 335.274305 -400.93186)
			(xy 335.237554 -400.968611) (xy 335.195506 -400.999161) (xy 335.149196 -401.022757) (xy 335.099766 -401.038818)
			(xy 335.048431 -401.046948) (xy 334.996457 -401.046948) (xy 334.945122 -401.038818) (xy 334.895692 -401.022757)
			(xy 334.849382 -400.999161) (xy 334.807334 -400.968611) (xy 334.770583 -400.93186) (xy 334.740033 -400.889812)
			(xy 334.716437 -400.843502) (xy 334.700376 -400.794072) (xy 334.692246 -400.742737) (xy 334.691736 -400.71675)
			(xy 333.344685 -400.71675) (xy 333.342648 -400.728012) (xy 333.345009 -400.757502) (xy 333.355727 -400.785077)
			(xy 333.373903 -400.808419) (xy 333.39801 -400.825569) (xy 333.426022 -400.835085) (xy 333.440786 -400.83613)
			(xy 333.46732 -400.8376) (xy 333.519615 -400.847048) (xy 333.570093 -400.863661) (xy 333.617779 -400.887118)
			(xy 333.661748 -400.916964) (xy 333.701151 -400.952622) (xy 333.735225 -400.993402) (xy 333.763311 -401.038516)
			(xy 333.784866 -401.08709) (xy 333.799472 -401.138185) (xy 333.806848 -401.190813) (xy 333.807308 -401.217384)
			(xy 333.806822 -401.244635) (xy 333.799066 -401.298583) (xy 333.783711 -401.350878) (xy 333.761069 -401.400455)
			(xy 333.731603 -401.446305) (xy 333.695912 -401.487496) (xy 333.654721 -401.523187) (xy 333.608871 -401.552653)
			(xy 333.559294 -401.575295) (xy 333.506999 -401.59065) (xy 333.453051 -401.598406) (xy 333.398549 -401.598406)
			(xy 333.344601 -401.59065) (xy 333.292306 -401.575295) (xy 333.242729 -401.552653) (xy 333.196879 -401.523187)
			(xy 333.155688 -401.487496) (xy 333.119997 -401.446305) (xy 333.090531 -401.400455) (xy 333.067889 -401.350878)
			(xy 333.052534 -401.298583) (xy 333.044778 -401.244635) (xy 333.044292 -401.217384) (xy 333.044547 -401.197357)
			(xy 333.048747 -401.157522) (xy 333.052674 -401.137882) (xy 333.055318 -401.123318) (xy 333.052965 -401.093823)
			(xy 333.042248 -401.066243) (xy 333.024069 -401.042897) (xy 332.999956 -401.025749) (xy 332.971936 -401.01624)
			(xy 332.95717 -401.0152) (xy 332.930642 -401.013651) (xy 332.878351 -401.004211) (xy 332.827875 -400.987606)
			(xy 332.780192 -400.964158) (xy 332.736223 -400.934321) (xy 332.69682 -400.898671) (xy 332.662745 -400.857898)
			(xy 332.634657 -400.812792) (xy 332.613099 -400.764225) (xy 332.59849 -400.713136) (xy 332.59111 -400.660514)
			(xy 332.590648 -400.633946) (xy 332.305499 -400.633946) (xy 332.305497 -400.660295) (xy 332.297664 -400.714477)
			(xy 332.282162 -400.766981) (xy 332.25931 -400.816728) (xy 332.229578 -400.862696) (xy 332.211934 -400.883628)
			(xy 332.205838 -400.89074) (xy 332.199488 -400.907758) (xy 332.199488 -400.993102) (xy 332.205838 -401.01012)
			(xy 332.211934 -401.017232) (xy 332.229606 -401.03814) (xy 332.259332 -401.084111) (xy 332.282178 -401.133861)
			(xy 332.297674 -401.186367) (xy 332.305501 -401.24055) (xy 332.305497 -401.295295) (xy 332.297664 -401.349477)
			(xy 332.282162 -401.401981) (xy 332.25931 -401.451728) (xy 332.229578 -401.497696) (xy 332.211934 -401.518628)
			(xy 332.205838 -401.52574) (xy 332.199488 -401.542758) (xy 332.199488 -401.628102) (xy 332.205838 -401.64512)
			(xy 332.211934 -401.652232) (xy 332.22956 -401.673175) (xy 332.230635 -401.674838) (xy 335.962244 -401.674838)
			(xy 335.962244 -400.811238) (xy 335.962723 -400.784882) (xy 335.969986 -400.732674) (xy 335.984365 -400.681961)
			(xy 336.005586 -400.63371) (xy 336.033247 -400.588839) (xy 336.066819 -400.548202) (xy 336.085942 -400.53006)
			(xy 336.093054 -400.52371) (xy 336.101182 -400.506946) (xy 336.109564 -400.420332) (xy 336.104484 -400.402552)
			(xy 336.098896 -400.394678) (xy 336.084751 -400.374827) (xy 336.062291 -400.331571) (xy 336.046977 -400.285299)
			(xy 336.039197 -400.237184) (xy 336.038698 -400.212814) (xy 336.03922 -400.187559) (xy 336.047533 -400.137737)
			(xy 336.063934 -400.089963) (xy 336.087975 -400.04554) (xy 336.118999 -400.00568) (xy 336.156161 -399.97147)
			(xy 336.198447 -399.943844) (xy 336.244703 -399.923554) (xy 336.293668 -399.911154) (xy 336.344006 -399.906983)
			(xy 336.394344 -399.911154) (xy 336.443309 -399.923554) (xy 336.489565 -399.943844) (xy 336.531851 -399.97147)
			(xy 336.569013 -400.00568) (xy 336.600037 -400.04554) (xy 336.624078 -400.089963) (xy 336.640479 -400.137737)
			(xy 336.648792 -400.187559) (xy 336.649314 -400.212814) (xy 336.648843 -400.237187) (xy 336.641083 -400.28531)
			(xy 336.625763 -400.331586) (xy 336.603275 -400.374834) (xy 336.589116 -400.394678) (xy 336.583528 -400.402552)
			(xy 336.578448 -400.420332) (xy 336.58683 -400.506946) (xy 336.594958 -400.52371) (xy 336.60207 -400.53006)
			(xy 336.621208 -400.54819) (xy 336.654795 -400.588822) (xy 336.682465 -400.633693) (xy 336.703692 -400.681947)
			(xy 336.71807 -400.732665) (xy 336.725325 -400.78488) (xy 336.725768 -400.811238) (xy 336.725768 -401.674838)
			(xy 337.16214 -401.674838) (xy 337.16214 -400.811238) (xy 337.16262 -400.784882) (xy 337.169883 -400.732674)
			(xy 337.184262 -400.681962) (xy 337.205483 -400.633711) (xy 337.233143 -400.58884) (xy 337.266715 -400.548202)
			(xy 337.285838 -400.53006) (xy 337.29295 -400.523456) (xy 337.301332 -400.506946) (xy 337.30946 -400.420078)
			(xy 337.304634 -400.402298) (xy 337.298792 -400.394678) (xy 337.284687 -400.374809) (xy 337.262264 -400.331554)
			(xy 337.247007 -400.285284) (xy 337.239302 -400.237175) (xy 337.238848 -400.212814) (xy 337.23937 -400.187559)
			(xy 337.247683 -400.137737) (xy 337.264084 -400.089963) (xy 337.288125 -400.04554) (xy 337.319149 -400.00568)
			(xy 337.356311 -399.97147) (xy 337.398597 -399.943844) (xy 337.444853 -399.923554) (xy 337.493818 -399.911154)
			(xy 337.544156 -399.906983) (xy 337.594494 -399.911154) (xy 337.643459 -399.923554) (xy 337.689715 -399.943844)
			(xy 337.732001 -399.97147) (xy 337.769163 -400.00568) (xy 337.800187 -400.04554) (xy 337.824228 -400.089963)
			(xy 337.840629 -400.137737) (xy 337.848942 -400.187559) (xy 337.849464 -400.212814) (xy 337.848997 -400.237217)
			(xy 337.841238 -400.285401) (xy 337.825918 -400.331739) (xy 337.803427 -400.375053) (xy 337.789266 -400.394932)
			(xy 337.783678 -400.402552) (xy 337.778598 -400.420332) (xy 337.786726 -400.5072) (xy 337.795108 -400.52371)
			(xy 337.80222 -400.530314) (xy 337.821289 -400.548466) (xy 337.85478 -400.589089) (xy 337.882377 -400.633924)
			(xy 337.903558 -400.682122) (xy 337.917923 -400.732772) (xy 337.925199 -400.784915) (xy 337.925664 -400.811238)
			(xy 337.925664 -401.674838) (xy 338.362544 -401.674838) (xy 338.362544 -400.811238) (xy 338.36301 -400.784893)
			(xy 338.370257 -400.732705) (xy 338.384606 -400.682007) (xy 338.405784 -400.633761) (xy 338.433389 -400.588882)
			(xy 338.466898 -400.548221) (xy 338.485988 -400.53006) (xy 338.4931 -400.52371) (xy 338.501228 -400.506946)
			(xy 338.50961 -400.420332) (xy 338.50453 -400.402552) (xy 338.498942 -400.394678) (xy 338.484791 -400.374832)
			(xy 338.462334 -400.331573) (xy 338.447022 -400.2853) (xy 338.439242 -400.237184) (xy 338.438744 -400.212814)
			(xy 338.439266 -400.187559) (xy 338.447579 -400.137737) (xy 338.46398 -400.089963) (xy 338.488021 -400.04554)
			(xy 338.519045 -400.00568) (xy 338.556207 -399.97147) (xy 338.598493 -399.943844) (xy 338.644749 -399.923554)
			(xy 338.693714 -399.911154) (xy 338.744052 -399.906983) (xy 338.79439 -399.911154) (xy 338.843355 -399.923554)
			(xy 338.889611 -399.943844) (xy 338.931897 -399.97147) (xy 338.969059 -400.00568) (xy 339.000083 -400.04554)
			(xy 339.024124 -400.089963) (xy 339.040525 -400.137737) (xy 339.048838 -400.187559) (xy 339.04936 -400.212814)
			(xy 339.04888 -400.237186) (xy 339.041121 -400.285309) (xy 339.025804 -400.331585) (xy 339.003319 -400.374833)
			(xy 338.989162 -400.394678) (xy 338.983574 -400.402552) (xy 338.978494 -400.420332) (xy 338.986876 -400.506946)
			(xy 338.995004 -400.52371) (xy 339.002116 -400.53006) (xy 339.021212 -400.548217) (xy 339.054735 -400.588871)
			(xy 339.08235 -400.633748) (xy 339.103533 -400.681996) (xy 339.11788 -400.732698) (xy 339.12512 -400.784891)
			(xy 339.12556 -400.811238) (xy 339.12556 -401.674838) (xy 339.56244 -401.674838) (xy 339.56244 -400.811238)
			(xy 339.562907 -400.784893) (xy 339.570154 -400.732705) (xy 339.584503 -400.682007) (xy 339.60568 -400.633761)
			(xy 339.633285 -400.588882) (xy 339.666794 -400.548221) (xy 339.685884 -400.53006) (xy 339.692996 -400.52371)
			(xy 339.701124 -400.506946) (xy 339.709506 -400.420332) (xy 339.704426 -400.402552) (xy 339.698838 -400.394678)
			(xy 339.684686 -400.374832) (xy 339.66223 -400.331573) (xy 339.646918 -400.2853) (xy 339.639138 -400.237184)
			(xy 339.63864 -400.212814) (xy 339.639162 -400.187559) (xy 339.647475 -400.137737) (xy 339.663876 -400.089963)
			(xy 339.687917 -400.04554) (xy 339.718941 -400.00568) (xy 339.756103 -399.97147) (xy 339.798389 -399.943844)
			(xy 339.844645 -399.923554) (xy 339.89361 -399.911154) (xy 339.943948 -399.906983) (xy 339.994286 -399.911154)
			(xy 340.043251 -399.923554) (xy 340.089507 -399.943844) (xy 340.131793 -399.97147) (xy 340.168955 -400.00568)
			(xy 340.199979 -400.04554) (xy 340.22402 -400.089963) (xy 340.240421 -400.137737) (xy 340.248734 -400.187559)
			(xy 340.249256 -400.212814) (xy 340.248777 -400.237186) (xy 340.241018 -400.285309) (xy 340.225701 -400.331585)
			(xy 340.203215 -400.374833) (xy 340.189058 -400.394678) (xy 340.18347 -400.402552) (xy 340.17839 -400.420332)
			(xy 340.186772 -400.506946) (xy 340.1949 -400.52371) (xy 340.202012 -400.53006) (xy 340.221107 -400.548218)
			(xy 340.254631 -400.588871) (xy 340.282246 -400.633748) (xy 340.303428 -400.681996) (xy 340.317776 -400.732698)
			(xy 340.325016 -400.784891) (xy 340.325456 -400.811238) (xy 340.325456 -401.674838) (xy 340.762336 -401.674838)
			(xy 340.762336 -400.811238) (xy 340.762817 -400.784882) (xy 340.77008 -400.732674) (xy 340.784459 -400.681962)
			(xy 340.80568 -400.633711) (xy 340.83334 -400.58884) (xy 340.866912 -400.548202) (xy 340.886034 -400.53006)
			(xy 340.893146 -400.52371) (xy 340.901274 -400.506946) (xy 340.909656 -400.420332) (xy 340.904576 -400.402552)
			(xy 340.898988 -400.394678) (xy 340.884842 -400.374828) (xy 340.862383 -400.331571) (xy 340.847069 -400.285299)
			(xy 340.839289 -400.237184) (xy 340.83879 -400.212814) (xy 340.839312 -400.187559) (xy 340.847625 -400.137737)
			(xy 340.864026 -400.089963) (xy 340.888067 -400.04554) (xy 340.919091 -400.00568) (xy 340.956253 -399.97147)
			(xy 340.998539 -399.943844) (xy 341.044795 -399.923554) (xy 341.09376 -399.911154) (xy 341.144098 -399.906983)
			(xy 341.194436 -399.911154) (xy 341.243401 -399.923554) (xy 341.289657 -399.943844) (xy 341.331943 -399.97147)
			(xy 341.369105 -400.00568) (xy 341.400129 -400.04554) (xy 341.42417 -400.089963) (xy 341.440571 -400.137737)
			(xy 341.448884 -400.187559) (xy 341.449406 -400.212814) (xy 341.448936 -400.237187) (xy 341.441176 -400.285311)
			(xy 341.425856 -400.331586) (xy 341.403367 -400.374834) (xy 341.389208 -400.394678) (xy 341.38362 -400.402552)
			(xy 341.37854 -400.420332) (xy 341.386922 -400.506946) (xy 341.39505 -400.52371) (xy 341.402162 -400.53006)
			(xy 341.421298 -400.548192) (xy 341.454886 -400.588823) (xy 341.482556 -400.633693) (xy 341.503783 -400.681947)
			(xy 341.518162 -400.732665) (xy 341.525417 -400.78488) (xy 341.52586 -400.811238) (xy 341.52586 -401.674838)
			(xy 341.962232 -401.674838) (xy 341.962232 -400.811238) (xy 341.962714 -400.784883) (xy 341.969977 -400.732674)
			(xy 341.984356 -400.681962) (xy 342.005577 -400.633711) (xy 342.033236 -400.58884) (xy 342.066808 -400.548203)
			(xy 342.08593 -400.53006) (xy 342.093042 -400.52371) (xy 342.10117 -400.506946) (xy 342.109552 -400.420332)
			(xy 342.104472 -400.402552) (xy 342.098884 -400.394678) (xy 342.084738 -400.374828) (xy 342.062279 -400.331571)
			(xy 342.046965 -400.285299) (xy 342.039185 -400.237184) (xy 342.038686 -400.212814) (xy 342.039208 -400.187559)
			(xy 342.047521 -400.137737) (xy 342.063922 -400.089963) (xy 342.087963 -400.04554) (xy 342.118987 -400.00568)
			(xy 342.156149 -399.97147) (xy 342.198435 -399.943844) (xy 342.244691 -399.923554) (xy 342.293656 -399.911154)
			(xy 342.343994 -399.906983) (xy 342.394332 -399.911154) (xy 342.443297 -399.923554) (xy 342.489553 -399.943844)
			(xy 342.531839 -399.97147) (xy 342.569001 -400.00568) (xy 342.600025 -400.04554) (xy 342.624066 -400.089963)
			(xy 342.640467 -400.137737) (xy 342.64878 -400.187559) (xy 342.649302 -400.212814) (xy 342.648833 -400.237187)
			(xy 342.641073 -400.285311) (xy 342.625753 -400.331586) (xy 342.603263 -400.374834) (xy 342.589104 -400.394678)
			(xy 342.583516 -400.402552) (xy 342.578436 -400.420332) (xy 342.586818 -400.506946) (xy 342.594946 -400.52371)
			(xy 342.602058 -400.53006) (xy 342.621193 -400.548192) (xy 342.654781 -400.588824) (xy 342.682452 -400.633694)
			(xy 342.703679 -400.681947) (xy 342.718058 -400.732665) (xy 342.725313 -400.78488) (xy 342.725756 -400.811238)
			(xy 342.725756 -401.674838) (xy 343.162636 -401.674838) (xy 343.162636 -400.811238) (xy 343.163105 -400.784893)
			(xy 343.170352 -400.732705) (xy 343.1847 -400.682007) (xy 343.205877 -400.633761) (xy 343.233482 -400.588882)
			(xy 343.26699 -400.548221) (xy 343.28608 -400.53006) (xy 343.293192 -400.52371) (xy 343.30132 -400.506946)
			(xy 343.309702 -400.420332) (xy 343.304622 -400.402552) (xy 343.299034 -400.394678) (xy 343.284882 -400.374833)
			(xy 343.262425 -400.331573) (xy 343.247114 -400.2853) (xy 343.239334 -400.237184) (xy 343.238836 -400.212814)
			(xy 343.239358 -400.187559) (xy 343.247671 -400.137737) (xy 343.264072 -400.089963) (xy 343.288113 -400.04554)
			(xy 343.319137 -400.00568) (xy 343.356299 -399.97147) (xy 343.398585 -399.943844) (xy 343.444841 -399.923554)
			(xy 343.493806 -399.911154) (xy 343.544144 -399.906983) (xy 343.594482 -399.911154) (xy 343.643447 -399.923554)
			(xy 343.689703 -399.943844) (xy 343.731989 -399.97147) (xy 343.769151 -400.00568) (xy 343.800175 -400.04554)
			(xy 343.824216 -400.089963) (xy 343.840617 -400.137737) (xy 343.84893 -400.187559) (xy 343.849452 -400.212814)
			(xy 343.848973 -400.237186) (xy 343.841215 -400.285309) (xy 343.825897 -400.331585) (xy 343.803411 -400.374833)
			(xy 343.789254 -400.394678) (xy 343.783666 -400.402552) (xy 343.778586 -400.420332) (xy 343.786968 -400.506946)
			(xy 343.795096 -400.52371) (xy 343.802208 -400.53006) (xy 343.821303 -400.548218) (xy 343.854826 -400.588872)
			(xy 343.882442 -400.633749) (xy 343.903624 -400.681996) (xy 343.917972 -400.732698) (xy 343.925212 -400.784892)
			(xy 343.925652 -400.811238) (xy 343.925652 -401.674838) (xy 344.362532 -401.674838) (xy 344.362532 -400.811238)
			(xy 344.363002 -400.784894) (xy 344.370249 -400.732705) (xy 344.384597 -400.682007) (xy 344.405774 -400.633761)
			(xy 344.433378 -400.588882) (xy 344.466887 -400.548221) (xy 344.485976 -400.53006) (xy 344.493088 -400.52371)
			(xy 344.501216 -400.506946) (xy 344.509598 -400.420332) (xy 344.504518 -400.402552) (xy 344.49893 -400.394678)
			(xy 344.484777 -400.374833) (xy 344.462321 -400.331573) (xy 344.44701 -400.2853) (xy 344.43923 -400.237184)
			(xy 344.438732 -400.212814) (xy 344.439254 -400.187559) (xy 344.447567 -400.137737) (xy 344.463968 -400.089963)
			(xy 344.488009 -400.04554) (xy 344.519033 -400.00568) (xy 344.556195 -399.97147) (xy 344.598481 -399.943844)
			(xy 344.644737 -399.923554) (xy 344.693702 -399.911154) (xy 344.74404 -399.906983) (xy 344.794378 -399.911154)
			(xy 344.843343 -399.923554) (xy 344.889599 -399.943844) (xy 344.931885 -399.97147) (xy 344.969047 -400.00568)
			(xy 345.000071 -400.04554) (xy 345.024112 -400.089963) (xy 345.040513 -400.137737) (xy 345.048826 -400.187559)
			(xy 345.049348 -400.212814) (xy 345.04887 -400.237186) (xy 345.041111 -400.28531) (xy 345.025793 -400.331585)
			(xy 345.003307 -400.374833) (xy 344.98915 -400.394678) (xy 344.983562 -400.402552) (xy 344.978482 -400.420332)
			(xy 344.986864 -400.506946) (xy 344.994992 -400.52371) (xy 345.002104 -400.53006) (xy 345.021198 -400.548219)
			(xy 345.054722 -400.588873) (xy 345.082337 -400.633749) (xy 345.10352 -400.681997) (xy 345.117868 -400.732698)
			(xy 345.125108 -400.784892) (xy 345.125548 -400.811238) (xy 345.125548 -401.674838) (xy 345.562428 -401.674838)
			(xy 345.562428 -400.811238) (xy 345.562861 -400.784911) (xy 345.570111 -400.732757) (xy 345.584465 -400.682096)
			(xy 345.60565 -400.633891) (xy 345.633263 -400.589057) (xy 345.66678 -400.548447) (xy 345.685872 -400.530314)
			(xy 345.692984 -400.52371) (xy 345.701366 -400.5072) (xy 345.709494 -400.420332) (xy 345.704414 -400.402552)
			(xy 345.698826 -400.394932) (xy 345.684674 -400.375048) (xy 345.662185 -400.331735) (xy 345.646866 -400.285398)
			(xy 345.639106 -400.237216) (xy 345.638628 -400.212814) (xy 345.63915 -400.187559) (xy 345.647463 -400.137737)
			(xy 345.663864 -400.089963) (xy 345.687905 -400.04554) (xy 345.718929 -400.00568) (xy 345.756091 -399.97147)
			(xy 345.798377 -399.943844) (xy 345.844633 -399.923554) (xy 345.893598 -399.911154) (xy 345.943936 -399.906983)
			(xy 345.994274 -399.911154) (xy 346.043239 -399.923554) (xy 346.089495 -399.943844) (xy 346.131781 -399.97147)
			(xy 346.168943 -400.00568) (xy 346.199967 -400.04554) (xy 346.224008 -400.089963) (xy 346.240409 -400.137737)
			(xy 346.248722 -400.187559) (xy 346.249244 -400.212814) (xy 346.248748 -400.237172) (xy 346.241035 -400.285275)
			(xy 346.225792 -400.331545) (xy 346.203403 -400.374812) (xy 346.1893 -400.394678) (xy 346.183458 -400.402298)
			(xy 346.178632 -400.420078) (xy 346.18676 -400.506946) (xy 346.195142 -400.523456) (xy 346.202254 -400.53006)
			(xy 346.221389 -400.548193) (xy 346.254976 -400.588824) (xy 346.282648 -400.633694) (xy 346.303875 -400.681948)
			(xy 346.318253 -400.732665) (xy 346.325509 -400.78488) (xy 346.325952 -400.811238) (xy 346.325952 -401.674838)
			(xy 346.762324 -401.674838) (xy 346.762324 -400.811238) (xy 346.762809 -400.784883) (xy 346.770072 -400.732674)
			(xy 346.78445 -400.681963) (xy 346.80567 -400.633712) (xy 346.833329 -400.588841) (xy 346.8669 -400.548203)
			(xy 346.886022 -400.53006) (xy 346.893134 -400.52371) (xy 346.901262 -400.506946) (xy 346.909644 -400.420332)
			(xy 346.904564 -400.402552) (xy 346.898976 -400.394678) (xy 346.884829 -400.374829) (xy 346.86237 -400.331571)
			(xy 346.847057 -400.285299) (xy 346.839276 -400.237184) (xy 346.838778 -400.212814) (xy 346.8393 -400.187559)
			(xy 346.847613 -400.137737) (xy 346.864014 -400.089963) (xy 346.888055 -400.04554) (xy 346.919079 -400.00568)
			(xy 346.956241 -399.97147) (xy 346.998527 -399.943844) (xy 347.044783 -399.923554) (xy 347.093748 -399.911154)
			(xy 347.144086 -399.906983) (xy 347.194424 -399.911154) (xy 347.243389 -399.923554) (xy 347.289645 -399.943844)
			(xy 347.331931 -399.97147) (xy 347.369093 -400.00568) (xy 347.400117 -400.04554) (xy 347.424158 -400.089963)
			(xy 347.440559 -400.137737) (xy 347.448872 -400.187559) (xy 347.449394 -400.212814) (xy 347.448927 -400.237187)
			(xy 347.441166 -400.285311) (xy 347.425846 -400.331587) (xy 347.403355 -400.374834) (xy 347.389196 -400.394678)
			(xy 347.383608 -400.402552) (xy 347.378528 -400.420332) (xy 347.38691 -400.506946) (xy 347.395038 -400.52371)
			(xy 347.40215 -400.53006) (xy 347.421284 -400.548194) (xy 347.454872 -400.588825) (xy 347.482543 -400.633694)
			(xy 347.503771 -400.681948) (xy 347.518149 -400.732665) (xy 347.525405 -400.78488) (xy 347.525848 -400.811238)
			(xy 347.525848 -401.674838) (xy 347.962728 -401.674838) (xy 347.962728 -400.811238) (xy 347.963151 -400.784921)
			(xy 347.970376 -400.732785) (xy 347.984694 -400.682136) (xy 348.005834 -400.633934) (xy 348.033395 -400.589093)
			(xy 348.066855 -400.548463) (xy 348.085918 -400.530314) (xy 348.09303 -400.52371) (xy 348.101412 -400.5072)
			(xy 348.10954 -400.420332) (xy 348.10446 -400.402552) (xy 348.098872 -400.394932) (xy 348.084713 -400.375052)
			(xy 348.062227 -400.331737) (xy 348.04691 -400.285399) (xy 348.039152 -400.237216) (xy 348.038674 -400.212814)
			(xy 348.039196 -400.187559) (xy 348.047509 -400.137737) (xy 348.06391 -400.089963) (xy 348.087951 -400.04554)
			(xy 348.118975 -400.00568) (xy 348.156137 -399.97147) (xy 348.198423 -399.943844) (xy 348.244679 -399.923554)
			(xy 348.293644 -399.911154) (xy 348.343982 -399.906983) (xy 348.39432 -399.911154) (xy 348.443285 -399.923554)
			(xy 348.489541 -399.943844) (xy 348.531827 -399.97147) (xy 348.568989 -400.00568) (xy 348.600013 -400.04554)
			(xy 348.624054 -400.089963) (xy 348.640455 -400.137737) (xy 348.648768 -400.187559) (xy 348.64929 -400.212814)
			(xy 348.648804 -400.237173) (xy 348.64109 -400.285276) (xy 348.625844 -400.331546) (xy 348.603451 -400.374813)
			(xy 348.589346 -400.394678) (xy 348.583504 -400.402298) (xy 348.578678 -400.420078) (xy 348.586806 -400.506946)
			(xy 348.595188 -400.523456) (xy 348.6023 -400.53006) (xy 348.621413 -400.5482) (xy 348.654931 -400.58886)
			(xy 348.682542 -400.633741) (xy 348.703721 -400.681992) (xy 348.718066 -400.732696) (xy 348.725304 -400.784891)
			(xy 348.725744 -400.811238) (xy 348.725744 -401.674838) (xy 349.162624 -401.674838) (xy 349.162624 -400.811238)
			(xy 349.163064 -400.784892) (xy 349.170313 -400.732701) (xy 349.184665 -400.682002) (xy 349.205847 -400.633755)
			(xy 349.233459 -400.588877) (xy 349.266975 -400.548219) (xy 349.286068 -400.53006) (xy 349.29318 -400.52371)
			(xy 349.301308 -400.506946) (xy 349.30969 -400.420332) (xy 349.30461 -400.402552) (xy 349.299022 -400.394678)
			(xy 349.284868 -400.374834) (xy 349.262412 -400.331574) (xy 349.247101 -400.2853) (xy 349.239322 -400.237184)
			(xy 349.238824 -400.212814) (xy 349.239346 -400.187559) (xy 349.247659 -400.137737) (xy 349.26406 -400.089963)
			(xy 349.288101 -400.04554) (xy 349.319125 -400.00568) (xy 349.356287 -399.97147) (xy 349.398573 -399.943844)
			(xy 349.444829 -399.923554) (xy 349.493794 -399.911154) (xy 349.544132 -399.906983) (xy 349.59447 -399.911154)
			(xy 349.643435 -399.923554) (xy 349.689691 -399.943844) (xy 349.731977 -399.97147) (xy 349.769139 -400.00568)
			(xy 349.800163 -400.04554) (xy 349.824204 -400.089963) (xy 349.840605 -400.137737) (xy 349.848918 -400.187559)
			(xy 349.84944 -400.212814) (xy 349.848964 -400.237186) (xy 349.841205 -400.28531) (xy 349.825886 -400.331585)
			(xy 349.803399 -400.374833) (xy 349.789242 -400.394678) (xy 349.783654 -400.402552) (xy 349.778574 -400.420332)
			(xy 349.786956 -400.506946) (xy 349.795084 -400.52371) (xy 349.802196 -400.53006) (xy 349.821308 -400.548201)
			(xy 349.854827 -400.58886) (xy 349.882438 -400.633741) (xy 349.903617 -400.681992) (xy 349.917962 -400.732696)
			(xy 349.9252 -400.784891) (xy 349.92564 -400.811238) (xy 349.92564 -401.674838) (xy 350.36252 -401.674838)
			(xy 350.36252 -400.811238) (xy 350.362962 -400.784892) (xy 350.37021 -400.732702) (xy 350.384562 -400.682002)
			(xy 350.405744 -400.633756) (xy 350.433355 -400.588877) (xy 350.466871 -400.548219) (xy 350.485964 -400.53006)
			(xy 350.493076 -400.52371) (xy 350.501204 -400.506946) (xy 350.509586 -400.420332) (xy 350.504506 -400.402552)
			(xy 350.498918 -400.394678) (xy 350.484764 -400.374834) (xy 350.462308 -400.331574) (xy 350.446997 -400.2853)
			(xy 350.439218 -400.237184) (xy 350.43872 -400.212814) (xy 350.439242 -400.187559) (xy 350.447555 -400.137737)
			(xy 350.463956 -400.089963) (xy 350.487997 -400.04554) (xy 350.519021 -400.00568) (xy 350.556183 -399.97147)
			(xy 350.598469 -399.943844) (xy 350.644725 -399.923554) (xy 350.69369 -399.911154) (xy 350.744028 -399.906983)
			(xy 350.794366 -399.911154) (xy 350.843331 -399.923554) (xy 350.889587 -399.943844) (xy 350.931873 -399.97147)
			(xy 350.969035 -400.00568) (xy 351.000059 -400.04554) (xy 351.0241 -400.089963) (xy 351.040501 -400.137737)
			(xy 351.048814 -400.187559) (xy 351.049336 -400.212814) (xy 351.04886 -400.237186) (xy 351.041101 -400.28531)
			(xy 351.025783 -400.331585) (xy 351.003296 -400.374833) (xy 350.989138 -400.394678) (xy 350.98355 -400.402552)
			(xy 350.97847 -400.420332) (xy 350.986852 -400.506946) (xy 350.99498 -400.52371) (xy 351.002092 -400.53006)
			(xy 351.021203 -400.548201) (xy 351.054722 -400.588861) (xy 351.082333 -400.633742) (xy 351.103513 -400.681992)
			(xy 351.117858 -400.732696) (xy 351.125096 -400.784891) (xy 351.125536 -400.811238) (xy 351.125536 -401.674838)
			(xy 351.562416 -401.674838) (xy 351.562416 -400.811238) (xy 351.562859 -400.784892) (xy 351.570108 -400.732702)
			(xy 351.584459 -400.682002) (xy 351.605641 -400.633756) (xy 351.633252 -400.588878) (xy 351.666767 -400.548219)
			(xy 351.68586 -400.53006) (xy 351.692972 -400.52371) (xy 351.7011 -400.506946) (xy 351.709482 -400.420332)
			(xy 351.704402 -400.402552) (xy 351.698814 -400.394678) (xy 351.684659 -400.374834) (xy 351.662204 -400.331574)
			(xy 351.646893 -400.2853) (xy 351.639114 -400.237184) (xy 351.638616 -400.212814) (xy 351.639138 -400.187559)
			(xy 351.647451 -400.137737) (xy 351.663852 -400.089963) (xy 351.687893 -400.04554) (xy 351.718917 -400.00568)
			(xy 351.756079 -399.97147) (xy 351.798365 -399.943844) (xy 351.844621 -399.923554) (xy 351.893586 -399.911154)
			(xy 351.943924 -399.906983) (xy 351.994262 -399.911154) (xy 352.043227 -399.923554) (xy 352.089483 -399.943844)
			(xy 352.131769 -399.97147) (xy 352.168931 -400.00568) (xy 352.199955 -400.04554) (xy 352.223996 -400.089963)
			(xy 352.240397 -400.137737) (xy 352.24871 -400.187559) (xy 352.249232 -400.212814) (xy 352.248757 -400.237186)
			(xy 352.240998 -400.28531) (xy 352.225679 -400.331585) (xy 352.203192 -400.374833) (xy 352.189034 -400.394678)
			(xy 352.183446 -400.402552) (xy 352.178366 -400.420332) (xy 352.186748 -400.506946) (xy 352.194876 -400.52371)
			(xy 352.201988 -400.53006) (xy 352.221098 -400.548202) (xy 352.254617 -400.588861) (xy 352.282229 -400.633742)
			(xy 352.303408 -400.681992) (xy 352.317754 -400.732696) (xy 352.324992 -400.784891) (xy 352.325432 -400.811238)
			(xy 352.325432 -401.674838) (xy 352.762312 -401.674838) (xy 352.762312 -400.811238) (xy 352.762801 -400.784883)
			(xy 352.770063 -400.732675) (xy 352.784441 -400.681963) (xy 352.805661 -400.633713) (xy 352.833319 -400.588841)
			(xy 352.866889 -400.548203) (xy 352.88601 -400.53006) (xy 352.893122 -400.52371) (xy 352.90125 -400.506946)
			(xy 352.909632 -400.420332) (xy 352.904552 -400.402552) (xy 352.898964 -400.394678) (xy 352.884815 -400.37483)
			(xy 352.862357 -400.331572) (xy 352.847044 -400.285299) (xy 352.839264 -400.237184) (xy 352.838766 -400.212814)
			(xy 352.839288 -400.187559) (xy 352.847601 -400.137737) (xy 352.864002 -400.089963) (xy 352.888043 -400.04554)
			(xy 352.919067 -400.00568) (xy 352.956229 -399.97147) (xy 352.998515 -399.943844) (xy 353.044771 -399.923554)
			(xy 353.093736 -399.911154) (xy 353.144074 -399.906983) (xy 353.194412 -399.911154) (xy 353.243377 -399.923554)
			(xy 353.289633 -399.943844) (xy 353.331919 -399.97147) (xy 353.369081 -400.00568) (xy 353.400105 -400.04554)
			(xy 353.424146 -400.089963) (xy 353.440547 -400.137737) (xy 353.44886 -400.187559) (xy 353.449382 -400.212814)
			(xy 353.448917 -400.237187) (xy 353.441156 -400.285311) (xy 353.425835 -400.331587) (xy 353.403344 -400.374834)
			(xy 353.389184 -400.394678) (xy 353.383596 -400.402552) (xy 353.378516 -400.420332) (xy 353.386898 -400.506946)
			(xy 353.395026 -400.52371) (xy 353.402138 -400.53006) (xy 353.42127 -400.548196) (xy 353.454858 -400.588826)
			(xy 353.48253 -400.633695) (xy 353.503758 -400.681948) (xy 353.518137 -400.732666) (xy 353.525393 -400.78488)
			(xy 353.525836 -400.811238) (xy 353.525836 -401.674838) (xy 353.525409 -401.701012) (xy 353.518213 -401.752864)
			(xy 353.504 -401.803247) (xy 353.483039 -401.851216) (xy 353.455722 -401.895872) (xy 353.422561 -401.936378)
			(xy 353.403662 -401.954492) (xy 353.396296 -401.96135) (xy 353.388168 -401.978876) (xy 353.382834 -402.069046)
			(xy 353.38893 -402.087334) (xy 353.395534 -402.094954) (xy 353.410439 -402.112994) (xy 353.435502 -402.152513)
			(xy 353.454748 -402.195169) (xy 353.467794 -402.240109) (xy 353.47438 -402.28644) (xy 353.474782 -402.309838)
			(xy 353.474272 -402.335825) (xy 353.466142 -402.38716) (xy 353.450081 -402.43659) (xy 353.426485 -402.4829)
			(xy 353.395935 -402.524948) (xy 353.359184 -402.561699) (xy 353.317136 -402.592249) (xy 353.270826 -402.615845)
			(xy 353.221396 -402.631906) (xy 353.170061 -402.640036) (xy 353.118087 -402.640036) (xy 353.066752 -402.631906)
			(xy 353.017322 -402.615845) (xy 352.971012 -402.592249) (xy 352.928964 -402.561699) (xy 352.892213 -402.524948)
			(xy 352.861663 -402.4829) (xy 352.838067 -402.43659) (xy 352.822006 -402.38716) (xy 352.813876 -402.335825)
			(xy 352.813366 -402.309838) (xy 352.813787 -402.286441) (xy 352.820374 -402.240114) (xy 352.833421 -402.195177)
			(xy 352.852668 -402.152526) (xy 352.877732 -402.113011) (xy 352.892614 -402.094954) (xy 352.899218 -402.087334)
			(xy 352.905314 -402.069046) (xy 352.89998 -401.978876) (xy 352.891852 -401.96135) (xy 352.884486 -401.954492)
			(xy 352.865587 -401.936378) (xy 352.832424 -401.895874) (xy 352.805108 -401.851218) (xy 352.784151 -401.803248)
			(xy 352.769946 -401.752864) (xy 352.76276 -401.701012) (xy 352.762312 -401.674838) (xy 352.325432 -401.674838)
			(xy 352.324981 -401.701002) (xy 352.31783 -401.752838) (xy 352.303667 -401.803213) (xy 352.282757 -401.851181)
			(xy 352.255493 -401.895844) (xy 352.222385 -401.936366) (xy 352.203512 -401.954492) (xy 352.196146 -401.96135)
			(xy 352.188018 -401.978876) (xy 352.182684 -402.069046) (xy 352.18878 -402.087334) (xy 352.195384 -402.094954)
			(xy 352.210282 -402.113) (xy 352.235347 -402.152517) (xy 352.254595 -402.195171) (xy 352.267643 -402.24011)
			(xy 352.27423 -402.28644) (xy 352.274632 -402.309838) (xy 352.274122 -402.335825) (xy 352.265992 -402.38716)
			(xy 352.249931 -402.43659) (xy 352.226335 -402.4829) (xy 352.195785 -402.524948) (xy 352.159034 -402.561699)
			(xy 352.116986 -402.592249) (xy 352.070676 -402.615845) (xy 352.021246 -402.631906) (xy 351.969911 -402.640036)
			(xy 351.917937 -402.640036) (xy 351.866602 -402.631906) (xy 351.817172 -402.615845) (xy 351.770862 -402.592249)
			(xy 351.728814 -402.561699) (xy 351.692063 -402.524948) (xy 351.661513 -402.4829) (xy 351.637917 -402.43659)
			(xy 351.621856 -402.38716) (xy 351.613726 -402.335825) (xy 351.613216 -402.309838) (xy 351.613649 -402.286442)
			(xy 351.620234 -402.240116) (xy 351.633279 -402.195179) (xy 351.652524 -402.152528) (xy 351.677584 -402.113012)
			(xy 351.692464 -402.094954) (xy 351.699068 -402.087334) (xy 351.705164 -402.069046) (xy 351.69983 -401.978876)
			(xy 351.691702 -401.96135) (xy 351.684336 -401.954492) (xy 351.665448 -401.936379) (xy 351.632329 -401.895861)
			(xy 351.605058 -401.851197) (xy 351.584146 -401.803225) (xy 351.569986 -401.752846) (xy 351.562843 -401.701004)
			(xy 351.562416 -401.674838) (xy 351.125536 -401.674838) (xy 351.125002 -401.703743) (xy 351.116297 -401.760893)
			(xy 351.099076 -401.816077) (xy 351.073733 -401.868035) (xy 351.040848 -401.915579) (xy 351.021396 -401.936966)
			(xy 351.0153 -401.94357) (xy 351.008188 -401.959572) (xy 351.0026 -402.041868) (xy 351.007426 -402.058886)
			(xy 351.012506 -402.065998) (xy 351.027149 -402.087223) (xy 351.050399 -402.133246) (xy 351.066223 -402.182321)
			(xy 351.074237 -402.233257) (xy 351.074736 -402.259038) (xy 351.074226 -402.285025) (xy 351.066096 -402.33636)
			(xy 351.050035 -402.38579) (xy 351.026439 -402.4321) (xy 350.995889 -402.474148) (xy 350.959138 -402.510899)
			(xy 350.91709 -402.541449) (xy 350.87078 -402.565045) (xy 350.82135 -402.581106) (xy 350.770015 -402.589236)
			(xy 350.718041 -402.589236) (xy 350.666706 -402.581106) (xy 350.617276 -402.565045) (xy 350.570966 -402.541449)
			(xy 350.528918 -402.510899) (xy 350.492167 -402.474148) (xy 350.461617 -402.4321) (xy 350.438021 -402.38579)
			(xy 350.42196 -402.33636) (xy 350.41383 -402.285025) (xy 350.41332 -402.259038) (xy 350.413789 -402.233254)
			(xy 350.421797 -402.182313) (xy 350.437624 -402.133234) (xy 350.460887 -402.087212) (xy 350.47555 -402.065998)
			(xy 350.48063 -402.058886) (xy 350.485456 -402.041868) (xy 350.479868 -401.959572) (xy 350.472756 -401.94357)
			(xy 350.46666 -401.936966) (xy 350.44717 -401.915609) (xy 350.414265 -401.868069) (xy 350.388916 -401.816106)
			(xy 350.371705 -401.760909) (xy 350.363028 -401.703747) (xy 350.36252 -401.674838) (xy 349.92564 -401.674838)
			(xy 349.925186 -401.701002) (xy 349.918035 -401.752838) (xy 349.903873 -401.803212) (xy 349.882964 -401.85118)
			(xy 349.8557 -401.895844) (xy 349.822593 -401.936366) (xy 349.80372 -401.954492) (xy 349.796354 -401.96135)
			(xy 349.788226 -401.978876) (xy 349.782892 -402.069046) (xy 349.788988 -402.087334) (xy 349.795592 -402.094954)
			(xy 349.810491 -402.112999) (xy 349.835556 -402.152516) (xy 349.854804 -402.19517) (xy 349.867851 -402.24011)
			(xy 349.874438 -402.28644) (xy 349.87484 -402.309838) (xy 349.87433 -402.335825) (xy 349.8662 -402.38716)
			(xy 349.850139 -402.43659) (xy 349.826543 -402.4829) (xy 349.795993 -402.524948) (xy 349.759242 -402.561699)
			(xy 349.717194 -402.592249) (xy 349.670884 -402.615845) (xy 349.621454 -402.631906) (xy 349.570119 -402.640036)
			(xy 349.518145 -402.640036) (xy 349.46681 -402.631906) (xy 349.41738 -402.615845) (xy 349.37107 -402.592249)
			(xy 349.329022 -402.561699) (xy 349.292271 -402.524948) (xy 349.261721 -402.4829) (xy 349.238125 -402.43659)
			(xy 349.222064 -402.38716) (xy 349.213934 -402.335825) (xy 349.213424 -402.309838) (xy 349.213855 -402.286442)
			(xy 349.220441 -402.240116) (xy 349.233486 -402.195179) (xy 349.252731 -402.152528) (xy 349.277791 -402.113012)
			(xy 349.292672 -402.094954) (xy 349.299276 -402.087334) (xy 349.305372 -402.069046) (xy 349.300038 -401.978876)
			(xy 349.29191 -401.96135) (xy 349.284544 -401.954492) (xy 349.265658 -401.936377) (xy 349.232538 -401.89586)
			(xy 349.205267 -401.851196) (xy 349.184354 -401.803225) (xy 349.170194 -401.752845) (xy 349.163051 -401.701004)
			(xy 349.162624 -401.674838) (xy 348.725744 -401.674838) (xy 348.725289 -401.701002) (xy 348.718138 -401.752838)
			(xy 348.703976 -401.803212) (xy 348.683067 -401.85118) (xy 348.655804 -401.895844) (xy 348.622696 -401.936366)
			(xy 348.603824 -401.954492) (xy 348.596458 -401.96135) (xy 348.58833 -401.978876) (xy 348.582996 -402.069046)
			(xy 348.589092 -402.087334) (xy 348.595696 -402.094954) (xy 348.610595 -402.112999) (xy 348.63566 -402.152516)
			(xy 348.654908 -402.19517) (xy 348.667955 -402.24011) (xy 348.674542 -402.28644) (xy 348.674944 -402.309838)
			(xy 348.674434 -402.335825) (xy 348.666304 -402.38716) (xy 348.650243 -402.43659) (xy 348.626647 -402.4829)
			(xy 348.596097 -402.524948) (xy 348.559346 -402.561699) (xy 348.517298 -402.592249) (xy 348.470988 -402.615845)
			(xy 348.421558 -402.631906) (xy 348.370223 -402.640036) (xy 348.318249 -402.640036) (xy 348.266914 -402.631906)
			(xy 348.217484 -402.615845) (xy 348.171174 -402.592249) (xy 348.129126 -402.561699) (xy 348.092375 -402.524948)
			(xy 348.061825 -402.4829) (xy 348.038229 -402.43659) (xy 348.022168 -402.38716) (xy 348.014038 -402.335825)
			(xy 348.013528 -402.309838) (xy 348.013958 -402.286442) (xy 348.020544 -402.240116) (xy 348.033589 -402.195179)
			(xy 348.052834 -402.152527) (xy 348.077895 -402.113012) (xy 348.092776 -402.094954) (xy 348.09938 -402.087334)
			(xy 348.105476 -402.069046) (xy 348.100142 -401.978876) (xy 348.092014 -401.96135) (xy 348.084648 -401.954492)
			(xy 348.065763 -401.936377) (xy 348.032643 -401.895859) (xy 348.005371 -401.851196) (xy 347.984459 -401.803224)
			(xy 347.970298 -401.752845) (xy 347.963155 -401.701004) (xy 347.962728 -401.674838) (xy 347.525848 -401.674838)
			(xy 347.525418 -401.701012) (xy 347.518221 -401.752863) (xy 347.504009 -401.803246) (xy 347.483049 -401.851215)
			(xy 347.455732 -401.895871) (xy 347.422572 -401.936377) (xy 347.403674 -401.954492) (xy 347.396308 -401.96135)
			(xy 347.38818 -401.978876) (xy 347.382846 -402.069046) (xy 347.388942 -402.087334) (xy 347.395546 -402.094954)
			(xy 347.410453 -402.112993) (xy 347.435515 -402.152512) (xy 347.45476 -402.195168) (xy 347.467806 -402.240109)
			(xy 347.474392 -402.28644) (xy 347.474794 -402.309838) (xy 347.474284 -402.335825) (xy 347.466154 -402.38716)
			(xy 347.450093 -402.43659) (xy 347.426497 -402.4829) (xy 347.395947 -402.524948) (xy 347.359196 -402.561699)
			(xy 347.317148 -402.592249) (xy 347.270838 -402.615845) (xy 347.221408 -402.631906) (xy 347.170073 -402.640036)
			(xy 347.118099 -402.640036) (xy 347.066764 -402.631906) (xy 347.017334 -402.615845) (xy 346.971024 -402.592249)
			(xy 346.928976 -402.561699) (xy 346.892225 -402.524948) (xy 346.861675 -402.4829) (xy 346.838079 -402.43659)
			(xy 346.822018 -402.38716) (xy 346.813888 -402.335825) (xy 346.813378 -402.309838) (xy 346.813796 -402.286441)
			(xy 346.820383 -402.240114) (xy 346.83343 -402.195177) (xy 346.852678 -402.152525) (xy 346.877743 -402.113011)
			(xy 346.892626 -402.094954) (xy 346.89923 -402.087334) (xy 346.905326 -402.069046) (xy 346.899992 -401.978876)
			(xy 346.891864 -401.96135) (xy 346.884498 -401.954492) (xy 346.865601 -401.936376) (xy 346.832438 -401.895873)
			(xy 346.805121 -401.851218) (xy 346.784164 -401.803248) (xy 346.769958 -401.752864) (xy 346.762772 -401.701012)
			(xy 346.762324 -401.674838) (xy 346.325952 -401.674838) (xy 346.32552 -401.701012) (xy 346.318324 -401.752863)
			(xy 346.304112 -401.803246) (xy 346.283152 -401.851215) (xy 346.255836 -401.895871) (xy 346.222676 -401.936377)
			(xy 346.203778 -401.954492) (xy 346.196412 -401.96135) (xy 346.188284 -401.978876) (xy 346.18295 -402.069046)
			(xy 346.189046 -402.087334) (xy 346.19565 -402.094954) (xy 346.210558 -402.112992) (xy 346.235619 -402.152512)
			(xy 346.254865 -402.195168) (xy 346.26791 -402.240109) (xy 346.274496 -402.28644) (xy 346.274898 -402.309838)
			(xy 346.274388 -402.335825) (xy 346.266258 -402.38716) (xy 346.250197 -402.43659) (xy 346.226601 -402.4829)
			(xy 346.196051 -402.524948) (xy 346.1593 -402.561699) (xy 346.117252 -402.592249) (xy 346.070942 -402.615845)
			(xy 346.021512 -402.631906) (xy 345.970177 -402.640036) (xy 345.918203 -402.640036) (xy 345.866868 -402.631906)
			(xy 345.817438 -402.615845) (xy 345.771128 -402.592249) (xy 345.72908 -402.561699) (xy 345.692329 -402.524948)
			(xy 345.661779 -402.4829) (xy 345.638183 -402.43659) (xy 345.622122 -402.38716) (xy 345.613992 -402.335825)
			(xy 345.613482 -402.309838) (xy 345.613923 -402.286442) (xy 345.620508 -402.240117) (xy 345.633551 -402.195181)
			(xy 345.652793 -402.152529) (xy 345.677851 -402.113013) (xy 345.69273 -402.094954) (xy 345.699334 -402.087334)
			(xy 345.70543 -402.069046) (xy 345.700096 -401.978876) (xy 345.691968 -401.96135) (xy 345.684602 -401.954492)
			(xy 345.665706 -401.936375) (xy 345.632543 -401.895872) (xy 345.605226 -401.851217) (xy 345.584268 -401.803248)
			(xy 345.570062 -401.752864) (xy 345.562876 -401.701012) (xy 345.562428 -401.674838) (xy 345.125548 -401.674838)
			(xy 345.124991 -401.704987) (xy 345.115535 -401.764538) (xy 345.096832 -401.821862) (xy 345.069348 -401.875532)
			(xy 345.033767 -401.924212) (xy 345.012772 -401.945856) (xy 345.006168 -401.95246) (xy 344.998548 -401.969224)
			(xy 344.993214 -402.05533) (xy 344.998548 -402.07311) (xy 345.00439 -402.080476) (xy 345.020901 -402.102461)
			(xy 345.047174 -402.150756) (xy 345.065104 -402.202728) (xy 345.0742 -402.256949) (xy 345.074748 -402.284438)
			(xy 345.074238 -402.310425) (xy 345.066108 -402.36176) (xy 345.050047 -402.41119) (xy 345.026451 -402.4575)
			(xy 344.995901 -402.499548) (xy 344.95915 -402.536299) (xy 344.917102 -402.566849) (xy 344.870792 -402.590445)
			(xy 344.821362 -402.606506) (xy 344.770027 -402.614636) (xy 344.718053 -402.614636) (xy 344.666718 -402.606506)
			(xy 344.617288 -402.590445) (xy 344.570978 -402.566849) (xy 344.52893 -402.536299) (xy 344.492179 -402.499548)
			(xy 344.461629 -402.4575) (xy 344.438033 -402.41119) (xy 344.421972 -402.36176) (xy 344.413842 -402.310425)
			(xy 344.413332 -402.284438) (xy 344.413878 -402.256947) (xy 344.422955 -402.20272) (xy 344.440882 -402.150744)
			(xy 344.467164 -402.102451) (xy 344.48369 -402.080476) (xy 344.489532 -402.07311) (xy 344.494866 -402.05533)
			(xy 344.489532 -401.969224) (xy 344.481912 -401.95246) (xy 344.475308 -401.945856) (xy 344.454314 -401.924209)
			(xy 344.418722 -401.875535) (xy 344.391232 -401.821867) (xy 344.37253 -401.764542) (xy 344.363082 -401.704988)
			(xy 344.362532 -401.674838) (xy 343.925652 -401.674838) (xy 343.925114 -401.703742) (xy 343.916409 -401.760892)
			(xy 343.899189 -401.816076) (xy 343.873847 -401.868034) (xy 343.840963 -401.915579) (xy 343.821512 -401.936966)
			(xy 343.815416 -401.94357) (xy 343.808304 -401.959572) (xy 343.802716 -402.041868) (xy 343.807542 -402.058886)
			(xy 343.812622 -402.065998) (xy 343.827255 -402.08723) (xy 343.85051 -402.13325) (xy 343.866337 -402.182322)
			(xy 343.874353 -402.233257) (xy 343.874852 -402.259038) (xy 343.874342 -402.285025) (xy 343.866212 -402.33636)
			(xy 343.850151 -402.38579) (xy 343.826555 -402.4321) (xy 343.796005 -402.474148) (xy 343.759254 -402.510899)
			(xy 343.717206 -402.541449) (xy 343.670896 -402.565045) (xy 343.621466 -402.581106) (xy 343.570131 -402.589236)
			(xy 343.518157 -402.589236) (xy 343.466822 -402.581106) (xy 343.417392 -402.565045) (xy 343.371082 -402.541449)
			(xy 343.329034 -402.510899) (xy 343.292283 -402.474148) (xy 343.261733 -402.4321) (xy 343.238137 -402.38579)
			(xy 343.222076 -402.33636) (xy 343.213946 -402.285025) (xy 343.213436 -402.259038) (xy 343.21392 -402.233255)
			(xy 343.221926 -402.182315) (xy 343.237749 -402.133237) (xy 343.261006 -402.087213) (xy 343.275666 -402.065998)
			(xy 343.280746 -402.058886) (xy 343.285572 -402.041868) (xy 343.279984 -401.959572) (xy 343.272872 -401.94357)
			(xy 343.266776 -401.936966) (xy 343.247289 -401.915607) (xy 343.214382 -401.868068) (xy 343.189033 -401.816105)
			(xy 343.171821 -401.760909) (xy 343.163144 -401.703747) (xy 343.162636 -401.674838) (xy 342.725756 -401.674838)
			(xy 342.725324 -401.701012) (xy 342.718127 -401.752863) (xy 342.703916 -401.803246) (xy 342.682956 -401.851215)
			(xy 342.65564 -401.895871) (xy 342.62248 -401.936378) (xy 342.603582 -401.954492) (xy 342.596216 -401.96135)
			(xy 342.588088 -401.978876) (xy 342.582754 -402.069046) (xy 342.58885 -402.087334) (xy 342.595454 -402.094954)
			(xy 342.610347 -402.113004) (xy 342.635414 -402.152519) (xy 342.654664 -402.195172) (xy 342.667713 -402.240111)
			(xy 342.6743 -402.28644) (xy 342.674702 -402.309838) (xy 342.674192 -402.335825) (xy 342.666062 -402.38716)
			(xy 342.650001 -402.43659) (xy 342.626405 -402.4829) (xy 342.595855 -402.524948) (xy 342.559104 -402.561699)
			(xy 342.517056 -402.592249) (xy 342.470746 -402.615845) (xy 342.421316 -402.631906) (xy 342.369981 -402.640036)
			(xy 342.318007 -402.640036) (xy 342.266672 -402.631906) (xy 342.217242 -402.615845) (xy 342.170932 -402.592249)
			(xy 342.128884 -402.561699) (xy 342.092133 -402.524948) (xy 342.061583 -402.4829) (xy 342.037987 -402.43659)
			(xy 342.021926 -402.38716) (xy 342.013796 -402.335825) (xy 342.013286 -402.309838) (xy 342.013726 -402.286442)
			(xy 342.020311 -402.240117) (xy 342.033354 -402.19518) (xy 342.052597 -402.152529) (xy 342.077655 -402.113013)
			(xy 342.092534 -402.094954) (xy 342.099138 -402.087334) (xy 342.105234 -402.069046) (xy 342.0999 -401.978876)
			(xy 342.091772 -401.96135) (xy 342.084406 -401.954492) (xy 342.065511 -401.936375) (xy 342.032347 -401.895872)
			(xy 342.00503 -401.851217) (xy 341.984072 -401.803247) (xy 341.969866 -401.752864) (xy 341.96268 -401.701012)
			(xy 341.962232 -401.674838) (xy 341.52586 -401.674838) (xy 341.525457 -401.701013) (xy 341.518259 -401.752867)
			(xy 341.504044 -401.803251) (xy 341.483078 -401.851221) (xy 341.455756 -401.895876) (xy 341.422588 -401.93638)
			(xy 341.403686 -401.954492) (xy 341.39632 -401.96135) (xy 341.388192 -401.978876) (xy 341.382858 -402.069046)
			(xy 341.388954 -402.087334) (xy 341.395558 -402.094954) (xy 341.410452 -402.113004) (xy 341.435518 -402.152519)
			(xy 341.454768 -402.195172) (xy 341.467817 -402.240111) (xy 341.474404 -402.28644) (xy 341.474806 -402.309838)
			(xy 341.474296 -402.335825) (xy 341.466166 -402.38716) (xy 341.450105 -402.43659) (xy 341.426509 -402.4829)
			(xy 341.395959 -402.524948) (xy 341.359208 -402.561699) (xy 341.31716 -402.592249) (xy 341.27085 -402.615845)
			(xy 341.22142 -402.631906) (xy 341.170085 -402.640036) (xy 341.118111 -402.640036) (xy 341.066776 -402.631906)
			(xy 341.017346 -402.615845) (xy 340.971036 -402.592249) (xy 340.928988 -402.561699) (xy 340.892237 -402.524948)
			(xy 340.861687 -402.4829) (xy 340.838091 -402.43659) (xy 340.82203 -402.38716) (xy 340.8139 -402.335825)
			(xy 340.81339 -402.309838) (xy 340.813829 -402.286442) (xy 340.820414 -402.240117) (xy 340.833458 -402.19518)
			(xy 340.852701 -402.152529) (xy 340.877759 -402.113013) (xy 340.892638 -402.094954) (xy 340.899242 -402.087334)
			(xy 340.905338 -402.069046) (xy 340.900004 -401.978876) (xy 340.891876 -401.96135) (xy 340.88451 -401.954492)
			(xy 340.865616 -401.936374) (xy 340.832452 -401.895871) (xy 340.805134 -401.851217) (xy 340.784176 -401.803247)
			(xy 340.76997 -401.752864) (xy 340.762784 -401.701012) (xy 340.762336 -401.674838) (xy 340.325456 -401.674838)
			(xy 340.324917 -401.703742) (xy 340.316212 -401.760892) (xy 340.298992 -401.816076) (xy 340.273651 -401.868034)
			(xy 340.240767 -401.915579) (xy 340.221316 -401.936966) (xy 340.21522 -401.94357) (xy 340.208108 -401.959572)
			(xy 340.20252 -402.041868) (xy 340.207346 -402.058886) (xy 340.212426 -402.065998) (xy 340.227059 -402.08723)
			(xy 340.250314 -402.13325) (xy 340.266141 -402.182322) (xy 340.274157 -402.233257) (xy 340.274656 -402.259038)
			(xy 340.274146 -402.285025) (xy 340.266016 -402.33636) (xy 340.249955 -402.38579) (xy 340.226359 -402.4321)
			(xy 340.195809 -402.474148) (xy 340.159058 -402.510899) (xy 340.11701 -402.541449) (xy 340.0707 -402.565045)
			(xy 340.02127 -402.581106) (xy 339.969935 -402.589236) (xy 339.917961 -402.589236) (xy 339.866626 -402.581106)
			(xy 339.817196 -402.565045) (xy 339.770886 -402.541449) (xy 339.728838 -402.510899) (xy 339.692087 -402.474148)
			(xy 339.661537 -402.4321) (xy 339.637941 -402.38579) (xy 339.62188 -402.33636) (xy 339.61375 -402.285025)
			(xy 339.61324 -402.259038) (xy 339.613723 -402.233255) (xy 339.621729 -402.182314) (xy 339.637553 -402.133236)
			(xy 339.660809 -402.087213) (xy 339.67547 -402.065998) (xy 339.68055 -402.058886) (xy 339.685376 -402.041868)
			(xy 339.679788 -401.959572) (xy 339.672676 -401.94357) (xy 339.66658 -401.936966) (xy 339.647094 -401.915606)
			(xy 339.614187 -401.868068) (xy 339.588837 -401.816105) (xy 339.571625 -401.760909) (xy 339.562948 -401.703747)
			(xy 339.56244 -401.674838) (xy 339.12556 -401.674838) (xy 339.1251 -401.701001) (xy 339.11795 -401.752837)
			(xy 339.103788 -401.803211) (xy 339.08288 -401.851179) (xy 339.055618 -401.895843) (xy 339.022512 -401.936366)
			(xy 339.00364 -401.954492) (xy 338.996274 -401.96135) (xy 338.988146 -401.978876) (xy 338.982812 -402.069046)
			(xy 338.988908 -402.087334) (xy 338.995512 -402.094954) (xy 339.010414 -402.112997) (xy 339.035478 -402.152515)
			(xy 339.054725 -402.195169) (xy 339.067772 -402.24011) (xy 339.074358 -402.28644) (xy 339.07476 -402.309838)
			(xy 339.07425 -402.335825) (xy 339.06612 -402.38716) (xy 339.050059 -402.43659) (xy 339.026463 -402.4829)
			(xy 338.995913 -402.524948) (xy 338.959162 -402.561699) (xy 338.917114 -402.592249) (xy 338.870804 -402.615845)
			(xy 338.821374 -402.631906) (xy 338.770039 -402.640036) (xy 338.718065 -402.640036) (xy 338.66673 -402.631906)
			(xy 338.6173 -402.615845) (xy 338.57099 -402.592249) (xy 338.528942 -402.561699) (xy 338.492191 -402.524948)
			(xy 338.461641 -402.4829) (xy 338.438045 -402.43659) (xy 338.421984 -402.38716) (xy 338.413854 -402.335825)
			(xy 338.413344 -402.309838) (xy 338.41377 -402.286442) (xy 338.420356 -402.240115) (xy 338.433402 -402.195178)
			(xy 338.452648 -402.152527) (xy 338.47771 -402.113012) (xy 338.492592 -402.094954) (xy 338.499196 -402.087334)
			(xy 338.505292 -402.069046) (xy 338.499958 -401.978876) (xy 338.49183 -401.96135) (xy 338.484464 -401.954492)
			(xy 338.465563 -401.936393) (xy 338.432448 -401.89587) (xy 338.40518 -401.851203) (xy 338.384271 -401.803229)
			(xy 338.370113 -401.752847) (xy 338.362971 -401.701004) (xy 338.362544 -401.674838) (xy 337.925664 -401.674838)
			(xy 337.925049 -401.704996) (xy 337.915555 -401.764559) (xy 337.89681 -401.821888) (xy 337.869281 -401.875554)
			(xy 337.833653 -401.924222) (xy 337.812634 -401.945856) (xy 337.80603 -401.95246) (xy 337.79841 -401.969224)
			(xy 337.793076 -402.05533) (xy 337.79841 -402.07311) (xy 337.804252 -402.080476) (xy 337.820758 -402.102465)
			(xy 337.847033 -402.150758) (xy 337.864965 -402.202729) (xy 337.874061 -402.256949) (xy 337.87461 -402.284438)
			(xy 337.8741 -402.310425) (xy 337.86597 -402.36176) (xy 337.849909 -402.41119) (xy 337.826313 -402.4575)
			(xy 337.795763 -402.499548) (xy 337.759012 -402.536299) (xy 337.716964 -402.566849) (xy 337.670654 -402.590445)
			(xy 337.621224 -402.606506) (xy 337.569889 -402.614636) (xy 337.517915 -402.614636) (xy 337.46658 -402.606506)
			(xy 337.41715 -402.590445) (xy 337.37084 -402.566849) (xy 337.328792 -402.536299) (xy 337.292041 -402.499548)
			(xy 337.261491 -402.4575) (xy 337.237895 -402.41119) (xy 337.221834 -402.36176) (xy 337.213704 -402.310425)
			(xy 337.213194 -402.284438) (xy 337.213748 -402.256948) (xy 337.222824 -402.202722) (xy 337.240748 -402.150745)
			(xy 337.267027 -402.102452) (xy 337.283552 -402.080476) (xy 337.289394 -402.07311) (xy 337.294728 -402.05533)
			(xy 337.289394 -401.969224) (xy 337.281774 -401.95246) (xy 337.27517 -401.945856) (xy 337.254126 -401.924242)
			(xy 337.21848 -401.875577) (xy 337.190941 -401.821908) (xy 337.172194 -401.764572) (xy 337.162707 -401.705)
			(xy 337.16214 -401.674838) (xy 336.725768 -401.674838) (xy 336.725152 -401.704996) (xy 336.715658 -401.764559)
			(xy 336.696913 -401.821888) (xy 336.669384 -401.875554) (xy 336.633756 -401.924222) (xy 336.612738 -401.945856)
			(xy 336.606134 -401.95246) (xy 336.598514 -401.969224) (xy 336.59318 -402.05533) (xy 336.598514 -402.07311)
			(xy 336.604356 -402.080476) (xy 336.620862 -402.102465) (xy 336.647137 -402.150758) (xy 336.665069 -402.202729)
			(xy 336.674165 -402.256949) (xy 336.674714 -402.284438) (xy 336.674204 -402.310425) (xy 336.666074 -402.36176)
			(xy 336.650013 -402.41119) (xy 336.626417 -402.4575) (xy 336.595867 -402.499548) (xy 336.559116 -402.536299)
			(xy 336.517068 -402.566849) (xy 336.470758 -402.590445) (xy 336.421328 -402.606506) (xy 336.369993 -402.614636)
			(xy 336.318019 -402.614636) (xy 336.266684 -402.606506) (xy 336.217254 -402.590445) (xy 336.170944 -402.566849)
			(xy 336.128896 -402.536299) (xy 336.092145 -402.499548) (xy 336.061595 -402.4575) (xy 336.037999 -402.41119)
			(xy 336.021938 -402.36176) (xy 336.013808 -402.310425) (xy 336.013298 -402.284438) (xy 336.013851 -402.256948)
			(xy 336.022927 -402.202722) (xy 336.040852 -402.150745) (xy 336.067131 -402.102452) (xy 336.083656 -402.080476)
			(xy 336.089498 -402.07311) (xy 336.094832 -402.05533) (xy 336.089498 -401.969224) (xy 336.081878 -401.95246)
			(xy 336.075274 -401.945856) (xy 336.05423 -401.924242) (xy 336.018585 -401.875577) (xy 335.991045 -401.821908)
			(xy 335.972298 -401.764572) (xy 335.962811 -401.705) (xy 335.962244 -401.674838) (xy 332.230635 -401.674838)
			(xy 332.259273 -401.719145) (xy 332.282111 -401.76889) (xy 332.297605 -401.821388) (xy 332.305437 -401.875562)
			(xy 332.305914 -401.90293) (xy 332.30545 -401.930182) (xy 332.29769 -401.98413) (xy 332.282331 -402.036425)
			(xy 332.259687 -402.086002) (xy 332.230218 -402.131852) (xy 332.194524 -402.173041) (xy 332.153332 -402.208732)
			(xy 332.107481 -402.238198) (xy 332.057902 -402.260839) (xy 332.005606 -402.276195) (xy 331.951658 -402.283952)
			(xy 331.924406 -402.284438) (xy 331.897035 -402.283984) (xy 331.842855 -402.276165) (xy 331.790351 -402.260674)
			(xy 331.740604 -402.23783) (xy 331.694639 -402.208101) (xy 331.673708 -402.190458) (xy 331.666596 -402.184362)
			(xy 331.649578 -402.178012) (xy 331.564234 -402.178012) (xy 331.547216 -402.184362) (xy 331.540104 -402.190458)
			(xy 331.519171 -402.208099) (xy 331.473203 -402.237823) (xy 331.423457 -402.260669) (xy 331.370955 -402.276165)
			(xy 331.316777 -402.283994) (xy 331.262035 -402.283994) (xy 331.207857 -402.276165) (xy 331.155355 -402.260669)
			(xy 331.105609 -402.237823) (xy 331.059641 -402.208099) (xy 331.038708 -402.190458) (xy 331.031596 -402.184362)
			(xy 331.014578 -402.178012) (xy 330.929234 -402.178012) (xy 330.912216 -402.184362) (xy 330.905104 -402.190458)
			(xy 330.884171 -402.208099) (xy 330.838203 -402.237823) (xy 330.788457 -402.260669) (xy 330.735955 -402.276165)
			(xy 330.681777 -402.283994) (xy 330.627035 -402.283994) (xy 330.572857 -402.276165) (xy 330.520355 -402.260669)
			(xy 330.470609 -402.237823) (xy 330.424641 -402.208099) (xy 330.403708 -402.190458) (xy 330.396596 -402.184362)
			(xy 330.379578 -402.178012) (xy 330.294234 -402.178012) (xy 330.277216 -402.184362) (xy 330.270104 -402.190458)
			(xy 330.249176 -402.208102) (xy 330.203203 -402.237815) (xy 330.153454 -402.26065) (xy 330.100952 -402.27614)
			(xy 330.046776 -402.283966) (xy 330.019406 -402.284438) (xy 329.992156 -402.283917) (xy 329.938211 -402.276162)
			(xy 329.885919 -402.260809) (xy 329.836344 -402.238171) (xy 329.790495 -402.208708) (xy 329.749305 -402.17302)
			(xy 329.713614 -402.131834) (xy 329.684147 -402.085988) (xy 329.661504 -402.036415) (xy 329.646146 -401.984124)
			(xy 329.638386 -401.93018) (xy 329.637898 -401.90293) (xy 328.782934 -401.90293) (xy 328.782468 -401.93366)
			(xy 328.775057 -401.994673) (xy 328.760346 -402.054347) (xy 328.73855 -402.111813) (xy 328.709986 -402.166233)
			(xy 328.675071 -402.216814) (xy 328.634315 -402.262818) (xy 328.588311 -402.303574) (xy 328.53773 -402.338488)
			(xy 328.483309 -402.367051) (xy 328.425843 -402.388847) (xy 328.366169 -402.403558) (xy 328.305156 -402.410968)
			(xy 328.274426 -402.411438) (xy 328.243732 -402.410955) (xy 328.182796 -402.403526) (xy 328.123195 -402.38882)
			(xy 328.065796 -402.367052) (xy 328.011432 -402.338538) (xy 327.985882 -402.321522) (xy 327.97713 -402.316051)
			(xy 327.956926 -402.311923) (xy 327.936722 -402.316051) (xy 327.92797 -402.321522) (xy 327.898467 -402.341198)
			(xy 327.835085 -402.373005) (xy 327.76789 -402.395671) (xy 327.733152 -402.402802) (xy 327.718928 -402.405342)
			(xy 327.6981 -402.423884) (xy 327.667366 -402.523452) (xy 327.665035 -402.532401) (xy 327.666211 -402.550841)
			(xy 327.673831 -402.567674) (xy 327.680066 -402.574506) (xy 327.839578 -402.734018) (xy 334.732628 -402.734018)
			(xy 334.736699 -402.678396) (xy 334.748825 -402.623959) (xy 334.768748 -402.571868) (xy 334.796044 -402.523233)
			(xy 334.83013 -402.47909) (xy 334.870279 -402.440381) (xy 334.915637 -402.40793) (xy 334.965237 -402.382429)
			(xy 335.018021 -402.364422) (xy 335.072864 -402.354292) (xy 335.128598 -402.352255) (xy 335.184035 -402.358355)
			(xy 335.237992 -402.372461) (xy 335.289321 -402.394273) (xy 335.336927 -402.423327) (xy 335.379795 -402.459002)
			(xy 335.417012 -402.500539) (xy 335.447785 -402.547052) (xy 335.471457 -402.597549) (xy 335.487525 -402.650956)
			(xy 335.495645 -402.706132) (xy 335.496154 -402.734018) (xy 335.495645 -402.761904) (xy 335.487525 -402.81708)
			(xy 335.471457 -402.870487) (xy 335.447785 -402.920984) (xy 335.417012 -402.967497) (xy 335.379795 -403.009034)
			(xy 335.336927 -403.044709) (xy 335.289321 -403.073763) (xy 335.237992 -403.095575) (xy 335.184035 -403.109681)
			(xy 335.128598 -403.115781) (xy 335.072864 -403.113744) (xy 335.018021 -403.103614) (xy 334.965237 -403.085607)
			(xy 334.915637 -403.060106) (xy 334.870279 -403.027655) (xy 334.83013 -402.988946) (xy 334.796044 -402.944803)
			(xy 334.768748 -402.896168) (xy 334.748825 -402.844077) (xy 334.736699 -402.78964) (xy 334.732628 -402.734018)
			(xy 327.839578 -402.734018) (xy 328.518012 -403.412452) (xy 328.525425 -403.419129) (xy 328.54386 -403.426698)
			(xy 328.553826 -403.427184)
		)
		(stroke
			(width 0)
			(type solid)
		)
		(fill yes)
		(layer "In2.Cu")
		(net "P0V9_CPU0_RT1_2A_2D")
	)
	(gr_poly
		(pts
			(xy 47.233586 -392.588242) (xy 47.243648 -392.587802) (xy 47.262224 -392.580059) (xy 47.269654 -392.573256)
			(xy 47.428658 -392.414252) (xy 47.436024 -392.398758) (xy 47.436786 -392.389868) (xy 47.440153 -392.362387)
			(xy 47.453794 -392.308728) (xy 47.475034 -392.2576) (xy 47.50343 -392.210071) (xy 47.538387 -392.167137)
			(xy 47.558452 -392.14806) (xy 47.56531 -392.14171) (xy 47.573692 -392.124946) (xy 47.581058 -392.047476)
			(xy 47.58155 -392.038302) (xy 47.576739 -392.020586) (xy 47.57166 -392.012932) (xy 47.571406 -392.012678)
			(xy 47.557247 -391.992834) (xy 47.534756 -391.949587) (xy 47.519435 -391.903311) (xy 47.511675 -391.855187)
			(xy 47.511208 -391.830814) (xy 47.51173 -391.805559) (xy 47.520043 -391.755737) (xy 47.536444 -391.707963)
			(xy 47.560485 -391.66354) (xy 47.591509 -391.62368) (xy 47.628671 -391.58947) (xy 47.670957 -391.561844)
			(xy 47.717213 -391.541554) (xy 47.766178 -391.529154) (xy 47.816516 -391.524983) (xy 47.866854 -391.529154)
			(xy 47.915819 -391.541554) (xy 47.962075 -391.561844) (xy 48.004361 -391.58947) (xy 48.041523 -391.62368)
			(xy 48.072547 -391.66354) (xy 48.096588 -391.707963) (xy 48.112989 -391.755737) (xy 48.121302 -391.805559)
			(xy 48.121824 -391.830814) (xy 48.121356 -391.855144) (xy 48.113639 -391.903189) (xy 48.098387 -391.949397)
			(xy 48.075988 -391.992596) (xy 48.06188 -392.012424) (xy 48.061372 -392.012932) (xy 48.056038 -392.020298)
			(xy 48.051212 -392.038332) (xy 48.058578 -392.115548) (xy 48.059824 -392.124768) (xy 48.068039 -392.141443)
			(xy 48.07458 -392.14806) (xy 48.096625 -392.169051) (xy 48.134406 -392.216774) (xy 48.149764 -392.243056)
			(xy 48.154478 -392.250708) (xy 48.168141 -392.262369) (xy 48.18498 -392.268623) (xy 48.19396 -392.268964)
			(xy 48.638968 -392.268964) (xy 48.647951 -392.26861) (xy 48.664805 -392.262392) (xy 48.678457 -392.250716)
			(xy 48.683164 -392.243056) (xy 48.698552 -392.216795) (xy 48.736328 -392.169073) (xy 48.758348 -392.14806)
			(xy 48.764957 -392.141395) (xy 48.77328 -392.124588) (xy 48.774604 -392.115294) (xy 48.78197 -392.038332)
			(xy 48.77689 -392.020044) (xy 48.771302 -392.012678) (xy 48.757215 -391.992839) (xy 48.734847 -391.949633)
			(xy 48.719604 -391.903429) (xy 48.711872 -391.855394) (xy 48.711358 -391.831068) (xy 48.711358 -391.830814)
			(xy 48.71188 -391.805559) (xy 48.720193 -391.755737) (xy 48.736594 -391.707963) (xy 48.760635 -391.66354)
			(xy 48.791659 -391.62368) (xy 48.828821 -391.58947) (xy 48.871107 -391.561844) (xy 48.917363 -391.541554)
			(xy 48.966328 -391.529154) (xy 49.016666 -391.524983) (xy 49.067004 -391.529154) (xy 49.115969 -391.541554)
			(xy 49.162225 -391.561844) (xy 49.204511 -391.58947) (xy 49.241673 -391.62368) (xy 49.272697 -391.66354)
			(xy 49.296738 -391.707963) (xy 49.313139 -391.755737) (xy 49.321452 -391.805559) (xy 49.321974 -391.830814)
			(xy 49.321496 -391.855216) (xy 49.313736 -391.903398) (xy 49.298418 -391.949735) (xy 49.275929 -391.993048)
			(xy 49.261776 -392.012932) (xy 49.256188 -392.020298) (xy 49.251108 -392.038586) (xy 49.258474 -392.115548)
			(xy 49.259686 -392.124873) (xy 49.268037 -392.141709) (xy 49.27473 -392.148314) (xy 49.29669 -392.169262)
			(xy 49.334336 -392.21686) (xy 49.34966 -392.243056) (xy 49.354374 -392.250709) (xy 49.368037 -392.26237)
			(xy 49.384876 -392.268625) (xy 49.393856 -392.268964) (xy 49.839118 -392.268964) (xy 49.848105 -392.268619)
			(xy 49.864973 -392.262411) (xy 49.878639 -392.250738) (xy 49.883314 -392.243056) (xy 49.8987 -392.216793)
			(xy 49.936473 -392.169068) (xy 49.958498 -392.14806) (xy 49.965356 -392.14171) (xy 49.973738 -392.124946)
			(xy 49.981104 -392.047476) (xy 49.981597 -392.038302) (xy 49.976789 -392.020584) (xy 49.971706 -392.012932)
			(xy 49.971452 -392.012678) (xy 49.957295 -391.992833) (xy 49.934808 -391.949585) (xy 49.91949 -391.90331)
			(xy 49.911731 -391.855186) (xy 49.911254 -391.830814) (xy 49.911776 -391.805559) (xy 49.920089 -391.755737)
			(xy 49.93649 -391.707963) (xy 49.960531 -391.66354) (xy 49.991555 -391.62368) (xy 50.028717 -391.58947)
			(xy 50.071003 -391.561844) (xy 50.117259 -391.541554) (xy 50.166224 -391.529154) (xy 50.216562 -391.524983)
			(xy 50.2669 -391.529154) (xy 50.315865 -391.541554) (xy 50.362121 -391.561844) (xy 50.404407 -391.58947)
			(xy 50.441569 -391.62368) (xy 50.472593 -391.66354) (xy 50.496634 -391.707963) (xy 50.513035 -391.755737)
			(xy 50.521348 -391.805559) (xy 50.52187 -391.830814) (xy 50.521402 -391.855145) (xy 50.513686 -391.90319)
			(xy 50.498436 -391.949399) (xy 50.47604 -391.9926) (xy 50.461926 -392.012424) (xy 50.461418 -392.012932)
			(xy 50.456084 -392.020298) (xy 50.451258 -392.038332) (xy 50.458624 -392.115548) (xy 50.459872 -392.124767)
			(xy 50.468092 -392.141436) (xy 50.474626 -392.14806) (xy 50.496669 -392.169052) (xy 50.534446 -392.216778)
			(xy 50.54981 -392.243056) (xy 50.554527 -392.250703) (xy 50.568192 -392.262352) (xy 50.585029 -392.26859)
			(xy 50.594006 -392.268964) (xy 51.039014 -392.268964) (xy 51.048002 -392.268619) (xy 51.06487 -392.262413)
			(xy 51.078538 -392.25074) (xy 51.08321 -392.243056) (xy 51.098599 -392.216796) (xy 51.136378 -392.169078)
			(xy 51.158394 -392.14806) (xy 51.165252 -392.14171) (xy 51.173634 -392.124946) (xy 51.181 -392.047476)
			(xy 51.181493 -392.038302) (xy 51.176685 -392.020584) (xy 51.171602 -392.012932) (xy 51.171348 -392.012678)
			(xy 51.157191 -391.992833) (xy 51.134705 -391.949585) (xy 51.119387 -391.90331) (xy 51.111628 -391.855186)
			(xy 51.11115 -391.830814) (xy 51.111672 -391.805559) (xy 51.119985 -391.755737) (xy 51.136386 -391.707963)
			(xy 51.160427 -391.66354) (xy 51.191451 -391.62368) (xy 51.228613 -391.58947) (xy 51.270899 -391.561844)
			(xy 51.317155 -391.541554) (xy 51.36612 -391.529154) (xy 51.416458 -391.524983) (xy 51.466796 -391.529154)
			(xy 51.515761 -391.541554) (xy 51.562017 -391.561844) (xy 51.604303 -391.58947) (xy 51.641465 -391.62368)
			(xy 51.672489 -391.66354) (xy 51.69653 -391.707963) (xy 51.712931 -391.755737) (xy 51.721244 -391.805559)
			(xy 51.721766 -391.830814) (xy 51.721298 -391.855145) (xy 51.713582 -391.90319) (xy 51.698332 -391.949399)
			(xy 51.675935 -391.9926) (xy 51.661822 -392.012424) (xy 51.661314 -392.012932) (xy 51.65598 -392.020298)
			(xy 51.651154 -392.038332) (xy 51.65852 -392.115548) (xy 51.659768 -392.124767) (xy 51.667988 -392.141437)
			(xy 51.674522 -392.14806) (xy 51.696565 -392.169052) (xy 51.734343 -392.216778) (xy 51.749706 -392.243056)
			(xy 51.754422 -392.250704) (xy 51.768088 -392.262353) (xy 51.784925 -392.268593) (xy 51.793902 -392.268964)
			(xy 52.239164 -392.268964) (xy 52.248147 -392.268611) (xy 52.265002 -392.262394) (xy 52.278656 -392.250718)
			(xy 52.28336 -392.243056) (xy 52.298748 -392.216795) (xy 52.336523 -392.169073) (xy 52.358544 -392.14806)
			(xy 52.365402 -392.14171) (xy 52.373784 -392.124946) (xy 52.38115 -392.047476) (xy 52.381643 -392.038301)
			(xy 52.376839 -392.020581) (xy 52.371752 -392.012932) (xy 52.371498 -392.012678) (xy 52.357339 -391.992834)
			(xy 52.334849 -391.949586) (xy 52.319529 -391.903311) (xy 52.311769 -391.855187) (xy 52.3113 -391.830814)
			(xy 52.311822 -391.805559) (xy 52.320135 -391.755737) (xy 52.336536 -391.707963) (xy 52.360577 -391.66354)
			(xy 52.391601 -391.62368) (xy 52.428763 -391.58947) (xy 52.471049 -391.561844) (xy 52.517305 -391.541554)
			(xy 52.56627 -391.529154) (xy 52.616608 -391.524983) (xy 52.666946 -391.529154) (xy 52.715911 -391.541554)
			(xy 52.762167 -391.561844) (xy 52.804453 -391.58947) (xy 52.841615 -391.62368) (xy 52.872639 -391.66354)
			(xy 52.89668 -391.707963) (xy 52.913081 -391.755737) (xy 52.921394 -391.805559) (xy 52.921916 -391.830814)
			(xy 52.921448 -391.855145) (xy 52.913733 -391.903191) (xy 52.898485 -391.949402) (xy 52.876091 -391.992604)
			(xy 52.861972 -392.012424) (xy 52.861464 -392.012932) (xy 52.85613 -392.020298) (xy 52.851304 -392.038332)
			(xy 52.85867 -392.115548) (xy 52.859916 -392.124768) (xy 52.86813 -392.141444) (xy 52.874672 -392.14806)
			(xy 52.896718 -392.16905) (xy 52.934499 -392.216774) (xy 52.949856 -392.243056) (xy 52.95457 -392.250709)
			(xy 52.968233 -392.262372) (xy 52.985072 -392.268628) (xy 52.994052 -392.268964) (xy 53.43906 -392.268964)
			(xy 53.448043 -392.268612) (xy 53.4649 -392.262395) (xy 53.478555 -392.250719) (xy 53.483256 -392.243056)
			(xy 53.498644 -392.216795) (xy 53.536419 -392.169072) (xy 53.55844 -392.14806) (xy 53.565298 -392.14171)
			(xy 53.57368 -392.124946) (xy 53.581046 -392.047476) (xy 53.581539 -392.038301) (xy 53.576735 -392.020582)
			(xy 53.571648 -392.012932) (xy 53.571394 -392.012678) (xy 53.557235 -391.992834) (xy 53.534745 -391.949586)
			(xy 53.519425 -391.903311) (xy 53.511665 -391.855187) (xy 53.511196 -391.830814) (xy 53.511718 -391.805559)
			(xy 53.520031 -391.755737) (xy 53.536432 -391.707963) (xy 53.560473 -391.66354) (xy 53.591497 -391.62368)
			(xy 53.628659 -391.58947) (xy 53.670945 -391.561844) (xy 53.717201 -391.541554) (xy 53.766166 -391.529154)
			(xy 53.816504 -391.524983) (xy 53.866842 -391.529154) (xy 53.915807 -391.541554) (xy 53.962063 -391.561844)
			(xy 54.004349 -391.58947) (xy 54.041511 -391.62368) (xy 54.072535 -391.66354) (xy 54.096576 -391.707963)
			(xy 54.112977 -391.755737) (xy 54.12129 -391.805559) (xy 54.121812 -391.830814) (xy 54.121344 -391.855145)
			(xy 54.113629 -391.903191) (xy 54.098381 -391.949401) (xy 54.075987 -391.992604) (xy 54.061868 -392.012424)
			(xy 54.06136 -392.012932) (xy 54.056026 -392.020298) (xy 54.0512 -392.038332) (xy 54.058566 -392.115548)
			(xy 54.059812 -392.124768) (xy 54.068025 -392.141444) (xy 54.074568 -392.14806) (xy 54.096614 -392.16905)
			(xy 54.134396 -392.216774) (xy 54.149752 -392.243056) (xy 54.154466 -392.25071) (xy 54.168128 -392.262373)
			(xy 54.184967 -392.268631) (xy 54.193948 -392.268964) (xy 54.63921 -392.268964) (xy 54.648198 -392.26862)
			(xy 54.665067 -392.262414) (xy 54.678736 -392.250742) (xy 54.683406 -392.243056) (xy 54.698795 -392.216796)
			(xy 54.736574 -392.169077) (xy 54.75859 -392.14806) (xy 54.765448 -392.14171) (xy 54.77383 -392.124946)
			(xy 54.781196 -392.047476) (xy 54.781689 -392.038302) (xy 54.776881 -392.020584) (xy 54.771798 -392.012932)
			(xy 54.771544 -392.012678) (xy 54.757387 -391.992833) (xy 54.734901 -391.949585) (xy 54.719584 -391.903309)
			(xy 54.711825 -391.855186) (xy 54.711346 -391.830814) (xy 54.711868 -391.805559) (xy 54.720181 -391.755737)
			(xy 54.736582 -391.707963) (xy 54.760623 -391.66354) (xy 54.791647 -391.62368) (xy 54.828809 -391.58947)
			(xy 54.871095 -391.561844) (xy 54.917351 -391.541554) (xy 54.966316 -391.529154) (xy 55.016654 -391.524983)
			(xy 55.066992 -391.529154) (xy 55.115957 -391.541554) (xy 55.162213 -391.561844) (xy 55.204499 -391.58947)
			(xy 55.241661 -391.62368) (xy 55.272685 -391.66354) (xy 55.296726 -391.707963) (xy 55.313127 -391.755737)
			(xy 55.32144 -391.805559) (xy 55.321962 -391.830814) (xy 55.321494 -391.855145) (xy 55.313778 -391.90319)
			(xy 55.298528 -391.949399) (xy 55.276131 -391.992599) (xy 55.262018 -392.012424) (xy 55.26151 -392.012932)
			(xy 55.256176 -392.020298) (xy 55.25135 -392.038332) (xy 55.258716 -392.115548) (xy 55.259964 -392.124767)
			(xy 55.268183 -392.141437) (xy 55.274718 -392.14806) (xy 55.296762 -392.169052) (xy 55.334539 -392.216778)
			(xy 55.349902 -392.243056) (xy 55.354618 -392.250704) (xy 55.368283 -392.262354) (xy 55.385121 -392.268596)
			(xy 55.394098 -392.268964) (xy 55.839106 -392.268964) (xy 55.848094 -392.268621) (xy 55.864965 -392.262416)
			(xy 55.878635 -392.250744) (xy 55.883302 -392.243056) (xy 55.898691 -392.216796) (xy 55.93647 -392.169077)
			(xy 55.958486 -392.14806) (xy 55.965344 -392.14171) (xy 55.973726 -392.124946) (xy 55.981092 -392.047476)
			(xy 55.981585 -392.038302) (xy 55.976776 -392.020584) (xy 55.971694 -392.012932) (xy 55.97144 -392.012678)
			(xy 55.957283 -391.992833) (xy 55.934798 -391.949585) (xy 55.91948 -391.903309) (xy 55.911722 -391.855186)
			(xy 55.911242 -391.830814) (xy 55.911764 -391.805559) (xy 55.920077 -391.755737) (xy 55.936478 -391.707963)
			(xy 55.960519 -391.66354) (xy 55.991543 -391.62368) (xy 56.028705 -391.58947) (xy 56.070991 -391.561844)
			(xy 56.117247 -391.541554) (xy 56.166212 -391.529154) (xy 56.21655 -391.524983) (xy 56.266888 -391.529154)
			(xy 56.315853 -391.541554) (xy 56.362109 -391.561844) (xy 56.404395 -391.58947) (xy 56.441557 -391.62368)
			(xy 56.472581 -391.66354) (xy 56.496622 -391.707963) (xy 56.513023 -391.755737) (xy 56.521336 -391.805559)
			(xy 56.521858 -391.830814) (xy 56.52139 -391.855145) (xy 56.513674 -391.90319) (xy 56.498423 -391.949399)
			(xy 56.476026 -391.992599) (xy 56.461914 -392.012424) (xy 56.461406 -392.012932) (xy 56.456072 -392.020298)
			(xy 56.451246 -392.038332) (xy 56.458612 -392.115548) (xy 56.45986 -392.124767) (xy 56.468078 -392.141438)
			(xy 56.474614 -392.14806) (xy 56.496658 -392.169052) (xy 56.534436 -392.216777) (xy 56.549798 -392.243056)
			(xy 56.554514 -392.250705) (xy 56.568179 -392.262356) (xy 56.585017 -392.268599) (xy 56.593994 -392.268964)
			(xy 57.039256 -392.268964) (xy 57.04824 -392.268612) (xy 57.065097 -392.262397) (xy 57.078753 -392.250721)
			(xy 57.083452 -392.243056) (xy 57.098785 -392.216866) (xy 57.136427 -392.169266) (xy 57.158382 -392.148314)
			(xy 57.164995 -392.14165) (xy 57.17333 -392.124845) (xy 57.174638 -392.115548) (xy 57.182004 -392.038586)
			(xy 57.176924 -392.020298) (xy 57.171336 -392.012932) (xy 57.157175 -391.993053) (xy 57.134684 -391.949739)
			(xy 57.119364 -391.903401) (xy 57.111604 -391.855217) (xy 57.111138 -391.830814) (xy 57.11166 -391.805559)
			(xy 57.119973 -391.755737) (xy 57.136374 -391.707963) (xy 57.160415 -391.66354) (xy 57.191439 -391.62368)
			(xy 57.228601 -391.58947) (xy 57.270887 -391.561844) (xy 57.317143 -391.541554) (xy 57.366108 -391.529154)
			(xy 57.416446 -391.524983) (xy 57.466784 -391.529154) (xy 57.515749 -391.541554) (xy 57.562005 -391.561844)
			(xy 57.604291 -391.58947) (xy 57.641453 -391.62368) (xy 57.672477 -391.66354) (xy 57.696518 -391.707963)
			(xy 57.712919 -391.755737) (xy 57.721232 -391.805559) (xy 57.721754 -391.830814) (xy 57.721754 -391.831068)
			(xy 57.721282 -391.855397) (xy 57.713558 -391.903438) (xy 57.698301 -391.949642) (xy 57.675898 -391.992837)
			(xy 57.66181 -392.012678) (xy 57.656222 -392.020044) (xy 57.651142 -392.038332) (xy 57.658508 -392.115294)
			(xy 57.659729 -392.124614) (xy 57.668094 -392.141434) (xy 57.674764 -392.14806) (xy 57.69681 -392.16905)
			(xy 57.734592 -392.216773) (xy 57.749948 -392.243056) (xy 57.754662 -392.25071) (xy 57.768324 -392.262375)
			(xy 57.785163 -392.268634) (xy 57.794144 -392.268964) (xy 58.239152 -392.268964) (xy 58.248136 -392.268613)
			(xy 58.264995 -392.262398) (xy 58.278652 -392.250723) (xy 58.283348 -392.243056) (xy 58.298735 -392.216794)
			(xy 58.33651 -392.169072) (xy 58.358532 -392.14806) (xy 58.36539 -392.14171) (xy 58.373772 -392.124946)
			(xy 58.381138 -392.047476) (xy 58.381631 -392.038301) (xy 58.376827 -392.020582) (xy 58.37174 -392.012932)
			(xy 58.371486 -392.012678) (xy 58.357327 -391.992834) (xy 58.334838 -391.949586) (xy 58.319519 -391.903311)
			(xy 58.311759 -391.855187) (xy 58.311288 -391.830814) (xy 58.31181 -391.805559) (xy 58.320123 -391.755737)
			(xy 58.336524 -391.707963) (xy 58.360565 -391.66354) (xy 58.391589 -391.62368) (xy 58.428751 -391.58947)
			(xy 58.471037 -391.561844) (xy 58.517293 -391.541554) (xy 58.566258 -391.529154) (xy 58.616596 -391.524983)
			(xy 58.666934 -391.529154) (xy 58.715899 -391.541554) (xy 58.762155 -391.561844) (xy 58.804441 -391.58947)
			(xy 58.841603 -391.62368) (xy 58.872627 -391.66354) (xy 58.896668 -391.707963) (xy 58.913069 -391.755737)
			(xy 58.921382 -391.805559) (xy 58.921904 -391.830814) (xy 58.921436 -391.855145) (xy 58.913721 -391.903191)
			(xy 58.898472 -391.949401) (xy 58.876078 -391.992603) (xy 58.86196 -392.012424) (xy 58.861452 -392.012932)
			(xy 58.856118 -392.020298) (xy 58.851292 -392.038332) (xy 58.858658 -392.115548) (xy 58.859904 -392.124768)
			(xy 58.868116 -392.141445) (xy 58.87466 -392.14806) (xy 58.896706 -392.16905) (xy 58.934489 -392.216773)
			(xy 58.949844 -392.243056) (xy 58.954562 -392.250699) (xy 58.968229 -392.262338) (xy 58.985066 -392.268566)
			(xy 58.99404 -392.268964) (xy 59.439302 -392.268964) (xy 59.448291 -392.268621) (xy 59.465162 -392.262417)
			(xy 59.478833 -392.250745) (xy 59.483498 -392.243056) (xy 59.498833 -392.216867) (xy 59.536477 -392.16927)
			(xy 59.558428 -392.148314) (xy 59.565047 -392.141653) (xy 59.573391 -392.124848) (xy 59.574684 -392.115548)
			(xy 59.58205 -392.038586) (xy 59.57697 -392.020298) (xy 59.571382 -392.012932) (xy 59.557219 -391.993054)
			(xy 59.534725 -391.949741) (xy 59.519402 -391.903402) (xy 59.511641 -391.855217) (xy 59.511184 -391.830814)
			(xy 59.511706 -391.805559) (xy 59.520019 -391.755737) (xy 59.53642 -391.707963) (xy 59.560461 -391.66354)
			(xy 59.591485 -391.62368) (xy 59.628647 -391.58947) (xy 59.670933 -391.561844) (xy 59.717189 -391.541554)
			(xy 59.766154 -391.529154) (xy 59.816492 -391.524983) (xy 59.86683 -391.529154) (xy 59.915795 -391.541554)
			(xy 59.962051 -391.561844) (xy 60.004337 -391.58947) (xy 60.041499 -391.62368) (xy 60.072523 -391.66354)
			(xy 60.096564 -391.707963) (xy 60.112965 -391.755737) (xy 60.121278 -391.805559) (xy 60.1218 -391.830814)
			(xy 60.1218 -391.831068) (xy 60.121328 -391.855397) (xy 60.113605 -391.903439) (xy 60.09835 -391.949645)
			(xy 60.07595 -391.992841) (xy 60.061856 -392.012678) (xy 60.056268 -392.020044) (xy 60.051188 -392.038332)
			(xy 60.058554 -392.115294) (xy 60.059773 -392.124616) (xy 60.068132 -392.141442) (xy 60.07481 -392.14806)
			(xy 60.096854 -392.169052) (xy 60.134632 -392.216777) (xy 60.149994 -392.243056) (xy 60.15471 -392.250705)
			(xy 60.168374 -392.262357) (xy 60.185212 -392.268601) (xy 60.19419 -392.268964) (xy 60.639198 -392.268964)
			(xy 60.648187 -392.268622) (xy 60.66506 -392.262419) (xy 60.678732 -392.250747) (xy 60.683394 -392.243056)
			(xy 60.698783 -392.216796) (xy 60.736561 -392.169076) (xy 60.758578 -392.14806) (xy 60.765436 -392.14171)
			(xy 60.773818 -392.124946) (xy 60.781184 -392.047476) (xy 60.781677 -392.038302) (xy 60.776868 -392.020585)
			(xy 60.771786 -392.012932) (xy 60.771532 -392.012678) (xy 60.757376 -391.992833) (xy 60.734891 -391.949584)
			(xy 60.719574 -391.903309) (xy 60.711815 -391.855186) (xy 60.711334 -391.830814) (xy 60.711856 -391.805559)
			(xy 60.720169 -391.755737) (xy 60.73657 -391.707963) (xy 60.760611 -391.66354) (xy 60.791635 -391.62368)
			(xy 60.828797 -391.58947) (xy 60.871083 -391.561844) (xy 60.917339 -391.541554) (xy 60.966304 -391.529154)
			(xy 61.016642 -391.524983) (xy 61.06698 -391.529154) (xy 61.115945 -391.541554) (xy 61.162201 -391.561844)
			(xy 61.204487 -391.58947) (xy 61.241649 -391.62368) (xy 61.272673 -391.66354) (xy 61.296714 -391.707963)
			(xy 61.313115 -391.755737) (xy 61.321428 -391.805559) (xy 61.32195 -391.830814) (xy 61.321482 -391.855144)
			(xy 61.313766 -391.903189) (xy 61.298515 -391.949399) (xy 61.276117 -391.992598) (xy 61.262006 -392.012424)
			(xy 61.261498 -392.012932) (xy 61.256164 -392.020298) (xy 61.251338 -392.038332) (xy 61.258704 -392.115548)
			(xy 61.259952 -392.124767) (xy 61.268169 -392.141439) (xy 61.274706 -392.14806) (xy 61.29675 -392.169051)
			(xy 61.334529 -392.216777) (xy 61.34989 -392.243056) (xy 61.354606 -392.250705) (xy 61.36827 -392.262359)
			(xy 61.385108 -392.268604) (xy 61.394086 -392.268964) (xy 61.839094 -392.268964) (xy 61.848083 -392.268623)
			(xy 61.864957 -392.26242) (xy 61.87863 -392.250749) (xy 61.88329 -392.243056) (xy 61.898679 -392.216796)
			(xy 61.936456 -392.169076) (xy 61.958474 -392.14806) (xy 61.965332 -392.14171) (xy 61.973714 -392.124946)
			(xy 61.98108 -392.047476) (xy 61.981573 -392.038302) (xy 61.976763 -392.020585) (xy 61.971682 -392.012932)
			(xy 61.971428 -392.012678) (xy 61.957272 -391.992833) (xy 61.934787 -391.949584) (xy 61.91947 -391.903309)
			(xy 61.911712 -391.855186) (xy 61.91123 -391.830814) (xy 61.911752 -391.805559) (xy 61.920065 -391.755737)
			(xy 61.936466 -391.707963) (xy 61.960507 -391.66354) (xy 61.991531 -391.62368) (xy 62.028693 -391.58947)
			(xy 62.070979 -391.561844) (xy 62.117235 -391.541554) (xy 62.1662 -391.529154) (xy 62.216538 -391.524983)
			(xy 62.266876 -391.529154) (xy 62.315841 -391.541554) (xy 62.362097 -391.561844) (xy 62.404383 -391.58947)
			(xy 62.441545 -391.62368) (xy 62.472569 -391.66354) (xy 62.49661 -391.707963) (xy 62.513011 -391.755737)
			(xy 62.521324 -391.805559) (xy 62.521846 -391.830814) (xy 62.521378 -391.855144) (xy 62.513661 -391.903189)
			(xy 62.498411 -391.949398) (xy 62.476013 -391.992598) (xy 62.461902 -392.012424) (xy 62.461394 -392.012932)
			(xy 62.45606 -392.020298) (xy 62.451234 -392.038332) (xy 62.4586 -392.115548) (xy 62.459847 -392.124767)
			(xy 62.468064 -392.14144) (xy 62.474602 -392.14806) (xy 62.496646 -392.169051) (xy 62.534425 -392.216776)
			(xy 62.549786 -392.243056) (xy 62.554502 -392.250706) (xy 62.568166 -392.26236) (xy 62.585004 -392.268607)
			(xy 62.593982 -392.268964) (xy 63.03899 -392.268964) (xy 63.04798 -392.268623) (xy 63.064854 -392.262422)
			(xy 63.078529 -392.250751) (xy 63.083186 -392.243056) (xy 63.098575 -392.216795) (xy 63.136352 -392.169075)
			(xy 63.15837 -392.14806) (xy 63.165228 -392.14171) (xy 63.17361 -392.124946) (xy 63.180976 -392.047476)
			(xy 63.181469 -392.038302) (xy 63.176659 -392.020585) (xy 63.171578 -392.012932) (xy 63.171324 -392.012678)
			(xy 63.157168 -391.992833) (xy 63.134684 -391.949584) (xy 63.119367 -391.903309) (xy 63.111609 -391.855186)
			(xy 63.111126 -391.830814) (xy 63.111648 -391.805559) (xy 63.119961 -391.755737) (xy 63.136362 -391.707963)
			(xy 63.160403 -391.66354) (xy 63.191427 -391.62368) (xy 63.228589 -391.58947) (xy 63.270875 -391.561844)
			(xy 63.317131 -391.541554) (xy 63.366096 -391.529154) (xy 63.416434 -391.524983) (xy 63.466772 -391.529154)
			(xy 63.515737 -391.541554) (xy 63.561993 -391.561844) (xy 63.604279 -391.58947) (xy 63.641441 -391.62368)
			(xy 63.672465 -391.66354) (xy 63.696506 -391.707963) (xy 63.712907 -391.755737) (xy 63.72122 -391.805559)
			(xy 63.721742 -391.830814) (xy 63.721274 -391.855144) (xy 63.713557 -391.903189) (xy 63.698306 -391.949398)
			(xy 63.675908 -391.992598) (xy 63.661798 -392.012424) (xy 63.66129 -392.012932) (xy 63.655956 -392.020298)
			(xy 63.65113 -392.038332) (xy 63.658496 -392.115548) (xy 63.659743 -392.124768) (xy 63.66796 -392.14144)
			(xy 63.674498 -392.14806) (xy 63.696543 -392.169051) (xy 63.734322 -392.216776) (xy 63.749682 -392.243056)
			(xy 63.754397 -392.250706) (xy 63.768061 -392.262362) (xy 63.7849 -392.26861) (xy 63.793878 -392.268964)
			(xy 64.23914 -392.268964) (xy 64.248125 -392.268615) (xy 64.264987 -392.262403) (xy 64.278647 -392.250728)
			(xy 64.283336 -392.243056) (xy 64.298723 -392.216794) (xy 64.336497 -392.16907) (xy 64.35852 -392.14806)
			(xy 64.365378 -392.14171) (xy 64.37376 -392.124946) (xy 64.381126 -392.047476) (xy 64.381619 -392.038301)
			(xy 64.376814 -392.020583) (xy 64.371728 -392.012932) (xy 64.371474 -392.012678) (xy 64.357316 -391.992834)
			(xy 64.334828 -391.949586) (xy 64.319509 -391.90331) (xy 64.311749 -391.855187) (xy 64.311276 -391.830814)
			(xy 64.311798 -391.805559) (xy 64.320111 -391.755737) (xy 64.336512 -391.707963) (xy 64.360553 -391.66354)
			(xy 64.391577 -391.62368) (xy 64.428739 -391.58947) (xy 64.471025 -391.561844) (xy 64.517281 -391.541554)
			(xy 64.566246 -391.529154) (xy 64.616584 -391.524983) (xy 64.666922 -391.529154) (xy 64.715887 -391.541554)
			(xy 64.762143 -391.561844) (xy 64.804429 -391.58947) (xy 64.841591 -391.62368) (xy 64.872615 -391.66354)
			(xy 64.896656 -391.707963) (xy 64.913057 -391.755737) (xy 64.92137 -391.805559) (xy 64.921892 -391.830814)
			(xy 64.921424 -391.855145) (xy 64.913709 -391.90319) (xy 64.89846 -391.9494) (xy 64.876064 -391.992602)
			(xy 64.861948 -392.012424) (xy 64.86144 -392.012932) (xy 64.856106 -392.020298) (xy 64.85128 -392.038332)
			(xy 64.858646 -392.115548) (xy 64.859892 -392.124769) (xy 64.868102 -392.141447) (xy 64.874648 -392.14806)
			(xy 64.89669 -392.169053) (xy 64.934465 -392.21678) (xy 64.949832 -392.243056) (xy 64.95455 -392.250701)
			(xy 64.968216 -392.262343) (xy 64.985053 -392.268575) (xy 64.994028 -392.268964) (xy 65.439036 -392.268964)
			(xy 65.448022 -392.268616) (xy 65.464884 -392.262404) (xy 65.478546 -392.25073) (xy 65.483232 -392.243056)
			(xy 65.498619 -392.216794) (xy 65.536393 -392.16907) (xy 65.558416 -392.14806) (xy 65.565274 -392.14171)
			(xy 65.573656 -392.124946) (xy 65.581022 -392.047476) (xy 65.581515 -392.038301) (xy 65.576709 -392.020583)
			(xy 65.571624 -392.012932) (xy 65.57137 -392.012678) (xy 65.557212 -391.992834) (xy 65.534724 -391.949586)
			(xy 65.519405 -391.90331) (xy 65.511646 -391.855187) (xy 65.511172 -391.830814) (xy 65.511694 -391.805559)
			(xy 65.520007 -391.755737) (xy 65.536408 -391.707963) (xy 65.560449 -391.66354) (xy 65.591473 -391.62368)
			(xy 65.628635 -391.58947) (xy 65.670921 -391.561844) (xy 65.717177 -391.541554) (xy 65.766142 -391.529154)
			(xy 65.81648 -391.524983) (xy 65.866818 -391.529154) (xy 65.915783 -391.541554) (xy 65.962039 -391.561844)
			(xy 66.004325 -391.58947) (xy 66.041487 -391.62368) (xy 66.072511 -391.66354) (xy 66.096552 -391.707963)
			(xy 66.112953 -391.755737) (xy 66.121266 -391.805559) (xy 66.121788 -391.830814) (xy 66.12132 -391.855145)
			(xy 66.113604 -391.90319) (xy 66.098355 -391.9494) (xy 66.07596 -391.992602) (xy 66.061844 -392.012424)
			(xy 66.061336 -392.012932) (xy 66.056002 -392.020298) (xy 66.051176 -392.038332) (xy 66.058542 -392.115548)
			(xy 66.059787 -392.124769) (xy 66.067997 -392.141448) (xy 66.074544 -392.14806) (xy 66.096586 -392.169053)
			(xy 66.134362 -392.21678) (xy 66.149728 -392.243056) (xy 66.154445 -392.250701) (xy 66.168111 -392.262345)
			(xy 66.184948 -392.268578) (xy 66.193924 -392.268964) (xy 67.39255 -392.268964) (xy 67.402615 -392.268531)
			(xy 67.421203 -392.2608) (xy 67.428618 -392.253978) (xy 68.123816 -391.55878) (xy 68.130668 -391.551384)
			(xy 68.138409 -391.532785) (xy 68.138802 -391.522712) (xy 68.138802 -390.695942) (xy 68.138462 -390.687334)
			(xy 68.132768 -390.671086) (xy 68.122038 -390.657623) (xy 68.114926 -390.652762) (xy 68.042028 -390.607042)
			(xy 68.034594 -390.602788) (xy 68.0179 -390.598995) (xy 68.000886 -390.600886) (xy 67.993006 -390.604248)
			(xy 67.970482 -390.61465) (xy 67.923096 -390.629344) (xy 67.874047 -390.636799) (xy 67.849242 -390.637268)
			(xy 67.823252 -390.636788) (xy 67.77191 -390.628662) (xy 67.722473 -390.612603) (xy 67.676157 -390.589007)
			(xy 67.634103 -390.558454) (xy 67.597347 -390.521699) (xy 67.566795 -390.479645) (xy 67.543198 -390.433329)
			(xy 67.527139 -390.383892) (xy 67.519012 -390.33255) (xy 67.518534 -390.30656) (xy 67.518949 -390.282787)
			(xy 67.525765 -390.235733) (xy 67.539249 -390.190139) (xy 67.559125 -390.146948) (xy 67.584982 -390.107048)
			(xy 67.600322 -390.088882) (xy 67.606003 -390.08176) (xy 67.612383 -390.06471) (xy 67.612768 -390.055608)
			(xy 67.612768 -390.024112) (xy 67.612389 -390.01501) (xy 67.606 -389.997963) (xy 67.600322 -389.990838)
			(xy 67.584974 -389.972678) (xy 67.559108 -389.932782) (xy 67.539231 -389.889589) (xy 67.525754 -389.843992)
			(xy 67.518956 -389.796934) (xy 67.518534 -389.77316) (xy 67.518967 -389.748749) (xy 67.52614 -389.700456)
			(xy 67.540337 -389.653744) (xy 67.56125 -389.609628) (xy 67.588425 -389.569068) (xy 67.62127 -389.532946)
			(xy 67.659071 -389.502048) (xy 67.679824 -389.489188) (xy 67.691508 -389.48233) (xy 67.704462 -389.459216)
			(xy 67.704462 -389.358124) (xy 67.704073 -389.349467) (xy 67.698229 -389.333166) (xy 67.687298 -389.319734)
			(xy 67.680078 -389.314944) (xy 67.679824 -389.31469) (xy 67.659118 -389.301812) (xy 67.621387 -389.270925)
			(xy 67.588604 -389.234829) (xy 67.561482 -389.194308) (xy 67.540609 -389.150241) (xy 67.526438 -389.103584)
			(xy 67.519276 -389.055352) (xy 67.518788 -389.030972) (xy 67.519345 -389.003351) (xy 67.528523 -388.948878)
			(xy 67.546619 -388.896684) (xy 67.573131 -388.84822) (xy 67.607323 -388.804832) (xy 67.648244 -388.767723)
			(xy 67.671188 -388.752334) (xy 67.682618 -388.745222) (xy 67.695064 -388.721346) (xy 67.691508 -388.6073)
			(xy 67.677792 -388.584694) (xy 67.665854 -388.57809) (xy 67.644162 -388.565456) (xy 67.604521 -388.53466)
			(xy 67.569988 -388.498228) (xy 67.541357 -388.456996) (xy 67.519284 -388.411912) (xy 67.504276 -388.36401)
			(xy 67.496677 -388.314391) (xy 67.496182 -388.289292) (xy 67.496692 -388.263305) (xy 67.504824 -388.211971)
			(xy 67.520885 -388.162541) (xy 67.544481 -388.116232) (xy 67.575031 -388.074184) (xy 67.611782 -388.037432)
			(xy 67.65383 -388.006882) (xy 67.700139 -387.983286) (xy 67.749569 -387.967224) (xy 67.800903 -387.959092)
			(xy 67.82689 -387.958584) (xy 67.827144 -387.958584) (xy 67.855099 -387.959192) (xy 67.910207 -387.968628)
			(xy 67.962951 -387.987175) (xy 67.987672 -388.00024) (xy 67.99961 -388.006844) (xy 68.026534 -388.00659)
			(xy 68.113656 -387.955282) (xy 68.121081 -387.950517) (xy 68.132375 -387.936982) (xy 68.138381 -387.920408)
			(xy 68.138802 -387.911594) (xy 68.138802 -386.352542) (xy 68.138192 -386.340691) (xy 68.127607 -386.319486)
			(xy 68.118482 -386.311902) (xy 68.043298 -386.256022) (xy 68.019676 -386.251704) (xy 68.008246 -386.25526)
			(xy 67.981739 -386.262626) (xy 67.927295 -386.270536) (xy 67.899788 -386.271008) (xy 67.872537 -386.270521)
			(xy 67.818591 -386.262763) (xy 67.766298 -386.247407) (xy 67.716722 -386.224765) (xy 67.670873 -386.195299)
			(xy 67.629684 -386.159607) (xy 67.593994 -386.118417) (xy 67.564529 -386.072568) (xy 67.541888 -386.022991)
			(xy 67.526534 -385.970697) (xy 67.518778 -385.916751) (xy 67.51828 -385.8895) (xy 67.51828 -385.887976)
			(xy 67.517918 -385.878722) (xy 67.511388 -385.86141) (xy 67.50558 -385.854194) (xy 67.48526 -385.83108)
			(xy 67.478657 -385.824178) (xy 67.461694 -385.815424) (xy 67.45224 -385.814062) (xy 67.414551 -385.809599)
			(xy 67.340439 -385.793228) (xy 67.26866 -385.768565) (xy 67.200139 -385.735926) (xy 67.135757 -385.695733)
			(xy 67.076344 -385.648504) (xy 67.049142 -385.622038) (xy 66.599816 -385.172712) (xy 66.573696 -385.145841)
			(xy 66.526978 -385.087243) (xy 66.487111 -385.023784) (xy 66.454597 -384.956263) (xy 66.429843 -384.885528)
			(xy 66.413161 -384.812466) (xy 66.40476 -384.737997) (xy 66.404236 -384.700526) (xy 66.404236 -384.018536)
			(xy 66.404774 -383.981066) (xy 66.413184 -383.906598) (xy 66.429869 -383.833538) (xy 66.454619 -383.762803)
			(xy 66.487124 -383.695278) (xy 66.526977 -383.631813) (xy 66.573677 -383.573201) (xy 66.599816 -383.54635)
			(xy 67.098926 -383.04724) (xy 67.105654 -383.039869) (xy 67.113394 -383.021496) (xy 67.113602 -383.001559)
			(xy 67.110356 -382.992122) (xy 67.099151 -382.962497) (xy 67.087001 -382.900342) (xy 67.086226 -382.868678)
			(xy 67.086226 -382.86817) (xy 67.086711 -382.842183) (xy 67.094847 -382.79085) (xy 67.110912 -382.741422)
			(xy 67.134512 -382.695115) (xy 67.165065 -382.653071) (xy 67.20182 -382.616323) (xy 67.24387 -382.585778)
			(xy 67.290181 -382.562187) (xy 67.339613 -382.546132) (xy 67.390947 -382.538006) (xy 67.416934 -382.537462)
			(xy 67.439407 -382.537854) (xy 67.483935 -382.543969) (xy 67.527226 -382.556054) (xy 67.547998 -382.56464)
			(xy 67.556287 -382.567793) (xy 67.573976 -382.568834) (xy 67.590964 -382.563792) (xy 67.59829 -382.558798)
			(xy 67.60083 -382.55702) (xy 67.582288 -382.500124) (xy 67.578458 -382.49015) (xy 67.564181 -382.474288)
			(xy 67.544697 -382.465582) (xy 67.534028 -382.465072) (xy 66.14033 -382.465072) (xy 66.130577 -382.465493)
			(xy 66.112478 -382.472765) (xy 66.098431 -382.486296) (xy 66.094102 -382.495044) (xy 66.056002 -382.579372)
			(xy 66.052397 -382.588464) (xy 66.05163 -382.607989) (xy 66.058226 -382.626383) (xy 66.064384 -382.633982)
			(xy 66.079902 -382.652212) (xy 66.10607 -382.692299) (xy 66.126192 -382.735738) (xy 66.139848 -382.781622)
			(xy 66.146752 -382.828994) (xy 66.147188 -382.85293) (xy 66.146678 -382.878917) (xy 66.138548 -382.930252)
			(xy 66.122487 -382.979682) (xy 66.098891 -383.025992) (xy 66.068341 -383.06804) (xy 66.03159 -383.104791)
			(xy 65.989542 -383.135341) (xy 65.943232 -383.158937) (xy 65.893802 -383.174998) (xy 65.842467 -383.183128)
			(xy 65.790493 -383.183128) (xy 65.739158 -383.174998) (xy 65.689728 -383.158937) (xy 65.643418 -383.135341)
			(xy 65.60137 -383.104791) (xy 65.564619 -383.06804) (xy 65.534069 -383.025992) (xy 65.510473 -382.979682)
			(xy 65.494412 -382.930252) (xy 65.486282 -382.878917) (xy 65.485772 -382.85293) (xy 65.486193 -382.828992)
			(xy 65.49309 -382.781616) (xy 65.506744 -382.735729) (xy 65.526869 -382.692288) (xy 65.553046 -382.652203)
			(xy 65.568576 -382.633982) (xy 65.574761 -382.626396) (xy 65.581378 -382.607993) (xy 65.580608 -382.588452)
			(xy 65.576958 -382.579372) (xy 65.538858 -382.495044) (xy 65.534449 -382.486355) (xy 65.520406 -382.472873)
			(xy 65.502362 -382.465566) (xy 65.49263 -382.465072) (xy 64.940434 -382.465072) (xy 64.93068 -382.465492)
			(xy 64.912581 -382.472763) (xy 64.898532 -382.486295) (xy 64.894206 -382.495044) (xy 64.856106 -382.579372)
			(xy 64.852501 -382.588463) (xy 64.851734 -382.607989) (xy 64.85833 -382.626383) (xy 64.864488 -382.633982)
			(xy 64.880006 -382.652212) (xy 64.906174 -382.6923) (xy 64.926295 -382.735738) (xy 64.939951 -382.781622)
			(xy 64.946855 -382.828994) (xy 64.947292 -382.85293) (xy 64.946782 -382.878917) (xy 64.938652 -382.930252)
			(xy 64.922591 -382.979682) (xy 64.898995 -383.025992) (xy 64.868445 -383.06804) (xy 64.831694 -383.104791)
			(xy 64.789646 -383.135341) (xy 64.743336 -383.158937) (xy 64.693906 -383.174998) (xy 64.642571 -383.183128)
			(xy 64.590597 -383.183128) (xy 64.539262 -383.174998) (xy 64.489832 -383.158937) (xy 64.443522 -383.135341)
			(xy 64.401474 -383.104791) (xy 64.364723 -383.06804) (xy 64.334173 -383.025992) (xy 64.310577 -382.979682)
			(xy 64.294516 -382.930252) (xy 64.286386 -382.878917) (xy 64.285876 -382.85293) (xy 64.286297 -382.828992)
			(xy 64.293194 -382.781616) (xy 64.306848 -382.735729) (xy 64.326973 -382.692289) (xy 64.35315 -382.652203)
			(xy 64.36868 -382.633982) (xy 64.374865 -382.626396) (xy 64.381481 -382.607993) (xy 64.380711 -382.588453)
			(xy 64.377062 -382.579372) (xy 64.338962 -382.495044) (xy 64.334554 -382.486355) (xy 64.32051 -382.472872)
			(xy 64.302466 -382.465563) (xy 64.292734 -382.465072) (xy 63.740284 -382.465072) (xy 63.730535 -382.465501)
			(xy 63.712451 -382.472783) (xy 63.698417 -382.486316) (xy 63.694056 -382.495044) (xy 63.655956 -382.579372)
			(xy 63.652354 -382.588464) (xy 63.651588 -382.60799) (xy 63.658178 -382.626385) (xy 63.664338 -382.633982)
			(xy 63.679854 -382.652213) (xy 63.706018 -382.692302) (xy 63.726136 -382.73574) (xy 63.739789 -382.781623)
			(xy 63.746693 -382.828994) (xy 63.747142 -382.85293) (xy 63.746632 -382.878917) (xy 63.738502 -382.930252)
			(xy 63.722441 -382.979682) (xy 63.698845 -383.025992) (xy 63.668295 -383.06804) (xy 63.631544 -383.104791)
			(xy 63.589496 -383.135341) (xy 63.543186 -383.158937) (xy 63.493756 -383.174998) (xy 63.442421 -383.183128)
			(xy 63.390447 -383.183128) (xy 63.339112 -383.174998) (xy 63.289682 -383.158937) (xy 63.243372 -383.135341)
			(xy 63.201324 -383.104791) (xy 63.164573 -383.06804) (xy 63.134023 -383.025992) (xy 63.110427 -382.979682)
			(xy 63.094366 -382.930252) (xy 63.086236 -382.878917) (xy 63.085726 -382.85293) (xy 63.086147 -382.828992)
			(xy 63.093045 -382.781617) (xy 63.1067 -382.735731) (xy 63.126828 -382.692293) (xy 63.153008 -382.65221)
			(xy 63.16853 -382.633982) (xy 63.17472 -382.626397) (xy 63.181342 -382.607994) (xy 63.180571 -382.58845)
			(xy 63.176912 -382.579372) (xy 63.138812 -382.495044) (xy 63.134406 -382.486349) (xy 63.120365 -382.472852)
			(xy 63.10232 -382.465527) (xy 63.092584 -382.465072) (xy 62.540388 -382.465072) (xy 62.530639 -382.4655)
			(xy 62.512553 -382.472781) (xy 62.498519 -382.486314) (xy 62.49416 -382.495044) (xy 62.45606 -382.579372)
			(xy 62.452457 -382.588464) (xy 62.451692 -382.60799) (xy 62.458282 -382.626385) (xy 62.464442 -382.633982)
			(xy 62.479957 -382.652213) (xy 62.506121 -382.692302) (xy 62.526239 -382.735741) (xy 62.539893 -382.781624)
			(xy 62.546796 -382.828994) (xy 62.547246 -382.85293) (xy 62.546736 -382.878917) (xy 62.538606 -382.930252)
			(xy 62.522545 -382.979682) (xy 62.498949 -383.025992) (xy 62.468399 -383.06804) (xy 62.431648 -383.104791)
			(xy 62.3896 -383.135341) (xy 62.34329 -383.158937) (xy 62.29386 -383.174998) (xy 62.242525 -383.183128)
			(xy 62.190551 -383.183128) (xy 62.139216 -383.174998) (xy 62.089786 -383.158937) (xy 62.043476 -383.135341)
			(xy 62.001428 -383.104791) (xy 61.964677 -383.06804) (xy 61.934127 -383.025992) (xy 61.910531 -382.979682)
			(xy 61.89447 -382.930252) (xy 61.88634 -382.878917) (xy 61.88583 -382.85293) (xy 61.886251 -382.828993)
			(xy 61.893149 -382.781617) (xy 61.906805 -382.735731) (xy 61.926933 -382.692293) (xy 61.953113 -382.652211)
			(xy 61.968634 -382.633982) (xy 61.974823 -382.626397) (xy 61.981445 -382.607994) (xy 61.980675 -382.58845)
			(xy 61.977016 -382.579372) (xy 61.938916 -382.495044) (xy 61.934506 -382.48636) (xy 61.92046 -382.472889)
			(xy 61.902417 -382.465596) (xy 61.892688 -382.465072) (xy 61.340492 -382.465072) (xy 61.330743 -382.465499)
			(xy 61.312656 -382.472779) (xy 61.29862 -382.486312) (xy 61.294264 -382.495044) (xy 61.256164 -382.579372)
			(xy 61.252561 -382.588464) (xy 61.251795 -382.60799) (xy 61.258387 -382.626385) (xy 61.264546 -382.633982)
			(xy 61.280061 -382.652213) (xy 61.306225 -382.692302) (xy 61.326343 -382.735741) (xy 61.339996 -382.781624)
			(xy 61.346899 -382.828994) (xy 61.34735 -382.85293) (xy 61.34684 -382.878917) (xy 61.33871 -382.930252)
			(xy 61.322649 -382.979682) (xy 61.299053 -383.025992) (xy 61.268503 -383.06804) (xy 61.231752 -383.104791)
			(xy 61.189704 -383.135341) (xy 61.143394 -383.158937) (xy 61.093964 -383.174998) (xy 61.042629 -383.183128)
			(xy 60.990655 -383.183128) (xy 60.93932 -383.174998) (xy 60.88989 -383.158937) (xy 60.84358 -383.135341)
			(xy 60.801532 -383.104791) (xy 60.764781 -383.06804) (xy 60.734231 -383.025992) (xy 60.710635 -382.979682)
			(xy 60.694574 -382.930252) (xy 60.686444 -382.878917) (xy 60.685934 -382.85293) (xy 60.686355 -382.828993)
			(xy 60.693253 -382.781617) (xy 60.706909 -382.735731) (xy 60.727037 -382.692293) (xy 60.753218 -382.652211)
			(xy 60.768738 -382.633982) (xy 60.774927 -382.626397) (xy 60.781548 -382.607994) (xy 60.780778 -382.58845)
			(xy 60.77712 -382.579372) (xy 60.73902 -382.495044) (xy 60.73461 -382.486359) (xy 60.720564 -382.472887)
			(xy 60.702521 -382.465593) (xy 60.692792 -382.465072) (xy 60.140342 -382.465072) (xy 60.130598 -382.465508)
			(xy 60.112526 -382.472799) (xy 60.098505 -382.486333) (xy 60.094114 -382.495044) (xy 60.056014 -382.579372)
			(xy 60.052409 -382.588463) (xy 60.051642 -382.607989) (xy 60.058239 -382.626382) (xy 60.064396 -382.633982)
			(xy 60.079913 -382.652212) (xy 60.106081 -382.6923) (xy 60.126202 -382.735738) (xy 60.139857 -382.781622)
			(xy 60.146762 -382.828994) (xy 60.1472 -382.85293) (xy 60.14669 -382.878917) (xy 60.13856 -382.930252)
			(xy 60.122499 -382.979682) (xy 60.098903 -383.025992) (xy 60.068353 -383.06804) (xy 60.031602 -383.104791)
			(xy 59.989554 -383.135341) (xy 59.943244 -383.158937) (xy 59.893814 -383.174998) (xy 59.842479 -383.183128)
			(xy 59.790505 -383.183128) (xy 59.73917 -383.174998) (xy 59.68974 -383.158937) (xy 59.64343 -383.135341)
			(xy 59.601382 -383.104791) (xy 59.564631 -383.06804) (xy 59.534081 -383.025992) (xy 59.510485 -382.979682)
			(xy 59.494424 -382.930252) (xy 59.486294 -382.878917) (xy 59.485784 -382.85293) (xy 59.486205 -382.828992)
			(xy 59.493102 -382.781616) (xy 59.506756 -382.735729) (xy 59.526882 -382.692289) (xy 59.55306 -382.652204)
			(xy 59.568588 -382.633982) (xy 59.574772 -382.626395) (xy 59.581387 -382.607993) (xy 59.580617 -382.588453)
			(xy 59.57697 -382.579372) (xy 59.53887 -382.495044) (xy 59.534462 -382.486354) (xy 59.520419 -382.472869)
			(xy 59.502375 -382.465558) (xy 59.492642 -382.465072) (xy 58.940446 -382.465072) (xy 58.930702 -382.465507)
			(xy 58.912628 -382.472797) (xy 58.898606 -382.486332) (xy 58.894218 -382.495044) (xy 58.856118 -382.579372)
			(xy 58.852512 -382.588463) (xy 58.851746 -382.607989) (xy 58.858343 -382.626382) (xy 58.8645 -382.633982)
			(xy 58.880017 -382.652212) (xy 58.906184 -382.6923) (xy 58.926305 -382.735739) (xy 58.93996 -382.781622)
			(xy 58.946865 -382.828994) (xy 58.947304 -382.85293) (xy 58.946794 -382.878917) (xy 58.938664 -382.930252)
			(xy 58.922603 -382.979682) (xy 58.899007 -383.025992) (xy 58.868457 -383.06804) (xy 58.831706 -383.104791)
			(xy 58.789658 -383.135341) (xy 58.743348 -383.158937) (xy 58.693918 -383.174998) (xy 58.642583 -383.183128)
			(xy 58.590609 -383.183128) (xy 58.539274 -383.174998) (xy 58.489844 -383.158937) (xy 58.443534 -383.135341)
			(xy 58.401486 -383.104791) (xy 58.364735 -383.06804) (xy 58.334185 -383.025992) (xy 58.310589 -382.979682)
			(xy 58.294528 -382.930252) (xy 58.286398 -382.878917) (xy 58.285888 -382.85293) (xy 58.286309 -382.828992)
			(xy 58.293206 -382.781616) (xy 58.30686 -382.735729) (xy 58.326987 -382.69229) (xy 58.353164 -382.652205)
			(xy 58.368692 -382.633982) (xy 58.374876 -382.626395) (xy 58.38149 -382.607993) (xy 58.38072 -382.588453)
			(xy 58.377074 -382.579372) (xy 58.338974 -382.495044) (xy 58.334566 -382.486353) (xy 58.320524 -382.472867)
			(xy 58.302479 -382.465554) (xy 58.292746 -382.465072) (xy 57.740296 -382.465072) (xy 57.730546 -382.465499)
			(xy 57.712458 -382.472778) (xy 57.698421 -382.486311) (xy 57.694068 -382.495044) (xy 57.655968 -382.579372)
			(xy 57.652365 -382.588464) (xy 57.651599 -382.607989) (xy 57.658191 -382.626384) (xy 57.66435 -382.633982)
			(xy 57.679865 -382.652213) (xy 57.706028 -382.692302) (xy 57.726146 -382.735741) (xy 57.739799 -382.781624)
			(xy 57.746702 -382.828995) (xy 57.747154 -382.85293) (xy 57.746644 -382.878917) (xy 57.738514 -382.930252)
			(xy 57.722453 -382.979682) (xy 57.698857 -383.025992) (xy 57.668307 -383.06804) (xy 57.631556 -383.104791)
			(xy 57.589508 -383.135341) (xy 57.543198 -383.158937) (xy 57.493768 -383.174998) (xy 57.442433 -383.183128)
			(xy 57.390459 -383.183128) (xy 57.339124 -383.174998) (xy 57.289694 -383.158937) (xy 57.243384 -383.135341)
			(xy 57.201336 -383.104791) (xy 57.164585 -383.06804) (xy 57.134035 -383.025992) (xy 57.110439 -382.979682)
			(xy 57.094378 -382.930252) (xy 57.086248 -382.878917) (xy 57.085738 -382.85293) (xy 57.086159 -382.828993)
			(xy 57.093057 -382.781617) (xy 57.106713 -382.735731) (xy 57.126842 -382.692294) (xy 57.153022 -382.652212)
			(xy 57.168542 -382.633982) (xy 57.174731 -382.626397) (xy 57.181351 -382.607994) (xy 57.180581 -382.588451)
			(xy 57.176924 -382.579372) (xy 57.138824 -382.495044) (xy 57.134414 -382.486359) (xy 57.120369 -382.472886)
			(xy 57.102325 -382.465591) (xy 57.092596 -382.465072) (xy 56.5404 -382.465072) (xy 56.53065 -382.465498)
			(xy 56.51256 -382.472776) (xy 56.498522 -382.486309) (xy 56.494172 -382.495044) (xy 56.456072 -382.579372)
			(xy 56.452469 -382.588464) (xy 56.451703 -382.607989) (xy 56.458295 -382.626384) (xy 56.464454 -382.633982)
			(xy 56.479969 -382.652213) (xy 56.506132 -382.692302) (xy 56.526249 -382.735741) (xy 56.539902 -382.781624)
			(xy 56.546805 -382.828995) (xy 56.547258 -382.85293) (xy 56.546748 -382.878917) (xy 56.538618 -382.930252)
			(xy 56.522557 -382.979682) (xy 56.498961 -383.025992) (xy 56.468411 -383.06804) (xy 56.43166 -383.104791)
			(xy 56.389612 -383.135341) (xy 56.343302 -383.158937) (xy 56.293872 -383.174998) (xy 56.242537 -383.183128)
			(xy 56.190563 -383.183128) (xy 56.139228 -383.174998) (xy 56.089798 -383.158937) (xy 56.043488 -383.135341)
			(xy 56.00144 -383.104791) (xy 55.964689 -383.06804) (xy 55.934139 -383.025992) (xy 55.910543 -382.979682)
			(xy 55.894482 -382.930252) (xy 55.886352 -382.878917) (xy 55.885842 -382.85293) (xy 55.886263 -382.828993)
			(xy 55.893161 -382.781617) (xy 55.906817 -382.735732) (xy 55.926946 -382.692294) (xy 55.953127 -382.652212)
			(xy 55.968646 -382.633982) (xy 55.974834 -382.626397) (xy 55.981454 -382.607994) (xy 55.980684 -382.588451)
			(xy 55.977028 -382.579372) (xy 55.938928 -382.495044) (xy 55.934518 -382.486358) (xy 55.920473 -382.472884)
			(xy 55.90243 -382.465588) (xy 55.8927 -382.465072) (xy 55.340504 -382.465072) (xy 55.330753 -382.465497)
			(xy 55.312663 -382.472775) (xy 55.298623 -382.486307) (xy 55.294276 -382.495044) (xy 55.256176 -382.579372)
			(xy 55.252572 -382.588464) (xy 55.251807 -382.607989) (xy 55.258399 -382.626384) (xy 55.264558 -382.633982)
			(xy 55.280073 -382.652213) (xy 55.306235 -382.692302) (xy 55.326352 -382.735741) (xy 55.340005 -382.781624)
			(xy 55.346908 -382.828995) (xy 55.347362 -382.85293) (xy 55.346852 -382.878917) (xy 55.338722 -382.930252)
			(xy 55.322661 -382.979682) (xy 55.299065 -383.025992) (xy 55.268515 -383.06804) (xy 55.231764 -383.104791)
			(xy 55.189716 -383.135341) (xy 55.143406 -383.158937) (xy 55.093976 -383.174998) (xy 55.042641 -383.183128)
			(xy 54.990667 -383.183128) (xy 54.939332 -383.174998) (xy 54.889902 -383.158937) (xy 54.843592 -383.135341)
			(xy 54.801544 -383.104791) (xy 54.764793 -383.06804) (xy 54.734243 -383.025992) (xy 54.710647 -382.979682)
			(xy 54.694586 -382.930252) (xy 54.686456 -382.878917) (xy 54.685946 -382.85293) (xy 54.686368 -382.828993)
			(xy 54.693265 -382.781617) (xy 54.706921 -382.735732) (xy 54.72705 -382.692294) (xy 54.753231 -382.652213)
			(xy 54.76875 -382.633982) (xy 54.774938 -382.626397) (xy 54.781557 -382.607993) (xy 54.780787 -382.588451)
			(xy 54.777132 -382.579372) (xy 54.739032 -382.495044) (xy 54.734622 -382.486358) (xy 54.720578 -382.472883)
			(xy 54.702534 -382.465585) (xy 54.692804 -382.465072) (xy 54.140354 -382.465072) (xy 54.130609 -382.465506)
			(xy 54.112533 -382.472794) (xy 54.098509 -382.486328) (xy 54.094126 -382.495044) (xy 54.056026 -382.579372)
			(xy 54.05242 -382.588463) (xy 54.051653 -382.607989) (xy 54.058251 -382.626382) (xy 54.064408 -382.633982)
			(xy 54.079925 -382.652212) (xy 54.106091 -382.6923) (xy 54.126212 -382.735739) (xy 54.139866 -382.781622)
			(xy 54.146771 -382.828994) (xy 54.147212 -382.85293) (xy 54.146702 -382.878917) (xy 54.138572 -382.930252)
			(xy 54.122511 -382.979682) (xy 54.098915 -383.025992) (xy 54.068365 -383.06804) (xy 54.031614 -383.104791)
			(xy 53.989566 -383.135341) (xy 53.943256 -383.158937) (xy 53.893826 -383.174998) (xy 53.842491 -383.183128)
			(xy 53.790517 -383.183128) (xy 53.739182 -383.174998) (xy 53.689752 -383.158937) (xy 53.643442 -383.135341)
			(xy 53.601394 -383.104791) (xy 53.564643 -383.06804) (xy 53.534093 -383.025992) (xy 53.510497 -382.979682)
			(xy 53.494436 -382.930252) (xy 53.486306 -382.878917) (xy 53.485796 -382.85293) (xy 53.486217 -382.828992)
			(xy 53.493114 -382.781616) (xy 53.506769 -382.73573) (xy 53.526895 -382.69229) (xy 53.553074 -382.652206)
			(xy 53.5686 -382.633982) (xy 53.574783 -382.626395) (xy 53.581396 -382.607993) (xy 53.580626 -382.588454)
			(xy 53.576982 -382.579372) (xy 53.538882 -382.495044) (xy 53.534475 -382.486352) (xy 53.520433 -382.472864)
			(xy 53.502387 -382.465548) (xy 53.492654 -382.465072) (xy 52.940458 -382.465072) (xy 52.930712 -382.465505)
			(xy 52.912635 -382.472793) (xy 52.89861 -382.486327) (xy 52.89423 -382.495044) (xy 52.85613 -382.579372)
			(xy 52.852524 -382.588463) (xy 52.851757 -382.607989) (xy 52.858355 -382.626381) (xy 52.864512 -382.633982)
			(xy 52.880029 -382.652212) (xy 52.906195 -382.692301) (xy 52.926315 -382.735739) (xy 52.939969 -382.781623)
			(xy 52.946874 -382.828994) (xy 52.947316 -382.85293) (xy 52.946806 -382.878917) (xy 52.938676 -382.930252)
			(xy 52.922615 -382.979682) (xy 52.899019 -383.025992) (xy 52.868469 -383.06804) (xy 52.831718 -383.104791)
			(xy 52.78967 -383.135341) (xy 52.74336 -383.158937) (xy 52.69393 -383.174998) (xy 52.642595 -383.183128)
			(xy 52.590621 -383.183128) (xy 52.539286 -383.174998) (xy 52.489856 -383.158937) (xy 52.443546 -383.135341)
			(xy 52.401498 -383.104791) (xy 52.364747 -383.06804) (xy 52.334197 -383.025992) (xy 52.310601 -382.979682)
			(xy 52.29454 -382.930252) (xy 52.28641 -382.878917) (xy 52.2859 -382.85293) (xy 52.286321 -382.828992)
			(xy 52.293219 -382.781617) (xy 52.306873 -382.73573) (xy 52.327 -382.692291) (xy 52.353178 -382.652207)
			(xy 52.368704 -382.633982) (xy 52.374886 -382.626395) (xy 52.381499 -382.607993) (xy 52.38073 -382.588454)
			(xy 52.377086 -382.579372) (xy 52.338986 -382.495044) (xy 52.334579 -382.486352) (xy 52.320537 -382.472862)
			(xy 52.302492 -382.465546) (xy 52.292758 -382.465072) (xy 51.740308 -382.465072) (xy 51.730557 -382.465496)
			(xy 51.712465 -382.472773) (xy 51.698424 -382.486306) (xy 51.69408 -382.495044) (xy 51.65598 -382.579372)
			(xy 51.652376 -382.588464) (xy 51.65161 -382.607989) (xy 51.658203 -382.626384) (xy 51.664362 -382.633982)
			(xy 51.679881 -382.652211) (xy 51.706051 -382.692298) (xy 51.726174 -382.735737) (xy 51.739831 -382.781621)
			(xy 51.746736 -382.828993) (xy 51.747166 -382.85293) (xy 51.746656 -382.878917) (xy 51.738526 -382.930252)
			(xy 51.722465 -382.979682) (xy 51.698869 -383.025992) (xy 51.668319 -383.06804) (xy 51.631568 -383.104791)
			(xy 51.58952 -383.135341) (xy 51.54321 -383.158937) (xy 51.49378 -383.174998) (xy 51.442445 -383.183128)
			(xy 51.390471 -383.183128) (xy 51.339136 -383.174998) (xy 51.289706 -383.158937) (xy 51.243396 -383.135341)
			(xy 51.201348 -383.104791) (xy 51.164597 -383.06804) (xy 51.134047 -383.025992) (xy 51.110451 -382.979682)
			(xy 51.09439 -382.930252) (xy 51.08626 -382.878917) (xy 51.08575 -382.85293) (xy 51.086172 -382.828993)
			(xy 51.09307 -382.781618) (xy 51.106726 -382.735732) (xy 51.126855 -382.692295) (xy 51.153036 -382.652213)
			(xy 51.168554 -382.633982) (xy 51.174742 -382.626397) (xy 51.181361 -382.607993) (xy 51.180591 -382.588451)
			(xy 51.176936 -382.579372) (xy 51.138836 -382.495044) (xy 51.134427 -382.486358) (xy 51.120382 -382.472881)
			(xy 51.102338 -382.465582) (xy 51.092608 -382.465072) (xy 50.540412 -382.465072) (xy 50.53066 -382.465496)
			(xy 50.512567 -382.472772) (xy 50.498526 -382.486304) (xy 50.494184 -382.495044) (xy 50.456084 -382.579372)
			(xy 50.45248 -382.588464) (xy 50.451714 -382.607989) (xy 50.458307 -382.626384) (xy 50.464466 -382.633982)
			(xy 50.479985 -382.652211) (xy 50.506154 -382.692299) (xy 50.526277 -382.735737) (xy 50.539934 -382.781621)
			(xy 50.546839 -382.828994) (xy 50.54727 -382.85293) (xy 50.54676 -382.878917) (xy 50.53863 -382.930252)
			(xy 50.522569 -382.979682) (xy 50.498973 -383.025992) (xy 50.468423 -383.06804) (xy 50.431672 -383.104791)
			(xy 50.389624 -383.135341) (xy 50.343314 -383.158937) (xy 50.293884 -383.174998) (xy 50.242549 -383.183128)
			(xy 50.190575 -383.183128) (xy 50.13924 -383.174998) (xy 50.08981 -383.158937) (xy 50.0435 -383.135341)
			(xy 50.001452 -383.104791) (xy 49.964701 -383.06804) (xy 49.934151 -383.025992) (xy 49.910555 -382.979682)
			(xy 49.894494 -382.930252) (xy 49.886364 -382.878917) (xy 49.885854 -382.85293) (xy 49.886276 -382.828993)
			(xy 49.893174 -382.781618) (xy 49.90683 -382.735732) (xy 49.926959 -382.692295) (xy 49.953141 -382.652214)
			(xy 49.968658 -382.633982) (xy 49.974845 -382.626397) (xy 49.981464 -382.607993) (xy 49.980694 -382.588451)
			(xy 49.97704 -382.579372) (xy 49.93894 -382.495044) (xy 49.934531 -382.486357) (xy 49.920486 -382.47288)
			(xy 49.902442 -382.465579) (xy 49.892712 -382.465072) (xy 49.340516 -382.465072) (xy 49.330764 -382.465495)
			(xy 49.31267 -382.47277) (xy 49.298627 -382.486302) (xy 49.294288 -382.495044) (xy 49.256188 -382.579372)
			(xy 49.252584 -382.588464) (xy 49.251818 -382.607989) (xy 49.258411 -382.626384) (xy 49.26457 -382.633982)
			(xy 49.280088 -382.652211) (xy 49.306258 -382.692299) (xy 49.32638 -382.735737) (xy 49.340037 -382.781621)
			(xy 49.346942 -382.828994) (xy 49.347374 -382.85293) (xy 49.346864 -382.878917) (xy 49.338734 -382.930252)
			(xy 49.322673 -382.979682) (xy 49.299077 -383.025992) (xy 49.268527 -383.06804) (xy 49.231776 -383.104791)
			(xy 49.189728 -383.135341) (xy 49.143418 -383.158937) (xy 49.093988 -383.174998) (xy 49.042653 -383.183128)
			(xy 48.990679 -383.183128) (xy 48.939344 -383.174998) (xy 48.889914 -383.158937) (xy 48.843604 -383.135341)
			(xy 48.801556 -383.104791) (xy 48.764805 -383.06804) (xy 48.734255 -383.025992) (xy 48.710659 -382.979682)
			(xy 48.694598 -382.930252) (xy 48.686468 -382.878917) (xy 48.685958 -382.85293) (xy 48.68638 -382.828993)
			(xy 48.693278 -382.781618) (xy 48.706934 -382.735732) (xy 48.727064 -382.692295) (xy 48.753245 -382.652214)
			(xy 48.768762 -382.633982) (xy 48.774949 -382.626396) (xy 48.781567 -382.607993) (xy 48.780797 -382.588452)
			(xy 48.777144 -382.579372) (xy 48.739044 -382.495044) (xy 48.734635 -382.486357) (xy 48.720591 -382.472878)
			(xy 48.702547 -382.465576) (xy 48.692816 -382.465072) (xy 48.140366 -382.465072) (xy 48.130619 -382.465504)
			(xy 48.11254 -382.472789) (xy 48.098512 -382.486323) (xy 48.094138 -382.495044) (xy 48.056038 -382.579372)
			(xy 48.052436 -382.588465) (xy 48.051671 -382.60799) (xy 48.058259 -382.626386) (xy 48.06442 -382.633982)
			(xy 48.079936 -382.652212) (xy 48.106102 -382.692301) (xy 48.126221 -382.73574) (xy 48.139875 -382.781623)
			(xy 48.14678 -382.828994) (xy 48.147224 -382.85293) (xy 48.146714 -382.878917) (xy 48.138584 -382.930252)
			(xy 48.122523 -382.979682) (xy 48.098927 -383.025992) (xy 48.068377 -383.06804) (xy 48.031626 -383.104791)
			(xy 47.989578 -383.135341) (xy 47.943268 -383.158937) (xy 47.893838 -383.174998) (xy 47.842503 -383.183128)
			(xy 47.790529 -383.183128) (xy 47.739194 -383.174998) (xy 47.689764 -383.158937) (xy 47.643454 -383.135341)
			(xy 47.601406 -383.104791) (xy 47.564655 -383.06804) (xy 47.534105 -383.025992) (xy 47.510509 -382.979682)
			(xy 47.494448 -382.930252) (xy 47.486318 -382.878917) (xy 47.485808 -382.85293) (xy 47.486229 -382.828992)
			(xy 47.493127 -382.781617) (xy 47.506781 -382.73573) (xy 47.526909 -382.692291) (xy 47.553087 -382.652208)
			(xy 47.568612 -382.633982) (xy 47.574793 -382.626394) (xy 47.581405 -382.607993) (xy 47.580636 -382.588454)
			(xy 47.576994 -382.579372) (xy 47.538894 -382.495044) (xy 47.534487 -382.486351) (xy 47.520446 -382.472859)
			(xy 47.5024 -382.46554) (xy 47.492666 -382.465072) (xy 45.44822 -382.465072) (xy 45.438169 -382.465578)
			(xy 45.419609 -382.473299) (xy 45.412152 -382.480058) (xy 44.958175 -382.934035) (xy 46.13834 -382.934035)
			(xy 46.13834 -382.882061) (xy 46.14647 -382.830726) (xy 46.162531 -382.781296) (xy 46.186127 -382.734986)
			(xy 46.216677 -382.692938) (xy 46.253428 -382.656187) (xy 46.295476 -382.625637) (xy 46.341786 -382.602041)
			(xy 46.391216 -382.58598) (xy 46.442551 -382.57785) (xy 46.494525 -382.57785) (xy 46.54586 -382.58598)
			(xy 46.59529 -382.602041) (xy 46.6416 -382.625637) (xy 46.683648 -382.656187) (xy 46.720399 -382.692938)
			(xy 46.750949 -382.734986) (xy 46.774545 -382.781296) (xy 46.790606 -382.830726) (xy 46.798736 -382.882061)
			(xy 46.799246 -382.908048) (xy 46.798736 -382.934035) (xy 46.790606 -382.98537) (xy 46.774545 -383.0348)
			(xy 46.750949 -383.08111) (xy 46.720399 -383.123158) (xy 46.683648 -383.159909) (xy 46.6416 -383.190459)
			(xy 46.59529 -383.214055) (xy 46.54586 -383.230116) (xy 46.494525 -383.238246) (xy 46.442551 -383.238246)
			(xy 46.391216 -383.230116) (xy 46.341786 -383.214055) (xy 46.295476 -383.190459) (xy 46.253428 -383.159909)
			(xy 46.216677 -383.123158) (xy 46.186127 -383.08111) (xy 46.162531 -383.0348) (xy 46.14647 -382.98537)
			(xy 46.13834 -382.934035) (xy 44.958175 -382.934035) (xy 44.920154 -382.972056) (xy 44.91331 -382.979455)
			(xy 44.905588 -382.998054) (xy 44.905168 -383.008124) (xy 44.905168 -384.383359) (xy 45.071032 -384.383359)
			(xy 45.071032 -384.331385) (xy 45.079162 -384.28005) (xy 45.095223 -384.23062) (xy 45.118819 -384.18431)
			(xy 45.149369 -384.142262) (xy 45.18612 -384.105511) (xy 45.228168 -384.074961) (xy 45.274478 -384.051365)
			(xy 45.323908 -384.035304) (xy 45.375243 -384.027174) (xy 45.427217 -384.027174) (xy 45.478552 -384.035304)
			(xy 45.527982 -384.051365) (xy 45.574292 -384.074961) (xy 45.61634 -384.105511) (xy 45.653091 -384.142262)
			(xy 45.683641 -384.18431) (xy 45.707237 -384.23062) (xy 45.723298 -384.28005) (xy 45.731428 -384.331385)
			(xy 45.731938 -384.357372) (xy 45.731428 -384.383359) (xy 45.723298 -384.434694) (xy 45.707237 -384.484124)
			(xy 45.683641 -384.530434) (xy 45.653091 -384.572482) (xy 45.61634 -384.609233) (xy 45.574292 -384.639783)
			(xy 45.566587 -384.643709) (xy 47.132242 -384.643709) (xy 47.132242 -384.591735) (xy 47.140372 -384.5404)
			(xy 47.156433 -384.49097) (xy 47.180029 -384.44466) (xy 47.210579 -384.402612) (xy 47.24733 -384.365861)
			(xy 47.289378 -384.335311) (xy 47.335688 -384.311715) (xy 47.385118 -384.295654) (xy 47.436453 -384.287524)
			(xy 47.488427 -384.287524) (xy 47.539762 -384.295654) (xy 47.589192 -384.311715) (xy 47.635502 -384.335311)
			(xy 47.67755 -384.365861) (xy 47.714301 -384.402612) (xy 47.744851 -384.44466) (xy 47.768447 -384.49097)
			(xy 47.784508 -384.5404) (xy 47.792638 -384.591735) (xy 47.793148 -384.617722) (xy 47.792638 -384.643709)
			(xy 48.332138 -384.643709) (xy 48.332138 -384.591735) (xy 48.340268 -384.5404) (xy 48.356329 -384.49097)
			(xy 48.379925 -384.44466) (xy 48.410475 -384.402612) (xy 48.447226 -384.365861) (xy 48.489274 -384.335311)
			(xy 48.535584 -384.311715) (xy 48.585014 -384.295654) (xy 48.636349 -384.287524) (xy 48.688323 -384.287524)
			(xy 48.739658 -384.295654) (xy 48.789088 -384.311715) (xy 48.835398 -384.335311) (xy 48.877446 -384.365861)
			(xy 48.914197 -384.402612) (xy 48.944747 -384.44466) (xy 48.968343 -384.49097) (xy 48.984404 -384.5404)
			(xy 48.992534 -384.591735) (xy 48.993044 -384.617722) (xy 48.992534 -384.643709) (xy 49.532288 -384.643709)
			(xy 49.532288 -384.591735) (xy 49.540418 -384.5404) (xy 49.556479 -384.49097) (xy 49.580075 -384.44466)
			(xy 49.610625 -384.402612) (xy 49.647376 -384.365861) (xy 49.689424 -384.335311) (xy 49.735734 -384.311715)
			(xy 49.785164 -384.295654) (xy 49.836499 -384.287524) (xy 49.888473 -384.287524) (xy 49.939808 -384.295654)
			(xy 49.989238 -384.311715) (xy 50.035548 -384.335311) (xy 50.077596 -384.365861) (xy 50.114347 -384.402612)
			(xy 50.144897 -384.44466) (xy 50.168493 -384.49097) (xy 50.184554 -384.5404) (xy 50.192684 -384.591735)
			(xy 50.193194 -384.617722) (xy 50.192684 -384.643709) (xy 50.732184 -384.643709) (xy 50.732184 -384.591735)
			(xy 50.740314 -384.5404) (xy 50.756375 -384.49097) (xy 50.779971 -384.44466) (xy 50.810521 -384.402612)
			(xy 50.847272 -384.365861) (xy 50.88932 -384.335311) (xy 50.93563 -384.311715) (xy 50.98506 -384.295654)
			(xy 51.036395 -384.287524) (xy 51.088369 -384.287524) (xy 51.139704 -384.295654) (xy 51.189134 -384.311715)
			(xy 51.235444 -384.335311) (xy 51.277492 -384.365861) (xy 51.314243 -384.402612) (xy 51.344793 -384.44466)
			(xy 51.368389 -384.49097) (xy 51.38445 -384.5404) (xy 51.39258 -384.591735) (xy 51.39309 -384.617722)
			(xy 51.39258 -384.643709) (xy 51.932334 -384.643709) (xy 51.932334 -384.591735) (xy 51.940464 -384.5404)
			(xy 51.956525 -384.49097) (xy 51.980121 -384.44466) (xy 52.010671 -384.402612) (xy 52.047422 -384.365861)
			(xy 52.08947 -384.335311) (xy 52.13578 -384.311715) (xy 52.18521 -384.295654) (xy 52.236545 -384.287524)
			(xy 52.288519 -384.287524) (xy 52.339854 -384.295654) (xy 52.389284 -384.311715) (xy 52.435594 -384.335311)
			(xy 52.477642 -384.365861) (xy 52.514393 -384.402612) (xy 52.544943 -384.44466) (xy 52.568539 -384.49097)
			(xy 52.5846 -384.5404) (xy 52.59273 -384.591735) (xy 52.59324 -384.617722) (xy 52.59273 -384.643709)
			(xy 53.13223 -384.643709) (xy 53.13223 -384.591735) (xy 53.14036 -384.5404) (xy 53.156421 -384.49097)
			(xy 53.180017 -384.44466) (xy 53.210567 -384.402612) (xy 53.247318 -384.365861) (xy 53.289366 -384.335311)
			(xy 53.335676 -384.311715) (xy 53.385106 -384.295654) (xy 53.436441 -384.287524) (xy 53.488415 -384.287524)
			(xy 53.53975 -384.295654) (xy 53.58918 -384.311715) (xy 53.63549 -384.335311) (xy 53.677538 -384.365861)
			(xy 53.714289 -384.402612) (xy 53.744839 -384.44466) (xy 53.768435 -384.49097) (xy 53.784496 -384.5404)
			(xy 53.792626 -384.591735) (xy 53.793136 -384.617722) (xy 53.792626 -384.643709) (xy 54.332126 -384.643709)
			(xy 54.332126 -384.591735) (xy 54.340256 -384.5404) (xy 54.356317 -384.49097) (xy 54.379913 -384.44466)
			(xy 54.410463 -384.402612) (xy 54.447214 -384.365861) (xy 54.489262 -384.335311) (xy 54.535572 -384.311715)
			(xy 54.585002 -384.295654) (xy 54.636337 -384.287524) (xy 54.688311 -384.287524) (xy 54.739646 -384.295654)
			(xy 54.789076 -384.311715) (xy 54.835386 -384.335311) (xy 54.877434 -384.365861) (xy 54.914185 -384.402612)
			(xy 54.944735 -384.44466) (xy 54.968331 -384.49097) (xy 54.984392 -384.5404) (xy 54.992522 -384.591735)
			(xy 54.993032 -384.617722) (xy 54.992522 -384.643709) (xy 55.532276 -384.643709) (xy 55.532276 -384.591735)
			(xy 55.540406 -384.5404) (xy 55.556467 -384.49097) (xy 55.580063 -384.44466) (xy 55.610613 -384.402612)
			(xy 55.647364 -384.365861) (xy 55.689412 -384.335311) (xy 55.735722 -384.311715) (xy 55.785152 -384.295654)
			(xy 55.836487 -384.287524) (xy 55.888461 -384.287524) (xy 55.939796 -384.295654) (xy 55.989226 -384.311715)
			(xy 56.035536 -384.335311) (xy 56.077584 -384.365861) (xy 56.114335 -384.402612) (xy 56.144885 -384.44466)
			(xy 56.168481 -384.49097) (xy 56.184542 -384.5404) (xy 56.192672 -384.591735) (xy 56.193182 -384.617722)
			(xy 56.192672 -384.643709) (xy 56.732172 -384.643709) (xy 56.732172 -384.591735) (xy 56.740302 -384.5404)
			(xy 56.756363 -384.49097) (xy 56.779959 -384.44466) (xy 56.810509 -384.402612) (xy 56.84726 -384.365861)
			(xy 56.889308 -384.335311) (xy 56.935618 -384.311715) (xy 56.985048 -384.295654) (xy 57.036383 -384.287524)
			(xy 57.088357 -384.287524) (xy 57.139692 -384.295654) (xy 57.189122 -384.311715) (xy 57.235432 -384.335311)
			(xy 57.27748 -384.365861) (xy 57.314231 -384.402612) (xy 57.344781 -384.44466) (xy 57.368377 -384.49097)
			(xy 57.384438 -384.5404) (xy 57.392568 -384.591735) (xy 57.393078 -384.617722) (xy 57.392568 -384.643709)
			(xy 57.932322 -384.643709) (xy 57.932322 -384.591735) (xy 57.940452 -384.5404) (xy 57.956513 -384.49097)
			(xy 57.980109 -384.44466) (xy 58.010659 -384.402612) (xy 58.04741 -384.365861) (xy 58.089458 -384.335311)
			(xy 58.135768 -384.311715) (xy 58.185198 -384.295654) (xy 58.236533 -384.287524) (xy 58.288507 -384.287524)
			(xy 58.339842 -384.295654) (xy 58.389272 -384.311715) (xy 58.435582 -384.335311) (xy 58.47763 -384.365861)
			(xy 58.514381 -384.402612) (xy 58.544931 -384.44466) (xy 58.568527 -384.49097) (xy 58.584588 -384.5404)
			(xy 58.592718 -384.591735) (xy 58.593228 -384.617722) (xy 58.592718 -384.643709) (xy 59.132218 -384.643709)
			(xy 59.132218 -384.591735) (xy 59.140348 -384.5404) (xy 59.156409 -384.49097) (xy 59.180005 -384.44466)
			(xy 59.210555 -384.402612) (xy 59.247306 -384.365861) (xy 59.289354 -384.335311) (xy 59.335664 -384.311715)
			(xy 59.385094 -384.295654) (xy 59.436429 -384.287524) (xy 59.488403 -384.287524) (xy 59.539738 -384.295654)
			(xy 59.589168 -384.311715) (xy 59.635478 -384.335311) (xy 59.677526 -384.365861) (xy 59.714277 -384.402612)
			(xy 59.744827 -384.44466) (xy 59.768423 -384.49097) (xy 59.784484 -384.5404) (xy 59.792614 -384.591735)
			(xy 59.793124 -384.617722) (xy 59.792614 -384.643709) (xy 60.332114 -384.643709) (xy 60.332114 -384.591735)
			(xy 60.340244 -384.5404) (xy 60.356305 -384.49097) (xy 60.379901 -384.44466) (xy 60.410451 -384.402612)
			(xy 60.447202 -384.365861) (xy 60.48925 -384.335311) (xy 60.53556 -384.311715) (xy 60.58499 -384.295654)
			(xy 60.636325 -384.287524) (xy 60.688299 -384.287524) (xy 60.739634 -384.295654) (xy 60.789064 -384.311715)
			(xy 60.835374 -384.335311) (xy 60.877422 -384.365861) (xy 60.914173 -384.402612) (xy 60.944723 -384.44466)
			(xy 60.968319 -384.49097) (xy 60.98438 -384.5404) (xy 60.99251 -384.591735) (xy 60.99302 -384.617722)
			(xy 60.99251 -384.643709) (xy 61.532264 -384.643709) (xy 61.532264 -384.591735) (xy 61.540394 -384.5404)
			(xy 61.556455 -384.49097) (xy 61.580051 -384.44466) (xy 61.610601 -384.402612) (xy 61.647352 -384.365861)
			(xy 61.6894 -384.335311) (xy 61.73571 -384.311715) (xy 61.78514 -384.295654) (xy 61.836475 -384.287524)
			(xy 61.888449 -384.287524) (xy 61.939784 -384.295654) (xy 61.989214 -384.311715) (xy 62.035524 -384.335311)
			(xy 62.077572 -384.365861) (xy 62.114323 -384.402612) (xy 62.144873 -384.44466) (xy 62.168469 -384.49097)
			(xy 62.18453 -384.5404) (xy 62.19266 -384.591735) (xy 62.19317 -384.617722) (xy 62.19266 -384.643709)
			(xy 62.73216 -384.643709) (xy 62.73216 -384.591735) (xy 62.74029 -384.5404) (xy 62.756351 -384.49097)
			(xy 62.779947 -384.44466) (xy 62.810497 -384.402612) (xy 62.847248 -384.365861) (xy 62.889296 -384.335311)
			(xy 62.935606 -384.311715) (xy 62.985036 -384.295654) (xy 63.036371 -384.287524) (xy 63.088345 -384.287524)
			(xy 63.13968 -384.295654) (xy 63.18911 -384.311715) (xy 63.23542 -384.335311) (xy 63.277468 -384.365861)
			(xy 63.314219 -384.402612) (xy 63.344769 -384.44466) (xy 63.368365 -384.49097) (xy 63.384426 -384.5404)
			(xy 63.392556 -384.591735) (xy 63.393066 -384.617722) (xy 63.392556 -384.643709) (xy 63.93231 -384.643709)
			(xy 63.93231 -384.591735) (xy 63.94044 -384.5404) (xy 63.956501 -384.49097) (xy 63.980097 -384.44466)
			(xy 64.010647 -384.402612) (xy 64.047398 -384.365861) (xy 64.089446 -384.335311) (xy 64.135756 -384.311715)
			(xy 64.185186 -384.295654) (xy 64.236521 -384.287524) (xy 64.288495 -384.287524) (xy 64.33983 -384.295654)
			(xy 64.38926 -384.311715) (xy 64.43557 -384.335311) (xy 64.477618 -384.365861) (xy 64.514369 -384.402612)
			(xy 64.544919 -384.44466) (xy 64.568515 -384.49097) (xy 64.584576 -384.5404) (xy 64.592706 -384.591735)
			(xy 64.593216 -384.617722) (xy 64.592706 -384.643709) (xy 65.132206 -384.643709) (xy 65.132206 -384.591735)
			(xy 65.140336 -384.5404) (xy 65.156397 -384.49097) (xy 65.179993 -384.44466) (xy 65.210543 -384.402612)
			(xy 65.247294 -384.365861) (xy 65.289342 -384.335311) (xy 65.335652 -384.311715) (xy 65.385082 -384.295654)
			(xy 65.436417 -384.287524) (xy 65.488391 -384.287524) (xy 65.539726 -384.295654) (xy 65.589156 -384.311715)
			(xy 65.635466 -384.335311) (xy 65.677514 -384.365861) (xy 65.714265 -384.402612) (xy 65.744815 -384.44466)
			(xy 65.768411 -384.49097) (xy 65.784472 -384.5404) (xy 65.792602 -384.591735) (xy 65.793112 -384.617722)
			(xy 65.792602 -384.643709) (xy 65.784472 -384.695044) (xy 65.768411 -384.744474) (xy 65.744815 -384.790784)
			(xy 65.714265 -384.832832) (xy 65.677514 -384.869583) (xy 65.635466 -384.900133) (xy 65.589156 -384.923729)
			(xy 65.539726 -384.93979) (xy 65.488391 -384.94792) (xy 65.436417 -384.94792) (xy 65.385082 -384.93979)
			(xy 65.335652 -384.923729) (xy 65.289342 -384.900133) (xy 65.247294 -384.869583) (xy 65.210543 -384.832832)
			(xy 65.179993 -384.790784) (xy 65.156397 -384.744474) (xy 65.140336 -384.695044) (xy 65.132206 -384.643709)
			(xy 64.592706 -384.643709) (xy 64.584576 -384.695044) (xy 64.568515 -384.744474) (xy 64.544919 -384.790784)
			(xy 64.514369 -384.832832) (xy 64.477618 -384.869583) (xy 64.43557 -384.900133) (xy 64.38926 -384.923729)
			(xy 64.33983 -384.93979) (xy 64.288495 -384.94792) (xy 64.236521 -384.94792) (xy 64.185186 -384.93979)
			(xy 64.135756 -384.923729) (xy 64.089446 -384.900133) (xy 64.047398 -384.869583) (xy 64.010647 -384.832832)
			(xy 63.980097 -384.790784) (xy 63.956501 -384.744474) (xy 63.94044 -384.695044) (xy 63.93231 -384.643709)
			(xy 63.392556 -384.643709) (xy 63.384426 -384.695044) (xy 63.368365 -384.744474) (xy 63.344769 -384.790784)
			(xy 63.314219 -384.832832) (xy 63.277468 -384.869583) (xy 63.23542 -384.900133) (xy 63.18911 -384.923729)
			(xy 63.13968 -384.93979) (xy 63.088345 -384.94792) (xy 63.036371 -384.94792) (xy 62.985036 -384.93979)
			(xy 62.935606 -384.923729) (xy 62.889296 -384.900133) (xy 62.847248 -384.869583) (xy 62.810497 -384.832832)
			(xy 62.779947 -384.790784) (xy 62.756351 -384.744474) (xy 62.74029 -384.695044) (xy 62.73216 -384.643709)
			(xy 62.19266 -384.643709) (xy 62.18453 -384.695044) (xy 62.168469 -384.744474) (xy 62.144873 -384.790784)
			(xy 62.114323 -384.832832) (xy 62.077572 -384.869583) (xy 62.035524 -384.900133) (xy 61.989214 -384.923729)
			(xy 61.939784 -384.93979) (xy 61.888449 -384.94792) (xy 61.836475 -384.94792) (xy 61.78514 -384.93979)
			(xy 61.73571 -384.923729) (xy 61.6894 -384.900133) (xy 61.647352 -384.869583) (xy 61.610601 -384.832832)
			(xy 61.580051 -384.790784) (xy 61.556455 -384.744474) (xy 61.540394 -384.695044) (xy 61.532264 -384.643709)
			(xy 60.99251 -384.643709) (xy 60.98438 -384.695044) (xy 60.968319 -384.744474) (xy 60.944723 -384.790784)
			(xy 60.914173 -384.832832) (xy 60.877422 -384.869583) (xy 60.835374 -384.900133) (xy 60.789064 -384.923729)
			(xy 60.739634 -384.93979) (xy 60.688299 -384.94792) (xy 60.636325 -384.94792) (xy 60.58499 -384.93979)
			(xy 60.53556 -384.923729) (xy 60.48925 -384.900133) (xy 60.447202 -384.869583) (xy 60.410451 -384.832832)
			(xy 60.379901 -384.790784) (xy 60.356305 -384.744474) (xy 60.340244 -384.695044) (xy 60.332114 -384.643709)
			(xy 59.792614 -384.643709) (xy 59.784484 -384.695044) (xy 59.768423 -384.744474) (xy 59.744827 -384.790784)
			(xy 59.714277 -384.832832) (xy 59.677526 -384.869583) (xy 59.635478 -384.900133) (xy 59.589168 -384.923729)
			(xy 59.539738 -384.93979) (xy 59.488403 -384.94792) (xy 59.436429 -384.94792) (xy 59.385094 -384.93979)
			(xy 59.335664 -384.923729) (xy 59.289354 -384.900133) (xy 59.247306 -384.869583) (xy 59.210555 -384.832832)
			(xy 59.180005 -384.790784) (xy 59.156409 -384.744474) (xy 59.140348 -384.695044) (xy 59.132218 -384.643709)
			(xy 58.592718 -384.643709) (xy 58.584588 -384.695044) (xy 58.568527 -384.744474) (xy 58.544931 -384.790784)
			(xy 58.514381 -384.832832) (xy 58.47763 -384.869583) (xy 58.435582 -384.900133) (xy 58.389272 -384.923729)
			(xy 58.339842 -384.93979) (xy 58.288507 -384.94792) (xy 58.236533 -384.94792) (xy 58.185198 -384.93979)
			(xy 58.135768 -384.923729) (xy 58.089458 -384.900133) (xy 58.04741 -384.869583) (xy 58.010659 -384.832832)
			(xy 57.980109 -384.790784) (xy 57.956513 -384.744474) (xy 57.940452 -384.695044) (xy 57.932322 -384.643709)
			(xy 57.392568 -384.643709) (xy 57.384438 -384.695044) (xy 57.368377 -384.744474) (xy 57.344781 -384.790784)
			(xy 57.314231 -384.832832) (xy 57.27748 -384.869583) (xy 57.235432 -384.900133) (xy 57.189122 -384.923729)
			(xy 57.139692 -384.93979) (xy 57.088357 -384.94792) (xy 57.036383 -384.94792) (xy 56.985048 -384.93979)
			(xy 56.935618 -384.923729) (xy 56.889308 -384.900133) (xy 56.84726 -384.869583) (xy 56.810509 -384.832832)
			(xy 56.779959 -384.790784) (xy 56.756363 -384.744474) (xy 56.740302 -384.695044) (xy 56.732172 -384.643709)
			(xy 56.192672 -384.643709) (xy 56.184542 -384.695044) (xy 56.168481 -384.744474) (xy 56.144885 -384.790784)
			(xy 56.114335 -384.832832) (xy 56.077584 -384.869583) (xy 56.035536 -384.900133) (xy 55.989226 -384.923729)
			(xy 55.939796 -384.93979) (xy 55.888461 -384.94792) (xy 55.836487 -384.94792) (xy 55.785152 -384.93979)
			(xy 55.735722 -384.923729) (xy 55.689412 -384.900133) (xy 55.647364 -384.869583) (xy 55.610613 -384.832832)
			(xy 55.580063 -384.790784) (xy 55.556467 -384.744474) (xy 55.540406 -384.695044) (xy 55.532276 -384.643709)
			(xy 54.992522 -384.643709) (xy 54.984392 -384.695044) (xy 54.968331 -384.744474) (xy 54.944735 -384.790784)
			(xy 54.914185 -384.832832) (xy 54.877434 -384.869583) (xy 54.835386 -384.900133) (xy 54.789076 -384.923729)
			(xy 54.739646 -384.93979) (xy 54.688311 -384.94792) (xy 54.636337 -384.94792) (xy 54.585002 -384.93979)
			(xy 54.535572 -384.923729) (xy 54.489262 -384.900133) (xy 54.447214 -384.869583) (xy 54.410463 -384.832832)
			(xy 54.379913 -384.790784) (xy 54.356317 -384.744474) (xy 54.340256 -384.695044) (xy 54.332126 -384.643709)
			(xy 53.792626 -384.643709) (xy 53.784496 -384.695044) (xy 53.768435 -384.744474) (xy 53.744839 -384.790784)
			(xy 53.714289 -384.832832) (xy 53.677538 -384.869583) (xy 53.63549 -384.900133) (xy 53.58918 -384.923729)
			(xy 53.53975 -384.93979) (xy 53.488415 -384.94792) (xy 53.436441 -384.94792) (xy 53.385106 -384.93979)
			(xy 53.335676 -384.923729) (xy 53.289366 -384.900133) (xy 53.247318 -384.869583) (xy 53.210567 -384.832832)
			(xy 53.180017 -384.790784) (xy 53.156421 -384.744474) (xy 53.14036 -384.695044) (xy 53.13223 -384.643709)
			(xy 52.59273 -384.643709) (xy 52.5846 -384.695044) (xy 52.568539 -384.744474) (xy 52.544943 -384.790784)
			(xy 52.514393 -384.832832) (xy 52.477642 -384.869583) (xy 52.435594 -384.900133) (xy 52.389284 -384.923729)
			(xy 52.339854 -384.93979) (xy 52.288519 -384.94792) (xy 52.236545 -384.94792) (xy 52.18521 -384.93979)
			(xy 52.13578 -384.923729) (xy 52.08947 -384.900133) (xy 52.047422 -384.869583) (xy 52.010671 -384.832832)
			(xy 51.980121 -384.790784) (xy 51.956525 -384.744474) (xy 51.940464 -384.695044) (xy 51.932334 -384.643709)
			(xy 51.39258 -384.643709) (xy 51.38445 -384.695044) (xy 51.368389 -384.744474) (xy 51.344793 -384.790784)
			(xy 51.314243 -384.832832) (xy 51.277492 -384.869583) (xy 51.235444 -384.900133) (xy 51.189134 -384.923729)
			(xy 51.139704 -384.93979) (xy 51.088369 -384.94792) (xy 51.036395 -384.94792) (xy 50.98506 -384.93979)
			(xy 50.93563 -384.923729) (xy 50.88932 -384.900133) (xy 50.847272 -384.869583) (xy 50.810521 -384.832832)
			(xy 50.779971 -384.790784) (xy 50.756375 -384.744474) (xy 50.740314 -384.695044) (xy 50.732184 -384.643709)
			(xy 50.192684 -384.643709) (xy 50.184554 -384.695044) (xy 50.168493 -384.744474) (xy 50.144897 -384.790784)
			(xy 50.114347 -384.832832) (xy 50.077596 -384.869583) (xy 50.035548 -384.900133) (xy 49.989238 -384.923729)
			(xy 49.939808 -384.93979) (xy 49.888473 -384.94792) (xy 49.836499 -384.94792) (xy 49.785164 -384.93979)
			(xy 49.735734 -384.923729) (xy 49.689424 -384.900133) (xy 49.647376 -384.869583) (xy 49.610625 -384.832832)
			(xy 49.580075 -384.790784) (xy 49.556479 -384.744474) (xy 49.540418 -384.695044) (xy 49.532288 -384.643709)
			(xy 48.992534 -384.643709) (xy 48.984404 -384.695044) (xy 48.968343 -384.744474) (xy 48.944747 -384.790784)
			(xy 48.914197 -384.832832) (xy 48.877446 -384.869583) (xy 48.835398 -384.900133) (xy 48.789088 -384.923729)
			(xy 48.739658 -384.93979) (xy 48.688323 -384.94792) (xy 48.636349 -384.94792) (xy 48.585014 -384.93979)
			(xy 48.535584 -384.923729) (xy 48.489274 -384.900133) (xy 48.447226 -384.869583) (xy 48.410475 -384.832832)
			(xy 48.379925 -384.790784) (xy 48.356329 -384.744474) (xy 48.340268 -384.695044) (xy 48.332138 -384.643709)
			(xy 47.792638 -384.643709) (xy 47.784508 -384.695044) (xy 47.768447 -384.744474) (xy 47.744851 -384.790784)
			(xy 47.714301 -384.832832) (xy 47.67755 -384.869583) (xy 47.635502 -384.900133) (xy 47.589192 -384.923729)
			(xy 47.539762 -384.93979) (xy 47.488427 -384.94792) (xy 47.436453 -384.94792) (xy 47.385118 -384.93979)
			(xy 47.335688 -384.923729) (xy 47.289378 -384.900133) (xy 47.24733 -384.869583) (xy 47.210579 -384.832832)
			(xy 47.180029 -384.790784) (xy 47.156433 -384.744474) (xy 47.140372 -384.695044) (xy 47.132242 -384.643709)
			(xy 45.566587 -384.643709) (xy 45.527982 -384.663379) (xy 45.478552 -384.67944) (xy 45.427217 -384.68757)
			(xy 45.375243 -384.68757) (xy 45.323908 -384.67944) (xy 45.274478 -384.663379) (xy 45.228168 -384.639783)
			(xy 45.18612 -384.609233) (xy 45.149369 -384.572482) (xy 45.118819 -384.530434) (xy 45.095223 -384.484124)
			(xy 45.079162 -384.434694) (xy 45.071032 -384.383359) (xy 44.905168 -384.383359) (xy 44.905168 -385.171442)
			(xy 44.905575 -385.181055) (xy 44.91261 -385.198947) (xy 44.918884 -385.20624) (xy 44.966636 -385.256786)
			(xy 44.973487 -385.263536) (xy 44.990855 -385.271761) (xy 45.000418 -385.272788) (xy 45.026609 -385.274908)
			(xy 45.077882 -385.286395) (xy 45.126692 -385.305848) (xy 45.134285 -385.31038) (xy 47.460662 -385.31038)
			(xy 47.461183 -385.284394) (xy 47.469316 -385.233062) (xy 47.485377 -385.183633) (xy 47.508973 -385.137326)
			(xy 47.539522 -385.095279) (xy 47.576271 -385.058528) (xy 47.618317 -385.027978) (xy 47.664624 -385.004381)
			(xy 47.714052 -384.988318) (xy 47.765384 -384.980184) (xy 47.79137 -384.979672) (xy 47.817379 -384.980169)
			(xy 47.868755 -384.988323) (xy 47.91822 -385.00442) (xy 47.964556 -385.028062) (xy 48.00662 -385.058666)
			(xy 48.043373 -385.095477) (xy 48.073911 -385.137589) (xy 48.09748 -385.183962) (xy 48.113499 -385.233453)
			(xy 48.118014 -385.259072) (xy 48.119538 -385.26847) (xy 48.143764 -385.31038) (xy 48.660558 -385.31038)
			(xy 48.661083 -385.284394) (xy 48.669215 -385.233062) (xy 48.685277 -385.183634) (xy 48.708872 -385.137327)
			(xy 48.739421 -385.09528) (xy 48.77617 -385.05853) (xy 48.818215 -385.02798) (xy 48.864521 -385.004382)
			(xy 48.913948 -384.988319) (xy 48.96528 -384.980184) (xy 48.991266 -384.979672) (xy 49.017275 -384.980172)
			(xy 49.068651 -384.988326) (xy 49.118116 -385.004422) (xy 49.164452 -385.028063) (xy 49.206515 -385.058667)
			(xy 49.243269 -385.095479) (xy 49.273807 -385.13759) (xy 49.297376 -385.183963) (xy 49.313395 -385.233453)
			(xy 49.31791 -385.259072) (xy 49.319434 -385.26847) (xy 49.34366 -385.31038) (xy 49.860708 -385.31038)
			(xy 49.861183 -385.284391) (xy 49.869317 -385.233055) (xy 49.885382 -385.183623) (xy 49.908982 -385.137312)
			(xy 49.939535 -385.095263) (xy 49.976291 -385.058512) (xy 50.018343 -385.027963) (xy 50.064656 -385.004368)
			(xy 50.11409 -384.988309) (xy 50.165427 -384.98018) (xy 50.191416 -384.979672) (xy 50.21746 -384.980119)
			(xy 50.268902 -384.988309) (xy 50.318426 -385.004453) (xy 50.364811 -385.028153) (xy 50.406913 -385.058824)
			(xy 50.443693 -385.09571) (xy 50.474243 -385.137899) (xy 50.49781 -385.184352) (xy 50.513813 -385.233923)
			(xy 50.518314 -385.25958) (xy 50.519584 -385.268978) (xy 50.54352 -385.31038) (xy 51.060604 -385.31038)
			(xy 51.061083 -385.284392) (xy 51.069217 -385.233055) (xy 51.085282 -385.183623) (xy 51.108881 -385.137313)
			(xy 51.139434 -385.095265) (xy 51.176189 -385.058513) (xy 51.21824 -385.027964) (xy 51.264553 -385.004369)
			(xy 51.313987 -384.98831) (xy 51.365324 -384.980181) (xy 51.391312 -384.979672) (xy 51.417322 -384.980131)
			(xy 51.4687 -384.988291) (xy 51.518166 -385.004394) (xy 51.564502 -385.028041) (xy 51.606565 -385.05865)
			(xy 51.643318 -385.095466) (xy 51.673855 -385.137581) (xy 51.697423 -385.183958) (xy 51.713441 -385.233452)
			(xy 51.717956 -385.259072) (xy 51.71948 -385.26847) (xy 51.743706 -385.31038) (xy 52.2605 -385.31038)
			(xy 52.260983 -385.284392) (xy 52.269117 -385.233056) (xy 52.285181 -385.183624) (xy 52.30878 -385.137314)
			(xy 52.339333 -385.095266) (xy 52.376087 -385.058515) (xy 52.418138 -385.027966) (xy 52.46445 -385.00437)
			(xy 52.513883 -384.98831) (xy 52.56522 -384.980181) (xy 52.591208 -384.979672) (xy 52.617218 -384.980134)
			(xy 52.668595 -384.988294) (xy 52.718062 -385.004396) (xy 52.764398 -385.028043) (xy 52.806461 -385.058651)
			(xy 52.843214 -385.095467) (xy 52.873751 -385.137582) (xy 52.897319 -385.183958) (xy 52.913337 -385.233452)
			(xy 52.917852 -385.259072) (xy 52.919376 -385.26847) (xy 52.943602 -385.31038) (xy 53.46065 -385.31038)
			(xy 53.461183 -385.284394) (xy 53.469315 -385.233063) (xy 53.485376 -385.183636) (xy 53.508971 -385.137329)
			(xy 53.539518 -385.095283) (xy 53.576266 -385.058533) (xy 53.61831 -385.027983) (xy 53.664616 -385.004385)
			(xy 53.714042 -384.98832) (xy 53.765372 -384.980185) (xy 53.791358 -384.979672) (xy 53.81737 -384.980089)
			(xy 53.868749 -384.988256) (xy 53.918216 -385.004365) (xy 53.964552 -385.028018) (xy 54.006615 -385.058633)
			(xy 54.043367 -385.095453) (xy 54.073903 -385.137573) (xy 54.09747 -385.183953) (xy 54.113487 -385.23345)
			(xy 54.118002 -385.259072) (xy 54.119526 -385.26847) (xy 54.143752 -385.31038) (xy 54.660546 -385.31038)
			(xy 54.661083 -385.284395) (xy 54.669215 -385.233064) (xy 54.685276 -385.183637) (xy 54.70887 -385.13733)
			(xy 54.739417 -385.095285) (xy 54.776165 -385.058534) (xy 54.818208 -385.027984) (xy 54.864513 -385.004386)
			(xy 54.913939 -384.988321) (xy 54.965269 -384.980185) (xy 54.991254 -384.979672) (xy 55.017266 -384.980092)
			(xy 55.068645 -384.988259) (xy 55.118112 -385.004368) (xy 55.164448 -385.02802) (xy 55.206511 -385.058634)
			(xy 55.243263 -385.095455) (xy 55.273799 -385.137574) (xy 55.297366 -385.183953) (xy 55.313383 -385.23345)
			(xy 55.317898 -385.259072) (xy 55.319422 -385.26847) (xy 55.343648 -385.31038) (xy 55.860696 -385.31038)
			(xy 55.861183 -385.284392) (xy 55.869317 -385.233057) (xy 55.885381 -385.183625) (xy 55.908979 -385.137316)
			(xy 55.939532 -385.095267) (xy 55.976286 -385.058516) (xy 56.018336 -385.027967) (xy 56.064648 -385.004372)
			(xy 56.11408 -384.988311) (xy 56.165416 -384.980181) (xy 56.191404 -384.979672) (xy 56.217448 -384.980129)
			(xy 56.268889 -384.988318) (xy 56.318413 -385.00446) (xy 56.364798 -385.028159) (xy 56.4069 -385.058829)
			(xy 56.44368 -385.095713) (xy 56.474231 -385.137901) (xy 56.497798 -385.184354) (xy 56.513801 -385.233923)
			(xy 56.518302 -385.25958) (xy 56.519572 -385.268978) (xy 56.543508 -385.31038) (xy 57.060592 -385.31038)
			(xy 57.061083 -385.284392) (xy 57.069217 -385.233057) (xy 57.08528 -385.183626) (xy 57.108879 -385.137317)
			(xy 57.139431 -385.095269) (xy 57.176184 -385.058518) (xy 57.218234 -385.027968) (xy 57.264545 -385.004373)
			(xy 57.313977 -384.988312) (xy 57.365312 -384.980182) (xy 57.3913 -384.979672) (xy 57.41731 -384.980142)
			(xy 57.468687 -384.9883) (xy 57.518153 -385.004401) (xy 57.564489 -385.028047) (xy 57.606552 -385.058654)
			(xy 57.643305 -385.095469) (xy 57.673843 -385.137584) (xy 57.697411 -385.183959) (xy 57.713429 -385.233452)
			(xy 57.717944 -385.259072) (xy 57.719468 -385.26847) (xy 57.743694 -385.31038) (xy 58.260488 -385.31038)
			(xy 58.260983 -385.284392) (xy 58.269117 -385.233058) (xy 58.28518 -385.183627) (xy 58.308778 -385.137318)
			(xy 58.339329 -385.09527) (xy 58.376082 -385.058519) (xy 58.418132 -385.02797) (xy 58.464442 -385.004374)
			(xy 58.513873 -384.988313) (xy 58.565208 -384.980182) (xy 58.591196 -384.979672) (xy 58.617206 -384.980145)
			(xy 58.668583 -384.988303) (xy 58.718049 -385.004404) (xy 58.764385 -385.028049) (xy 58.806448 -385.058656)
			(xy 58.843201 -385.09547) (xy 58.873738 -385.137584) (xy 58.897307 -385.183959) (xy 58.913325 -385.233452)
			(xy 58.91784 -385.259072) (xy 58.919364 -385.26847) (xy 58.94359 -385.31038) (xy 59.460638 -385.31038)
			(xy 59.461057 -385.284388) (xy 59.469192 -385.233044) (xy 59.48526 -385.183605) (xy 59.508865 -385.137289)
			(xy 59.539424 -385.095236) (xy 59.576186 -385.058481) (xy 59.618246 -385.02793) (xy 59.664567 -385.004335)
			(xy 59.714008 -384.988277) (xy 59.765354 -384.980152) (xy 59.791346 -384.979672) (xy 59.817357 -384.9801)
			(xy 59.868736 -384.988265) (xy 59.918203 -385.004373) (xy 59.964539 -385.028024) (xy 60.006602 -385.058637)
			(xy 60.043355 -385.095457) (xy 60.073891 -385.137575) (xy 60.097458 -385.183954) (xy 60.113475 -385.233451)
			(xy 60.11799 -385.259072) (xy 60.119514 -385.26847) (xy 60.14374 -385.31038) (xy 60.660534 -385.31038)
			(xy 60.660957 -385.284388) (xy 60.669092 -385.233045) (xy 60.68516 -385.183606) (xy 60.708764 -385.13729)
			(xy 60.739323 -385.095237) (xy 60.776084 -385.058482) (xy 60.818143 -385.027931) (xy 60.864464 -385.004336)
			(xy 60.913905 -384.988278) (xy 60.96525 -384.980152) (xy 60.991242 -384.979672) (xy 61.017253 -384.980103)
			(xy 61.068632 -384.988268) (xy 61.118099 -385.004375) (xy 61.164435 -385.028026) (xy 61.206498 -385.058639)
			(xy 61.24325 -385.095458) (xy 61.273787 -385.137576) (xy 61.297354 -385.183955) (xy 61.313371 -385.233451)
			(xy 61.317886 -385.259072) (xy 61.31941 -385.26847) (xy 61.343636 -385.31038) (xy 61.860684 -385.31038)
			(xy 61.861183 -385.284393) (xy 61.869316 -385.233058) (xy 61.88538 -385.183628) (xy 61.908977 -385.137319)
			(xy 61.939528 -385.095272) (xy 61.976281 -385.058521) (xy 62.018329 -385.027971) (xy 62.064639 -385.004375)
			(xy 62.11407 -384.988314) (xy 62.165405 -384.980182) (xy 62.191392 -384.979672) (xy 62.217436 -384.98014)
			(xy 62.268876 -384.988327) (xy 62.3184 -385.004468) (xy 62.364785 -385.028165) (xy 62.406887 -385.058833)
			(xy 62.443668 -385.095716) (xy 62.474218 -385.137904) (xy 62.497786 -385.184355) (xy 62.513788 -385.233923)
			(xy 62.51829 -385.25958) (xy 62.51956 -385.268978) (xy 62.543496 -385.31038) (xy 63.06058 -385.31038)
			(xy 63.061083 -385.284393) (xy 63.069216 -385.233059) (xy 63.085279 -385.183629) (xy 63.108877 -385.13732)
			(xy 63.139427 -385.095273) (xy 63.176179 -385.058522) (xy 63.218227 -385.027972) (xy 63.264536 -385.004376)
			(xy 63.313967 -384.988314) (xy 63.365301 -384.980182) (xy 63.391288 -384.979672) (xy 63.417298 -384.980152)
			(xy 63.468674 -384.988309) (xy 63.51814 -385.004409) (xy 63.564476 -385.028053) (xy 63.606539 -385.058659)
			(xy 63.643293 -385.095473) (xy 63.67383 -385.137586) (xy 63.697398 -385.18396) (xy 63.713417 -385.233452)
			(xy 63.717932 -385.259072) (xy 63.719456 -385.26847) (xy 63.743682 -385.31038) (xy 64.26073 -385.31038)
			(xy 64.261157 -385.284388) (xy 64.269292 -385.233045) (xy 64.28536 -385.183607) (xy 64.308963 -385.137292)
			(xy 64.339522 -385.095239) (xy 64.376283 -385.058484) (xy 64.418341 -385.027933) (xy 64.464661 -385.004337)
			(xy 64.514102 -384.988279) (xy 64.565446 -384.980152) (xy 64.591438 -384.979672) (xy 64.617483 -384.980099)
			(xy 64.668925 -384.988292) (xy 64.71845 -385.004439) (xy 64.764835 -385.028142) (xy 64.806937 -385.058816)
			(xy 64.843717 -385.095704) (xy 64.874266 -385.137895) (xy 64.897833 -385.18435) (xy 64.913835 -385.233922)
			(xy 64.918336 -385.25958) (xy 64.919606 -385.268978) (xy 64.943542 -385.31038) (xy 65.460626 -385.31038)
			(xy 65.461057 -385.284388) (xy 65.469192 -385.233046) (xy 65.485259 -385.183608) (xy 65.508862 -385.137293)
			(xy 65.53942 -385.09524) (xy 65.576181 -385.058485) (xy 65.618239 -385.027934) (xy 65.664558 -385.004338)
			(xy 65.713999 -384.988279) (xy 65.765342 -384.980153) (xy 65.791334 -384.979672) (xy 65.817345 -384.980111)
			(xy 65.868723 -384.988275) (xy 65.91819 -385.00438) (xy 65.964526 -385.02803) (xy 66.006589 -385.058642)
			(xy 66.043342 -385.09546) (xy 66.073878 -385.137577) (xy 66.097446 -385.183956) (xy 66.113463 -385.233451)
			(xy 66.117978 -385.259072) (xy 66.119502 -385.26847) (xy 66.392298 -385.740402) (xy 66.399664 -385.746244)
			(xy 66.418459 -385.762026) (xy 66.451572 -385.798249) (xy 66.478978 -385.838962) (xy 66.500076 -385.883273)
			(xy 66.514403 -385.930213) (xy 66.521647 -385.978753) (xy 66.522092 -386.003292) (xy 66.521838 -386.014976)
			(xy 66.521938 -386.024687) (xy 66.528458 -386.042964) (xy 66.534538 -386.050536) (xy 66.587116 -386.109972)
			(xy 66.604388 -386.118862) (xy 66.61404 -386.119624) (xy 66.638376 -386.122272) (xy 66.685926 -386.133908)
			(xy 66.731242 -386.152421) (xy 66.773337 -386.177408) (xy 66.811292 -386.208324) (xy 66.844278 -386.244494)
			(xy 66.871576 -386.285129) (xy 66.89259 -386.329342) (xy 66.906861 -386.376168) (xy 66.914078 -386.424586)
			(xy 66.914522 -386.449062) (xy 66.914012 -386.475049) (xy 66.905882 -386.526384) (xy 66.889821 -386.575814)
			(xy 66.866225 -386.622124) (xy 66.835675 -386.664172) (xy 66.798924 -386.700923) (xy 66.756876 -386.731473)
			(xy 66.710566 -386.755069) (xy 66.661136 -386.77113) (xy 66.609801 -386.77926) (xy 66.557827 -386.77926)
			(xy 66.506492 -386.77113) (xy 66.457062 -386.755069) (xy 66.410752 -386.731473) (xy 66.368704 -386.700923)
			(xy 66.331953 -386.664172) (xy 66.301403 -386.622124) (xy 66.277807 -386.575814) (xy 66.261746 -386.526384)
			(xy 66.253616 -386.475049) (xy 66.253106 -386.449062) (xy 66.25336 -386.437378) (xy 66.253284 -386.427665)
			(xy 66.246747 -386.409388) (xy 66.24066 -386.401818) (xy 66.188082 -386.342382) (xy 66.17081 -386.333492)
			(xy 66.161158 -386.33273) (xy 66.136971 -386.330089) (xy 66.089706 -386.318544) (xy 66.044639 -386.300205)
			(xy 66.002741 -386.275469) (xy 65.964915 -386.244867) (xy 65.931975 -386.209058) (xy 65.90463 -386.168815)
			(xy 65.883469 -386.125002) (xy 65.868949 -386.078565) (xy 65.86474 -386.0546) (xy 65.863216 -386.045202)
			(xy 65.59042 -385.57327) (xy 65.583054 -385.567428) (xy 65.564298 -385.551602) (xy 65.53118 -385.515389)
			(xy 65.50377 -385.474685) (xy 65.482665 -385.430382) (xy 65.46833 -385.38345) (xy 65.461076 -385.334916)
			(xy 65.460626 -385.31038) (xy 64.943542 -385.31038) (xy 65.192148 -385.740402) (xy 65.199514 -385.746244)
			(xy 65.218298 -385.762038) (xy 65.251415 -385.798257) (xy 65.278823 -385.838967) (xy 65.299923 -385.883276)
			(xy 65.314252 -385.930215) (xy 65.321497 -385.978754) (xy 65.321942 -386.003292) (xy 65.321688 -386.015484)
			(xy 65.321434 -386.025136) (xy 65.32753 -386.042916) (xy 65.3796 -386.10286) (xy 65.386225 -386.109871)
			(xy 65.403327 -386.118755) (xy 65.412874 -386.120132) (xy 65.439633 -386.123513) (xy 65.491656 -386.137731)
			(xy 65.540682 -386.160202) (xy 65.585411 -386.190331) (xy 65.62466 -386.227319) (xy 65.657386 -386.270185)
			(xy 65.682723 -386.317793) (xy 65.699999 -386.368882) (xy 65.708756 -386.422097) (xy 65.709292 -386.449062)
			(xy 65.708778 -386.476364) (xy 65.69981 -386.530226) (xy 65.682096 -386.581876) (xy 65.656119 -386.629904)
			(xy 65.622589 -386.673) (xy 65.602866 -386.691886) (xy 65.595526 -386.69943) (xy 65.587133 -386.718711)
			(xy 65.58661 -386.729224) (xy 65.58661 -386.8039) (xy 65.587081 -386.814424) (xy 65.59549 -386.833715)
			(xy 65.602866 -386.841238) (xy 65.622507 -386.860196) (xy 65.655988 -386.903303) (xy 65.681945 -386.951318)
			(xy 65.699675 -387.002941) (xy 65.708699 -387.056772) (xy 65.709292 -387.084062) (xy 65.708835 -387.108178)
			(xy 65.70184 -387.155899) (xy 65.687992 -387.2021) (xy 65.667585 -387.245802) (xy 65.654682 -387.26618)
			(xy 65.64884 -387.274816) (xy 65.645284 -387.295136) (xy 65.666366 -387.387338) (xy 65.678558 -387.404102)
			(xy 65.687194 -387.409436) (xy 65.687702 -387.409436) (xy 65.708487 -387.422294) (xy 65.746336 -387.453216)
			(xy 65.779224 -387.489369) (xy 65.806439 -387.529966) (xy 65.827386 -387.574124) (xy 65.841611 -387.620883)
			(xy 65.848805 -387.669225) (xy 65.849246 -387.693662) (xy 65.848845 -387.718036) (xy 65.841698 -387.766257)
			(xy 65.827552 -387.812908) (xy 65.806716 -387.856979) (xy 65.779638 -387.897515) (xy 65.746906 -387.933639)
			(xy 65.728342 -387.94944) (xy 65.72016 -387.956797) (xy 65.710544 -387.976561) (xy 65.7098 -387.98754)
			(xy 65.707514 -388.064248) (xy 65.707797 -388.07523) (xy 65.716473 -388.095381) (xy 65.724278 -388.10311)
			(xy 65.742731 -388.120567) (xy 65.774076 -388.16054) (xy 65.798372 -388.20515) (xy 65.814948 -388.253166)
			(xy 65.823347 -388.303264) (xy 65.823846 -388.328662) (xy 65.823846 -388.328916) (xy 65.823734 -388.340134)
			(xy 65.822082 -388.362508) (xy 65.820544 -388.37362) (xy 65.819274 -388.38251) (xy 65.822576 -388.400036)
			(xy 65.866264 -388.470902) (xy 65.87998 -388.482078) (xy 65.888616 -388.484872) (xy 65.910872 -388.492779)
			(xy 65.952792 -388.514538) (xy 65.990863 -388.542489) (xy 66.024179 -388.575967) (xy 66.051945 -388.614174)
			(xy 66.063114 -388.634986) (xy 66.063622 -388.636002) (xy 66.456052 -389.314944) (xy 66.468771 -389.338269)
			(xy 66.486869 -389.388214) (xy 66.496091 -389.44053) (xy 66.496692 -389.46709) (xy 66.496692 -389.467344)
			(xy 66.496278 -389.491337) (xy 66.488765 -389.538732) (xy 66.47393 -389.584368) (xy 66.45214 -389.627122)
			(xy 66.42393 -389.665941) (xy 66.389995 -389.699869) (xy 66.351171 -389.728071) (xy 66.308412 -389.749853)
			(xy 66.262774 -389.764679) (xy 66.215377 -389.772183) (xy 66.191384 -389.772652) (xy 66.167853 -389.772182)
			(xy 66.121346 -389.764979) (xy 66.076499 -389.750715) (xy 66.034375 -389.729731) (xy 65.995976 -389.702523)
			(xy 65.962213 -389.669738) (xy 65.933889 -389.632154) (xy 65.922398 -389.611616) (xy 65.922144 -389.611108)
			(xy 65.921636 -389.610346) (xy 65.523872 -388.922006) (xy 65.511954 -388.899339) (xy 65.495018 -388.851013)
			(xy 65.486359 -388.800542) (xy 65.485772 -388.77494) (xy 65.485772 -388.774432) (xy 65.48593 -388.763083)
			(xy 65.487706 -388.740454) (xy 65.489328 -388.72922) (xy 65.490237 -388.720506) (xy 65.486718 -388.703355)
			(xy 65.48247 -388.695692) (xy 65.443608 -388.631938) (xy 65.429892 -388.620762) (xy 65.421256 -388.617968)
			(xy 65.398857 -388.609927) (xy 65.356638 -388.58797) (xy 65.318341 -388.559724) (xy 65.284894 -388.525873)
			(xy 65.257109 -388.48724) (xy 65.23566 -388.444761) (xy 65.221067 -388.399467) (xy 65.213683 -388.352456)
			(xy 65.21323 -388.328662) (xy 65.213746 -388.303267) (xy 65.222156 -388.253177) (xy 65.238738 -388.205169)
			(xy 65.263035 -388.160566) (xy 65.294376 -388.120598) (xy 65.312798 -388.10311) (xy 65.320573 -388.095362)
			(xy 65.329254 -388.075221) (xy 65.329562 -388.064248) (xy 65.327276 -387.98754) (xy 65.326447 -387.976584)
			(xy 65.316853 -387.956842) (xy 65.308734 -387.94944) (xy 65.290193 -387.933617) (xy 65.257473 -387.897489)
			(xy 65.230404 -387.856955) (xy 65.209571 -387.81289) (xy 65.195423 -387.766247) (xy 65.188268 -387.718033)
			(xy 65.18783 -387.693662) (xy 65.188247 -387.669545) (xy 65.195254 -387.621821) (xy 65.209113 -387.575621)
			(xy 65.229532 -387.531921) (xy 65.24244 -387.511544) (xy 65.248282 -387.502908) (xy 65.251838 -387.482588)
			(xy 65.230756 -387.390386) (xy 65.218564 -387.373622) (xy 65.209928 -387.368288) (xy 65.20942 -387.368288)
			(xy 65.188651 -387.355406) (xy 65.150801 -387.324488) (xy 65.117911 -387.28834) (xy 65.090694 -387.247747)
			(xy 65.069744 -387.203593) (xy 65.055516 -387.156838) (xy 65.048319 -387.108498) (xy 65.047876 -387.084062)
			(xy 65.048416 -387.056761) (xy 65.057379 -387.002901) (xy 65.075088 -386.951252) (xy 65.101058 -386.903223)
			(xy 65.134582 -386.860125) (xy 65.154302 -386.841238) (xy 65.161627 -386.83368) (xy 65.17003 -386.81441)
			(xy 65.170558 -386.8039) (xy 65.170558 -386.729224) (xy 65.170084 -386.7187) (xy 65.161679 -386.699408)
			(xy 65.154302 -386.691886) (xy 65.134619 -386.67297) (xy 65.101144 -386.629851) (xy 65.075196 -386.581825)
			(xy 65.057475 -386.530194) (xy 65.048463 -386.476355) (xy 65.047876 -386.449062) (xy 65.04813 -386.43687)
			(xy 65.048384 -386.427218) (xy 65.042288 -386.409438) (xy 64.990218 -386.349494) (xy 64.983593 -386.342483)
			(xy 64.96649 -386.3336) (xy 64.956944 -386.332222) (xy 64.930035 -386.328863) (xy 64.877749 -386.314497)
			(xy 64.828506 -386.291796) (xy 64.783624 -386.261369) (xy 64.744304 -386.22403) (xy 64.7116 -386.180778)
			(xy 64.686387 -386.132773) (xy 64.66934 -386.081298) (xy 64.66459 -386.0546) (xy 64.663066 -386.045202)
			(xy 64.390016 -385.572762) (xy 64.382904 -385.56692) (xy 64.364173 -385.551138) (xy 64.331118 -385.514997)
			(xy 64.303761 -385.474372) (xy 64.282702 -385.430153) (xy 64.268401 -385.38331) (xy 64.261173 -385.334869)
			(xy 64.26073 -385.31038) (xy 63.743682 -385.31038) (xy 63.992252 -385.740402) (xy 63.999618 -385.746244)
			(xy 64.018403 -385.762037) (xy 64.05152 -385.798256) (xy 64.078928 -385.838967) (xy 64.100027 -385.883276)
			(xy 64.114356 -385.930214) (xy 64.121601 -385.978754) (xy 64.122046 -386.003292) (xy 64.121792 -386.015484)
			(xy 64.121538 -386.025136) (xy 64.127634 -386.042916) (xy 64.179704 -386.10286) (xy 64.186328 -386.109872)
			(xy 64.203431 -386.118756) (xy 64.212978 -386.120132) (xy 64.239737 -386.123509) (xy 64.29176 -386.137728)
			(xy 64.340786 -386.1602) (xy 64.385516 -386.19033) (xy 64.424764 -386.227318) (xy 64.45749 -386.270184)
			(xy 64.482827 -386.317793) (xy 64.500103 -386.368882) (xy 64.50886 -386.422097) (xy 64.509396 -386.449062)
			(xy 64.50888 -386.476364) (xy 64.499912 -386.530226) (xy 64.482199 -386.581876) (xy 64.456222 -386.629904)
			(xy 64.422693 -386.673) (xy 64.40297 -386.691886) (xy 64.39563 -386.699431) (xy 64.387237 -386.718711)
			(xy 64.386714 -386.729224) (xy 64.386714 -386.8039) (xy 64.387184 -386.814424) (xy 64.395593 -386.833716)
			(xy 64.40297 -386.841238) (xy 64.422612 -386.860195) (xy 64.456092 -386.903303) (xy 64.482049 -386.951318)
			(xy 64.499779 -387.00294) (xy 64.508803 -387.056772) (xy 64.509396 -387.084062) (xy 64.508955 -387.108179)
			(xy 64.501957 -387.155901) (xy 64.488105 -387.202103) (xy 64.467692 -387.245803) (xy 64.454786 -387.26618)
			(xy 64.448944 -387.274816) (xy 64.445388 -387.295136) (xy 64.46647 -387.387338) (xy 64.478662 -387.404102)
			(xy 64.487298 -387.409436) (xy 64.487806 -387.409436) (xy 64.508569 -387.422328) (xy 64.546422 -387.453241)
			(xy 64.579316 -387.489387) (xy 64.606535 -387.529978) (xy 64.627486 -387.574131) (xy 64.641714 -387.620886)
			(xy 64.648909 -387.669226) (xy 64.64935 -387.693662) (xy 64.648947 -387.718036) (xy 64.6418 -387.766257)
			(xy 64.627655 -387.812908) (xy 64.606819 -387.856978) (xy 64.579742 -387.897515) (xy 64.54701 -387.933639)
			(xy 64.528446 -387.94944) (xy 64.520264 -387.956797) (xy 64.510648 -387.976562) (xy 64.509904 -387.98754)
			(xy 64.507618 -388.064248) (xy 64.507899 -388.07523) (xy 64.516577 -388.095382) (xy 64.524382 -388.10311)
			(xy 64.542836 -388.120567) (xy 64.574181 -388.160539) (xy 64.598476 -388.205149) (xy 64.615052 -388.253166)
			(xy 64.623451 -388.303263) (xy 64.62395 -388.328662) (xy 64.62395 -388.328916) (xy 64.623838 -388.340134)
			(xy 64.622186 -388.362508) (xy 64.620648 -388.37362) (xy 64.619378 -388.38251) (xy 64.62268 -388.400036)
			(xy 64.666368 -388.470902) (xy 64.680084 -388.482078) (xy 64.68872 -388.484872) (xy 64.716888 -388.49506)
			(xy 64.768832 -388.524878) (xy 64.791844 -388.544054) (xy 64.813334 -388.56363) (xy 64.849143 -388.609412)
			(xy 64.862964 -388.634986) (xy 64.863726 -388.636256) (xy 65.255902 -389.314944) (xy 65.268705 -389.338288)
			(xy 65.286934 -389.388305) (xy 65.296203 -389.440727) (xy 65.296796 -389.467344) (xy 65.296379 -389.491324)
			(xy 65.288874 -389.538694) (xy 65.274055 -389.584308) (xy 65.252287 -389.627045) (xy 65.224106 -389.665852)
			(xy 65.190203 -389.699777) (xy 65.151414 -389.727984) (xy 65.108692 -389.749779) (xy 65.063087 -389.764628)
			(xy 65.015722 -389.772163) (xy 64.991742 -389.772652) (xy 64.991234 -389.772652) (xy 64.967702 -389.772222)
			(xy 64.921193 -389.765011) (xy 64.876344 -389.750741) (xy 64.834221 -389.729749) (xy 64.795822 -389.702535)
			(xy 64.762061 -389.669745) (xy 64.733738 -389.632157) (xy 64.722248 -389.611616) (xy 64.721994 -389.611108)
			(xy 64.721486 -389.610346) (xy 64.323976 -388.921752) (xy 64.313401 -388.901827) (xy 64.297599 -388.859576)
			(xy 64.288193 -388.815459) (xy 64.286384 -388.792974) (xy 64.285876 -388.781798) (xy 64.285876 -388.774432)
			(xy 64.285968 -388.763087) (xy 64.287622 -388.740458) (xy 64.289178 -388.72922) (xy 64.289178 -388.728966)
			(xy 64.290057 -388.720251) (xy 64.286557 -388.703103) (xy 64.28232 -388.695438) (xy 64.243458 -388.631938)
			(xy 64.229742 -388.620762) (xy 64.221106 -388.617968) (xy 64.198711 -388.609951) (xy 64.15654 -388.587953)
			(xy 64.11829 -388.55968) (xy 64.084889 -388.525816) (xy 64.057144 -388.487182) (xy 64.035727 -388.444712)
			(xy 64.021157 -388.399434) (xy 64.013785 -388.352444) (xy 64.013334 -388.328662) (xy 64.013849 -388.303266)
			(xy 64.022259 -388.253176) (xy 64.038841 -388.205168) (xy 64.063138 -388.160566) (xy 64.09448 -388.120598)
			(xy 64.112902 -388.10311) (xy 64.120678 -388.095362) (xy 64.129358 -388.075221) (xy 64.129666 -388.064248)
			(xy 64.12738 -387.98754) (xy 64.12655 -387.976584) (xy 64.116956 -387.956842) (xy 64.108838 -387.94944)
			(xy 64.090298 -387.933616) (xy 64.057578 -387.897489) (xy 64.030508 -387.856955) (xy 64.009675 -387.81289)
			(xy 63.995527 -387.766246) (xy 63.988372 -387.718033) (xy 63.987934 -387.693662) (xy 63.98835 -387.669545)
			(xy 63.995357 -387.621821) (xy 64.009217 -387.575621) (xy 64.029635 -387.531921) (xy 64.042544 -387.511544)
			(xy 64.048386 -387.502908) (xy 64.051942 -387.482588) (xy 64.03086 -387.390386) (xy 64.018668 -387.373622)
			(xy 64.010032 -387.368288) (xy 64.009524 -387.368288) (xy 63.988755 -387.355405) (xy 63.950906 -387.324487)
			(xy 63.918015 -387.288339) (xy 63.890799 -387.247746) (xy 63.869848 -387.203592) (xy 63.85562 -387.156837)
			(xy 63.848423 -387.108498) (xy 63.84798 -387.084062) (xy 63.848519 -387.056761) (xy 63.857482 -387.002901)
			(xy 63.875191 -386.951252) (xy 63.901162 -386.903223) (xy 63.934686 -386.860125) (xy 63.954406 -386.841238)
			(xy 63.961731 -386.833681) (xy 63.970134 -386.81441) (xy 63.970662 -386.8039) (xy 63.970662 -386.729224)
			(xy 63.970187 -386.7187) (xy 63.961782 -386.699408) (xy 63.954406 -386.691886) (xy 63.934723 -386.67297)
			(xy 63.901249 -386.62985) (xy 63.8753 -386.581825) (xy 63.857579 -386.530194) (xy 63.848567 -386.476355)
			(xy 63.84798 -386.449062) (xy 63.848234 -386.43687) (xy 63.848488 -386.427218) (xy 63.842392 -386.409438)
			(xy 63.790322 -386.349494) (xy 63.783696 -386.342484) (xy 63.766594 -386.333601) (xy 63.757048 -386.332222)
			(xy 63.73014 -386.32886) (xy 63.677854 -386.314494) (xy 63.62861 -386.291794) (xy 63.583728 -386.261367)
			(xy 63.544408 -386.224029) (xy 63.511704 -386.180778) (xy 63.486491 -386.132772) (xy 63.469444 -386.081298)
			(xy 63.464694 -386.0546) (xy 63.46317 -386.045202) (xy 63.190374 -385.57327) (xy 63.183008 -385.567428)
			(xy 63.164263 -385.551589) (xy 63.131143 -385.51538) (xy 63.103729 -385.47468) (xy 63.082622 -385.430379)
			(xy 63.068285 -385.383448) (xy 63.061031 -385.334916) (xy 63.06058 -385.31038) (xy 62.543496 -385.31038)
			(xy 62.792102 -385.740402) (xy 62.799468 -385.746244) (xy 62.818263 -385.762025) (xy 62.851377 -385.798248)
			(xy 62.878783 -385.838961) (xy 62.89988 -385.883273) (xy 62.914207 -385.930213) (xy 62.921451 -385.978753)
			(xy 62.921896 -386.003292) (xy 62.921642 -386.015484) (xy 62.921388 -386.025136) (xy 62.927484 -386.042916)
			(xy 62.979554 -386.10286) (xy 62.986196 -386.109853) (xy 63.003286 -386.118747) (xy 63.012828 -386.120132)
			(xy 63.039593 -386.123468) (xy 63.091616 -386.137695) (xy 63.140642 -386.160174) (xy 63.185371 -386.190309)
			(xy 63.224618 -386.227302) (xy 63.257343 -386.270173) (xy 63.282679 -386.317785) (xy 63.299954 -386.368877)
			(xy 63.308711 -386.422095) (xy 63.309246 -386.449062) (xy 63.308746 -386.476365) (xy 63.299777 -386.530228)
			(xy 63.28206 -386.581879) (xy 63.25608 -386.629907) (xy 63.222545 -386.673002) (xy 63.20282 -386.691886)
			(xy 63.195473 -386.699424) (xy 63.187085 -386.71871) (xy 63.186564 -386.729224) (xy 63.186564 -386.8039)
			(xy 63.187019 -386.814426) (xy 63.195437 -386.833719) (xy 63.20282 -386.841238) (xy 63.222471 -386.860186)
			(xy 63.255948 -386.903297) (xy 63.281902 -386.951315) (xy 63.29963 -387.002939) (xy 63.308653 -387.056771)
			(xy 63.309246 -387.084062) (xy 63.308797 -387.108178) (xy 63.3018 -387.1559) (xy 63.287951 -387.202101)
			(xy 63.267541 -387.245802) (xy 63.254636 -387.26618) (xy 63.248794 -387.274816) (xy 63.245238 -387.295136)
			(xy 63.26632 -387.387338) (xy 63.278512 -387.404102) (xy 63.287148 -387.409436) (xy 63.287656 -387.409436)
			(xy 63.308431 -387.42231) (xy 63.346281 -387.453228) (xy 63.379173 -387.489378) (xy 63.406389 -387.529972)
			(xy 63.427338 -387.574128) (xy 63.441565 -387.620884) (xy 63.448759 -387.669225) (xy 63.4492 -387.693662)
			(xy 63.448779 -387.718035) (xy 63.441633 -387.766255) (xy 63.427491 -387.812904) (xy 63.406658 -387.856974)
			(xy 63.379584 -387.897511) (xy 63.346857 -387.933638) (xy 63.328296 -387.94944) (xy 63.320106 -387.956789)
			(xy 63.310497 -387.97656) (xy 63.309754 -387.98754) (xy 63.307468 -388.064248) (xy 63.307764 -388.075228)
			(xy 63.316433 -388.095379) (xy 63.324232 -388.10311) (xy 63.342676 -388.120577) (xy 63.374025 -388.160546)
			(xy 63.398323 -388.205153) (xy 63.4149 -388.253167) (xy 63.4233 -388.303264) (xy 63.4238 -388.328662)
			(xy 63.4238 -388.328916) (xy 63.423688 -388.340134) (xy 63.422036 -388.362508) (xy 63.420498 -388.37362)
			(xy 63.419228 -388.38251) (xy 63.42253 -388.400036) (xy 63.466218 -388.470902) (xy 63.479934 -388.482078)
			(xy 63.48857 -388.484872) (xy 63.510818 -388.492801) (xy 63.552739 -388.514553) (xy 63.590812 -388.5425)
			(xy 63.624129 -388.575973) (xy 63.651897 -388.614176) (xy 63.663068 -388.634986) (xy 63.663576 -388.636002)
			(xy 64.056006 -389.314944) (xy 64.06881 -389.338287) (xy 64.087038 -389.388304) (xy 64.096307 -389.440727)
			(xy 64.0969 -389.467344) (xy 64.096479 -389.491324) (xy 64.088974 -389.538694) (xy 64.074156 -389.584307)
			(xy 64.052388 -389.627044) (xy 64.024207 -389.665851) (xy 63.990305 -389.699775) (xy 63.951516 -389.727982)
			(xy 63.908794 -389.749778) (xy 63.86319 -389.764627) (xy 63.815826 -389.772163) (xy 63.791846 -389.772652)
			(xy 63.791338 -389.772652) (xy 63.767806 -389.772219) (xy 63.721297 -389.765009) (xy 63.676449 -389.750739)
			(xy 63.634325 -389.729748) (xy 63.595927 -389.702534) (xy 63.562165 -389.669744) (xy 63.533842 -389.632157)
			(xy 63.522352 -389.611616) (xy 63.522098 -389.611108) (xy 63.52159 -389.610346) (xy 63.123826 -388.922006)
			(xy 63.111947 -388.89933) (xy 63.095098 -388.850996) (xy 63.086526 -388.800533) (xy 63.08598 -388.77494)
			(xy 63.08598 -388.774432) (xy 63.086072 -388.763087) (xy 63.087726 -388.740458) (xy 63.089282 -388.72922)
			(xy 63.090183 -388.720506) (xy 63.086668 -388.703356) (xy 63.082424 -388.695692) (xy 63.043562 -388.631938)
			(xy 63.029846 -388.620762) (xy 63.02121 -388.617968) (xy 62.998801 -388.609954) (xy 62.956584 -388.58799)
			(xy 62.918288 -388.559739) (xy 62.884843 -388.525884) (xy 62.85706 -388.487247) (xy 62.835612 -388.444766)
			(xy 62.82102 -388.399469) (xy 62.813637 -388.352456) (xy 62.813184 -388.328662) (xy 62.813715 -388.303267)
			(xy 62.822124 -388.253179) (xy 62.838703 -388.205172) (xy 62.862996 -388.160569) (xy 62.894333 -388.120599)
			(xy 62.912752 -388.10311) (xy 62.920535 -388.095369) (xy 62.929209 -388.075223) (xy 62.929516 -388.064248)
			(xy 62.92723 -387.98754) (xy 62.926384 -387.976586) (xy 62.9168 -387.956846) (xy 62.908688 -387.94944)
			(xy 62.890158 -387.933604) (xy 62.857435 -387.897481) (xy 62.830363 -387.85695) (xy 62.809527 -387.812887)
			(xy 62.795378 -387.766245) (xy 62.788222 -387.718032) (xy 62.787784 -387.693662) (xy 62.788192 -387.669544)
			(xy 62.7952 -387.62182) (xy 62.809062 -387.575619) (xy 62.829484 -387.53192) (xy 62.842394 -387.511544)
			(xy 62.848236 -387.502908) (xy 62.851792 -387.482588) (xy 62.83071 -387.390386) (xy 62.818518 -387.373622)
			(xy 62.809882 -387.368288) (xy 62.809374 -387.368288) (xy 62.788617 -387.355387) (xy 62.750765 -387.324474)
			(xy 62.717871 -387.28833) (xy 62.690653 -387.24774) (xy 62.6697 -387.203589) (xy 62.655471 -387.156835)
			(xy 62.648273 -387.108497) (xy 62.64783 -387.084062) (xy 62.648353 -387.05676) (xy 62.657318 -387.002899)
			(xy 62.675029 -386.951248) (xy 62.701004 -386.90322) (xy 62.734533 -386.860124) (xy 62.754256 -386.841238)
			(xy 62.761589 -386.833687) (xy 62.769985 -386.814412) (xy 62.770512 -386.8039) (xy 62.770512 -386.729224)
			(xy 62.770022 -386.718702) (xy 62.761626 -386.699411) (xy 62.754256 -386.691886) (xy 62.734564 -386.672979)
			(xy 62.701093 -386.629856) (xy 62.675147 -386.581828) (xy 62.657428 -386.530195) (xy 62.648417 -386.476356)
			(xy 62.64783 -386.449062) (xy 62.648084 -386.43687) (xy 62.648338 -386.427218) (xy 62.642242 -386.409438)
			(xy 62.590172 -386.349494) (xy 62.583564 -386.342465) (xy 62.566449 -386.333593) (xy 62.556898 -386.332222)
			(xy 62.529995 -386.32882) (xy 62.47771 -386.314462) (xy 62.428467 -386.291769) (xy 62.383583 -386.261349)
			(xy 62.344263 -386.224015) (xy 62.311557 -386.180769) (xy 62.286342 -386.132768) (xy 62.269294 -386.081297)
			(xy 62.264544 -386.0546) (xy 62.26302 -386.045202) (xy 61.98997 -385.572762) (xy 61.982858 -385.56692)
			(xy 61.964118 -385.551149) (xy 61.931065 -385.515005) (xy 61.90371 -385.474377) (xy 61.882653 -385.430156)
			(xy 61.868354 -385.383312) (xy 61.861127 -385.334869) (xy 61.860684 -385.31038) (xy 61.343636 -385.31038)
			(xy 61.592206 -385.740402) (xy 61.599572 -385.746244) (xy 61.618368 -385.762024) (xy 61.651482 -385.798248)
			(xy 61.678887 -385.838961) (xy 61.699984 -385.883273) (xy 61.714311 -385.930213) (xy 61.721555 -385.978753)
			(xy 61.722 -386.003292) (xy 61.721746 -386.015484) (xy 61.721492 -386.025136) (xy 61.727588 -386.042916)
			(xy 61.779658 -386.10286) (xy 61.786298 -386.109854) (xy 61.803389 -386.118748) (xy 61.812932 -386.120132)
			(xy 61.839697 -386.123465) (xy 61.891721 -386.137692) (xy 61.940747 -386.160172) (xy 61.985476 -386.190308)
			(xy 62.024722 -386.227301) (xy 62.057447 -386.270172) (xy 62.082783 -386.317785) (xy 62.100058 -386.368877)
			(xy 62.108815 -386.422095) (xy 62.10935 -386.449062) (xy 62.108849 -386.476365) (xy 62.09988 -386.530228)
			(xy 62.082163 -386.581879) (xy 62.056183 -386.629907) (xy 62.022649 -386.673002) (xy 62.002924 -386.691886)
			(xy 61.995578 -386.699425) (xy 61.987189 -386.71871) (xy 61.986668 -386.729224) (xy 61.986668 -386.8039)
			(xy 61.987122 -386.814427) (xy 61.99554 -386.833719) (xy 62.002924 -386.841238) (xy 62.022576 -386.860185)
			(xy 62.056053 -386.903297) (xy 62.082006 -386.951315) (xy 62.099735 -387.002939) (xy 62.108757 -387.056771)
			(xy 62.10935 -387.084062) (xy 62.1089 -387.108178) (xy 62.101904 -387.1559) (xy 62.088054 -387.202101)
			(xy 62.067644 -387.245802) (xy 62.05474 -387.26618) (xy 62.048898 -387.274816) (xy 62.045342 -387.295136)
			(xy 62.066424 -387.387338) (xy 62.078616 -387.404102) (xy 62.087252 -387.409436) (xy 62.08776 -387.409436)
			(xy 62.108536 -387.422309) (xy 62.146386 -387.453227) (xy 62.179277 -387.489377) (xy 62.206493 -387.529971)
			(xy 62.227442 -387.574127) (xy 62.241669 -387.620884) (xy 62.248863 -387.669225) (xy 62.249304 -387.693662)
			(xy 62.248882 -387.718035) (xy 62.241736 -387.766255) (xy 62.227594 -387.812904) (xy 62.206761 -387.856974)
			(xy 62.179688 -387.897511) (xy 62.146961 -387.933638) (xy 62.1284 -387.94944) (xy 62.120211 -387.95679)
			(xy 62.110601 -387.97656) (xy 62.109858 -387.98754) (xy 62.107572 -388.064248) (xy 62.107867 -388.075228)
			(xy 62.116537 -388.095379) (xy 62.124336 -388.10311) (xy 62.142781 -388.120576) (xy 62.174129 -388.160545)
			(xy 62.198427 -388.205153) (xy 62.215004 -388.253167) (xy 62.223404 -388.303264) (xy 62.223904 -388.328662)
			(xy 62.223904 -388.328916) (xy 62.223792 -388.340134) (xy 62.22214 -388.362508) (xy 62.220602 -388.37362)
			(xy 62.219332 -388.38251) (xy 62.222634 -388.400036) (xy 62.266322 -388.470902) (xy 62.280038 -388.482078)
			(xy 62.288674 -388.484872) (xy 62.316838 -388.495071) (xy 62.368784 -388.524881) (xy 62.391798 -388.544054)
			(xy 62.413283 -388.563635) (xy 62.449096 -388.609414) (xy 62.462918 -388.634986) (xy 62.46368 -388.636256)
			(xy 62.855856 -389.314944) (xy 62.868575 -389.338269) (xy 62.886673 -389.388214) (xy 62.895895 -389.440529)
			(xy 62.896496 -389.46709) (xy 62.896496 -389.467344) (xy 62.896078 -389.491337) (xy 62.888565 -389.538731)
			(xy 62.873731 -389.584367) (xy 62.851941 -389.627121) (xy 62.823731 -389.665939) (xy 62.789797 -389.699868)
			(xy 62.750973 -389.72807) (xy 62.708215 -389.749852) (xy 62.662577 -389.764678) (xy 62.615181 -389.772182)
			(xy 62.591188 -389.772652) (xy 62.567657 -389.772178) (xy 62.521151 -389.764976) (xy 62.476303 -389.750713)
			(xy 62.434179 -389.729729) (xy 62.39578 -389.702522) (xy 62.362018 -389.669737) (xy 62.333693 -389.632154)
			(xy 62.322202 -389.611616) (xy 62.321948 -389.611108) (xy 62.32144 -389.610346) (xy 61.92393 -388.921752)
			(xy 61.913359 -388.901824) (xy 61.897555 -388.859575) (xy 61.888147 -388.815459) (xy 61.886338 -388.792974)
			(xy 61.88583 -388.781798) (xy 61.885576 -388.775194) (xy 61.885576 -388.77367) (xy 61.885759 -388.762512)
			(xy 61.887536 -388.740265) (xy 61.889132 -388.72922) (xy 61.889132 -388.728966) (xy 61.890017 -388.720251)
			(xy 61.886514 -388.703103) (xy 61.882274 -388.695438) (xy 61.843412 -388.631938) (xy 61.829696 -388.620762)
			(xy 61.82106 -388.617968) (xy 61.798655 -388.609978) (xy 61.756485 -388.587973) (xy 61.718237 -388.559695)
			(xy 61.684838 -388.525827) (xy 61.657095 -388.48719) (xy 61.63568 -388.444717) (xy 61.62111 -388.399437)
			(xy 61.613739 -388.352445) (xy 61.613288 -388.328662) (xy 61.613818 -388.303267) (xy 61.622226 -388.253179)
			(xy 61.638806 -388.205171) (xy 61.663099 -388.160568) (xy 61.694437 -388.120599) (xy 61.712856 -388.10311)
			(xy 61.72064 -388.095369) (xy 61.729314 -388.075223) (xy 61.72962 -388.064248) (xy 61.727334 -387.98754)
			(xy 61.726487 -387.976587) (xy 61.716903 -387.956846) (xy 61.708792 -387.94944) (xy 61.690263 -387.933603)
			(xy 61.65754 -387.89748) (xy 61.630467 -387.856949) (xy 61.609631 -387.812887) (xy 61.595482 -387.766245)
			(xy 61.588326 -387.718032) (xy 61.587888 -387.693662) (xy 61.588296 -387.669544) (xy 61.595304 -387.62182)
			(xy 61.609165 -387.575619) (xy 61.629587 -387.53192) (xy 61.642498 -387.511544) (xy 61.64834 -387.502908)
			(xy 61.651896 -387.482588) (xy 61.630814 -387.390386) (xy 61.618622 -387.373622) (xy 61.609986 -387.368288)
			(xy 61.609478 -387.368288) (xy 61.588722 -387.355385) (xy 61.550869 -387.324473) (xy 61.517976 -387.288329)
			(xy 61.490757 -387.24774) (xy 61.469805 -387.203588) (xy 61.455575 -387.156835) (xy 61.448377 -387.108497)
			(xy 61.447934 -387.084062) (xy 61.448456 -387.05676) (xy 61.457421 -387.002898) (xy 61.475132 -386.951248)
			(xy 61.501108 -386.903219) (xy 61.534637 -386.860123) (xy 61.55436 -386.841238) (xy 61.561693 -386.833688)
			(xy 61.570089 -386.814412) (xy 61.570616 -386.8039) (xy 61.570616 -386.729224) (xy 61.570124 -386.718702)
			(xy 61.561729 -386.699411) (xy 61.55436 -386.691886) (xy 61.534669 -386.672978) (xy 61.501197 -386.629856)
			(xy 61.475251 -386.581828) (xy 61.457532 -386.530195) (xy 61.448521 -386.476356) (xy 61.447934 -386.449062)
			(xy 61.448188 -386.43687) (xy 61.448442 -386.427218) (xy 61.442346 -386.409438) (xy 61.390276 -386.349494)
			(xy 61.383666 -386.342467) (xy 61.366552 -386.333593) (xy 61.357002 -386.332222) (xy 61.3301 -386.328817)
			(xy 61.277815 -386.31446) (xy 61.228571 -386.291767) (xy 61.183688 -386.261347) (xy 61.144367 -386.224014)
			(xy 61.111661 -386.180768) (xy 61.086447 -386.132767) (xy 61.069398 -386.081296) (xy 61.064648 -386.0546)
			(xy 61.063124 -386.045202) (xy 60.790328 -385.57327) (xy 60.782962 -385.567428) (xy 60.764207 -385.5516)
			(xy 60.73109 -385.515388) (xy 60.703678 -385.474685) (xy 60.682574 -385.430382) (xy 60.668238 -385.38345)
			(xy 60.660984 -385.334916) (xy 60.660534 -385.31038) (xy 60.14374 -385.31038) (xy 60.39231 -385.740402)
			(xy 60.399676 -385.746244) (xy 60.418452 -385.762047) (xy 60.451571 -385.798263) (xy 60.478981 -385.838971)
			(xy 60.500083 -385.883279) (xy 60.514413 -385.930216) (xy 60.521658 -385.978754) (xy 60.522104 -386.003292)
			(xy 60.52185 -386.015484) (xy 60.521596 -386.025136) (xy 60.527692 -386.042916) (xy 60.586112 -386.110226)
			(xy 60.603384 -386.119116) (xy 60.612782 -386.120132) (xy 60.639542 -386.123506) (xy 60.691565 -386.137726)
			(xy 60.74059 -386.160198) (xy 60.78532 -386.190328) (xy 60.824568 -386.227317) (xy 60.857294 -386.270183)
			(xy 60.882631 -386.317792) (xy 60.899907 -386.368881) (xy 60.908664 -386.422097) (xy 60.9092 -386.449062)
			(xy 60.908683 -386.476364) (xy 60.899715 -386.530225) (xy 60.882002 -386.581875) (xy 60.856026 -386.629904)
			(xy 60.822497 -386.673) (xy 60.802774 -386.691886) (xy 60.795435 -386.699432) (xy 60.787041 -386.718711)
			(xy 60.786518 -386.729224) (xy 60.786518 -386.8039) (xy 60.786987 -386.814424) (xy 60.795397 -386.833716)
			(xy 60.802774 -386.841238) (xy 60.822416 -386.860194) (xy 60.855897 -386.903302) (xy 60.881853 -386.951318)
			(xy 60.899583 -387.00294) (xy 60.908607 -387.056772) (xy 60.9092 -387.084062) (xy 60.908758 -387.108179)
			(xy 60.901761 -387.155901) (xy 60.887909 -387.202102) (xy 60.867496 -387.245803) (xy 60.85459 -387.26618)
			(xy 60.848748 -387.274816) (xy 60.845192 -387.295136) (xy 60.866274 -387.387338) (xy 60.878466 -387.404102)
			(xy 60.887102 -387.409436) (xy 60.88761 -387.409436) (xy 60.908374 -387.422327) (xy 60.946227 -387.45324)
			(xy 60.979121 -387.489386) (xy 61.006339 -387.529977) (xy 61.02729 -387.574131) (xy 61.041518 -387.620886)
			(xy 61.048713 -387.669226) (xy 61.049154 -387.693662) (xy 61.04875 -387.718036) (xy 61.041603 -387.766257)
			(xy 61.027458 -387.812908) (xy 61.006622 -387.856978) (xy 60.979545 -387.897514) (xy 60.946814 -387.933639)
			(xy 60.92825 -387.94944) (xy 60.920069 -387.956798) (xy 60.910453 -387.976562) (xy 60.909708 -387.98754)
			(xy 60.907422 -388.064248) (xy 60.907702 -388.07523) (xy 60.91638 -388.095382) (xy 60.924186 -388.10311)
			(xy 60.942641 -388.120566) (xy 60.973985 -388.160539) (xy 60.998281 -388.205149) (xy 61.014856 -388.253166)
			(xy 61.023255 -388.303263) (xy 61.023754 -388.328662) (xy 61.023754 -388.328916) (xy 61.023642 -388.340134)
			(xy 61.02199 -388.362508) (xy 61.020452 -388.37362) (xy 61.019182 -388.38251) (xy 61.022484 -388.400036)
			(xy 61.066172 -388.470902) (xy 61.079888 -388.482078) (xy 61.088524 -388.484872) (xy 61.110781 -388.492775)
			(xy 61.152701 -388.514535) (xy 61.190772 -388.542488) (xy 61.224087 -388.575967) (xy 61.251853 -388.614174)
			(xy 61.263022 -388.634986) (xy 61.26353 -388.636002) (xy 61.65596 -389.314944) (xy 61.66868 -389.338269)
			(xy 61.686777 -389.388214) (xy 61.695999 -389.440529) (xy 61.6966 -389.46709) (xy 61.6966 -389.467344)
			(xy 61.696178 -389.491337) (xy 61.688665 -389.538731) (xy 61.673831 -389.584366) (xy 61.652041 -389.627119)
			(xy 61.623832 -389.665938) (xy 61.589898 -389.699866) (xy 61.551075 -389.728069) (xy 61.508318 -389.749851)
			(xy 61.46268 -389.764677) (xy 61.415285 -389.772182) (xy 61.391292 -389.772652) (xy 61.367761 -389.772175)
			(xy 61.321255 -389.764973) (xy 61.276407 -389.750711) (xy 61.234284 -389.729728) (xy 61.195885 -389.702521)
			(xy 61.162122 -389.669737) (xy 61.133797 -389.632154) (xy 61.122306 -389.611616) (xy 61.122052 -389.611108)
			(xy 61.121544 -389.610346) (xy 60.72378 -388.922006) (xy 60.711863 -388.899339) (xy 60.694927 -388.851013)
			(xy 60.686267 -388.800542) (xy 60.68568 -388.77494) (xy 60.68568 -388.774432) (xy 60.685838 -388.763083)
			(xy 60.687614 -388.740454) (xy 60.689236 -388.72922) (xy 60.690144 -388.720506) (xy 60.686625 -388.703355)
			(xy 60.682378 -388.695692) (xy 60.643516 -388.631938) (xy 60.6298 -388.620762) (xy 60.621164 -388.617968)
			(xy 60.598766 -388.609923) (xy 60.556547 -388.587967) (xy 60.51825 -388.559721) (xy 60.484803 -388.525871)
			(xy 60.457018 -388.487239) (xy 60.435568 -388.44476) (xy 60.420975 -388.399466) (xy 60.413591 -388.352455)
			(xy 60.413138 -388.328662) (xy 60.413652 -388.303266) (xy 60.422062 -388.253176) (xy 60.438644 -388.205168)
			(xy 60.462941 -388.160565) (xy 60.494284 -388.120598) (xy 60.512706 -388.10311) (xy 60.520482 -388.095363)
			(xy 60.529162 -388.075222) (xy 60.52947 -388.064248) (xy 60.527184 -387.98754) (xy 60.526353 -387.976584)
			(xy 60.51676 -387.956843) (xy 60.508642 -387.94944) (xy 60.490103 -387.933615) (xy 60.457382 -387.897488)
			(xy 60.430313 -387.856954) (xy 60.409479 -387.81289) (xy 60.395331 -387.766246) (xy 60.388176 -387.718033)
			(xy 60.387738 -387.693662) (xy 60.388154 -387.669545) (xy 60.395161 -387.621821) (xy 60.40902 -387.57562)
			(xy 60.429439 -387.531921) (xy 60.442348 -387.511544) (xy 60.44819 -387.502908) (xy 60.451746 -387.482588)
			(xy 60.430664 -387.390386) (xy 60.418472 -387.373622) (xy 60.409836 -387.368288) (xy 60.409328 -387.368288)
			(xy 60.38856 -387.355403) (xy 60.350711 -387.324486) (xy 60.31782 -387.288338) (xy 60.290603 -387.247746)
			(xy 60.269652 -387.203592) (xy 60.255424 -387.156837) (xy 60.248227 -387.108498) (xy 60.247784 -387.084062)
			(xy 60.248322 -387.056761) (xy 60.257285 -387.002901) (xy 60.274994 -386.951251) (xy 60.300965 -386.903222)
			(xy 60.33449 -386.860125) (xy 60.35421 -386.841238) (xy 60.361536 -386.833681) (xy 60.369938 -386.81441)
			(xy 60.370466 -386.8039) (xy 60.370466 -386.729224) (xy 60.369989 -386.7187) (xy 60.361586 -386.699408)
			(xy 60.35421 -386.691886) (xy 60.334528 -386.672969) (xy 60.301053 -386.62985) (xy 60.275104 -386.581825)
			(xy 60.257383 -386.530194) (xy 60.248371 -386.476355) (xy 60.247784 -386.449062) (xy 60.248038 -386.43687)
			(xy 60.248292 -386.427218) (xy 60.242196 -386.409438) (xy 60.183776 -386.342128) (xy 60.166504 -386.333238)
			(xy 60.157106 -386.332222) (xy 60.130204 -386.328814) (xy 60.077919 -386.314457) (xy 60.028676 -386.291765)
			(xy 59.983792 -386.261346) (xy 59.944471 -386.224013) (xy 59.911765 -386.180768) (xy 59.886551 -386.132767)
			(xy 59.869502 -386.081296) (xy 59.864752 -386.0546) (xy 59.863228 -386.045202) (xy 59.590432 -385.57327)
			(xy 59.583066 -385.567428) (xy 59.564312 -385.551599) (xy 59.531194 -385.515387) (xy 59.503783 -385.474684)
			(xy 59.482678 -385.430382) (xy 59.468342 -385.38345) (xy 59.461088 -385.334916) (xy 59.460638 -385.31038)
			(xy 58.94359 -385.31038) (xy 59.19216 -385.740402) (xy 59.199526 -385.746244) (xy 59.218313 -385.762035)
			(xy 59.251429 -385.798255) (xy 59.278837 -385.838966) (xy 59.299936 -385.883276) (xy 59.314265 -385.930214)
			(xy 59.321509 -385.978754) (xy 59.321954 -386.003292) (xy 59.3217 -386.015484) (xy 59.321446 -386.025136)
			(xy 59.327542 -386.042916) (xy 59.379612 -386.10286) (xy 59.386233 -386.109875) (xy 59.403338 -386.118757)
			(xy 59.412886 -386.120132) (xy 59.439646 -386.123503) (xy 59.491669 -386.137723) (xy 59.540695 -386.160196)
			(xy 59.585425 -386.190326) (xy 59.624673 -386.227315) (xy 59.657399 -386.270182) (xy 59.682735 -386.317792)
			(xy 59.700011 -386.368881) (xy 59.708768 -386.422096) (xy 59.709304 -386.449062) (xy 59.708786 -386.476364)
			(xy 59.699818 -386.530225) (xy 59.682105 -386.581875) (xy 59.656129 -386.629904) (xy 59.6226 -386.673)
			(xy 59.602878 -386.691886) (xy 59.59554 -386.699432) (xy 59.587145 -386.718711) (xy 59.586622 -386.729224)
			(xy 59.586622 -386.8039) (xy 59.587089 -386.814425) (xy 59.5955 -386.833716) (xy 59.602878 -386.841238)
			(xy 59.622521 -386.860194) (xy 59.656001 -386.903302) (xy 59.681958 -386.951318) (xy 59.699687 -387.00294)
			(xy 59.708711 -387.056772) (xy 59.709304 -387.084062) (xy 59.708861 -387.108179) (xy 59.701864 -387.155901)
			(xy 59.688013 -387.202102) (xy 59.6676 -387.245803) (xy 59.654694 -387.26618) (xy 59.648852 -387.274816)
			(xy 59.645296 -387.295136) (xy 59.666378 -387.387338) (xy 59.67857 -387.404102) (xy 59.687206 -387.409436)
			(xy 59.687714 -387.409436) (xy 59.708479 -387.422325) (xy 59.746332 -387.453239) (xy 59.779225 -387.489385)
			(xy 59.806443 -387.529977) (xy 59.827394 -387.574131) (xy 59.841622 -387.620886) (xy 59.848817 -387.669226)
			(xy 59.849258 -387.693662) (xy 59.848852 -387.718036) (xy 59.841705 -387.766257) (xy 59.827561 -387.812907)
			(xy 59.806725 -387.856978) (xy 59.779648 -387.897514) (xy 59.746917 -387.933639) (xy 59.728354 -387.94944)
			(xy 59.720173 -387.956799) (xy 59.710557 -387.976562) (xy 59.709812 -387.98754) (xy 59.707526 -388.064248)
			(xy 59.707805 -388.07523) (xy 59.716484 -388.095382) (xy 59.72429 -388.10311) (xy 59.742746 -388.120565)
			(xy 59.77409 -388.160539) (xy 59.798385 -388.205149) (xy 59.81496 -388.253165) (xy 59.823359 -388.303263)
			(xy 59.823858 -388.328662) (xy 59.823858 -388.328916) (xy 59.823746 -388.340134) (xy 59.822094 -388.362508)
			(xy 59.820556 -388.37362) (xy 59.819286 -388.38251) (xy 59.822588 -388.400036) (xy 59.866276 -388.470902)
			(xy 59.879992 -388.482078) (xy 59.888628 -388.484872) (xy 59.910868 -388.49282) (xy 59.95279 -388.514567)
			(xy 59.990865 -388.542509) (xy 60.024184 -388.575978) (xy 60.051954 -388.614178) (xy 60.063126 -388.634986)
			(xy 60.063634 -388.636002) (xy 60.456064 -389.314944) (xy 60.468784 -389.338268) (xy 60.486881 -389.388213)
			(xy 60.496104 -389.440529) (xy 60.496704 -389.46709) (xy 60.496704 -389.467344) (xy 60.496278 -389.491337)
			(xy 60.488765 -389.53873) (xy 60.473931 -389.584365) (xy 60.452142 -389.627118) (xy 60.423933 -389.665937)
			(xy 60.39 -389.699865) (xy 60.351177 -389.728067) (xy 60.308421 -389.74985) (xy 60.262783 -389.764676)
			(xy 60.215389 -389.772182) (xy 60.191396 -389.772652) (xy 60.167865 -389.772172) (xy 60.121359 -389.764971)
			(xy 60.076512 -389.750709) (xy 60.034388 -389.729726) (xy 59.995989 -389.70252) (xy 59.962226 -389.669736)
			(xy 59.933902 -389.632154) (xy 59.92241 -389.611616) (xy 59.922156 -389.611108) (xy 59.921648 -389.610346)
			(xy 59.523884 -388.922006) (xy 59.511967 -388.899338) (xy 59.495031 -388.851013) (xy 59.486371 -388.800542)
			(xy 59.485784 -388.77494) (xy 59.485784 -388.774432) (xy 59.485942 -388.763083) (xy 59.487718 -388.740454)
			(xy 59.48934 -388.72922) (xy 59.490247 -388.720506) (xy 59.486729 -388.703356) (xy 59.482482 -388.695692)
			(xy 59.44362 -388.631938) (xy 59.429904 -388.620762) (xy 59.421268 -388.617968) (xy 59.398871 -388.609921)
			(xy 59.356652 -388.587965) (xy 59.318355 -388.55972) (xy 59.284907 -388.52587) (xy 59.257122 -388.487238)
			(xy 59.235672 -388.44476) (xy 59.221079 -388.399466) (xy 59.213695 -388.352455) (xy 59.213242 -388.328662)
			(xy 59.213754 -388.303266) (xy 59.222165 -388.253176) (xy 59.238747 -388.205168) (xy 59.263045 -388.160565)
			(xy 59.294388 -388.120598) (xy 59.31281 -388.10311) (xy 59.320587 -388.095363) (xy 59.329266 -388.075222)
			(xy 59.329574 -388.064248) (xy 59.327288 -387.98754) (xy 59.326456 -387.976584) (xy 59.316863 -387.956843)
			(xy 59.308746 -387.94944) (xy 59.290207 -387.933614) (xy 59.257487 -387.897487) (xy 59.230417 -387.856954)
			(xy 59.209583 -387.812889) (xy 59.195435 -387.766246) (xy 59.18828 -387.718033) (xy 59.187842 -387.693662)
			(xy 59.188257 -387.669545) (xy 59.195264 -387.621821) (xy 59.209124 -387.57562) (xy 59.229543 -387.531921)
			(xy 59.242452 -387.511544) (xy 59.248294 -387.502908) (xy 59.25185 -387.482588) (xy 59.230768 -387.390386)
			(xy 59.218576 -387.373622) (xy 59.20994 -387.368288) (xy 59.209432 -387.368288) (xy 59.188665 -387.355402)
			(xy 59.150815 -387.324485) (xy 59.117924 -387.288337) (xy 59.090707 -387.247745) (xy 59.069757 -387.203592)
			(xy 59.055528 -387.156837) (xy 59.048331 -387.108498) (xy 59.047888 -387.084062) (xy 59.048424 -387.056761)
			(xy 59.057388 -387.002901) (xy 59.075097 -386.951251) (xy 59.101069 -386.903222) (xy 59.134593 -386.860125)
			(xy 59.154314 -386.841238) (xy 59.161641 -386.833682) (xy 59.170042 -386.814411) (xy 59.17057 -386.8039)
			(xy 59.17057 -386.729224) (xy 59.170092 -386.7187) (xy 59.161689 -386.699409) (xy 59.154314 -386.691886)
			(xy 59.134633 -386.672968) (xy 59.101158 -386.629849) (xy 59.075208 -386.581824) (xy 59.057488 -386.530193)
			(xy 59.048475 -386.476355) (xy 59.047888 -386.449062) (xy 59.048142 -386.43687) (xy 59.048396 -386.427218)
			(xy 59.0423 -386.409438) (xy 58.99023 -386.349494) (xy 58.983601 -386.342488) (xy 58.966501 -386.333602)
			(xy 58.956956 -386.332222) (xy 58.930049 -386.328854) (xy 58.877763 -386.314489) (xy 58.828519 -386.29179)
			(xy 58.783637 -386.261364) (xy 58.744317 -386.224027) (xy 58.711613 -386.180776) (xy 58.686399 -386.132772)
			(xy 58.669352 -386.081298) (xy 58.664602 -386.0546) (xy 58.663078 -386.045202) (xy 58.390282 -385.57327)
			(xy 58.382916 -385.567428) (xy 58.364173 -385.551587) (xy 58.331052 -385.515379) (xy 58.303638 -385.474679)
			(xy 58.282531 -385.430379) (xy 58.268193 -385.383448) (xy 58.260939 -385.334916) (xy 58.260488 -385.31038)
			(xy 57.743694 -385.31038) (xy 57.992264 -385.740402) (xy 57.99963 -385.746244) (xy 58.018418 -385.762034)
			(xy 58.051533 -385.798254) (xy 58.078941 -385.838965) (xy 58.10004 -385.883275) (xy 58.114369 -385.930214)
			(xy 58.121613 -385.978754) (xy 58.122058 -386.003292) (xy 58.121804 -386.015484) (xy 58.12155 -386.025136)
			(xy 58.127646 -386.042916) (xy 58.186066 -386.110226) (xy 58.203338 -386.119116) (xy 58.212736 -386.120132)
			(xy 58.239502 -386.123462) (xy 58.291525 -386.13769) (xy 58.340551 -386.16017) (xy 58.38528 -386.190306)
			(xy 58.424527 -386.2273) (xy 58.457252 -386.270171) (xy 58.482587 -386.317784) (xy 58.499862 -386.368877)
			(xy 58.508619 -386.422095) (xy 58.509154 -386.449062) (xy 58.508652 -386.476365) (xy 58.499683 -386.530228)
			(xy 58.481966 -386.581878) (xy 58.455987 -386.629907) (xy 58.422453 -386.673001) (xy 58.402728 -386.691886)
			(xy 58.395382 -386.699426) (xy 58.386994 -386.71871) (xy 58.386472 -386.729224) (xy 58.386472 -386.8039)
			(xy 58.386925 -386.814427) (xy 58.395344 -386.833719) (xy 58.402728 -386.841238) (xy 58.42238 -386.860184)
			(xy 58.455857 -386.903296) (xy 58.481811 -386.951314) (xy 58.499539 -387.002939) (xy 58.508561 -387.056771)
			(xy 58.509154 -387.084062) (xy 58.508703 -387.108178) (xy 58.501707 -387.1559) (xy 58.487858 -387.202101)
			(xy 58.467448 -387.245802) (xy 58.454544 -387.26618) (xy 58.448702 -387.274816) (xy 58.445146 -387.295136)
			(xy 58.466228 -387.387338) (xy 58.47842 -387.404102) (xy 58.487056 -387.409436) (xy 58.487564 -387.409436)
			(xy 58.508341 -387.422307) (xy 58.546191 -387.453226) (xy 58.579082 -387.489376) (xy 58.606297 -387.529971)
			(xy 58.627246 -387.574127) (xy 58.641473 -387.620884) (xy 58.648667 -387.669225) (xy 58.649108 -387.693662)
			(xy 58.648684 -387.718035) (xy 58.641539 -387.766254) (xy 58.627396 -387.812904) (xy 58.606564 -387.856974)
			(xy 58.579491 -387.897511) (xy 58.546765 -387.933637) (xy 58.528204 -387.94944) (xy 58.520015 -387.956791)
			(xy 58.510405 -387.97656) (xy 58.509662 -387.98754) (xy 58.507376 -388.064248) (xy 58.50767 -388.075228)
			(xy 58.51634 -388.095379) (xy 58.52414 -388.10311) (xy 58.542586 -388.120575) (xy 58.573933 -388.160545)
			(xy 58.598231 -388.205152) (xy 58.614809 -388.253167) (xy 58.623208 -388.303264) (xy 58.623708 -388.328662)
			(xy 58.623708 -388.328916) (xy 58.623596 -388.340134) (xy 58.621944 -388.362508) (xy 58.620406 -388.37362)
			(xy 58.619136 -388.38251) (xy 58.622438 -388.400036) (xy 58.666126 -388.470902) (xy 58.679842 -388.482078)
			(xy 58.688478 -388.484872) (xy 58.710727 -388.492796) (xy 58.752648 -388.51455) (xy 58.790721 -388.542497)
			(xy 58.824038 -388.575972) (xy 58.851806 -388.614176) (xy 58.862976 -388.634986) (xy 58.863484 -388.636002)
			(xy 59.255914 -389.314944) (xy 59.268718 -389.338287) (xy 59.286947 -389.388304) (xy 59.296215 -389.440727)
			(xy 59.296808 -389.467344) (xy 59.296379 -389.491324) (xy 59.288874 -389.538693) (xy 59.274056 -389.584306)
			(xy 59.252289 -389.627041) (xy 59.224109 -389.665848) (xy 59.190208 -389.699772) (xy 59.15142 -389.72798)
			(xy 59.1087 -389.749776) (xy 59.063097 -389.764625) (xy 59.015733 -389.772162) (xy 58.991754 -389.772652)
			(xy 58.991246 -389.772652) (xy 58.967714 -389.772212) (xy 58.921206 -389.765003) (xy 58.876357 -389.750735)
			(xy 58.834234 -389.729745) (xy 58.795835 -389.702532) (xy 58.762074 -389.669743) (xy 58.733751 -389.632156)
			(xy 58.72226 -389.611616) (xy 58.722006 -389.611108) (xy 58.721498 -389.610346) (xy 58.323734 -388.922006)
			(xy 58.311856 -388.89933) (xy 58.295006 -388.850996) (xy 58.286434 -388.800533) (xy 58.285888 -388.77494)
			(xy 58.285888 -388.774432) (xy 58.285979 -388.763087) (xy 58.287634 -388.740458) (xy 58.28919 -388.72922)
			(xy 58.290104 -388.720506) (xy 58.286582 -388.703355) (xy 58.282332 -388.695692) (xy 58.24347 -388.631938)
			(xy 58.229754 -388.620762) (xy 58.221118 -388.617968) (xy 58.198711 -388.609949) (xy 58.156493 -388.587987)
			(xy 58.118197 -388.559736) (xy 58.084752 -388.525882) (xy 58.056968 -388.487246) (xy 58.03552 -388.444765)
			(xy 58.020928 -388.399469) (xy 58.013545 -388.352456) (xy 58.013092 -388.328662) (xy 58.01362 -388.303267)
			(xy 58.022029 -388.253178) (xy 58.038609 -388.205171) (xy 58.062902 -388.160568) (xy 58.09424 -388.120599)
			(xy 58.11266 -388.10311) (xy 58.120444 -388.09537) (xy 58.129118 -388.075223) (xy 58.129424 -388.064248)
			(xy 58.127138 -387.98754) (xy 58.126322 -387.976581) (xy 58.11672 -387.95684) (xy 58.108596 -387.94944)
			(xy 58.090068 -387.933602) (xy 58.057344 -387.89748) (xy 58.030272 -387.856949) (xy 58.009436 -387.812886)
			(xy 57.995286 -387.766245) (xy 57.98813 -387.718032) (xy 57.987692 -387.693662) (xy 57.988099 -387.669544)
			(xy 57.995107 -387.62182) (xy 58.008969 -387.575619) (xy 58.029391 -387.53192) (xy 58.042302 -387.511544)
			(xy 58.048144 -387.502908) (xy 58.0517 -387.482588) (xy 58.030618 -387.390386) (xy 58.018426 -387.373622)
			(xy 58.00979 -387.368288) (xy 58.009282 -387.368288) (xy 57.988527 -387.355384) (xy 57.950674 -387.324472)
			(xy 57.91778 -387.288328) (xy 57.890561 -387.247739) (xy 57.869609 -387.203588) (xy 57.855379 -387.156835)
			(xy 57.848181 -387.108497) (xy 57.847738 -387.084062) (xy 57.848259 -387.05676) (xy 57.857224 -387.002898)
			(xy 57.874936 -386.951248) (xy 57.900911 -386.903219) (xy 57.934441 -386.860123) (xy 57.954164 -386.841238)
			(xy 57.961498 -386.833688) (xy 57.969893 -386.814412) (xy 57.97042 -386.8039) (xy 57.97042 -386.729224)
			(xy 57.969957 -386.718698) (xy 57.961545 -386.699406) (xy 57.954164 -386.691886) (xy 57.934474 -386.672977)
			(xy 57.901002 -386.629855) (xy 57.875055 -386.581828) (xy 57.857336 -386.530195) (xy 57.848325 -386.476356)
			(xy 57.847738 -386.449062) (xy 57.847992 -386.43687) (xy 57.848246 -386.427218) (xy 57.84215 -386.409438)
			(xy 57.78373 -386.342128) (xy 57.766458 -386.333238) (xy 57.75706 -386.332222) (xy 57.730153 -386.328851)
			(xy 57.677867 -386.314487) (xy 57.628624 -386.291788) (xy 57.583741 -386.261363) (xy 57.544421 -386.224025)
			(xy 57.511717 -386.180776) (xy 57.486503 -386.132771) (xy 57.469456 -386.081298) (xy 57.464706 -386.0546)
			(xy 57.463182 -386.045202) (xy 57.190386 -385.57327) (xy 57.18302 -385.567428) (xy 57.164278 -385.551586)
			(xy 57.131156 -385.515378) (xy 57.103742 -385.474678) (xy 57.082635 -385.430378) (xy 57.068297 -385.383448)
			(xy 57.061043 -385.334916) (xy 57.060592 -385.31038) (xy 56.543508 -385.31038) (xy 56.792114 -385.740402)
			(xy 56.79948 -385.746244) (xy 56.818257 -385.762047) (xy 56.851376 -385.798263) (xy 56.878786 -385.838971)
			(xy 56.899887 -385.883279) (xy 56.914217 -385.930216) (xy 56.921462 -385.978754) (xy 56.921908 -386.003292)
			(xy 56.921654 -386.015484) (xy 56.9214 -386.025136) (xy 56.927496 -386.042916) (xy 56.979566 -386.10286)
			(xy 56.986203 -386.109858) (xy 57.003297 -386.118749) (xy 57.01284 -386.120132) (xy 57.039606 -386.123459)
			(xy 57.09163 -386.137687) (xy 57.140655 -386.160168) (xy 57.185384 -386.190304) (xy 57.224631 -386.227299)
			(xy 57.257356 -386.270171) (xy 57.282691 -386.317784) (xy 57.299966 -386.368876) (xy 57.308723 -386.422095)
			(xy 57.309258 -386.449062) (xy 57.308754 -386.476364) (xy 57.299785 -386.530227) (xy 57.282069 -386.581878)
			(xy 57.25609 -386.629906) (xy 57.222557 -386.673001) (xy 57.202832 -386.691886) (xy 57.195487 -386.699426)
			(xy 57.187098 -386.71871) (xy 57.186576 -386.729224) (xy 57.186576 -386.8039) (xy 57.187028 -386.814427)
			(xy 57.195448 -386.833719) (xy 57.202832 -386.841238) (xy 57.222485 -386.860183) (xy 57.255962 -386.903296)
			(xy 57.281915 -386.951314) (xy 57.299643 -387.002938) (xy 57.308665 -387.056771) (xy 57.309258 -387.084062)
			(xy 57.308807 -387.108178) (xy 57.301811 -387.1559) (xy 57.287961 -387.202101) (xy 57.267552 -387.245802)
			(xy 57.254648 -387.26618) (xy 57.248806 -387.274816) (xy 57.24525 -387.295136) (xy 57.266332 -387.387338)
			(xy 57.278524 -387.404102) (xy 57.28716 -387.409436) (xy 57.287668 -387.409436) (xy 57.308445 -387.422306)
			(xy 57.346295 -387.453225) (xy 57.379186 -387.489375) (xy 57.406402 -387.52997) (xy 57.427351 -387.574127)
			(xy 57.441577 -387.620884) (xy 57.448771 -387.669225) (xy 57.449212 -387.693662) (xy 57.448787 -387.718035)
			(xy 57.441641 -387.766254) (xy 57.427499 -387.812903) (xy 57.406667 -387.856973) (xy 57.379595 -387.89751)
			(xy 57.346869 -387.933637) (xy 57.328308 -387.94944) (xy 57.32012 -387.956791) (xy 57.310509 -387.97656)
			(xy 57.309766 -387.98754) (xy 57.30748 -388.064248) (xy 57.307773 -388.075228) (xy 57.316444 -388.095379)
			(xy 57.324244 -388.10311) (xy 57.342691 -388.120574) (xy 57.374038 -388.160544) (xy 57.398336 -388.205152)
			(xy 57.414913 -388.253167) (xy 57.423312 -388.303264) (xy 57.423812 -388.328662) (xy 57.423812 -388.328916)
			(xy 57.4237 -388.340134) (xy 57.422048 -388.362508) (xy 57.42051 -388.37362) (xy 57.41924 -388.38251)
			(xy 57.422542 -388.400036) (xy 57.46623 -388.470902) (xy 57.479946 -388.482078) (xy 57.488582 -388.484872)
			(xy 57.510832 -388.492795) (xy 57.552753 -388.514549) (xy 57.590825 -388.542497) (xy 57.624142 -388.575971)
			(xy 57.65191 -388.614176) (xy 57.66308 -388.634986) (xy 57.663588 -388.636002) (xy 58.056018 -389.314944)
			(xy 58.068823 -389.338287) (xy 58.087051 -389.388304) (xy 58.096319 -389.440727) (xy 58.096912 -389.467344)
			(xy 58.096479 -389.491324) (xy 58.088974 -389.538692) (xy 58.074157 -389.584305) (xy 58.05239 -389.62704)
			(xy 58.02421 -389.665847) (xy 57.99031 -389.699771) (xy 57.951523 -389.727978) (xy 57.908803 -389.749775)
			(xy 57.8632 -389.764624) (xy 57.815837 -389.772162) (xy 57.791858 -389.772652) (xy 57.79135 -389.772652)
			(xy 57.767818 -389.772209) (xy 57.72131 -389.765001) (xy 57.676462 -389.750733) (xy 57.634338 -389.729743)
			(xy 57.59594 -389.702531) (xy 57.562178 -389.669743) (xy 57.533855 -389.632156) (xy 57.522364 -389.611616)
			(xy 57.52211 -389.611108) (xy 57.521602 -389.610346) (xy 57.123838 -388.922006) (xy 57.11196 -388.89933)
			(xy 57.095111 -388.850996) (xy 57.086538 -388.800533) (xy 57.085992 -388.77494) (xy 57.085992 -388.774432)
			(xy 57.086083 -388.763087) (xy 57.087738 -388.740458) (xy 57.089294 -388.72922) (xy 57.090207 -388.720506)
			(xy 57.086686 -388.703355) (xy 57.082436 -388.695692) (xy 57.043574 -388.631938) (xy 57.029858 -388.620762)
			(xy 57.021222 -388.617968) (xy 56.998815 -388.609947) (xy 56.956598 -388.587985) (xy 56.918302 -388.559735)
			(xy 56.884856 -388.525881) (xy 56.857073 -388.487245) (xy 56.835625 -388.444764) (xy 56.821032 -388.399469)
			(xy 56.813649 -388.352456) (xy 56.813196 -388.328662) (xy 56.813723 -388.303267) (xy 56.822132 -388.253178)
			(xy 56.838712 -388.205171) (xy 56.863006 -388.160568) (xy 56.894344 -388.120599) (xy 56.912764 -388.10311)
			(xy 56.920549 -388.09537) (xy 56.929222 -388.075223) (xy 56.929528 -388.064248) (xy 56.927242 -387.98754)
			(xy 56.926424 -387.976582) (xy 56.916823 -387.95684) (xy 56.9087 -387.94944) (xy 56.890172 -387.933601)
			(xy 56.857449 -387.897479) (xy 56.830376 -387.856948) (xy 56.80954 -387.812886) (xy 56.79539 -387.766245)
			(xy 56.788234 -387.718032) (xy 56.787796 -387.693662) (xy 56.788202 -387.669544) (xy 56.79521 -387.62182)
			(xy 56.809073 -387.575619) (xy 56.829495 -387.53192) (xy 56.842406 -387.511544) (xy 56.848248 -387.502908)
			(xy 56.851804 -387.482588) (xy 56.830722 -387.390386) (xy 56.81853 -387.373622) (xy 56.809894 -387.368288)
			(xy 56.809386 -387.368288) (xy 56.788632 -387.355382) (xy 56.750779 -387.324471) (xy 56.717885 -387.288328)
			(xy 56.690666 -387.247739) (xy 56.669713 -387.203588) (xy 56.655483 -387.156835) (xy 56.648285 -387.108497)
			(xy 56.647842 -387.084062) (xy 56.648361 -387.05676) (xy 56.657326 -387.002898) (xy 56.675039 -386.951247)
			(xy 56.701014 -386.903219) (xy 56.734545 -386.860123) (xy 56.754268 -386.841238) (xy 56.761602 -386.833689)
			(xy 56.769997 -386.814412) (xy 56.770524 -386.8039) (xy 56.770524 -386.729224) (xy 56.77006 -386.718699)
			(xy 56.761648 -386.699406) (xy 56.754268 -386.691886) (xy 56.734578 -386.672977) (xy 56.701106 -386.629855)
			(xy 56.675159 -386.581827) (xy 56.65744 -386.530195) (xy 56.648429 -386.476355) (xy 56.647842 -386.449062)
			(xy 56.648096 -386.43687) (xy 56.64835 -386.427218) (xy 56.642254 -386.409438) (xy 56.590184 -386.349494)
			(xy 56.583571 -386.34247) (xy 56.566459 -386.333595) (xy 56.55691 -386.332222) (xy 56.530009 -386.328811)
			(xy 56.477724 -386.314455) (xy 56.42848 -386.291763) (xy 56.383597 -386.261344) (xy 56.344276 -386.224012)
			(xy 56.31157 -386.180767) (xy 56.286355 -386.132766) (xy 56.269306 -386.081296) (xy 56.264556 -386.0546)
			(xy 56.263032 -386.045202) (xy 55.989982 -385.572762) (xy 55.98287 -385.56692) (xy 55.964132 -385.551146)
			(xy 55.931079 -385.515003) (xy 55.903724 -385.474376) (xy 55.882666 -385.430156) (xy 55.868366 -385.383311)
			(xy 55.861139 -385.334869) (xy 55.860696 -385.31038) (xy 55.343648 -385.31038) (xy 55.592218 -385.740402)
			(xy 55.599584 -385.746244) (xy 55.618362 -385.762046) (xy 55.65148 -385.798262) (xy 55.67889 -385.83897)
			(xy 55.699991 -385.883278) (xy 55.714321 -385.930216) (xy 55.721566 -385.978754) (xy 55.722012 -386.003292)
			(xy 55.721758 -386.015484) (xy 55.721504 -386.025136) (xy 55.7276 -386.042916) (xy 55.77967 -386.10286)
			(xy 55.786306 -386.109859) (xy 55.8034 -386.11875) (xy 55.812944 -386.120132) (xy 55.839711 -386.123455)
			(xy 55.891734 -386.137685) (xy 55.94076 -386.160166) (xy 55.985489 -386.190303) (xy 56.024735 -386.227298)
			(xy 56.05746 -386.27017) (xy 56.082795 -386.317783) (xy 56.10007 -386.368876) (xy 56.108827 -386.422095)
			(xy 56.109362 -386.449062) (xy 56.108857 -386.476364) (xy 56.099888 -386.530227) (xy 56.082173 -386.581878)
			(xy 56.056194 -386.629906) (xy 56.022661 -386.673001) (xy 56.002936 -386.691886) (xy 55.995592 -386.699427)
			(xy 55.987202 -386.71871) (xy 55.98668 -386.729224) (xy 55.98668 -386.8039) (xy 55.98713 -386.814427)
			(xy 55.995551 -386.833719) (xy 56.002936 -386.841238) (xy 56.02259 -386.860183) (xy 56.056066 -386.903295)
			(xy 56.082019 -386.951314) (xy 56.099747 -387.002938) (xy 56.108769 -387.056771) (xy 56.109362 -387.084062)
			(xy 56.10891 -387.108178) (xy 56.101914 -387.1559) (xy 56.088065 -387.202101) (xy 56.067656 -387.245802)
			(xy 56.054752 -387.26618) (xy 56.04891 -387.274816) (xy 56.045354 -387.295136) (xy 56.066436 -387.387338)
			(xy 56.078628 -387.404102) (xy 56.087264 -387.409436) (xy 56.087772 -387.409436) (xy 56.10855 -387.422304)
			(xy 56.1464 -387.453224) (xy 56.179291 -387.489375) (xy 56.206506 -387.52997) (xy 56.227455 -387.574126)
			(xy 56.241681 -387.620884) (xy 56.248875 -387.669225) (xy 56.249316 -387.693662) (xy 56.248889 -387.718035)
			(xy 56.241744 -387.766254) (xy 56.227602 -387.812903) (xy 56.20677 -387.856973) (xy 56.179698 -387.89751)
			(xy 56.146973 -387.933637) (xy 56.128412 -387.94944) (xy 56.120225 -387.956792) (xy 56.110613 -387.97656)
			(xy 56.10987 -387.98754) (xy 56.107584 -388.064248) (xy 56.107875 -388.075229) (xy 56.116547 -388.09538)
			(xy 56.124348 -388.10311) (xy 56.142796 -388.120573) (xy 56.174143 -388.160543) (xy 56.19844 -388.205152)
			(xy 56.215017 -388.253167) (xy 56.223417 -388.303264) (xy 56.223916 -388.328662) (xy 56.223916 -388.328916)
			(xy 56.223803 -388.340134) (xy 56.222152 -388.362508) (xy 56.220614 -388.37362) (xy 56.219344 -388.38251)
			(xy 56.222646 -388.400036) (xy 56.266334 -388.470902) (xy 56.28005 -388.482078) (xy 56.288686 -388.484872)
			(xy 56.316851 -388.495068) (xy 56.368797 -388.52488) (xy 56.39181 -388.544054) (xy 56.413296 -388.563634)
			(xy 56.449108 -388.609414) (xy 56.46293 -388.634986) (xy 56.463692 -388.636256) (xy 56.855868 -389.314944)
			(xy 56.868588 -389.338268) (xy 56.886686 -389.388213) (xy 56.895908 -389.440529) (xy 56.896508 -389.46709)
			(xy 56.896508 -389.467344) (xy 56.896078 -389.491336) (xy 56.888565 -389.53873) (xy 56.873732 -389.584364)
			(xy 56.851943 -389.627117) (xy 56.823735 -389.665935) (xy 56.789802 -389.699863) (xy 56.750979 -389.728066)
			(xy 56.708224 -389.749849) (xy 56.662587 -389.764676) (xy 56.615192 -389.772181) (xy 56.5912 -389.772652)
			(xy 56.56767 -389.772169) (xy 56.521163 -389.764968) (xy 56.476316 -389.750707) (xy 56.434192 -389.729725)
			(xy 56.395793 -389.702519) (xy 56.36203 -389.669735) (xy 56.333706 -389.632154) (xy 56.322214 -389.611616)
			(xy 56.32196 -389.611108) (xy 56.321452 -389.610346) (xy 55.923942 -388.921752) (xy 55.913372 -388.901824)
			(xy 55.897567 -388.859575) (xy 55.888159 -388.815459) (xy 55.88635 -388.792974) (xy 55.885842 -388.781798)
			(xy 55.885588 -388.775194) (xy 55.885588 -388.77367) (xy 55.885771 -388.762512) (xy 55.887548 -388.740265)
			(xy 55.889144 -388.72922) (xy 55.889144 -388.728966) (xy 55.890027 -388.720251) (xy 55.886525 -388.703103)
			(xy 55.882286 -388.695438) (xy 55.843424 -388.631938) (xy 55.829708 -388.620762) (xy 55.821072 -388.617968)
			(xy 55.79867 -388.609971) (xy 55.756499 -388.587968) (xy 55.718251 -388.559691) (xy 55.684851 -388.525824)
			(xy 55.657108 -388.487188) (xy 55.635692 -388.444716) (xy 55.621122 -388.399436) (xy 55.613751 -388.352445)
			(xy 55.6133 -388.328662) (xy 55.613826 -388.303267) (xy 55.622235 -388.253178) (xy 55.638815 -388.205171)
			(xy 55.663109 -388.160568) (xy 55.694448 -388.120599) (xy 55.712868 -388.10311) (xy 55.720653 -388.095371)
			(xy 55.729326 -388.075223) (xy 55.729632 -388.064248) (xy 55.727346 -387.98754) (xy 55.726527 -387.976582)
			(xy 55.716926 -387.95684) (xy 55.708804 -387.94944) (xy 55.690257 -387.933624) (xy 55.657539 -387.897494)
			(xy 55.630471 -387.856958) (xy 55.609639 -387.812892) (xy 55.595493 -387.766247) (xy 55.588337 -387.718033)
			(xy 55.5879 -387.693662) (xy 55.588306 -387.669544) (xy 55.595314 -387.62182) (xy 55.609176 -387.575619)
			(xy 55.629599 -387.53192) (xy 55.64251 -387.511544) (xy 55.648352 -387.502908) (xy 55.651908 -387.482588)
			(xy 55.630826 -387.390386) (xy 55.618634 -387.373622) (xy 55.609998 -387.368288) (xy 55.60949 -387.368288)
			(xy 55.588737 -387.355381) (xy 55.550884 -387.32447) (xy 55.51799 -387.288327) (xy 55.49077 -387.247739)
			(xy 55.469817 -387.203588) (xy 55.455587 -387.156835) (xy 55.448389 -387.108497) (xy 55.447946 -387.084062)
			(xy 55.448464 -387.05676) (xy 55.457429 -387.002898) (xy 55.475142 -386.951247) (xy 55.501118 -386.903219)
			(xy 55.534648 -386.860123) (xy 55.554372 -386.841238) (xy 55.561707 -386.833689) (xy 55.570101 -386.814412)
			(xy 55.570628 -386.8039) (xy 55.570628 -386.729224) (xy 55.570162 -386.718699) (xy 55.561752 -386.699406)
			(xy 55.554372 -386.691886) (xy 55.534683 -386.672976) (xy 55.501211 -386.629854) (xy 55.475264 -386.581827)
			(xy 55.457545 -386.530195) (xy 55.448533 -386.476355) (xy 55.447946 -386.449062) (xy 55.4482 -386.43687)
			(xy 55.448454 -386.427218) (xy 55.442358 -386.409438) (xy 55.390288 -386.349494) (xy 55.383674 -386.342471)
			(xy 55.366563 -386.333595) (xy 55.357014 -386.332222) (xy 55.330113 -386.328808) (xy 55.277828 -386.314452)
			(xy 55.228585 -386.291761) (xy 55.183701 -386.261343) (xy 55.14438 -386.224011) (xy 55.111674 -386.180766)
			(xy 55.086459 -386.132766) (xy 55.06941 -386.081296) (xy 55.06466 -386.0546) (xy 55.063136 -386.045202)
			(xy 54.79034 -385.57327) (xy 54.782974 -385.567428) (xy 54.764222 -385.551598) (xy 54.731103 -385.515386)
			(xy 54.703691 -385.474683) (xy 54.682586 -385.430381) (xy 54.66825 -385.38345) (xy 54.660996 -385.334916)
			(xy 54.660546 -385.31038) (xy 54.143752 -385.31038) (xy 54.392322 -385.740402) (xy 54.399688 -385.746244)
			(xy 54.418467 -385.762045) (xy 54.451585 -385.798261) (xy 54.478995 -385.83897) (xy 54.500096 -385.883278)
			(xy 54.514425 -385.930216) (xy 54.52167 -385.978754) (xy 54.522116 -386.003292) (xy 54.521862 -386.015484)
			(xy 54.521608 -386.025136) (xy 54.527704 -386.042916) (xy 54.586124 -386.110226) (xy 54.603396 -386.119116)
			(xy 54.612794 -386.120132) (xy 54.639555 -386.123496) (xy 54.691578 -386.137718) (xy 54.740604 -386.160192)
			(xy 54.785333 -386.190323) (xy 54.824581 -386.227313) (xy 54.857307 -386.270181) (xy 54.882643 -386.31779)
			(xy 54.899919 -386.36888) (xy 54.908676 -386.422096) (xy 54.909212 -386.449062) (xy 54.908691 -386.476364)
			(xy 54.899724 -386.530225) (xy 54.882011 -386.581875) (xy 54.856036 -386.629903) (xy 54.822508 -386.673)
			(xy 54.802786 -386.691886) (xy 54.795449 -386.699433) (xy 54.787053 -386.718711) (xy 54.78653 -386.729224)
			(xy 54.78653 -386.8039) (xy 54.786995 -386.814425) (xy 54.795407 -386.833717) (xy 54.802786 -386.841238)
			(xy 54.822431 -386.860192) (xy 54.85591 -386.903301) (xy 54.881866 -386.951317) (xy 54.899596 -387.00294)
			(xy 54.908619 -387.056771) (xy 54.909212 -387.084062) (xy 54.908768 -387.108178) (xy 54.901771 -387.155901)
			(xy 54.88792 -387.202102) (xy 54.867508 -387.245803) (xy 54.854602 -387.26618) (xy 54.84876 -387.274816)
			(xy 54.845204 -387.295136) (xy 54.866286 -387.387338) (xy 54.878478 -387.404102) (xy 54.887114 -387.409436)
			(xy 54.887622 -387.409436) (xy 54.908389 -387.422322) (xy 54.946241 -387.453237) (xy 54.979134 -387.489384)
			(xy 55.006352 -387.529976) (xy 55.027303 -387.57413) (xy 55.04153 -387.620886) (xy 55.048725 -387.669226)
			(xy 55.049166 -387.693662) (xy 55.048757 -387.718036) (xy 55.041611 -387.766256) (xy 55.027467 -387.812907)
			(xy 55.006631 -387.856977) (xy 54.979555 -387.897513) (xy 54.946825 -387.933639) (xy 54.928262 -387.94944)
			(xy 54.920083 -387.9568) (xy 54.910465 -387.976562) (xy 54.90972 -387.98754) (xy 54.907434 -388.064248)
			(xy 54.90771 -388.07523) (xy 54.916391 -388.095383) (xy 54.924198 -388.10311) (xy 54.942636 -388.120583)
			(xy 54.973986 -388.16055) (xy 54.998287 -388.205155) (xy 55.014866 -388.253169) (xy 55.023266 -388.303264)
			(xy 55.023766 -388.328662) (xy 55.023766 -388.328916) (xy 55.023654 -388.340134) (xy 55.022002 -388.362508)
			(xy 55.020464 -388.37362) (xy 55.019194 -388.38251) (xy 55.022496 -388.400036) (xy 55.066184 -388.470902)
			(xy 55.0799 -388.482078) (xy 55.088536 -388.484872) (xy 55.110778 -388.492817) (xy 55.152699 -388.514565)
			(xy 55.190774 -388.542507) (xy 55.224093 -388.575977) (xy 55.251863 -388.614177) (xy 55.263034 -388.634986)
			(xy 55.263542 -388.636002) (xy 55.655972 -389.314944) (xy 55.668693 -389.338268) (xy 55.68679 -389.388213)
			(xy 55.696012 -389.440529) (xy 55.696612 -389.46709) (xy 55.696612 -389.467344) (xy 55.696178 -389.491336)
			(xy 55.688665 -389.538729) (xy 55.673832 -389.584363) (xy 55.652044 -389.627116) (xy 55.623836 -389.665934)
			(xy 55.589903 -389.699862) (xy 55.551082 -389.728065) (xy 55.508326 -389.749848) (xy 55.46269 -389.764675)
			(xy 55.415296 -389.772181) (xy 55.391304 -389.772652) (xy 55.367774 -389.772165) (xy 55.321268 -389.764965)
			(xy 55.27642 -389.750705) (xy 55.234297 -389.729723) (xy 55.195897 -389.702518) (xy 55.162134 -389.669735)
			(xy 55.13381 -389.632154) (xy 55.122318 -389.611616) (xy 55.122064 -389.611108) (xy 55.121556 -389.610346)
			(xy 54.723792 -388.922006) (xy 54.711876 -388.899338) (xy 54.694939 -388.851012) (xy 54.686279 -388.800542)
			(xy 54.685692 -388.77494) (xy 54.685692 -388.774432) (xy 54.685849 -388.763083) (xy 54.687626 -388.740454)
			(xy 54.689248 -388.72922) (xy 54.690154 -388.720506) (xy 54.686636 -388.703356) (xy 54.68239 -388.695692)
			(xy 54.643528 -388.631938) (xy 54.629812 -388.620762) (xy 54.621176 -388.617968) (xy 54.598781 -388.609916)
			(xy 54.556562 -388.587961) (xy 54.518264 -388.559717) (xy 54.484816 -388.525868) (xy 54.45703 -388.487237)
			(xy 54.435581 -388.444759) (xy 54.420987 -388.399465) (xy 54.413603 -388.352455) (xy 54.41315 -388.328662)
			(xy 54.41366 -388.303266) (xy 54.42207 -388.253176) (xy 54.438653 -388.205167) (xy 54.462952 -388.160565)
			(xy 54.494295 -388.120597) (xy 54.512718 -388.10311) (xy 54.520496 -388.095364) (xy 54.529175 -388.075222)
			(xy 54.529482 -388.064248) (xy 54.527196 -387.98754) (xy 54.526361 -387.976585) (xy 54.51677 -387.956844)
			(xy 54.508654 -387.94944) (xy 54.490117 -387.933612) (xy 54.457396 -387.897486) (xy 54.430326 -387.856953)
			(xy 54.409492 -387.812889) (xy 54.395343 -387.766246) (xy 54.388188 -387.718033) (xy 54.38775 -387.693662)
			(xy 54.388164 -387.669544) (xy 54.395171 -387.621821) (xy 54.409031 -387.57562) (xy 54.429451 -387.53192)
			(xy 54.44236 -387.511544) (xy 54.448202 -387.502908) (xy 54.451758 -387.482588) (xy 54.430676 -387.390386)
			(xy 54.418484 -387.373622) (xy 54.409848 -387.368288) (xy 54.40934 -387.368288) (xy 54.388575 -387.355399)
			(xy 54.350725 -387.324483) (xy 54.317833 -387.288336) (xy 54.290616 -387.247745) (xy 54.269665 -387.203591)
			(xy 54.255436 -387.156837) (xy 54.248239 -387.108498) (xy 54.247796 -387.084062) (xy 54.24833 -387.056761)
			(xy 54.257294 -387.0029) (xy 54.275003 -386.951251) (xy 54.300975 -386.903222) (xy 54.334501 -386.860125)
			(xy 54.354222 -386.841238) (xy 54.36155 -386.833683) (xy 54.36995 -386.814411) (xy 54.370478 -386.8039)
			(xy 54.370478 -386.729224) (xy 54.369998 -386.718701) (xy 54.361596 -386.699409) (xy 54.354222 -386.691886)
			(xy 54.334542 -386.672966) (xy 54.301067 -386.629849) (xy 54.275117 -386.581824) (xy 54.257396 -386.530193)
			(xy 54.248383 -386.476355) (xy 54.247796 -386.449062) (xy 54.24805 -386.43687) (xy 54.248304 -386.427218)
			(xy 54.242208 -386.409438) (xy 54.183788 -386.342128) (xy 54.166516 -386.333238) (xy 54.157118 -386.332222)
			(xy 54.130207 -386.328884) (xy 54.07792 -386.314514) (xy 54.028677 -386.291809) (xy 53.983795 -386.261379)
			(xy 53.944476 -386.224037) (xy 53.911772 -386.180783) (xy 53.88656 -386.132775) (xy 53.869513 -386.081299)
			(xy 53.864764 -386.0546) (xy 53.86324 -386.045202) (xy 53.590444 -385.57327) (xy 53.583078 -385.567428)
			(xy 53.564327 -385.551597) (xy 53.531208 -385.515385) (xy 53.503796 -385.474683) (xy 53.48269 -385.430381)
			(xy 53.468354 -385.383449) (xy 53.4611 -385.334916) (xy 53.46065 -385.31038) (xy 52.943602 -385.31038)
			(xy 53.192172 -385.740402) (xy 53.199538 -385.746244) (xy 53.218327 -385.762032) (xy 53.251443 -385.798253)
			(xy 53.27885 -385.838965) (xy 53.299948 -385.883275) (xy 53.314277 -385.930214) (xy 53.321521 -385.978753)
			(xy 53.321966 -386.003292) (xy 53.321712 -386.015484) (xy 53.321458 -386.025136) (xy 53.327554 -386.042916)
			(xy 53.379624 -386.10286) (xy 53.386241 -386.10988) (xy 53.403349 -386.118759) (xy 53.412898 -386.120132)
			(xy 53.43966 -386.123493) (xy 53.491683 -386.137715) (xy 53.540708 -386.16019) (xy 53.585438 -386.190322)
			(xy 53.624685 -386.227312) (xy 53.657411 -386.27018) (xy 53.682748 -386.31779) (xy 53.700023 -386.36888)
			(xy 53.70878 -386.422096) (xy 53.709316 -386.449062) (xy 53.708794 -386.476363) (xy 53.699827 -386.530225)
			(xy 53.682114 -386.581874) (xy 53.656139 -386.629903) (xy 53.622612 -386.673) (xy 53.60289 -386.691886)
			(xy 53.595553 -386.699434) (xy 53.587158 -386.718711) (xy 53.586634 -386.729224) (xy 53.586634 -386.8039)
			(xy 53.587098 -386.814425) (xy 53.595511 -386.833717) (xy 53.60289 -386.841238) (xy 53.622535 -386.860191)
			(xy 53.656015 -386.903301) (xy 53.68197 -386.951317) (xy 53.6997 -387.00294) (xy 53.708723 -387.056771)
			(xy 53.709316 -387.084062) (xy 53.708871 -387.108178) (xy 53.701875 -387.155901) (xy 53.688023 -387.202102)
			(xy 53.667612 -387.245803) (xy 53.654706 -387.26618) (xy 53.648864 -387.274816) (xy 53.645308 -387.295136)
			(xy 53.66639 -387.387338) (xy 53.678582 -387.404102) (xy 53.687218 -387.409436) (xy 53.687726 -387.409436)
			(xy 53.708494 -387.422321) (xy 53.746346 -387.453236) (xy 53.779239 -387.489383) (xy 53.806456 -387.529975)
			(xy 53.827407 -387.57413) (xy 53.841634 -387.620886) (xy 53.848829 -387.669226) (xy 53.84927 -387.693662)
			(xy 53.84886 -387.718036) (xy 53.841713 -387.766256) (xy 53.827569 -387.812906) (xy 53.806734 -387.856977)
			(xy 53.779659 -387.897513) (xy 53.746929 -387.933639) (xy 53.728366 -387.94944) (xy 53.720187 -387.956801)
			(xy 53.710569 -387.976562) (xy 53.709824 -387.98754) (xy 53.707538 -388.064248) (xy 53.707813 -388.075231)
			(xy 53.716494 -388.095383) (xy 53.724302 -388.10311) (xy 53.742741 -388.120582) (xy 53.774091 -388.160549)
			(xy 53.798391 -388.205155) (xy 53.81497 -388.253168) (xy 53.82337 -388.303264) (xy 53.82387 -388.328662)
			(xy 53.82387 -388.328916) (xy 53.823758 -388.340134) (xy 53.822106 -388.362508) (xy 53.820568 -388.37362)
			(xy 53.819298 -388.38251) (xy 53.8226 -388.400036) (xy 53.866288 -388.470902) (xy 53.880004 -388.482078)
			(xy 53.88864 -388.484872) (xy 53.910882 -388.492815) (xy 53.952804 -388.514563) (xy 53.990878 -388.542506)
			(xy 54.024197 -388.575977) (xy 54.051967 -388.614177) (xy 54.063138 -388.634986) (xy 54.063646 -388.636002)
			(xy 54.456076 -389.314944) (xy 54.468797 -389.338268) (xy 54.486894 -389.388213) (xy 54.496116 -389.440529)
			(xy 54.496716 -389.46709) (xy 54.496716 -389.467344) (xy 54.496278 -389.491336) (xy 54.488766 -389.538728)
			(xy 54.473933 -389.584362) (xy 54.452144 -389.627115) (xy 54.423937 -389.665932) (xy 54.390005 -389.69986)
			(xy 54.351184 -389.728063) (xy 54.308429 -389.749846) (xy 54.262793 -389.764674) (xy 54.2154 -389.772181)
			(xy 54.191408 -389.772652) (xy 54.167878 -389.772162) (xy 54.121372 -389.764963) (xy 54.076525 -389.750703)
			(xy 54.034401 -389.729721) (xy 53.996002 -389.702517) (xy 53.962239 -389.669734) (xy 53.933914 -389.632153)
			(xy 53.922422 -389.611616) (xy 53.922168 -389.611108) (xy 53.92166 -389.610346) (xy 53.523896 -388.922006)
			(xy 53.51198 -388.899338) (xy 53.495043 -388.851012) (xy 53.486383 -388.800542) (xy 53.485796 -388.77494)
			(xy 53.485796 -388.774432) (xy 53.485953 -388.763083) (xy 53.48773 -388.740454) (xy 53.489352 -388.72922)
			(xy 53.490257 -388.720506) (xy 53.48674 -388.703356) (xy 53.482494 -388.695692) (xy 53.443632 -388.631938)
			(xy 53.429916 -388.620762) (xy 53.42128 -388.617968) (xy 53.398886 -388.609914) (xy 53.356666 -388.58796)
			(xy 53.318368 -388.559716) (xy 53.284921 -388.525867) (xy 53.257135 -388.487236) (xy 53.235685 -388.444758)
			(xy 53.221091 -388.399465) (xy 53.213707 -388.352455) (xy 53.213254 -388.328662) (xy 53.213762 -388.303266)
			(xy 53.222173 -388.253175) (xy 53.238756 -388.205167) (xy 53.263055 -388.160564) (xy 53.294399 -388.120597)
			(xy 53.312822 -388.10311) (xy 53.320601 -388.095365) (xy 53.329279 -388.075222) (xy 53.329586 -388.064248)
			(xy 53.3273 -387.98754) (xy 53.326464 -387.976585) (xy 53.316874 -387.956844) (xy 53.308758 -387.94944)
			(xy 53.290222 -387.933611) (xy 53.257501 -387.897485) (xy 53.23043 -387.856953) (xy 53.209596 -387.812889)
			(xy 53.195448 -387.766246) (xy 53.188292 -387.718033) (xy 53.187854 -387.693662) (xy 53.188267 -387.669544)
			(xy 53.195274 -387.621821) (xy 53.209135 -387.57562) (xy 53.229555 -387.53192) (xy 53.242464 -387.511544)
			(xy 53.248306 -387.502908) (xy 53.251862 -387.482588) (xy 53.23078 -387.390386) (xy 53.218588 -387.373622)
			(xy 53.209952 -387.368288) (xy 53.209444 -387.368288) (xy 53.18868 -387.355397) (xy 53.150829 -387.324482)
			(xy 53.117938 -387.288335) (xy 53.09072 -387.247744) (xy 53.069769 -387.203591) (xy 53.05554 -387.156837)
			(xy 53.048343 -387.108498) (xy 53.0479 -387.084062) (xy 53.048433 -387.056761) (xy 53.057397 -387.0029)
			(xy 53.075106 -386.95125) (xy 53.101079 -386.903221) (xy 53.134605 -386.860124) (xy 53.154326 -386.841238)
			(xy 53.161654 -386.833683) (xy 53.170054 -386.814411) (xy 53.170582 -386.8039) (xy 53.170582 -386.729224)
			(xy 53.170101 -386.718701) (xy 53.1617 -386.699409) (xy 53.154326 -386.691886) (xy 53.134647 -386.672966)
			(xy 53.101171 -386.629848) (xy 53.075221 -386.581824) (xy 53.0575 -386.530193) (xy 53.048487 -386.476355)
			(xy 53.0479 -386.449062) (xy 53.048154 -386.43687) (xy 53.048408 -386.427218) (xy 53.042312 -386.409438)
			(xy 52.990242 -386.349494) (xy 52.983609 -386.342492) (xy 52.966512 -386.333604) (xy 52.956968 -386.332222)
			(xy 52.930062 -386.328844) (xy 52.877776 -386.314481) (xy 52.828533 -386.291784) (xy 52.78365 -386.26136)
			(xy 52.74433 -386.224023) (xy 52.711625 -386.180774) (xy 52.686411 -386.132771) (xy 52.669364 -386.081298)
			(xy 52.664614 -386.0546) (xy 52.66309 -386.045202) (xy 52.390294 -385.57327) (xy 52.382928 -385.567428)
			(xy 52.364166 -385.551608) (xy 52.331051 -385.515393) (xy 52.303641 -385.474688) (xy 52.282538 -385.430384)
			(xy 52.268203 -385.383451) (xy 52.26095 -385.334917) (xy 52.2605 -385.31038) (xy 51.743706 -385.31038)
			(xy 51.992276 -385.740402) (xy 51.999642 -385.746244) (xy 52.018432 -385.762031) (xy 52.051547 -385.798252)
			(xy 52.078954 -385.838964) (xy 52.100053 -385.883275) (xy 52.114381 -385.930214) (xy 52.121625 -385.978753)
			(xy 52.12207 -386.003292) (xy 52.121816 -386.015484) (xy 52.121562 -386.025136) (xy 52.127658 -386.042916)
			(xy 52.186078 -386.110226) (xy 52.20335 -386.119116) (xy 52.212748 -386.120132) (xy 52.239515 -386.123452)
			(xy 52.291539 -386.137682) (xy 52.340564 -386.160164) (xy 52.385293 -386.190301) (xy 52.42454 -386.227296)
			(xy 52.457264 -386.270169) (xy 52.482599 -386.317783) (xy 52.499874 -386.368876) (xy 52.508631 -386.422095)
			(xy 52.509166 -386.449062) (xy 52.50866 -386.476364) (xy 52.499691 -386.530227) (xy 52.481976 -386.581878)
			(xy 52.455997 -386.629906) (xy 52.422464 -386.673001) (xy 52.40274 -386.691886) (xy 52.395396 -386.699427)
			(xy 52.387006 -386.71871) (xy 52.386484 -386.729224) (xy 52.386484 -386.8039) (xy 52.386962 -386.814423)
			(xy 52.395367 -386.833714) (xy 52.40274 -386.841238) (xy 52.422395 -386.860182) (xy 52.45587 -386.903295)
			(xy 52.481823 -386.951314) (xy 52.499551 -387.002938) (xy 52.508573 -387.056771) (xy 52.509166 -387.084062)
			(xy 52.508713 -387.108178) (xy 52.501718 -387.1559) (xy 52.487869 -387.202101) (xy 52.46746 -387.245802)
			(xy 52.454556 -387.26618) (xy 52.448714 -387.274816) (xy 52.445158 -387.295136) (xy 52.46624 -387.387338)
			(xy 52.478432 -387.404102) (xy 52.487068 -387.409436) (xy 52.487576 -387.409436) (xy 52.508355 -387.422303)
			(xy 52.546205 -387.453223) (xy 52.579095 -387.489374) (xy 52.60631 -387.529969) (xy 52.627259 -387.574126)
			(xy 52.641485 -387.620884) (xy 52.648679 -387.669225) (xy 52.64912 -387.693662) (xy 52.648692 -387.718035)
			(xy 52.641546 -387.766254) (xy 52.627405 -387.812903) (xy 52.606573 -387.856973) (xy 52.579502 -387.89751)
			(xy 52.546776 -387.933637) (xy 52.528216 -387.94944) (xy 52.520029 -387.956793) (xy 52.510417 -387.976561)
			(xy 52.509674 -387.98754) (xy 52.507388 -388.064248) (xy 52.507678 -388.075229) (xy 52.51635 -388.09538)
			(xy 52.524152 -388.10311) (xy 52.542601 -388.120572) (xy 52.573947 -388.160543) (xy 52.598244 -388.205151)
			(xy 52.614821 -388.253167) (xy 52.623221 -388.303264) (xy 52.62372 -388.328662) (xy 52.62372 -388.328916)
			(xy 52.623607 -388.340134) (xy 52.621956 -388.362508) (xy 52.620418 -388.37362) (xy 52.619148 -388.38251)
			(xy 52.62245 -388.400036) (xy 52.666138 -388.470902) (xy 52.679854 -388.482078) (xy 52.68849 -388.484872)
			(xy 52.710741 -388.492791) (xy 52.752662 -388.514546) (xy 52.790734 -388.542495) (xy 52.824051 -388.57597)
			(xy 52.851818 -388.614175) (xy 52.862988 -388.634986) (xy 52.863496 -388.636002) (xy 53.255926 -389.314944)
			(xy 53.268731 -389.338286) (xy 53.286959 -389.388304) (xy 53.296227 -389.440727) (xy 53.29682 -389.467344)
			(xy 53.296379 -389.491323) (xy 53.288875 -389.538691) (xy 53.274057 -389.584303) (xy 53.252292 -389.627038)
			(xy 53.224113 -389.665844) (xy 53.190213 -389.699768) (xy 53.151427 -389.727975) (xy 53.108708 -389.749772)
			(xy 53.063107 -389.764623) (xy 53.015745 -389.772162) (xy 52.991766 -389.772652) (xy 52.991258 -389.772652)
			(xy 52.967726 -389.772202) (xy 52.921219 -389.764996) (xy 52.87637 -389.750729) (xy 52.834247 -389.72974)
			(xy 52.795848 -389.702529) (xy 52.762086 -389.669741) (xy 52.733763 -389.632156) (xy 52.722272 -389.611616)
			(xy 52.722018 -389.611108) (xy 52.72151 -389.610346) (xy 52.323746 -388.922006) (xy 52.311869 -388.89933)
			(xy 52.295019 -388.850996) (xy 52.286446 -388.800533) (xy 52.2859 -388.77494) (xy 52.2859 -388.774432)
			(xy 52.285991 -388.763087) (xy 52.287646 -388.740458) (xy 52.289202 -388.72922) (xy 52.290114 -388.720506)
			(xy 52.286593 -388.703355) (xy 52.282344 -388.695692) (xy 52.243482 -388.631938) (xy 52.229766 -388.620762)
			(xy 52.22113 -388.617968) (xy 52.198725 -388.609942) (xy 52.156507 -388.587982) (xy 52.118211 -388.559732)
			(xy 52.084765 -388.525879) (xy 52.056981 -388.487244) (xy 52.035533 -388.444764) (xy 52.02094 -388.399468)
			(xy 52.013557 -388.352456) (xy 52.013104 -388.328662) (xy 52.013629 -388.303267) (xy 52.022038 -388.253178)
			(xy 52.038618 -388.20517) (xy 52.062913 -388.160567) (xy 52.094252 -388.120599) (xy 52.112672 -388.10311)
			(xy 52.120458 -388.095371) (xy 52.12913 -388.075223) (xy 52.129436 -388.064248) (xy 52.12715 -387.98754)
			(xy 52.12633 -387.976582) (xy 52.11673 -387.956841) (xy 52.108608 -387.94944) (xy 52.090062 -387.933623)
			(xy 52.057343 -387.897493) (xy 52.030276 -387.856958) (xy 52.009443 -387.812892) (xy 51.995297 -387.766247)
			(xy 51.988141 -387.718033) (xy 51.987704 -387.693662) (xy 51.988109 -387.669544) (xy 51.995117 -387.62182)
			(xy 52.00898 -387.575619) (xy 52.029403 -387.53192) (xy 52.042314 -387.511544) (xy 52.048156 -387.502908)
			(xy 52.051712 -387.482588) (xy 52.03063 -387.390386) (xy 52.018438 -387.373622) (xy 52.009802 -387.368288)
			(xy 52.009294 -387.368288) (xy 51.988541 -387.355379) (xy 51.950688 -387.324469) (xy 51.917794 -387.288326)
			(xy 51.890574 -387.247738) (xy 51.869621 -387.203587) (xy 51.855391 -387.156835) (xy 51.848193 -387.108497)
			(xy 51.84775 -387.084062) (xy 51.848267 -387.05676) (xy 51.857232 -387.002898) (xy 51.874945 -386.951247)
			(xy 51.900921 -386.903218) (xy 51.934452 -386.860123) (xy 51.954176 -386.841238) (xy 51.961512 -386.83369)
			(xy 51.969906 -386.814412) (xy 51.970432 -386.8039) (xy 51.970432 -386.729224) (xy 51.969965 -386.718699)
			(xy 51.961555 -386.699407) (xy 51.954176 -386.691886) (xy 51.934488 -386.672975) (xy 51.901015 -386.629854)
			(xy 51.875068 -386.581827) (xy 51.857349 -386.530195) (xy 51.848337 -386.476355) (xy 51.84775 -386.449062)
			(xy 51.848004 -386.43687) (xy 51.848258 -386.427218) (xy 51.842162 -386.409438) (xy 51.783742 -386.342128)
			(xy 51.76647 -386.333238) (xy 51.757072 -386.332222) (xy 51.730167 -386.328841) (xy 51.677881 -386.314479)
			(xy 51.628637 -386.291782) (xy 51.583755 -386.261358) (xy 51.544434 -386.224022) (xy 51.511729 -386.180774)
			(xy 51.486516 -386.13277) (xy 51.469468 -386.081297) (xy 51.464718 -386.0546) (xy 51.463194 -386.045202)
			(xy 51.190398 -385.57327) (xy 51.183032 -385.567428) (xy 51.164271 -385.551608) (xy 51.131155 -385.515393)
			(xy 51.103746 -385.474688) (xy 51.082642 -385.430384) (xy 51.068307 -385.383451) (xy 51.061054 -385.334917)
			(xy 51.060604 -385.31038) (xy 50.54352 -385.31038) (xy 50.792126 -385.740402) (xy 50.799492 -385.746244)
			(xy 50.818272 -385.762044) (xy 50.851389 -385.798261) (xy 50.878799 -385.838969) (xy 50.8999 -385.883278)
			(xy 50.914229 -385.930215) (xy 50.921474 -385.978754) (xy 50.92192 -386.003292) (xy 50.921666 -386.015484)
			(xy 50.921412 -386.025136) (xy 50.927508 -386.042916) (xy 50.979578 -386.10286) (xy 50.986211 -386.109862)
			(xy 51.003308 -386.118751) (xy 51.012852 -386.120132) (xy 51.039609 -386.12353) (xy 51.091631 -386.137745)
			(xy 51.140657 -386.160214) (xy 51.185387 -386.19034) (xy 51.224636 -386.227326) (xy 51.257363 -386.27019)
			(xy 51.2827 -386.317796) (xy 51.299977 -386.368884) (xy 51.308734 -386.422097) (xy 51.30927 -386.449062)
			(xy 51.308763 -386.476364) (xy 51.299794 -386.530227) (xy 51.282079 -386.581877) (xy 51.2561 -386.629906)
			(xy 51.222568 -386.673001) (xy 51.202844 -386.691886) (xy 51.195501 -386.699428) (xy 51.18711 -386.71871)
			(xy 51.186588 -386.729224) (xy 51.186588 -386.8039) (xy 51.187065 -386.814423) (xy 51.19547 -386.833714)
			(xy 51.202844 -386.841238) (xy 51.222499 -386.860181) (xy 51.255975 -386.903294) (xy 51.281928 -386.951313)
			(xy 51.299655 -387.002938) (xy 51.308677 -387.056771) (xy 51.30927 -387.084062) (xy 51.308817 -387.108178)
			(xy 51.301821 -387.1559) (xy 51.287972 -387.202101) (xy 51.267564 -387.245802) (xy 51.25466 -387.26618)
			(xy 51.248818 -387.274816) (xy 51.245262 -387.295136) (xy 51.266344 -387.387338) (xy 51.278536 -387.404102)
			(xy 51.287172 -387.409436) (xy 51.28768 -387.409436) (xy 51.30846 -387.422302) (xy 51.34631 -387.453222)
			(xy 51.3792 -387.489373) (xy 51.406415 -387.529969) (xy 51.427363 -387.574126) (xy 51.441589 -387.620883)
			(xy 51.448783 -387.669225) (xy 51.449224 -387.693662) (xy 51.448794 -387.718035) (xy 51.441649 -387.766254)
			(xy 51.427508 -387.812903) (xy 51.406676 -387.856972) (xy 51.379605 -387.89751) (xy 51.34688 -387.933637)
			(xy 51.32832 -387.94944) (xy 51.320134 -387.956793) (xy 51.310521 -387.976561) (xy 51.309778 -387.98754)
			(xy 51.307492 -388.064248) (xy 51.307781 -388.075229) (xy 51.316454 -388.09538) (xy 51.324256 -388.10311)
			(xy 51.342705 -388.120572) (xy 51.374052 -388.160542) (xy 51.398349 -388.205151) (xy 51.414925 -388.253167)
			(xy 51.423325 -388.303264) (xy 51.423824 -388.328662) (xy 51.423824 -388.328916) (xy 51.423711 -388.340134)
			(xy 51.42206 -388.362508) (xy 51.420522 -388.37362) (xy 51.419252 -388.38251) (xy 51.422554 -388.400036)
			(xy 51.466242 -388.470902) (xy 51.479958 -388.482078) (xy 51.488594 -388.484872) (xy 51.510846 -388.492789)
			(xy 51.552766 -388.514545) (xy 51.590839 -388.542494) (xy 51.624155 -388.57597) (xy 51.651922 -388.614175)
			(xy 51.663092 -388.634986) (xy 51.6636 -388.636002) (xy 52.05603 -389.314944) (xy 52.068836 -389.338286)
			(xy 52.087063 -389.388304) (xy 52.096331 -389.440727) (xy 52.096924 -389.467344) (xy 52.096479 -389.491323)
			(xy 52.088975 -389.53869) (xy 52.074158 -389.584302) (xy 52.052392 -389.627036) (xy 52.024214 -389.665843)
			(xy 51.990315 -389.699767) (xy 51.951529 -389.727974) (xy 51.908811 -389.749771) (xy 51.86321 -389.764622)
			(xy 51.815849 -389.772161) (xy 51.79187 -389.772652) (xy 51.791362 -389.772652) (xy 51.76783 -389.772199)
			(xy 51.721323 -389.764993) (xy 51.676475 -389.750727) (xy 51.634351 -389.729739) (xy 51.595952 -389.702528)
			(xy 51.56219 -389.669741) (xy 51.533867 -389.632155) (xy 51.522376 -389.611616) (xy 51.522122 -389.611108)
			(xy 51.521614 -389.610346) (xy 51.12385 -388.922006) (xy 51.111973 -388.899329) (xy 51.095123 -388.850996)
			(xy 51.08655 -388.800533) (xy 51.086004 -388.77494) (xy 51.086004 -388.774432) (xy 51.086095 -388.763087)
			(xy 51.08775 -388.740458) (xy 51.089306 -388.72922) (xy 51.090217 -388.720506) (xy 51.086697 -388.703355)
			(xy 51.082448 -388.695692) (xy 51.043586 -388.631938) (xy 51.02987 -388.620762) (xy 51.021234 -388.617968)
			(xy 50.99883 -388.60994) (xy 50.956612 -388.58798) (xy 50.918316 -388.559731) (xy 50.88487 -388.525878)
			(xy 50.857086 -388.487244) (xy 50.835637 -388.444763) (xy 50.821044 -388.399468) (xy 50.813661 -388.352456)
			(xy 50.813208 -388.328662) (xy 50.813731 -388.303267) (xy 50.822141 -388.253178) (xy 50.838721 -388.20517)
			(xy 50.863016 -388.160567) (xy 50.894355 -388.120599) (xy 50.912776 -388.10311) (xy 50.920563 -388.095372)
			(xy 50.929234 -388.075223) (xy 50.92954 -388.064248) (xy 50.927254 -387.98754) (xy 50.926432 -387.976582)
			(xy 50.916833 -387.956841) (xy 50.908712 -387.94944) (xy 50.890167 -387.933622) (xy 50.857448 -387.897493)
			(xy 50.83038 -387.856957) (xy 50.809547 -387.812891) (xy 50.795401 -387.766247) (xy 50.788245 -387.718033)
			(xy 50.787808 -387.693662) (xy 50.788229 -387.669545) (xy 50.795235 -387.621822) (xy 50.809093 -387.575621)
			(xy 50.82951 -387.531921) (xy 50.842418 -387.511544) (xy 50.84826 -387.502908) (xy 50.851816 -387.482588)
			(xy 50.830734 -387.390386) (xy 50.818542 -387.373622) (xy 50.809906 -387.368288) (xy 50.809398 -387.368288)
			(xy 50.788624 -387.355414) (xy 50.750775 -387.324494) (xy 50.717886 -387.288344) (xy 50.69067 -387.24775)
			(xy 50.669721 -387.203594) (xy 50.655493 -387.156838) (xy 50.648297 -387.108498) (xy 50.647854 -387.084062)
			(xy 50.648369 -387.05676) (xy 50.657335 -387.002897) (xy 50.675048 -386.951247) (xy 50.701025 -386.903218)
			(xy 50.734556 -386.860123) (xy 50.75428 -386.841238) (xy 50.761616 -386.833691) (xy 50.77001 -386.814412)
			(xy 50.770536 -386.8039) (xy 50.770536 -386.729224) (xy 50.770068 -386.718699) (xy 50.761659 -386.699407)
			(xy 50.75428 -386.691886) (xy 50.734593 -386.672974) (xy 50.70112 -386.629853) (xy 50.675172 -386.581827)
			(xy 50.657453 -386.530194) (xy 50.648441 -386.476355) (xy 50.647854 -386.449062) (xy 50.648108 -386.43687)
			(xy 50.648362 -386.427218) (xy 50.642266 -386.409438) (xy 50.590196 -386.349494) (xy 50.583579 -386.342474)
			(xy 50.56647 -386.333597) (xy 50.556922 -386.332222) (xy 50.530011 -386.328881) (xy 50.477725 -386.314511)
			(xy 50.428481 -386.291807) (xy 50.383599 -386.261377) (xy 50.34428 -386.224036) (xy 50.311577 -386.180782)
			(xy 50.286364 -386.132775) (xy 50.269317 -386.081299) (xy 50.264568 -386.0546) (xy 50.263044 -386.045202)
			(xy 49.989994 -385.572762) (xy 49.982882 -385.56692) (xy 49.964147 -385.551143) (xy 49.931093 -385.515001)
			(xy 49.903737 -385.474374) (xy 49.882678 -385.430155) (xy 49.868379 -385.383311) (xy 49.861151 -385.334869)
			(xy 49.860708 -385.31038) (xy 49.34366 -385.31038) (xy 49.59223 -385.740402) (xy 49.599596 -385.746244)
			(xy 49.618376 -385.762043) (xy 49.651494 -385.79826) (xy 49.678903 -385.838969) (xy 49.700004 -385.883278)
			(xy 49.714333 -385.930215) (xy 49.721578 -385.978754) (xy 49.722024 -386.003292) (xy 49.72177 -386.015484)
			(xy 49.721516 -386.025136) (xy 49.727612 -386.042916) (xy 49.779682 -386.10286) (xy 49.786314 -386.109864)
			(xy 49.803411 -386.118752) (xy 49.812956 -386.120132) (xy 49.839713 -386.123527) (xy 49.891735 -386.137743)
			(xy 49.940761 -386.160212) (xy 49.985492 -386.190339) (xy 50.02474 -386.227324) (xy 50.057467 -386.270189)
			(xy 50.082804 -386.317796) (xy 50.100081 -386.368883) (xy 50.108838 -386.422097) (xy 50.109374 -386.449062)
			(xy 50.108865 -386.476364) (xy 50.099897 -386.530227) (xy 50.082182 -386.581877) (xy 50.056204 -386.629905)
			(xy 50.022672 -386.673001) (xy 50.002948 -386.691886) (xy 49.995605 -386.699428) (xy 49.987214 -386.71871)
			(xy 49.986692 -386.729224) (xy 49.986692 -386.8039) (xy 49.987168 -386.814423) (xy 49.995574 -386.833715)
			(xy 50.002948 -386.841238) (xy 50.022604 -386.86018) (xy 50.056079 -386.903294) (xy 50.082032 -386.951313)
			(xy 50.099759 -387.002938) (xy 50.108781 -387.056771) (xy 50.109374 -387.084062) (xy 50.10892 -387.108178)
			(xy 50.101924 -387.1559) (xy 50.088076 -387.202101) (xy 50.067668 -387.245802) (xy 50.054764 -387.26618)
			(xy 50.048922 -387.274816) (xy 50.045366 -387.295136) (xy 50.066448 -387.387338) (xy 50.07864 -387.404102)
			(xy 50.087276 -387.409436) (xy 50.087784 -387.409436) (xy 50.108565 -387.4223) (xy 50.146414 -387.453221)
			(xy 50.179304 -387.489373) (xy 50.206519 -387.529968) (xy 50.227467 -387.574125) (xy 50.241693 -387.620883)
			(xy 50.248887 -387.669225) (xy 50.249328 -387.693662) (xy 50.248897 -387.718035) (xy 50.241752 -387.766253)
			(xy 50.227611 -387.812902) (xy 50.206779 -387.856972) (xy 50.179708 -387.897509) (xy 50.146984 -387.933637)
			(xy 50.128424 -387.94944) (xy 50.120238 -387.956794) (xy 50.110625 -387.976561) (xy 50.109882 -387.98754)
			(xy 50.107596 -388.064248) (xy 50.107884 -388.075229) (xy 50.116557 -388.095381) (xy 50.12436 -388.10311)
			(xy 50.14281 -388.120571) (xy 50.174156 -388.160542) (xy 50.198453 -388.205151) (xy 50.21503 -388.253166)
			(xy 50.223429 -388.303264) (xy 50.223928 -388.328662) (xy 50.223928 -388.328916) (xy 50.223815 -388.340134)
			(xy 50.222164 -388.362508) (xy 50.220626 -388.37362) (xy 50.219356 -388.38251) (xy 50.222658 -388.400036)
			(xy 50.266346 -388.470902) (xy 50.280062 -388.482078) (xy 50.288698 -388.484872) (xy 50.316864 -388.495065)
			(xy 50.368809 -388.524879) (xy 50.391822 -388.544054) (xy 50.413309 -388.563632) (xy 50.44912 -388.609413)
			(xy 50.462942 -388.634986) (xy 50.463704 -388.636256) (xy 50.85588 -389.314944) (xy 50.868601 -389.338268)
			(xy 50.886698 -389.388213) (xy 50.89592 -389.440529) (xy 50.89652 -389.46709) (xy 50.89652 -389.467344)
			(xy 50.896078 -389.491336) (xy 50.888566 -389.538728) (xy 50.873733 -389.584362) (xy 50.851945 -389.627113)
			(xy 50.823738 -389.665931) (xy 50.789807 -389.699859) (xy 50.750986 -389.728062) (xy 50.708232 -389.749845)
			(xy 50.662597 -389.764673) (xy 50.615204 -389.772181) (xy 50.591212 -389.772652) (xy 50.567679 -389.77224)
			(xy 50.52117 -389.765026) (xy 50.476321 -389.750752) (xy 50.434197 -389.729758) (xy 50.395799 -389.702541)
			(xy 50.362038 -389.669748) (xy 50.333716 -389.632158) (xy 50.322226 -389.611616) (xy 50.321972 -389.611108)
			(xy 50.321464 -389.610346) (xy 49.923954 -388.921752) (xy 49.913377 -388.901828) (xy 49.897576 -388.859577)
			(xy 49.888171 -388.815459) (xy 49.886362 -388.792974) (xy 49.885854 -388.781798) (xy 49.8856 -388.775194)
			(xy 49.8856 -388.77367) (xy 49.885783 -388.762512) (xy 49.88756 -388.740265) (xy 49.889156 -388.72922)
			(xy 49.889156 -388.728966) (xy 49.890038 -388.720251) (xy 49.886537 -388.703103) (xy 49.882298 -388.695438)
			(xy 49.843436 -388.631938) (xy 49.82972 -388.620762) (xy 49.821084 -388.617968) (xy 49.798685 -388.609964)
			(xy 49.756513 -388.587963) (xy 49.718265 -388.559687) (xy 49.684865 -388.525822) (xy 49.657121 -388.487186)
			(xy 49.635705 -388.444714) (xy 49.621135 -388.399435) (xy 49.613763 -388.352445) (xy 49.613312 -388.328662)
			(xy 49.613834 -388.303267) (xy 49.622243 -388.253177) (xy 49.638824 -388.20517) (xy 49.663119 -388.160567)
			(xy 49.694459 -388.120598) (xy 49.71288 -388.10311) (xy 49.720667 -388.095373) (xy 49.729338 -388.075223)
			(xy 49.729644 -388.064248) (xy 49.727358 -387.98754) (xy 49.726535 -387.976582) (xy 49.716937 -387.956841)
			(xy 49.708816 -387.94944) (xy 49.690271 -387.933621) (xy 49.657553 -387.897492) (xy 49.630484 -387.856957)
			(xy 49.609652 -387.812891) (xy 49.595505 -387.766247) (xy 49.588349 -387.718033) (xy 49.587912 -387.693662)
			(xy 49.588332 -387.669545) (xy 49.595338 -387.621822) (xy 49.609197 -387.575621) (xy 49.629614 -387.531921)
			(xy 49.642522 -387.511544) (xy 49.648364 -387.502908) (xy 49.65192 -387.482588) (xy 49.630838 -387.390386)
			(xy 49.618646 -387.373622) (xy 49.61001 -387.368288) (xy 49.609502 -387.368288) (xy 49.588728 -387.355412)
			(xy 49.55088 -387.324493) (xy 49.51799 -387.288343) (xy 49.490775 -387.247749) (xy 49.469825 -387.203594)
			(xy 49.455597 -387.156838) (xy 49.448401 -387.108498) (xy 49.447958 -387.084062) (xy 49.448472 -387.05676)
			(xy 49.457438 -387.002897) (xy 49.475151 -386.951246) (xy 49.501128 -386.903218) (xy 49.53466 -386.860123)
			(xy 49.554384 -386.841238) (xy 49.561721 -386.833691) (xy 49.570114 -386.814412) (xy 49.57064 -386.8039)
			(xy 49.57064 -386.729224) (xy 49.570171 -386.718699) (xy 49.561762 -386.699407) (xy 49.554384 -386.691886)
			(xy 49.534697 -386.672974) (xy 49.501224 -386.629853) (xy 49.475277 -386.581826) (xy 49.457557 -386.530194)
			(xy 49.448545 -386.476355) (xy 49.447958 -386.449062) (xy 49.448212 -386.43687) (xy 49.448466 -386.427218)
			(xy 49.44237 -386.409438) (xy 49.3903 -386.349494) (xy 49.383682 -386.342476) (xy 49.366574 -386.333597)
			(xy 49.357026 -386.332222) (xy 49.330115 -386.328878) (xy 49.277829 -386.314508) (xy 49.228586 -386.291805)
			(xy 49.183704 -386.261376) (xy 49.144384 -386.224035) (xy 49.111681 -386.180782) (xy 49.086468 -386.132775)
			(xy 49.069421 -386.081299) (xy 49.064672 -386.0546) (xy 49.063148 -386.045202) (xy 48.790352 -385.57327)
			(xy 48.782986 -385.567428) (xy 48.764236 -385.551595) (xy 48.731117 -385.515384) (xy 48.703705 -385.474682)
			(xy 48.682599 -385.430381) (xy 48.668262 -385.383449) (xy 48.661008 -385.334916) (xy 48.660558 -385.31038)
			(xy 48.143764 -385.31038) (xy 48.392334 -385.740402) (xy 48.3997 -385.746244) (xy 48.418481 -385.762042)
			(xy 48.451599 -385.79826) (xy 48.479008 -385.838969) (xy 48.500108 -385.883277) (xy 48.514438 -385.930215)
			(xy 48.521682 -385.978754) (xy 48.522128 -386.003292) (xy 48.521874 -386.015484) (xy 48.52162 -386.025136)
			(xy 48.527716 -386.042916) (xy 48.586136 -386.110226) (xy 48.603408 -386.119116) (xy 48.612806 -386.120132)
			(xy 48.639569 -386.123487) (xy 48.691591 -386.13771) (xy 48.740617 -386.160186) (xy 48.785347 -386.190318)
			(xy 48.824594 -386.227309) (xy 48.85732 -386.270178) (xy 48.882656 -386.317789) (xy 48.899931 -386.368879)
			(xy 48.908688 -386.422096) (xy 48.909224 -386.449062) (xy 48.908699 -386.476363) (xy 48.899732 -386.530224)
			(xy 48.88202 -386.581874) (xy 48.856046 -386.629902) (xy 48.822519 -386.672999) (xy 48.802798 -386.691886)
			(xy 48.795462 -386.699435) (xy 48.787066 -386.718712) (xy 48.786542 -386.729224) (xy 48.786542 -386.8039)
			(xy 48.787003 -386.814425) (xy 48.795418 -386.833717) (xy 48.802798 -386.841238) (xy 48.822445 -386.86019)
			(xy 48.855923 -386.9033) (xy 48.881879 -386.951316) (xy 48.899608 -387.00294) (xy 48.908631 -387.056771)
			(xy 48.909224 -387.084062) (xy 48.908778 -387.108178) (xy 48.901781 -387.155901) (xy 48.887931 -387.202102)
			(xy 48.867519 -387.245803) (xy 48.854614 -387.26618) (xy 48.848772 -387.274816) (xy 48.845216 -387.295136)
			(xy 48.866298 -387.387338) (xy 48.87849 -387.404102) (xy 48.887126 -387.409436) (xy 48.887634 -387.409436)
			(xy 48.908404 -387.422318) (xy 48.946255 -387.453234) (xy 48.979148 -387.489382) (xy 49.006365 -387.529974)
			(xy 49.027315 -387.574129) (xy 49.041542 -387.620885) (xy 49.048737 -387.669226) (xy 49.049178 -387.693662)
			(xy 49.048765 -387.718036) (xy 49.041619 -387.766256) (xy 49.027475 -387.812906) (xy 49.00664 -387.856976)
			(xy 48.979566 -387.897513) (xy 48.946836 -387.933638) (xy 48.928274 -387.94944) (xy 48.920097 -387.956802)
			(xy 48.910477 -387.976563) (xy 48.909732 -387.98754) (xy 48.907446 -388.064248) (xy 48.907718 -388.075231)
			(xy 48.916401 -388.095383) (xy 48.92421 -388.10311) (xy 48.94265 -388.120581) (xy 48.974 -388.160548)
			(xy 48.998299 -388.205154) (xy 49.014878 -388.253168) (xy 49.023278 -388.303264) (xy 49.023778 -388.328662)
			(xy 49.023778 -388.328916) (xy 49.023666 -388.340134) (xy 49.022014 -388.362508) (xy 49.020476 -388.37362)
			(xy 49.019206 -388.38251) (xy 49.022508 -388.400036) (xy 49.066196 -388.470902) (xy 49.079912 -388.482078)
			(xy 49.088548 -388.484872) (xy 49.110792 -388.492811) (xy 49.152713 -388.514561) (xy 49.190787 -388.542504)
			(xy 49.224106 -388.575976) (xy 49.251875 -388.614177) (xy 49.263046 -388.634986) (xy 49.263554 -388.636002)
			(xy 49.655984 -389.314944) (xy 49.668697 -389.338272) (xy 49.686799 -389.388215) (xy 49.696023 -389.44053)
			(xy 49.696624 -389.46709) (xy 49.696624 -389.467344) (xy 49.696178 -389.491336) (xy 49.688666 -389.538727)
			(xy 49.673833 -389.584361) (xy 49.652046 -389.627112) (xy 49.623839 -389.66593) (xy 49.589908 -389.699858)
			(xy 49.551088 -389.72806) (xy 49.508335 -389.749844) (xy 49.4627 -389.764672) (xy 49.415308 -389.77218)
			(xy 49.391316 -389.772652) (xy 49.367783 -389.772236) (xy 49.321274 -389.765023) (xy 49.276425 -389.75075)
			(xy 49.234301 -389.729756) (xy 49.195903 -389.70254) (xy 49.162142 -389.669748) (xy 49.13382 -389.632158)
			(xy 49.12233 -389.611616) (xy 49.122076 -389.611108) (xy 49.121568 -389.610346) (xy 48.723804 -388.922006)
			(xy 48.711889 -388.899338) (xy 48.694951 -388.851012) (xy 48.686292 -388.800542) (xy 48.685704 -388.77494)
			(xy 48.685704 -388.774432) (xy 48.685861 -388.763083) (xy 48.687638 -388.740454) (xy 48.68926 -388.72922)
			(xy 48.690164 -388.720506) (xy 48.686647 -388.703356) (xy 48.682402 -388.695692) (xy 48.64354 -388.631938)
			(xy 48.629824 -388.620762) (xy 48.621188 -388.617968) (xy 48.598795 -388.609909) (xy 48.556576 -388.587956)
			(xy 48.518278 -388.559713) (xy 48.48483 -388.525866) (xy 48.457043 -388.487235) (xy 48.435593 -388.444757)
			(xy 48.420999 -388.399465) (xy 48.413615 -388.352455) (xy 48.413162 -388.328662) (xy 48.413668 -388.303266)
			(xy 48.422079 -388.253175) (xy 48.438663 -388.205166) (xy 48.462962 -388.160564) (xy 48.494307 -388.120597)
			(xy 48.51273 -388.10311) (xy 48.52051 -388.095366) (xy 48.529187 -388.075222) (xy 48.529494 -388.064248)
			(xy 48.527208 -387.98754) (xy 48.526369 -387.976585) (xy 48.516781 -387.956844) (xy 48.508666 -387.94944)
			(xy 48.490132 -387.933609) (xy 48.45741 -387.897484) (xy 48.430339 -387.856952) (xy 48.409504 -387.812888)
			(xy 48.395356 -387.766246) (xy 48.3882 -387.718033) (xy 48.387762 -387.693662) (xy 48.388174 -387.669544)
			(xy 48.395181 -387.621821) (xy 48.409042 -387.57562) (xy 48.429462 -387.53192) (xy 48.442372 -387.511544)
			(xy 48.448214 -387.502908) (xy 48.45177 -387.482588) (xy 48.430688 -387.390386) (xy 48.418496 -387.373622)
			(xy 48.40986 -387.368288) (xy 48.409352 -387.368288) (xy 48.38859 -387.355394) (xy 48.350739 -387.32448)
			(xy 48.317847 -387.288334) (xy 48.290629 -387.247743) (xy 48.269677 -387.20359) (xy 48.255448 -387.156836)
			(xy 48.248251 -387.108498) (xy 48.247808 -387.084062) (xy 48.248338 -387.056761) (xy 48.257302 -387.0029)
			(xy 48.275013 -386.95125) (xy 48.300986 -386.903221) (xy 48.334512 -386.860124) (xy 48.354234 -386.841238)
			(xy 48.361564 -386.833685) (xy 48.369963 -386.814411) (xy 48.37049 -386.8039) (xy 48.37049 -386.729224)
			(xy 48.370006 -386.718701) (xy 48.361607 -386.69941) (xy 48.354234 -386.691886) (xy 48.334557 -386.672964)
			(xy 48.30108 -386.629847) (xy 48.27513 -386.581823) (xy 48.257408 -386.530193) (xy 48.248395 -386.476355)
			(xy 48.247808 -386.449062) (xy 48.248062 -386.43687) (xy 48.248316 -386.427218) (xy 48.24222 -386.409438)
			(xy 48.1838 -386.342128) (xy 48.166528 -386.333238) (xy 48.15713 -386.332222) (xy 48.13022 -386.328874)
			(xy 48.077934 -386.314506) (xy 48.02869 -386.291803) (xy 47.983808 -386.261374) (xy 47.944489 -386.224034)
			(xy 47.911785 -386.180781) (xy 47.886572 -386.132774) (xy 47.869526 -386.081299) (xy 47.864776 -386.0546)
			(xy 47.863252 -386.045202) (xy 47.590456 -385.57327) (xy 47.58309 -385.567428) (xy 47.564341 -385.551594)
			(xy 47.531222 -385.515383) (xy 47.503809 -385.474682) (xy 47.482703 -385.43038) (xy 47.468366 -385.383449)
			(xy 47.461112 -385.334916) (xy 47.460662 -385.31038) (xy 45.134285 -385.31038) (xy 45.171809 -385.332778)
			(xy 45.212098 -385.366507) (xy 45.246543 -385.406185) (xy 45.274278 -385.450812) (xy 45.294602 -385.499266)
			(xy 45.307005 -385.550324) (xy 45.311175 -385.602702) (xy 45.307005 -385.65508) (xy 45.294601 -385.706138)
			(xy 45.274276 -385.754592) (xy 45.246541 -385.799219) (xy 45.212095 -385.838896) (xy 45.171806 -385.872625)
			(xy 45.166939 -385.87553) (xy 46.834044 -385.87553) (xy 46.834554 -385.849543) (xy 46.842684 -385.798208)
			(xy 46.858745 -385.748778) (xy 46.882341 -385.702468) (xy 46.912891 -385.66042) (xy 46.949642 -385.623669)
			(xy 46.99169 -385.593119) (xy 47.038 -385.569523) (xy 47.08743 -385.553462) (xy 47.138765 -385.545332)
			(xy 47.190739 -385.545332) (xy 47.242074 -385.553462) (xy 47.291504 -385.569523) (xy 47.337814 -385.593119)
			(xy 47.379862 -385.623669) (xy 47.416613 -385.66042) (xy 47.447163 -385.702468) (xy 47.470759 -385.748778)
			(xy 47.48682 -385.798208) (xy 47.49495 -385.849543) (xy 47.49546 -385.87553) (xy 47.49546 -385.875784)
			(xy 47.495061 -385.899418) (xy 47.488316 -385.946201) (xy 47.474963 -385.991543) (xy 47.465488 -386.013198)
			(xy 47.461635 -386.022538) (xy 47.460837 -386.042708) (xy 47.463964 -386.052314) (xy 47.492666 -386.129276)
			(xy 47.506382 -386.144008) (xy 47.51578 -386.148072) (xy 47.540156 -386.159749) (xy 47.585024 -386.189879)
			(xy 47.624401 -386.2269) (xy 47.657238 -386.269828) (xy 47.682663 -386.317521) (xy 47.7 -386.368711)
			(xy 47.708789 -386.422039) (xy 47.709328 -386.449062) (xy 47.708802 -386.476363) (xy 47.699835 -386.530224)
			(xy 47.682123 -386.581873) (xy 47.65615 -386.629902) (xy 47.622623 -386.672999) (xy 47.602902 -386.691886)
			(xy 47.595567 -386.699435) (xy 47.58717 -386.718712) (xy 47.586646 -386.729224) (xy 47.586646 -386.8039)
			(xy 47.587106 -386.814426) (xy 47.595521 -386.833718) (xy 47.602902 -386.841238) (xy 47.62255 -386.860189)
			(xy 47.656028 -386.903299) (xy 47.681983 -386.951316) (xy 47.699712 -387.002939) (xy 47.708735 -387.056771)
			(xy 47.709328 -387.084062) (xy 47.708882 -387.108178) (xy 47.701885 -387.155901) (xy 47.688034 -387.202102)
			(xy 47.667623 -387.245803) (xy 47.654718 -387.26618) (xy 47.648876 -387.274816) (xy 47.64532 -387.295136)
			(xy 47.666402 -387.387338) (xy 47.678594 -387.404102) (xy 47.68723 -387.409436) (xy 47.687738 -387.409436)
			(xy 47.708509 -387.422317) (xy 47.74636 -387.453233) (xy 47.779252 -387.489381) (xy 47.806469 -387.529974)
			(xy 47.827419 -387.574129) (xy 47.841646 -387.620885) (xy 47.848841 -387.669226) (xy 47.849282 -387.693662)
			(xy 47.848868 -387.718035) (xy 47.841721 -387.766256) (xy 47.827578 -387.812906) (xy 47.806744 -387.856976)
			(xy 47.779669 -387.897512) (xy 47.74694 -387.933638) (xy 47.728378 -387.94944) (xy 47.720201 -387.956803)
			(xy 47.710582 -387.976563) (xy 47.709836 -387.98754) (xy 47.70755 -388.064248) (xy 47.707821 -388.075231)
			(xy 47.716505 -388.095384) (xy 47.724314 -388.10311) (xy 47.742755 -388.12058) (xy 47.774104 -388.160548)
			(xy 47.798404 -388.205154) (xy 47.814982 -388.253168) (xy 47.823382 -388.303264) (xy 47.823882 -388.328662)
			(xy 47.823882 -388.328916) (xy 47.82377 -388.340134) (xy 47.822118 -388.362508) (xy 47.82058 -388.37362)
			(xy 47.81931 -388.38251) (xy 47.822612 -388.400036) (xy 47.8663 -388.470902) (xy 47.880016 -388.482078)
			(xy 47.888652 -388.484872) (xy 47.910896 -388.492809) (xy 47.952818 -388.514559) (xy 47.990892 -388.542503)
			(xy 48.02421 -388.575975) (xy 48.051979 -388.614177) (xy 48.06315 -388.634986) (xy 48.063658 -388.636002)
			(xy 48.456088 -389.314944) (xy 48.468802 -389.338272) (xy 48.486903 -389.388215) (xy 48.496127 -389.44053)
			(xy 48.496728 -389.46709) (xy 48.496728 -389.467344) (xy 48.496278 -389.491335) (xy 48.488766 -389.538727)
			(xy 48.473934 -389.58436) (xy 48.452147 -389.627111) (xy 48.423941 -389.665928) (xy 48.39001 -389.699856)
			(xy 48.351191 -389.728059) (xy 48.308437 -389.749843) (xy 48.262803 -389.764672) (xy 48.215411 -389.77218)
			(xy 48.19142 -389.772652) (xy 48.167887 -389.772233) (xy 48.121378 -389.76502) (xy 48.076529 -389.750748)
			(xy 48.034406 -389.729755) (xy 47.996007 -389.702539) (xy 47.962246 -389.669747) (xy 47.933924 -389.632157)
			(xy 47.922434 -389.611616) (xy 47.92218 -389.611108) (xy 47.921672 -389.610346) (xy 47.523908 -388.922006)
			(xy 47.511993 -388.899337) (xy 47.495055 -388.851012) (xy 47.486396 -388.800542) (xy 47.485808 -388.77494)
			(xy 47.485808 -388.774432) (xy 47.485965 -388.763083) (xy 47.487742 -388.740454) (xy 47.489364 -388.72922)
			(xy 47.490267 -388.720506) (xy 47.486751 -388.703356) (xy 47.482506 -388.695692) (xy 47.443644 -388.631938)
			(xy 47.429928 -388.620762) (xy 47.421292 -388.617968) (xy 47.398879 -388.609965) (xy 47.356662 -388.587999)
			(xy 47.318367 -388.559745) (xy 47.284923 -388.525889) (xy 47.25714 -388.487251) (xy 47.235693 -388.444768)
			(xy 47.221101 -388.39947) (xy 47.213719 -388.352457) (xy 47.213266 -388.328662) (xy 47.213803 -388.303268)
			(xy 47.222211 -388.25318) (xy 47.238789 -388.205173) (xy 47.26308 -388.16057) (xy 47.294416 -388.1206)
			(xy 47.312834 -388.10311) (xy 47.320614 -388.095366) (xy 47.329291 -388.075222) (xy 47.329598 -388.064248)
			(xy 47.327312 -387.98754) (xy 47.326472 -387.976585) (xy 47.316884 -387.956845) (xy 47.30877 -387.94944)
			(xy 47.290236 -387.933608) (xy 47.257514 -387.897484) (xy 47.230443 -387.856951) (xy 47.209608 -387.812888)
			(xy 47.19546 -387.766245) (xy 47.188304 -387.718032) (xy 47.187866 -387.693662) (xy 47.188277 -387.669544)
			(xy 47.195285 -387.621821) (xy 47.209145 -387.57562) (xy 47.229566 -387.53192) (xy 47.242476 -387.511544)
			(xy 47.248318 -387.502908) (xy 47.251874 -387.482588) (xy 47.230792 -387.390386) (xy 47.2186 -387.373622)
			(xy 47.209964 -387.368288) (xy 47.209456 -387.368288) (xy 47.188695 -387.355393) (xy 47.150844 -387.324479)
			(xy 47.117951 -387.288333) (xy 47.090733 -387.247743) (xy 47.069782 -387.20359) (xy 47.055552 -387.156836)
			(xy 47.048355 -387.108498) (xy 47.047912 -387.084062) (xy 47.048441 -387.056761) (xy 47.057405 -387.002899)
			(xy 47.075116 -386.951249) (xy 47.101089 -386.903221) (xy 47.134616 -386.860124) (xy 47.154338 -386.841238)
			(xy 47.161668 -386.833685) (xy 47.170067 -386.814411) (xy 47.170594 -386.8039) (xy 47.170594 -386.729224)
			(xy 47.170109 -386.718701) (xy 47.16171 -386.69941) (xy 47.154338 -386.691886) (xy 47.134643 -386.672982)
			(xy 47.101173 -386.629858) (xy 47.075228 -386.581829) (xy 47.05751 -386.530196) (xy 47.048499 -386.476356)
			(xy 47.047912 -386.449062) (xy 47.047912 -386.448808) (xy 47.048311 -386.425174) (xy 47.055056 -386.378391)
			(xy 47.068409 -386.333049) (xy 47.077884 -386.311394) (xy 47.08174 -386.302055) (xy 47.082534 -386.281885)
			(xy 47.079408 -386.272278) (xy 47.050706 -386.195316) (xy 47.03699 -386.180584) (xy 47.027592 -386.17652)
			(xy 47.00323 -386.164816) (xy 46.958358 -386.134694) (xy 46.918978 -386.097679) (xy 46.886138 -386.054756)
			(xy 46.86071 -386.007066) (xy 46.843372 -385.955878) (xy 46.834583 -385.902552) (xy 46.834044 -385.87553)
			(xy 45.166939 -385.87553) (xy 45.126688 -385.899554) (xy 45.077878 -385.919007) (xy 45.026605 -385.930492)
			(xy 45.000418 -385.93268) (xy 44.990512 -385.933188) (xy 44.973494 -385.941316) (xy 44.918884 -385.999228)
			(xy 44.9126 -386.006518) (xy 44.905548 -386.024409) (xy 44.905168 -386.034026) (xy 44.905168 -386.063744)
			(xy 44.905732 -386.07485) (xy 44.915091 -386.094997) (xy 44.923202 -386.102606) (xy 44.982892 -386.152644)
			(xy 44.991761 -386.159379) (xy 45.013238 -386.165163) (xy 45.024294 -386.16382) (xy 45.038528 -386.161461)
			(xy 45.067271 -386.158919) (xy 45.081698 -386.15874) (xy 45.081952 -386.15874) (xy 45.107925 -386.159269)
			(xy 45.159226 -386.167431) (xy 45.20862 -386.183515) (xy 45.254891 -386.207125) (xy 45.2969 -386.23768)
			(xy 45.333615 -386.274428) (xy 45.364132 -386.316466) (xy 45.3877 -386.362758) (xy 45.403739 -386.412166)
			(xy 45.411855 -386.463475) (xy 45.412406 -386.489448) (xy 45.411848 -386.516778) (xy 45.402868 -386.570694)
			(xy 45.385145 -386.622401) (xy 45.359161 -386.670489) (xy 45.34281 -386.692394) (xy 45.337579 -386.699666)
			(xy 45.332102 -386.716711) (xy 45.332142 -386.725668) (xy 45.334936 -386.791708) (xy 45.335708 -386.800538)
			(xy 45.342454 -386.816916) (xy 45.348144 -386.823712) (xy 45.36452 -386.842121) (xy 45.392195 -386.882881)
			(xy 45.413513 -386.927298) (xy 45.428001 -386.974388) (xy 45.435338 -387.023106) (xy 45.435774 -387.04774)
			(xy 45.435261 -387.073724) (xy 45.427126 -387.125052) (xy 45.411061 -387.174475) (xy 45.387462 -387.220776)
			(xy 45.356911 -387.262816) (xy 45.32016 -387.299559) (xy 45.278113 -387.330101) (xy 45.231806 -387.353689)
			(xy 45.18238 -387.369743) (xy 45.13105 -387.377867) (xy 45.105066 -387.378448) (xy 45.104812 -387.378448)
			(xy 45.08591 -387.37816) (xy 45.048355 -387.373828) (xy 45.029882 -387.369812) (xy 45.018452 -387.367018)
			(xy 44.9961 -387.372098) (xy 44.924472 -387.428994) (xy 44.91576 -387.436572) (xy 44.905716 -387.457338)
			(xy 44.905168 -387.468872) (xy 44.905168 -387.875018) (xy 44.905717 -387.886549) (xy 44.915773 -387.907305)
			(xy 44.924472 -387.914896) (xy 44.9961 -387.971792) (xy 45.018452 -387.976872) (xy 45.029882 -387.974078)
			(xy 45.048349 -387.97003) (xy 45.085908 -387.965697) (xy 45.104812 -387.965442) (xy 45.105066 -387.965442)
			(xy 45.131053 -387.965922) (xy 45.182388 -387.974048) (xy 45.23182 -387.990105) (xy 45.278131 -388.013697)
			(xy 45.32018 -388.044244) (xy 45.356933 -388.080994) (xy 45.387485 -388.12304) (xy 45.411082 -388.169349)
			(xy 45.427144 -388.218779) (xy 45.435275 -388.270113) (xy 45.435275 -388.322087) (xy 45.427144 -388.373421)
			(xy 45.411082 -388.422851) (xy 45.387485 -388.46916) (xy 45.356933 -388.511206) (xy 45.32018 -388.547956)
			(xy 45.278131 -388.578503) (xy 45.23182 -388.602095) (xy 45.182388 -388.618152) (xy 45.131053 -388.626278)
			(xy 45.105066 -388.626858) (xy 45.104812 -388.626858) (xy 45.08591 -388.62657) (xy 45.048355 -388.622238)
			(xy 45.029882 -388.618222) (xy 45.018452 -388.615428) (xy 44.9961 -388.620508) (xy 44.924472 -388.677404)
			(xy 44.915762 -388.684983) (xy 44.905722 -388.705748) (xy 44.905168 -388.717282) (xy 44.905168 -389.64362)
			(xy 44.905773 -389.654949) (xy 44.915539 -389.675391) (xy 44.923964 -389.68299) (xy 44.993814 -389.74014)
			(xy 45.015658 -389.745474) (xy 45.027088 -389.743188) (xy 45.043483 -389.740073) (xy 45.076694 -389.736764)
			(xy 45.093382 -389.736584) (xy 45.119372 -389.737066) (xy 45.170714 -389.745195) (xy 45.220151 -389.761255)
			(xy 45.266467 -389.784852) (xy 45.308522 -389.815404) (xy 45.345279 -389.852158) (xy 45.375834 -389.89421)
			(xy 45.399435 -389.940525) (xy 45.415499 -389.989961) (xy 45.423632 -390.041302) (xy 45.42409 -390.067292)
			(xy 45.423697 -390.090526) (xy 45.417195 -390.136537) (xy 45.410427 -390.160002) (xy 47.085262 -390.160002)
			(xy 47.089222 -390.110948) (xy 47.100999 -390.063164) (xy 47.12029 -390.017888) (xy 47.146593 -389.976292)
			(xy 47.179228 -389.939455) (xy 47.217349 -389.90833) (xy 47.25997 -389.883723) (xy 47.305986 -389.866271)
			(xy 47.354205 -389.856427) (xy 47.40338 -389.854446) (xy 47.452235 -389.860378) (xy 47.499506 -389.87407)
			(xy 47.543968 -389.895168) (xy 47.584471 -389.923124) (xy 47.619964 -389.957216) (xy 47.649529 -389.99656)
			(xy 47.6724 -390.040137) (xy 47.687984 -390.086818) (xy 47.695879 -390.135395) (xy 47.696374 -390.160002)
			(xy 48.285412 -390.160002) (xy 48.289372 -390.110948) (xy 48.301149 -390.063164) (xy 48.32044 -390.017888)
			(xy 48.346743 -389.976292) (xy 48.379378 -389.939455) (xy 48.417499 -389.90833) (xy 48.46012 -389.883723)
			(xy 48.506136 -389.866271) (xy 48.554355 -389.856427) (xy 48.60353 -389.854446) (xy 48.652385 -389.860378)
			(xy 48.699656 -389.87407) (xy 48.744118 -389.895168) (xy 48.784621 -389.923124) (xy 48.820114 -389.957216)
			(xy 48.849679 -389.99656) (xy 48.87255 -390.040137) (xy 48.888134 -390.086818) (xy 48.896029 -390.135395)
			(xy 48.896524 -390.160002) (xy 49.485562 -390.160002) (xy 49.489522 -390.110948) (xy 49.501299 -390.063164)
			(xy 49.52059 -390.017888) (xy 49.546893 -389.976292) (xy 49.579528 -389.939455) (xy 49.617649 -389.90833)
			(xy 49.66027 -389.883723) (xy 49.706286 -389.866271) (xy 49.754505 -389.856427) (xy 49.80368 -389.854446)
			(xy 49.852535 -389.860378) (xy 49.899806 -389.87407) (xy 49.944268 -389.895168) (xy 49.984771 -389.923124)
			(xy 50.020264 -389.957216) (xy 50.049829 -389.99656) (xy 50.0727 -390.040137) (xy 50.088284 -390.086818)
			(xy 50.096179 -390.135395) (xy 50.096674 -390.160002) (xy 50.685458 -390.160002) (xy 50.689418 -390.110948)
			(xy 50.701195 -390.063164) (xy 50.720486 -390.017888) (xy 50.746789 -389.976292) (xy 50.779424 -389.939455)
			(xy 50.817545 -389.90833) (xy 50.860166 -389.883723) (xy 50.906182 -389.866271) (xy 50.954401 -389.856427)
			(xy 51.003576 -389.854446) (xy 51.052431 -389.860378) (xy 51.099702 -389.87407) (xy 51.144164 -389.895168)
			(xy 51.184667 -389.923124) (xy 51.22016 -389.957216) (xy 51.249725 -389.99656) (xy 51.272596 -390.040137)
			(xy 51.28818 -390.086818) (xy 51.296075 -390.135395) (xy 51.29657 -390.160002) (xy 51.885608 -390.160002)
			(xy 51.889568 -390.110948) (xy 51.901345 -390.063164) (xy 51.920636 -390.017888) (xy 51.946939 -389.976292)
			(xy 51.979574 -389.939455) (xy 52.017695 -389.90833) (xy 52.060316 -389.883723) (xy 52.106332 -389.866271)
			(xy 52.154551 -389.856427) (xy 52.203726 -389.854446) (xy 52.252581 -389.860378) (xy 52.299852 -389.87407)
			(xy 52.344314 -389.895168) (xy 52.384817 -389.923124) (xy 52.42031 -389.957216) (xy 52.449875 -389.99656)
			(xy 52.472746 -390.040137) (xy 52.48833 -390.086818) (xy 52.496225 -390.135395) (xy 52.49672 -390.160002)
			(xy 53.085504 -390.160002) (xy 53.089464 -390.110948) (xy 53.101241 -390.063164) (xy 53.120532 -390.017888)
			(xy 53.146835 -389.976292) (xy 53.17947 -389.939455) (xy 53.217591 -389.90833) (xy 53.260212 -389.883723)
			(xy 53.306228 -389.866271) (xy 53.354447 -389.856427) (xy 53.403622 -389.854446) (xy 53.452477 -389.860378)
			(xy 53.499748 -389.87407) (xy 53.54421 -389.895168) (xy 53.584713 -389.923124) (xy 53.620206 -389.957216)
			(xy 53.649771 -389.99656) (xy 53.672642 -390.040137) (xy 53.688226 -390.086818) (xy 53.696121 -390.135395)
			(xy 53.696616 -390.160002) (xy 54.2854 -390.160002) (xy 54.28936 -390.110948) (xy 54.301137 -390.063164)
			(xy 54.320428 -390.017888) (xy 54.346731 -389.976292) (xy 54.379366 -389.939455) (xy 54.417487 -389.90833)
			(xy 54.460108 -389.883723) (xy 54.506124 -389.866271) (xy 54.554343 -389.856427) (xy 54.603518 -389.854446)
			(xy 54.652373 -389.860378) (xy 54.699644 -389.87407) (xy 54.744106 -389.895168) (xy 54.784609 -389.923124)
			(xy 54.820102 -389.957216) (xy 54.849667 -389.99656) (xy 54.872538 -390.040137) (xy 54.888122 -390.086818)
			(xy 54.896017 -390.135395) (xy 54.896512 -390.160002) (xy 55.48555 -390.160002) (xy 55.48951 -390.110948)
			(xy 55.501287 -390.063164) (xy 55.520578 -390.017888) (xy 55.546881 -389.976292) (xy 55.579516 -389.939455)
			(xy 55.617637 -389.90833) (xy 55.660258 -389.883723) (xy 55.706274 -389.866271) (xy 55.754493 -389.856427)
			(xy 55.803668 -389.854446) (xy 55.852523 -389.860378) (xy 55.899794 -389.87407) (xy 55.944256 -389.895168)
			(xy 55.984759 -389.923124) (xy 56.020252 -389.957216) (xy 56.049817 -389.99656) (xy 56.072688 -390.040137)
			(xy 56.088272 -390.086818) (xy 56.096167 -390.135395) (xy 56.096662 -390.160002) (xy 56.685446 -390.160002)
			(xy 56.689406 -390.110948) (xy 56.701183 -390.063164) (xy 56.720474 -390.017888) (xy 56.746777 -389.976292)
			(xy 56.779412 -389.939455) (xy 56.817533 -389.90833) (xy 56.860154 -389.883723) (xy 56.90617 -389.866271)
			(xy 56.954389 -389.856427) (xy 57.003564 -389.854446) (xy 57.052419 -389.860378) (xy 57.09969 -389.87407)
			(xy 57.144152 -389.895168) (xy 57.184655 -389.923124) (xy 57.220148 -389.957216) (xy 57.249713 -389.99656)
			(xy 57.272584 -390.040137) (xy 57.288168 -390.086818) (xy 57.296063 -390.135395) (xy 57.296558 -390.160002)
			(xy 57.885596 -390.160002) (xy 57.889556 -390.110948) (xy 57.901333 -390.063164) (xy 57.920624 -390.017888)
			(xy 57.946927 -389.976292) (xy 57.979562 -389.939455) (xy 58.017683 -389.90833) (xy 58.060304 -389.883723)
			(xy 58.10632 -389.866271) (xy 58.154539 -389.856427) (xy 58.203714 -389.854446) (xy 58.252569 -389.860378)
			(xy 58.29984 -389.87407) (xy 58.344302 -389.895168) (xy 58.384805 -389.923124) (xy 58.420298 -389.957216)
			(xy 58.449863 -389.99656) (xy 58.472734 -390.040137) (xy 58.488318 -390.086818) (xy 58.496213 -390.135395)
			(xy 58.496708 -390.160002) (xy 59.085492 -390.160002) (xy 59.089452 -390.110948) (xy 59.101229 -390.063164)
			(xy 59.12052 -390.017888) (xy 59.146823 -389.976292) (xy 59.179458 -389.939455) (xy 59.217579 -389.90833)
			(xy 59.2602 -389.883723) (xy 59.306216 -389.866271) (xy 59.354435 -389.856427) (xy 59.40361 -389.854446)
			(xy 59.452465 -389.860378) (xy 59.499736 -389.87407) (xy 59.544198 -389.895168) (xy 59.584701 -389.923124)
			(xy 59.620194 -389.957216) (xy 59.649759 -389.99656) (xy 59.67263 -390.040137) (xy 59.688214 -390.086818)
			(xy 59.696109 -390.135395) (xy 59.696604 -390.160002) (xy 60.285388 -390.160002) (xy 60.289348 -390.110948)
			(xy 60.301125 -390.063164) (xy 60.320416 -390.017888) (xy 60.346719 -389.976292) (xy 60.379354 -389.939455)
			(xy 60.417475 -389.90833) (xy 60.460096 -389.883723) (xy 60.506112 -389.866271) (xy 60.554331 -389.856427)
			(xy 60.603506 -389.854446) (xy 60.652361 -389.860378) (xy 60.699632 -389.87407) (xy 60.744094 -389.895168)
			(xy 60.784597 -389.923124) (xy 60.82009 -389.957216) (xy 60.849655 -389.99656) (xy 60.872526 -390.040137)
			(xy 60.88811 -390.086818) (xy 60.896005 -390.135395) (xy 60.8965 -390.160002) (xy 61.485538 -390.160002)
			(xy 61.489498 -390.110948) (xy 61.501275 -390.063164) (xy 61.520566 -390.017888) (xy 61.546869 -389.976292)
			(xy 61.579504 -389.939455) (xy 61.617625 -389.90833) (xy 61.660246 -389.883723) (xy 61.706262 -389.866271)
			(xy 61.754481 -389.856427) (xy 61.803656 -389.854446) (xy 61.852511 -389.860378) (xy 61.899782 -389.87407)
			(xy 61.944244 -389.895168) (xy 61.984747 -389.923124) (xy 62.02024 -389.957216) (xy 62.049805 -389.99656)
			(xy 62.072676 -390.040137) (xy 62.08826 -390.086818) (xy 62.096155 -390.135395) (xy 62.09665 -390.160002)
			(xy 62.685434 -390.160002) (xy 62.689394 -390.110948) (xy 62.701171 -390.063164) (xy 62.720462 -390.017888)
			(xy 62.746765 -389.976292) (xy 62.7794 -389.939455) (xy 62.817521 -389.90833) (xy 62.860142 -389.883723)
			(xy 62.906158 -389.866271) (xy 62.954377 -389.856427) (xy 63.003552 -389.854446) (xy 63.052407 -389.860378)
			(xy 63.099678 -389.87407) (xy 63.14414 -389.895168) (xy 63.184643 -389.923124) (xy 63.220136 -389.957216)
			(xy 63.249701 -389.99656) (xy 63.272572 -390.040137) (xy 63.288156 -390.086818) (xy 63.296051 -390.135395)
			(xy 63.296546 -390.160002) (xy 63.885584 -390.160002) (xy 63.889544 -390.110948) (xy 63.901321 -390.063164)
			(xy 63.920612 -390.017888) (xy 63.946915 -389.976292) (xy 63.97955 -389.939455) (xy 64.017671 -389.90833)
			(xy 64.060292 -389.883723) (xy 64.106308 -389.866271) (xy 64.154527 -389.856427) (xy 64.203702 -389.854446)
			(xy 64.252557 -389.860378) (xy 64.299828 -389.87407) (xy 64.34429 -389.895168) (xy 64.384793 -389.923124)
			(xy 64.420286 -389.957216) (xy 64.449851 -389.99656) (xy 64.472722 -390.040137) (xy 64.488306 -390.086818)
			(xy 64.496201 -390.135395) (xy 64.496696 -390.160002) (xy 65.08548 -390.160002) (xy 65.08944 -390.110948)
			(xy 65.101217 -390.063164) (xy 65.120508 -390.017888) (xy 65.146811 -389.976292) (xy 65.179446 -389.939455)
			(xy 65.217567 -389.90833) (xy 65.260188 -389.883723) (xy 65.306204 -389.866271) (xy 65.354423 -389.856427)
			(xy 65.403598 -389.854446) (xy 65.452453 -389.860378) (xy 65.499724 -389.87407) (xy 65.544186 -389.895168)
			(xy 65.584689 -389.923124) (xy 65.620182 -389.957216) (xy 65.649747 -389.99656) (xy 65.672618 -390.040137)
			(xy 65.688202 -390.086818) (xy 65.696097 -390.135395) (xy 65.696592 -390.160002) (xy 65.696097 -390.184609)
			(xy 65.695873 -390.185989) (xy 66.41516 -390.185989) (xy 66.41516 -390.134015) (xy 66.42329 -390.08268)
			(xy 66.439351 -390.03325) (xy 66.462947 -389.98694) (xy 66.493497 -389.944892) (xy 66.530248 -389.908141)
			(xy 66.572296 -389.877591) (xy 66.618606 -389.853995) (xy 66.668036 -389.837934) (xy 66.719371 -389.829804)
			(xy 66.771345 -389.829804) (xy 66.82268 -389.837934) (xy 66.87211 -389.853995) (xy 66.91842 -389.877591)
			(xy 66.960468 -389.908141) (xy 66.997219 -389.944892) (xy 67.027769 -389.98694) (xy 67.051365 -390.03325)
			(xy 67.067426 -390.08268) (xy 67.075556 -390.134015) (xy 67.076066 -390.160002) (xy 67.075556 -390.185989)
			(xy 67.067426 -390.237324) (xy 67.051365 -390.286754) (xy 67.027769 -390.333064) (xy 66.997219 -390.375112)
			(xy 66.960468 -390.411863) (xy 66.91842 -390.442413) (xy 66.87211 -390.466009) (xy 66.82268 -390.48207)
			(xy 66.771345 -390.4902) (xy 66.719371 -390.4902) (xy 66.668036 -390.48207) (xy 66.618606 -390.466009)
			(xy 66.572296 -390.442413) (xy 66.530248 -390.411863) (xy 66.493497 -390.375112) (xy 66.462947 -390.333064)
			(xy 66.439351 -390.286754) (xy 66.42329 -390.237324) (xy 66.41516 -390.185989) (xy 65.695873 -390.185989)
			(xy 65.688202 -390.233186) (xy 65.672618 -390.279867) (xy 65.649747 -390.323444) (xy 65.620182 -390.362788)
			(xy 65.584689 -390.39688) (xy 65.544186 -390.424836) (xy 65.499724 -390.445934) (xy 65.452453 -390.459626)
			(xy 65.403598 -390.465558) (xy 65.354423 -390.463577) (xy 65.306204 -390.453733) (xy 65.260188 -390.436281)
			(xy 65.217567 -390.411674) (xy 65.179446 -390.380549) (xy 65.146811 -390.343712) (xy 65.120508 -390.302116)
			(xy 65.101217 -390.25684) (xy 65.08944 -390.209056) (xy 65.08548 -390.160002) (xy 64.496696 -390.160002)
			(xy 64.496201 -390.184609) (xy 64.488306 -390.233186) (xy 64.472722 -390.279867) (xy 64.449851 -390.323444)
			(xy 64.420286 -390.362788) (xy 64.384793 -390.39688) (xy 64.34429 -390.424836) (xy 64.299828 -390.445934)
			(xy 64.252557 -390.459626) (xy 64.203702 -390.465558) (xy 64.154527 -390.463577) (xy 64.106308 -390.453733)
			(xy 64.060292 -390.436281) (xy 64.017671 -390.411674) (xy 63.97955 -390.380549) (xy 63.946915 -390.343712)
			(xy 63.920612 -390.302116) (xy 63.901321 -390.25684) (xy 63.889544 -390.209056) (xy 63.885584 -390.160002)
			(xy 63.296546 -390.160002) (xy 63.296051 -390.184609) (xy 63.288156 -390.233186) (xy 63.272572 -390.279867)
			(xy 63.249701 -390.323444) (xy 63.220136 -390.362788) (xy 63.184643 -390.39688) (xy 63.14414 -390.424836)
			(xy 63.099678 -390.445934) (xy 63.052407 -390.459626) (xy 63.003552 -390.465558) (xy 62.954377 -390.463577)
			(xy 62.906158 -390.453733) (xy 62.860142 -390.436281) (xy 62.817521 -390.411674) (xy 62.7794 -390.380549)
			(xy 62.746765 -390.343712) (xy 62.720462 -390.302116) (xy 62.701171 -390.25684) (xy 62.689394 -390.209056)
			(xy 62.685434 -390.160002) (xy 62.09665 -390.160002) (xy 62.096155 -390.184609) (xy 62.08826 -390.233186)
			(xy 62.072676 -390.279867) (xy 62.049805 -390.323444) (xy 62.02024 -390.362788) (xy 61.984747 -390.39688)
			(xy 61.944244 -390.424836) (xy 61.899782 -390.445934) (xy 61.852511 -390.459626) (xy 61.803656 -390.465558)
			(xy 61.754481 -390.463577) (xy 61.706262 -390.453733) (xy 61.660246 -390.436281) (xy 61.617625 -390.411674)
			(xy 61.579504 -390.380549) (xy 61.546869 -390.343712) (xy 61.520566 -390.302116) (xy 61.501275 -390.25684)
			(xy 61.489498 -390.209056) (xy 61.485538 -390.160002) (xy 60.8965 -390.160002) (xy 60.896005 -390.184609)
			(xy 60.88811 -390.233186) (xy 60.872526 -390.279867) (xy 60.849655 -390.323444) (xy 60.82009 -390.362788)
			(xy 60.784597 -390.39688) (xy 60.744094 -390.424836) (xy 60.699632 -390.445934) (xy 60.652361 -390.459626)
			(xy 60.603506 -390.465558) (xy 60.554331 -390.463577) (xy 60.506112 -390.453733) (xy 60.460096 -390.436281)
			(xy 60.417475 -390.411674) (xy 60.379354 -390.380549) (xy 60.346719 -390.343712) (xy 60.320416 -390.302116)
			(xy 60.301125 -390.25684) (xy 60.289348 -390.209056) (xy 60.285388 -390.160002) (xy 59.696604 -390.160002)
			(xy 59.696109 -390.184609) (xy 59.688214 -390.233186) (xy 59.67263 -390.279867) (xy 59.649759 -390.323444)
			(xy 59.620194 -390.362788) (xy 59.584701 -390.39688) (xy 59.544198 -390.424836) (xy 59.499736 -390.445934)
			(xy 59.452465 -390.459626) (xy 59.40361 -390.465558) (xy 59.354435 -390.463577) (xy 59.306216 -390.453733)
			(xy 59.2602 -390.436281) (xy 59.217579 -390.411674) (xy 59.179458 -390.380549) (xy 59.146823 -390.343712)
			(xy 59.12052 -390.302116) (xy 59.101229 -390.25684) (xy 59.089452 -390.209056) (xy 59.085492 -390.160002)
			(xy 58.496708 -390.160002) (xy 58.496213 -390.184609) (xy 58.488318 -390.233186) (xy 58.472734 -390.279867)
			(xy 58.449863 -390.323444) (xy 58.420298 -390.362788) (xy 58.384805 -390.39688) (xy 58.344302 -390.424836)
			(xy 58.29984 -390.445934) (xy 58.252569 -390.459626) (xy 58.203714 -390.465558) (xy 58.154539 -390.463577)
			(xy 58.10632 -390.453733) (xy 58.060304 -390.436281) (xy 58.017683 -390.411674) (xy 57.979562 -390.380549)
			(xy 57.946927 -390.343712) (xy 57.920624 -390.302116) (xy 57.901333 -390.25684) (xy 57.889556 -390.209056)
			(xy 57.885596 -390.160002) (xy 57.296558 -390.160002) (xy 57.296063 -390.184609) (xy 57.288168 -390.233186)
			(xy 57.272584 -390.279867) (xy 57.249713 -390.323444) (xy 57.220148 -390.362788) (xy 57.184655 -390.39688)
			(xy 57.144152 -390.424836) (xy 57.09969 -390.445934) (xy 57.052419 -390.459626) (xy 57.003564 -390.465558)
			(xy 56.954389 -390.463577) (xy 56.90617 -390.453733) (xy 56.860154 -390.436281) (xy 56.817533 -390.411674)
			(xy 56.779412 -390.380549) (xy 56.746777 -390.343712) (xy 56.720474 -390.302116) (xy 56.701183 -390.25684)
			(xy 56.689406 -390.209056) (xy 56.685446 -390.160002) (xy 56.096662 -390.160002) (xy 56.096167 -390.184609)
			(xy 56.088272 -390.233186) (xy 56.072688 -390.279867) (xy 56.049817 -390.323444) (xy 56.020252 -390.362788)
			(xy 55.984759 -390.39688) (xy 55.944256 -390.424836) (xy 55.899794 -390.445934) (xy 55.852523 -390.459626)
			(xy 55.803668 -390.465558) (xy 55.754493 -390.463577) (xy 55.706274 -390.453733) (xy 55.660258 -390.436281)
			(xy 55.617637 -390.411674) (xy 55.579516 -390.380549) (xy 55.546881 -390.343712) (xy 55.520578 -390.302116)
			(xy 55.501287 -390.25684) (xy 55.48951 -390.209056) (xy 55.48555 -390.160002) (xy 54.896512 -390.160002)
			(xy 54.896017 -390.184609) (xy 54.888122 -390.233186) (xy 54.872538 -390.279867) (xy 54.849667 -390.323444)
			(xy 54.820102 -390.362788) (xy 54.784609 -390.39688) (xy 54.744106 -390.424836) (xy 54.699644 -390.445934)
			(xy 54.652373 -390.459626) (xy 54.603518 -390.465558) (xy 54.554343 -390.463577) (xy 54.506124 -390.453733)
			(xy 54.460108 -390.436281) (xy 54.417487 -390.411674) (xy 54.379366 -390.380549) (xy 54.346731 -390.343712)
			(xy 54.320428 -390.302116) (xy 54.301137 -390.25684) (xy 54.28936 -390.209056) (xy 54.2854 -390.160002)
			(xy 53.696616 -390.160002) (xy 53.696121 -390.184609) (xy 53.688226 -390.233186) (xy 53.672642 -390.279867)
			(xy 53.649771 -390.323444) (xy 53.620206 -390.362788) (xy 53.584713 -390.39688) (xy 53.54421 -390.424836)
			(xy 53.499748 -390.445934) (xy 53.452477 -390.459626) (xy 53.403622 -390.465558) (xy 53.354447 -390.463577)
			(xy 53.306228 -390.453733) (xy 53.260212 -390.436281) (xy 53.217591 -390.411674) (xy 53.17947 -390.380549)
			(xy 53.146835 -390.343712) (xy 53.120532 -390.302116) (xy 53.101241 -390.25684) (xy 53.089464 -390.209056)
			(xy 53.085504 -390.160002) (xy 52.49672 -390.160002) (xy 52.496225 -390.184609) (xy 52.48833 -390.233186)
			(xy 52.472746 -390.279867) (xy 52.449875 -390.323444) (xy 52.42031 -390.362788) (xy 52.384817 -390.39688)
			(xy 52.344314 -390.424836) (xy 52.299852 -390.445934) (xy 52.252581 -390.459626) (xy 52.203726 -390.465558)
			(xy 52.154551 -390.463577) (xy 52.106332 -390.453733) (xy 52.060316 -390.436281) (xy 52.017695 -390.411674)
			(xy 51.979574 -390.380549) (xy 51.946939 -390.343712) (xy 51.920636 -390.302116) (xy 51.901345 -390.25684)
			(xy 51.889568 -390.209056) (xy 51.885608 -390.160002) (xy 51.29657 -390.160002) (xy 51.296075 -390.184609)
			(xy 51.28818 -390.233186) (xy 51.272596 -390.279867) (xy 51.249725 -390.323444) (xy 51.22016 -390.362788)
			(xy 51.184667 -390.39688) (xy 51.144164 -390.424836) (xy 51.099702 -390.445934) (xy 51.052431 -390.459626)
			(xy 51.003576 -390.465558) (xy 50.954401 -390.463577) (xy 50.906182 -390.453733) (xy 50.860166 -390.436281)
			(xy 50.817545 -390.411674) (xy 50.779424 -390.380549) (xy 50.746789 -390.343712) (xy 50.720486 -390.302116)
			(xy 50.701195 -390.25684) (xy 50.689418 -390.209056) (xy 50.685458 -390.160002) (xy 50.096674 -390.160002)
			(xy 50.096179 -390.184609) (xy 50.088284 -390.233186) (xy 50.0727 -390.279867) (xy 50.049829 -390.323444)
			(xy 50.020264 -390.362788) (xy 49.984771 -390.39688) (xy 49.944268 -390.424836) (xy 49.899806 -390.445934)
			(xy 49.852535 -390.459626) (xy 49.80368 -390.465558) (xy 49.754505 -390.463577) (xy 49.706286 -390.453733)
			(xy 49.66027 -390.436281) (xy 49.617649 -390.411674) (xy 49.579528 -390.380549) (xy 49.546893 -390.343712)
			(xy 49.52059 -390.302116) (xy 49.501299 -390.25684) (xy 49.489522 -390.209056) (xy 49.485562 -390.160002)
			(xy 48.896524 -390.160002) (xy 48.896029 -390.184609) (xy 48.888134 -390.233186) (xy 48.87255 -390.279867)
			(xy 48.849679 -390.323444) (xy 48.820114 -390.362788) (xy 48.784621 -390.39688) (xy 48.744118 -390.424836)
			(xy 48.699656 -390.445934) (xy 48.652385 -390.459626) (xy 48.60353 -390.465558) (xy 48.554355 -390.463577)
			(xy 48.506136 -390.453733) (xy 48.46012 -390.436281) (xy 48.417499 -390.411674) (xy 48.379378 -390.380549)
			(xy 48.346743 -390.343712) (xy 48.32044 -390.302116) (xy 48.301149 -390.25684) (xy 48.289372 -390.209056)
			(xy 48.285412 -390.160002) (xy 47.696374 -390.160002) (xy 47.695879 -390.184609) (xy 47.687984 -390.233186)
			(xy 47.6724 -390.279867) (xy 47.649529 -390.323444) (xy 47.619964 -390.362788) (xy 47.584471 -390.39688)
			(xy 47.543968 -390.424836) (xy 47.499506 -390.445934) (xy 47.452235 -390.459626) (xy 47.40338 -390.465558)
			(xy 47.354205 -390.463577) (xy 47.305986 -390.453733) (xy 47.25997 -390.436281) (xy 47.217349 -390.411674)
			(xy 47.179228 -390.380549) (xy 47.146593 -390.343712) (xy 47.12029 -390.302116) (xy 47.100999 -390.25684)
			(xy 47.089222 -390.209056) (xy 47.085262 -390.160002) (xy 45.410427 -390.160002) (xy 45.404318 -390.181185)
			(xy 45.385319 -390.223591) (xy 45.360572 -390.262921) (xy 45.345858 -390.280906) (xy 45.340016 -390.287764)
			(xy 45.333666 -390.304782) (xy 45.333666 -390.388602) (xy 45.340016 -390.40562) (xy 45.345858 -390.412478)
			(xy 45.360564 -390.430469) (xy 45.385314 -390.469796) (xy 45.404313 -390.5122) (xy 45.417187 -390.556848)
			(xy 45.423682 -390.602859) (xy 45.42409 -390.626092) (xy 45.423607 -390.652081) (xy 45.415477 -390.70342)
			(xy 45.399415 -390.752854) (xy 45.375818 -390.799167) (xy 45.345265 -390.841218) (xy 45.308511 -390.877972)
			(xy 45.266459 -390.908523) (xy 45.220145 -390.932119) (xy 45.17071 -390.948179) (xy 45.119371 -390.956308)
			(xy 45.093382 -390.9568) (xy 45.076694 -390.956617) (xy 45.043484 -390.953308) (xy 45.027088 -390.950196)
			(xy 45.015658 -390.94791) (xy 44.993814 -390.953244) (xy 44.923964 -391.010394) (xy 44.915558 -391.018007)
			(xy 44.905785 -391.038441) (xy 44.905168 -391.049764) (xy 44.905168 -391.438892) (xy 44.905589 -391.448964)
			(xy 44.913298 -391.467573) (xy 44.920154 -391.47496) (xy 45.247131 -391.801937) (xy 46.164756 -391.801937)
			(xy 46.164756 -391.749963) (xy 46.172886 -391.698628) (xy 46.188947 -391.649198) (xy 46.212543 -391.602888)
			(xy 46.243093 -391.56084) (xy 46.279844 -391.524089) (xy 46.321892 -391.493539) (xy 46.368202 -391.469943)
			(xy 46.417632 -391.453882) (xy 46.468967 -391.445752) (xy 46.520941 -391.445752) (xy 46.572276 -391.453882)
			(xy 46.621706 -391.469943) (xy 46.668016 -391.493539) (xy 46.710064 -391.524089) (xy 46.746815 -391.56084)
			(xy 46.777365 -391.602888) (xy 46.800961 -391.649198) (xy 46.817022 -391.698628) (xy 46.825152 -391.749963)
			(xy 46.825662 -391.77595) (xy 46.825152 -391.801937) (xy 46.817022 -391.853272) (xy 46.800961 -391.902702)
			(xy 46.777365 -391.949012) (xy 46.746815 -391.99106) (xy 46.710064 -392.027811) (xy 46.668016 -392.058361)
			(xy 46.621706 -392.081957) (xy 46.572276 -392.098018) (xy 46.520941 -392.106148) (xy 46.468967 -392.106148)
			(xy 46.417632 -392.098018) (xy 46.368202 -392.081957) (xy 46.321892 -392.058361) (xy 46.279844 -392.027811)
			(xy 46.243093 -391.99106) (xy 46.212543 -391.949012) (xy 46.188947 -391.902702) (xy 46.172886 -391.853272)
			(xy 46.164756 -391.801937) (xy 45.247131 -391.801937) (xy 46.01845 -392.573256) (xy 46.025849 -392.580099)
			(xy 46.044448 -392.587822) (xy 46.054518 -392.588242)
		)
		(stroke
			(width 0)
			(type solid)
		)
		(fill yes)
		(layer "In2.Cu")
		(net "NCF_CPU1_P0_GND")
	)
	(gr_poly
		(pts
			(xy 182.031386 -366.871504) (xy 182.041375 -366.870969) (xy 182.059811 -366.86326) (xy 182.0672 -366.856518)
			(xy 182.39613 -366.527588) (xy 182.404004 -366.519968) (xy 182.404258 -366.51946) (xy 182.55234 -366.371378)
			(xy 182.563008 -366.361218) (xy 182.563262 -366.36071) (xy 182.733442 -366.190784) (xy 182.740785 -366.183971)
			(xy 182.759249 -366.17624) (xy 182.769256 -366.175798) (xy 183.012588 -366.175798) (xy 183.025034 -366.175544)
			(xy 190.989458 -366.175544) (xy 190.997758 -366.174675) (xy 191.013184 -366.168331) (xy 191.019684 -366.163098)
			(xy 191.343788 -365.838994) (xy 191.352223 -365.829542) (xy 191.359423 -365.805288) (xy 191.357504 -365.792766)
			(xy 191.355726 -365.783876) (xy 191.35344 -365.771684) (xy 191.337946 -365.751872) (xy 191.326008 -365.746792)
			(xy 191.286697 -365.729198) (xy 191.211354 -365.687462) (xy 191.140399 -365.638638) (xy 191.074495 -365.583184)
			(xy 191.01426 -365.521619) (xy 190.960257 -365.454521) (xy 190.912994 -365.382516) (xy 190.872912 -365.306281)
			(xy 190.840386 -365.226527) (xy 190.815722 -365.144004) (xy 190.79915 -365.059483) (xy 190.790825 -364.973755)
			(xy 190.790322 -364.93069) (xy 190.790783 -364.889588) (xy 190.798369 -364.807734) (xy 190.813475 -364.726929)
			(xy 190.835972 -364.647863) (xy 190.865669 -364.571209) (xy 190.902312 -364.497623) (xy 190.945589 -364.427732)
			(xy 190.99513 -364.362133) (xy 191.050512 -364.301384) (xy 191.111263 -364.246004) (xy 191.176865 -364.196466)
			(xy 191.246758 -364.153193) (xy 191.320346 -364.116553) (xy 191.397001 -364.08686) (xy 191.476068 -364.064366)
			(xy 191.556873 -364.049263) (xy 191.638728 -364.041681) (xy 191.67983 -364.041182) (xy 191.722895 -364.041689)
			(xy 191.80862 -364.050017) (xy 191.89314 -364.066592) (xy 191.975661 -364.091258) (xy 192.055412 -364.123785)
			(xy 192.131646 -364.163867) (xy 192.203649 -364.211131) (xy 192.270746 -364.265133) (xy 192.33231 -364.325367)
			(xy 192.387763 -364.391269) (xy 192.436587 -364.462223) (xy 192.478324 -364.537564) (xy 192.495932 -364.576868)
			(xy 192.501012 -364.588806) (xy 192.520824 -364.6043) (xy 192.533016 -364.606586) (xy 192.55486 -364.611158)
			(xy 192.565633 -364.612763) (xy 192.586822 -364.607807) (xy 192.604103 -364.594581) (xy 192.609724 -364.58525)
			(xy 192.620646 -364.565184) (xy 192.622409 -364.561932) (xy 192.626747 -364.55594) (xy 192.629282 -364.553246)
			(xy 203.359004 -353.823778) (xy 203.364805 -353.816564) (xy 203.371303 -353.799246) (xy 203.371704 -353.789996)
			(xy 203.371704 -350.269048) (xy 203.371958 -350.25203) (xy 203.371958 -350.01327) (xy 203.372502 -350.003286)
			(xy 203.38023 -349.984868) (xy 203.386944 -349.977456) (xy 203.5556 -349.808546) (xy 203.556108 -349.808038)
			(xy 203.556616 -349.80753) (xy 203.567538 -349.796354) (xy 205.077822 -348.28607) (xy 205.086191 -348.276804)
			(xy 205.093525 -348.252968) (xy 205.091792 -348.240604) (xy 205.073758 -348.145608) (xy 205.05801 -348.12605)
			(xy 205.046326 -348.12097) (xy 205.021277 -348.109589) (xy 204.974461 -348.080687) (xy 204.932281 -348.045362)
			(xy 204.89561 -348.004347) (xy 204.865209 -347.95849) (xy 204.841707 -347.908744) (xy 204.825593 -347.856138)
			(xy 204.817199 -347.801764) (xy 204.816456 -347.77426) (xy 204.816456 -347.770958) (xy 204.816589 -347.756614)
			(xy 204.818752 -347.728009) (xy 204.820774 -347.713808) (xy 204.820774 -347.713554) (xy 204.821735 -347.70486)
			(xy 204.818405 -347.687701) (xy 204.809502 -347.67266) (xy 204.802994 -347.666818) (xy 204.726032 -347.60281)
			(xy 204.69987 -347.597984) (xy 204.687424 -347.602302) (xy 204.657539 -347.611946) (xy 204.595628 -347.622419)
			(xy 204.564234 -347.62313) (xy 204.557884 -347.62313) (xy 204.531031 -347.622316) (xy 204.477945 -347.614069)
			(xy 204.426543 -347.598445) (xy 204.377847 -347.575755) (xy 204.332821 -347.546449) (xy 204.312266 -347.52915)
			(xy 204.305154 -347.523054) (xy 204.28839 -347.516704) (xy 204.202538 -347.516704) (xy 204.185774 -347.523054)
			(xy 204.178662 -347.52915) (xy 204.157731 -347.546792) (xy 204.111765 -347.576517) (xy 204.062018 -347.599358)
			(xy 204.009514 -347.614846) (xy 203.955334 -347.62266) (xy 203.927964 -347.62313) (xy 203.900713 -347.622642)
			(xy 203.846766 -347.614881) (xy 203.794472 -347.599521) (xy 203.744897 -347.576877) (xy 203.699048 -347.547408)
			(xy 203.65786 -347.511714) (xy 203.62217 -347.470523) (xy 203.592706 -347.424671) (xy 203.570066 -347.375094)
			(xy 203.554712 -347.322799) (xy 203.546956 -347.268851) (xy 203.546956 -347.214349) (xy 203.554712 -347.160401)
			(xy 203.570066 -347.108106) (xy 203.592706 -347.058529) (xy 203.62217 -347.012677) (xy 203.65786 -346.971486)
			(xy 203.699048 -346.935792) (xy 203.744897 -346.906323) (xy 203.794472 -346.883679) (xy 203.846766 -346.868319)
			(xy 203.900713 -346.860558) (xy 203.927964 -346.860114) (xy 203.955332 -346.86059) (xy 204.009506 -346.868423)
			(xy 204.062004 -346.883917) (xy 204.111748 -346.906756) (xy 204.157718 -346.93647) (xy 204.178662 -346.954094)
			(xy 204.185774 -346.96019) (xy 204.202538 -346.96654) (xy 204.28839 -346.96654) (xy 204.305154 -346.96019)
			(xy 204.312266 -346.954094) (xy 204.333197 -346.93645) (xy 204.379163 -346.906721) (xy 204.428909 -346.883873)
			(xy 204.481413 -346.868379) (xy 204.535593 -346.860556) (xy 204.562964 -346.860114) (xy 204.589907 -346.860587)
			(xy 204.643257 -346.868177) (xy 204.695011 -346.883184) (xy 204.744146 -346.90531) (xy 204.76718 -346.919296)
			(xy 204.771177 -346.921772) (xy 204.77987 -346.925355) (xy 204.784452 -346.926408) (xy 204.792834 -346.927932)
			(xy 204.869288 -346.915232) (xy 204.878204 -346.913362) (xy 204.893964 -346.904254) (xy 204.900022 -346.897452)
			(xy 204.90053 -346.896944) (xy 204.900784 -346.89669) (xy 204.919003 -346.874894) (xy 204.960795 -346.836419)
			(xy 205.007831 -346.804567) (xy 205.059071 -346.780043) (xy 205.113381 -346.763389) (xy 205.169561 -346.754974)
			(xy 205.197964 -346.75445) (xy 205.225218 -346.754933) (xy 205.279172 -346.762685) (xy 205.331473 -346.778037)
			(xy 205.381058 -346.800676) (xy 205.426916 -346.83014) (xy 205.468114 -346.865831) (xy 205.503813 -346.907022)
			(xy 205.533287 -346.952874) (xy 205.555936 -347.002453) (xy 205.571298 -347.054752) (xy 205.579061 -347.108704)
			(xy 205.579472 -347.135958) (xy 205.578996 -347.163326) (xy 205.571164 -347.2175) (xy 205.55567 -347.269998)
			(xy 205.532831 -347.319743) (xy 205.503117 -347.365713) (xy 205.485492 -347.386656) (xy 205.479396 -347.393768)
			(xy 205.473046 -347.410532) (xy 205.473046 -347.496384) (xy 205.479396 -347.513148) (xy 205.485492 -347.52026)
			(xy 205.504411 -347.542787) (xy 205.535791 -347.592544) (xy 205.547976 -347.61932) (xy 205.553056 -347.631004)
			(xy 205.572614 -347.646752) (xy 205.66761 -347.664786) (xy 205.679979 -347.666545) (xy 205.703834 -347.659222)
			(xy 205.713076 -347.650816) (xy 206.942182 -346.42171) (xy 206.948996 -346.414366) (xy 206.956735 -346.395904)
			(xy 206.957168 -346.385896) (xy 206.957168 -320.324988) (xy 206.956691 -320.31465) (xy 206.948575 -320.295633)
			(xy 206.94142 -320.288158) (xy 206.919322 -320.267076) (xy 206.912024 -320.260632) (xy 206.893995 -320.253327)
			(xy 206.88427 -320.252852) (xy 158.189676 -320.252852) (xy 158.179609 -320.253281) (xy 158.161016 -320.261007)
			(xy 158.153608 -320.267838) (xy 157.561534 -320.859912) (xy 157.554686 -320.86731) (xy 157.54695 -320.885908)
			(xy 157.546548 -320.89598) (xy 157.546548 -321.80276) (xy 157.546802 -321.803522) (xy 157.547108 -321.831297)
			(xy 157.540659 -321.886466) (xy 157.526285 -321.940119) (xy 157.504289 -321.991123) (xy 157.475136 -322.038402)
			(xy 157.43944 -322.080958) (xy 157.397956 -322.117894) (xy 157.351558 -322.14843) (xy 157.301226 -322.171922)
			(xy 157.248021 -322.187874) (xy 157.193066 -322.195949) (xy 157.165294 -322.19646) (xy 157.148314 -322.19632)
			(xy 157.114482 -322.193396) (xy 157.09773 -322.190618) (xy 157.097476 -322.190618) (xy 157.086426 -322.189295)
			(xy 157.064967 -322.195101) (xy 157.056074 -322.201794) (xy 156.996638 -322.251832) (xy 156.988504 -322.259423)
			(xy 156.979151 -322.279582) (xy 156.978604 -322.290694) (xy 156.978604 -323.798692) (xy 156.978182 -323.808763)
			(xy 156.97047 -323.82737) (xy 156.963618 -323.83476) (xy 156.949648 -323.84873) (xy 156.942807 -323.856098)
			(xy 156.935061 -323.874635) (xy 156.935053 -323.894725) (xy 156.942784 -323.913268) (xy 156.949648 -323.920612)
			(xy 156.958792 -323.929756) (xy 156.982668 -323.937122) (xy 156.995368 -323.934582) (xy 157.037401 -323.926645)
			(xy 157.122522 -323.918124) (xy 157.165294 -323.917564) (xy 157.207716 -323.918078) (xy 157.292149 -323.926413)
			(xy 157.375358 -323.942986) (xy 157.456542 -323.967635) (xy 157.534919 -324.000124) (xy 157.609733 -324.040139)
			(xy 157.680264 -324.087295) (xy 157.745834 -324.141139) (xy 157.776164 -324.170802) (xy 157.98927 -324.383908)
			(xy 160.93135 -324.383908) (xy 160.935421 -324.328286) (xy 160.947547 -324.273849) (xy 160.96747 -324.221758)
			(xy 160.994766 -324.173123) (xy 161.028852 -324.12898) (xy 161.069001 -324.090271) (xy 161.114359 -324.05782)
			(xy 161.163959 -324.032319) (xy 161.216743 -324.014312) (xy 161.271586 -324.004182) (xy 161.32732 -324.002145)
			(xy 161.382757 -324.008245) (xy 161.436714 -324.022351) (xy 161.488043 -324.044163) (xy 161.535649 -324.073217)
			(xy 161.578517 -324.108892) (xy 161.615734 -324.150429) (xy 161.646507 -324.196942) (xy 161.670179 -324.247439)
			(xy 161.686247 -324.300846) (xy 161.694367 -324.356022) (xy 161.694876 -324.383908) (xy 161.694367 -324.411794)
			(xy 161.686247 -324.46697) (xy 161.670179 -324.520377) (xy 161.646507 -324.570874) (xy 161.615734 -324.617387)
			(xy 161.578517 -324.658924) (xy 161.535649 -324.694599) (xy 161.488043 -324.723653) (xy 161.436714 -324.745465)
			(xy 161.382757 -324.759571) (xy 161.32732 -324.765671) (xy 161.271586 -324.763634) (xy 161.216743 -324.753504)
			(xy 161.163959 -324.735497) (xy 161.114359 -324.709996) (xy 161.069001 -324.677545) (xy 161.028852 -324.638836)
			(xy 160.994766 -324.594693) (xy 160.96747 -324.546058) (xy 160.947547 -324.493967) (xy 160.935421 -324.43953)
			(xy 160.93135 -324.383908) (xy 157.98927 -324.383908) (xy 159.580072 -325.97471) (xy 159.609688 -326.005075)
			(xy 159.66349 -326.070657) (xy 159.710607 -326.141194) (xy 159.750587 -326.216008) (xy 159.783045 -326.294379)
			(xy 159.807669 -326.375553) (xy 159.824222 -326.458749) (xy 159.832544 -326.543167) (xy 159.833056 -326.58558)
			(xy 159.833056 -328.20864) (xy 199.140062 -328.20864) (xy 199.144133 -328.153018) (xy 199.156259 -328.098581)
			(xy 199.176182 -328.04649) (xy 199.203478 -327.997855) (xy 199.237564 -327.953712) (xy 199.277713 -327.915003)
			(xy 199.323071 -327.882552) (xy 199.372671 -327.857051) (xy 199.425455 -327.839044) (xy 199.480298 -327.828914)
			(xy 199.536032 -327.826877) (xy 199.591469 -327.832977) (xy 199.645426 -327.847083) (xy 199.696755 -327.868895)
			(xy 199.744361 -327.897949) (xy 199.787229 -327.933624) (xy 199.824446 -327.975161) (xy 199.855219 -328.021674)
			(xy 199.878891 -328.072171) (xy 199.894959 -328.125578) (xy 199.903079 -328.180754) (xy 199.903588 -328.20864)
			(xy 200.029062 -328.20864) (xy 200.033133 -328.153018) (xy 200.045259 -328.098581) (xy 200.065182 -328.04649)
			(xy 200.092478 -327.997855) (xy 200.126564 -327.953712) (xy 200.166713 -327.915003) (xy 200.212071 -327.882552)
			(xy 200.261671 -327.857051) (xy 200.314455 -327.839044) (xy 200.369298 -327.828914) (xy 200.425032 -327.826877)
			(xy 200.480469 -327.832977) (xy 200.534426 -327.847083) (xy 200.585755 -327.868895) (xy 200.633361 -327.897949)
			(xy 200.676229 -327.933624) (xy 200.713446 -327.975161) (xy 200.744219 -328.021674) (xy 200.767891 -328.072171)
			(xy 200.783959 -328.125578) (xy 200.792079 -328.180754) (xy 200.792588 -328.20864) (xy 200.918062 -328.20864)
			(xy 200.922133 -328.153018) (xy 200.934259 -328.098581) (xy 200.954182 -328.04649) (xy 200.981478 -327.997855)
			(xy 201.015564 -327.953712) (xy 201.055713 -327.915003) (xy 201.101071 -327.882552) (xy 201.150671 -327.857051)
			(xy 201.203455 -327.839044) (xy 201.258298 -327.828914) (xy 201.314032 -327.826877) (xy 201.369469 -327.832977)
			(xy 201.423426 -327.847083) (xy 201.474755 -327.868895) (xy 201.522361 -327.897949) (xy 201.565229 -327.933624)
			(xy 201.602446 -327.975161) (xy 201.633219 -328.021674) (xy 201.656891 -328.072171) (xy 201.672959 -328.125578)
			(xy 201.681079 -328.180754) (xy 201.681588 -328.20864) (xy 201.807062 -328.20864) (xy 201.811133 -328.153018)
			(xy 201.823259 -328.098581) (xy 201.843182 -328.04649) (xy 201.870478 -327.997855) (xy 201.904564 -327.953712)
			(xy 201.944713 -327.915003) (xy 201.990071 -327.882552) (xy 202.039671 -327.857051) (xy 202.092455 -327.839044)
			(xy 202.147298 -327.828914) (xy 202.203032 -327.826877) (xy 202.258469 -327.832977) (xy 202.312426 -327.847083)
			(xy 202.363755 -327.868895) (xy 202.411361 -327.897949) (xy 202.454229 -327.933624) (xy 202.491446 -327.975161)
			(xy 202.522219 -328.021674) (xy 202.545891 -328.072171) (xy 202.561959 -328.125578) (xy 202.570079 -328.180754)
			(xy 202.570588 -328.20864) (xy 202.570079 -328.236526) (xy 202.561959 -328.291702) (xy 202.545891 -328.345109)
			(xy 202.522219 -328.395606) (xy 202.491446 -328.442119) (xy 202.454229 -328.483656) (xy 202.411361 -328.519331)
			(xy 202.363755 -328.548385) (xy 202.312426 -328.570197) (xy 202.258469 -328.584303) (xy 202.203032 -328.590403)
			(xy 202.147298 -328.588366) (xy 202.092455 -328.578236) (xy 202.039671 -328.560229) (xy 201.990071 -328.534728)
			(xy 201.944713 -328.502277) (xy 201.904564 -328.463568) (xy 201.870478 -328.419425) (xy 201.843182 -328.37079)
			(xy 201.823259 -328.318699) (xy 201.811133 -328.264262) (xy 201.807062 -328.20864) (xy 201.681588 -328.20864)
			(xy 201.681079 -328.236526) (xy 201.672959 -328.291702) (xy 201.656891 -328.345109) (xy 201.633219 -328.395606)
			(xy 201.602446 -328.442119) (xy 201.565229 -328.483656) (xy 201.522361 -328.519331) (xy 201.474755 -328.548385)
			(xy 201.423426 -328.570197) (xy 201.369469 -328.584303) (xy 201.314032 -328.590403) (xy 201.258298 -328.588366)
			(xy 201.203455 -328.578236) (xy 201.150671 -328.560229) (xy 201.101071 -328.534728) (xy 201.055713 -328.502277)
			(xy 201.015564 -328.463568) (xy 200.981478 -328.419425) (xy 200.954182 -328.37079) (xy 200.934259 -328.318699)
			(xy 200.922133 -328.264262) (xy 200.918062 -328.20864) (xy 200.792588 -328.20864) (xy 200.792079 -328.236526)
			(xy 200.783959 -328.291702) (xy 200.767891 -328.345109) (xy 200.744219 -328.395606) (xy 200.713446 -328.442119)
			(xy 200.676229 -328.483656) (xy 200.633361 -328.519331) (xy 200.585755 -328.548385) (xy 200.534426 -328.570197)
			(xy 200.480469 -328.584303) (xy 200.425032 -328.590403) (xy 200.369298 -328.588366) (xy 200.314455 -328.578236)
			(xy 200.261671 -328.560229) (xy 200.212071 -328.534728) (xy 200.166713 -328.502277) (xy 200.126564 -328.463568)
			(xy 200.092478 -328.419425) (xy 200.065182 -328.37079) (xy 200.045259 -328.318699) (xy 200.033133 -328.264262)
			(xy 200.029062 -328.20864) (xy 199.903588 -328.20864) (xy 199.903079 -328.236526) (xy 199.894959 -328.291702)
			(xy 199.878891 -328.345109) (xy 199.855219 -328.395606) (xy 199.824446 -328.442119) (xy 199.787229 -328.483656)
			(xy 199.744361 -328.519331) (xy 199.696755 -328.548385) (xy 199.645426 -328.570197) (xy 199.591469 -328.584303)
			(xy 199.536032 -328.590403) (xy 199.480298 -328.588366) (xy 199.425455 -328.578236) (xy 199.372671 -328.560229)
			(xy 199.323071 -328.534728) (xy 199.277713 -328.502277) (xy 199.237564 -328.463568) (xy 199.203478 -328.419425)
			(xy 199.176182 -328.37079) (xy 199.156259 -328.318699) (xy 199.144133 -328.264262) (xy 199.140062 -328.20864)
			(xy 159.833056 -328.20864) (xy 159.833056 -329.277055) (xy 197.238541 -329.277055) (xy 197.238541 -329.222545)
			(xy 197.246299 -329.16859) (xy 197.261656 -329.116289) (xy 197.284301 -329.066706) (xy 197.313772 -329.02085)
			(xy 197.349469 -328.979655) (xy 197.390666 -328.94396) (xy 197.436523 -328.914492) (xy 197.486108 -328.891849)
			(xy 197.53841 -328.876494) (xy 197.592365 -328.86874) (xy 197.61962 -328.868278) (xy 197.646992 -328.868713)
			(xy 197.701173 -328.876536) (xy 197.753677 -328.892031) (xy 197.803423 -328.91488) (xy 197.849388 -328.944613)
			(xy 197.870318 -328.962258) (xy 197.87743 -328.968354) (xy 197.894448 -328.974704) (xy 197.979792 -328.974704)
			(xy 197.99681 -328.968354) (xy 198.003922 -328.962258) (xy 198.024867 -328.944635) (xy 198.070837 -328.914922)
			(xy 198.120581 -328.892084) (xy 198.173079 -328.876589) (xy 198.227252 -328.868755) (xy 198.25462 -328.868278)
			(xy 198.282153 -328.868754) (xy 198.336646 -328.876679) (xy 198.389435 -328.892348) (xy 198.439428 -328.915436)
			(xy 198.485586 -328.945463) (xy 198.506588 -328.963274) (xy 198.514716 -328.970386) (xy 198.534274 -328.976736)
			(xy 198.629016 -328.9681) (xy 198.64705 -328.958448) (xy 198.653654 -328.950066) (xy 198.671814 -328.927811)
			(xy 198.713736 -328.888544) (xy 198.761072 -328.856009) (xy 198.812754 -328.830942) (xy 198.86761 -328.813909)
			(xy 198.9244 -328.805297) (xy 198.95312 -328.804778) (xy 198.980371 -328.805259) (xy 199.034318 -328.813018)
			(xy 199.086612 -328.828375) (xy 199.136189 -328.851017) (xy 199.182038 -328.880484) (xy 199.223228 -328.916176)
			(xy 199.258919 -328.957367) (xy 199.288385 -329.003217) (xy 199.311027 -329.052793) (xy 199.326383 -329.105088)
			(xy 199.334141 -329.159035) (xy 199.334628 -329.186286) (xy 199.334171 -329.213657) (xy 199.326354 -329.267837)
			(xy 199.310864 -329.320341) (xy 199.288019 -329.370088) (xy 199.258291 -329.416053) (xy 199.240648 -329.436984)
			(xy 199.234552 -329.444096) (xy 199.228202 -329.461114) (xy 199.228202 -329.546458) (xy 199.234552 -329.563476)
			(xy 199.240648 -329.570588) (xy 199.258276 -329.591531) (xy 199.288003 -329.637497) (xy 199.310851 -329.687241)
			(xy 199.326349 -329.739742) (xy 199.33418 -329.793919) (xy 199.334181 -329.84866) (xy 199.326354 -329.902838)
			(xy 199.310858 -329.955339) (xy 199.288013 -330.005085) (xy 199.258289 -330.051052) (xy 199.240648 -330.071984)
			(xy 199.234552 -330.079096) (xy 199.228202 -330.096114) (xy 199.228202 -330.181458) (xy 199.234552 -330.198476)
			(xy 199.240648 -330.205588) (xy 199.258287 -330.22652) (xy 199.288001 -330.272492) (xy 199.310837 -330.32224)
			(xy 199.326328 -330.374741) (xy 199.334155 -330.428917) (xy 199.334628 -330.456286) (xy 202.635612 -330.456286)
			(xy 202.636067 -330.428915) (xy 202.643887 -330.374736) (xy 202.659379 -330.322232) (xy 202.682223 -330.272486)
			(xy 202.71195 -330.226519) (xy 202.729592 -330.205588) (xy 202.735688 -330.198476) (xy 202.742038 -330.181458)
			(xy 202.742038 -330.096114) (xy 202.735688 -330.079096) (xy 202.729592 -330.071984) (xy 202.711939 -330.051062)
			(xy 202.682217 -330.005091) (xy 202.659375 -329.955343) (xy 202.643881 -329.90284) (xy 202.636055 -329.84866)
			(xy 202.636056 -329.793919) (xy 202.643886 -329.73974) (xy 202.659383 -329.687237) (xy 202.682228 -329.63749)
			(xy 202.711952 -329.591521) (xy 202.729592 -329.570588) (xy 202.735688 -329.563476) (xy 202.742038 -329.546458)
			(xy 202.742038 -329.461114) (xy 202.735688 -329.444096) (xy 202.729592 -329.436984) (xy 202.711978 -329.416032)
			(xy 202.682262 -329.370065) (xy 202.659422 -329.320322) (xy 202.643925 -329.267826) (xy 202.63609 -329.213654)
			(xy 202.635612 -329.186286) (xy 202.636042 -329.159032) (xy 202.643801 -329.105079) (xy 202.65916 -329.052779)
			(xy 202.681806 -329.003197) (xy 202.711277 -328.957343) (xy 202.746974 -328.91615) (xy 202.788171 -328.880457)
			(xy 202.834027 -328.850989) (xy 202.883611 -328.828348) (xy 202.935912 -328.812994) (xy 202.989866 -328.805239)
			(xy 203.01712 -328.804778) (xy 203.04584 -328.805265) (xy 203.10263 -328.813885) (xy 203.157484 -328.830927)
			(xy 203.209161 -328.856004) (xy 203.256492 -328.88855) (xy 203.298404 -328.927828) (xy 203.316586 -328.950066)
			(xy 203.32319 -328.958448) (xy 203.341224 -328.9681) (xy 203.435966 -328.976736) (xy 203.455524 -328.970386)
			(xy 203.463652 -328.963274) (xy 203.484661 -328.945471) (xy 203.530812 -328.915432) (xy 203.580802 -328.892339)
			(xy 203.633593 -328.876673) (xy 203.688087 -328.868759) (xy 203.71562 -328.868278) (xy 203.742992 -328.868713)
			(xy 203.797173 -328.876536) (xy 203.849677 -328.892031) (xy 203.899423 -328.91488) (xy 203.945388 -328.944613)
			(xy 203.966318 -328.962258) (xy 203.97343 -328.968354) (xy 203.990448 -328.974704) (xy 204.075792 -328.974704)
			(xy 204.09281 -328.968354) (xy 204.099922 -328.962258) (xy 204.120867 -328.944635) (xy 204.166837 -328.914922)
			(xy 204.216581 -328.892084) (xy 204.269079 -328.876589) (xy 204.323252 -328.868755) (xy 204.35062 -328.868278)
			(xy 204.377869 -328.868794) (xy 204.431813 -328.876552) (xy 204.484103 -328.891908) (xy 204.533676 -328.91455)
			(xy 204.579522 -328.944016) (xy 204.620708 -328.979706) (xy 204.656396 -329.020894) (xy 204.68586 -329.066742)
			(xy 204.708499 -329.116316) (xy 204.723852 -329.168607) (xy 204.731608 -329.222551) (xy 204.731608 -329.277049)
			(xy 204.723852 -329.330993) (xy 204.708499 -329.383284) (xy 204.68586 -329.432858) (xy 204.656396 -329.478706)
			(xy 204.620708 -329.519894) (xy 204.579522 -329.555584) (xy 204.533676 -329.58505) (xy 204.484103 -329.607692)
			(xy 204.431813 -329.623048) (xy 204.377869 -329.630806) (xy 204.35062 -329.631294) (xy 204.32325 -329.630818)
			(xy 204.269071 -329.623003) (xy 204.216568 -329.607516) (xy 204.166821 -329.584676) (xy 204.120854 -329.554954)
			(xy 204.099922 -329.537314) (xy 204.09281 -329.531218) (xy 204.075792 -329.524868) (xy 203.990448 -329.524868)
			(xy 203.97343 -329.531218) (xy 203.966318 -329.537314) (xy 203.945392 -329.55496) (xy 203.899417 -329.584671)
			(xy 203.849668 -329.607505) (xy 203.797166 -329.622994) (xy 203.74299 -329.630821) (xy 203.71562 -329.631294)
			(xy 203.689034 -329.630851) (xy 203.63638 -329.623441) (xy 203.585265 -329.608788) (xy 203.536681 -329.587178)
			(xy 203.49157 -329.55903) (xy 203.450806 -329.524888) (xy 203.415179 -329.485415) (xy 203.399898 -329.463654)
			(xy 203.393029 -329.454642) (xy 203.373521 -329.443171) (xy 203.362306 -329.441556) (xy 203.305156 -329.436476)
			(xy 203.304648 -329.436984) (xy 203.298552 -329.444096) (xy 203.292202 -329.461114) (xy 203.292202 -329.546458)
			(xy 203.298552 -329.563476) (xy 203.304648 -329.570588) (xy 203.322276 -329.591531) (xy 203.352003 -329.637497)
			(xy 203.374851 -329.687241) (xy 203.390349 -329.739742) (xy 203.39818 -329.793919) (xy 203.398181 -329.84866)
			(xy 203.390354 -329.902838) (xy 203.374858 -329.955339) (xy 203.352013 -330.005085) (xy 203.350636 -330.007214)
			(xy 204.748636 -330.007214) (xy 204.752707 -329.951592) (xy 204.764833 -329.897155) (xy 204.784756 -329.845064)
			(xy 204.812052 -329.796429) (xy 204.846138 -329.752286) (xy 204.886287 -329.713577) (xy 204.931645 -329.681126)
			(xy 204.981245 -329.655625) (xy 205.034029 -329.637618) (xy 205.088872 -329.627488) (xy 205.144606 -329.625451)
			(xy 205.200043 -329.631551) (xy 205.254 -329.645657) (xy 205.305329 -329.667469) (xy 205.352935 -329.696523)
			(xy 205.395803 -329.732198) (xy 205.43302 -329.773735) (xy 205.463793 -329.820248) (xy 205.487465 -329.870745)
			(xy 205.503533 -329.924152) (xy 205.511653 -329.979328) (xy 205.512162 -330.007214) (xy 205.511653 -330.0351)
			(xy 205.503533 -330.090276) (xy 205.487465 -330.143683) (xy 205.463793 -330.19418) (xy 205.43302 -330.240693)
			(xy 205.395803 -330.28223) (xy 205.352935 -330.317905) (xy 205.305329 -330.346959) (xy 205.254 -330.368771)
			(xy 205.200043 -330.382877) (xy 205.144606 -330.388977) (xy 205.088872 -330.38694) (xy 205.034029 -330.37681)
			(xy 204.981245 -330.358803) (xy 204.931645 -330.333302) (xy 204.886287 -330.300851) (xy 204.846138 -330.262142)
			(xy 204.812052 -330.217999) (xy 204.784756 -330.169364) (xy 204.764833 -330.117273) (xy 204.752707 -330.062836)
			(xy 204.748636 -330.007214) (xy 203.350636 -330.007214) (xy 203.322289 -330.051052) (xy 203.304648 -330.071984)
			(xy 203.298552 -330.079096) (xy 203.292202 -330.096114) (xy 203.292202 -330.181458) (xy 203.298552 -330.198476)
			(xy 203.304648 -330.205588) (xy 203.322287 -330.22652) (xy 203.352001 -330.272492) (xy 203.374837 -330.32224)
			(xy 203.390328 -330.374741) (xy 203.398155 -330.428917) (xy 203.398628 -330.456286) (xy 203.398142 -330.483537)
			(xy 203.390386 -330.537485) (xy 203.375031 -330.58978) (xy 203.352389 -330.639357) (xy 203.322923 -330.685207)
			(xy 203.287232 -330.726398) (xy 203.246041 -330.762089) (xy 203.200191 -330.791555) (xy 203.150614 -330.814197)
			(xy 203.098319 -330.829552) (xy 203.044371 -330.837308) (xy 202.989869 -330.837308) (xy 202.935921 -330.829552)
			(xy 202.883626 -330.814197) (xy 202.834049 -330.791555) (xy 202.788199 -330.762089) (xy 202.747008 -330.726398)
			(xy 202.711317 -330.685207) (xy 202.681851 -330.639357) (xy 202.659209 -330.58978) (xy 202.643854 -330.537485)
			(xy 202.636098 -330.483537) (xy 202.635612 -330.456286) (xy 199.334628 -330.456286) (xy 199.334142 -330.483537)
			(xy 199.326386 -330.537485) (xy 199.311031 -330.58978) (xy 199.288389 -330.639357) (xy 199.258923 -330.685207)
			(xy 199.223232 -330.726398) (xy 199.182041 -330.762089) (xy 199.136191 -330.791555) (xy 199.086614 -330.814197)
			(xy 199.034319 -330.829552) (xy 198.980371 -330.837308) (xy 198.925869 -330.837308) (xy 198.871921 -330.829552)
			(xy 198.819626 -330.814197) (xy 198.770049 -330.791555) (xy 198.724199 -330.762089) (xy 198.683008 -330.726398)
			(xy 198.647317 -330.685207) (xy 198.617851 -330.639357) (xy 198.595209 -330.58978) (xy 198.579854 -330.537485)
			(xy 198.572098 -330.483537) (xy 198.571612 -330.456286) (xy 198.572067 -330.428915) (xy 198.579887 -330.374736)
			(xy 198.595379 -330.322232) (xy 198.618223 -330.272486) (xy 198.64795 -330.226519) (xy 198.665592 -330.205588)
			(xy 198.671688 -330.198476) (xy 198.678038 -330.181458) (xy 198.678038 -330.096114) (xy 198.671688 -330.079096)
			(xy 198.665592 -330.071984) (xy 198.647939 -330.051062) (xy 198.618217 -330.005091) (xy 198.595375 -329.955343)
			(xy 198.579881 -329.90284) (xy 198.572055 -329.84866) (xy 198.572056 -329.793919) (xy 198.579886 -329.73974)
			(xy 198.595383 -329.687237) (xy 198.618228 -329.63749) (xy 198.647952 -329.591521) (xy 198.665592 -329.570588)
			(xy 198.671688 -329.563476) (xy 198.678038 -329.546458) (xy 198.678038 -329.461114) (xy 198.671688 -329.444096)
			(xy 198.665592 -329.436984) (xy 198.665084 -329.436476) (xy 198.607934 -329.441556) (xy 198.596721 -329.443186)
			(xy 198.577209 -329.454643) (xy 198.570342 -329.463654) (xy 198.555042 -329.485398) (xy 198.519407 -329.524854)
			(xy 198.47864 -329.558983) (xy 198.433532 -329.587124) (xy 198.384955 -329.608732) (xy 198.333849 -329.623389)
			(xy 198.281203 -329.630812) (xy 198.25462 -329.631294) (xy 198.22725 -329.630818) (xy 198.173071 -329.623003)
			(xy 198.120568 -329.607516) (xy 198.070821 -329.584676) (xy 198.024854 -329.554954) (xy 198.003922 -329.537314)
			(xy 197.99681 -329.531218) (xy 197.979792 -329.524868) (xy 197.894448 -329.524868) (xy 197.87743 -329.531218)
			(xy 197.870318 -329.537314) (xy 197.849392 -329.55496) (xy 197.803417 -329.584671) (xy 197.753668 -329.607505)
			(xy 197.701166 -329.622994) (xy 197.64699 -329.630821) (xy 197.61962 -329.631294) (xy 197.592365 -329.63086)
			(xy 197.53841 -329.623106) (xy 197.486108 -329.607751) (xy 197.436523 -329.585108) (xy 197.390666 -329.55564)
			(xy 197.349469 -329.519945) (xy 197.313772 -329.47875) (xy 197.284301 -329.432894) (xy 197.261656 -329.383311)
			(xy 197.246299 -329.33101) (xy 197.238541 -329.277055) (xy 159.833056 -329.277055) (xy 159.833056 -332.849474)
			(xy 159.832537 -332.891888) (xy 159.824226 -332.976307) (xy 159.807681 -333.059506) (xy 159.783061 -333.140682)
			(xy 159.750605 -333.219055) (xy 159.710623 -333.29387) (xy 159.663501 -333.364405) (xy 159.609693 -333.429983)
			(xy 159.580072 -333.460344) (xy 158.56585 -334.474566) (xy 158.559008 -334.481966) (xy 158.55129 -334.500564)
			(xy 158.550864 -334.510634) (xy 158.550864 -342.97747) (xy 159.02686 -342.97747) (xy 159.02686 -340.755478)
			(xy 159.027472 -340.730481) (xy 159.037282 -340.681456) (xy 159.056463 -340.635286) (xy 159.084277 -340.593741)
			(xy 159.101536 -340.575646) (xy 167.302942 -332.37424) (xy 167.321032 -332.356978) (xy 167.362578 -332.329167)
			(xy 167.408751 -332.309995) (xy 167.457777 -332.300199) (xy 167.482774 -332.299564) (xy 167.900096 -332.299564)
			(xy 167.92702 -332.278736) (xy 167.931592 -332.261972) (xy 167.939179 -332.235197) (xy 167.961073 -332.184033)
			(xy 167.990167 -332.136593) (xy 168.025846 -332.093884) (xy 168.067351 -332.056812) (xy 168.113802 -332.026164)
			(xy 168.164213 -332.00259) (xy 168.217514 -331.98659) (xy 168.272575 -331.978505) (xy 168.3004 -331.978)
			(xy 168.327653 -331.978455) (xy 168.381605 -331.986213) (xy 168.433903 -332.001569) (xy 168.483484 -332.024212)
			(xy 168.529337 -332.053681) (xy 168.57053 -332.089375) (xy 168.606224 -332.130569) (xy 168.635692 -332.176423)
			(xy 168.658334 -332.226004) (xy 168.673689 -332.278303) (xy 168.681445 -332.332255) (xy 168.681908 -332.359508)
			(xy 168.681358 -332.388424) (xy 168.672641 -332.445595) (xy 168.655391 -332.500795) (xy 168.630006 -332.552758)
			(xy 168.597066 -332.600292) (xy 168.557327 -332.642308) (xy 168.534842 -332.660498) (xy 168.526076 -332.668055)
			(xy 168.515897 -332.688818) (xy 168.515284 -332.700376) (xy 168.515284 -332.78064) (xy 168.515894 -332.792203)
			(xy 168.526061 -332.812974) (xy 168.534842 -332.820518) (xy 168.557343 -332.838688) (xy 168.597075 -332.880714)
			(xy 168.630011 -332.928253) (xy 168.655396 -332.980218) (xy 168.672649 -333.035419) (xy 168.681375 -333.092591)
			(xy 168.681908 -333.121508) (xy 168.68143 -333.148759) (xy 168.673672 -333.202707) (xy 168.658316 -333.255002)
			(xy 168.635674 -333.30458) (xy 168.606207 -333.35043) (xy 168.570514 -333.39162) (xy 168.529324 -333.427312)
			(xy 168.483473 -333.456778) (xy 168.433895 -333.479419) (xy 168.3816 -333.494774) (xy 168.327651 -333.50253)
			(xy 168.3004 -333.503016) (xy 168.272998 -333.5026) (xy 168.218759 -333.494746) (xy 168.166201 -333.479212)
			(xy 168.116407 -333.456319) (xy 168.0704 -333.426538) (xy 168.029127 -333.390481) (xy 167.993437 -333.34889)
			(xy 167.964064 -333.302621) (xy 167.941613 -333.252626) (xy 167.933624 -333.22641) (xy 167.928798 -333.209646)
			(xy 167.901874 -333.18958) (xy 167.767254 -333.18958) (xy 167.757206 -333.18993) (xy 167.738609 -333.197531)
			(xy 167.731186 -333.204312) (xy 165.577278 -335.35822) (xy 174.360114 -335.35822) (xy 174.363841 -335.304972)
			(xy 174.374954 -335.252763) (xy 174.393236 -335.202614) (xy 174.41833 -335.155502) (xy 174.449747 -335.112349)
			(xy 174.486872 -335.073996) (xy 174.507652 -335.057242) (xy 174.516399 -335.049667) (xy 174.526589 -335.028918)
			(xy 174.52721 -335.017364) (xy 174.52721 -334.9371) (xy 174.526636 -334.925533) (xy 174.516444 -334.904762)
			(xy 174.507652 -334.897222) (xy 174.486901 -334.88043) (xy 174.449772 -334.842081) (xy 174.418351 -334.798931)
			(xy 174.393252 -334.751822) (xy 174.374964 -334.701675) (xy 174.363846 -334.649467) (xy 174.360114 -334.59622)
			(xy 174.363841 -334.542972) (xy 174.374954 -334.490763) (xy 174.393236 -334.440614) (xy 174.41833 -334.393502)
			(xy 174.449747 -334.350349) (xy 174.486872 -334.311996) (xy 174.507652 -334.295242) (xy 174.516399 -334.287667)
			(xy 174.526589 -334.266918) (xy 174.52721 -334.255364) (xy 174.52721 -334.1751) (xy 174.526636 -334.163533)
			(xy 174.516444 -334.142762) (xy 174.507652 -334.135222) (xy 174.485169 -334.117031) (xy 174.445436 -334.07501)
			(xy 174.412498 -334.027474) (xy 174.38711 -333.975513) (xy 174.369853 -333.920316) (xy 174.361122 -333.863148)
			(xy 174.360586 -333.834232) (xy 174.361072 -333.806981) (xy 174.368828 -333.753033) (xy 174.384183 -333.700738)
			(xy 174.406825 -333.651161) (xy 174.436291 -333.605311) (xy 174.471982 -333.56412) (xy 174.513173 -333.528429)
			(xy 174.559023 -333.498963) (xy 174.6086 -333.476321) (xy 174.660895 -333.460966) (xy 174.714843 -333.45321)
			(xy 174.769345 -333.45321) (xy 174.823293 -333.460966) (xy 174.875588 -333.476321) (xy 174.925165 -333.498963)
			(xy 174.971015 -333.528429) (xy 175.012206 -333.56412) (xy 175.047897 -333.605311) (xy 175.077363 -333.651161)
			(xy 175.100005 -333.700738) (xy 175.11536 -333.753033) (xy 175.123116 -333.806981) (xy 175.123602 -333.834232)
			(xy 175.123034 -333.863147) (xy 175.114315 -333.920316) (xy 175.097067 -333.975514) (xy 175.071685 -334.027476)
			(xy 175.03875 -334.075011) (xy 174.999018 -334.11703) (xy 174.976536 -334.135222) (xy 174.967758 -334.142768)
			(xy 174.957586 -334.163539) (xy 174.956978 -334.1751) (xy 174.956978 -334.255364) (xy 174.957577 -334.266928)
			(xy 174.967752 -334.287699) (xy 174.976536 -334.295242) (xy 174.997351 -334.311958) (xy 175.034482 -334.350315)
			(xy 175.065904 -334.393474) (xy 175.091002 -334.440592) (xy 175.109288 -334.490748) (xy 175.120402 -334.542964)
			(xy 175.12413 -334.59622) (xy 175.120397 -334.649475) (xy 175.109277 -334.701689) (xy 175.090986 -334.751844)
			(xy 175.065883 -334.798959) (xy 175.034457 -334.842115) (xy 174.997321 -334.880469) (xy 174.976536 -334.897222)
			(xy 174.967758 -334.904768) (xy 174.957586 -334.925539) (xy 174.956978 -334.9371) (xy 174.956978 -335.017364)
			(xy 174.957577 -335.028928) (xy 174.967752 -335.049699) (xy 174.976536 -335.057242) (xy 174.997351 -335.073958)
			(xy 175.034482 -335.112315) (xy 175.065904 -335.155474) (xy 175.091002 -335.202592) (xy 175.109288 -335.252748)
			(xy 175.115518 -335.28202) (xy 176.773114 -335.28202) (xy 176.776841 -335.228772) (xy 176.787954 -335.176563)
			(xy 176.806236 -335.126414) (xy 176.83133 -335.079302) (xy 176.862747 -335.036149) (xy 176.899872 -334.997796)
			(xy 176.920652 -334.981042) (xy 176.929399 -334.973467) (xy 176.939589 -334.952718) (xy 176.94021 -334.941164)
			(xy 176.94021 -334.8609) (xy 176.939636 -334.849333) (xy 176.929444 -334.828562) (xy 176.920652 -334.821022)
			(xy 176.899901 -334.80423) (xy 176.862772 -334.765881) (xy 176.831351 -334.722731) (xy 176.806252 -334.675622)
			(xy 176.787964 -334.625475) (xy 176.776846 -334.573267) (xy 176.773114 -334.52002) (xy 176.776841 -334.466772)
			(xy 176.787954 -334.414563) (xy 176.806236 -334.364414) (xy 176.83133 -334.317302) (xy 176.862747 -334.274149)
			(xy 176.899872 -334.235796) (xy 176.920652 -334.219042) (xy 176.929399 -334.211467) (xy 176.939589 -334.190718)
			(xy 176.94021 -334.179164) (xy 176.94021 -334.0989) (xy 176.939636 -334.087333) (xy 176.929444 -334.066562)
			(xy 176.920652 -334.059022) (xy 176.898169 -334.040831) (xy 176.858436 -333.99881) (xy 176.825498 -333.951274)
			(xy 176.80011 -333.899313) (xy 176.782853 -333.844116) (xy 176.774122 -333.786948) (xy 176.773586 -333.758032)
			(xy 176.774072 -333.730781) (xy 176.781828 -333.676833) (xy 176.797183 -333.624538) (xy 176.819825 -333.574961)
			(xy 176.849291 -333.529111) (xy 176.884982 -333.48792) (xy 176.926173 -333.452229) (xy 176.972023 -333.422763)
			(xy 177.0216 -333.400121) (xy 177.073895 -333.384766) (xy 177.127843 -333.37701) (xy 177.182345 -333.37701)
			(xy 177.236293 -333.384766) (xy 177.288588 -333.400121) (xy 177.338165 -333.422763) (xy 177.384015 -333.452229)
			(xy 177.425206 -333.48792) (xy 177.460897 -333.529111) (xy 177.490363 -333.574961) (xy 177.513005 -333.624538)
			(xy 177.52836 -333.676833) (xy 177.536116 -333.730781) (xy 177.536602 -333.758032) (xy 177.536034 -333.786947)
			(xy 177.527315 -333.844116) (xy 177.510067 -333.899314) (xy 177.484685 -333.951276) (xy 177.45175 -333.998811)
			(xy 177.412018 -334.04083) (xy 177.389536 -334.059022) (xy 177.380758 -334.066568) (xy 177.370586 -334.087339)
			(xy 177.369978 -334.0989) (xy 177.369978 -334.179164) (xy 177.370577 -334.190728) (xy 177.380752 -334.211499)
			(xy 177.389536 -334.219042) (xy 177.410351 -334.235758) (xy 177.447482 -334.274115) (xy 177.478904 -334.317274)
			(xy 177.504002 -334.364392) (xy 177.522288 -334.414548) (xy 177.533402 -334.466764) (xy 177.53713 -334.52002)
			(xy 177.533397 -334.573275) (xy 177.522277 -334.625489) (xy 177.503986 -334.675644) (xy 177.478883 -334.722759)
			(xy 177.447457 -334.765915) (xy 177.410321 -334.804269) (xy 177.389536 -334.821022) (xy 177.380758 -334.828568)
			(xy 177.370586 -334.849339) (xy 177.369978 -334.8609) (xy 177.369978 -334.941164) (xy 177.370577 -334.952728)
			(xy 177.380752 -334.973499) (xy 177.389536 -334.981042) (xy 177.410351 -334.997758) (xy 177.447482 -335.036115)
			(xy 177.478904 -335.079274) (xy 177.504002 -335.126392) (xy 177.522288 -335.176548) (xy 177.533402 -335.228764)
			(xy 177.53713 -335.28202) (xy 177.533397 -335.335275) (xy 177.526343 -335.368395) (xy 180.425089 -335.368395)
			(xy 180.42882 -335.315143) (xy 180.439937 -335.26293) (xy 180.458225 -335.212777) (xy 180.483325 -335.165663)
			(xy 180.514748 -335.122508) (xy 180.55188 -335.084155) (xy 180.572664 -335.067402) (xy 180.581431 -335.059846)
			(xy 180.591609 -335.039082) (xy 180.592222 -335.027524) (xy 180.592222 -334.94726) (xy 180.59161 -334.935698)
			(xy 180.581444 -334.914927) (xy 180.572664 -334.907382) (xy 180.551873 -334.890638) (xy 180.514742 -334.852284)
			(xy 180.48332 -334.809128) (xy 180.458221 -334.762014) (xy 180.439935 -334.71186) (xy 180.428818 -334.659648)
			(xy 180.425089 -334.606395) (xy 180.42882 -334.553143) (xy 180.439937 -334.50093) (xy 180.458225 -334.450777)
			(xy 180.483325 -334.403663) (xy 180.514748 -334.360508) (xy 180.55188 -334.322155) (xy 180.572664 -334.305402)
			(xy 180.581431 -334.297846) (xy 180.591609 -334.277082) (xy 180.592222 -334.265524) (xy 180.592222 -334.18526)
			(xy 180.59161 -334.173698) (xy 180.581444 -334.152927) (xy 180.572664 -334.145382) (xy 180.550164 -334.12721)
			(xy 180.510432 -334.085185) (xy 180.477496 -334.037646) (xy 180.452111 -333.985681) (xy 180.434857 -333.930481)
			(xy 180.426131 -333.873309) (xy 180.425598 -333.844392) (xy 180.426084 -333.817141) (xy 180.43384 -333.763193)
			(xy 180.449195 -333.710898) (xy 180.471837 -333.661321) (xy 180.501303 -333.615471) (xy 180.536994 -333.57428)
			(xy 180.578185 -333.538589) (xy 180.624035 -333.509123) (xy 180.673612 -333.486481) (xy 180.725907 -333.471126)
			(xy 180.779855 -333.46337) (xy 180.834357 -333.46337) (xy 180.888305 -333.471126) (xy 180.9406 -333.486481)
			(xy 180.990177 -333.509123) (xy 181.036027 -333.538589) (xy 181.077218 -333.57428) (xy 181.112909 -333.615471)
			(xy 181.142375 -333.661321) (xy 181.165017 -333.710898) (xy 181.180372 -333.763193) (xy 181.188128 -333.817141)
			(xy 181.188614 -333.844392) (xy 181.188123 -333.87331) (xy 181.179393 -333.930484) (xy 181.162132 -333.985685)
			(xy 181.136735 -334.037647) (xy 181.103785 -334.08518) (xy 181.064037 -334.127194) (xy 181.041548 -334.145382)
			(xy 181.03279 -334.152947) (xy 181.022606 -334.173704) (xy 181.02199 -334.18526) (xy 181.02199 -334.265524)
			(xy 181.022608 -334.277086) (xy 181.032769 -334.297857) (xy 181.041548 -334.305402) (xy 181.062323 -334.322165)
			(xy 181.099452 -334.360517) (xy 181.130873 -334.403671) (xy 181.155972 -334.450783) (xy 181.174258 -334.500934)
			(xy 181.185375 -334.553145) (xy 181.189106 -334.606395) (xy 181.185377 -334.659646) (xy 181.174261 -334.711856)
			(xy 181.155976 -334.762008) (xy 181.130879 -334.809121) (xy 181.099459 -334.852275) (xy 181.06233 -334.890628)
			(xy 181.041548 -334.907382) (xy 181.03279 -334.914947) (xy 181.022606 -334.935704) (xy 181.02199 -334.94726)
			(xy 181.02199 -335.027524) (xy 181.022608 -335.039086) (xy 181.032769 -335.059857) (xy 181.041548 -335.067402)
			(xy 181.062323 -335.084165) (xy 181.099452 -335.122517) (xy 181.130873 -335.165671) (xy 181.155972 -335.212783)
			(xy 181.174258 -335.262934) (xy 181.180488 -335.292195) (xy 182.838089 -335.292195) (xy 182.84182 -335.238943)
			(xy 182.852937 -335.18673) (xy 182.871225 -335.136577) (xy 182.896325 -335.089463) (xy 182.927748 -335.046308)
			(xy 182.96488 -335.007955) (xy 182.985664 -334.991202) (xy 182.994431 -334.983646) (xy 183.004609 -334.962882)
			(xy 183.005222 -334.951324) (xy 183.005222 -334.87106) (xy 183.00461 -334.859498) (xy 182.994444 -334.838727)
			(xy 182.985664 -334.831182) (xy 182.964873 -334.814438) (xy 182.927742 -334.776084) (xy 182.89632 -334.732928)
			(xy 182.871221 -334.685814) (xy 182.852935 -334.63566) (xy 182.841818 -334.583448) (xy 182.838089 -334.530195)
			(xy 182.84182 -334.476943) (xy 182.852937 -334.42473) (xy 182.871225 -334.374577) (xy 182.896325 -334.327463)
			(xy 182.927748 -334.284308) (xy 182.96488 -334.245955) (xy 182.985664 -334.229202) (xy 182.994431 -334.221646)
			(xy 183.004609 -334.200882) (xy 183.005222 -334.189324) (xy 183.005222 -334.10906) (xy 183.00461 -334.097498)
			(xy 182.994444 -334.076727) (xy 182.985664 -334.069182) (xy 182.963164 -334.05101) (xy 182.923432 -334.008985)
			(xy 182.890496 -333.961446) (xy 182.865111 -333.909481) (xy 182.847857 -333.854281) (xy 182.839131 -333.797109)
			(xy 182.838598 -333.768192) (xy 182.839084 -333.740941) (xy 182.84684 -333.686993) (xy 182.862195 -333.634698)
			(xy 182.884837 -333.585121) (xy 182.914303 -333.539271) (xy 182.949994 -333.49808) (xy 182.991185 -333.462389)
			(xy 183.037035 -333.432923) (xy 183.086612 -333.410281) (xy 183.138907 -333.394926) (xy 183.192855 -333.38717)
			(xy 183.247357 -333.38717) (xy 183.301305 -333.394926) (xy 183.3536 -333.410281) (xy 183.403177 -333.432923)
			(xy 183.449027 -333.462389) (xy 183.490218 -333.49808) (xy 183.525909 -333.539271) (xy 183.555375 -333.585121)
			(xy 183.578017 -333.634698) (xy 183.593372 -333.686993) (xy 183.601128 -333.740941) (xy 183.601614 -333.768192)
			(xy 183.601123 -333.79711) (xy 183.592393 -333.854284) (xy 183.575132 -333.909485) (xy 183.549735 -333.961447)
			(xy 183.516785 -334.00898) (xy 183.477037 -334.050994) (xy 183.454548 -334.069182) (xy 183.44579 -334.076747)
			(xy 183.435606 -334.097504) (xy 183.43499 -334.10906) (xy 183.43499 -334.189324) (xy 183.435608 -334.200886)
			(xy 183.445769 -334.221657) (xy 183.454548 -334.229202) (xy 183.475323 -334.245965) (xy 183.512452 -334.284317)
			(xy 183.543873 -334.327471) (xy 183.568972 -334.374583) (xy 183.587258 -334.424734) (xy 183.598375 -334.476945)
			(xy 183.602106 -334.530195) (xy 183.598377 -334.583446) (xy 183.587261 -334.635656) (xy 183.568976 -334.685808)
			(xy 183.543879 -334.732921) (xy 183.512459 -334.776075) (xy 183.47533 -334.814428) (xy 183.454548 -334.831182)
			(xy 183.44579 -334.838747) (xy 183.435606 -334.859504) (xy 183.43499 -334.87106) (xy 183.43499 -334.951324)
			(xy 183.435608 -334.962886) (xy 183.445769 -334.983657) (xy 183.454548 -334.991202) (xy 183.475323 -335.007965)
			(xy 183.512452 -335.046317) (xy 183.543873 -335.089471) (xy 183.568972 -335.136583) (xy 183.587258 -335.186734)
			(xy 183.598375 -335.238945) (xy 183.602106 -335.292195) (xy 186.495689 -335.292195) (xy 186.49942 -335.238943)
			(xy 186.510537 -335.18673) (xy 186.528825 -335.136577) (xy 186.553925 -335.089463) (xy 186.585348 -335.046308)
			(xy 186.62248 -335.007955) (xy 186.643264 -334.991202) (xy 186.652031 -334.983646) (xy 186.662209 -334.962882)
			(xy 186.662822 -334.951324) (xy 186.662822 -334.87106) (xy 186.66221 -334.859498) (xy 186.652044 -334.838727)
			(xy 186.643264 -334.831182) (xy 186.622473 -334.814438) (xy 186.585342 -334.776084) (xy 186.55392 -334.732928)
			(xy 186.528821 -334.685814) (xy 186.510535 -334.63566) (xy 186.499418 -334.583448) (xy 186.495689 -334.530195)
			(xy 186.49942 -334.476943) (xy 186.510537 -334.42473) (xy 186.528825 -334.374577) (xy 186.553925 -334.327463)
			(xy 186.585348 -334.284308) (xy 186.62248 -334.245955) (xy 186.643264 -334.229202) (xy 186.652031 -334.221646)
			(xy 186.662209 -334.200882) (xy 186.662822 -334.189324) (xy 186.662822 -334.10906) (xy 186.66221 -334.097498)
			(xy 186.652044 -334.076727) (xy 186.643264 -334.069182) (xy 186.620764 -334.05101) (xy 186.581032 -334.008985)
			(xy 186.548096 -333.961446) (xy 186.522711 -333.909481) (xy 186.505457 -333.854281) (xy 186.496731 -333.797109)
			(xy 186.496198 -333.768192) (xy 186.496684 -333.740941) (xy 186.50444 -333.686993) (xy 186.519795 -333.634698)
			(xy 186.542437 -333.585121) (xy 186.571903 -333.539271) (xy 186.607594 -333.49808) (xy 186.648785 -333.462389)
			(xy 186.694635 -333.432923) (xy 186.744212 -333.410281) (xy 186.796507 -333.394926) (xy 186.850455 -333.38717)
			(xy 186.904957 -333.38717) (xy 186.958905 -333.394926) (xy 187.0112 -333.410281) (xy 187.060777 -333.432923)
			(xy 187.106627 -333.462389) (xy 187.147818 -333.49808) (xy 187.183509 -333.539271) (xy 187.212975 -333.585121)
			(xy 187.235617 -333.634698) (xy 187.250972 -333.686993) (xy 187.258728 -333.740941) (xy 187.259214 -333.768192)
			(xy 187.258723 -333.79711) (xy 187.249993 -333.854284) (xy 187.232732 -333.909485) (xy 187.207335 -333.961447)
			(xy 187.174385 -334.00898) (xy 187.134637 -334.050994) (xy 187.112148 -334.069182) (xy 187.10339 -334.076747)
			(xy 187.093206 -334.097504) (xy 187.09259 -334.10906) (xy 187.09259 -334.189324) (xy 187.093208 -334.200886)
			(xy 187.103369 -334.221657) (xy 187.112148 -334.229202) (xy 187.132923 -334.245965) (xy 187.170052 -334.284317)
			(xy 187.201473 -334.327471) (xy 187.226572 -334.374583) (xy 187.244858 -334.424734) (xy 187.255975 -334.476945)
			(xy 187.259706 -334.530195) (xy 187.255977 -334.583446) (xy 187.244861 -334.635656) (xy 187.226576 -334.685808)
			(xy 187.201479 -334.732921) (xy 187.170059 -334.776075) (xy 187.13293 -334.814428) (xy 187.112148 -334.831182)
			(xy 187.10339 -334.838747) (xy 187.093206 -334.859504) (xy 187.09259 -334.87106) (xy 187.09259 -334.951324)
			(xy 187.093208 -334.962886) (xy 187.103369 -334.983657) (xy 187.112148 -334.991202) (xy 187.132923 -335.007965)
			(xy 187.170052 -335.046317) (xy 187.201473 -335.089471) (xy 187.226572 -335.136583) (xy 187.244858 -335.186734)
			(xy 187.255975 -335.238945) (xy 187.259706 -335.292195) (xy 188.959489 -335.292195) (xy 188.96322 -335.238943)
			(xy 188.974337 -335.18673) (xy 188.992625 -335.136577) (xy 189.017725 -335.089463) (xy 189.049148 -335.046308)
			(xy 189.08628 -335.007955) (xy 189.107064 -334.991202) (xy 189.115831 -334.983646) (xy 189.126009 -334.962882)
			(xy 189.126622 -334.951324) (xy 189.126622 -334.87106) (xy 189.12601 -334.859498) (xy 189.115844 -334.838727)
			(xy 189.107064 -334.831182) (xy 189.086273 -334.814438) (xy 189.049142 -334.776084) (xy 189.01772 -334.732928)
			(xy 188.992621 -334.685814) (xy 188.974335 -334.63566) (xy 188.963218 -334.583448) (xy 188.959489 -334.530195)
			(xy 188.96322 -334.476943) (xy 188.974337 -334.42473) (xy 188.992625 -334.374577) (xy 189.017725 -334.327463)
			(xy 189.049148 -334.284308) (xy 189.08628 -334.245955) (xy 189.107064 -334.229202) (xy 189.115831 -334.221646)
			(xy 189.126009 -334.200882) (xy 189.126622 -334.189324) (xy 189.126622 -334.10906) (xy 189.12601 -334.097498)
			(xy 189.115844 -334.076727) (xy 189.107064 -334.069182) (xy 189.084564 -334.05101) (xy 189.044832 -334.008985)
			(xy 189.011896 -333.961446) (xy 188.986511 -333.909481) (xy 188.969257 -333.854281) (xy 188.960531 -333.797109)
			(xy 188.959998 -333.768192) (xy 188.960484 -333.740941) (xy 188.96824 -333.686993) (xy 188.983595 -333.634698)
			(xy 189.006237 -333.585121) (xy 189.035703 -333.539271) (xy 189.071394 -333.49808) (xy 189.112585 -333.462389)
			(xy 189.158435 -333.432923) (xy 189.208012 -333.410281) (xy 189.260307 -333.394926) (xy 189.314255 -333.38717)
			(xy 189.368757 -333.38717) (xy 189.422705 -333.394926) (xy 189.475 -333.410281) (xy 189.524577 -333.432923)
			(xy 189.570427 -333.462389) (xy 189.611618 -333.49808) (xy 189.647309 -333.539271) (xy 189.676775 -333.585121)
			(xy 189.699417 -333.634698) (xy 189.714772 -333.686993) (xy 189.722528 -333.740941) (xy 189.723014 -333.768192)
			(xy 189.722523 -333.79711) (xy 189.713793 -333.854284) (xy 189.696532 -333.909485) (xy 189.671135 -333.961447)
			(xy 189.638185 -334.00898) (xy 189.598437 -334.050994) (xy 189.575948 -334.069182) (xy 189.56719 -334.076747)
			(xy 189.557006 -334.097504) (xy 189.55639 -334.10906) (xy 189.55639 -334.189324) (xy 189.557008 -334.200886)
			(xy 189.567169 -334.221657) (xy 189.575948 -334.229202) (xy 189.596723 -334.245965) (xy 189.633852 -334.284317)
			(xy 189.665273 -334.327471) (xy 189.690372 -334.374583) (xy 189.708658 -334.424734) (xy 189.719775 -334.476945)
			(xy 189.723506 -334.530195) (xy 189.719777 -334.583446) (xy 189.708661 -334.635656) (xy 189.690376 -334.685808)
			(xy 189.665279 -334.732921) (xy 189.633859 -334.776075) (xy 189.59673 -334.814428) (xy 189.575948 -334.831182)
			(xy 189.56719 -334.838747) (xy 189.557006 -334.859504) (xy 189.55639 -334.87106) (xy 189.55639 -334.951324)
			(xy 189.557008 -334.962886) (xy 189.567169 -334.983657) (xy 189.575948 -334.991202) (xy 189.596723 -335.007965)
			(xy 189.633852 -335.046317) (xy 189.665273 -335.089471) (xy 189.690372 -335.136583) (xy 189.708658 -335.186734)
			(xy 189.719775 -335.238945) (xy 189.721726 -335.266795) (xy 192.617089 -335.266795) (xy 192.62082 -335.213543)
			(xy 192.631937 -335.16133) (xy 192.650225 -335.111177) (xy 192.675325 -335.064063) (xy 192.706748 -335.020908)
			(xy 192.74388 -334.982555) (xy 192.764664 -334.965802) (xy 192.773431 -334.958246) (xy 192.783609 -334.937482)
			(xy 192.784222 -334.925924) (xy 192.784222 -334.84566) (xy 192.78361 -334.834098) (xy 192.773444 -334.813327)
			(xy 192.764664 -334.805782) (xy 192.743873 -334.789038) (xy 192.706742 -334.750684) (xy 192.67532 -334.707528)
			(xy 192.650221 -334.660414) (xy 192.631935 -334.61026) (xy 192.620818 -334.558048) (xy 192.617089 -334.504795)
			(xy 192.62082 -334.451543) (xy 192.631937 -334.39933) (xy 192.650225 -334.349177) (xy 192.675325 -334.302063)
			(xy 192.706748 -334.258908) (xy 192.74388 -334.220555) (xy 192.764664 -334.203802) (xy 192.773431 -334.196246)
			(xy 192.783609 -334.175482) (xy 192.784222 -334.163924) (xy 192.784222 -334.08366) (xy 192.78361 -334.072098)
			(xy 192.773444 -334.051327) (xy 192.764664 -334.043782) (xy 192.742164 -334.02561) (xy 192.702432 -333.983585)
			(xy 192.669496 -333.936046) (xy 192.644111 -333.884081) (xy 192.626857 -333.828881) (xy 192.618131 -333.771709)
			(xy 192.617598 -333.742792) (xy 192.618084 -333.715541) (xy 192.62584 -333.661593) (xy 192.641195 -333.609298)
			(xy 192.663837 -333.559721) (xy 192.693303 -333.513871) (xy 192.728994 -333.47268) (xy 192.770185 -333.436989)
			(xy 192.816035 -333.407523) (xy 192.865612 -333.384881) (xy 192.917907 -333.369526) (xy 192.971855 -333.36177)
			(xy 193.026357 -333.36177) (xy 193.080305 -333.369526) (xy 193.1326 -333.384881) (xy 193.182177 -333.407523)
			(xy 193.228027 -333.436989) (xy 193.269218 -333.47268) (xy 193.304909 -333.513871) (xy 193.334375 -333.559721)
			(xy 193.357017 -333.609298) (xy 193.372372 -333.661593) (xy 193.380128 -333.715541) (xy 193.380614 -333.742792)
			(xy 193.380123 -333.77171) (xy 193.371393 -333.828884) (xy 193.354132 -333.884085) (xy 193.328735 -333.936047)
			(xy 193.295785 -333.98358) (xy 193.256037 -334.025594) (xy 193.233548 -334.043782) (xy 193.22479 -334.051347)
			(xy 193.214606 -334.072104) (xy 193.21399 -334.08366) (xy 193.21399 -334.163924) (xy 193.214608 -334.175486)
			(xy 193.224769 -334.196257) (xy 193.233548 -334.203802) (xy 193.254323 -334.220565) (xy 193.291452 -334.258917)
			(xy 193.322873 -334.302071) (xy 193.347972 -334.349183) (xy 193.366258 -334.399334) (xy 193.377375 -334.451545)
			(xy 193.381106 -334.504795) (xy 193.377377 -334.558046) (xy 193.366261 -334.610256) (xy 193.347976 -334.660408)
			(xy 193.322879 -334.707521) (xy 193.291459 -334.750675) (xy 193.25433 -334.789028) (xy 193.233548 -334.805782)
			(xy 193.22479 -334.813347) (xy 193.214606 -334.834104) (xy 193.21399 -334.84566) (xy 193.21399 -334.925924)
			(xy 193.214608 -334.937486) (xy 193.224769 -334.958257) (xy 193.233548 -334.965802) (xy 193.254323 -334.982565)
			(xy 193.291452 -335.020917) (xy 193.322873 -335.064071) (xy 193.347972 -335.111183) (xy 193.366258 -335.161334)
			(xy 193.377375 -335.213545) (xy 193.381106 -335.266795) (xy 195.055489 -335.266795) (xy 195.05922 -335.213543)
			(xy 195.070337 -335.16133) (xy 195.088625 -335.111177) (xy 195.113725 -335.064063) (xy 195.145148 -335.020908)
			(xy 195.18228 -334.982555) (xy 195.203064 -334.965802) (xy 195.211831 -334.958246) (xy 195.222009 -334.937482)
			(xy 195.222622 -334.925924) (xy 195.222622 -334.84566) (xy 195.22201 -334.834098) (xy 195.211844 -334.813327)
			(xy 195.203064 -334.805782) (xy 195.182273 -334.789038) (xy 195.145142 -334.750684) (xy 195.11372 -334.707528)
			(xy 195.088621 -334.660414) (xy 195.070335 -334.61026) (xy 195.059218 -334.558048) (xy 195.055489 -334.504795)
			(xy 195.05922 -334.451543) (xy 195.070337 -334.39933) (xy 195.088625 -334.349177) (xy 195.113725 -334.302063)
			(xy 195.145148 -334.258908) (xy 195.18228 -334.220555) (xy 195.203064 -334.203802) (xy 195.211831 -334.196246)
			(xy 195.222009 -334.175482) (xy 195.222622 -334.163924) (xy 195.222622 -334.08366) (xy 195.22201 -334.072098)
			(xy 195.211844 -334.051327) (xy 195.203064 -334.043782) (xy 195.180564 -334.02561) (xy 195.140832 -333.983585)
			(xy 195.107896 -333.936046) (xy 195.082511 -333.884081) (xy 195.065257 -333.828881) (xy 195.056531 -333.771709)
			(xy 195.055998 -333.742792) (xy 195.056484 -333.715541) (xy 195.06424 -333.661593) (xy 195.079595 -333.609298)
			(xy 195.102237 -333.559721) (xy 195.131703 -333.513871) (xy 195.167394 -333.47268) (xy 195.208585 -333.436989)
			(xy 195.254435 -333.407523) (xy 195.304012 -333.384881) (xy 195.356307 -333.369526) (xy 195.410255 -333.36177)
			(xy 195.464757 -333.36177) (xy 195.518705 -333.369526) (xy 195.571 -333.384881) (xy 195.620577 -333.407523)
			(xy 195.666427 -333.436989) (xy 195.707618 -333.47268) (xy 195.743309 -333.513871) (xy 195.772775 -333.559721)
			(xy 195.795417 -333.609298) (xy 195.810772 -333.661593) (xy 195.818528 -333.715541) (xy 195.819014 -333.742792)
			(xy 195.818523 -333.77171) (xy 195.809793 -333.828884) (xy 195.792532 -333.884085) (xy 195.767135 -333.936047)
			(xy 195.734185 -333.98358) (xy 195.694437 -334.025594) (xy 195.671948 -334.043782) (xy 195.66319 -334.051347)
			(xy 195.653006 -334.072104) (xy 195.65239 -334.08366) (xy 195.65239 -334.163924) (xy 195.653008 -334.175486)
			(xy 195.663169 -334.196257) (xy 195.671948 -334.203802) (xy 195.692723 -334.220565) (xy 195.729852 -334.258917)
			(xy 195.761273 -334.302071) (xy 195.786372 -334.349183) (xy 195.804658 -334.399334) (xy 195.815775 -334.451545)
			(xy 195.819506 -334.504795) (xy 195.815777 -334.558046) (xy 195.804661 -334.610256) (xy 195.786376 -334.660408)
			(xy 195.761279 -334.707521) (xy 195.729859 -334.750675) (xy 195.69273 -334.789028) (xy 195.671948 -334.805782)
			(xy 195.66319 -334.813347) (xy 195.653006 -334.834104) (xy 195.65239 -334.84566) (xy 195.65239 -334.925924)
			(xy 195.653008 -334.937486) (xy 195.663169 -334.958257) (xy 195.671948 -334.965802) (xy 195.692723 -334.982565)
			(xy 195.729852 -335.020917) (xy 195.761273 -335.064071) (xy 195.786372 -335.111183) (xy 195.804658 -335.161334)
			(xy 195.815775 -335.213545) (xy 195.819506 -335.266795) (xy 195.815777 -335.320046) (xy 195.804661 -335.372256)
			(xy 195.786376 -335.422408) (xy 195.761279 -335.469521) (xy 195.729859 -335.512675) (xy 195.69273 -335.551028)
			(xy 195.671948 -335.567782) (xy 195.66319 -335.575347) (xy 195.653006 -335.596104) (xy 195.65239 -335.60766)
			(xy 195.65239 -335.687924) (xy 195.653008 -335.699486) (xy 195.663169 -335.720257) (xy 195.671948 -335.727802)
			(xy 195.694442 -335.74598) (xy 195.734175 -335.788004) (xy 195.767111 -335.835542) (xy 195.792497 -335.887505)
			(xy 195.809752 -335.942705) (xy 195.818479 -335.999875) (xy 195.819014 -336.028792) (xy 195.818528 -336.056043)
			(xy 195.810772 -336.109991) (xy 195.795417 -336.162286) (xy 195.772775 -336.211863) (xy 195.743309 -336.257713)
			(xy 195.707618 -336.298904) (xy 195.666427 -336.334595) (xy 195.620577 -336.364061) (xy 195.571 -336.386703)
			(xy 195.518705 -336.402058) (xy 195.464757 -336.409814) (xy 195.410255 -336.409814) (xy 195.356307 -336.402058)
			(xy 195.304012 -336.386703) (xy 195.254435 -336.364061) (xy 195.208585 -336.334595) (xy 195.167394 -336.298904)
			(xy 195.131703 -336.257713) (xy 195.102237 -336.211863) (xy 195.079595 -336.162286) (xy 195.06424 -336.109991)
			(xy 195.056484 -336.056043) (xy 195.055998 -336.028792) (xy 195.056583 -335.999878) (xy 195.065298 -335.942709)
			(xy 195.082543 -335.887512) (xy 195.107922 -335.83555) (xy 195.140854 -335.788014) (xy 195.180584 -335.745994)
			(xy 195.203064 -335.727802) (xy 195.211831 -335.720246) (xy 195.222009 -335.699482) (xy 195.222622 -335.687924)
			(xy 195.222622 -335.60766) (xy 195.22201 -335.596098) (xy 195.211844 -335.575327) (xy 195.203064 -335.567782)
			(xy 195.182273 -335.551038) (xy 195.145142 -335.512684) (xy 195.11372 -335.469528) (xy 195.088621 -335.422414)
			(xy 195.070335 -335.37226) (xy 195.059218 -335.320048) (xy 195.055489 -335.266795) (xy 193.381106 -335.266795)
			(xy 193.377377 -335.320046) (xy 193.366261 -335.372256) (xy 193.347976 -335.422408) (xy 193.322879 -335.469521)
			(xy 193.291459 -335.512675) (xy 193.25433 -335.551028) (xy 193.233548 -335.567782) (xy 193.22479 -335.575347)
			(xy 193.214606 -335.596104) (xy 193.21399 -335.60766) (xy 193.21399 -335.687924) (xy 193.214608 -335.699486)
			(xy 193.224769 -335.720257) (xy 193.233548 -335.727802) (xy 193.256042 -335.74598) (xy 193.295775 -335.788004)
			(xy 193.328711 -335.835542) (xy 193.354097 -335.887505) (xy 193.371352 -335.942705) (xy 193.380079 -335.999875)
			(xy 193.380614 -336.028792) (xy 193.380128 -336.056043) (xy 193.372372 -336.109991) (xy 193.357017 -336.162286)
			(xy 193.334375 -336.211863) (xy 193.304909 -336.257713) (xy 193.269218 -336.298904) (xy 193.228027 -336.334595)
			(xy 193.182177 -336.364061) (xy 193.1326 -336.386703) (xy 193.080305 -336.402058) (xy 193.026357 -336.409814)
			(xy 192.971855 -336.409814) (xy 192.917907 -336.402058) (xy 192.865612 -336.386703) (xy 192.816035 -336.364061)
			(xy 192.770185 -336.334595) (xy 192.728994 -336.298904) (xy 192.693303 -336.257713) (xy 192.663837 -336.211863)
			(xy 192.641195 -336.162286) (xy 192.62584 -336.109991) (xy 192.618084 -336.056043) (xy 192.617598 -336.028792)
			(xy 192.618183 -335.999878) (xy 192.626898 -335.942709) (xy 192.644143 -335.887512) (xy 192.669522 -335.83555)
			(xy 192.702454 -335.788014) (xy 192.742184 -335.745994) (xy 192.764664 -335.727802) (xy 192.773431 -335.720246)
			(xy 192.783609 -335.699482) (xy 192.784222 -335.687924) (xy 192.784222 -335.60766) (xy 192.78361 -335.596098)
			(xy 192.773444 -335.575327) (xy 192.764664 -335.567782) (xy 192.743873 -335.551038) (xy 192.706742 -335.512684)
			(xy 192.67532 -335.469528) (xy 192.650221 -335.422414) (xy 192.631935 -335.37226) (xy 192.620818 -335.320048)
			(xy 192.617089 -335.266795) (xy 189.721726 -335.266795) (xy 189.723506 -335.292195) (xy 189.719777 -335.345446)
			(xy 189.708661 -335.397656) (xy 189.690376 -335.447808) (xy 189.665279 -335.494921) (xy 189.633859 -335.538075)
			(xy 189.59673 -335.576428) (xy 189.575948 -335.593182) (xy 189.56719 -335.600747) (xy 189.557006 -335.621504)
			(xy 189.55639 -335.63306) (xy 189.55639 -335.713324) (xy 189.557008 -335.724886) (xy 189.567169 -335.745657)
			(xy 189.575948 -335.753202) (xy 189.598442 -335.77138) (xy 189.638175 -335.813404) (xy 189.671111 -335.860942)
			(xy 189.696497 -335.912905) (xy 189.713752 -335.968105) (xy 189.722479 -336.025275) (xy 189.723014 -336.054192)
			(xy 189.722528 -336.081443) (xy 189.714772 -336.135391) (xy 189.699417 -336.187686) (xy 189.676775 -336.237263)
			(xy 189.647309 -336.283113) (xy 189.611618 -336.324304) (xy 189.570427 -336.359995) (xy 189.524577 -336.389461)
			(xy 189.475 -336.412103) (xy 189.422705 -336.427458) (xy 189.368757 -336.435214) (xy 189.314255 -336.435214)
			(xy 189.260307 -336.427458) (xy 189.208012 -336.412103) (xy 189.158435 -336.389461) (xy 189.112585 -336.359995)
			(xy 189.071394 -336.324304) (xy 189.035703 -336.283113) (xy 189.006237 -336.237263) (xy 188.983595 -336.187686)
			(xy 188.96824 -336.135391) (xy 188.960484 -336.081443) (xy 188.959998 -336.054192) (xy 188.960583 -336.025278)
			(xy 188.969298 -335.968109) (xy 188.986543 -335.912912) (xy 189.011922 -335.86095) (xy 189.044854 -335.813414)
			(xy 189.084584 -335.771394) (xy 189.107064 -335.753202) (xy 189.115831 -335.745646) (xy 189.126009 -335.724882)
			(xy 189.126622 -335.713324) (xy 189.126622 -335.63306) (xy 189.12601 -335.621498) (xy 189.115844 -335.600727)
			(xy 189.107064 -335.593182) (xy 189.086273 -335.576438) (xy 189.049142 -335.538084) (xy 189.01772 -335.494928)
			(xy 188.992621 -335.447814) (xy 188.974335 -335.39766) (xy 188.963218 -335.345448) (xy 188.959489 -335.292195)
			(xy 187.259706 -335.292195) (xy 187.255977 -335.345446) (xy 187.244861 -335.397656) (xy 187.226576 -335.447808)
			(xy 187.201479 -335.494921) (xy 187.170059 -335.538075) (xy 187.13293 -335.576428) (xy 187.112148 -335.593182)
			(xy 187.10339 -335.600747) (xy 187.093206 -335.621504) (xy 187.09259 -335.63306) (xy 187.09259 -335.713324)
			(xy 187.093208 -335.724886) (xy 187.103369 -335.745657) (xy 187.112148 -335.753202) (xy 187.134642 -335.77138)
			(xy 187.174375 -335.813404) (xy 187.207311 -335.860942) (xy 187.232697 -335.912905) (xy 187.249952 -335.968105)
			(xy 187.258679 -336.025275) (xy 187.259214 -336.054192) (xy 187.258728 -336.081443) (xy 187.250972 -336.135391)
			(xy 187.235617 -336.187686) (xy 187.212975 -336.237263) (xy 187.183509 -336.283113) (xy 187.147818 -336.324304)
			(xy 187.106627 -336.359995) (xy 187.060777 -336.389461) (xy 187.0112 -336.412103) (xy 186.958905 -336.427458)
			(xy 186.904957 -336.435214) (xy 186.850455 -336.435214) (xy 186.796507 -336.427458) (xy 186.744212 -336.412103)
			(xy 186.694635 -336.389461) (xy 186.648785 -336.359995) (xy 186.607594 -336.324304) (xy 186.571903 -336.283113)
			(xy 186.542437 -336.237263) (xy 186.519795 -336.187686) (xy 186.50444 -336.135391) (xy 186.496684 -336.081443)
			(xy 186.496198 -336.054192) (xy 186.496783 -336.025278) (xy 186.505498 -335.968109) (xy 186.522743 -335.912912)
			(xy 186.548122 -335.86095) (xy 186.581054 -335.813414) (xy 186.620784 -335.771394) (xy 186.643264 -335.753202)
			(xy 186.652031 -335.745646) (xy 186.662209 -335.724882) (xy 186.662822 -335.713324) (xy 186.662822 -335.63306)
			(xy 186.66221 -335.621498) (xy 186.652044 -335.600727) (xy 186.643264 -335.593182) (xy 186.622473 -335.576438)
			(xy 186.585342 -335.538084) (xy 186.55392 -335.494928) (xy 186.528821 -335.447814) (xy 186.510535 -335.39766)
			(xy 186.499418 -335.345448) (xy 186.495689 -335.292195) (xy 183.602106 -335.292195) (xy 183.598377 -335.345446)
			(xy 183.587261 -335.397656) (xy 183.568976 -335.447808) (xy 183.543879 -335.494921) (xy 183.512459 -335.538075)
			(xy 183.47533 -335.576428) (xy 183.454548 -335.593182) (xy 183.44579 -335.600747) (xy 183.435606 -335.621504)
			(xy 183.43499 -335.63306) (xy 183.43499 -335.713324) (xy 183.435608 -335.724886) (xy 183.445769 -335.745657)
			(xy 183.454548 -335.753202) (xy 183.477042 -335.77138) (xy 183.516775 -335.813404) (xy 183.549711 -335.860942)
			(xy 183.575097 -335.912905) (xy 183.592352 -335.968105) (xy 183.601079 -336.025275) (xy 183.601614 -336.054192)
			(xy 183.601128 -336.081443) (xy 183.593372 -336.135391) (xy 183.578017 -336.187686) (xy 183.555375 -336.237263)
			(xy 183.525909 -336.283113) (xy 183.490218 -336.324304) (xy 183.449027 -336.359995) (xy 183.403177 -336.389461)
			(xy 183.3536 -336.412103) (xy 183.301305 -336.427458) (xy 183.247357 -336.435214) (xy 183.192855 -336.435214)
			(xy 183.138907 -336.427458) (xy 183.086612 -336.412103) (xy 183.037035 -336.389461) (xy 182.991185 -336.359995)
			(xy 182.949994 -336.324304) (xy 182.914303 -336.283113) (xy 182.884837 -336.237263) (xy 182.862195 -336.187686)
			(xy 182.84684 -336.135391) (xy 182.839084 -336.081443) (xy 182.838598 -336.054192) (xy 182.839183 -336.025278)
			(xy 182.847898 -335.968109) (xy 182.865143 -335.912912) (xy 182.890522 -335.86095) (xy 182.923454 -335.813414)
			(xy 182.963184 -335.771394) (xy 182.985664 -335.753202) (xy 182.994431 -335.745646) (xy 183.004609 -335.724882)
			(xy 183.005222 -335.713324) (xy 183.005222 -335.63306) (xy 183.00461 -335.621498) (xy 182.994444 -335.600727)
			(xy 182.985664 -335.593182) (xy 182.964873 -335.576438) (xy 182.927742 -335.538084) (xy 182.89632 -335.494928)
			(xy 182.871221 -335.447814) (xy 182.852935 -335.39766) (xy 182.841818 -335.345448) (xy 182.838089 -335.292195)
			(xy 181.180488 -335.292195) (xy 181.185375 -335.315145) (xy 181.189106 -335.368395) (xy 181.185377 -335.421646)
			(xy 181.174261 -335.473856) (xy 181.155976 -335.524008) (xy 181.130879 -335.571121) (xy 181.099459 -335.614275)
			(xy 181.06233 -335.652628) (xy 181.041548 -335.669382) (xy 181.03279 -335.676947) (xy 181.022606 -335.697704)
			(xy 181.02199 -335.70926) (xy 181.02199 -335.789524) (xy 181.022608 -335.801086) (xy 181.032769 -335.821857)
			(xy 181.041548 -335.829402) (xy 181.064042 -335.84758) (xy 181.103775 -335.889604) (xy 181.136711 -335.937142)
			(xy 181.162097 -335.989105) (xy 181.179352 -336.044305) (xy 181.188079 -336.101475) (xy 181.188614 -336.130392)
			(xy 181.188128 -336.157643) (xy 181.180372 -336.211591) (xy 181.165017 -336.263886) (xy 181.142375 -336.313463)
			(xy 181.112909 -336.359313) (xy 181.077218 -336.400504) (xy 181.036027 -336.436195) (xy 180.990177 -336.465661)
			(xy 180.9406 -336.488303) (xy 180.888305 -336.503658) (xy 180.834357 -336.511414) (xy 180.779855 -336.511414)
			(xy 180.725907 -336.503658) (xy 180.673612 -336.488303) (xy 180.624035 -336.465661) (xy 180.578185 -336.436195)
			(xy 180.536994 -336.400504) (xy 180.501303 -336.359313) (xy 180.471837 -336.313463) (xy 180.449195 -336.263886)
			(xy 180.43384 -336.211591) (xy 180.426084 -336.157643) (xy 180.425598 -336.130392) (xy 180.426183 -336.101478)
			(xy 180.434898 -336.044309) (xy 180.452143 -335.989112) (xy 180.477522 -335.93715) (xy 180.510454 -335.889614)
			(xy 180.550184 -335.847594) (xy 180.572664 -335.829402) (xy 180.581431 -335.821846) (xy 180.591609 -335.801082)
			(xy 180.592222 -335.789524) (xy 180.592222 -335.70926) (xy 180.59161 -335.697698) (xy 180.581444 -335.676927)
			(xy 180.572664 -335.669382) (xy 180.551873 -335.652638) (xy 180.514742 -335.614284) (xy 180.48332 -335.571128)
			(xy 180.458221 -335.524014) (xy 180.439935 -335.47386) (xy 180.428818 -335.421648) (xy 180.425089 -335.368395)
			(xy 177.526343 -335.368395) (xy 177.522277 -335.387489) (xy 177.503986 -335.437644) (xy 177.478883 -335.484759)
			(xy 177.447457 -335.527915) (xy 177.410321 -335.566269) (xy 177.389536 -335.583022) (xy 177.380758 -335.590568)
			(xy 177.370586 -335.611339) (xy 177.369978 -335.6229) (xy 177.369978 -335.703164) (xy 177.370577 -335.714728)
			(xy 177.380752 -335.735499) (xy 177.389536 -335.743042) (xy 177.412047 -335.7612) (xy 177.451779 -335.803228)
			(xy 177.484714 -335.85077) (xy 177.510097 -335.902737) (xy 177.527348 -335.95794) (xy 177.53607 -336.015114)
			(xy 177.536602 -336.044032) (xy 177.536116 -336.071283) (xy 177.52836 -336.125231) (xy 177.513005 -336.177526)
			(xy 177.490363 -336.227103) (xy 177.460897 -336.272953) (xy 177.425206 -336.314144) (xy 177.384015 -336.349835)
			(xy 177.338165 -336.379301) (xy 177.288588 -336.401943) (xy 177.236293 -336.417298) (xy 177.182345 -336.425054)
			(xy 177.127843 -336.425054) (xy 177.073895 -336.417298) (xy 177.0216 -336.401943) (xy 176.972023 -336.379301)
			(xy 176.926173 -336.349835) (xy 176.884982 -336.314144) (xy 176.849291 -336.272953) (xy 176.819825 -336.227103)
			(xy 176.797183 -336.177526) (xy 176.781828 -336.125231) (xy 176.774072 -336.071283) (xy 176.773586 -336.044032)
			(xy 176.774095 -336.015114) (xy 176.782821 -335.957941) (xy 176.800079 -335.902741) (xy 176.825472 -335.850778)
			(xy 176.858419 -335.803245) (xy 176.898164 -335.76123) (xy 176.920652 -335.743042) (xy 176.929399 -335.735467)
			(xy 176.939589 -335.714718) (xy 176.94021 -335.703164) (xy 176.94021 -335.6229) (xy 176.939636 -335.611333)
			(xy 176.929444 -335.590562) (xy 176.920652 -335.583022) (xy 176.899901 -335.56623) (xy 176.862772 -335.527881)
			(xy 176.831351 -335.484731) (xy 176.806252 -335.437622) (xy 176.787964 -335.387475) (xy 176.776846 -335.335267)
			(xy 176.773114 -335.28202) (xy 175.115518 -335.28202) (xy 175.120402 -335.304964) (xy 175.12413 -335.35822)
			(xy 175.120397 -335.411475) (xy 175.109277 -335.463689) (xy 175.090986 -335.513844) (xy 175.065883 -335.560959)
			(xy 175.034457 -335.604115) (xy 174.997321 -335.642469) (xy 174.976536 -335.659222) (xy 174.967758 -335.666768)
			(xy 174.957586 -335.687539) (xy 174.956978 -335.6991) (xy 174.956978 -335.779364) (xy 174.957577 -335.790928)
			(xy 174.967752 -335.811699) (xy 174.976536 -335.819242) (xy 174.999047 -335.8374) (xy 175.038779 -335.879428)
			(xy 175.071714 -335.92697) (xy 175.097097 -335.978937) (xy 175.114348 -336.03414) (xy 175.12307 -336.091314)
			(xy 175.123602 -336.120232) (xy 175.123116 -336.147483) (xy 175.11536 -336.201431) (xy 175.100005 -336.253726)
			(xy 175.077363 -336.303303) (xy 175.047897 -336.349153) (xy 175.012206 -336.390344) (xy 174.971015 -336.426035)
			(xy 174.925165 -336.455501) (xy 174.875588 -336.478143) (xy 174.823293 -336.493498) (xy 174.769345 -336.501254)
			(xy 174.714843 -336.501254) (xy 174.660895 -336.493498) (xy 174.6086 -336.478143) (xy 174.559023 -336.455501)
			(xy 174.513173 -336.426035) (xy 174.471982 -336.390344) (xy 174.436291 -336.349153) (xy 174.406825 -336.303303)
			(xy 174.384183 -336.253726) (xy 174.368828 -336.201431) (xy 174.361072 -336.147483) (xy 174.360586 -336.120232)
			(xy 174.361095 -336.091314) (xy 174.369821 -336.034141) (xy 174.387079 -335.978941) (xy 174.412472 -335.926978)
			(xy 174.445419 -335.879445) (xy 174.485164 -335.83743) (xy 174.507652 -335.819242) (xy 174.516399 -335.811667)
			(xy 174.526589 -335.790918) (xy 174.52721 -335.779364) (xy 174.52721 -335.6991) (xy 174.526636 -335.687533)
			(xy 174.516444 -335.666762) (xy 174.507652 -335.659222) (xy 174.486901 -335.64243) (xy 174.449772 -335.604081)
			(xy 174.418351 -335.560931) (xy 174.393252 -335.513822) (xy 174.374964 -335.463675) (xy 174.363846 -335.411467)
			(xy 174.360114 -335.35822) (xy 165.577278 -335.35822) (xy 160.67278 -340.262718) (xy 172.934884 -340.262718)
			(xy 172.93534 -340.235347) (xy 172.943157 -340.181167) (xy 172.958647 -340.128663) (xy 172.981492 -340.078916)
			(xy 173.01122 -340.03295) (xy 173.028864 -340.01202) (xy 173.03496 -340.004908) (xy 173.04131 -339.98789)
			(xy 173.04131 -339.902546) (xy 173.03496 -339.885528) (xy 173.028864 -339.878416) (xy 173.011239 -339.85747)
			(xy 172.981511 -339.811505) (xy 172.958662 -339.761761) (xy 172.943163 -339.709261) (xy 172.935332 -339.655084)
			(xy 172.93533 -339.600343) (xy 172.943157 -339.546165) (xy 172.958653 -339.493664) (xy 172.981498 -339.443919)
			(xy 173.011223 -339.397952) (xy 173.028864 -339.37702) (xy 173.03496 -339.369908) (xy 173.04131 -339.35289)
			(xy 173.04131 -339.267546) (xy 173.03496 -339.250528) (xy 173.028864 -339.243416) (xy 173.011239 -339.22247)
			(xy 172.981511 -339.176505) (xy 172.958662 -339.126761) (xy 172.943163 -339.074261) (xy 172.935332 -339.020084)
			(xy 172.93533 -338.965343) (xy 172.943157 -338.911165) (xy 172.958653 -338.858664) (xy 172.981498 -338.808919)
			(xy 173.011223 -338.762952) (xy 173.028864 -338.74202) (xy 173.03496 -338.734908) (xy 173.04131 -338.71789)
			(xy 173.04131 -338.632546) (xy 173.03496 -338.615528) (xy 173.028864 -338.608416) (xy 173.011239 -338.58747)
			(xy 172.981511 -338.541505) (xy 172.958662 -338.491761) (xy 172.943163 -338.439261) (xy 172.935332 -338.385084)
			(xy 172.93533 -338.330343) (xy 172.943157 -338.276165) (xy 172.958653 -338.223664) (xy 172.981498 -338.173919)
			(xy 173.011223 -338.127952) (xy 173.028864 -338.10702) (xy 173.03496 -338.099908) (xy 173.04131 -338.08289)
			(xy 173.04131 -337.997546) (xy 173.03496 -337.980528) (xy 173.028864 -337.973416) (xy 173.011239 -337.95247)
			(xy 172.981511 -337.906505) (xy 172.958662 -337.856761) (xy 172.943163 -337.804261) (xy 172.935332 -337.750084)
			(xy 172.93533 -337.695343) (xy 172.943157 -337.641165) (xy 172.958653 -337.588664) (xy 172.981498 -337.538919)
			(xy 173.011223 -337.492952) (xy 173.028864 -337.47202) (xy 173.03496 -337.464908) (xy 173.04131 -337.44789)
			(xy 173.04131 -337.362546) (xy 173.03496 -337.345528) (xy 173.028864 -337.338416) (xy 173.011213 -337.317493)
			(xy 172.981504 -337.271517) (xy 172.958671 -337.221767) (xy 172.943183 -337.169265) (xy 172.935357 -337.115088)
			(xy 172.934884 -337.087718) (xy 172.935372 -337.060466) (xy 172.943126 -337.006516) (xy 172.95848 -336.954219)
			(xy 172.98112 -336.90464) (xy 173.010585 -336.858787) (xy 173.046276 -336.817594) (xy 173.087466 -336.781901)
			(xy 173.133317 -336.752432) (xy 173.182895 -336.729789) (xy 173.235191 -336.714432) (xy 173.28914 -336.706674)
			(xy 173.316392 -336.70621) (xy 173.344029 -336.706721) (xy 173.398725 -336.714708) (xy 173.451696 -336.730501)
			(xy 173.501835 -336.75377) (xy 173.548093 -336.784028) (xy 173.569122 -336.801968) (xy 173.576234 -336.808064)
			(xy 173.593506 -336.814668) (xy 173.679358 -336.814668) (xy 173.69663 -336.808064) (xy 173.703742 -336.801968)
			(xy 173.724753 -336.784003) (xy 173.771009 -336.753732) (xy 173.821151 -336.730458) (xy 173.874129 -336.714669)
			(xy 173.928832 -336.706697) (xy 173.956472 -336.70621) (xy 173.983725 -336.706681) (xy 174.037677 -336.714435)
			(xy 174.089975 -336.729788) (xy 174.139557 -336.752429) (xy 174.185411 -336.781896) (xy 174.226604 -336.817589)
			(xy 174.262298 -336.858781) (xy 174.291766 -336.904635) (xy 174.314408 -336.954215) (xy 174.329763 -337.006514)
			(xy 174.337518 -337.060465) (xy 174.33798 -337.087718) (xy 174.337529 -337.115089) (xy 174.329709 -337.169269)
			(xy 174.314216 -337.221772) (xy 174.291371 -337.271519) (xy 174.261643 -337.317485) (xy 174.244 -337.338416)
			(xy 174.237904 -337.345528) (xy 174.231554 -337.362546) (xy 174.231554 -337.44789) (xy 174.237904 -337.464908)
			(xy 174.244 -337.47202) (xy 174.261657 -337.492939) (xy 174.291379 -337.53891) (xy 174.314222 -337.588659)
			(xy 174.329716 -337.641162) (xy 174.337542 -337.695342) (xy 174.33754 -337.750085) (xy 174.32971 -337.804264)
			(xy 174.314212 -337.856767) (xy 174.291366 -337.906514) (xy 174.261641 -337.952483) (xy 174.244 -337.973416)
			(xy 174.237904 -337.980528) (xy 174.231554 -337.997546) (xy 174.231554 -338.08289) (xy 174.237904 -338.099908)
			(xy 174.244 -338.10702) (xy 174.261657 -338.127939) (xy 174.291379 -338.17391) (xy 174.314222 -338.223659)
			(xy 174.329716 -338.276162) (xy 174.337542 -338.330342) (xy 174.33754 -338.385085) (xy 174.32971 -338.439264)
			(xy 174.314212 -338.491767) (xy 174.291366 -338.541514) (xy 174.261641 -338.587483) (xy 174.244 -338.608416)
			(xy 174.237904 -338.615528) (xy 174.231554 -338.632546) (xy 174.231554 -338.71789) (xy 174.237904 -338.734908)
			(xy 174.244 -338.74202) (xy 174.261657 -338.762939) (xy 174.291379 -338.80891) (xy 174.314222 -338.858659)
			(xy 174.329716 -338.911162) (xy 174.337542 -338.965342) (xy 174.33754 -339.020085) (xy 174.32971 -339.074264)
			(xy 174.314212 -339.126767) (xy 174.291366 -339.176514) (xy 174.261641 -339.222483) (xy 174.244 -339.243416)
			(xy 174.237904 -339.250528) (xy 174.231554 -339.267546) (xy 174.231554 -339.35289) (xy 174.237904 -339.369908)
			(xy 174.244 -339.37702) (xy 174.261657 -339.397939) (xy 174.291379 -339.44391) (xy 174.314222 -339.493659)
			(xy 174.329716 -339.546162) (xy 174.337542 -339.600342) (xy 174.33754 -339.655085) (xy 174.32971 -339.709264)
			(xy 174.314212 -339.761767) (xy 174.291366 -339.811514) (xy 174.261641 -339.857483) (xy 174.244 -339.878416)
			(xy 174.237904 -339.885528) (xy 174.231554 -339.902546) (xy 174.231554 -339.98789) (xy 174.237904 -340.004908)
			(xy 174.244 -340.01202) (xy 174.261615 -340.032971) (xy 174.291331 -340.078939) (xy 174.314171 -340.128682)
			(xy 174.329668 -340.181178) (xy 174.337502 -340.23535) (xy 174.33798 -340.262718) (xy 174.337941 -340.265258)
			(xy 177.384964 -340.265258) (xy 177.385448 -340.237888) (xy 177.393259 -340.183709) (xy 177.408743 -340.131206)
			(xy 177.431581 -340.081459) (xy 177.461304 -340.035492) (xy 177.478944 -340.01456) (xy 177.48504 -340.007448)
			(xy 177.49139 -339.99043) (xy 177.49139 -339.905086) (xy 177.48504 -339.888068) (xy 177.478944 -339.880956)
			(xy 177.461261 -339.860057) (xy 177.431537 -339.814084) (xy 177.408693 -339.764332) (xy 177.393199 -339.711825)
			(xy 177.385374 -339.657641) (xy 177.385379 -339.602896) (xy 177.393213 -339.548713) (xy 177.408715 -339.496209)
			(xy 177.431568 -339.446461) (xy 177.4613 -339.400492) (xy 177.478944 -339.37956) (xy 177.48504 -339.372448)
			(xy 177.49139 -339.35543) (xy 177.49139 -339.270086) (xy 177.48504 -339.253068) (xy 177.478944 -339.245956)
			(xy 177.461261 -339.225057) (xy 177.431537 -339.179084) (xy 177.408693 -339.129332) (xy 177.393199 -339.076825)
			(xy 177.385374 -339.022641) (xy 177.385379 -338.967896) (xy 177.393213 -338.913713) (xy 177.408715 -338.861209)
			(xy 177.431568 -338.811461) (xy 177.4613 -338.765492) (xy 177.478944 -338.74456) (xy 177.48504 -338.737448)
			(xy 177.49139 -338.72043) (xy 177.49139 -338.635086) (xy 177.48504 -338.618068) (xy 177.478944 -338.610956)
			(xy 177.461261 -338.590057) (xy 177.431537 -338.544084) (xy 177.408693 -338.494332) (xy 177.393199 -338.441825)
			(xy 177.385374 -338.387641) (xy 177.385379 -338.332896) (xy 177.393213 -338.278713) (xy 177.408715 -338.226209)
			(xy 177.431568 -338.176461) (xy 177.4613 -338.130492) (xy 177.478944 -338.10956) (xy 177.48504 -338.102448)
			(xy 177.49139 -338.08543) (xy 177.49139 -338.000086) (xy 177.48504 -337.983068) (xy 177.478944 -337.975956)
			(xy 177.461261 -337.955057) (xy 177.431537 -337.909084) (xy 177.408693 -337.859332) (xy 177.393199 -337.806825)
			(xy 177.385374 -337.752641) (xy 177.385379 -337.697896) (xy 177.393213 -337.643713) (xy 177.408715 -337.591209)
			(xy 177.431568 -337.541461) (xy 177.4613 -337.495492) (xy 177.478944 -337.47456) (xy 177.48504 -337.467448)
			(xy 177.49139 -337.45043) (xy 177.49139 -337.365086) (xy 177.48504 -337.348068) (xy 177.478944 -337.340956)
			(xy 177.461325 -337.320008) (xy 177.431608 -337.27404) (xy 177.408768 -337.224297) (xy 177.393272 -337.171799)
			(xy 177.38544 -337.117626) (xy 177.384964 -337.090258) (xy 177.385439 -337.063007) (xy 177.3932 -337.00906)
			(xy 177.408559 -336.956767) (xy 177.431203 -336.907192) (xy 177.460671 -336.861343) (xy 177.496364 -336.820154)
			(xy 177.537554 -336.784463) (xy 177.583404 -336.754996) (xy 177.63298 -336.732354) (xy 177.685274 -336.716997)
			(xy 177.739221 -336.709238) (xy 177.766472 -336.70875) (xy 177.794111 -336.709229) (xy 177.848806 -336.717226)
			(xy 177.901777 -336.733027) (xy 177.951916 -336.756303) (xy 177.998173 -336.786566) (xy 178.019202 -336.804508)
			(xy 178.026314 -336.810604) (xy 178.043586 -336.817208) (xy 178.129438 -336.817208) (xy 178.14671 -336.810604)
			(xy 178.153822 -336.804508) (xy 178.174846 -336.786558) (xy 178.221097 -336.756284) (xy 178.271237 -336.733006)
			(xy 178.324212 -336.717214) (xy 178.378912 -336.709238) (xy 178.406552 -336.70875) (xy 178.433802 -336.7093)
			(xy 178.487747 -336.717049) (xy 178.540041 -336.732397) (xy 178.589618 -336.755031) (xy 178.63547 -336.78449)
			(xy 178.676662 -336.820175) (xy 178.712356 -336.861358) (xy 178.741826 -336.907203) (xy 178.764472 -336.956774)
			(xy 178.779832 -337.009065) (xy 178.787594 -337.063008) (xy 178.78806 -337.090258) (xy 178.787579 -337.117628)
			(xy 178.779766 -337.171807) (xy 178.764281 -337.22431) (xy 178.741443 -337.274057) (xy 178.71172 -337.320024)
			(xy 178.69408 -337.340956) (xy 178.687984 -337.348068) (xy 178.681634 -337.365086) (xy 178.681634 -337.45043)
			(xy 178.687984 -337.467448) (xy 178.69408 -337.47456) (xy 178.711679 -337.495526) (xy 178.741405 -337.541488)
			(xy 178.764253 -337.591229) (xy 178.779752 -337.643726) (xy 178.787584 -337.6979) (xy 178.787589 -337.752637)
			(xy 178.779765 -337.806812) (xy 178.764275 -337.859312) (xy 178.741436 -337.909056) (xy 178.711717 -337.955023)
			(xy 178.69408 -337.975956) (xy 178.687984 -337.983068) (xy 178.681634 -338.000086) (xy 178.681634 -338.08543)
			(xy 178.687984 -338.102448) (xy 178.69408 -338.10956) (xy 178.711679 -338.130526) (xy 178.741405 -338.176488)
			(xy 178.764253 -338.226229) (xy 178.779752 -338.278726) (xy 178.787584 -338.3329) (xy 178.787589 -338.387637)
			(xy 178.779765 -338.441812) (xy 178.764275 -338.494312) (xy 178.741436 -338.544056) (xy 178.711717 -338.590023)
			(xy 178.69408 -338.610956) (xy 178.687984 -338.618068) (xy 178.681634 -338.635086) (xy 178.681634 -338.72043)
			(xy 178.687984 -338.737448) (xy 178.69408 -338.74456) (xy 178.711679 -338.765526) (xy 178.741405 -338.811488)
			(xy 178.764253 -338.861229) (xy 178.779752 -338.913726) (xy 178.787584 -338.9679) (xy 178.787589 -339.022637)
			(xy 178.779765 -339.076812) (xy 178.764275 -339.129312) (xy 178.741436 -339.179056) (xy 178.711717 -339.225023)
			(xy 178.69408 -339.245956) (xy 178.687984 -339.253068) (xy 178.681634 -339.270086) (xy 178.681634 -339.35543)
			(xy 178.687984 -339.372448) (xy 178.69408 -339.37956) (xy 178.711679 -339.400526) (xy 178.741405 -339.446488)
			(xy 178.764253 -339.496229) (xy 178.779752 -339.548726) (xy 178.787584 -339.6029) (xy 178.787589 -339.657637)
			(xy 178.779765 -339.711812) (xy 178.764275 -339.764312) (xy 178.741436 -339.814056) (xy 178.711717 -339.860023)
			(xy 178.69408 -339.880956) (xy 178.687984 -339.888068) (xy 178.681634 -339.905086) (xy 178.681634 -339.99043)
			(xy 178.687984 -340.007448) (xy 178.69408 -340.01456) (xy 178.711711 -340.035499) (xy 178.741424 -340.08147)
			(xy 178.764262 -340.131215) (xy 178.779755 -340.183715) (xy 178.787585 -340.237889) (xy 178.78806 -340.265258)
			(xy 178.787627 -340.291269) (xy 178.780551 -340.342808) (xy 178.766539 -340.392908) (xy 178.74585 -340.44064)
			(xy 178.718867 -340.485118) (xy 178.686092 -340.525518) (xy 178.648133 -340.56109) (xy 178.605692 -340.591175)
			(xy 178.582828 -340.603586) (xy 178.572668 -340.60892) (xy 178.559206 -340.6267) (xy 178.53787 -340.725506)
			(xy 178.54295 -340.74735) (xy 178.549808 -340.756494) (xy 178.565166 -340.77672) (xy 178.590971 -340.820461)
			(xy 178.610745 -340.867239) (xy 178.624135 -340.916227) (xy 178.630907 -340.96656) (xy 178.631342 -340.991952)
			(xy 178.630862 -341.019322) (xy 178.62305 -341.073501) (xy 178.607565 -341.126004) (xy 178.584726 -341.175752)
			(xy 178.555003 -341.221718) (xy 178.537362 -341.24265) (xy 178.531266 -341.249762) (xy 178.524916 -341.26678)
			(xy 178.524916 -341.352124) (xy 178.531266 -341.369142) (xy 178.537362 -341.376254) (xy 178.554987 -341.397197)
			(xy 178.584702 -341.443167) (xy 178.607542 -341.492911) (xy 178.623036 -341.545409) (xy 178.630867 -341.599584)
			(xy 178.631342 -341.626952) (xy 178.630856 -341.654203) (xy 178.6231 -341.708151) (xy 178.607745 -341.760446)
			(xy 178.585103 -341.810023) (xy 178.555637 -341.855873) (xy 178.519946 -341.897064) (xy 178.478755 -341.932755)
			(xy 178.432905 -341.962221) (xy 178.383328 -341.984863) (xy 178.331033 -342.000218) (xy 178.277085 -342.007974)
			(xy 178.222583 -342.007974) (xy 178.168635 -342.000218) (xy 178.11634 -341.984863) (xy 178.066763 -341.962221)
			(xy 178.020913 -341.932755) (xy 177.979722 -341.897064) (xy 177.944031 -341.855873) (xy 177.914565 -341.810023)
			(xy 177.891923 -341.760446) (xy 177.876568 -341.708151) (xy 177.868812 -341.654203) (xy 177.868326 -341.626952)
			(xy 177.868816 -341.599583) (xy 177.876627 -341.545404) (xy 177.89211 -341.492901) (xy 177.914947 -341.443154)
			(xy 177.944667 -341.397186) (xy 177.962306 -341.376254) (xy 177.968402 -341.369142) (xy 177.974752 -341.352124)
			(xy 177.974752 -341.26678) (xy 177.968402 -341.249762) (xy 177.962306 -341.24265) (xy 177.944678 -341.221709)
			(xy 177.914964 -341.175739) (xy 177.892126 -341.125994) (xy 177.876632 -341.073495) (xy 177.868801 -341.019321)
			(xy 177.868326 -340.991952) (xy 177.868849 -340.963834) (xy 177.877098 -340.908206) (xy 177.893425 -340.854393)
			(xy 177.917476 -340.803559) (xy 177.94873 -340.756808) (xy 177.98651 -340.715152) (xy 178.029996 -340.679494)
			(xy 178.078245 -340.650608) (xy 178.104038 -340.6394) (xy 178.115319 -340.634138) (xy 178.13131 -340.615104)
			(xy 178.134518 -340.603078) (xy 178.146964 -340.544912) (xy 178.138074 -340.53653) (xy 178.130703 -340.529904)
			(xy 178.112412 -340.52232) (xy 178.102514 -340.521798) (xy 178.07051 -340.521798) (xy 178.060603 -340.522268)
			(xy 178.042302 -340.52987) (xy 178.03495 -340.53653) (xy 178.013388 -340.557093) (xy 177.965026 -340.591891)
			(xy 177.911841 -340.618746) (xy 177.855126 -340.637003) (xy 177.796263 -340.646218) (xy 177.766472 -340.646766)
			(xy 177.739217 -340.646371) (xy 177.685261 -340.638609) (xy 177.632959 -340.623247) (xy 177.583376 -340.600599)
			(xy 177.537521 -340.571124) (xy 177.496328 -340.535423) (xy 177.460634 -340.494223) (xy 177.431168 -340.448362)
			(xy 177.408528 -340.398775) (xy 177.393176 -340.346471) (xy 177.385424 -340.292514) (xy 177.384964 -340.265258)
			(xy 174.337941 -340.265258) (xy 174.337562 -340.289973) (xy 174.329802 -340.343927) (xy 174.314442 -340.396227)
			(xy 174.291795 -340.445809) (xy 174.262323 -340.491664) (xy 174.226624 -340.532857) (xy 174.185427 -340.56855)
			(xy 174.139569 -340.598017) (xy 174.089984 -340.620658) (xy 174.037682 -340.636011) (xy 173.983727 -340.643765)
			(xy 173.956472 -340.644226) (xy 173.928834 -340.643727) (xy 173.874139 -340.635736) (xy 173.821168 -340.61994)
			(xy 173.771029 -340.596668) (xy 173.724771 -340.566409) (xy 173.703742 -340.548468) (xy 173.69663 -340.542372)
			(xy 173.679358 -340.535768) (xy 173.593506 -340.535768) (xy 173.576234 -340.542372) (xy 173.569122 -340.548468)
			(xy 173.567598 -340.549738) (xy 173.559605 -340.557488) (xy 173.550626 -340.577833) (xy 173.551046 -340.600068)
			(xy 173.560787 -340.62006) (xy 173.578039 -340.634094) (xy 173.58868 -340.637368) (xy 173.615784 -340.64465)
			(xy 173.667598 -340.666219) (xy 173.715691 -340.695148) (xy 173.759026 -340.730812) (xy 173.796667 -340.772442)
			(xy 173.827801 -340.819138) (xy 173.851756 -340.869893) (xy 173.868014 -340.92361) (xy 173.876226 -340.97913)
			(xy 173.876716 -341.007192) (xy 173.876266 -341.034563) (xy 173.868447 -341.088744) (xy 173.852956 -341.141248)
			(xy 173.83011 -341.190994) (xy 173.80038 -341.23696) (xy 173.782736 -341.25789) (xy 173.77664 -341.265002)
			(xy 173.77029 -341.28202) (xy 173.77029 -341.367364) (xy 173.77664 -341.384382) (xy 173.782736 -341.391494)
			(xy 173.800391 -341.412413) (xy 173.8301 -341.45839) (xy 173.852932 -341.508141) (xy 173.868419 -341.560644)
			(xy 173.876244 -341.614822) (xy 173.876716 -341.642192) (xy 173.87623 -341.669443) (xy 173.868474 -341.723391)
			(xy 173.853119 -341.775686) (xy 173.830477 -341.825263) (xy 173.801011 -341.871113) (xy 173.76532 -341.912304)
			(xy 173.724129 -341.947995) (xy 173.678279 -341.977461) (xy 173.628702 -342.000103) (xy 173.576407 -342.015458)
			(xy 173.522459 -342.023214) (xy 173.467957 -342.023214) (xy 173.414009 -342.015458) (xy 173.361714 -342.000103)
			(xy 173.312137 -341.977461) (xy 173.266287 -341.947995) (xy 173.225096 -341.912304) (xy 173.189405 -341.871113)
			(xy 173.159939 -341.825263) (xy 173.137297 -341.775686) (xy 173.121942 -341.723391) (xy 173.114186 -341.669443)
			(xy 173.1137 -341.642192) (xy 173.114161 -341.614822) (xy 173.12198 -341.560642) (xy 173.137471 -341.508139)
			(xy 173.160313 -341.458392) (xy 173.190039 -341.412426) (xy 173.20768 -341.391494) (xy 173.213776 -341.384382)
			(xy 173.220126 -341.367364) (xy 173.220126 -341.28202) (xy 173.213776 -341.265002) (xy 173.20768 -341.25789)
			(xy 173.19002 -341.236975) (xy 173.160312 -341.190997) (xy 173.13748 -341.141245) (xy 173.121994 -341.088741)
			(xy 173.114171 -341.034562) (xy 173.1137 -341.007192) (xy 173.11411 -340.981285) (xy 173.121135 -340.929949)
			(xy 173.135041 -340.880036) (xy 173.155572 -340.832463) (xy 173.182352 -340.788105) (xy 173.198282 -340.76767)
			(xy 173.205902 -340.758272) (xy 173.210982 -340.735412) (xy 173.186598 -340.633812) (xy 173.171612 -340.616032)
			(xy 173.16069 -340.610952) (xy 173.135824 -340.599335) (xy 173.089438 -340.569997) (xy 173.047738 -340.534313)
			(xy 173.011585 -340.493018) (xy 172.981725 -340.446967) (xy 172.958776 -340.397111) (xy 172.943213 -340.344479)
			(xy 172.935356 -340.29016) (xy 172.934884 -340.262718) (xy 160.67278 -340.262718) (xy 159.931608 -341.00389)
			(xy 159.92488 -341.011344) (xy 159.917311 -341.029924) (xy 159.916876 -341.039958) (xy 159.916876 -341.626952)
			(xy 170.9547 -341.626952) (xy 170.955197 -341.599583) (xy 170.963007 -341.545405) (xy 170.978489 -341.492902)
			(xy 171.001324 -341.443155) (xy 171.031042 -341.397187) (xy 171.04868 -341.376254) (xy 171.054776 -341.369142)
			(xy 171.061126 -341.352124) (xy 171.061126 -341.26678) (xy 171.054776 -341.249762) (xy 171.04868 -341.24265)
			(xy 171.031048 -341.221712) (xy 171.001336 -341.175741) (xy 170.978499 -341.125995) (xy 170.963006 -341.073495)
			(xy 170.955175 -341.019321) (xy 170.9547 -340.991952) (xy 170.955186 -340.964701) (xy 170.962942 -340.910753)
			(xy 170.978297 -340.858458) (xy 171.000939 -340.808881) (xy 171.030405 -340.763031) (xy 171.066096 -340.72184)
			(xy 171.107287 -340.686149) (xy 171.153137 -340.656683) (xy 171.202714 -340.634041) (xy 171.255009 -340.618686)
			(xy 171.308957 -340.61093) (xy 171.363459 -340.61093) (xy 171.417407 -340.618686) (xy 171.469702 -340.634041)
			(xy 171.519279 -340.656683) (xy 171.565129 -340.686149) (xy 171.60632 -340.72184) (xy 171.642011 -340.763031)
			(xy 171.671477 -340.808881) (xy 171.694119 -340.858458) (xy 171.709474 -340.910753) (xy 171.71723 -340.964701)
			(xy 171.717716 -340.991952) (xy 171.717242 -341.019322) (xy 171.709429 -341.073502) (xy 171.693943 -341.126006)
			(xy 171.671103 -341.175753) (xy 171.641378 -341.221719) (xy 171.623736 -341.24265) (xy 171.61764 -341.249762)
			(xy 171.61129 -341.26678) (xy 171.61129 -341.352124) (xy 171.61764 -341.369142) (xy 171.623736 -341.376254)
			(xy 171.641373 -341.397188) (xy 171.671084 -341.443161) (xy 171.693919 -341.492908) (xy 171.709411 -341.545408)
			(xy 171.717241 -341.599583) (xy 171.717716 -341.626952) (xy 171.71723 -341.654203) (xy 171.709474 -341.708151)
			(xy 171.694119 -341.760446) (xy 171.671477 -341.810023) (xy 171.642011 -341.855873) (xy 171.60632 -341.897064)
			(xy 171.565129 -341.932755) (xy 171.519279 -341.962221) (xy 171.469702 -341.984863) (xy 171.417407 -342.000218)
			(xy 171.363459 -342.007974) (xy 171.308957 -342.007974) (xy 171.255009 -342.000218) (xy 171.202714 -341.984863)
			(xy 171.153137 -341.962221) (xy 171.107287 -341.932755) (xy 171.066096 -341.897064) (xy 171.030405 -341.855873)
			(xy 171.000939 -341.810023) (xy 170.978297 -341.760446) (xy 170.962942 -341.708151) (xy 170.955186 -341.654203)
			(xy 170.9547 -341.626952) (xy 159.916876 -341.626952) (xy 159.916876 -342.46058) (xy 159.917414 -342.472213)
			(xy 159.927601 -342.493124) (xy 159.936434 -342.500712) (xy 160.00984 -342.5571) (xy 160.032446 -342.561672)
			(xy 160.04413 -342.558624) (xy 160.067962 -342.552797) (xy 160.116627 -342.546558) (xy 160.141158 -342.546178)
			(xy 160.168409 -342.546694) (xy 160.222357 -342.554445) (xy 160.274653 -342.569795) (xy 160.324233 -342.592432)
			(xy 160.370085 -342.621894) (xy 160.411278 -342.657582) (xy 160.446972 -342.69877) (xy 160.476441 -342.744618)
			(xy 160.499085 -342.794194) (xy 160.514443 -342.846488) (xy 160.522202 -342.900435) (xy 160.522666 -342.927686)
			(xy 160.52215 -342.956603) (xy 160.513423 -343.013775) (xy 160.496165 -343.068975) (xy 160.470773 -343.120936)
			(xy 160.437828 -343.16847) (xy 160.398086 -343.210486) (xy 160.3756 -343.228676) (xy 160.366853 -343.236253)
			(xy 160.356662 -343.257) (xy 160.356042 -343.268554) (xy 160.356042 -343.348818) (xy 160.356588 -343.360389)
			(xy 160.366798 -343.381161) (xy 160.3756 -343.388696) (xy 160.398082 -343.406889) (xy 160.437817 -343.448909)
			(xy 160.470756 -343.496443) (xy 160.496145 -343.548404) (xy 160.513401 -343.603601) (xy 160.522131 -343.66077)
			(xy 160.522666 -343.689686) (xy 160.522232 -343.71694) (xy 160.514475 -343.770895) (xy 160.499119 -343.823196)
			(xy 160.487012 -343.849706) (xy 160.851086 -343.849706) (xy 160.855157 -343.794084) (xy 160.867283 -343.739647)
			(xy 160.887206 -343.687556) (xy 160.914502 -343.638921) (xy 160.948588 -343.594778) (xy 160.988737 -343.556069)
			(xy 161.034095 -343.523618) (xy 161.083695 -343.498117) (xy 161.136479 -343.48011) (xy 161.191322 -343.46998)
			(xy 161.247056 -343.467943) (xy 161.302493 -343.474043) (xy 161.35645 -343.488149) (xy 161.407779 -343.509961)
			(xy 161.455385 -343.539015) (xy 161.498253 -343.57469) (xy 161.53547 -343.616227) (xy 161.566243 -343.66274)
			(xy 161.589915 -343.713237) (xy 161.605983 -343.766644) (xy 161.614103 -343.82182) (xy 161.614612 -343.849706)
			(xy 161.614103 -343.877592) (xy 161.605983 -343.932768) (xy 161.589915 -343.986175) (xy 161.566243 -344.036672)
			(xy 161.53547 -344.083185) (xy 161.498253 -344.124722) (xy 161.455385 -344.160397) (xy 161.407779 -344.189451)
			(xy 161.35645 -344.211263) (xy 161.302493 -344.225369) (xy 161.247056 -344.231469) (xy 161.191322 -344.229432)
			(xy 161.136479 -344.219302) (xy 161.083695 -344.201295) (xy 161.034095 -344.175794) (xy 160.988737 -344.143343)
			(xy 160.948588 -344.104634) (xy 160.914502 -344.060491) (xy 160.887206 -344.011856) (xy 160.867283 -343.959765)
			(xy 160.855157 -343.905328) (xy 160.851086 -343.849706) (xy 160.487012 -343.849706) (xy 160.476475 -343.872778)
			(xy 160.447005 -343.918634) (xy 160.411308 -343.959828) (xy 160.370111 -343.995521) (xy 160.324254 -344.024988)
			(xy 160.274669 -344.047629) (xy 160.222367 -344.062981) (xy 160.168412 -344.070734) (xy 160.141158 -344.071194)
			(xy 160.114654 -344.070692) (xy 160.062157 -344.063336) (xy 160.011184 -344.048787) (xy 159.962715 -344.027323)
			(xy 159.917682 -343.999359) (xy 159.876953 -343.965431) (xy 159.841311 -343.926193) (xy 159.811442 -343.882401)
			(xy 159.799274 -343.85885) (xy 159.795464 -343.85123) (xy 159.101536 -343.157302) (xy 159.084294 -343.139194)
			(xy 159.05648 -343.097654) (xy 159.037302 -343.051487) (xy 159.027499 -343.002465) (xy 159.02686 -342.97747)
			(xy 158.550864 -342.97747) (xy 158.550864 -345.078304) (xy 160.503106 -345.078304) (xy 160.507177 -345.022682)
			(xy 160.519303 -344.968245) (xy 160.539226 -344.916154) (xy 160.566522 -344.867519) (xy 160.600608 -344.823376)
			(xy 160.640757 -344.784667) (xy 160.686115 -344.752216) (xy 160.735715 -344.726715) (xy 160.788499 -344.708708)
			(xy 160.843342 -344.698578) (xy 160.899076 -344.696541) (xy 160.954513 -344.702641) (xy 161.00847 -344.716747)
			(xy 161.059799 -344.738559) (xy 161.107405 -344.767613) (xy 161.150273 -344.803288) (xy 161.18749 -344.844825)
			(xy 161.218263 -344.891338) (xy 161.241935 -344.941835) (xy 161.258003 -344.995242) (xy 161.266123 -345.050418)
			(xy 161.266632 -345.078304) (xy 161.266123 -345.10619) (xy 161.258003 -345.161366) (xy 161.241935 -345.214773)
			(xy 161.218263 -345.26527) (xy 161.18749 -345.311783) (xy 161.150273 -345.35332) (xy 161.107405 -345.388995)
			(xy 161.059799 -345.418049) (xy 161.00847 -345.439861) (xy 160.954513 -345.453967) (xy 160.899076 -345.460067)
			(xy 160.843342 -345.45803) (xy 160.788499 -345.4479) (xy 160.735715 -345.429893) (xy 160.686115 -345.404392)
			(xy 160.640757 -345.371941) (xy 160.600608 -345.333232) (xy 160.566522 -345.289089) (xy 160.539226 -345.240454)
			(xy 160.519303 -345.188363) (xy 160.507177 -345.133926) (xy 160.503106 -345.078304) (xy 158.550864 -345.078304)
			(xy 158.550864 -346.211652) (xy 165.219634 -346.211652) (xy 165.22012 -346.184401) (xy 165.227876 -346.130453)
			(xy 165.243231 -346.078158) (xy 165.265873 -346.028581) (xy 165.295339 -345.982731) (xy 165.33103 -345.94154)
			(xy 165.372221 -345.905849) (xy 165.418071 -345.876383) (xy 165.467648 -345.853741) (xy 165.519943 -345.838386)
			(xy 165.573891 -345.83063) (xy 165.628393 -345.83063) (xy 165.682341 -345.838386) (xy 165.734636 -345.853741)
			(xy 165.784213 -345.876383) (xy 165.830063 -345.905849) (xy 165.871254 -345.94154) (xy 165.906945 -345.982731)
			(xy 165.936411 -346.028581) (xy 165.959053 -346.078158) (xy 165.974408 -346.130453) (xy 165.982164 -346.184401)
			(xy 165.98265 -346.211652) (xy 165.982081 -346.242062) (xy 165.972456 -346.302076) (xy 167.694608 -346.302076)
			(xy 167.698679 -346.246454) (xy 167.710805 -346.192017) (xy 167.730728 -346.139926) (xy 167.758024 -346.091291)
			(xy 167.79211 -346.047148) (xy 167.832259 -346.008439) (xy 167.877617 -345.975988) (xy 167.927217 -345.950487)
			(xy 167.980001 -345.93248) (xy 168.034844 -345.92235) (xy 168.090578 -345.920313) (xy 168.146015 -345.926413)
			(xy 168.199972 -345.940519) (xy 168.251301 -345.962331) (xy 168.298907 -345.991385) (xy 168.341775 -346.02706)
			(xy 168.378992 -346.068597) (xy 168.409765 -346.11511) (xy 168.433437 -346.165607) (xy 168.449505 -346.219014)
			(xy 168.457625 -346.27419) (xy 168.458134 -346.302076) (xy 168.457625 -346.329962) (xy 168.449505 -346.385138)
			(xy 168.433437 -346.438545) (xy 168.409765 -346.489042) (xy 168.378992 -346.535555) (xy 168.341775 -346.577092)
			(xy 168.298907 -346.612767) (xy 168.251301 -346.641821) (xy 168.199972 -346.663633) (xy 168.146015 -346.677739)
			(xy 168.090578 -346.683839) (xy 168.034844 -346.681802) (xy 167.980001 -346.671672) (xy 167.927217 -346.653665)
			(xy 167.877617 -346.628164) (xy 167.832259 -346.595713) (xy 167.79211 -346.557004) (xy 167.758024 -346.512861)
			(xy 167.730728 -346.464226) (xy 167.710805 -346.412135) (xy 167.698679 -346.357698) (xy 167.694608 -346.302076)
			(xy 165.972456 -346.302076) (xy 165.97245 -346.302116) (xy 165.953425 -346.359884) (xy 165.939978 -346.387166)
			(xy 165.93403 -346.39961) (xy 165.928387 -346.426599) (xy 165.930175 -346.454113) (xy 165.939261 -346.480145)
			(xy 165.954984 -346.502794) (xy 165.976196 -346.520409) (xy 166.001348 -346.531704) (xy 166.014908 -346.534232)
			(xy 166.041624 -346.538778) (xy 166.093505 -346.554432) (xy 166.142648 -346.577269) (xy 166.188066 -346.60683)
			(xy 166.228844 -346.642521) (xy 166.264161 -346.683623) (xy 166.293307 -346.729308) (xy 166.315695 -346.778659)
			(xy 166.330874 -346.83068) (xy 166.338539 -346.884326) (xy 166.339012 -346.911422) (xy 166.338526 -346.938673)
			(xy 166.33077 -346.992621) (xy 166.315415 -347.044916) (xy 166.292773 -347.094493) (xy 166.263307 -347.140343)
			(xy 166.227616 -347.181534) (xy 166.186425 -347.217225) (xy 166.140575 -347.246691) (xy 166.090998 -347.269333)
			(xy 166.038703 -347.284688) (xy 165.984755 -347.292444) (xy 165.930253 -347.292444) (xy 165.876305 -347.284688)
			(xy 165.82401 -347.269333) (xy 165.774433 -347.246691) (xy 165.728583 -347.217225) (xy 165.687392 -347.181534)
			(xy 165.651701 -347.140343) (xy 165.622235 -347.094493) (xy 165.599593 -347.044916) (xy 165.584238 -346.992621)
			(xy 165.576482 -346.938673) (xy 165.575996 -346.911422) (xy 165.576599 -346.881013) (xy 165.586217 -346.820961)
			(xy 165.605228 -346.763192) (xy 165.618668 -346.735908) (xy 165.624614 -346.723465) (xy 165.630247 -346.696478)
			(xy 165.628455 -346.668967) (xy 165.619367 -346.642939) (xy 165.603648 -346.620292) (xy 165.582442 -346.602675)
			(xy 165.557295 -346.591375) (xy 165.543738 -346.588842) (xy 165.517029 -346.584266) (xy 165.465153 -346.56861)
			(xy 165.416014 -346.545772) (xy 165.3706 -346.516212) (xy 165.329825 -346.480524) (xy 165.294508 -346.439427)
			(xy 165.265362 -346.393747) (xy 165.24297 -346.344402) (xy 165.227785 -346.292386) (xy 165.220112 -346.238745)
			(xy 165.219634 -346.211652) (xy 158.550864 -346.211652) (xy 158.550864 -348.207584) (xy 158.550665 -348.234388)
			(xy 158.547363 -348.287894) (xy 158.54426 -348.314518) (xy 158.54299 -348.326202) (xy 158.550102 -348.348046)
			(xy 158.623 -348.421706) (xy 158.644336 -348.429326) (xy 158.656274 -348.428056) (xy 158.666655 -348.426988)
			(xy 158.687495 -348.425843) (xy 158.69793 -348.42577) (xy 158.725181 -348.426258) (xy 158.779129 -348.434018)
			(xy 158.831423 -348.449377) (xy 158.880999 -348.472021) (xy 158.926849 -348.50149) (xy 158.968038 -348.537183)
			(xy 159.003728 -348.578375) (xy 159.033193 -348.624227) (xy 159.055834 -348.673805) (xy 159.071188 -348.7261)
			(xy 159.078944 -348.780049) (xy 159.078944 -348.834551) (xy 159.071188 -348.8885) (xy 159.055834 -348.940795)
			(xy 159.033193 -348.990373) (xy 159.003728 -349.036225) (xy 158.968038 -349.077417) (xy 158.926849 -349.11311)
			(xy 158.880999 -349.142579) (xy 158.831423 -349.165223) (xy 158.779129 -349.180582) (xy 158.725181 -349.188342)
			(xy 158.69793 -349.188786) (xy 158.670444 -349.1883) (xy 158.616043 -349.180396) (xy 158.563342 -349.164761)
			(xy 158.513431 -349.141719) (xy 158.467348 -349.111749) (xy 158.426045 -349.075472) (xy 158.390381 -349.033639)
			(xy 158.361094 -348.987118) (xy 158.349442 -348.962218) (xy 158.344108 -348.950534) (xy 158.324804 -348.935294)
			(xy 158.229808 -348.917768) (xy 158.217505 -348.916075) (xy 158.193807 -348.923406) (xy 158.184596 -348.931738)
			(xy 157.788102 -349.328232) (xy 165.391846 -349.328232) (xy 165.392346 -349.30034) (xy 165.400459 -349.245149)
			(xy 165.416529 -349.19173) (xy 165.440215 -349.141225) (xy 165.47101 -349.094712) (xy 165.508257 -349.053184)
			(xy 165.551158 -349.017529) (xy 165.574726 -349.002604) (xy 165.584124 -348.996762) (xy 165.596316 -348.978728)
			(xy 165.613588 -348.882208) (xy 165.608254 -348.861126) (xy 165.601396 -348.85249) (xy 165.585731 -348.832176)
			(xy 165.55946 -348.788114) (xy 165.539321 -348.740933) (xy 165.525677 -348.691482) (xy 165.518773 -348.640649)
			(xy 165.518338 -348.615) (xy 165.518907 -348.586442) (xy 165.527415 -348.529964) (xy 165.544241 -348.475384)
			(xy 165.569009 -348.423918) (xy 165.601167 -348.376716) (xy 165.620192 -348.355412) (xy 165.62705 -348.348046)
			(xy 165.633908 -348.330012) (xy 165.632384 -348.239334) (xy 165.624764 -348.221554) (xy 165.617652 -348.214442)
			(xy 165.596896 -348.192852) (xy 165.561726 -348.14438) (xy 165.534565 -348.091007) (xy 165.516081 -348.034044)
			(xy 165.506728 -347.974892) (xy 165.506146 -347.944948) (xy 165.506632 -347.917697) (xy 165.514388 -347.863749)
			(xy 165.529743 -347.811454) (xy 165.552385 -347.761877) (xy 165.581851 -347.716027) (xy 165.617542 -347.674836)
			(xy 165.658733 -347.639145) (xy 165.704583 -347.609679) (xy 165.75416 -347.587037) (xy 165.806455 -347.571682)
			(xy 165.860403 -347.563926) (xy 165.914905 -347.563926) (xy 165.968853 -347.571682) (xy 166.021148 -347.587037)
			(xy 166.070725 -347.609679) (xy 166.116575 -347.639145) (xy 166.157766 -347.674836) (xy 166.193457 -347.716027)
			(xy 166.222923 -347.761877) (xy 166.245565 -347.811454) (xy 166.26092 -347.863749) (xy 166.268676 -347.917697)
			(xy 166.269162 -347.944948) (xy 166.268622 -347.973507) (xy 166.264541 -348.000574) (xy 167.718484 -348.000574)
			(xy 167.722555 -347.944952) (xy 167.734681 -347.890515) (xy 167.754604 -347.838424) (xy 167.7819 -347.789789)
			(xy 167.815986 -347.745646) (xy 167.856135 -347.706937) (xy 167.901493 -347.674486) (xy 167.951093 -347.648985)
			(xy 168.003877 -347.630978) (xy 168.05872 -347.620848) (xy 168.114454 -347.618811) (xy 168.169891 -347.624911)
			(xy 168.223848 -347.639017) (xy 168.275177 -347.660829) (xy 168.322783 -347.689883) (xy 168.365651 -347.725558)
			(xy 168.402868 -347.767095) (xy 168.433641 -347.813608) (xy 168.457313 -347.864105) (xy 168.473381 -347.917512)
			(xy 168.481501 -347.972688) (xy 168.48201 -348.000574) (xy 168.481501 -348.02846) (xy 168.473381 -348.083636)
			(xy 168.457313 -348.137043) (xy 168.433641 -348.18754) (xy 168.402868 -348.234053) (xy 168.365651 -348.27559)
			(xy 168.322783 -348.311265) (xy 168.275177 -348.340319) (xy 168.223848 -348.362131) (xy 168.169891 -348.376237)
			(xy 168.114454 -348.382337) (xy 168.05872 -348.3803) (xy 168.003877 -348.37017) (xy 167.951093 -348.352163)
			(xy 167.901493 -348.326662) (xy 167.856135 -348.294211) (xy 167.815986 -348.255502) (xy 167.7819 -348.211359)
			(xy 167.754604 -348.162724) (xy 167.734681 -348.110633) (xy 167.722555 -348.056196) (xy 167.718484 -348.000574)
			(xy 166.264541 -348.000574) (xy 166.260107 -348.029986) (xy 166.243274 -348.084567) (xy 166.2185 -348.136032)
			(xy 166.186336 -348.183232) (xy 166.167308 -348.204536) (xy 166.16045 -348.211902) (xy 166.153592 -348.229936)
			(xy 166.155116 -348.320614) (xy 166.162736 -348.338394) (xy 166.169848 -348.345506) (xy 166.190635 -348.367138)
			(xy 166.225858 -348.415699) (xy 166.253044 -348.469175) (xy 166.271521 -348.526249) (xy 166.280835 -348.585512)
			(xy 166.281354 -348.615508) (xy 166.281354 -348.625922) (xy 166.288974 -348.644464) (xy 167.360854 -349.716344)
			(xy 168.5704 -349.716344) (xy 168.574471 -349.660722) (xy 168.586597 -349.606285) (xy 168.60652 -349.554194)
			(xy 168.633816 -349.505559) (xy 168.667902 -349.461416) (xy 168.708051 -349.422707) (xy 168.753409 -349.390256)
			(xy 168.803009 -349.364755) (xy 168.855793 -349.346748) (xy 168.910636 -349.336618) (xy 168.96637 -349.334581)
			(xy 169.021807 -349.340681) (xy 169.075764 -349.354787) (xy 169.127093 -349.376599) (xy 169.174699 -349.405653)
			(xy 169.217567 -349.441328) (xy 169.254784 -349.482865) (xy 169.285557 -349.529378) (xy 169.309229 -349.579875)
			(xy 169.325297 -349.633282) (xy 169.333417 -349.688458) (xy 169.333926 -349.716344) (xy 169.333417 -349.74423)
			(xy 169.325297 -349.799406) (xy 169.309229 -349.852813) (xy 169.285557 -349.90331) (xy 169.254784 -349.949823)
			(xy 169.217567 -349.99136) (xy 169.174699 -350.027035) (xy 169.127093 -350.056089) (xy 169.075764 -350.077901)
			(xy 169.021807 -350.092007) (xy 168.96637 -350.098107) (xy 168.910636 -350.09607) (xy 168.855793 -350.08594)
			(xy 168.803009 -350.067933) (xy 168.753409 -350.042432) (xy 168.708051 -350.009981) (xy 168.667902 -349.971272)
			(xy 168.633816 -349.927129) (xy 168.60652 -349.878494) (xy 168.586597 -349.826403) (xy 168.574471 -349.771966)
			(xy 168.5704 -349.716344) (xy 167.360854 -349.716344) (xy 167.533066 -349.888556) (xy 167.550301 -349.906669)
			(xy 167.578056 -349.948247) (xy 167.588184 -349.971106) (xy 167.903487 -350.732344) (xy 168.5704 -350.732344)
			(xy 168.574471 -350.676722) (xy 168.586597 -350.622285) (xy 168.60652 -350.570194) (xy 168.633816 -350.521559)
			(xy 168.667902 -350.477416) (xy 168.708051 -350.438707) (xy 168.753409 -350.406256) (xy 168.803009 -350.380755)
			(xy 168.855793 -350.362748) (xy 168.910636 -350.352618) (xy 168.96637 -350.350581) (xy 169.021807 -350.356681)
			(xy 169.075764 -350.370787) (xy 169.127093 -350.392599) (xy 169.174699 -350.421653) (xy 169.217567 -350.457328)
			(xy 169.254784 -350.498865) (xy 169.285557 -350.545378) (xy 169.309229 -350.595875) (xy 169.325297 -350.649282)
			(xy 169.333417 -350.704458) (xy 169.333926 -350.732344) (xy 169.333417 -350.76023) (xy 169.325297 -350.815406)
			(xy 169.309229 -350.868813) (xy 169.285557 -350.91931) (xy 169.254784 -350.965823) (xy 169.217567 -351.00736)
			(xy 169.174699 -351.043035) (xy 169.127093 -351.072089) (xy 169.075764 -351.093901) (xy 169.021807 -351.108007)
			(xy 168.96637 -351.114107) (xy 168.910636 -351.11207) (xy 168.855793 -351.10194) (xy 168.803009 -351.083933)
			(xy 168.753409 -351.058432) (xy 168.708051 -351.025981) (xy 168.667902 -350.987272) (xy 168.633816 -350.943129)
			(xy 168.60652 -350.894494) (xy 168.586597 -350.842403) (xy 168.574471 -350.787966) (xy 168.5704 -350.732344)
			(xy 167.903487 -350.732344) (xy 168.42994 -352.00336) (xy 168.438918 -352.026672) (xy 168.448634 -352.075668)
			(xy 168.449244 -352.100642) (xy 168.449244 -352.950272) (xy 178.85537 -352.950272) (xy 178.855851 -352.922361)
			(xy 178.863989 -352.867135) (xy 178.880088 -352.813684) (xy 178.903803 -352.763149) (xy 178.934629 -352.71661)
			(xy 178.952906 -352.69551) (xy 178.959256 -352.688398) (xy 178.96586 -352.671126) (xy 178.96586 -352.584004)
			(xy 178.959256 -352.566732) (xy 178.952906 -352.55962) (xy 178.934617 -352.538529) (xy 178.903791 -352.491989)
			(xy 178.880078 -352.441452) (xy 178.863984 -352.387998) (xy 178.855853 -352.33277) (xy 178.85537 -352.304858)
			(xy 178.855856 -352.277607) (xy 178.863612 -352.223659) (xy 178.878967 -352.171364) (xy 178.901609 -352.121787)
			(xy 178.931075 -352.075937) (xy 178.966766 -352.034746) (xy 179.007957 -351.999055) (xy 179.053807 -351.969589)
			(xy 179.103384 -351.946947) (xy 179.155679 -351.931592) (xy 179.209627 -351.923836) (xy 179.264129 -351.923836)
			(xy 179.318077 -351.931592) (xy 179.370372 -351.946947) (xy 179.419949 -351.969589) (xy 179.465799 -351.999055)
			(xy 179.50699 -352.034746) (xy 179.542681 -352.075937) (xy 179.572147 -352.121787) (xy 179.594789 -352.171364)
			(xy 179.610144 -352.223659) (xy 179.6179 -352.277607) (xy 179.618386 -352.304858) (xy 179.617909 -352.332769)
			(xy 179.609768 -352.387995) (xy 179.593667 -352.441445) (xy 179.569952 -352.491979) (xy 179.539127 -352.538519)
			(xy 179.52085 -352.55962) (xy 179.5145 -352.566732) (xy 179.507896 -352.584004) (xy 179.507896 -352.671126)
			(xy 179.5145 -352.688398) (xy 179.52085 -352.69551) (xy 179.538941 -352.716389) (xy 179.56953 -352.762391)
			(xy 179.593172 -352.812321) (xy 179.609374 -352.865135) (xy 179.614068 -352.89236) (xy 179.6161 -352.906838)
			(xy 179.634642 -352.928682) (xy 179.734464 -352.961194) (xy 179.743479 -352.963772) (xy 179.762194 -352.962867)
			(xy 179.779338 -352.955307) (xy 179.78628 -352.949002) (xy 179.840636 -352.894646) (xy 179.847341 -352.887173)
			(xy 179.854925 -352.868608) (xy 179.855368 -352.858578) (xy 179.855368 -351.755964) (xy 179.855 -351.745918)
			(xy 179.847411 -351.727322) (xy 179.840636 -351.719896) (xy 179.547266 -351.42678) (xy 179.526527 -351.405141)
			(xy 179.491337 -351.356627) (xy 179.464164 -351.303209) (xy 179.445678 -351.246198) (xy 179.436334 -351.186999)
			(xy 179.43576 -351.157032) (xy 179.43576 -344.88755) (xy 179.435319 -344.877482) (xy 179.42761 -344.858884)
			(xy 179.420774 -344.851482) (xy 179.307998 -344.73896) (xy 179.287238 -344.717341) (xy 179.252053 -344.668821)
			(xy 179.224886 -344.615397) (xy 179.206405 -344.558382) (xy 179.197064 -344.49918) (xy 179.196492 -344.469212)
			(xy 179.196492 -342.33104) (xy 179.197029 -342.301068) (xy 179.206347 -342.241854) (xy 179.224823 -342.184829)
			(xy 179.252 -342.131401) (xy 179.287208 -342.082888) (xy 179.307998 -342.061292) (xy 180.012086 -341.357204)
			(xy 180.020547 -341.348918) (xy 180.038339 -341.333285) (xy 180.047646 -341.325962) (xy 180.055012 -341.32012)
			(xy 180.064664 -341.304372) (xy 180.080158 -341.218774) (xy 180.076602 -341.200486) (xy 180.071522 -341.192358)
			(xy 180.05803 -341.169676) (xy 180.036754 -341.12138) (xy 180.022342 -341.070611) (xy 180.01507 -341.01834)
			(xy 180.014626 -340.991952) (xy 180.015119 -340.964738) (xy 180.022847 -340.910863) (xy 180.038155 -340.858633)
			(xy 180.060731 -340.80911) (xy 180.090117 -340.763297) (xy 180.125716 -340.722127) (xy 180.145944 -340.703916)
			(xy 180.154072 -340.696804) (xy 180.163216 -340.6775) (xy 180.165502 -340.58098) (xy 180.157374 -340.561168)
			(xy 180.1495 -340.553802) (xy 180.131195 -340.535757) (xy 180.099159 -340.495557) (xy 180.072808 -340.451423)
			(xy 180.052617 -340.404151) (xy 180.038952 -340.354598) (xy 180.03206 -340.303659) (xy 180.031644 -340.277958)
			(xy 180.032133 -340.250588) (xy 180.039944 -340.19641) (xy 180.055427 -340.143907) (xy 180.078264 -340.094159)
			(xy 180.107984 -340.048192) (xy 180.125624 -340.02726) (xy 180.13172 -340.020148) (xy 180.13807 -340.00313)
			(xy 180.13807 -339.917786) (xy 180.13172 -339.900768) (xy 180.125624 -339.893656) (xy 180.107942 -339.872757)
			(xy 180.078219 -339.826783) (xy 180.055377 -339.777031) (xy 180.039884 -339.724524) (xy 180.032059 -339.670341)
			(xy 180.032064 -339.615596) (xy 180.039897 -339.561414) (xy 180.055399 -339.50891) (xy 180.07825 -339.459162)
			(xy 180.10798 -339.413193) (xy 180.125624 -339.39226) (xy 180.13172 -339.385148) (xy 180.13807 -339.36813)
			(xy 180.13807 -339.282786) (xy 180.13172 -339.265768) (xy 180.125624 -339.258656) (xy 180.107942 -339.237757)
			(xy 180.078219 -339.191783) (xy 180.055377 -339.142031) (xy 180.039884 -339.089524) (xy 180.032059 -339.035341)
			(xy 180.032064 -338.980596) (xy 180.039897 -338.926414) (xy 180.055399 -338.87391) (xy 180.07825 -338.824162)
			(xy 180.10798 -338.778193) (xy 180.125624 -338.75726) (xy 180.13172 -338.750148) (xy 180.13807 -338.73313)
			(xy 180.13807 -338.647786) (xy 180.13172 -338.630768) (xy 180.125624 -338.623656) (xy 180.107942 -338.602757)
			(xy 180.078219 -338.556783) (xy 180.055377 -338.507031) (xy 180.039884 -338.454524) (xy 180.032059 -338.400341)
			(xy 180.032064 -338.345596) (xy 180.039897 -338.291414) (xy 180.055399 -338.23891) (xy 180.07825 -338.189162)
			(xy 180.10798 -338.143193) (xy 180.125624 -338.12226) (xy 180.13172 -338.115148) (xy 180.13807 -338.09813)
			(xy 180.13807 -338.012786) (xy 180.13172 -337.995768) (xy 180.125624 -337.988656) (xy 180.108001 -337.967711)
			(xy 180.078286 -337.921742) (xy 180.055447 -337.871998) (xy 180.039952 -337.8195) (xy 180.03212 -337.765326)
			(xy 180.031644 -337.737958) (xy 180.032075 -337.71253) (xy 180.038826 -337.662123) (xy 180.052214 -337.61306)
			(xy 180.072004 -337.566211) (xy 180.097843 -337.522408) (xy 180.129275 -337.482427) (xy 180.147214 -337.4644)
			(xy 180.154072 -337.457796) (xy 180.161692 -337.441286) (xy 180.16855 -337.355688) (xy 180.163724 -337.338416)
			(xy 180.157882 -337.330796) (xy 180.140125 -337.305947) (xy 180.111948 -337.251765) (xy 180.092757 -337.193787)
			(xy 180.083041 -337.133494) (xy 180.082444 -337.102958) (xy 180.082939 -337.075708) (xy 180.0907 -337.021763)
			(xy 180.106058 -336.969471) (xy 180.1287 -336.919897) (xy 180.158166 -336.874049) (xy 180.193857 -336.832861)
			(xy 180.235044 -336.79717) (xy 180.280892 -336.767703) (xy 180.330466 -336.74506) (xy 180.382757 -336.729701)
			(xy 180.436702 -336.721939) (xy 180.463952 -336.72145) (xy 180.49159 -336.721941) (xy 180.546286 -336.729935)
			(xy 180.599256 -336.745733) (xy 180.649395 -336.769006) (xy 180.695653 -336.799267) (xy 180.716682 -336.817208)
			(xy 180.723794 -336.823304) (xy 180.741066 -336.829908) (xy 180.826918 -336.829908) (xy 180.84419 -336.823304)
			(xy 180.851302 -336.817208) (xy 180.872333 -336.799268) (xy 180.918583 -336.768992) (xy 180.96872 -336.745713)
			(xy 181.021694 -336.729918) (xy 181.076393 -336.72194) (xy 181.104032 -336.72145) (xy 181.131742 -336.721927)
			(xy 181.186579 -336.729943) (xy 181.239678 -336.745816) (xy 181.289918 -336.769212) (xy 181.33624 -336.799636)
			(xy 181.377667 -336.836448) (xy 181.395878 -336.85734) (xy 181.40299 -336.865722) (xy 181.42204 -336.874866)
			(xy 181.519068 -336.878422) (xy 181.53888 -336.870548) (xy 181.5465 -336.862674) (xy 181.564512 -336.844677)
			(xy 181.604524 -336.813185) (xy 181.648369 -336.787293) (xy 181.695267 -336.76746) (xy 181.744386 -336.754041)
			(xy 181.794853 -336.747271) (xy 181.820312 -336.74685) (xy 181.847562 -336.747366) (xy 181.901506 -336.755124)
			(xy 181.953798 -336.770478) (xy 182.003372 -336.793118) (xy 182.04922 -336.822581) (xy 182.090409 -336.858269)
			(xy 182.126101 -336.899455) (xy 182.155568 -336.945301) (xy 182.178211 -336.994874) (xy 182.19357 -337.047165)
			(xy 182.201331 -337.101108) (xy 182.20182 -337.128358) (xy 182.201434 -337.154335) (xy 182.194383 -337.205809)
			(xy 182.180405 -337.255849) (xy 182.15976 -337.303526) (xy 182.132831 -337.347957) (xy 182.100116 -337.388318)
			(xy 182.062223 -337.423862) (xy 182.041292 -337.439254) (xy 182.031809 -337.446895) (xy 182.020658 -337.4685)
			(xy 182.019956 -337.480656) (xy 182.019956 -337.56346) (xy 182.020637 -337.575624) (xy 182.031783 -337.597246)
			(xy 182.041292 -337.604862) (xy 182.062217 -337.620257) (xy 182.100092 -337.655812) (xy 182.13279 -337.696179)
			(xy 182.159708 -337.74061) (xy 182.180345 -337.788283) (xy 182.194322 -337.838316) (xy 182.201378 -337.889784)
			(xy 182.20182 -337.915758) (xy 182.201349 -337.943128) (xy 182.193535 -337.997308) (xy 182.178048 -338.049812)
			(xy 182.155207 -338.099559) (xy 182.125482 -338.145525) (xy 182.10784 -338.166456) (xy 182.101744 -338.173568)
			(xy 182.095394 -338.190586) (xy 182.095394 -338.27593) (xy 182.101744 -338.292948) (xy 182.10784 -338.30006)
			(xy 182.125441 -338.321025) (xy 182.15517 -338.366987) (xy 182.17802 -338.416727) (xy 182.193521 -338.469225)
			(xy 182.201354 -338.523399) (xy 182.201358 -338.578137) (xy 182.193534 -338.632313) (xy 182.178042 -338.684813)
			(xy 182.1552 -338.734558) (xy 182.125479 -338.780524) (xy 182.10784 -338.801456) (xy 182.101744 -338.808568)
			(xy 182.095394 -338.825586) (xy 182.095394 -338.91093) (xy 182.101744 -338.927948) (xy 182.10784 -338.93506)
			(xy 182.12548 -338.955991) (xy 182.155191 -339.001965) (xy 182.178026 -339.051713) (xy 182.193517 -339.104213)
			(xy 182.201346 -339.158389) (xy 182.20182 -339.185758) (xy 183.714644 -339.185758) (xy 183.715133 -339.158388)
			(xy 183.722944 -339.10421) (xy 183.738427 -339.051707) (xy 183.761264 -339.001959) (xy 183.790984 -338.955992)
			(xy 183.808624 -338.93506) (xy 183.81472 -338.927948) (xy 183.82107 -338.91093) (xy 183.82107 -338.825586)
			(xy 183.81472 -338.808568) (xy 183.808624 -338.801456) (xy 183.790942 -338.780557) (xy 183.761219 -338.734583)
			(xy 183.738377 -338.684831) (xy 183.722884 -338.632324) (xy 183.715059 -338.578141) (xy 183.715064 -338.523396)
			(xy 183.722897 -338.469214) (xy 183.738399 -338.41671) (xy 183.76125 -338.366962) (xy 183.79098 -338.320993)
			(xy 183.808624 -338.30006) (xy 183.81472 -338.292948) (xy 183.82107 -338.27593) (xy 183.82107 -338.190586)
			(xy 183.81472 -338.173568) (xy 183.808624 -338.166456) (xy 183.791001 -338.145511) (xy 183.761286 -338.099542)
			(xy 183.738447 -338.049798) (xy 183.722952 -337.9973) (xy 183.71512 -337.943126) (xy 183.714644 -337.915758)
			(xy 183.715057 -337.889782) (xy 183.722106 -337.838309) (xy 183.73608 -337.788271) (xy 183.75672 -337.740595)
			(xy 183.783645 -337.696164) (xy 183.816355 -337.655802) (xy 183.854244 -337.620256) (xy 183.875172 -337.604862)
			(xy 183.884659 -337.597226) (xy 183.895805 -337.575617) (xy 183.896508 -337.56346) (xy 183.896508 -337.480656)
			(xy 183.895832 -337.468491) (xy 183.884684 -337.446868) (xy 183.875172 -337.439254) (xy 183.854269 -337.423831)
			(xy 183.81639 -337.388282) (xy 183.783688 -337.347922) (xy 183.756767 -337.303495) (xy 183.736126 -337.255826)
			(xy 183.722146 -337.205796) (xy 183.715087 -337.154331) (xy 183.714644 -337.128358) (xy 183.715139 -337.101108)
			(xy 183.7229 -337.047163) (xy 183.738258 -336.994871) (xy 183.7609 -336.945297) (xy 183.790366 -336.899449)
			(xy 183.826057 -336.858261) (xy 183.867244 -336.82257) (xy 183.913092 -336.793103) (xy 183.962666 -336.77046)
			(xy 184.014957 -336.755101) (xy 184.068902 -336.747339) (xy 184.096152 -336.74685) (xy 184.125808 -336.747405)
			(xy 184.184404 -336.756591) (xy 184.240873 -336.774733) (xy 184.293855 -336.801394) (xy 184.342073 -336.835933)
			(xy 184.363614 -336.856324) (xy 184.37098 -336.86369) (xy 184.389776 -336.871056) (xy 184.482994 -336.869532)
			(xy 184.501282 -336.861404) (xy 184.508648 -336.853784) (xy 184.526731 -336.835375) (xy 184.566968 -336.803068)
			(xy 184.611194 -336.776483) (xy 184.658601 -336.756106) (xy 184.708324 -336.742308) (xy 184.759453 -336.735343)
			(xy 184.785254 -336.734912) (xy 184.812893 -336.735386) (xy 184.86759 -336.743382) (xy 184.920561 -336.759184)
			(xy 184.970699 -336.782461) (xy 185.016956 -336.812726) (xy 185.037984 -336.83067) (xy 185.045096 -336.836766)
			(xy 185.062368 -336.84337) (xy 185.14822 -336.84337) (xy 185.165492 -336.836766) (xy 185.172604 -336.83067)
			(xy 185.193629 -336.812723) (xy 185.239881 -336.782449) (xy 185.29002 -336.759172) (xy 185.342995 -336.743379)
			(xy 185.397695 -336.735401) (xy 185.425334 -336.734912) (xy 185.452587 -336.735346) (xy 185.506538 -336.743108)
			(xy 185.558835 -336.758468) (xy 185.608413 -336.781115) (xy 185.654264 -336.810587) (xy 185.695455 -336.846283)
			(xy 185.731146 -336.887479) (xy 185.760611 -336.933334) (xy 185.783251 -336.982916) (xy 185.798604 -337.035215)
			(xy 185.806358 -337.089167) (xy 185.806842 -337.11642) (xy 185.806402 -337.143791) (xy 185.79858 -337.197972)
			(xy 185.783086 -337.250476) (xy 185.760238 -337.300223) (xy 185.730507 -337.346188) (xy 185.712862 -337.367118)
			(xy 185.706766 -337.37423) (xy 185.700416 -337.391248) (xy 185.700416 -337.476592) (xy 185.706766 -337.49361)
			(xy 185.712862 -337.500722) (xy 185.730523 -337.521639) (xy 185.760248 -337.567609) (xy 185.783092 -337.617358)
			(xy 185.798588 -337.669862) (xy 185.806415 -337.724043) (xy 185.806412 -337.778787) (xy 185.798581 -337.832967)
			(xy 185.783082 -337.88547) (xy 185.760233 -337.935217) (xy 185.730505 -337.981185) (xy 185.712862 -338.002118)
			(xy 185.706766 -338.00923) (xy 185.700416 -338.026248) (xy 185.700416 -338.111592) (xy 185.706766 -338.12861)
			(xy 185.712862 -338.135722) (xy 185.730523 -338.156639) (xy 185.760248 -338.202609) (xy 185.783092 -338.252358)
			(xy 185.798588 -338.304862) (xy 185.806415 -338.359043) (xy 185.806412 -338.413787) (xy 185.798581 -338.467967)
			(xy 185.783082 -338.52047) (xy 185.760233 -338.570217) (xy 185.730505 -338.616185) (xy 185.712862 -338.637118)
			(xy 185.706766 -338.64423) (xy 185.700416 -338.661248) (xy 185.700416 -338.746592) (xy 185.706766 -338.76361)
			(xy 185.712862 -338.770722) (xy 185.730523 -338.791639) (xy 185.760248 -338.837609) (xy 185.783092 -338.887358)
			(xy 185.798588 -338.939862) (xy 185.806415 -338.994043) (xy 185.806412 -339.048787) (xy 185.798581 -339.102967)
			(xy 185.783082 -339.15547) (xy 185.760233 -339.205217) (xy 185.730505 -339.251185) (xy 185.712862 -339.272118)
			(xy 185.706766 -339.27923) (xy 185.700416 -339.296248) (xy 185.700416 -339.381592) (xy 185.706766 -339.39861)
			(xy 185.712862 -339.405722) (xy 185.730523 -339.426639) (xy 185.760248 -339.472609) (xy 185.783092 -339.522358)
			(xy 185.798588 -339.574862) (xy 185.806415 -339.629043) (xy 185.806412 -339.683787) (xy 185.798581 -339.737967)
			(xy 185.783082 -339.79047) (xy 185.760233 -339.840217) (xy 185.730505 -339.886185) (xy 185.712862 -339.907118)
			(xy 185.706766 -339.91423) (xy 185.700416 -339.931248) (xy 185.700416 -340.016592) (xy 185.706766 -340.03361)
			(xy 185.712862 -340.040722) (xy 185.730472 -340.061678) (xy 185.76019 -340.107643) (xy 185.783032 -340.157385)
			(xy 185.798529 -340.20988) (xy 185.806365 -340.264052) (xy 185.806842 -340.29142) (xy 185.806386 -340.318035)
			(xy 185.798985 -340.370749) (xy 185.784314 -340.421918) (xy 185.762661 -340.470546) (xy 185.74893 -340.49335)
			(xy 185.743088 -340.502748) (xy 185.740294 -340.52383) (xy 185.766964 -340.617302) (xy 185.780426 -340.633558)
			(xy 185.790332 -340.638384) (xy 185.813987 -340.650488) (xy 185.85794 -340.680349) (xy 185.897327 -340.716017)
			(xy 185.931386 -340.756803) (xy 185.95946 -340.801919) (xy 185.981005 -340.850492) (xy 185.995605 -340.901584)
			(xy 186.002978 -340.954207) (xy 186.003438 -340.980776) (xy 186.002973 -341.008146) (xy 185.995157 -341.062326)
			(xy 185.979669 -341.11483) (xy 185.956826 -341.164577) (xy 185.9271 -341.210543) (xy 185.909458 -341.231474)
			(xy 185.903362 -341.238586) (xy 185.897012 -341.255604) (xy 185.897012 -341.340948) (xy 185.903362 -341.357966)
			(xy 185.909458 -341.365078) (xy 185.927094 -341.386013) (xy 185.956807 -341.431984) (xy 185.979645 -341.481731)
			(xy 185.995136 -341.534231) (xy 185.999578 -341.564976) (xy 187.451746 -341.564976) (xy 187.452187 -341.537605)
			(xy 187.460009 -341.483424) (xy 187.475503 -341.43092) (xy 187.498351 -341.381174) (xy 187.528082 -341.335208)
			(xy 187.545726 -341.314278) (xy 187.551822 -341.307166) (xy 187.558172 -341.290148) (xy 187.558172 -341.204804)
			(xy 187.551822 -341.187786) (xy 187.545726 -341.180674) (xy 187.528112 -341.159721) (xy 187.498396 -341.113755)
			(xy 187.475554 -341.064012) (xy 187.460058 -341.011516) (xy 187.452223 -340.957344) (xy 187.451746 -340.929976)
			(xy 187.452232 -340.902725) (xy 187.459988 -340.848777) (xy 187.475343 -340.796482) (xy 187.497985 -340.746905)
			(xy 187.527451 -340.701055) (xy 187.563142 -340.659864) (xy 187.604333 -340.624173) (xy 187.650183 -340.594707)
			(xy 187.69976 -340.572065) (xy 187.752055 -340.55671) (xy 187.806003 -340.548954) (xy 187.860505 -340.548954)
			(xy 187.914453 -340.55671) (xy 187.966748 -340.572065) (xy 188.016325 -340.594707) (xy 188.062175 -340.624173)
			(xy 188.103366 -340.659864) (xy 188.139057 -340.701055) (xy 188.168523 -340.746905) (xy 188.191165 -340.796482)
			(xy 188.20652 -340.848777) (xy 188.214276 -340.902725) (xy 188.214762 -340.929976) (xy 188.214291 -340.957346)
			(xy 188.206476 -341.011525) (xy 188.190988 -341.064029) (xy 188.168148 -341.113776) (xy 188.138423 -341.159743)
			(xy 188.120782 -341.180674) (xy 188.114686 -341.187786) (xy 188.108336 -341.204804) (xy 188.108336 -341.290148)
			(xy 188.114686 -341.307166) (xy 188.120782 -341.314278) (xy 188.138421 -341.33521) (xy 188.168134 -341.381182)
			(xy 188.19097 -341.43093) (xy 188.206461 -341.483431) (xy 188.214288 -341.537607) (xy 188.214762 -341.564976)
			(xy 188.214276 -341.592227) (xy 188.20652 -341.646175) (xy 188.191165 -341.69847) (xy 188.168523 -341.748047)
			(xy 188.139057 -341.793897) (xy 188.103366 -341.835088) (xy 188.062175 -341.870779) (xy 188.016325 -341.900245)
			(xy 187.966748 -341.922887) (xy 187.914453 -341.938242) (xy 187.860505 -341.945998) (xy 187.806003 -341.945998)
			(xy 187.752055 -341.938242) (xy 187.69976 -341.922887) (xy 187.650183 -341.900245) (xy 187.604333 -341.870779)
			(xy 187.563142 -341.835088) (xy 187.527451 -341.793897) (xy 187.497985 -341.748047) (xy 187.475343 -341.69847)
			(xy 187.459988 -341.646175) (xy 187.452232 -341.592227) (xy 187.451746 -341.564976) (xy 185.999578 -341.564976)
			(xy 186.002964 -341.588407) (xy 186.003438 -341.615776) (xy 186.002952 -341.643027) (xy 185.995196 -341.696975)
			(xy 185.979841 -341.74927) (xy 185.957199 -341.798847) (xy 185.927733 -341.844697) (xy 185.892042 -341.885888)
			(xy 185.850851 -341.921579) (xy 185.805001 -341.951045) (xy 185.755424 -341.973687) (xy 185.703129 -341.989042)
			(xy 185.649181 -341.996798) (xy 185.594679 -341.996798) (xy 185.540731 -341.989042) (xy 185.488436 -341.973687)
			(xy 185.438859 -341.951045) (xy 185.393009 -341.921579) (xy 185.351818 -341.885888) (xy 185.316127 -341.844697)
			(xy 185.286661 -341.798847) (xy 185.264019 -341.74927) (xy 185.248664 -341.696975) (xy 185.240908 -341.643027)
			(xy 185.240422 -341.615776) (xy 185.240869 -341.588405) (xy 185.24869 -341.534225) (xy 185.264184 -341.481721)
			(xy 185.28703 -341.431975) (xy 185.316759 -341.386009) (xy 185.334402 -341.365078) (xy 185.340498 -341.357966)
			(xy 185.346848 -341.340948) (xy 185.346848 -341.255604) (xy 185.340498 -341.238586) (xy 185.334402 -341.231474)
			(xy 185.316784 -341.210525) (xy 185.287069 -341.164557) (xy 185.264229 -341.114813) (xy 185.248733 -341.062317)
			(xy 185.240899 -341.008144) (xy 185.240422 -340.980776) (xy 185.240866 -340.95416) (xy 185.24827 -340.901446)
			(xy 185.262943 -340.850276) (xy 185.284601 -340.801649) (xy 185.298334 -340.778846) (xy 185.304176 -340.769448)
			(xy 185.30697 -340.748366) (xy 185.2803 -340.654894) (xy 185.266838 -340.638638) (xy 185.256932 -340.633812)
			(xy 185.237436 -340.62388) (xy 185.200642 -340.600198) (xy 185.183526 -340.586568) (xy 185.175906 -340.580218)
			(xy 185.157364 -340.574376) (xy 185.067702 -340.581234) (xy 185.050176 -340.58987) (xy 185.043572 -340.597236)
			(xy 185.025414 -340.616781) (xy 184.984579 -340.65111) (xy 184.939358 -340.679413) (xy 184.890633 -340.701136)
			(xy 184.839356 -340.715856) (xy 184.786528 -340.723285) (xy 184.759854 -340.723728) (xy 184.732603 -340.723265)
			(xy 184.678655 -340.715503) (xy 184.626361 -340.700143) (xy 184.576785 -340.677498) (xy 184.530936 -340.648029)
			(xy 184.489747 -340.612335) (xy 184.454056 -340.571143) (xy 184.42459 -340.525292) (xy 184.401948 -340.475715)
			(xy 184.386592 -340.42342) (xy 184.378833 -340.369472) (xy 184.378346 -340.34222) (xy 184.378813 -340.31485)
			(xy 184.386629 -340.26067) (xy 184.402117 -340.208167) (xy 184.424959 -340.15842) (xy 184.454684 -340.112453)
			(xy 184.472326 -340.091522) (xy 184.478422 -340.08441) (xy 184.484772 -340.067392) (xy 184.484772 -339.982048)
			(xy 184.478422 -339.96503) (xy 184.472326 -339.957918) (xy 184.454686 -339.936987) (xy 184.424973 -339.891014)
			(xy 184.402137 -339.841266) (xy 184.386646 -339.788765) (xy 184.378819 -339.734589) (xy 184.378346 -339.70722)
			(xy 184.378521 -339.692168) (xy 184.380933 -339.662161) (xy 184.383172 -339.647276) (xy 184.385204 -339.63356)
			(xy 184.375298 -339.607906) (xy 184.283604 -339.536024) (xy 184.256172 -339.532214) (xy 184.243472 -339.537548)
			(xy 184.220054 -339.546925) (xy 184.171374 -339.560152) (xy 184.121374 -339.566841) (xy 184.096152 -339.567266)
			(xy 184.068898 -339.566867) (xy 184.014945 -339.559103) (xy 183.962646 -339.543739) (xy 183.913066 -339.521089)
			(xy 183.867213 -339.491614) (xy 183.826023 -339.455914) (xy 183.790332 -339.414715) (xy 183.760867 -339.368855)
			(xy 183.738229 -339.31927) (xy 183.722878 -339.266967) (xy 183.715127 -339.213012) (xy 183.714644 -339.185758)
			(xy 182.20182 -339.185758) (xy 182.201306 -339.213009) (xy 182.193555 -339.266958) (xy 182.178205 -339.319254)
			(xy 182.155568 -339.368833) (xy 182.126105 -339.414686) (xy 182.090417 -339.455879) (xy 182.049229 -339.491573)
			(xy 182.003381 -339.521042) (xy 181.953805 -339.543686) (xy 181.901511 -339.559043) (xy 181.847563 -339.566802)
			(xy 181.820312 -339.567266) (xy 181.793841 -339.566818) (xy 181.741411 -339.559475) (xy 181.690499 -339.544957)
			(xy 181.642082 -339.523542) (xy 181.597089 -339.495641) (xy 181.556384 -339.461789) (xy 181.520748 -339.422637)
			(xy 181.490865 -339.378935) (xy 181.478682 -339.35543) (xy 181.47281 -339.34503) (xy 181.453736 -339.330712)
			(xy 181.442106 -339.327998) (xy 181.384194 -339.317838) (xy 181.377336 -339.32495) (xy 181.370821 -339.3323)
			(xy 181.363366 -339.350449) (xy 181.362858 -339.360256) (xy 181.362858 -339.39226) (xy 181.363334 -339.402075)
			(xy 181.370787 -339.420239) (xy 181.377336 -339.427566) (xy 181.397491 -339.449082) (xy 181.431639 -339.497137)
			(xy 181.457989 -339.549872) (xy 181.475914 -339.606033) (xy 181.484988 -339.664282) (xy 181.48554 -339.693758)
			(xy 181.485064 -339.721128) (xy 181.477251 -339.775307) (xy 181.461765 -339.827811) (xy 181.438925 -339.877558)
			(xy 181.409201 -339.923525) (xy 181.39156 -339.944456) (xy 181.385464 -339.951568) (xy 181.379114 -339.968586)
			(xy 181.379114 -340.05393) (xy 181.385464 -340.070948) (xy 181.39156 -340.07806) (xy 181.409188 -340.099001)
			(xy 181.438903 -340.144971) (xy 181.461741 -340.194716) (xy 181.477235 -340.247215) (xy 181.485065 -340.301389)
			(xy 181.48554 -340.328758) (xy 181.485006 -340.356008) (xy 181.477255 -340.409955) (xy 181.461906 -340.46225)
			(xy 181.439271 -340.511828) (xy 181.40981 -340.557679) (xy 181.374124 -340.598872) (xy 181.332939 -340.634566)
			(xy 181.287093 -340.664035) (xy 181.237519 -340.68668) (xy 181.185227 -340.70204) (xy 181.131282 -340.7098)
			(xy 181.104032 -340.710266) (xy 181.076262 -340.70976) (xy 181.021309 -340.70171) (xy 180.968105 -340.685777)
			(xy 180.917773 -340.662296) (xy 180.871379 -340.631764) (xy 180.829902 -340.594827) (xy 180.811678 -340.573868)
			(xy 180.805074 -340.56574) (xy 180.78704 -340.556596) (xy 180.693314 -340.549738) (xy 180.674264 -340.556342)
			(xy 180.66639 -340.5632) (xy 180.663342 -340.565994) (xy 180.655214 -340.573106) (xy 180.64607 -340.59241)
			(xy 180.643784 -340.68893) (xy 180.651912 -340.708742) (xy 180.659786 -340.716108) (xy 180.678093 -340.734151)
			(xy 180.710129 -340.774351) (xy 180.736481 -340.818486) (xy 180.756671 -340.865757) (xy 180.770335 -340.915311)
			(xy 180.777226 -340.96625) (xy 180.777642 -340.991952) (xy 180.777162 -341.019322) (xy 180.76935 -341.073501)
			(xy 180.753865 -341.126004) (xy 180.731026 -341.175752) (xy 180.701303 -341.221718) (xy 180.683662 -341.24265)
			(xy 180.677566 -341.249762) (xy 180.671216 -341.26678) (xy 180.670962 -341.352378) (xy 180.677312 -341.369142)
			(xy 180.683662 -341.376254) (xy 180.701256 -341.39721) (xy 180.730909 -341.443195) (xy 180.753692 -341.492943)
			(xy 180.769137 -341.545434) (xy 180.776929 -341.599593) (xy 180.777388 -341.626952) (xy 180.776974 -341.653786)
			(xy 180.769454 -341.706925) (xy 180.754556 -341.758483) (xy 180.732574 -341.807443) (xy 180.703942 -341.852835)
			(xy 180.669227 -341.893764) (xy 180.629115 -341.929419) (xy 180.584399 -341.959096) (xy 180.535963 -341.982208)
			(xy 180.484764 -341.998299) (xy 180.458364 -342.003126) (xy 180.450236 -342.00465) (xy 180.43652 -342.011508)
			(xy 179.973986 -342.474042) (xy 179.967133 -342.481432) (xy 179.959421 -342.500039) (xy 179.959 -342.51011)
			(xy 179.959 -344.290142) (xy 179.959377 -344.300217) (xy 179.967129 -344.318816) (xy 179.973986 -344.32621)
			(xy 180.086762 -344.438732) (xy 180.107511 -344.460361) (xy 180.142699 -344.508878) (xy 180.169869 -344.562299)
			(xy 180.188353 -344.619312) (xy 180.197695 -344.678513) (xy 180.198268 -344.70848) (xy 180.198268 -350.977962)
			(xy 180.198695 -350.988031) (xy 180.206413 -351.00663) (xy 180.213254 -351.01403) (xy 180.506624 -351.307146)
			(xy 180.527424 -351.328744) (xy 180.562678 -351.377247) (xy 180.589907 -351.430668) (xy 180.608442 -351.487692)
			(xy 180.617826 -351.546914) (xy 180.618384 -351.576894) (xy 180.618384 -353.037648) (xy 180.617749 -353.067623)
			(xy 180.608367 -353.126836) (xy 180.589842 -353.183853) (xy 180.56263 -353.237273) (xy 180.528838 -353.2838)
			(xy 183.237633 -353.2838) (xy 183.241801 -353.228186) (xy 183.25421 -353.173815) (xy 183.274583 -353.1219)
			(xy 183.302466 -353.073601) (xy 183.337236 -353.029997) (xy 183.378116 -352.992062) (xy 183.424192 -352.960642)
			(xy 183.474437 -352.936441) (xy 183.527727 -352.919998) (xy 183.582873 -352.91168) (xy 183.610758 -352.911156)
			(xy 183.63718 -352.91159) (xy 183.689497 -352.919048) (xy 183.740235 -352.933819) (xy 183.788379 -352.955607)
			(xy 183.832963 -352.983977) (xy 183.853328 -353.000818) (xy 183.860186 -353.006914) (xy 183.877204 -353.01301)
			(xy 183.961532 -353.01301) (xy 183.97855 -353.006914) (xy 183.985408 -353.000818) (xy 184.005774 -352.983979)
			(xy 184.05036 -352.955614) (xy 184.098504 -352.933827) (xy 184.149241 -352.919056) (xy 184.201556 -352.911596)
			(xy 184.2544 -352.911596) (xy 184.306715 -352.919056) (xy 184.357452 -352.933827) (xy 184.405596 -352.955614)
			(xy 184.450182 -352.983979) (xy 184.470548 -353.000818) (xy 184.477406 -353.006914) (xy 184.494424 -353.01301)
			(xy 184.578752 -353.01301) (xy 184.59577 -353.006914) (xy 184.602628 -353.000818) (xy 184.614414 -352.990981)
			(xy 184.639338 -352.973051) (xy 184.652412 -352.965004) (xy 184.662064 -352.959162) (xy 184.67451 -352.940366)
			(xy 184.68975 -352.841052) (xy 184.6834 -352.819208) (xy 184.676034 -352.810826) (xy 184.658169 -352.789823)
			(xy 184.62806 -352.743633) (xy 184.604911 -352.69359) (xy 184.589205 -352.640736) (xy 184.58127 -352.586173)
			(xy 184.580784 -352.558604) (xy 184.581258 -352.53103) (xy 184.58921 -352.476458) (xy 184.604933 -352.423598)
			(xy 184.628102 -352.373552) (xy 184.658233 -352.327362) (xy 184.694698 -352.28599) (xy 184.715404 -352.267774)
			(xy 184.72353 -352.260179) (xy 184.73288 -352.240022) (xy 184.733438 -352.228912) (xy 184.733438 -352.151696)
			(xy 184.732908 -352.140581) (xy 184.723545 -352.120421) (xy 184.715404 -352.112834) (xy 184.694707 -352.094608)
			(xy 184.658235 -352.053242) (xy 184.628101 -352.007055) (xy 184.604933 -351.95701) (xy 184.589214 -351.904151)
			(xy 184.581271 -351.849578) (xy 184.580784 -351.822004) (xy 184.58127 -351.794753) (xy 184.589026 -351.740805)
			(xy 184.604381 -351.68851) (xy 184.627023 -351.638933) (xy 184.656489 -351.593083) (xy 184.69218 -351.551892)
			(xy 184.733371 -351.516201) (xy 184.779221 -351.486735) (xy 184.828798 -351.464093) (xy 184.881093 -351.448738)
			(xy 184.935041 -351.440982) (xy 184.989543 -351.440982) (xy 185.043491 -351.448738) (xy 185.095786 -351.464093)
			(xy 185.145363 -351.486735) (xy 185.191213 -351.516201) (xy 185.232404 -351.551892) (xy 185.268095 -351.593083)
			(xy 185.297561 -351.638933) (xy 185.320203 -351.68851) (xy 185.335558 -351.740805) (xy 185.343314 -351.794753)
			(xy 185.3438 -351.822004) (xy 185.343337 -351.849579) (xy 185.335384 -351.904152) (xy 185.319658 -351.957012)
			(xy 185.296488 -352.007057) (xy 185.266355 -352.053247) (xy 185.229887 -352.094618) (xy 185.20918 -352.112834)
			(xy 185.201048 -352.120424) (xy 185.191702 -352.140585) (xy 185.191146 -352.151696) (xy 185.191146 -352.228912)
			(xy 185.191677 -352.240027) (xy 185.20104 -352.260186) (xy 185.20918 -352.267774) (xy 185.229878 -352.286)
			(xy 185.26635 -352.327365) (xy 185.296484 -352.373552) (xy 185.319653 -352.423597) (xy 185.335372 -352.476457)
			(xy 185.343314 -352.53103) (xy 185.3438 -352.558604) (xy 185.343259 -352.587026) (xy 185.334845 -352.643242)
			(xy 185.318173 -352.697584) (xy 185.293614 -352.748848) (xy 185.261712 -352.795894) (xy 185.223177 -352.83768)
			(xy 185.178861 -352.873278) (xy 185.15457 -352.888042) (xy 185.144918 -352.893884) (xy 185.131964 -352.912426)
			(xy 185.121261 -352.975672) (xy 187.181998 -352.975672) (xy 187.182472 -352.94776) (xy 187.190611 -352.892534)
			(xy 187.20671 -352.839083) (xy 187.230427 -352.788548) (xy 187.261255 -352.742009) (xy 187.279534 -352.72091)
			(xy 187.285884 -352.713798) (xy 187.292488 -352.696526) (xy 187.292488 -352.609404) (xy 187.285884 -352.592132)
			(xy 187.279534 -352.58502) (xy 187.261234 -352.563939) (xy 187.230412 -352.517395) (xy 187.206702 -352.466855)
			(xy 187.19061 -352.4134) (xy 187.182481 -352.35817) (xy 187.181998 -352.330258) (xy 187.182484 -352.303007)
			(xy 187.19024 -352.249059) (xy 187.205595 -352.196764) (xy 187.228237 -352.147187) (xy 187.257703 -352.101337)
			(xy 187.293394 -352.060146) (xy 187.334585 -352.024455) (xy 187.380435 -351.994989) (xy 187.430012 -351.972347)
			(xy 187.482307 -351.956992) (xy 187.536255 -351.949236) (xy 187.590757 -351.949236) (xy 187.644705 -351.956992)
			(xy 187.697 -351.972347) (xy 187.746577 -351.994989) (xy 187.792427 -352.024455) (xy 187.833618 -352.060146)
			(xy 187.869309 -352.101337) (xy 187.898775 -352.147187) (xy 187.921417 -352.196764) (xy 187.936772 -352.249059)
			(xy 187.944528 -352.303007) (xy 187.945014 -352.330258) (xy 187.944555 -352.35817) (xy 187.936412 -352.413397)
			(xy 187.920309 -352.466848) (xy 187.896589 -352.517383) (xy 187.865758 -352.563921) (xy 187.847478 -352.58502)
			(xy 187.841128 -352.592132) (xy 187.834524 -352.609404) (xy 187.834524 -352.696526) (xy 187.841128 -352.713798)
			(xy 187.847478 -352.72091) (xy 187.865097 -352.74129) (xy 187.895056 -352.786063) (xy 187.918428 -352.834601)
			(xy 187.93475 -352.885941) (xy 187.93968 -352.912426) (xy 187.94222 -352.92665) (xy 187.960508 -352.947986)
			(xy 188.06033 -352.979736) (xy 188.069303 -352.982145) (xy 188.087834 -352.981123) (xy 188.104782 -352.973558)
			(xy 188.111638 -352.96729) (xy 188.152786 -352.926396) (xy 188.159618 -352.91899) (xy 188.167343 -352.900395)
			(xy 188.167772 -352.890328) (xy 188.167772 -348.27464) (xy 188.168314 -348.244668) (xy 188.177632 -348.185454)
			(xy 188.196106 -348.12843) (xy 188.223282 -348.075002) (xy 188.258489 -348.026488) (xy 188.279278 -348.004892)
			(xy 188.958474 -347.32595) (xy 188.965281 -347.318524) (xy 188.973021 -347.299945) (xy 188.97346 -347.289882)
			(xy 188.97346 -341.026496) (xy 188.97408 -340.995366) (xy 188.984168 -340.93393) (xy 189.004091 -340.874946)
			(xy 189.018164 -340.847172) (xy 189.021212 -340.841584) (xy 189.02426 -340.829646) (xy 189.02426 -340.700614)
			(xy 189.023898 -340.692043) (xy 189.018214 -340.67587) (xy 189.007485 -340.6625) (xy 189.000384 -340.657688)
			(xy 188.916564 -340.604602) (xy 188.89091 -340.603078) (xy 188.878718 -340.60892) (xy 188.85296 -340.620612)
			(xy 188.798861 -340.637133) (xy 188.742917 -340.645488) (xy 188.714634 -340.646004) (xy 188.687382 -340.645513)
			(xy 188.633432 -340.637761) (xy 188.581134 -340.622409) (xy 188.531554 -340.59977) (xy 188.4857 -340.570305)
			(xy 188.444507 -340.534614) (xy 188.408813 -340.493424) (xy 188.379345 -340.447573) (xy 188.356702 -340.397994)
			(xy 188.341346 -340.345698) (xy 188.333589 -340.291748) (xy 188.333126 -340.264496) (xy 188.333583 -340.237125)
			(xy 188.341402 -340.182946) (xy 188.356893 -340.130442) (xy 188.379737 -340.080695) (xy 188.409464 -340.034729)
			(xy 188.427106 -340.013798) (xy 188.433202 -340.006686) (xy 188.439552 -339.989668) (xy 188.439552 -339.904324)
			(xy 188.433202 -339.887306) (xy 188.427106 -339.880194) (xy 188.409462 -339.859264) (xy 188.379739 -339.813295)
			(xy 188.356895 -339.763548) (xy 188.3414 -339.711046) (xy 188.333573 -339.656868) (xy 188.333573 -339.602126)
			(xy 188.341402 -339.547948) (xy 188.356898 -339.495446) (xy 188.379742 -339.445699) (xy 188.409466 -339.399731)
			(xy 188.427106 -339.378798) (xy 188.433202 -339.371686) (xy 188.439552 -339.354668) (xy 188.439552 -339.269324)
			(xy 188.433202 -339.252306) (xy 188.427106 -339.245194) (xy 188.409462 -339.224264) (xy 188.379739 -339.178295)
			(xy 188.356895 -339.128548) (xy 188.3414 -339.076046) (xy 188.333573 -339.021868) (xy 188.333573 -338.967126)
			(xy 188.341402 -338.912948) (xy 188.356898 -338.860446) (xy 188.379742 -338.810699) (xy 188.409466 -338.764731)
			(xy 188.427106 -338.743798) (xy 188.433202 -338.736686) (xy 188.439552 -338.719668) (xy 188.439552 -338.634324)
			(xy 188.433202 -338.617306) (xy 188.427106 -338.610194) (xy 188.409462 -338.589264) (xy 188.379739 -338.543295)
			(xy 188.356895 -338.493548) (xy 188.3414 -338.441046) (xy 188.333573 -338.386868) (xy 188.333573 -338.332126)
			(xy 188.341402 -338.277948) (xy 188.356898 -338.225446) (xy 188.379742 -338.175699) (xy 188.409466 -338.129731)
			(xy 188.427106 -338.108798) (xy 188.433202 -338.101686) (xy 188.439552 -338.084668) (xy 188.439552 -337.999324)
			(xy 188.433202 -337.982306) (xy 188.427106 -337.975194) (xy 188.409462 -337.954264) (xy 188.379739 -337.908295)
			(xy 188.356895 -337.858548) (xy 188.3414 -337.806046) (xy 188.333573 -337.751868) (xy 188.333573 -337.697126)
			(xy 188.341402 -337.642948) (xy 188.356898 -337.590446) (xy 188.379742 -337.540699) (xy 188.409466 -337.494731)
			(xy 188.427106 -337.473798) (xy 188.433202 -337.466686) (xy 188.439552 -337.449668) (xy 188.439552 -337.364324)
			(xy 188.433202 -337.347306) (xy 188.427106 -337.340194) (xy 188.409452 -337.319274) (xy 188.379742 -337.273298)
			(xy 188.356909 -337.223548) (xy 188.341421 -337.171044) (xy 188.333598 -337.116866) (xy 188.333126 -337.089496)
			(xy 188.333552 -337.062242) (xy 188.34131 -337.008287) (xy 188.356668 -336.955987) (xy 188.379314 -336.906404)
			(xy 188.408785 -336.86055) (xy 188.444483 -336.819356) (xy 188.48568 -336.783663) (xy 188.531538 -336.754196)
			(xy 188.581122 -336.731555) (xy 188.633425 -336.716202) (xy 188.687379 -336.708449) (xy 188.714634 -336.707988)
			(xy 188.742272 -336.70848) (xy 188.796968 -336.716472) (xy 188.849939 -336.73227) (xy 188.900078 -336.755543)
			(xy 188.946335 -336.785805) (xy 188.967364 -336.803746) (xy 188.974476 -336.809842) (xy 188.991748 -336.816446)
			(xy 189.0776 -336.816446) (xy 189.094872 -336.809842) (xy 189.101984 -336.803746) (xy 189.123014 -336.785804)
			(xy 189.169265 -336.755531) (xy 189.219403 -336.732253) (xy 189.272376 -336.716458) (xy 189.327075 -336.708479)
			(xy 189.354714 -336.707988) (xy 189.382124 -336.708447) (xy 189.436381 -336.716295) (xy 189.488955 -336.731828)
			(xy 189.538765 -336.754726) (xy 189.584785 -336.784517) (xy 189.626067 -336.820589) (xy 189.644274 -336.841084)
			(xy 189.651132 -336.848958) (xy 189.669166 -336.858102) (xy 189.761622 -336.864706) (xy 189.780672 -336.858356)
			(xy 189.788292 -336.851498) (xy 189.809286 -336.833788) (xy 189.855374 -336.803912) (xy 189.905266 -336.780946)
			(xy 189.957934 -336.765365) (xy 190.01229 -336.75749) (xy 190.039752 -336.75701) (xy 190.067004 -336.7575)
			(xy 190.120955 -336.765251) (xy 190.173254 -336.780602) (xy 190.222835 -336.80324) (xy 190.268689 -336.832705)
			(xy 190.309883 -336.868396) (xy 190.345577 -336.909587) (xy 190.375046 -336.955439) (xy 190.397688 -337.005018)
			(xy 190.413043 -337.057315) (xy 190.420798 -337.111266) (xy 190.42126 -337.138518) (xy 190.420791 -337.165776)
			(xy 190.413022 -337.219736) (xy 190.397658 -337.272042) (xy 190.375011 -337.321632) (xy 190.345543 -337.367497)
			(xy 190.309851 -337.408705) (xy 190.268662 -337.444419) (xy 190.246 -337.459574) (xy 190.239038 -337.464434)
			(xy 190.228512 -337.477738) (xy 190.222947 -337.493763) (xy 190.222632 -337.502246) (xy 190.222632 -337.58759)
			(xy 190.223008 -337.596064) (xy 190.228578 -337.612073) (xy 190.23905 -337.625402) (xy 190.246 -337.630262)
			(xy 190.268664 -337.645414) (xy 190.30986 -337.681122) (xy 190.345555 -337.722328) (xy 190.375024 -337.768194)
			(xy 190.397666 -337.817787) (xy 190.41302 -337.870097) (xy 190.420775 -337.924059) (xy 190.42126 -337.951318)
			(xy 190.420814 -337.978689) (xy 190.412993 -338.032869) (xy 190.3975 -338.085373) (xy 190.374653 -338.13512)
			(xy 190.344924 -338.181085) (xy 190.32728 -338.202016) (xy 190.321184 -338.209128) (xy 190.314834 -338.226146)
			(xy 190.314834 -338.31149) (xy 190.321184 -338.328508) (xy 190.32728 -338.33562) (xy 190.344938 -338.356539)
			(xy 190.374662 -338.402509) (xy 190.397505 -338.452258) (xy 190.413 -338.504762) (xy 190.420827 -338.558942)
			(xy 190.420825 -338.613685) (xy 190.412994 -338.667865) (xy 190.397496 -338.720368) (xy 190.374649 -338.770115)
			(xy 190.344922 -338.816083) (xy 190.32728 -338.837016) (xy 190.321184 -338.844128) (xy 190.314834 -338.861146)
			(xy 190.314834 -338.94649) (xy 190.321184 -338.963508) (xy 190.32728 -338.97062) (xy 190.344892 -338.991574)
			(xy 190.374609 -339.03754) (xy 190.39745 -339.087282) (xy 190.412947 -339.139778) (xy 190.420782 -339.19395)
			(xy 190.42126 -339.221318) (xy 192.058544 -339.221318) (xy 192.05901 -339.193948) (xy 192.066826 -339.139768)
			(xy 192.082315 -339.087265) (xy 192.105157 -339.037518) (xy 192.134882 -338.991551) (xy 192.152524 -338.97062)
			(xy 192.15862 -338.963508) (xy 192.16497 -338.94649) (xy 192.16497 -338.861146) (xy 192.15862 -338.844128)
			(xy 192.152524 -338.837016) (xy 192.134901 -338.816069) (xy 192.105176 -338.770104) (xy 192.08233 -338.72036)
			(xy 192.066832 -338.66786) (xy 192.059002 -338.613683) (xy 192.059 -338.558944) (xy 192.066826 -338.504767)
			(xy 192.08232 -338.452266) (xy 192.105163 -338.40252) (xy 192.134885 -338.356553) (xy 192.152524 -338.33562)
			(xy 192.15862 -338.328508) (xy 192.16497 -338.31149) (xy 192.16497 -338.226146) (xy 192.15862 -338.209128)
			(xy 192.152524 -338.202016) (xy 192.134883 -338.181086) (xy 192.10517 -338.135113) (xy 192.082334 -338.085365)
			(xy 192.066844 -338.032864) (xy 192.059017 -337.978687) (xy 192.058544 -337.951318) (xy 192.059038 -337.924061)
			(xy 192.066803 -337.870102) (xy 192.082162 -337.817796) (xy 192.104805 -337.768207) (xy 192.134269 -337.722341)
			(xy 192.169957 -337.681132) (xy 192.211143 -337.645417) (xy 192.233804 -337.630262) (xy 192.240796 -337.625441)
			(xy 192.251316 -337.612119) (xy 192.256867 -337.596078) (xy 192.257172 -337.58759) (xy 192.257172 -337.502246)
			(xy 192.256881 -337.493763) (xy 192.25128 -337.477747) (xy 192.240772 -337.464424) (xy 192.233804 -337.459574)
			(xy 192.211157 -337.444397) (xy 192.169961 -337.408694) (xy 192.134265 -337.367492) (xy 192.104794 -337.32163)
			(xy 192.082149 -337.272041) (xy 192.066791 -337.219735) (xy 192.059031 -337.165775) (xy 192.058544 -337.138518)
			(xy 192.059095 -337.111269) (xy 192.066848 -337.057327) (xy 192.082198 -337.005036) (xy 192.104834 -336.955462)
			(xy 192.134293 -336.909614) (xy 192.169978 -336.868425) (xy 192.211161 -336.832733) (xy 192.257004 -336.803265)
			(xy 192.306574 -336.780621) (xy 192.358862 -336.765262) (xy 192.412803 -336.7575) (xy 192.440052 -336.75701)
			(xy 192.468271 -336.757497) (xy 192.524093 -336.765807) (xy 192.578081 -336.782251) (xy 192.629056 -336.806472)
			(xy 192.675906 -336.83794) (xy 192.6971 -336.856578) (xy 192.704212 -336.862928) (xy 192.721738 -336.869786)
			(xy 192.809368 -336.869786) (xy 192.827148 -336.862928) (xy 192.83426 -336.856324) (xy 192.855469 -336.837597)
			(xy 192.902388 -336.805982) (xy 192.953462 -336.781643) (xy 193.007571 -336.765115) (xy 193.063528 -336.756761)
			(xy 193.091816 -336.756248) (xy 193.119856 -336.756739) (xy 193.175334 -336.764942) (xy 193.229016 -336.781169)
			(xy 193.279748 -336.805071) (xy 193.32644 -336.836134) (xy 193.347594 -336.854546) (xy 193.354706 -336.86115)
			(xy 193.371978 -336.867754) (xy 193.459354 -336.867754) (xy 193.476626 -336.86115) (xy 193.483738 -336.854546)
			(xy 193.504888 -336.836126) (xy 193.551566 -336.805033) (xy 193.602298 -336.781118) (xy 193.655986 -336.764898)
			(xy 193.711473 -336.756723) (xy 193.739516 -336.756248) (xy 193.766766 -336.756763) (xy 193.82071 -336.76452)
			(xy 193.873002 -336.779875) (xy 193.922576 -336.802515) (xy 193.968424 -336.831979) (xy 194.009613 -336.867667)
			(xy 194.045304 -336.908853) (xy 194.074772 -336.954699) (xy 194.097415 -337.004272) (xy 194.112774 -337.056563)
			(xy 194.120535 -337.110506) (xy 194.121024 -337.137756) (xy 194.120551 -337.165126) (xy 194.112737 -337.219306)
			(xy 194.097251 -337.271809) (xy 194.07441 -337.321557) (xy 194.044686 -337.367523) (xy 194.027044 -337.388454)
			(xy 194.020948 -337.395566) (xy 194.014598 -337.412584) (xy 194.014598 -337.497928) (xy 194.020948 -337.514946)
			(xy 194.027044 -337.522058) (xy 194.044643 -337.543025) (xy 194.074372 -337.588986) (xy 194.097221 -337.638727)
			(xy 194.112722 -337.691224) (xy 194.120556 -337.745398) (xy 194.12056 -337.800136) (xy 194.112736 -337.854311)
			(xy 194.097245 -337.906811) (xy 194.074404 -337.956556) (xy 194.044683 -338.002522) (xy 194.027044 -338.023454)
			(xy 194.020948 -338.030566) (xy 194.014598 -338.047584) (xy 194.014598 -338.132928) (xy 194.020948 -338.149946)
			(xy 194.027044 -338.157058) (xy 194.044643 -338.178025) (xy 194.074372 -338.223986) (xy 194.097221 -338.273727)
			(xy 194.112722 -338.326224) (xy 194.120556 -338.380398) (xy 194.12056 -338.435136) (xy 194.112736 -338.489311)
			(xy 194.097245 -338.541811) (xy 194.074404 -338.591556) (xy 194.044683 -338.637522) (xy 194.027044 -338.658454)
			(xy 194.020948 -338.665566) (xy 194.014598 -338.682584) (xy 194.014598 -338.767928) (xy 194.020948 -338.784946)
			(xy 194.027044 -338.792058) (xy 194.044684 -338.812989) (xy 194.074394 -338.858963) (xy 194.084024 -338.879942)
			(xy 198.275192 -338.879942) (xy 198.279263 -338.82432) (xy 198.291389 -338.769883) (xy 198.311312 -338.717792)
			(xy 198.338608 -338.669157) (xy 198.372694 -338.625014) (xy 198.412843 -338.586305) (xy 198.458201 -338.553854)
			(xy 198.507801 -338.528353) (xy 198.560585 -338.510346) (xy 198.615428 -338.500216) (xy 198.671162 -338.498179)
			(xy 198.726599 -338.504279) (xy 198.780556 -338.518385) (xy 198.831885 -338.540197) (xy 198.879491 -338.569251)
			(xy 198.922359 -338.604926) (xy 198.959576 -338.646463) (xy 198.990349 -338.692976) (xy 199.014021 -338.743473)
			(xy 199.030089 -338.79688) (xy 199.038209 -338.852056) (xy 199.038718 -338.879942) (xy 199.038209 -338.907828)
			(xy 199.030089 -338.963004) (xy 199.014021 -339.016411) (xy 198.990349 -339.066908) (xy 198.959576 -339.113421)
			(xy 198.922359 -339.154958) (xy 198.879491 -339.190633) (xy 198.831885 -339.219687) (xy 198.780556 -339.241499)
			(xy 198.726599 -339.255605) (xy 198.671162 -339.261705) (xy 198.615428 -339.259668) (xy 198.560585 -339.249538)
			(xy 198.507801 -339.231531) (xy 198.458201 -339.20603) (xy 198.412843 -339.173579) (xy 198.372694 -339.13487)
			(xy 198.338608 -339.090727) (xy 198.311312 -339.042092) (xy 198.291389 -338.990001) (xy 198.279263 -338.935564)
			(xy 198.275192 -338.879942) (xy 194.084024 -338.879942) (xy 194.09723 -338.908711) (xy 194.112721 -338.961211)
			(xy 194.12055 -339.015387) (xy 194.121024 -339.042756) (xy 194.12061 -339.068923) (xy 194.113492 -339.120769)
			(xy 194.099345 -339.171153) (xy 194.078433 -339.219125) (xy 194.051152 -339.263784) (xy 194.034918 -339.28431)
			(xy 194.028822 -339.291676) (xy 194.02298 -339.308694) (xy 194.026282 -339.3948) (xy 194.03314 -339.41131)
			(xy 194.039744 -339.418168) (xy 194.059203 -339.439552) (xy 194.092113 -339.487084) (xy 194.117467 -339.539041)
			(xy 194.134685 -339.594231) (xy 194.143371 -339.651389) (xy 194.143884 -339.680296) (xy 194.143419 -339.707666)
			(xy 194.135602 -339.761846) (xy 194.120113 -339.814349) (xy 194.09727 -339.864096) (xy 194.067545 -339.910062)
			(xy 194.049904 -339.930994) (xy 194.043808 -339.938106) (xy 194.037458 -339.955124) (xy 194.037458 -340.040468)
			(xy 194.043808 -340.057486) (xy 194.049904 -340.064598) (xy 194.067556 -340.085519) (xy 194.090967 -340.121748)
			(xy 203.227938 -340.121748) (xy 203.232009 -340.066126) (xy 203.244135 -340.011689) (xy 203.264058 -339.959598)
			(xy 203.291354 -339.910963) (xy 203.32544 -339.86682) (xy 203.365589 -339.828111) (xy 203.410947 -339.79566)
			(xy 203.460547 -339.770159) (xy 203.513331 -339.752152) (xy 203.568174 -339.742022) (xy 203.623908 -339.739985)
			(xy 203.679345 -339.746085) (xy 203.733302 -339.760191) (xy 203.784631 -339.782003) (xy 203.832237 -339.811057)
			(xy 203.875105 -339.846732) (xy 203.912322 -339.888269) (xy 203.943095 -339.934782) (xy 203.966767 -339.985279)
			(xy 203.982835 -340.038686) (xy 203.990955 -340.093862) (xy 203.991464 -340.121748) (xy 203.990955 -340.149634)
			(xy 203.982835 -340.20481) (xy 203.966767 -340.258217) (xy 203.943095 -340.308714) (xy 203.912322 -340.355227)
			(xy 203.875105 -340.396764) (xy 203.832237 -340.432439) (xy 203.784631 -340.461493) (xy 203.733302 -340.483305)
			(xy 203.679345 -340.497411) (xy 203.623908 -340.503511) (xy 203.568174 -340.501474) (xy 203.513331 -340.491344)
			(xy 203.460547 -340.473337) (xy 203.410947 -340.447836) (xy 203.365589 -340.415385) (xy 203.32544 -340.376676)
			(xy 203.291354 -340.332533) (xy 203.264058 -340.283898) (xy 203.244135 -340.231807) (xy 203.232009 -340.17737)
			(xy 203.227938 -340.121748) (xy 194.090967 -340.121748) (xy 194.097266 -340.131495) (xy 194.120099 -340.181245)
			(xy 194.135587 -340.233748) (xy 194.143412 -340.287926) (xy 194.143884 -340.315296) (xy 194.143441 -340.34255)
			(xy 194.135684 -340.396503) (xy 194.120327 -340.448802) (xy 194.097683 -340.498384) (xy 194.068213 -340.544238)
			(xy 194.032518 -340.585432) (xy 193.991322 -340.621125) (xy 193.945467 -340.650593) (xy 193.895884 -340.673234)
			(xy 193.843583 -340.688588) (xy 193.78963 -340.696342) (xy 193.762376 -340.696804) (xy 193.735746 -340.696357)
			(xy 193.683004 -340.688946) (xy 193.631805 -340.674271) (xy 193.583145 -340.652617) (xy 193.53797 -340.624405)
			(xy 193.517266 -340.60765) (xy 193.509392 -340.601046) (xy 193.490596 -340.59495) (xy 193.399918 -340.601808)
			(xy 193.382138 -340.610698) (xy 193.375534 -340.618318) (xy 193.357363 -340.638279) (xy 193.316318 -340.673338)
			(xy 193.270742 -340.702263) (xy 193.221544 -340.724476) (xy 193.169708 -340.739535) (xy 193.116266 -340.747139)
			(xy 193.089276 -340.747604) (xy 193.062024 -340.747145) (xy 193.008075 -340.739385) (xy 192.95578 -340.724026)
			(xy 192.906202 -340.701382) (xy 192.860352 -340.671913) (xy 192.819162 -340.636219) (xy 192.78347 -340.595026)
			(xy 192.754005 -340.549173) (xy 192.731364 -340.499594) (xy 192.716009 -340.447298) (xy 192.708253 -340.393348)
			(xy 192.707768 -340.366096) (xy 192.708215 -340.338725) (xy 192.716035 -340.284544) (xy 192.731528 -340.23204)
			(xy 192.754374 -340.182294) (xy 192.784104 -340.136328) (xy 192.801748 -340.115398) (xy 192.807844 -340.108286)
			(xy 192.814194 -340.091268) (xy 192.814194 -340.005924) (xy 192.807844 -339.988906) (xy 192.801748 -339.981794)
			(xy 192.7841 -339.960869) (xy 192.754388 -339.914895) (xy 192.731553 -339.865146) (xy 192.716064 -339.812643)
			(xy 192.70824 -339.758466) (xy 192.707768 -339.731096) (xy 192.707879 -339.719764) (xy 192.70928 -339.697144)
			(xy 192.710562 -339.685884) (xy 192.712086 -339.672422) (xy 192.701926 -339.648038) (xy 192.612772 -339.577934)
			(xy 192.586356 -339.57387) (xy 192.57391 -339.578442) (xy 192.541622 -339.58982) (xy 192.474278 -339.602088)
			(xy 192.440052 -339.602826) (xy 192.4128 -339.602367) (xy 192.358853 -339.594604) (xy 192.306559 -339.579244)
			(xy 192.256982 -339.556599) (xy 192.211133 -339.527129) (xy 192.169944 -339.491435) (xy 192.134253 -339.450243)
			(xy 192.104787 -339.404391) (xy 192.082145 -339.354813) (xy 192.066789 -339.302518) (xy 192.059031 -339.24857)
			(xy 192.058544 -339.221318) (xy 190.42126 -339.221318) (xy 190.420862 -339.248574) (xy 190.413101 -339.302529)
			(xy 190.39774 -339.354831) (xy 190.375092 -339.404415) (xy 190.345618 -339.45027) (xy 190.309917 -339.491464)
			(xy 190.268717 -339.527157) (xy 190.222857 -339.556624) (xy 190.173269 -339.579263) (xy 190.120965 -339.594615)
			(xy 190.067008 -339.602366) (xy 190.039752 -339.602826) (xy 190.009246 -339.602249) (xy 189.949011 -339.592544)
			(xy 189.919864 -339.583522) (xy 189.907926 -339.579458) (xy 189.883034 -339.583776) (xy 189.79642 -339.649816)
			(xy 189.785752 -339.672676) (xy 189.786514 -339.685376) (xy 189.787022 -339.705696) (xy 189.786573 -339.733067)
			(xy 189.778754 -339.787248) (xy 189.763262 -339.839752) (xy 189.740416 -339.889498) (xy 189.710686 -339.935464)
			(xy 189.693042 -339.956394) (xy 189.686946 -339.963506) (xy 189.680596 -339.980524) (xy 189.680342 -340.066122)
			(xy 189.686692 -340.082886) (xy 189.693042 -340.089998) (xy 189.710653 -340.11094) (xy 189.740304 -340.156929)
			(xy 189.763084 -340.20668) (xy 189.778526 -340.259175) (xy 189.786312 -340.313336) (xy 189.786768 -340.340696)
			(xy 189.786768 -340.975696) (xy 189.786142 -341.006825) (xy 189.776056 -341.068261) (xy 189.756135 -341.127246)
			(xy 189.742064 -341.15502) (xy 189.739244 -341.160581) (xy 189.736173 -341.172663) (xy 189.735968 -341.178896)
			(xy 189.735968 -341.864696) (xy 193.232786 -341.864696) (xy 193.233253 -341.837326) (xy 193.241071 -341.783147)
			(xy 193.25656 -341.730644) (xy 193.279402 -341.680897) (xy 193.309125 -341.63493) (xy 193.326766 -341.613998)
			(xy 193.332862 -341.606886) (xy 193.339212 -341.589868) (xy 193.339212 -341.504524) (xy 193.332862 -341.487506)
			(xy 193.326766 -341.480394) (xy 193.309105 -341.459479) (xy 193.279398 -341.413501) (xy 193.256567 -341.363749)
			(xy 193.241081 -341.311245) (xy 193.233257 -341.257066) (xy 193.232786 -341.229696) (xy 193.233272 -341.202445)
			(xy 193.241028 -341.148497) (xy 193.256383 -341.096202) (xy 193.279025 -341.046625) (xy 193.308491 -341.000775)
			(xy 193.344182 -340.959584) (xy 193.385373 -340.923893) (xy 193.431223 -340.894427) (xy 193.4808 -340.871785)
			(xy 193.533095 -340.85643) (xy 193.587043 -340.848674) (xy 193.641545 -340.848674) (xy 193.695493 -340.85643)
			(xy 193.747788 -340.871785) (xy 193.797365 -340.894427) (xy 193.843215 -340.923893) (xy 193.884406 -340.959584)
			(xy 193.920097 -341.000775) (xy 193.949563 -341.046625) (xy 193.972205 -341.096202) (xy 193.98756 -341.148497)
			(xy 193.995316 -341.202445) (xy 193.995802 -341.229696) (xy 193.995333 -341.257066) (xy 193.987516 -341.311245)
			(xy 193.972027 -341.363748) (xy 193.949186 -341.413495) (xy 193.919463 -341.459462) (xy 193.901822 -341.480394)
			(xy 193.895726 -341.487506) (xy 193.889376 -341.504524) (xy 193.889376 -341.589868) (xy 193.895726 -341.606886)
			(xy 193.901822 -341.613998) (xy 193.919477 -341.634917) (xy 193.949186 -341.680894) (xy 193.972018 -341.730645)
			(xy 193.987506 -341.783148) (xy 193.99533 -341.837326) (xy 193.995452 -341.844376) (xy 195.422266 -341.844376)
			(xy 195.422702 -341.817004) (xy 195.430525 -341.762823) (xy 195.44602 -341.710319) (xy 195.468869 -341.660573)
			(xy 195.498601 -341.614608) (xy 195.516246 -341.593678) (xy 195.522342 -341.586566) (xy 195.528692 -341.569548)
			(xy 195.528692 -341.484204) (xy 195.522342 -341.467186) (xy 195.516246 -341.460074) (xy 195.498635 -341.439119)
			(xy 195.468918 -341.393153) (xy 195.446075 -341.343412) (xy 195.430578 -341.290916) (xy 195.422743 -341.236744)
			(xy 195.422266 -341.209376) (xy 195.422752 -341.182125) (xy 195.430508 -341.128177) (xy 195.445863 -341.075882)
			(xy 195.468505 -341.026305) (xy 195.497971 -340.980455) (xy 195.533662 -340.939264) (xy 195.574853 -340.903573)
			(xy 195.620703 -340.874107) (xy 195.67028 -340.851465) (xy 195.722575 -340.83611) (xy 195.776523 -340.828354)
			(xy 195.831025 -340.828354) (xy 195.884973 -340.83611) (xy 195.937268 -340.851465) (xy 195.986845 -340.874107)
			(xy 196.032695 -340.903573) (xy 196.073886 -340.939264) (xy 196.109577 -340.980455) (xy 196.139043 -341.026305)
			(xy 196.161685 -341.075882) (xy 196.17704 -341.128177) (xy 196.184796 -341.182125) (xy 196.185282 -341.209376)
			(xy 196.184806 -341.236746) (xy 196.176991 -341.290925) (xy 196.161505 -341.343428) (xy 196.138665 -341.393175)
			(xy 196.108942 -341.439142) (xy 196.091302 -341.460074) (xy 196.085206 -341.467186) (xy 196.078856 -341.484204)
			(xy 196.078856 -341.569548) (xy 196.085206 -341.586566) (xy 196.091302 -341.593678) (xy 196.108945 -341.614607)
			(xy 196.138656 -341.660581) (xy 196.161491 -341.710329) (xy 196.176981 -341.76283) (xy 196.184809 -341.817007)
			(xy 196.185282 -341.844376) (xy 196.184796 -341.871627) (xy 196.17704 -341.925575) (xy 196.161685 -341.97787)
			(xy 196.139043 -342.027447) (xy 196.109577 -342.073297) (xy 196.073886 -342.114488) (xy 196.032695 -342.150179)
			(xy 195.986845 -342.179645) (xy 195.937268 -342.202287) (xy 195.884973 -342.217642) (xy 195.831025 -342.225398)
			(xy 195.776523 -342.225398) (xy 195.722575 -342.217642) (xy 195.67028 -342.202287) (xy 195.620703 -342.179645)
			(xy 195.574853 -342.150179) (xy 195.533662 -342.114488) (xy 195.497971 -342.073297) (xy 195.468505 -342.027447)
			(xy 195.445863 -341.97787) (xy 195.430508 -341.925575) (xy 195.422752 -341.871627) (xy 195.422266 -341.844376)
			(xy 193.995452 -341.844376) (xy 193.995802 -341.864696) (xy 193.995316 -341.891947) (xy 193.98756 -341.945895)
			(xy 193.972205 -341.99819) (xy 193.949563 -342.047767) (xy 193.920097 -342.093617) (xy 193.884406 -342.134808)
			(xy 193.843215 -342.170499) (xy 193.797365 -342.199965) (xy 193.747788 -342.222607) (xy 193.695493 -342.237962)
			(xy 193.641545 -342.245718) (xy 193.587043 -342.245718) (xy 193.533095 -342.237962) (xy 193.4808 -342.222607)
			(xy 193.431223 -342.199965) (xy 193.385373 -342.170499) (xy 193.344182 -342.134808) (xy 193.308491 -342.093617)
			(xy 193.279025 -342.047767) (xy 193.256383 -341.99819) (xy 193.241028 -341.945895) (xy 193.233272 -341.891947)
			(xy 193.232786 -341.864696) (xy 189.735968 -341.864696) (xy 189.735968 -342.922352) (xy 202.582016 -342.922352)
			(xy 202.586087 -342.86673) (xy 202.598213 -342.812293) (xy 202.618136 -342.760202) (xy 202.645432 -342.711567)
			(xy 202.679518 -342.667424) (xy 202.719667 -342.628715) (xy 202.765025 -342.596264) (xy 202.814625 -342.570763)
			(xy 202.867409 -342.552756) (xy 202.922252 -342.542626) (xy 202.977986 -342.540589) (xy 203.033423 -342.546689)
			(xy 203.08738 -342.560795) (xy 203.138709 -342.582607) (xy 203.186315 -342.611661) (xy 203.229183 -342.647336)
			(xy 203.2664 -342.688873) (xy 203.297173 -342.735386) (xy 203.320845 -342.785883) (xy 203.336913 -342.83929)
			(xy 203.345033 -342.894466) (xy 203.345542 -342.922352) (xy 203.345033 -342.950238) (xy 203.336913 -343.005414)
			(xy 203.320845 -343.058821) (xy 203.297173 -343.109318) (xy 203.2664 -343.155831) (xy 203.229183 -343.197368)
			(xy 203.186315 -343.233043) (xy 203.138709 -343.262097) (xy 203.08738 -343.283909) (xy 203.033423 -343.298015)
			(xy 202.977986 -343.304115) (xy 202.922252 -343.302078) (xy 202.867409 -343.291948) (xy 202.814625 -343.273941)
			(xy 202.765025 -343.24844) (xy 202.719667 -343.215989) (xy 202.679518 -343.17728) (xy 202.645432 -343.133137)
			(xy 202.618136 -343.084502) (xy 202.598213 -343.032411) (xy 202.586087 -342.977974) (xy 202.582016 -342.922352)
			(xy 189.735968 -342.922352) (xy 189.735968 -344.8304) (xy 201.363834 -344.8304) (xy 201.36434 -344.801482)
			(xy 201.373069 -344.74431) (xy 201.390329 -344.68911) (xy 201.415723 -344.637149) (xy 201.448669 -344.589615)
			(xy 201.488413 -344.547599) (xy 201.5109 -344.52941) (xy 201.519653 -344.521839) (xy 201.529841 -344.501087)
			(xy 201.530458 -344.489532) (xy 201.530458 -344.409268) (xy 201.529863 -344.397703) (xy 201.519687 -344.376931)
			(xy 201.5109 -344.36939) (xy 201.488412 -344.351205) (xy 201.448677 -344.309184) (xy 201.415738 -344.261648)
			(xy 201.390351 -344.209685) (xy 201.373096 -344.154487) (xy 201.364368 -344.097316) (xy 201.363834 -344.0684)
			(xy 201.36432 -344.041149) (xy 201.372076 -343.987201) (xy 201.387431 -343.934906) (xy 201.410073 -343.885329)
			(xy 201.439539 -343.839479) (xy 201.47523 -343.798288) (xy 201.516421 -343.762597) (xy 201.562271 -343.733131)
			(xy 201.611848 -343.710489) (xy 201.664143 -343.695134) (xy 201.718091 -343.687378) (xy 201.772593 -343.687378)
			(xy 201.826541 -343.695134) (xy 201.878836 -343.710489) (xy 201.928413 -343.733131) (xy 201.974263 -343.762597)
			(xy 202.015454 -343.798288) (xy 202.051145 -343.839479) (xy 202.080611 -343.885329) (xy 202.103253 -343.934906)
			(xy 202.118608 -343.987201) (xy 202.126364 -344.041149) (xy 202.12685 -344.0684) (xy 202.126351 -344.097318)
			(xy 202.11762 -344.154491) (xy 202.10036 -344.209691) (xy 202.074965 -344.261653) (xy 202.052577 -344.293952)
			(xy 205.807816 -344.293952) (xy 205.811887 -344.23833) (xy 205.824013 -344.183893) (xy 205.843936 -344.131802)
			(xy 205.871232 -344.083167) (xy 205.905318 -344.039024) (xy 205.945467 -344.000315) (xy 205.990825 -343.967864)
			(xy 206.040425 -343.942363) (xy 206.093209 -343.924356) (xy 206.148052 -343.914226) (xy 206.203786 -343.912189)
			(xy 206.259223 -343.918289) (xy 206.31318 -343.932395) (xy 206.364509 -343.954207) (xy 206.412115 -343.983261)
			(xy 206.454983 -344.018936) (xy 206.4922 -344.060473) (xy 206.522973 -344.106986) (xy 206.546645 -344.157483)
			(xy 206.562713 -344.21089) (xy 206.570833 -344.266066) (xy 206.571342 -344.293952) (xy 206.570833 -344.321838)
			(xy 206.562713 -344.377014) (xy 206.546645 -344.430421) (xy 206.522973 -344.480918) (xy 206.4922 -344.527431)
			(xy 206.454983 -344.568968) (xy 206.412115 -344.604643) (xy 206.364509 -344.633697) (xy 206.31318 -344.655509)
			(xy 206.259223 -344.669615) (xy 206.203786 -344.675715) (xy 206.148052 -344.673678) (xy 206.093209 -344.663548)
			(xy 206.040425 -344.645541) (xy 205.990825 -344.62004) (xy 205.945467 -344.587589) (xy 205.905318 -344.54888)
			(xy 205.871232 -344.504737) (xy 205.843936 -344.456102) (xy 205.824013 -344.404011) (xy 205.811887 -344.349574)
			(xy 205.807816 -344.293952) (xy 202.052577 -344.293952) (xy 202.042017 -344.309186) (xy 202.002272 -344.351201)
			(xy 201.979784 -344.36939) (xy 201.971028 -344.376958) (xy 201.960842 -344.397712) (xy 201.960226 -344.409268)
			(xy 201.960226 -344.489532) (xy 201.960826 -344.501096) (xy 201.970999 -344.521868) (xy 201.979784 -344.52941)
			(xy 202.002269 -344.547599) (xy 202.042005 -344.589619) (xy 202.074944 -344.637154) (xy 202.100332 -344.689116)
			(xy 202.117588 -344.744314) (xy 202.126316 -344.801484) (xy 202.12685 -344.8304) (xy 202.126364 -344.857651)
			(xy 202.118608 -344.911599) (xy 202.103253 -344.963894) (xy 202.080611 -345.013471) (xy 202.051145 -345.059321)
			(xy 202.015454 -345.100512) (xy 201.974263 -345.136203) (xy 201.928413 -345.165669) (xy 201.878836 -345.188311)
			(xy 201.826541 -345.203666) (xy 201.772593 -345.211422) (xy 201.718091 -345.211422) (xy 201.664143 -345.203666)
			(xy 201.611848 -345.188311) (xy 201.562271 -345.165669) (xy 201.516421 -345.136203) (xy 201.47523 -345.100512)
			(xy 201.439539 -345.059321) (xy 201.410073 -345.013471) (xy 201.387431 -344.963894) (xy 201.372076 -344.911599)
			(xy 201.36432 -344.857651) (xy 201.363834 -344.8304) (xy 189.735968 -344.8304) (xy 189.735968 -346.583)
			(xy 201.363834 -346.583) (xy 201.36434 -346.554082) (xy 201.373069 -346.49691) (xy 201.390329 -346.44171)
			(xy 201.415723 -346.389749) (xy 201.448669 -346.342215) (xy 201.488413 -346.300199) (xy 201.5109 -346.28201)
			(xy 201.519653 -346.274439) (xy 201.529841 -346.253687) (xy 201.530458 -346.242132) (xy 201.530458 -346.161868)
			(xy 201.529863 -346.150303) (xy 201.519687 -346.129531) (xy 201.5109 -346.12199) (xy 201.488412 -346.103805)
			(xy 201.448677 -346.061784) (xy 201.415738 -346.014248) (xy 201.390351 -345.962285) (xy 201.373096 -345.907087)
			(xy 201.364368 -345.849916) (xy 201.363834 -345.821) (xy 201.36432 -345.793749) (xy 201.372076 -345.739801)
			(xy 201.387431 -345.687506) (xy 201.410073 -345.637929) (xy 201.439539 -345.592079) (xy 201.47523 -345.550888)
			(xy 201.516421 -345.515197) (xy 201.562271 -345.485731) (xy 201.611848 -345.463089) (xy 201.664143 -345.447734)
			(xy 201.718091 -345.439978) (xy 201.772593 -345.439978) (xy 201.826541 -345.447734) (xy 201.878836 -345.463089)
			(xy 201.928413 -345.485731) (xy 201.974263 -345.515197) (xy 202.015454 -345.550888) (xy 202.051145 -345.592079)
			(xy 202.080611 -345.637929) (xy 202.103253 -345.687506) (xy 202.118608 -345.739801) (xy 202.126364 -345.793749)
			(xy 202.12685 -345.821) (xy 202.126351 -345.849918) (xy 202.11762 -345.907091) (xy 202.10036 -345.962291)
			(xy 202.074965 -346.014253) (xy 202.042017 -346.061786) (xy 202.002272 -346.103801) (xy 201.979784 -346.12199)
			(xy 201.971028 -346.129558) (xy 201.960842 -346.150312) (xy 201.960226 -346.161868) (xy 201.960226 -346.242132)
			(xy 201.960826 -346.253696) (xy 201.970999 -346.274468) (xy 201.979784 -346.28201) (xy 202.002269 -346.300199)
			(xy 202.042005 -346.342219) (xy 202.074944 -346.389754) (xy 202.100332 -346.441716) (xy 202.117588 -346.496914)
			(xy 202.126316 -346.554084) (xy 202.12685 -346.583) (xy 202.126364 -346.610251) (xy 202.118608 -346.664199)
			(xy 202.103253 -346.716494) (xy 202.080611 -346.766071) (xy 202.051145 -346.811921) (xy 202.015454 -346.853112)
			(xy 201.974263 -346.888803) (xy 201.928413 -346.918269) (xy 201.878836 -346.940911) (xy 201.826541 -346.956266)
			(xy 201.772593 -346.964022) (xy 201.718091 -346.964022) (xy 201.664143 -346.956266) (xy 201.611848 -346.940911)
			(xy 201.562271 -346.918269) (xy 201.516421 -346.888803) (xy 201.47523 -346.853112) (xy 201.439539 -346.811921)
			(xy 201.410073 -346.766071) (xy 201.387431 -346.716494) (xy 201.372076 -346.664199) (xy 201.36432 -346.610251)
			(xy 201.363834 -346.583) (xy 189.735968 -346.583) (xy 189.735968 -347.468952) (xy 189.735438 -347.498925)
			(xy 189.72612 -347.55814) (xy 189.707643 -347.615165) (xy 189.680464 -347.668593) (xy 189.645253 -347.717105)
			(xy 189.624462 -347.7387) (xy 188.945266 -348.417642) (xy 188.93841 -348.42503) (xy 188.930701 -348.443639)
			(xy 188.93028 -348.45371) (xy 188.93028 -353.069398) (xy 188.929775 -353.099371) (xy 188.920451 -353.158588)
			(xy 188.901968 -353.215613) (xy 188.874783 -353.26904) (xy 188.845629 -353.3092) (xy 191.564233 -353.3092)
			(xy 191.568401 -353.253584) (xy 191.580811 -353.19921) (xy 191.601187 -353.147293) (xy 191.629072 -353.098992)
			(xy 191.663845 -353.055387) (xy 191.704728 -353.017452) (xy 191.750809 -352.986033) (xy 191.801057 -352.961833)
			(xy 191.854351 -352.945392) (xy 191.9095 -352.937078) (xy 191.937386 -352.936556) (xy 191.963807 -352.937032)
			(xy 192.016121 -352.944479) (xy 192.066859 -352.959241) (xy 192.115004 -352.98102) (xy 192.15959 -353.009381)
			(xy 192.179956 -353.026218) (xy 192.186814 -353.032314) (xy 192.203832 -353.03841) (xy 192.28816 -353.03841)
			(xy 192.305178 -353.032314) (xy 192.312036 -353.026218) (xy 192.332402 -353.009379) (xy 192.376988 -352.981014)
			(xy 192.425132 -352.959227) (xy 192.475869 -352.944456) (xy 192.528184 -352.936996) (xy 192.581028 -352.936996)
			(xy 192.633343 -352.944456) (xy 192.68408 -352.959227) (xy 192.732224 -352.981014) (xy 192.77681 -353.009379)
			(xy 192.797176 -353.026218) (xy 192.804034 -353.032314) (xy 192.821052 -353.03841) (xy 192.90538 -353.03841)
			(xy 192.922398 -353.032314) (xy 192.929256 -353.026218) (xy 192.943154 -353.014639) (xy 192.972794 -352.993899)
			(xy 192.988438 -352.984816) (xy 192.998852 -352.978974) (xy 193.01206 -352.95967) (xy 193.0273 -352.857054)
			(xy 193.020442 -352.834956) (xy 193.012314 -352.82632) (xy 192.992734 -352.804937) (xy 192.959615 -352.757351)
			(xy 192.934083 -352.705299) (xy 192.916729 -352.649981) (xy 192.907952 -352.592672) (xy 192.907412 -352.563684)
			(xy 192.907931 -352.536111) (xy 192.915872 -352.481541) (xy 192.931586 -352.428682) (xy 192.954746 -352.378635)
			(xy 192.98487 -352.332444) (xy 193.021329 -352.291071) (xy 193.042032 -352.272854) (xy 193.050172 -352.265271)
			(xy 193.059513 -352.245105) (xy 193.060066 -352.233992) (xy 193.060066 -352.156776) (xy 193.059538 -352.145661)
			(xy 193.050173 -352.125502) (xy 193.042032 -352.117914) (xy 193.021331 -352.099692) (xy 192.984858 -352.058326)
			(xy 192.954724 -352.012139) (xy 192.931556 -351.962093) (xy 192.915838 -351.909232) (xy 192.907898 -351.854658)
			(xy 192.907412 -351.827084) (xy 192.907898 -351.799833) (xy 192.915654 -351.745885) (xy 192.931009 -351.69359)
			(xy 192.953651 -351.644013) (xy 192.983117 -351.598163) (xy 193.018808 -351.556972) (xy 193.059999 -351.521281)
			(xy 193.105849 -351.491815) (xy 193.155426 -351.469173) (xy 193.207721 -351.453818) (xy 193.261669 -351.446062)
			(xy 193.316171 -351.446062) (xy 193.370119 -351.453818) (xy 193.422414 -351.469173) (xy 193.471991 -351.491815)
			(xy 193.517841 -351.521281) (xy 193.559032 -351.556972) (xy 193.594723 -351.598163) (xy 193.624189 -351.644013)
			(xy 193.646831 -351.69359) (xy 193.662186 -351.745885) (xy 193.669942 -351.799833) (xy 193.670428 -351.827084)
			(xy 193.669942 -351.854658) (xy 193.661992 -351.909229) (xy 193.64627 -351.962088) (xy 193.623104 -352.012134)
			(xy 193.592976 -352.058324) (xy 193.556513 -352.099697) (xy 193.535808 -352.117914) (xy 193.527689 -352.125516)
			(xy 193.518335 -352.145668) (xy 193.517774 -352.156776) (xy 193.517774 -352.233992) (xy 193.518307 -352.245107)
			(xy 193.527668 -352.265267) (xy 193.535808 -352.272854) (xy 193.556502 -352.291084) (xy 193.592973 -352.332449)
			(xy 193.623107 -352.378635) (xy 193.646276 -352.428679) (xy 193.661996 -352.481538) (xy 193.66994 -352.53611)
			(xy 193.670428 -352.563684) (xy 193.669837 -352.592875) (xy 193.660932 -352.650574) (xy 193.643341 -352.706243)
			(xy 193.617476 -352.758583) (xy 193.583941 -352.806372) (xy 193.543517 -352.848496) (xy 193.497149 -352.88397)
			(xy 193.4718 -352.898456) (xy 193.461386 -352.904298) (xy 193.447924 -352.923094) (xy 193.43116 -353.025456)
			(xy 193.437764 -353.047808) (xy 193.445638 -353.056444) (xy 193.464098 -353.077219) (xy 193.495309 -353.123201)
			(xy 193.519344 -353.173309) (xy 193.535671 -353.22643) (xy 193.543929 -353.281387) (xy 193.544444 -353.309174)
			(xy 193.543919 -353.335788) (xy 193.536348 -353.388476) (xy 193.521355 -353.43955) (xy 193.499246 -353.48797)
			(xy 193.470472 -353.53275) (xy 193.435617 -353.572981) (xy 193.395392 -353.607841) (xy 193.350615 -353.636621)
			(xy 193.302198 -353.658737) (xy 193.251127 -353.673737) (xy 193.19844 -353.681316) (xy 193.171826 -353.681792)
			(xy 193.145405 -353.681321) (xy 193.09309 -353.673875) (xy 193.042351 -353.659113) (xy 192.994207 -353.637332)
			(xy 192.949621 -353.608969) (xy 192.929256 -353.59213) (xy 192.922398 -353.586034) (xy 192.90538 -353.579938)
			(xy 192.821052 -353.579938) (xy 192.804034 -353.586034) (xy 192.797176 -353.59213) (xy 192.77681 -353.608969)
			(xy 192.732224 -353.637334) (xy 192.68408 -353.659121) (xy 192.633343 -353.673892) (xy 192.581028 -353.681352)
			(xy 192.528184 -353.681352) (xy 192.475869 -353.673892) (xy 192.425132 -353.659121) (xy 192.376988 -353.637334)
			(xy 192.332402 -353.608969) (xy 192.312036 -353.59213) (xy 192.305178 -353.586034) (xy 192.28816 -353.579938)
			(xy 192.203832 -353.579938) (xy 192.186814 -353.586034) (xy 192.179956 -353.59213) (xy 192.159598 -353.608978)
			(xy 192.115007 -353.637334) (xy 192.066861 -353.659112) (xy 192.016122 -353.673877) (xy 191.963808 -353.681334)
			(xy 191.937386 -353.681792) (xy 191.9095 -353.681322) (xy 191.854351 -353.673008) (xy 191.801057 -353.656567)
			(xy 191.750809 -353.632367) (xy 191.704728 -353.600948) (xy 191.663845 -353.563013) (xy 191.629072 -353.519408)
			(xy 191.601187 -353.471107) (xy 191.580811 -353.41919) (xy 191.568401 -353.364816) (xy 191.564233 -353.3092)
			(xy 188.845629 -353.3092) (xy 188.839567 -353.317551) (xy 188.818774 -353.339146) (xy 188.502544 -353.655122)
			(xy 188.496085 -353.662181) (xy 188.488449 -353.679707) (xy 188.487787 -353.698812) (xy 188.490606 -353.707954)
			(xy 188.525912 -353.808284) (xy 188.548772 -353.826572) (xy 188.56325 -353.828096) (xy 188.590936 -353.831599)
			(xy 188.64494 -353.845667) (xy 188.696318 -353.867454) (xy 188.743973 -353.896493) (xy 188.786888 -353.932167)
			(xy 188.824148 -353.973712) (xy 188.854957 -354.020243) (xy 188.878657 -354.070767) (xy 188.894743 -354.124204)
			(xy 188.902872 -354.179415) (xy 188.903356 -354.207318) (xy 188.902839 -354.234568) (xy 188.895081 -354.288512)
			(xy 188.879726 -354.340803) (xy 188.857087 -354.390377) (xy 188.827623 -354.436225) (xy 188.791935 -354.477414)
			(xy 188.750749 -354.513105) (xy 188.704903 -354.542572) (xy 188.655331 -354.565216) (xy 188.603041 -354.580575)
			(xy 188.549097 -354.588337) (xy 188.521848 -354.588826) (xy 188.493756 -354.588352) (xy 188.438176 -354.580137)
			(xy 188.384401 -354.563861) (xy 188.333593 -354.539877) (xy 188.286851 -354.508703) (xy 188.245184 -354.471013)
			(xy 188.226954 -354.449634) (xy 188.216794 -354.436934) (xy 188.18606 -354.428552) (xy 188.08065 -354.466144)
			(xy 188.071034 -354.470184) (xy 188.055812 -354.484408) (xy 188.047439 -354.503484) (xy 188.046868 -354.513896)
			(xy 188.046868 -354.646484) (xy 188.047284 -354.656555) (xy 188.055009 -354.675153) (xy 188.061854 -354.682552)
			(xy 188.212476 -354.83292) (xy 188.233303 -354.854494) (xy 188.268555 -354.903002) (xy 188.295781 -354.956429)
			(xy 188.314309 -355.013459) (xy 188.323683 -355.072686) (xy 188.324236 -355.102668) (xy 188.323715 -355.129919)
			(xy 188.315963 -355.183866) (xy 188.300613 -355.236161) (xy 188.277976 -355.285739) (xy 188.248514 -355.331591)
			(xy 188.212826 -355.372784) (xy 188.171639 -355.408478) (xy 188.125792 -355.437947) (xy 188.076218 -355.460592)
			(xy 188.023925 -355.47595) (xy 187.969979 -355.483711) (xy 187.942728 -355.484176) (xy 187.912752 -355.483558)
			(xy 187.853538 -355.474173) (xy 187.796521 -355.455644) (xy 187.743102 -355.428428) (xy 187.694595 -355.393193)
			(xy 187.67298 -355.372416) (xy 187.395866 -355.095302) (xy 187.375138 -355.073653) (xy 187.339946 -355.025142)
			(xy 187.312771 -354.971726) (xy 187.294283 -354.914718) (xy 187.284935 -354.85552) (xy 187.28436 -354.825554)
			(xy 187.28436 -353.95281) (xy 187.284858 -353.922836) (xy 187.294183 -353.863619) (xy 187.312666 -353.806593)
			(xy 187.339853 -353.753166) (xy 187.375071 -353.704656) (xy 187.395866 -353.683062) (xy 187.555124 -353.523804)
			(xy 187.561425 -353.516969) (xy 187.569009 -353.500012) (xy 187.570022 -353.481464) (xy 187.56757 -353.472496)
			(xy 187.53582 -353.372674) (xy 187.514484 -353.354386) (xy 187.50026 -353.351846) (xy 187.473909 -353.346955)
			(xy 187.422816 -353.330771) (xy 187.374493 -353.307593) (xy 187.32989 -353.277879) (xy 187.289886 -353.242213)
			(xy 187.255269 -353.201298) (xy 187.226721 -353.15594) (xy 187.204804 -353.107031) (xy 187.189949 -353.055537)
			(xy 187.18245 -353.002469) (xy 187.181998 -352.975672) (xy 185.121261 -352.975672) (xy 185.1152 -353.011486)
			(xy 185.121296 -353.03333) (xy 185.128662 -353.041712) (xy 185.145418 -353.062057) (xy 185.173643 -353.106568)
			(xy 185.19531 -353.154615) (xy 185.209986 -353.205236) (xy 185.217379 -353.257421) (xy 185.217816 -353.283774)
			(xy 185.217342 -353.310391) (xy 185.209769 -353.363084) (xy 185.194774 -353.414163) (xy 185.172662 -353.462588)
			(xy 185.143883 -353.507373) (xy 185.109023 -353.547606) (xy 185.068792 -353.582469) (xy 185.024009 -353.61125)
			(xy 184.975586 -353.633366) (xy 184.924508 -353.648364) (xy 184.871815 -353.65594) (xy 184.845198 -353.656392)
			(xy 184.818776 -353.655937) (xy 184.76646 -353.648487) (xy 184.715722 -353.633721) (xy 184.667577 -353.611937)
			(xy 184.622993 -353.58357) (xy 184.602628 -353.56673) (xy 184.59577 -353.560634) (xy 184.578752 -353.554538)
			(xy 184.494424 -353.554538) (xy 184.477406 -353.560634) (xy 184.470548 -353.56673) (xy 184.450182 -353.583569)
			(xy 184.405596 -353.611934) (xy 184.357452 -353.633721) (xy 184.306715 -353.648492) (xy 184.2544 -353.655952)
			(xy 184.201556 -353.655952) (xy 184.149241 -353.648492) (xy 184.098504 -353.633721) (xy 184.05036 -353.611934)
			(xy 184.005774 -353.583569) (xy 183.985408 -353.56673) (xy 183.97855 -353.560634) (xy 183.961532 -353.554538)
			(xy 183.877204 -353.554538) (xy 183.860186 -353.560634) (xy 183.853328 -353.56673) (xy 183.832943 -353.583544)
			(xy 183.78836 -353.611905) (xy 183.74022 -353.63369) (xy 183.689487 -353.648463) (xy 183.637178 -353.655929)
			(xy 183.610758 -353.656392) (xy 183.582873 -353.65592) (xy 183.527727 -353.647602) (xy 183.474437 -353.631159)
			(xy 183.424192 -353.606958) (xy 183.378116 -353.575538) (xy 183.337236 -353.537603) (xy 183.302466 -353.493999)
			(xy 183.274583 -353.4457) (xy 183.25421 -353.393785) (xy 183.241801 -353.339414) (xy 183.237633 -353.2838)
			(xy 180.528838 -353.2838) (xy 180.5274 -353.28578) (xy 180.506624 -353.307396) (xy 180.183282 -353.630738)
			(xy 180.176837 -353.637701) (xy 180.169163 -353.655034) (xy 180.168368 -353.673974) (xy 180.17109 -353.683062)
			(xy 180.20538 -353.783392) (xy 180.227986 -353.801426) (xy 180.242464 -353.803458) (xy 180.26981 -353.807282)
			(xy 180.323048 -353.82193) (xy 180.373617 -353.844104) (xy 180.42046 -353.873339) (xy 180.462596 -353.909024)
			(xy 180.499145 -353.950414) (xy 180.529342 -353.996642) (xy 180.552555 -354.046743) (xy 180.5683 -354.099667)
			(xy 180.576247 -354.154309) (xy 180.576728 -354.181918) (xy 180.576239 -354.209169) (xy 180.568481 -354.263115)
			(xy 180.553124 -354.315409) (xy 180.530482 -354.364985) (xy 180.501016 -354.410834) (xy 180.465325 -354.452024)
			(xy 180.424136 -354.487715) (xy 180.378287 -354.517181) (xy 180.328711 -354.539823) (xy 180.276417 -354.55518)
			(xy 180.222471 -354.562939) (xy 180.19522 -354.563426) (xy 180.169743 -354.563013) (xy 180.119241 -354.55624)
			(xy 180.070089 -354.542813) (xy 180.023158 -354.522969) (xy 179.979282 -354.497062) (xy 179.959 -354.481638)
			(xy 179.947316 -354.47224) (xy 179.918614 -354.469192) (xy 179.82311 -354.515674) (xy 179.814723 -354.5202)
			(xy 179.801766 -354.534152) (xy 179.794806 -354.551874) (xy 179.794408 -354.561394) (xy 179.794408 -354.987352)
			(xy 179.793922 -355.014585) (xy 179.786171 -355.068497) (xy 179.770826 -355.120757) (xy 179.7482 -355.170301)
			(xy 179.718753 -355.216121) (xy 179.683086 -355.257284) (xy 179.641923 -355.292951) (xy 179.596103 -355.322398)
			(xy 179.546559 -355.345024) (xy 179.494299 -355.360369) (xy 179.440387 -355.36812) (xy 179.385921 -355.36812)
			(xy 179.332009 -355.360369) (xy 179.279749 -355.345024) (xy 179.230205 -355.322398) (xy 179.184385 -355.292951)
			(xy 179.143222 -355.257284) (xy 179.107555 -355.216121) (xy 179.078108 -355.170301) (xy 179.055482 -355.120757)
			(xy 179.040137 -355.068497) (xy 179.032386 -355.014585) (xy 179.0319 -354.987352) (xy 179.0319 -353.86137)
			(xy 179.032453 -353.831399) (xy 179.041767 -353.772185) (xy 179.060239 -353.71516) (xy 179.087412 -353.661732)
			(xy 179.122618 -353.613218) (xy 179.143406 -353.591622) (xy 179.235608 -353.499674) (xy 179.241941 -353.492757)
			(xy 179.249485 -353.475603) (xy 179.250357 -353.456883) (xy 179.2478 -353.447858) (xy 179.215288 -353.348036)
			(xy 179.193444 -353.329494) (xy 179.178966 -353.327462) (xy 179.15228 -353.322887) (xy 179.100472 -353.307163)
			(xy 179.051404 -353.284277) (xy 179.006063 -353.254687) (xy 178.965358 -353.218987) (xy 178.930106 -353.177894)
			(xy 178.901013 -353.132232) (xy 178.878664 -353.082918) (xy 178.863508 -353.030941) (xy 178.855847 -352.977343)
			(xy 178.85537 -352.950272) (xy 168.449244 -352.950272) (xy 168.449244 -354.968302) (xy 176.841656 -354.968302)
			(xy 176.845727 -354.91268) (xy 176.857853 -354.858243) (xy 176.877776 -354.806152) (xy 176.905072 -354.757517)
			(xy 176.939158 -354.713374) (xy 176.979307 -354.674665) (xy 177.024665 -354.642214) (xy 177.074265 -354.616713)
			(xy 177.127049 -354.598706) (xy 177.181892 -354.588576) (xy 177.237626 -354.586539) (xy 177.293063 -354.592639)
			(xy 177.34702 -354.606745) (xy 177.398349 -354.628557) (xy 177.445955 -354.657611) (xy 177.488823 -354.693286)
			(xy 177.52604 -354.734823) (xy 177.556813 -354.781336) (xy 177.580485 -354.831833) (xy 177.596553 -354.88524)
			(xy 177.604673 -354.940416) (xy 177.605182 -354.968302) (xy 177.604673 -354.996188) (xy 177.596553 -355.051364)
			(xy 177.580485 -355.104771) (xy 177.556813 -355.155268) (xy 177.52604 -355.201781) (xy 177.488823 -355.243318)
			(xy 177.445955 -355.278993) (xy 177.398349 -355.308047) (xy 177.34702 -355.329859) (xy 177.293063 -355.343965)
			(xy 177.237626 -355.350065) (xy 177.181892 -355.348028) (xy 177.127049 -355.337898) (xy 177.074265 -355.319891)
			(xy 177.024665 -355.29439) (xy 176.979307 -355.261939) (xy 176.939158 -355.22323) (xy 176.905072 -355.179087)
			(xy 176.877776 -355.130452) (xy 176.857853 -355.078361) (xy 176.845727 -355.023924) (xy 176.841656 -354.968302)
			(xy 168.449244 -354.968302) (xy 168.449244 -354.994718) (xy 168.449648 -355.00479) (xy 168.457383 -355.023388)
			(xy 168.46423 -355.030786) (xy 168.917874 -355.48443) (xy 177.846988 -355.48443) (xy 177.851059 -355.428808)
			(xy 177.863185 -355.374371) (xy 177.883108 -355.32228) (xy 177.910404 -355.273645) (xy 177.94449 -355.229502)
			(xy 177.984639 -355.190793) (xy 178.029997 -355.158342) (xy 178.079597 -355.132841) (xy 178.132381 -355.114834)
			(xy 178.187224 -355.104704) (xy 178.242958 -355.102667) (xy 178.298395 -355.108767) (xy 178.352352 -355.122873)
			(xy 178.403681 -355.144685) (xy 178.451287 -355.173739) (xy 178.494155 -355.209414) (xy 178.531372 -355.250951)
			(xy 178.562145 -355.297464) (xy 178.585817 -355.347961) (xy 178.601885 -355.401368) (xy 178.610005 -355.456544)
			(xy 178.610514 -355.48443) (xy 178.610005 -355.512316) (xy 178.601885 -355.567492) (xy 178.585817 -355.620899)
			(xy 178.562145 -355.671396) (xy 178.531372 -355.717909) (xy 178.500013 -355.752908) (xy 180.572918 -355.752908)
			(xy 180.573405 -355.725433) (xy 180.581296 -355.671054) (xy 180.596916 -355.618371) (xy 180.61994 -355.568478)
			(xy 180.649892 -355.52241) (xy 180.66766 -355.501448) (xy 180.673756 -355.494336) (xy 180.680106 -355.477318)
			(xy 180.680106 -355.391466) (xy 180.673756 -355.374448) (xy 180.66766 -355.367336) (xy 180.649926 -355.34635)
			(xy 180.619998 -355.300274) (xy 180.59698 -355.250386) (xy 180.581347 -355.197714) (xy 180.573422 -355.143347)
			(xy 180.572918 -355.115876) (xy 180.573404 -355.088625) (xy 180.58116 -355.034677) (xy 180.596515 -354.982382)
			(xy 180.619157 -354.932805) (xy 180.648623 -354.886955) (xy 180.684314 -354.845764) (xy 180.725505 -354.810073)
			(xy 180.771355 -354.780607) (xy 180.820932 -354.757965) (xy 180.873227 -354.74261) (xy 180.927175 -354.734854)
			(xy 180.981677 -354.734854) (xy 181.035625 -354.74261) (xy 181.08792 -354.757965) (xy 181.137497 -354.780607)
			(xy 181.183347 -354.810073) (xy 181.224538 -354.845764) (xy 181.260229 -354.886955) (xy 181.289695 -354.932805)
			(xy 181.312337 -354.982382) (xy 181.327692 -355.034677) (xy 181.335448 -355.088625) (xy 181.335934 -355.115876)
			(xy 181.335425 -355.14335) (xy 181.327537 -355.197728) (xy 181.311922 -355.25041) (xy 181.288903 -355.300303)
			(xy 181.258957 -355.346373) (xy 181.241192 -355.367336) (xy 181.235096 -355.374448) (xy 181.228746 -355.391466)
			(xy 181.228746 -355.477318) (xy 181.235096 -355.494336) (xy 181.241192 -355.501448) (xy 181.258958 -355.522408)
			(xy 181.288883 -355.56849) (xy 181.311896 -355.618385) (xy 181.327521 -355.671063) (xy 181.335436 -355.725435)
			(xy 181.335934 -355.752908) (xy 181.335448 -355.780159) (xy 181.327692 -355.834107) (xy 181.312337 -355.886402)
			(xy 181.289695 -355.935979) (xy 181.260229 -355.981829) (xy 181.224538 -356.02302) (xy 181.183347 -356.058711)
			(xy 181.137497 -356.088177) (xy 181.08792 -356.110819) (xy 181.035625 -356.126174) (xy 180.981677 -356.13393)
			(xy 180.927175 -356.13393) (xy 180.873227 -356.126174) (xy 180.820932 -356.110819) (xy 180.771355 -356.088177)
			(xy 180.725505 -356.058711) (xy 180.684314 -356.02302) (xy 180.648623 -355.981829) (xy 180.619157 -355.935979)
			(xy 180.596515 -355.886402) (xy 180.58116 -355.834107) (xy 180.573404 -355.780159) (xy 180.572918 -355.752908)
			(xy 178.500013 -355.752908) (xy 178.494155 -355.759446) (xy 178.451287 -355.795121) (xy 178.403681 -355.824175)
			(xy 178.352352 -355.845987) (xy 178.298395 -355.860093) (xy 178.242958 -355.866193) (xy 178.187224 -355.864156)
			(xy 178.132381 -355.854026) (xy 178.079597 -355.836019) (xy 178.029997 -355.810518) (xy 177.984639 -355.778067)
			(xy 177.94449 -355.739358) (xy 177.910404 -355.695215) (xy 177.883108 -355.64658) (xy 177.863185 -355.594489)
			(xy 177.851059 -355.540052) (xy 177.846988 -355.48443) (xy 168.917874 -355.48443) (xy 171.327572 -357.894128)
			(xy 171.33504 -357.900839) (xy 171.353609 -357.90842) (xy 171.36364 -357.90886) (xy 180.386482 -357.90886)
			(xy 180.39653 -357.908518) (xy 180.415127 -357.90091) (xy 180.42255 -357.894128) (xy 180.697378 -357.6193)
			(xy 180.704208 -357.611892) (xy 180.711934 -357.593299) (xy 180.712364 -357.583232) (xy 180.712364 -357.14305)
			(xy 180.712959 -357.118066) (xy 180.722707 -357.069057) (xy 180.741819 -357.022887) (xy 180.769562 -356.981327)
			(xy 180.786786 -356.963218) (xy 181.168294 -356.58171) (xy 181.186403 -356.564487) (xy 181.227961 -356.536743)
			(xy 181.274132 -356.517635) (xy 181.323142 -356.507897) (xy 181.348126 -356.507288) (xy 181.653688 -356.507288)
			(xy 181.66371 -356.50687) (xy 181.682229 -356.499202) (xy 181.696402 -356.485029) (xy 181.70407 -356.46651)
			(xy 181.704488 -356.456488) (xy 181.704488 -355.534976) (xy 181.704012 -355.524973) (xy 181.696303 -355.506511)
			(xy 181.689502 -355.499162) (xy 181.668618 -355.477545) (xy 181.633206 -355.428981) (xy 181.60585 -355.375463)
			(xy 181.587227 -355.318318) (xy 181.577798 -355.258958) (xy 181.577234 -355.228906) (xy 181.577661 -355.201651)
			(xy 181.585418 -355.147697) (xy 181.600776 -355.095396) (xy 181.623421 -355.045813) (xy 181.652892 -354.999958)
			(xy 181.688589 -354.958764) (xy 181.729787 -354.92307) (xy 181.775645 -354.893603) (xy 181.82523 -354.870963)
			(xy 181.877532 -354.855611) (xy 181.931487 -354.847858) (xy 181.958742 -354.847398) (xy 181.983978 -354.847777)
			(xy 182.034013 -354.8544) (xy 182.082733 -354.867579) (xy 182.129284 -354.887081) (xy 182.151274 -354.899468)
			(xy 182.160926 -354.90531) (xy 182.183024 -354.907342) (xy 182.277512 -354.873814) (xy 182.293514 -354.85832)
			(xy 182.297578 -354.847906) (xy 182.308279 -354.821132) (xy 182.336565 -354.770889) (xy 182.372094 -354.725479)
			(xy 182.414055 -354.685936) (xy 182.461492 -354.653162) (xy 182.513322 -354.627904) (xy 182.568365 -354.610738)
			(xy 182.625365 -354.602055) (xy 182.654194 -354.601526) (xy 182.681448 -354.601961) (xy 182.735402 -354.609718)
			(xy 182.787702 -354.625075) (xy 182.837285 -354.647719) (xy 182.88314 -354.67719) (xy 182.924333 -354.712887)
			(xy 182.960027 -354.754083) (xy 182.989494 -354.79994) (xy 183.012135 -354.849524) (xy 183.024857 -354.892864)
			(xy 185.165746 -354.892864) (xy 185.16624 -354.86529) (xy 185.174184 -354.810718) (xy 185.189903 -354.757858)
			(xy 185.213067 -354.707811) (xy 185.243196 -354.661621) (xy 185.27966 -354.62025) (xy 185.300366 -354.602034)
			(xy 185.308475 -354.594424) (xy 185.317832 -354.574278) (xy 185.3184 -354.563172) (xy 185.3184 -354.485956)
			(xy 185.317817 -354.474848) (xy 185.308489 -354.454689) (xy 185.300366 -354.447094) (xy 185.279642 -354.428897)
			(xy 185.243174 -354.387524) (xy 185.213044 -354.341331) (xy 185.189881 -354.291281) (xy 185.174167 -354.238416)
			(xy 185.16623 -354.183839) (xy 185.165746 -354.156264) (xy 185.166244 -354.129014) (xy 185.174004 -354.075069)
			(xy 185.189362 -354.022777) (xy 185.212004 -353.973203) (xy 185.241469 -353.927355) (xy 185.277159 -353.886166)
			(xy 185.318347 -353.850476) (xy 185.364194 -353.821009) (xy 185.413768 -353.798365) (xy 185.466059 -353.783007)
			(xy 185.520004 -353.775245) (xy 185.547254 -353.774756) (xy 185.581544 -353.77628) (xy 185.591704 -353.777296)
			(xy 185.611008 -353.7712) (xy 185.68162 -353.712018) (xy 185.691018 -353.693984) (xy 185.692034 -353.683824)
			(xy 185.695012 -353.655655) (xy 185.708188 -353.600566) (xy 185.729366 -353.548033) (xy 185.758082 -353.499209)
			(xy 185.793704 -353.45517) (xy 185.835447 -353.416884) (xy 185.882395 -353.385194) (xy 185.933513 -353.360796)
			(xy 185.987677 -353.344227) (xy 186.043697 -353.335852) (xy 186.072018 -353.335336) (xy 186.090037 -353.335559)
			(xy 186.125912 -353.338992) (xy 186.143646 -353.342194) (xy 186.153044 -353.343972) (xy 186.172094 -353.340162)
			(xy 186.247278 -353.29241) (xy 186.258708 -353.276662) (xy 186.260994 -353.267264) (xy 186.268418 -353.240228)
			(xy 186.290044 -353.188502) (xy 186.319005 -353.140498) (xy 186.354678 -353.097246) (xy 186.396293 -353.059678)
			(xy 186.442958 -353.028603) (xy 186.493666 -353.004689) (xy 186.547327 -352.98845) (xy 186.602786 -352.980236)
			(xy 186.630818 -352.979736) (xy 186.658073 -352.980138) (xy 186.712029 -352.987899) (xy 186.764331 -353.003259)
			(xy 186.813914 -353.025907) (xy 186.859769 -353.055381) (xy 186.900963 -353.091081) (xy 186.936656 -353.132281)
			(xy 186.966123 -353.178141) (xy 186.988762 -353.227728) (xy 187.004114 -353.280032) (xy 187.011866 -353.333989)
			(xy 187.012326 -353.361244) (xy 187.011813 -353.388817) (xy 187.003869 -353.443387) (xy 186.988152 -353.496246)
			(xy 186.964991 -353.546292) (xy 186.934868 -353.592482) (xy 186.898409 -353.633856) (xy 186.877706 -353.652074)
			(xy 186.869605 -353.659692) (xy 186.860241 -353.679832) (xy 186.859672 -353.690936) (xy 186.859672 -353.768152)
			(xy 186.860228 -353.779264) (xy 186.869573 -353.799424) (xy 186.877706 -353.807014) (xy 186.898455 -353.825182)
			(xy 186.934918 -353.86656) (xy 186.965044 -353.912756) (xy 186.988204 -353.962809) (xy 187.003916 -354.015675)
			(xy 187.011853 -354.070253) (xy 187.011849 -354.125404) (xy 187.003904 -354.17998) (xy 186.988184 -354.232844)
			(xy 186.965016 -354.282894) (xy 186.934884 -354.329086) (xy 186.898415 -354.370458) (xy 186.877706 -354.388674)
			(xy 186.869605 -354.396292) (xy 186.860241 -354.416432) (xy 186.859672 -354.427536) (xy 186.859672 -354.504752)
			(xy 186.860228 -354.515864) (xy 186.869573 -354.536024) (xy 186.877706 -354.543614) (xy 186.898428 -354.561813)
			(xy 186.934897 -354.603184) (xy 186.965028 -354.649377) (xy 186.988192 -354.699427) (xy 187.003906 -354.752292)
			(xy 187.011842 -354.806869) (xy 187.012326 -354.834444) (xy 187.011863 -354.861696) (xy 187.004101 -354.915643)
			(xy 186.988741 -354.967937) (xy 186.966096 -355.017513) (xy 186.936627 -355.063363) (xy 186.900934 -355.104552)
			(xy 186.859742 -355.140243) (xy 186.813891 -355.169709) (xy 186.764313 -355.19235) (xy 186.712018 -355.207707)
			(xy 186.65807 -355.215465) (xy 186.630818 -355.215952) (xy 186.602962 -355.215448) (xy 186.547844 -355.207326)
			(xy 186.494491 -355.19128) (xy 186.444036 -355.167652) (xy 186.397551 -355.136943) (xy 186.356021 -355.099805)
			(xy 186.320329 -355.057026) (xy 186.291232 -355.009514) (xy 186.269348 -354.958279) (xy 186.261756 -354.931472)
			(xy 186.25947 -354.922582) (xy 186.248802 -354.907342) (xy 186.17692 -354.85959) (xy 186.158886 -354.855526)
			(xy 186.149742 -354.856796) (xy 186.136726 -354.858469) (xy 186.110541 -354.860246) (xy 186.097418 -354.860352)
			(xy 186.083269 -354.860256) (xy 186.055046 -354.858223) (xy 186.04103 -354.856288) (xy 186.03087 -354.854764)
			(xy 186.011312 -354.85959) (xy 185.93689 -354.91547) (xy 185.92673 -354.932996) (xy 185.92546 -354.943156)
			(xy 185.921339 -354.970304) (xy 185.906367 -355.023131) (xy 185.883977 -355.073266) (xy 185.854633 -355.119675)
			(xy 185.818939 -355.161398) (xy 185.777633 -355.197574) (xy 185.731569 -355.227457) (xy 185.681697 -355.250428)
			(xy 185.629048 -355.266013) (xy 185.574708 -355.273891) (xy 185.547254 -355.274372) (xy 185.52 -355.273965)
			(xy 185.466048 -355.266201) (xy 185.413749 -355.250838) (xy 185.364169 -355.228189) (xy 185.318317 -355.198715)
			(xy 185.277127 -355.163015) (xy 185.241436 -355.121817) (xy 185.211971 -355.075959) (xy 185.189333 -355.026374)
			(xy 185.173981 -354.974072) (xy 185.166229 -354.920118) (xy 185.165746 -354.892864) (xy 183.024857 -354.892864)
			(xy 183.027488 -354.901825) (xy 183.035241 -354.95578) (xy 183.035702 -354.983034) (xy 183.03504 -355.014597)
			(xy 183.024654 -355.076862) (xy 183.004169 -355.136571) (xy 182.989728 -355.164644) (xy 182.984902 -355.173534)
			(xy 182.98287 -355.193092) (xy 183.008524 -355.28123) (xy 183.02097 -355.296724) (xy 183.02986 -355.301804)
			(xy 183.054938 -355.31639) (xy 183.100822 -355.351886) (xy 183.140799 -355.393923) (xy 183.173948 -355.44153)
			(xy 183.199503 -355.493609) (xy 183.216874 -355.548959) (xy 183.22566 -355.6063) (xy 183.226202 -355.635306)
			(xy 183.225716 -355.662557) (xy 183.21796 -355.716505) (xy 183.202605 -355.7688) (xy 183.198263 -355.778308)
			(xy 188.899546 -355.778308) (xy 188.900026 -355.750833) (xy 188.907918 -355.696453) (xy 188.923539 -355.64377)
			(xy 188.946565 -355.593877) (xy 188.976519 -355.547809) (xy 188.994288 -355.526848) (xy 189.000384 -355.519736)
			(xy 189.006734 -355.502718) (xy 189.006734 -355.416866) (xy 189.000384 -355.399848) (xy 188.994288 -355.392736)
			(xy 188.976558 -355.371746) (xy 188.946629 -355.325672) (xy 188.923609 -355.275785) (xy 188.907976 -355.223114)
			(xy 188.90005 -355.168747) (xy 188.899546 -355.141276) (xy 188.900032 -355.114025) (xy 188.907788 -355.060077)
			(xy 188.923143 -355.007782) (xy 188.945785 -354.958205) (xy 188.975251 -354.912355) (xy 189.010942 -354.871164)
			(xy 189.052133 -354.835473) (xy 189.097983 -354.806007) (xy 189.14756 -354.783365) (xy 189.199855 -354.76801)
			(xy 189.253803 -354.760254) (xy 189.308305 -354.760254) (xy 189.362253 -354.76801) (xy 189.414548 -354.783365)
			(xy 189.464125 -354.806007) (xy 189.509975 -354.835473) (xy 189.551166 -354.871164) (xy 189.586857 -354.912355)
			(xy 189.616323 -354.958205) (xy 189.638965 -355.007782) (xy 189.65432 -355.060077) (xy 189.662076 -355.114025)
			(xy 189.662562 -355.141276) (xy 189.662071 -355.168751) (xy 189.654182 -355.22313) (xy 189.638563 -355.275813)
			(xy 189.615539 -355.325706) (xy 189.585588 -355.371774) (xy 189.56782 -355.392736) (xy 189.561724 -355.399848)
			(xy 189.555374 -355.416866) (xy 189.555374 -355.502718) (xy 189.561724 -355.519736) (xy 189.56782 -355.526848)
			(xy 189.585591 -355.547805) (xy 189.615514 -355.593888) (xy 189.638525 -355.643784) (xy 189.654149 -355.696462)
			(xy 189.662064 -355.750835) (xy 189.662562 -355.778308) (xy 189.662076 -355.805559) (xy 189.65432 -355.859507)
			(xy 189.638965 -355.911802) (xy 189.616323 -355.961379) (xy 189.586857 -356.007229) (xy 189.551166 -356.04842)
			(xy 189.509975 -356.084111) (xy 189.464125 -356.113577) (xy 189.414548 -356.136219) (xy 189.362253 -356.151574)
			(xy 189.308305 -356.15933) (xy 189.253803 -356.15933) (xy 189.199855 -356.151574) (xy 189.14756 -356.136219)
			(xy 189.097983 -356.113577) (xy 189.052133 -356.084111) (xy 189.010942 -356.04842) (xy 188.975251 -356.007229)
			(xy 188.945785 -355.961379) (xy 188.923143 -355.911802) (xy 188.907788 -355.859507) (xy 188.900032 -355.805559)
			(xy 188.899546 -355.778308) (xy 183.198263 -355.778308) (xy 183.179963 -355.818377) (xy 183.150497 -355.864227)
			(xy 183.114806 -355.905418) (xy 183.073615 -355.941109) (xy 183.027765 -355.970575) (xy 182.978188 -355.993217)
			(xy 182.925893 -356.008572) (xy 182.871945 -356.016328) (xy 182.817443 -356.016328) (xy 182.763495 -356.008572)
			(xy 182.7112 -355.993217) (xy 182.661623 -355.970575) (xy 182.615773 -355.941109) (xy 182.574582 -355.905418)
			(xy 182.538891 -355.864227) (xy 182.509425 -355.818377) (xy 182.486783 -355.7688) (xy 182.471428 -355.716505)
			(xy 182.463672 -355.662557) (xy 182.463186 -355.635306) (xy 182.463826 -355.603742) (xy 182.474222 -355.541477)
			(xy 182.494715 -355.481768) (xy 182.50916 -355.453696) (xy 182.513986 -355.444806) (xy 182.516018 -355.425248)
			(xy 182.490364 -355.33711) (xy 182.477918 -355.321616) (xy 182.469028 -355.316536) (xy 182.461662 -355.312472)
			(xy 182.45201 -355.30663) (xy 182.429912 -355.304598) (xy 182.335424 -355.338126) (xy 182.319422 -355.35362)
			(xy 182.315358 -355.364034) (xy 182.305362 -355.389156) (xy 182.279282 -355.436519) (xy 182.246784 -355.479731)
			(xy 182.227982 -355.499162) (xy 182.221257 -355.506564) (xy 182.213538 -355.52499) (xy 182.212996 -355.534976)
			(xy 182.212996 -356.677468) (xy 182.213413 -356.687539) (xy 182.221137 -356.706138) (xy 182.227982 -356.713536)
			(xy 182.860696 -357.34625) (xy 182.877968 -357.364331) (xy 182.905775 -357.405881) (xy 182.924944 -357.452057)
			(xy 182.934738 -357.501084) (xy 182.935372 -357.526082) (xy 182.935372 -357.928926) (xy 182.935735 -357.938972)
			(xy 182.943327 -357.957569) (xy 182.950104 -357.964994) (xy 183.273192 -358.288082) (xy 183.280603 -358.294909)
			(xy 183.299194 -358.302637) (xy 183.30926 -358.303068) (xy 189.479174 -358.303068) (xy 189.489243 -358.302637)
			(xy 189.507841 -358.294921) (xy 189.515242 -358.288082) (xy 190.01613 -357.787194) (xy 190.022969 -357.779794)
			(xy 190.030689 -357.761194) (xy 190.031116 -357.751126) (xy 190.031116 -355.560376) (xy 190.03066 -355.550371)
			(xy 190.022939 -355.531907) (xy 190.01613 -355.524562) (xy 189.995251 -355.50294) (xy 189.959837 -355.454378)
			(xy 189.932479 -355.400862) (xy 189.913855 -355.343717) (xy 189.904426 -355.284358) (xy 189.903862 -355.254306)
			(xy 189.904383 -355.227056) (xy 189.912138 -355.173111) (xy 189.927491 -355.120819) (xy 189.950129 -355.071244)
			(xy 189.979592 -355.025395) (xy 190.01528 -354.984205) (xy 190.056466 -354.948514) (xy 190.102312 -354.919047)
			(xy 190.151885 -354.896404) (xy 190.204176 -354.881046) (xy 190.25812 -354.873286) (xy 190.28537 -354.872798)
			(xy 190.310606 -354.873165) (xy 190.360641 -354.879792) (xy 190.409362 -354.892974) (xy 190.455912 -354.912479)
			(xy 190.477902 -354.924868) (xy 190.487554 -354.93071) (xy 190.509652 -354.932742) (xy 190.60414 -354.899214)
			(xy 190.620142 -354.88372) (xy 190.624206 -354.873306) (xy 190.634884 -354.846522) (xy 190.663173 -354.796278)
			(xy 190.698704 -354.750867) (xy 190.740669 -354.711325) (xy 190.788109 -354.678551) (xy 190.839943 -354.653295)
			(xy 190.894989 -354.636132) (xy 190.951992 -354.627453) (xy 190.980822 -354.626926) (xy 191.008077 -354.627335)
			(xy 191.062032 -354.635095) (xy 191.114333 -354.650456) (xy 191.163915 -354.673103) (xy 191.20977 -354.702577)
			(xy 191.250963 -354.738276) (xy 191.286657 -354.779475) (xy 191.316123 -354.825334) (xy 191.338764 -354.87492)
			(xy 191.351487 -354.918264) (xy 193.492374 -354.918264) (xy 193.492893 -354.890691) (xy 193.500836 -354.836121)
			(xy 193.516551 -354.783263) (xy 193.539711 -354.733217) (xy 193.569834 -354.687026) (xy 193.606292 -354.645652)
			(xy 193.626994 -354.627434) (xy 193.635092 -354.619813) (xy 193.644458 -354.599676) (xy 193.645028 -354.588572)
			(xy 193.645028 -354.511356) (xy 193.644468 -354.500245) (xy 193.635126 -354.480085) (xy 193.626994 -354.472494)
			(xy 193.606276 -354.454291) (xy 193.569806 -354.41292) (xy 193.539675 -354.366729) (xy 193.516511 -354.316679)
			(xy 193.500796 -354.263815) (xy 193.492858 -354.209239) (xy 193.492374 -354.181664) (xy 193.492844 -354.154413)
			(xy 193.500605 -354.100465) (xy 193.515964 -354.048171) (xy 193.538608 -353.998595) (xy 193.568076 -353.952746)
			(xy 193.603769 -353.911557) (xy 193.64496 -353.875866) (xy 193.690811 -353.846399) (xy 193.740388 -353.823758)
			(xy 193.792683 -353.808401) (xy 193.846631 -353.800643) (xy 193.873882 -353.800156) (xy 193.908172 -353.80168)
			(xy 193.918332 -353.802696) (xy 193.937636 -353.7966) (xy 194.008248 -353.737418) (xy 194.017646 -353.719384)
			(xy 194.018662 -353.709224) (xy 194.021613 -353.681051) (xy 194.03479 -353.62596) (xy 194.05597 -353.573425)
			(xy 194.084689 -353.5246) (xy 194.120314 -353.48056) (xy 194.16206 -353.442274) (xy 194.209011 -353.410584)
			(xy 194.260133 -353.386188) (xy 194.314301 -353.369622) (xy 194.370324 -353.36125) (xy 194.398646 -353.360736)
			(xy 194.416665 -353.360955) (xy 194.45254 -353.364391) (xy 194.470274 -353.367594) (xy 194.479672 -353.369372)
			(xy 194.498722 -353.365562) (xy 194.573906 -353.31781) (xy 194.585336 -353.302062) (xy 194.587622 -353.292664)
			(xy 194.59502 -353.26562) (xy 194.616649 -353.213893) (xy 194.645613 -353.165887) (xy 194.681288 -353.122635)
			(xy 194.722907 -353.085068) (xy 194.769575 -353.053993) (xy 194.820286 -353.030081) (xy 194.873951 -353.013845)
			(xy 194.929413 -353.005634) (xy 194.957446 -353.005136) (xy 194.9847 -353.005535) (xy 195.038654 -353.013299)
			(xy 195.090953 -353.028662) (xy 195.140533 -353.051312) (xy 195.186385 -353.080787) (xy 195.227576 -353.116488)
			(xy 195.263267 -353.157687) (xy 195.292731 -353.203546) (xy 195.315369 -353.253132) (xy 195.33072 -353.305435)
			(xy 195.338471 -353.35939) (xy 195.338954 -353.386644) (xy 195.338466 -353.414218) (xy 195.33052 -353.46879)
			(xy 195.314801 -353.521651) (xy 195.291635 -353.571697) (xy 195.261506 -353.617887) (xy 195.22504 -353.659258)
			(xy 195.204334 -353.677474) (xy 195.196221 -353.685081) (xy 195.186866 -353.70523) (xy 195.1863 -353.716336)
			(xy 195.1863 -353.793552) (xy 195.186879 -353.804661) (xy 195.19621 -353.824819) (xy 195.204334 -353.832414)
			(xy 195.225082 -353.850583) (xy 195.261542 -353.891961) (xy 195.291666 -353.938158) (xy 195.314824 -353.988211)
			(xy 195.330535 -354.041077) (xy 195.338471 -354.095653) (xy 195.338467 -354.150804) (xy 195.330523 -354.205379)
			(xy 195.314804 -354.258242) (xy 195.291638 -354.308291) (xy 195.261508 -354.354484) (xy 195.225041 -354.395857)
			(xy 195.204334 -354.414074) (xy 195.196221 -354.421681) (xy 195.186866 -354.44183) (xy 195.1863 -354.452936)
			(xy 195.1863 -354.530152) (xy 195.186879 -354.541261) (xy 195.19621 -354.561419) (xy 195.204334 -354.569014)
			(xy 195.225062 -354.587207) (xy 195.261529 -354.62858) (xy 195.291659 -354.674774) (xy 195.314821 -354.724826)
			(xy 195.330534 -354.777691) (xy 195.33847 -354.832268) (xy 195.338954 -354.859844) (xy 195.338463 -354.887094)
			(xy 195.330702 -354.941039) (xy 195.315344 -354.993331) (xy 195.292701 -355.042906) (xy 195.263234 -355.088753)
			(xy 195.227543 -355.129942) (xy 195.186355 -355.165633) (xy 195.140507 -355.1951) (xy 195.090933 -355.217743)
			(xy 195.038641 -355.233102) (xy 194.984696 -355.240863) (xy 194.957446 -355.241352) (xy 194.92959 -355.240823)
			(xy 194.874473 -355.232705) (xy 194.821121 -355.216663) (xy 194.770667 -355.193038) (xy 194.724181 -355.162332)
			(xy 194.682651 -355.125197) (xy 194.646958 -355.082421) (xy 194.617861 -355.034911) (xy 194.595976 -354.983678)
			(xy 194.588384 -354.956872) (xy 194.586098 -354.947982) (xy 194.57543 -354.932742) (xy 194.503548 -354.88499)
			(xy 194.485514 -354.880926) (xy 194.47637 -354.882196) (xy 194.463354 -354.883866) (xy 194.437169 -354.885645)
			(xy 194.424046 -354.885752) (xy 194.409897 -354.885653) (xy 194.381674 -354.883622) (xy 194.367658 -354.881688)
			(xy 194.357498 -354.880164) (xy 194.33794 -354.88499) (xy 194.263518 -354.94087) (xy 194.253358 -354.958396)
			(xy 194.252088 -354.968556) (xy 194.248037 -354.995716) (xy 194.233061 -355.048548) (xy 194.210665 -355.098688)
			(xy 194.181314 -355.1451) (xy 194.145612 -355.186825) (xy 194.104298 -355.223001) (xy 194.058225 -355.252881)
			(xy 194.008344 -355.275848) (xy 193.955686 -355.291427) (xy 193.901339 -355.299296) (xy 193.873882 -355.299772)
			(xy 193.846627 -355.299362) (xy 193.792672 -355.291601) (xy 193.740371 -355.276241) (xy 193.690789 -355.253594)
			(xy 193.644934 -355.224121) (xy 193.60374 -355.188421) (xy 193.568047 -355.147223) (xy 193.53858 -355.101364)
			(xy 193.51594 -355.051778) (xy 193.500587 -354.999475) (xy 193.492834 -354.945519) (xy 193.492374 -354.918264)
			(xy 191.351487 -354.918264) (xy 191.354117 -354.927223) (xy 191.361869 -354.981179) (xy 191.36233 -355.008434)
			(xy 191.361665 -355.039996) (xy 191.351279 -355.102261) (xy 191.330796 -355.161971) (xy 191.316356 -355.190044)
			(xy 191.31153 -355.198934) (xy 191.309498 -355.218492) (xy 191.335152 -355.30663) (xy 191.347598 -355.322124)
			(xy 191.356488 -355.327204) (xy 191.381573 -355.34178) (xy 191.427455 -355.377278) (xy 191.467431 -355.419317)
			(xy 191.500578 -355.466927) (xy 191.526132 -355.519007) (xy 191.543502 -355.574357) (xy 191.552288 -355.6317)
			(xy 191.55283 -355.660706) (xy 191.552344 -355.687957) (xy 191.544588 -355.741905) (xy 191.529233 -355.7942)
			(xy 191.506591 -355.843777) (xy 191.477125 -355.889627) (xy 191.441434 -355.930818) (xy 191.400243 -355.966509)
			(xy 191.354393 -355.995975) (xy 191.304816 -356.018617) (xy 191.252521 -356.033972) (xy 191.198573 -356.041728)
			(xy 191.144071 -356.041728) (xy 191.090123 -356.033972) (xy 191.037828 -356.018617) (xy 190.988251 -355.995975)
			(xy 190.942401 -355.966509) (xy 190.90121 -355.930818) (xy 190.865519 -355.889627) (xy 190.836053 -355.843777)
			(xy 190.813411 -355.7942) (xy 190.798056 -355.741905) (xy 190.7903 -355.687957) (xy 190.789814 -355.660706)
			(xy 190.79045 -355.629142) (xy 190.800847 -355.566876) (xy 190.821342 -355.507168) (xy 190.835788 -355.479096)
			(xy 190.840614 -355.470206) (xy 190.842646 -355.450648) (xy 190.816992 -355.36251) (xy 190.804546 -355.347016)
			(xy 190.795656 -355.341936) (xy 190.78829 -355.337872) (xy 190.778638 -355.33203) (xy 190.75654 -355.329998)
			(xy 190.662052 -355.363526) (xy 190.64605 -355.37902) (xy 190.641986 -355.389434) (xy 190.631985 -355.414554)
			(xy 190.605907 -355.461917) (xy 190.573411 -355.505131) (xy 190.55461 -355.524562) (xy 190.547888 -355.531967)
			(xy 190.540166 -355.550391) (xy 190.539624 -355.560376) (xy 190.539624 -357.877618) (xy 190.539013 -357.902602)
			(xy 190.52927 -357.95161) (xy 190.510163 -357.99778) (xy 190.482424 -358.03934) (xy 190.465202 -358.05745)
			(xy 189.785498 -358.737154) (xy 189.767402 -358.754392) (xy 189.725838 -358.78213) (xy 189.679664 -358.801233)
			(xy 189.630651 -358.810968) (xy 189.605666 -358.811576) (xy 183.182768 -358.811576) (xy 183.157785 -358.810958)
			(xy 183.108778 -358.801216) (xy 183.062608 -358.78211) (xy 183.021047 -358.754374) (xy 183.002936 -358.737154)
			(xy 182.501032 -358.23525) (xy 182.483765 -358.217164) (xy 182.455955 -358.175617) (xy 182.436785 -358.129442)
			(xy 182.42699 -358.080415) (xy 182.426356 -358.055418) (xy 182.426356 -357.652574) (xy 182.425986 -357.642529)
			(xy 182.418398 -357.623932) (xy 182.411624 -357.616506) (xy 181.8259 -357.030782) (xy 181.818496 -357.023947)
			(xy 181.7999 -357.016225) (xy 181.789832 -357.015796) (xy 181.474618 -357.015796) (xy 181.464546 -357.016205)
			(xy 181.445947 -357.023934) (xy 181.43855 -357.030782) (xy 181.235858 -357.233474) (xy 181.229031 -357.240884)
			(xy 181.221305 -357.259476) (xy 181.220872 -357.269542) (xy 181.220872 -357.709724) (xy 181.220251 -357.734707)
			(xy 181.210509 -357.783714) (xy 181.191405 -357.829884) (xy 181.16367 -357.871445) (xy 181.14645 -357.889556)
			(xy 180.692806 -358.3432) (xy 180.674702 -358.360446) (xy 180.63316 -358.388258) (xy 180.586991 -358.407434)
			(xy 180.537969 -358.417237) (xy 180.512974 -358.417876) (xy 171.237148 -358.417876) (xy 171.212153 -358.417211)
			(xy 171.163132 -358.407416) (xy 171.116962 -358.388251) (xy 171.075414 -358.360451) (xy 171.057316 -358.3432)
			(xy 168.015158 -355.301042) (xy 167.997943 -355.282926) (xy 167.9702 -355.241369) (xy 167.951091 -355.195201)
			(xy 167.941348 -355.146193) (xy 167.940736 -355.12121) (xy 167.940736 -352.161348) (xy 167.940564 -352.15632)
			(xy 167.938517 -352.146471) (xy 167.936672 -352.14179) (xy 167.141398 -350.221804) (xy 167.139406 -350.217231)
			(xy 167.133908 -350.208912) (xy 167.130476 -350.205294) (xy 166.310818 -349.385636) (xy 166.304227 -349.379679)
			(xy 166.28815 -349.372165) (xy 166.270477 -349.370552) (xy 166.261796 -349.372428) (xy 166.163752 -349.398082)
			(xy 166.144702 -349.417132) (xy 166.140892 -349.43034) (xy 166.134151 -349.453222) (xy 166.115742 -349.497229)
			(xy 166.091977 -349.538591) (xy 166.0779 -349.557848) (xy 166.07155 -349.56623) (xy 166.066724 -349.58655)
			(xy 166.082726 -349.680276) (xy 166.094156 -349.697802) (xy 166.102792 -349.703644) (xy 166.124874 -349.718903)
			(xy 166.164991 -349.754562) (xy 166.199711 -349.795494) (xy 166.228348 -349.840891) (xy 166.250337 -349.889854)
			(xy 166.265242 -349.941417) (xy 166.272769 -349.994561) (xy 166.273226 -350.021398) (xy 166.27274 -350.048649)
			(xy 166.264984 -350.102597) (xy 166.249629 -350.154892) (xy 166.226987 -350.204469) (xy 166.197521 -350.250319)
			(xy 166.16183 -350.29151) (xy 166.120639 -350.327201) (xy 166.074789 -350.356667) (xy 166.025212 -350.379309)
			(xy 165.972917 -350.394664) (xy 165.918969 -350.40242) (xy 165.864467 -350.40242) (xy 165.810519 -350.394664)
			(xy 165.758224 -350.379309) (xy 165.708647 -350.356667) (xy 165.662797 -350.327201) (xy 165.621606 -350.29151)
			(xy 165.585915 -350.250319) (xy 165.556449 -350.204469) (xy 165.533807 -350.154892) (xy 165.518452 -350.102597)
			(xy 165.510696 -350.048649) (xy 165.51021 -350.021398) (xy 165.510819 -349.990574) (xy 165.520742 -349.92973)
			(xy 165.540331 -349.871277) (xy 165.569073 -349.81674) (xy 165.587172 -349.791782) (xy 165.593522 -349.7834)
			(xy 165.598348 -349.76308) (xy 165.582346 -349.669354) (xy 165.570916 -349.651828) (xy 165.56228 -349.645986)
			(xy 165.540159 -349.63078) (xy 165.500044 -349.595112) (xy 165.465328 -349.55417) (xy 165.436696 -349.508764)
			(xy 165.414714 -349.459792) (xy 165.399817 -349.408222) (xy 165.392299 -349.355072) (xy 165.391846 -349.328232)
			(xy 157.788102 -349.328232) (xy 157.234636 -349.881698) (xy 157.204279 -349.911332) (xy 157.138708 -349.965168)
			(xy 157.068179 -350.01232) (xy 156.993368 -350.052335) (xy 156.914996 -350.084826) (xy 156.893015 -350.091502)
			(xy 158.361886 -350.091502) (xy 158.365957 -350.03588) (xy 158.378083 -349.981443) (xy 158.398006 -349.929352)
			(xy 158.425302 -349.880717) (xy 158.459388 -349.836574) (xy 158.499537 -349.797865) (xy 158.544895 -349.765414)
			(xy 158.594495 -349.739913) (xy 158.647279 -349.721906) (xy 158.702122 -349.711776) (xy 158.757856 -349.709739)
			(xy 158.813293 -349.715839) (xy 158.86725 -349.729945) (xy 158.918579 -349.751757) (xy 158.966185 -349.780811)
			(xy 159.009053 -349.816486) (xy 159.04627 -349.858023) (xy 159.077043 -349.904536) (xy 159.100715 -349.955033)
			(xy 159.116783 -350.00844) (xy 159.124903 -350.063616) (xy 159.125412 -350.091502) (xy 159.124903 -350.119388)
			(xy 159.116783 -350.174564) (xy 159.100715 -350.227971) (xy 159.077043 -350.278468) (xy 159.04627 -350.324981)
			(xy 159.009053 -350.366518) (xy 158.966185 -350.402193) (xy 158.918579 -350.431247) (xy 158.86725 -350.453059)
			(xy 158.813293 -350.467165) (xy 158.757856 -350.473265) (xy 158.702122 -350.471228) (xy 158.647279 -350.461098)
			(xy 158.594495 -350.443091) (xy 158.544895 -350.41759) (xy 158.499537 -350.385139) (xy 158.459388 -350.34643)
			(xy 158.425302 -350.302287) (xy 158.398006 -350.253652) (xy 158.378083 -350.201561) (xy 158.365957 -350.147124)
			(xy 158.361886 -350.091502) (xy 156.893015 -350.091502) (xy 156.833817 -350.109481) (xy 156.750614 -350.126063)
			(xy 156.666186 -350.134412) (xy 156.623766 -350.134936) (xy 156.581346 -350.13443) (xy 156.496914 -350.12611)
			(xy 156.413705 -350.109552) (xy 156.33252 -350.084917) (xy 156.254141 -350.052441) (xy 156.179324 -350.012438)
			(xy 156.108788 -349.965293) (xy 156.043214 -349.911461) (xy 155.983234 -349.851459) (xy 155.929424 -349.785866)
			(xy 155.882304 -349.715314) (xy 155.842328 -349.640482) (xy 155.80988 -349.562091) (xy 155.785274 -349.480898)
			(xy 155.768745 -349.397683) (xy 155.760455 -349.313248) (xy 155.759912 -349.270828) (xy 155.760431 -349.228414)
			(xy 155.768742 -349.143996) (xy 155.785288 -349.060798) (xy 155.809909 -348.979622) (xy 155.842368 -348.901251)
			(xy 155.882352 -348.826438) (xy 155.929476 -348.755905) (xy 155.983286 -348.69033) (xy 156.012896 -348.659958)
			(xy 156.80817 -347.864684) (xy 156.815017 -347.857286) (xy 156.822751 -347.838688) (xy 156.823156 -347.828616)
			(xy 156.823156 -347.674692) (xy 156.822812 -347.665704) (xy 156.816606 -347.648835) (xy 156.804933 -347.635167)
			(xy 156.797248 -347.630496) (xy 156.708348 -347.580204) (xy 156.68117 -347.580458) (xy 156.669232 -347.58757)
			(xy 156.646945 -347.600408) (xy 156.599657 -347.620636) (xy 156.550081 -347.634329) (xy 156.499114 -347.641238)
			(xy 156.473398 -347.641672) (xy 156.446149 -347.641186) (xy 156.392207 -347.63343) (xy 156.339918 -347.618076)
			(xy 156.290345 -347.595437) (xy 156.2445 -347.565973) (xy 156.203313 -347.530285) (xy 156.167626 -347.489099)
			(xy 156.138162 -347.443253) (xy 156.115523 -347.393681) (xy 156.10017 -347.341391) (xy 156.092414 -347.287449)
			(xy 156.092414 -347.232951) (xy 156.10017 -347.179009) (xy 156.115523 -347.126719) (xy 156.138162 -347.077147)
			(xy 156.167626 -347.031301) (xy 156.203313 -346.990115) (xy 156.2445 -346.954427) (xy 156.290345 -346.924963)
			(xy 156.339918 -346.902324) (xy 156.392207 -346.88697) (xy 156.446149 -346.879214) (xy 156.473398 -346.878656)
			(xy 156.499115 -346.879077) (xy 156.550082 -346.885988) (xy 156.599658 -346.899686) (xy 156.646944 -346.919921)
			(xy 156.669232 -346.932758) (xy 156.68117 -346.93987) (xy 156.708348 -346.940124) (xy 156.797248 -346.889832)
			(xy 156.804901 -346.885118) (xy 156.816562 -346.871455) (xy 156.822816 -346.854616) (xy 156.823156 -346.845636)
			(xy 156.823156 -334.131666) (xy 156.823673 -334.089251) (xy 156.831981 -334.00483) (xy 156.848523 -333.92163)
			(xy 156.873139 -333.840451) (xy 156.905594 -333.762076) (xy 156.945574 -333.687259) (xy 156.992694 -333.616721)
			(xy 157.046501 -333.551141) (xy 157.07614 -333.520796) (xy 158.090362 -332.506574) (xy 158.097209 -332.499176)
			(xy 158.10494 -332.480577) (xy 158.105348 -332.470506) (xy 158.105348 -326.964548) (xy 158.104914 -326.954483)
			(xy 158.09718 -326.935897) (xy 158.090362 -326.92848) (xy 156.887672 -325.726044) (xy 156.881388 -325.720183)
			(xy 156.865936 -325.712686) (xy 156.848873 -325.710739) (xy 156.840428 -325.712328) (xy 156.743654 -325.734426)
			(xy 156.72435 -325.751444) (xy 156.720032 -325.764144) (xy 156.710957 -325.788661) (xy 156.687046 -325.835152)
			(xy 156.657011 -325.877942) (xy 156.621415 -325.91623) (xy 156.580925 -325.9493) (xy 156.536298 -325.976531)
			(xy 156.488372 -325.997415) (xy 156.438042 -326.011559) (xy 156.386253 -326.018699) (xy 156.360114 -326.01916)
			(xy 156.33286 -326.018654) (xy 156.278911 -326.010858) (xy 156.22662 -325.995466) (xy 156.177051 -325.972791)
			(xy 156.153866 -325.958454) (xy 156.147262 -325.95439) (xy 156.1338 -325.95058) (xy 156.01442 -325.95058)
			(xy 156.00584 -325.950872) (xy 155.989617 -325.956458) (xy 155.98267 -325.961502) (xy 155.961708 -325.977614)
			(xy 155.915499 -326.003296) (xy 155.865631 -326.020845) (xy 155.813523 -326.029763) (xy 155.78709 -326.030336)
			(xy 154.272488 -326.030336) (xy 154.262522 -326.030814) (xy 154.244087 -326.038391) (xy 154.236674 -326.045068)
			(xy 152.847802 -327.43394) (xy 152.840962 -327.441341) (xy 152.833241 -327.459939) (xy 152.832816 -327.470008)
			(xy 152.832816 -348.96806) (xy 154.087574 -348.96806) (xy 154.091645 -348.912438) (xy 154.103771 -348.858001)
			(xy 154.123694 -348.80591) (xy 154.15099 -348.757275) (xy 154.185076 -348.713132) (xy 154.225225 -348.674423)
			(xy 154.270583 -348.641972) (xy 154.320183 -348.616471) (xy 154.372967 -348.598464) (xy 154.42781 -348.588334)
			(xy 154.483544 -348.586297) (xy 154.538981 -348.592397) (xy 154.592938 -348.606503) (xy 154.644267 -348.628315)
			(xy 154.691873 -348.657369) (xy 154.734741 -348.693044) (xy 154.771958 -348.734581) (xy 154.802731 -348.781094)
			(xy 154.826403 -348.831591) (xy 154.842471 -348.884998) (xy 154.850591 -348.940174) (xy 154.8511 -348.96806)
			(xy 154.850591 -348.995946) (xy 154.842471 -349.051122) (xy 154.826403 -349.104529) (xy 154.802731 -349.155026)
			(xy 154.771958 -349.201539) (xy 154.734741 -349.243076) (xy 154.691873 -349.278751) (xy 154.644267 -349.307805)
			(xy 154.592938 -349.329617) (xy 154.538981 -349.343723) (xy 154.483544 -349.349823) (xy 154.42781 -349.347786)
			(xy 154.372967 -349.337656) (xy 154.320183 -349.319649) (xy 154.270583 -349.294148) (xy 154.225225 -349.261697)
			(xy 154.185076 -349.222988) (xy 154.15099 -349.178845) (xy 154.123694 -349.13021) (xy 154.103771 -349.078119)
			(xy 154.091645 -349.023682) (xy 154.087574 -348.96806) (xy 152.832816 -348.96806) (xy 152.832816 -351.398078)
			(xy 158.417512 -351.398078) (xy 158.421583 -351.342456) (xy 158.433709 -351.288019) (xy 158.453632 -351.235928)
			(xy 158.480928 -351.187293) (xy 158.515014 -351.14315) (xy 158.555163 -351.104441) (xy 158.600521 -351.07199)
			(xy 158.650121 -351.046489) (xy 158.702905 -351.028482) (xy 158.757748 -351.018352) (xy 158.813482 -351.016315)
			(xy 158.868919 -351.022415) (xy 158.922876 -351.036521) (xy 158.974205 -351.058333) (xy 159.021811 -351.087387)
			(xy 159.064679 -351.123062) (xy 159.101896 -351.164599) (xy 159.132669 -351.211112) (xy 159.156341 -351.261609)
			(xy 159.172409 -351.315016) (xy 159.180529 -351.370192) (xy 159.181038 -351.398078) (xy 159.180529 -351.425964)
			(xy 159.172409 -351.48114) (xy 159.156341 -351.534547) (xy 159.132669 -351.585044) (xy 159.12092 -351.602802)
			(xy 159.687512 -351.602802) (xy 159.691583 -351.54718) (xy 159.703709 -351.492743) (xy 159.723632 -351.440652)
			(xy 159.750928 -351.392017) (xy 159.785014 -351.347874) (xy 159.825163 -351.309165) (xy 159.870521 -351.276714)
			(xy 159.920121 -351.251213) (xy 159.972905 -351.233206) (xy 160.027748 -351.223076) (xy 160.083482 -351.221039)
			(xy 160.138919 -351.227139) (xy 160.192876 -351.241245) (xy 160.244205 -351.263057) (xy 160.291811 -351.292111)
			(xy 160.334679 -351.327786) (xy 160.371896 -351.369323) (xy 160.402669 -351.415836) (xy 160.426341 -351.466333)
			(xy 160.442409 -351.51974) (xy 160.450529 -351.574916) (xy 160.451038 -351.602802) (xy 160.450529 -351.630688)
			(xy 160.443367 -351.679356) (xy 160.907633 -351.679356) (xy 160.907633 -351.624844) (xy 160.915391 -351.570887)
			(xy 160.93075 -351.518584) (xy 160.953396 -351.468999) (xy 160.982868 -351.423142) (xy 161.018567 -351.381946)
			(xy 161.059766 -351.34625) (xy 161.105625 -351.316781) (xy 161.155212 -351.294139) (xy 161.207517 -351.278785)
			(xy 161.261474 -351.271031) (xy 161.28873 -351.27057) (xy 161.314483 -351.27099) (xy 161.36552 -351.277935)
			(xy 161.415158 -351.291681) (xy 161.462497 -351.311979) (xy 161.506676 -351.338459) (xy 161.546892 -351.37064)
			(xy 161.582414 -351.407938) (xy 161.597848 -351.428558) (xy 161.606183 -351.439287) (xy 161.627314 -351.456343)
			(xy 161.652198 -351.467214) (xy 161.679069 -351.471129) (xy 161.706021 -351.467811) (xy 161.73114 -351.457494)
			(xy 161.752644 -351.440912) (xy 161.76117 -351.430336) (xy 161.779348 -351.407273) (xy 161.821549 -351.366444)
			(xy 161.86951 -351.332566) (xy 161.922099 -351.306442) (xy 161.97807 -351.288689) (xy 162.036102 -351.279727)
			(xy 162.065462 -351.279206) (xy 162.092718 -351.279638) (xy 162.146675 -351.287391) (xy 162.198979 -351.302744)
			(xy 162.248566 -351.325386) (xy 162.294426 -351.354854) (xy 162.335624 -351.390549) (xy 162.371323 -351.431744)
			(xy 162.400796 -351.477601) (xy 162.423442 -351.527185) (xy 162.437965 -351.57664) (xy 164.057836 -351.57664)
			(xy 164.061907 -351.521018) (xy 164.074033 -351.466581) (xy 164.093956 -351.41449) (xy 164.121252 -351.365855)
			(xy 164.155338 -351.321712) (xy 164.195487 -351.283003) (xy 164.240845 -351.250552) (xy 164.290445 -351.225051)
			(xy 164.343229 -351.207044) (xy 164.398072 -351.196914) (xy 164.453806 -351.194877) (xy 164.509243 -351.200977)
			(xy 164.5632 -351.215083) (xy 164.614529 -351.236895) (xy 164.662135 -351.265949) (xy 164.705003 -351.301624)
			(xy 164.74222 -351.343161) (xy 164.772993 -351.389674) (xy 164.796665 -351.440171) (xy 164.812733 -351.493578)
			(xy 164.820853 -351.548754) (xy 164.821362 -351.57664) (xy 164.820853 -351.604526) (xy 164.812733 -351.659702)
			(xy 164.796665 -351.713109) (xy 164.772993 -351.763606) (xy 164.74222 -351.810119) (xy 164.705003 -351.851656)
			(xy 164.662135 -351.887331) (xy 164.614529 -351.916385) (xy 164.5632 -351.938197) (xy 164.509243 -351.952303)
			(xy 164.453806 -351.958403) (xy 164.398072 -351.956366) (xy 164.343229 -351.946236) (xy 164.290445 -351.928229)
			(xy 164.240845 -351.902728) (xy 164.195487 -351.870277) (xy 164.155338 -351.831568) (xy 164.121252 -351.787425)
			(xy 164.093956 -351.73879) (xy 164.074033 -351.686699) (xy 164.061907 -351.632262) (xy 164.057836 -351.57664)
			(xy 162.437965 -351.57664) (xy 162.438801 -351.579488) (xy 162.446559 -351.633444) (xy 162.446559 -351.687956)
			(xy 162.438801 -351.741912) (xy 162.423442 -351.794215) (xy 162.400796 -351.843799) (xy 162.371323 -351.889656)
			(xy 162.335624 -351.930851) (xy 162.294426 -351.966546) (xy 162.248566 -351.996014) (xy 162.198979 -352.018656)
			(xy 162.146675 -352.034009) (xy 162.092718 -352.041762) (xy 162.065462 -352.042222) (xy 162.039708 -352.041811)
			(xy 161.988671 -352.034865) (xy 161.939033 -352.021117) (xy 161.891694 -352.000818) (xy 161.847515 -351.974337)
			(xy 161.807299 -351.942154) (xy 161.771778 -351.904855) (xy 161.756344 -351.884234) (xy 161.748018 -351.873497)
			(xy 161.726885 -351.856443) (xy 161.701999 -351.845574) (xy 161.675126 -351.84166) (xy 161.648173 -351.844979)
			(xy 161.623053 -351.855297) (xy 161.601548 -351.87188) (xy 161.593022 -351.882456) (xy 161.574846 -351.905521)
			(xy 161.532645 -351.946351) (xy 161.484683 -351.980228) (xy 161.432095 -352.006352) (xy 161.376122 -352.024105)
			(xy 161.31809 -352.033066) (xy 161.28873 -352.033586) (xy 161.261474 -352.033169) (xy 161.207517 -352.025415)
			(xy 161.155212 -352.010061) (xy 161.105625 -351.987419) (xy 161.059766 -351.95795) (xy 161.018567 -351.922254)
			(xy 160.982868 -351.881058) (xy 160.953396 -351.835201) (xy 160.93075 -351.785616) (xy 160.915391 -351.733313)
			(xy 160.907633 -351.679356) (xy 160.443367 -351.679356) (xy 160.442409 -351.685864) (xy 160.426341 -351.739271)
			(xy 160.402669 -351.789768) (xy 160.371896 -351.836281) (xy 160.334679 -351.877818) (xy 160.291811 -351.913493)
			(xy 160.244205 -351.942547) (xy 160.192876 -351.964359) (xy 160.138919 -351.978465) (xy 160.083482 -351.984565)
			(xy 160.027748 -351.982528) (xy 159.972905 -351.972398) (xy 159.920121 -351.954391) (xy 159.870521 -351.92889)
			(xy 159.825163 -351.896439) (xy 159.785014 -351.85773) (xy 159.750928 -351.813587) (xy 159.723632 -351.764952)
			(xy 159.703709 -351.712861) (xy 159.691583 -351.658424) (xy 159.687512 -351.602802) (xy 159.12092 -351.602802)
			(xy 159.101896 -351.631557) (xy 159.064679 -351.673094) (xy 159.021811 -351.708769) (xy 158.974205 -351.737823)
			(xy 158.922876 -351.759635) (xy 158.868919 -351.773741) (xy 158.813482 -351.779841) (xy 158.757748 -351.777804)
			(xy 158.702905 -351.767674) (xy 158.650121 -351.749667) (xy 158.600521 -351.724166) (xy 158.555163 -351.691715)
			(xy 158.515014 -351.653006) (xy 158.480928 -351.608863) (xy 158.453632 -351.560228) (xy 158.433709 -351.508137)
			(xy 158.421583 -351.4537) (xy 158.417512 -351.398078) (xy 152.832816 -351.398078) (xy 152.832816 -352.102928)
			(xy 156.238192 -352.102928) (xy 156.242263 -352.047306) (xy 156.254389 -351.992869) (xy 156.274312 -351.940778)
			(xy 156.301608 -351.892143) (xy 156.335694 -351.848) (xy 156.375843 -351.809291) (xy 156.421201 -351.77684)
			(xy 156.470801 -351.751339) (xy 156.523585 -351.733332) (xy 156.578428 -351.723202) (xy 156.634162 -351.721165)
			(xy 156.689599 -351.727265) (xy 156.743556 -351.741371) (xy 156.794885 -351.763183) (xy 156.842491 -351.792237)
			(xy 156.885359 -351.827912) (xy 156.922576 -351.869449) (xy 156.953349 -351.915962) (xy 156.977021 -351.966459)
			(xy 156.993089 -352.019866) (xy 157.001209 -352.075042) (xy 157.001718 -352.102928) (xy 157.001209 -352.130814)
			(xy 156.993089 -352.18599) (xy 156.977021 -352.239397) (xy 156.953349 -352.289894) (xy 156.922576 -352.336407)
			(xy 156.885359 -352.377944) (xy 156.842491 -352.413619) (xy 156.794885 -352.442673) (xy 156.743556 -352.464485)
			(xy 156.689599 -352.478591) (xy 156.634162 -352.484691) (xy 156.578428 -352.482654) (xy 156.523585 -352.472524)
			(xy 156.470801 -352.454517) (xy 156.421201 -352.429016) (xy 156.375843 -352.396565) (xy 156.335694 -352.357856)
			(xy 156.301608 -352.313713) (xy 156.274312 -352.265078) (xy 156.254389 -352.212987) (xy 156.242263 -352.15855)
			(xy 156.238192 -352.102928) (xy 152.832816 -352.102928) (xy 152.832816 -353.89439) (xy 157.69539 -353.89439)
			(xy 157.699461 -353.838768) (xy 157.711587 -353.784331) (xy 157.73151 -353.73224) (xy 157.758806 -353.683605)
			(xy 157.792892 -353.639462) (xy 157.833041 -353.600753) (xy 157.878399 -353.568302) (xy 157.927999 -353.542801)
			(xy 157.980783 -353.524794) (xy 158.035626 -353.514664) (xy 158.09136 -353.512627) (xy 158.146797 -353.518727)
			(xy 158.200754 -353.532833) (xy 158.252083 -353.554645) (xy 158.299689 -353.583699) (xy 158.342557 -353.619374)
			(xy 158.379774 -353.660911) (xy 158.410547 -353.707424) (xy 158.434219 -353.757921) (xy 158.450287 -353.811328)
			(xy 158.458407 -353.866504) (xy 158.458916 -353.89439) (xy 158.458407 -353.922276) (xy 158.450287 -353.977452)
			(xy 158.434219 -354.030859) (xy 158.410547 -354.081356) (xy 158.379774 -354.127869) (xy 158.342557 -354.169406)
			(xy 158.299689 -354.205081) (xy 158.252083 -354.234135) (xy 158.200754 -354.255947) (xy 158.146797 -354.270053)
			(xy 158.09136 -354.276153) (xy 158.035626 -354.274116) (xy 157.980783 -354.263986) (xy 157.927999 -354.245979)
			(xy 157.878399 -354.220478) (xy 157.833041 -354.188027) (xy 157.792892 -354.149318) (xy 157.758806 -354.105175)
			(xy 157.73151 -354.05654) (xy 157.711587 -354.004449) (xy 157.699461 -353.950012) (xy 157.69539 -353.89439)
			(xy 152.832816 -353.89439) (xy 152.832816 -357.655114) (xy 152.833242 -357.665183) (xy 152.840962 -357.683782)
			(xy 152.847802 -357.691182) (xy 153.543 -358.38638) (xy 153.550398 -358.393228) (xy 153.568996 -358.400966)
			(xy 153.579068 -358.401366) (xy 155.310586 -358.401366) (xy 155.320649 -358.400926) (xy 155.339227 -358.393186)
			(xy 155.346654 -358.38638) (xy 155.394406 -358.338628) (xy 155.401804 -358.33178) (xy 155.420402 -358.324043)
			(xy 155.430474 -358.323642) (xy 159.14116 -358.323642) (xy 159.151149 -358.32311) (xy 159.169586 -358.3154)
			(xy 159.176974 -358.308656) (xy 159.469582 -358.016302) (xy 159.476431 -358.008904) (xy 159.484169 -357.990306)
			(xy 159.484568 -357.980234) (xy 159.484568 -355.84511) (xy 159.484314 -355.84511) (xy 159.484314 -353.708716)
			(xy 159.484808 -353.671659) (xy 159.492992 -353.597998) (xy 159.509272 -353.525694) (xy 159.533449 -353.455634)
			(xy 159.565226 -353.388677) (xy 159.604213 -353.325646) (xy 159.649932 -353.267313) (xy 159.701821 -353.214394)
			(xy 159.759245 -353.167539) (xy 159.821499 -353.127321) (xy 159.887818 -353.094236) (xy 159.95739 -353.068688)
			(xy 160.029361 -353.050991) (xy 160.102847 -353.041362) (xy 160.139888 -353.040188) (xy 160.152842 -353.040188)
			(xy 160.190368 -353.040692) (xy 160.264948 -353.049095) (xy 160.338116 -353.065802) (xy 160.408952 -353.090602)
			(xy 160.476563 -353.123183) (xy 160.540098 -353.163134) (xy 160.598756 -353.209952) (xy 160.651798 -353.263049)
			(xy 160.698558 -353.321754) (xy 160.738445 -353.385329) (xy 160.770957 -353.452973) (xy 160.783778 -353.488244)
			(xy 160.788096 -353.50069) (xy 160.8074 -353.517962) (xy 160.903666 -353.539806) (xy 160.914532 -353.541758)
			(xy 160.936126 -353.537279) (xy 160.945322 -353.53117) (xy 160.950656 -353.527106) (xy 161.031428 -353.446588)
			(xy 161.032952 -353.44481) (xy 161.059829 -353.418631) (xy 161.118477 -353.371833) (xy 161.182 -353.3319)
			(xy 161.249597 -353.299337) (xy 161.320418 -353.274553) (xy 161.393569 -353.25786) (xy 161.46813 -353.249469)
			(xy 161.505646 -353.248976) (xy 161.543155 -353.249485) (xy 161.617702 -353.257891) (xy 161.690838 -353.274592)
			(xy 161.761645 -353.299377) (xy 161.82923 -353.331936) (xy 161.830598 -353.332796) (xy 165.19474 -353.332796)
			(xy 165.198811 -353.277174) (xy 165.210937 -353.222737) (xy 165.23086 -353.170646) (xy 165.258156 -353.122011)
			(xy 165.292242 -353.077868) (xy 165.332391 -353.039159) (xy 165.377749 -353.006708) (xy 165.427349 -352.981207)
			(xy 165.480133 -352.9632) (xy 165.534976 -352.95307) (xy 165.59071 -352.951033) (xy 165.646147 -352.957133)
			(xy 165.700104 -352.971239) (xy 165.751433 -352.993051) (xy 165.799039 -353.022105) (xy 165.841907 -353.05778)
			(xy 165.879124 -353.099317) (xy 165.909897 -353.14583) (xy 165.933569 -353.196327) (xy 165.949637 -353.249734)
			(xy 165.957757 -353.30491) (xy 165.958266 -353.332796) (xy 165.957757 -353.360682) (xy 165.949637 -353.415858)
			(xy 165.933569 -353.469265) (xy 165.909897 -353.519762) (xy 165.879124 -353.566275) (xy 165.841907 -353.607812)
			(xy 165.799039 -353.643487) (xy 165.751433 -353.672541) (xy 165.700104 -353.694353) (xy 165.646147 -353.708459)
			(xy 165.59071 -353.714559) (xy 165.534976 -353.712522) (xy 165.480133 -353.702392) (xy 165.427349 -353.684385)
			(xy 165.377749 -353.658884) (xy 165.332391 -353.626433) (xy 165.292242 -353.587724) (xy 165.258156 -353.543581)
			(xy 165.23086 -353.494946) (xy 165.210937 -353.442855) (xy 165.198811 -353.388418) (xy 165.19474 -353.332796)
			(xy 161.830598 -353.332796) (xy 161.892744 -353.371858) (xy 161.951388 -353.418642) (xy 162.004425 -353.471698)
			(xy 162.051186 -353.53036) (xy 162.091085 -353.593889) (xy 162.123618 -353.661487) (xy 162.148377 -353.732302)
			(xy 162.165051 -353.805445) (xy 162.173429 -353.879994) (xy 162.17392 -353.917504) (xy 162.173405 -353.95501)
			(xy 162.165031 -354.029551) (xy 162.148364 -354.102687) (xy 162.123616 -354.173498) (xy 162.091096 -354.241093)
			(xy 162.051215 -354.304623) (xy 162.004472 -354.36329) (xy 161.97834 -354.390198) (xy 161.279332 -355.088952)
			(xy 161.273493 -355.09622) (xy 161.266979 -355.113672) (xy 161.266632 -355.122988) (xy 161.266632 -355.82352)
			(xy 161.267059 -355.833588) (xy 161.274783 -355.852184) (xy 161.281618 -355.859588) (xy 165.695183 -360.273153)
			(xy 172.666349 -360.273153) (xy 172.666349 -360.218646) (xy 172.674107 -360.164693) (xy 172.689463 -360.112394)
			(xy 172.712107 -360.062813) (xy 172.741576 -360.016959) (xy 172.777271 -359.975765) (xy 172.818465 -359.940071)
			(xy 172.86432 -359.910603) (xy 172.913902 -359.887961) (xy 172.966201 -359.872605) (xy 173.020154 -359.864849)
			(xy 173.074661 -359.86485) (xy 173.128613 -359.872608) (xy 173.180912 -359.887966) (xy 173.230493 -359.91061)
			(xy 173.276347 -359.94008) (xy 173.317539 -359.975776) (xy 173.353233 -360.016971) (xy 173.3827 -360.062826)
			(xy 173.405342 -360.112408) (xy 173.420696 -360.164708) (xy 173.428452 -360.21866) (xy 173.428914 -360.245914)
			(xy 173.428704 -360.263673) (xy 173.425396 -360.299036) (xy 173.42231 -360.316526) (xy 173.420024 -360.328718)
			(xy 173.426628 -360.351832) (xy 173.49978 -360.429556) (xy 173.522386 -360.437684) (xy 173.534578 -360.43616)
			(xy 173.546215 -360.434823) (xy 173.5696 -360.433428) (xy 173.581314 -360.433366) (xy 173.608564 -360.433865)
			(xy 173.66251 -360.441622) (xy 173.714803 -360.456978) (xy 173.764379 -360.479619) (xy 173.810228 -360.509084)
			(xy 173.851417 -360.544774) (xy 173.887109 -360.585963) (xy 173.916575 -360.631811) (xy 173.939218 -360.681385)
			(xy 173.954575 -360.733678) (xy 173.962334 -360.787624) (xy 173.962822 -360.814874) (xy 173.962464 -360.839861)
			(xy 173.955968 -360.88941) (xy 173.943057 -360.937686) (xy 173.933866 -360.960924) (xy 173.928532 -360.973878)
			(xy 173.932088 -361.000802) (xy 174.004478 -361.092496) (xy 174.029878 -361.102148) (xy 174.043594 -361.100116)
			(xy 174.058542 -361.097863) (xy 174.088676 -361.095448) (xy 174.103792 -361.09529) (xy 174.131046 -361.095747)
			(xy 174.184998 -361.103503) (xy 174.237298 -361.118858) (xy 174.286879 -361.1415) (xy 174.332734 -361.170968)
			(xy 174.373929 -361.206662) (xy 174.409624 -361.247856) (xy 174.439093 -361.293709) (xy 174.461737 -361.343291)
			(xy 174.477094 -361.39559) (xy 174.484852 -361.449542) (xy 174.484853 -361.504049) (xy 174.477096 -361.558001)
			(xy 174.461741 -361.610301) (xy 174.439098 -361.659882) (xy 174.40963 -361.705737) (xy 174.373935 -361.746931)
			(xy 174.332742 -361.782626) (xy 174.286888 -361.812095) (xy 174.237306 -361.834738) (xy 174.185007 -361.850095)
			(xy 174.131055 -361.857853) (xy 174.076548 -361.857853) (xy 174.022595 -361.850096) (xy 173.970296 -361.834739)
			(xy 173.920715 -361.812096) (xy 173.87486 -361.782628) (xy 173.833667 -361.746933) (xy 173.797972 -361.705739)
			(xy 173.768503 -361.659885) (xy 173.74586 -361.610303) (xy 173.730504 -361.558004) (xy 173.722747 -361.504052)
			(xy 173.722284 -361.476798) (xy 173.722664 -361.451812) (xy 173.729152 -361.402264) (xy 173.742054 -361.353987)
			(xy 173.75124 -361.330748) (xy 173.756574 -361.317794) (xy 173.753018 -361.29087) (xy 173.680628 -361.199176)
			(xy 173.655228 -361.189524) (xy 173.641512 -361.191556) (xy 173.626564 -361.193808) (xy 173.59643 -361.196224)
			(xy 173.581314 -361.196382) (xy 173.55406 -361.195932) (xy 173.500108 -361.188176) (xy 173.447808 -361.17282)
			(xy 173.398226 -361.150177) (xy 173.352372 -361.120709) (xy 173.311178 -361.085013) (xy 173.275484 -361.043819)
			(xy 173.246017 -360.997963) (xy 173.223376 -360.948381) (xy 173.208022 -360.896081) (xy 173.200268 -360.842128)
			(xy 173.199806 -360.814874) (xy 173.200014 -360.797115) (xy 173.203323 -360.761752) (xy 173.20641 -360.744262)
			(xy 173.208696 -360.73207) (xy 173.202092 -360.708956) (xy 173.12894 -360.631232) (xy 173.106334 -360.623104)
			(xy 173.094142 -360.624628) (xy 173.082505 -360.625963) (xy 173.05912 -360.62736) (xy 173.047406 -360.627422)
			(xy 173.020152 -360.626951) (xy 172.9662 -360.619195) (xy 172.913901 -360.603839) (xy 172.864319 -360.581196)
			(xy 172.818464 -360.551728) (xy 172.77727 -360.516034) (xy 172.741575 -360.47484) (xy 172.712106 -360.428986)
			(xy 172.689463 -360.379404) (xy 172.674106 -360.327105) (xy 172.666349 -360.273153) (xy 165.695183 -360.273153)
			(xy 168.025839 -362.603809) (xy 174.761723 -362.603809) (xy 174.761729 -362.549315) (xy 174.769489 -362.495375)
			(xy 174.784847 -362.44309) (xy 174.80749 -362.393522) (xy 174.836956 -362.347681) (xy 174.872646 -362.306499)
			(xy 174.913833 -362.270816) (xy 174.95968 -362.241358) (xy 175.009252 -362.218724) (xy 175.06154 -362.203375)
			(xy 175.115481 -362.195624) (xy 175.169975 -362.195628) (xy 175.223915 -362.203387) (xy 175.276201 -362.218744)
			(xy 175.32577 -362.241385) (xy 175.371611 -362.27085) (xy 175.412794 -362.306539) (xy 175.448478 -362.347725)
			(xy 175.477937 -362.393571) (xy 175.500572 -362.443142) (xy 175.515922 -362.49543) (xy 175.523675 -362.549371)
			(xy 175.52416 -362.576618) (xy 175.52289 -362.607098) (xy 175.522128 -362.618274) (xy 175.529748 -362.639102)
			(xy 175.60036 -362.709714) (xy 175.621188 -362.717334) (xy 175.632364 -362.716572) (xy 175.663098 -362.715302)
			(xy 175.690349 -362.715776) (xy 175.744297 -362.723532) (xy 175.796592 -362.738887) (xy 175.846169 -362.761527)
			(xy 175.89202 -362.790993) (xy 175.933211 -362.826685) (xy 175.968903 -362.867875) (xy 175.998369 -362.913725)
			(xy 176.021011 -362.963302) (xy 176.036367 -363.015596) (xy 176.044124 -363.069544) (xy 176.044125 -363.124047)
			(xy 176.036369 -363.177994) (xy 176.021014 -363.230289) (xy 175.998374 -363.279867) (xy 175.968908 -363.325718)
			(xy 175.933217 -363.366909) (xy 175.892028 -363.402601) (xy 175.846178 -363.432068) (xy 175.796601 -363.45471)
			(xy 175.744306 -363.470066) (xy 175.690359 -363.477824) (xy 175.635856 -363.477825) (xy 175.581908 -363.470069)
			(xy 175.529613 -363.454715) (xy 175.480035 -363.432075) (xy 175.434184 -363.40261) (xy 175.392993 -363.366919)
			(xy 175.357301 -363.32573) (xy 175.327833 -363.27988) (xy 175.305191 -363.230303) (xy 175.289834 -363.178009)
			(xy 175.282076 -363.124061) (xy 175.28159 -363.09681) (xy 175.28286 -363.06633) (xy 175.283622 -363.055154)
			(xy 175.276002 -363.034326) (xy 175.20539 -362.963714) (xy 175.184562 -362.956094) (xy 175.173386 -362.956856)
			(xy 175.142652 -362.958126) (xy 175.115405 -362.95757) (xy 175.061466 -362.949808) (xy 175.00918 -362.934449)
			(xy 174.959613 -362.911805) (xy 174.913773 -362.882338) (xy 174.872592 -362.846647) (xy 174.83691 -362.805459)
			(xy 174.807453 -362.759612) (xy 174.784821 -362.710039) (xy 174.769473 -362.65775) (xy 174.761723 -362.603809)
			(xy 168.025839 -362.603809) (xy 168.218612 -362.796582) (xy 168.22601 -362.803428) (xy 168.244609 -362.811161)
			(xy 168.25468 -362.811568) (xy 170.538648 -362.811568) (xy 170.548715 -362.811999) (xy 170.56731 -362.819722)
			(xy 170.574716 -362.826554) (xy 171.06773 -363.319568) (xy 171.087288 -363.327442) (xy 171.097956 -363.326934)
			(xy 171.111926 -363.32668) (xy 171.112434 -363.32668) (xy 171.139684 -363.327168) (xy 171.193629 -363.334928)
			(xy 171.24592 -363.350286) (xy 171.295494 -363.372929) (xy 171.341341 -363.402396) (xy 171.382528 -363.438088)
			(xy 171.418217 -363.479277) (xy 171.447681 -363.525126) (xy 171.470321 -363.574701) (xy 171.485676 -363.626993)
			(xy 171.493433 -363.680938) (xy 171.493942 -363.708188) (xy 171.493942 -363.708696) (xy 171.493688 -363.722666)
			(xy 171.49318 -363.733334) (xy 171.501054 -363.752892) (xy 171.672504 -363.924342) (xy 179.856638 -363.924342)
			(xy 179.857119 -363.896972) (xy 179.864932 -363.842793) (xy 179.880417 -363.79029) (xy 179.903256 -363.740543)
			(xy 179.932978 -363.694576) (xy 179.950618 -363.673644) (xy 179.956714 -363.666532) (xy 179.963064 -363.649514)
			(xy 179.963064 -363.56417) (xy 179.956714 -363.547152) (xy 179.950618 -363.54004) (xy 179.932987 -363.519101)
			(xy 179.903273 -363.473131) (xy 179.880436 -363.423385) (xy 179.864943 -363.370886) (xy 179.857113 -363.316711)
			(xy 179.856638 -363.289342) (xy 179.857119 -363.261768) (xy 179.865067 -363.207195) (xy 179.880788 -363.154335)
			(xy 179.903955 -363.104289) (xy 179.934085 -363.058099) (xy 179.970551 -363.016728) (xy 179.991258 -362.998512)
			(xy 179.999376 -362.990909) (xy 180.008728 -362.970758) (xy 180.009292 -362.95965) (xy 180.009292 -362.882434)
			(xy 180.008724 -362.871324) (xy 179.999386 -362.851165) (xy 179.991258 -362.843572) (xy 179.970522 -362.825388)
			(xy 179.934055 -362.784013) (xy 179.903927 -362.737817) (xy 179.880766 -362.687764) (xy 179.865055 -362.634897)
			(xy 179.857121 -362.580318) (xy 179.856638 -362.552742) (xy 179.857119 -362.525372) (xy 179.864932 -362.471193)
			(xy 179.880417 -362.41869) (xy 179.903256 -362.368943) (xy 179.932978 -362.322976) (xy 179.950618 -362.302044)
			(xy 179.956714 -362.294932) (xy 179.963064 -362.277914) (xy 179.963064 -362.19257) (xy 179.956714 -362.175552)
			(xy 179.950618 -362.16844) (xy 179.933019 -362.147474) (xy 179.903293 -362.101512) (xy 179.880446 -362.051771)
			(xy 179.864947 -361.999274) (xy 179.857114 -361.9451) (xy 179.85711 -361.890363) (xy 179.864933 -361.836188)
			(xy 179.880423 -361.783689) (xy 179.903263 -361.733944) (xy 179.932981 -361.687977) (xy 179.950618 -361.667044)
			(xy 179.956714 -361.659932) (xy 179.963064 -361.642914) (xy 179.963064 -361.55757) (xy 179.956714 -361.540552)
			(xy 179.950618 -361.53344) (xy 179.933019 -361.512474) (xy 179.903293 -361.466512) (xy 179.880446 -361.416771)
			(xy 179.864947 -361.364274) (xy 179.857114 -361.3101) (xy 179.85711 -361.255363) (xy 179.864933 -361.201188)
			(xy 179.880423 -361.148689) (xy 179.903263 -361.098944) (xy 179.932981 -361.052977) (xy 179.950618 -361.032044)
			(xy 179.956714 -361.024932) (xy 179.963064 -361.007914) (xy 179.963064 -360.92257) (xy 179.956714 -360.905552)
			(xy 179.950618 -360.89844) (xy 179.932987 -360.877501) (xy 179.903273 -360.831531) (xy 179.880436 -360.781785)
			(xy 179.864943 -360.729286) (xy 179.857113 -360.675111) (xy 179.856638 -360.647742) (xy 179.857119 -360.620168)
			(xy 179.865067 -360.565595) (xy 179.880788 -360.512735) (xy 179.903955 -360.462689) (xy 179.934085 -360.416499)
			(xy 179.970551 -360.375128) (xy 179.991258 -360.356912) (xy 179.999376 -360.349309) (xy 180.008728 -360.329158)
			(xy 180.009292 -360.31805) (xy 180.009292 -360.240834) (xy 180.008724 -360.229724) (xy 179.999386 -360.209565)
			(xy 179.991258 -360.201972) (xy 179.970522 -360.183788) (xy 179.934055 -360.142413) (xy 179.903927 -360.096217)
			(xy 179.880766 -360.046164) (xy 179.865055 -359.993297) (xy 179.857121 -359.938718) (xy 179.856638 -359.911142)
			(xy 179.857119 -359.883772) (xy 179.864932 -359.829593) (xy 179.880417 -359.77709) (xy 179.903256 -359.727343)
			(xy 179.932978 -359.681376) (xy 179.950618 -359.660444) (xy 179.956714 -359.653332) (xy 179.963064 -359.636314)
			(xy 179.963064 -359.55097) (xy 179.956714 -359.533952) (xy 179.950618 -359.52684) (xy 179.932987 -359.505901)
			(xy 179.903273 -359.459931) (xy 179.880436 -359.410185) (xy 179.864943 -359.357686) (xy 179.857113 -359.303511)
			(xy 179.856638 -359.276142) (xy 179.857095 -359.248888) (xy 179.864847 -359.194935) (xy 179.8802 -359.142634)
			(xy 179.902841 -359.093051) (xy 179.932309 -359.047195) (xy 179.968004 -359.006001) (xy 180.009198 -358.970306)
			(xy 180.055054 -358.940839) (xy 180.104637 -358.918199) (xy 180.156938 -358.902846) (xy 180.210892 -358.895094)
			(xy 180.238146 -358.894634) (xy 180.265515 -358.895123) (xy 180.319694 -358.902934) (xy 180.372197 -358.918418)
			(xy 180.421944 -358.941254) (xy 180.467912 -358.970975) (xy 180.488844 -358.988614) (xy 180.495956 -358.99471)
			(xy 180.512974 -359.00106) (xy 180.598318 -359.00106) (xy 180.615336 -358.99471) (xy 180.622448 -358.988614)
			(xy 180.643381 -358.970973) (xy 180.689349 -358.941249) (xy 180.739095 -358.918403) (xy 180.791597 -358.902907)
			(xy 180.845775 -358.895078) (xy 180.900517 -358.895078) (xy 180.954695 -358.902907) (xy 181.007197 -358.918403)
			(xy 181.056943 -358.941249) (xy 181.102911 -358.970973) (xy 181.123844 -358.988614) (xy 181.130956 -358.99471)
			(xy 181.147974 -359.00106) (xy 181.233318 -359.00106) (xy 181.250336 -358.99471) (xy 181.257448 -358.988614)
			(xy 181.278381 -358.970973) (xy 181.324349 -358.941249) (xy 181.374095 -358.918403) (xy 181.426597 -358.902907)
			(xy 181.480775 -358.895078) (xy 181.535517 -358.895078) (xy 181.589695 -358.902907) (xy 181.642197 -358.918403)
			(xy 181.691943 -358.941249) (xy 181.737911 -358.970973) (xy 181.758844 -358.988614) (xy 181.765956 -358.99471)
			(xy 181.782974 -359.00106) (xy 181.868318 -359.00106) (xy 181.885336 -358.99471) (xy 181.892448 -358.988614)
			(xy 181.913391 -358.970988) (xy 181.95936 -358.941274) (xy 182.009105 -358.918435) (xy 182.061604 -358.902941)
			(xy 182.115778 -358.89511) (xy 182.143146 -358.894634) (xy 182.1704 -358.895035) (xy 182.224353 -358.902799)
			(xy 182.276652 -358.918162) (xy 182.326232 -358.940812) (xy 182.372085 -358.970287) (xy 182.413275 -359.005987)
			(xy 182.448966 -359.047186) (xy 182.478431 -359.093045) (xy 182.501069 -359.14263) (xy 182.51642 -359.194933)
			(xy 182.524171 -359.248888) (xy 182.524654 -359.276142) (xy 182.524165 -359.303512) (xy 182.516355 -359.35769)
			(xy 182.500871 -359.410193) (xy 182.478034 -359.459941) (xy 182.448314 -359.505908) (xy 182.430674 -359.52684)
			(xy 182.424578 -359.533952) (xy 182.418228 -359.55097) (xy 182.418228 -359.636314) (xy 182.424578 -359.653332)
			(xy 182.430674 -359.660444) (xy 182.448296 -359.68139) (xy 182.478012 -359.727358) (xy 182.500851 -359.777102)
			(xy 182.516346 -359.8296) (xy 182.524178 -359.883774) (xy 182.524654 -359.911142) (xy 182.524161 -359.938392)
			(xy 182.5164 -359.992337) (xy 182.501042 -360.044629) (xy 182.4784 -360.094203) (xy 182.448933 -360.140051)
			(xy 182.413243 -360.18124) (xy 182.372055 -360.216931) (xy 182.326207 -360.246398) (xy 182.276633 -360.269041)
			(xy 182.224341 -360.2844) (xy 182.170396 -360.292161) (xy 182.143146 -360.29265) (xy 182.115776 -360.292169)
			(xy 182.061597 -360.284357) (xy 182.009094 -360.268872) (xy 181.959347 -360.246033) (xy 181.91338 -360.216311)
			(xy 181.892448 -360.19867) (xy 181.885336 -360.192574) (xy 181.868318 -360.186224) (xy 181.782974 -360.186224)
			(xy 181.765956 -360.192574) (xy 181.758844 -360.19867) (xy 181.737911 -360.216311) (xy 181.691943 -360.246035)
			(xy 181.642197 -360.268881) (xy 181.589695 -360.284377) (xy 181.535517 -360.292206) (xy 181.480775 -360.292206)
			(xy 181.426597 -360.284377) (xy 181.374095 -360.268881) (xy 181.324349 -360.246035) (xy 181.278381 -360.216311)
			(xy 181.257448 -360.19867) (xy 181.250336 -360.192574) (xy 181.233318 -360.186224) (xy 181.147974 -360.186224)
			(xy 181.130956 -360.192574) (xy 181.123844 -360.19867) (xy 181.102911 -360.216311) (xy 181.056943 -360.246035)
			(xy 181.007197 -360.268881) (xy 180.954695 -360.284377) (xy 180.900517 -360.292206) (xy 180.845775 -360.292206)
			(xy 180.791597 -360.284377) (xy 180.739095 -360.268881) (xy 180.689349 -360.246035) (xy 180.643381 -360.216311)
			(xy 180.622448 -360.19867) (xy 180.615336 -360.192574) (xy 180.598318 -360.186224) (xy 180.512974 -360.186224)
			(xy 180.495956 -360.192574) (xy 180.488844 -360.19867) (xy 180.485034 -360.201972) (xy 180.476922 -360.20958)
			(xy 180.467567 -360.229728) (xy 180.467 -360.240834) (xy 180.467 -360.31805) (xy 180.46758 -360.329158)
			(xy 180.47691 -360.349317) (xy 180.485034 -360.356912) (xy 180.505761 -360.375106) (xy 180.542229 -360.416479)
			(xy 180.572358 -360.462673) (xy 180.595521 -360.512724) (xy 180.611234 -360.565589) (xy 180.61917 -360.620166)
			(xy 180.619654 -360.647742) (xy 180.619165 -360.675112) (xy 180.611355 -360.72929) (xy 180.595871 -360.781793)
			(xy 180.573034 -360.831541) (xy 180.543314 -360.877508) (xy 180.525674 -360.89844) (xy 180.519578 -360.905552)
			(xy 180.513228 -360.92257) (xy 180.513228 -361.007914) (xy 180.519578 -361.024932) (xy 180.525674 -361.032044)
			(xy 180.543356 -361.052943) (xy 180.573079 -361.098917) (xy 180.595922 -361.148669) (xy 180.611415 -361.201176)
			(xy 180.619239 -361.255359) (xy 180.619235 -361.310104) (xy 180.611401 -361.364286) (xy 180.595899 -361.416791)
			(xy 180.573048 -361.466539) (xy 180.568874 -361.472993) (xy 185.652165 -361.472993) (xy 185.655896 -361.419741)
			(xy 185.667013 -361.367529) (xy 185.685299 -361.317376) (xy 185.710397 -361.270262) (xy 185.741818 -361.227107)
			(xy 185.778948 -361.188752) (xy 185.79973 -361.171998) (xy 185.808493 -361.164438) (xy 185.818675 -361.143678)
			(xy 185.819288 -361.13212) (xy 185.819288 -361.051856) (xy 185.818689 -361.040292) (xy 185.808515 -361.01952)
			(xy 185.79973 -361.011978) (xy 185.777242 -360.993792) (xy 185.737506 -360.951772) (xy 185.704567 -360.904236)
			(xy 185.679179 -360.852274) (xy 185.661924 -360.797075) (xy 185.653197 -360.739904) (xy 185.652664 -360.710988)
			(xy 185.653167 -360.683738) (xy 185.660924 -360.629792) (xy 185.676279 -360.577499) (xy 185.69892 -360.527924)
			(xy 185.728385 -360.482075) (xy 185.764074 -360.440886) (xy 185.805262 -360.405194) (xy 185.85111 -360.375727)
			(xy 185.900684 -360.353085) (xy 185.952976 -360.337727) (xy 186.006922 -360.329968) (xy 186.034172 -360.32948)
			(xy 186.06309 -360.329988) (xy 186.120263 -360.338715) (xy 186.175463 -360.355973) (xy 186.227425 -360.381366)
			(xy 186.274959 -360.414313) (xy 186.316974 -360.454058) (xy 186.335162 -360.476546) (xy 186.342737 -360.485294)
			(xy 186.363486 -360.495483) (xy 186.37504 -360.496104) (xy 186.455304 -360.496104) (xy 186.466872 -360.495534)
			(xy 186.487643 -360.485339) (xy 186.495182 -360.476546) (xy 186.51337 -360.45406) (xy 186.555392 -360.414327)
			(xy 186.602928 -360.38139) (xy 186.654889 -360.356003) (xy 186.710087 -360.338746) (xy 186.767256 -360.330016)
			(xy 186.796172 -360.32948) (xy 186.823424 -360.329981) (xy 186.877373 -360.337734) (xy 186.929669 -360.353086)
			(xy 186.979248 -360.375724) (xy 187.025101 -360.405188) (xy 187.066294 -360.440878) (xy 187.101988 -360.482067)
			(xy 187.131456 -360.527917) (xy 187.1541 -360.577494) (xy 187.169457 -360.629788) (xy 187.177216 -360.683736)
			(xy 187.17768 -360.710988) (xy 187.177161 -360.739905) (xy 187.168433 -360.797076) (xy 187.151176 -360.852276)
			(xy 187.125784 -360.904237) (xy 187.092841 -360.951771) (xy 187.0531 -360.993788) (xy 187.030614 -361.011978)
			(xy 187.021869 -361.019556) (xy 187.011675 -361.040302) (xy 187.011056 -361.051856) (xy 187.011056 -361.13212)
			(xy 187.011653 -361.143685) (xy 187.021827 -361.164458) (xy 187.030614 -361.171998) (xy 187.051386 -361.188765)
			(xy 187.088519 -361.227115) (xy 187.119942 -361.270268) (xy 187.145044 -361.31738) (xy 187.163332 -361.367531)
			(xy 187.17445 -361.419742) (xy 187.178181 -361.472993) (xy 187.174452 -361.526244) (xy 187.163336 -361.578455)
			(xy 187.14505 -361.628607) (xy 187.11995 -361.67572) (xy 187.088528 -361.718873) (xy 187.051397 -361.757225)
			(xy 187.030614 -361.773978) (xy 187.021869 -361.781556) (xy 187.011675 -361.802302) (xy 187.011056 -361.813856)
			(xy 187.011056 -361.89412) (xy 187.011653 -361.905685) (xy 187.021827 -361.926458) (xy 187.030614 -361.933998)
			(xy 187.053099 -361.952187) (xy 187.092834 -361.994207) (xy 187.125772 -362.041743) (xy 187.15116 -362.093704)
			(xy 187.168416 -362.148902) (xy 187.177145 -362.206072) (xy 187.17768 -362.234988) (xy 187.177233 -362.262242)
			(xy 187.169477 -362.316195) (xy 187.154121 -362.368495) (xy 187.131478 -362.418077) (xy 187.102009 -362.463931)
			(xy 187.094223 -362.472916) (xy 190.790826 -362.472916) (xy 190.790826 -362.38822) (xy 190.798877 -362.303906)
			(xy 190.814906 -362.22074) (xy 190.838767 -362.139473) (xy 190.870246 -362.060843) (xy 190.909057 -361.985562)
			(xy 190.954847 -361.91431) (xy 191.007203 -361.847734) (xy 191.065651 -361.786436) (xy 191.129661 -361.730971)
			(xy 191.198653 -361.681842) (xy 191.272003 -361.639493) (xy 191.349046 -361.604309) (xy 191.429085 -361.576607)
			(xy 191.511394 -361.556639) (xy 191.595229 -361.544586) (xy 191.67983 -361.540556) (xy 191.764431 -361.544586)
			(xy 191.848266 -361.556639) (xy 191.930575 -361.576607) (xy 192.010614 -361.604309) (xy 192.087657 -361.639493)
			(xy 192.161007 -361.681842) (xy 192.229999 -361.730971) (xy 192.294009 -361.786436) (xy 192.352457 -361.847734)
			(xy 192.404813 -361.91431) (xy 192.450603 -361.985562) (xy 192.489414 -362.060843) (xy 192.520893 -362.139473)
			(xy 192.544754 -362.22074) (xy 192.560783 -362.303906) (xy 192.568834 -362.38822) (xy 192.569338 -362.430568)
			(xy 192.568834 -362.472916) (xy 192.560783 -362.55723) (xy 192.544754 -362.640396) (xy 192.520893 -362.721663)
			(xy 192.489414 -362.800293) (xy 192.450603 -362.875574) (xy 192.404813 -362.946826) (xy 192.352457 -363.013402)
			(xy 192.294009 -363.0747) (xy 192.229999 -363.130165) (xy 192.161007 -363.179294) (xy 192.087657 -363.221643)
			(xy 192.010614 -363.256827) (xy 191.930575 -363.284529) (xy 191.848266 -363.304497) (xy 191.764431 -363.31655)
			(xy 191.67983 -363.320581) (xy 191.595229 -363.31655) (xy 191.511394 -363.304497) (xy 191.429085 -363.284529)
			(xy 191.349046 -363.256827) (xy 191.272003 -363.221643) (xy 191.198653 -363.179294) (xy 191.129661 -363.130165)
			(xy 191.065651 -363.0747) (xy 191.007203 -363.013402) (xy 190.954847 -362.946826) (xy 190.909057 -362.875574)
			(xy 190.870246 -362.800293) (xy 190.838767 -362.721663) (xy 190.814906 -362.640396) (xy 190.798877 -362.55723)
			(xy 190.790826 -362.472916) (xy 187.094223 -362.472916) (xy 187.066313 -362.505125) (xy 187.025118 -362.540819)
			(xy 186.979263 -362.570286) (xy 186.92968 -362.592927) (xy 186.877379 -362.608281) (xy 186.823426 -362.616035)
			(xy 186.796172 -362.616496) (xy 186.767257 -362.615928) (xy 186.710088 -362.607209) (xy 186.65489 -362.589961)
			(xy 186.602928 -362.564579) (xy 186.555393 -362.531644) (xy 186.513374 -362.491912) (xy 186.495182 -362.46943)
			(xy 186.487636 -362.460653) (xy 186.466865 -362.450481) (xy 186.455304 -362.449872) (xy 186.37504 -362.449872)
			(xy 186.363471 -362.450441) (xy 186.342699 -362.460634) (xy 186.335162 -362.46943) (xy 186.317 -362.491938)
			(xy 186.274973 -362.53167) (xy 186.227432 -362.564605) (xy 186.175465 -362.589989) (xy 186.120263 -362.607241)
			(xy 186.06309 -362.615964) (xy 186.034172 -362.616496) (xy 186.00692 -362.616048) (xy 185.95297 -362.608288)
			(xy 185.900674 -362.592928) (xy 185.851095 -362.570283) (xy 185.805245 -362.540813) (xy 185.764054 -362.505117)
			(xy 185.728363 -362.463923) (xy 185.698898 -362.418069) (xy 185.676258 -362.368489) (xy 185.660904 -362.316191)
			(xy 185.653149 -362.262241) (xy 185.652664 -362.234988) (xy 185.653221 -362.206072) (xy 185.661939 -362.148902)
			(xy 185.679187 -362.093703) (xy 185.704572 -362.04174) (xy 185.73751 -361.994206) (xy 185.777246 -361.952188)
			(xy 185.79973 -361.933998) (xy 185.808493 -361.926438) (xy 185.818675 -361.905678) (xy 185.819288 -361.89412)
			(xy 185.819288 -361.813856) (xy 185.818689 -361.802292) (xy 185.808515 -361.78152) (xy 185.79973 -361.773978)
			(xy 185.778937 -361.757238) (xy 185.741809 -361.718882) (xy 185.71039 -361.675725) (xy 185.685293 -361.62861)
			(xy 185.667009 -361.578457) (xy 185.655894 -361.526245) (xy 185.652165 -361.472993) (xy 180.568874 -361.472993)
			(xy 180.543318 -361.512507) (xy 180.525674 -361.53344) (xy 180.519578 -361.540552) (xy 180.513228 -361.55757)
			(xy 180.513228 -361.642914) (xy 180.519578 -361.659932) (xy 180.525674 -361.667044) (xy 180.543356 -361.687943)
			(xy 180.573079 -361.733917) (xy 180.595922 -361.783669) (xy 180.611415 -361.836176) (xy 180.619239 -361.890359)
			(xy 180.619235 -361.945104) (xy 180.611401 -361.999286) (xy 180.595899 -362.051791) (xy 180.573048 -362.101539)
			(xy 180.543318 -362.147507) (xy 180.525674 -362.16844) (xy 180.519578 -362.175552) (xy 180.513228 -362.19257)
			(xy 180.513228 -362.277914) (xy 180.519578 -362.294932) (xy 180.525674 -362.302044) (xy 180.543296 -362.32299)
			(xy 180.573012 -362.368958) (xy 180.595851 -362.418702) (xy 180.611346 -362.4712) (xy 180.619178 -362.525374)
			(xy 180.619654 -362.552742) (xy 180.619164 -362.580316) (xy 180.611219 -362.634888) (xy 180.5955 -362.687748)
			(xy 180.572334 -362.737795) (xy 180.542205 -362.783985) (xy 180.50574 -362.825356) (xy 180.485034 -362.843572)
			(xy 180.476922 -362.85118) (xy 180.467567 -362.871328) (xy 180.467 -362.882434) (xy 180.467 -362.95965)
			(xy 180.46758 -362.970758) (xy 180.47691 -362.990917) (xy 180.485034 -362.998512) (xy 180.488844 -363.001814)
			(xy 180.495956 -363.00791) (xy 180.512974 -363.01426) (xy 180.598318 -363.01426) (xy 180.615336 -363.00791)
			(xy 180.622448 -363.001814) (xy 180.643381 -362.984173) (xy 180.689349 -362.954449) (xy 180.739095 -362.931603)
			(xy 180.791597 -362.916107) (xy 180.845775 -362.908278) (xy 180.900517 -362.908278) (xy 180.954695 -362.916107)
			(xy 181.007197 -362.931603) (xy 181.056943 -362.954449) (xy 181.102911 -362.984173) (xy 181.123844 -363.001814)
			(xy 181.130956 -363.00791) (xy 181.147974 -363.01426) (xy 181.233318 -363.01426) (xy 181.250336 -363.00791)
			(xy 181.257448 -363.001814) (xy 181.278381 -362.984173) (xy 181.324349 -362.954449) (xy 181.374095 -362.931603)
			(xy 181.426597 -362.916107) (xy 181.480775 -362.908278) (xy 181.535517 -362.908278) (xy 181.589695 -362.916107)
			(xy 181.642197 -362.931603) (xy 181.691943 -362.954449) (xy 181.737911 -362.984173) (xy 181.758844 -363.001814)
			(xy 181.765956 -363.00791) (xy 181.782974 -363.01426) (xy 181.868318 -363.01426) (xy 181.885336 -363.00791)
			(xy 181.892448 -363.001814) (xy 181.913391 -362.984188) (xy 181.95936 -362.954474) (xy 182.009105 -362.931635)
			(xy 182.061604 -362.916141) (xy 182.115778 -362.90831) (xy 182.143146 -362.907834) (xy 182.1704 -362.908235)
			(xy 182.224353 -362.915999) (xy 182.276652 -362.931362) (xy 182.326232 -362.954012) (xy 182.372085 -362.983487)
			(xy 182.413275 -363.019187) (xy 182.448966 -363.060386) (xy 182.478431 -363.106245) (xy 182.501069 -363.15583)
			(xy 182.51642 -363.208133) (xy 182.524171 -363.262088) (xy 182.524654 -363.289342) (xy 182.524165 -363.316712)
			(xy 182.516355 -363.37089) (xy 182.500871 -363.423393) (xy 182.478034 -363.473141) (xy 182.448314 -363.519108)
			(xy 182.430674 -363.54004) (xy 182.424578 -363.547152) (xy 182.418228 -363.56417) (xy 182.418228 -363.649514)
			(xy 182.424578 -363.666532) (xy 182.430674 -363.673644) (xy 182.448296 -363.69459) (xy 182.478012 -363.740558)
			(xy 182.500851 -363.790302) (xy 182.516346 -363.8428) (xy 182.524178 -363.896974) (xy 182.524654 -363.924342)
			(xy 182.524161 -363.951592) (xy 182.5164 -364.005537) (xy 182.501042 -364.057829) (xy 182.4784 -364.107403)
			(xy 182.448933 -364.153251) (xy 182.413243 -364.19444) (xy 182.372055 -364.230131) (xy 182.326207 -364.259598)
			(xy 182.276633 -364.282241) (xy 182.224341 -364.2976) (xy 182.170396 -364.305361) (xy 182.143146 -364.30585)
			(xy 182.115776 -364.305369) (xy 182.061597 -364.297557) (xy 182.009094 -364.282072) (xy 181.959347 -364.259233)
			(xy 181.91338 -364.229511) (xy 181.892448 -364.21187) (xy 181.885336 -364.205774) (xy 181.868318 -364.199424)
			(xy 181.782974 -364.199424) (xy 181.765956 -364.205774) (xy 181.758844 -364.21187) (xy 181.737911 -364.229511)
			(xy 181.691943 -364.259235) (xy 181.642197 -364.282081) (xy 181.589695 -364.297577) (xy 181.535517 -364.305406)
			(xy 181.480775 -364.305406) (xy 181.426597 -364.297577) (xy 181.374095 -364.282081) (xy 181.324349 -364.259235)
			(xy 181.278381 -364.229511) (xy 181.257448 -364.21187) (xy 181.250336 -364.205774) (xy 181.233318 -364.199424)
			(xy 181.147974 -364.199424) (xy 181.130956 -364.205774) (xy 181.123844 -364.21187) (xy 181.102911 -364.229511)
			(xy 181.056943 -364.259235) (xy 181.007197 -364.282081) (xy 180.954695 -364.297577) (xy 180.900517 -364.305406)
			(xy 180.845775 -364.305406) (xy 180.791597 -364.297577) (xy 180.739095 -364.282081) (xy 180.689349 -364.259235)
			(xy 180.643381 -364.229511) (xy 180.622448 -364.21187) (xy 180.615336 -364.205774) (xy 180.598318 -364.199424)
			(xy 180.512974 -364.199424) (xy 180.495956 -364.205774) (xy 180.488844 -364.21187) (xy 180.467902 -364.229497)
			(xy 180.421933 -364.259212) (xy 180.372188 -364.282051) (xy 180.319689 -364.297544) (xy 180.265515 -364.305375)
			(xy 180.238146 -364.30585) (xy 180.210896 -364.305302) (xy 180.15695 -364.297552) (xy 180.104657 -364.282204)
			(xy 180.05508 -364.25957) (xy 180.009228 -364.230111) (xy 179.968036 -364.194426) (xy 179.932342 -364.153242)
			(xy 179.902872 -364.107398) (xy 179.880226 -364.057826) (xy 179.864866 -364.005536) (xy 179.857104 -363.951592)
			(xy 179.856638 -363.924342) (xy 171.672504 -363.924342) (xy 172.567092 -364.81893) (xy 172.5676 -364.819438)
			(xy 172.574983 -364.826015) (xy 172.593282 -364.83345) (xy 172.60316 -364.833916) (xy 174.013622 -364.833916)
			(xy 174.03064 -364.83417) (xy 174.2694 -364.83417) (xy 174.279388 -364.834707) (xy 174.297823 -364.842417)
			(xy 174.305214 -364.849156) (xy 174.474124 -365.017812) (xy 174.474632 -365.01832) (xy 174.486316 -365.02975)
			(xy 174.915322 -365.45901) (xy 175.349916 -365.89335) (xy 175.357192 -365.900034) (xy 175.37536 -365.907752)
			(xy 175.385222 -365.908336) (xy 175.465486 -365.909606) (xy 175.484028 -365.90224) (xy 175.49114 -365.895382)
			(xy 175.509058 -365.879013) (xy 175.548311 -365.850471) (xy 175.590866 -365.827137) (xy 175.613314 -365.817912)
			(xy 175.625747 -365.812535) (xy 175.647419 -365.796302) (xy 175.664064 -365.774944) (xy 175.674511 -365.749962)
			(xy 175.678026 -365.723113) (xy 175.674361 -365.696285) (xy 175.663774 -365.671362) (xy 175.647009 -365.650098)
			(xy 175.636428 -365.641636) (xy 175.612883 -365.623499) (xy 175.571176 -365.581161) (xy 175.536529 -365.532874)
			(xy 175.509781 -365.479803) (xy 175.491576 -365.42323) (xy 175.482354 -365.364519) (xy 175.481742 -365.334804)
			(xy 175.482228 -365.307535) (xy 175.48999 -365.253551) (xy 175.505355 -365.201221) (xy 175.528012 -365.151611)
			(xy 175.557498 -365.10573) (xy 175.593213 -365.064513) (xy 175.63443 -365.028798) (xy 175.680311 -364.999312)
			(xy 175.729921 -364.976655) (xy 175.782251 -364.96129) (xy 175.836235 -364.953528) (xy 175.890773 -364.953528)
			(xy 175.944757 -364.96129) (xy 175.997087 -364.976655) (xy 176.046697 -364.999312) (xy 176.092578 -365.028798)
			(xy 176.133795 -365.064513) (xy 176.16951 -365.10573) (xy 176.198996 -365.151611) (xy 176.221653 -365.201221)
			(xy 176.237018 -365.253551) (xy 176.24478 -365.307535) (xy 176.245266 -365.334804) (xy 176.244735 -365.363324)
			(xy 176.236248 -365.419729) (xy 176.219463 -365.474243) (xy 176.194754 -365.525653) (xy 176.162671 -365.572815)
			(xy 176.123927 -365.614678) (xy 176.079387 -365.65031) (xy 176.030041 -365.67892) (xy 176.003712 -365.689896)
			(xy 175.991266 -365.695271) (xy 175.969566 -365.711506) (xy 175.952896 -365.732874) (xy 175.942428 -365.757872)
			(xy 175.938898 -365.784742) (xy 175.942555 -365.811596) (xy 175.953141 -365.836544) (xy 175.969912 -365.857832)
			(xy 175.980598 -365.866172) (xy 175.999862 -365.880897) (xy 176.034869 -365.914445) (xy 176.065342 -365.95216)
			(xy 176.078388 -365.972598) (xy 176.083218 -365.979762) (xy 176.09666 -365.990602) (xy 176.112935 -365.996371)
			(xy 176.121568 -365.996728) (xy 176.184052 -365.996728) (xy 176.209706 -365.979202) (xy 176.215294 -365.964216)
			(xy 176.225513 -365.939271) (xy 176.251955 -365.892296) (xy 176.28474 -365.849506) (xy 176.323216 -365.811751)
			(xy 176.366618 -365.779781) (xy 176.414085 -365.754232) (xy 176.464673 -365.735611) (xy 176.517376 -365.724288)
			(xy 176.571148 -365.720489) (xy 176.62492 -365.724288) (xy 176.677623 -365.735611) (xy 176.728211 -365.754232)
			(xy 176.775678 -365.779781) (xy 176.81908 -365.811751) (xy 176.857556 -365.849506) (xy 176.890341 -365.892296)
			(xy 176.916783 -365.939271) (xy 176.927002 -365.964216) (xy 176.93259 -365.979202) (xy 176.958244 -365.996728)
			(xy 179.68976 -365.996728) (xy 179.945538 -365.996728) (xy 179.955522 -365.997273) (xy 179.973941 -366.004999)
			(xy 179.981352 -366.011714) (xy 180.150008 -366.180116) (xy 180.151024 -366.181132) (xy 180.151532 -366.18164)
			(xy 180.162454 -366.192308) (xy 180.826664 -366.856518) (xy 180.827172 -366.857026) (xy 180.834553 -366.863608)
			(xy 180.852852 -366.871056) (xy 180.862732 -366.871504)
		)
		(stroke
			(width 0)
			(type solid)
		)
		(fill yes)
		(layer "In2.Cu")
		(net "GND")
	)
	(gr_poly
		(pts
			(xy 317.973202 -369.72113) (xy 348.77121 -364.222792) (xy 348.778848 -364.221147) (xy 348.792682 -364.213905)
			(xy 348.798388 -364.208568) (xy 350.801178 -362.205778) (xy 350.808577 -362.198935) (xy 350.827176 -362.191217)
			(xy 350.837246 -362.190792) (xy 364.527846 -348.500192) (xy 364.534697 -348.492796) (xy 364.542437 -348.474197)
			(xy 364.542832 -348.464124) (xy 364.542832 -342.459056) (xy 364.550706 -342.440514) (xy 364.557818 -342.433402)
			(xy 364.557818 -326.151494) (xy 364.557394 -326.141424) (xy 364.54968 -326.122819) (xy 364.542832 -326.115426)
			(xy 364.063026 -325.63562) (xy 364.055624 -325.628783) (xy 364.037026 -325.621073) (xy 364.026958 -325.620634)
			(xy 356.490778 -325.620634) (xy 356.48071 -325.621062) (xy 356.462115 -325.628786) (xy 356.45471 -325.63562)
			(xy 356.065582 -326.024748) (xy 356.058734 -326.032145) (xy 356.051004 -326.050744) (xy 356.050596 -326.060816)
			(xy 356.050596 -328.04227) (xy 356.05016 -328.052334) (xy 356.042427 -328.07092) (xy 356.03561 -328.078338)
			(xy 355.341936 -328.772012) (xy 355.334538 -328.778858) (xy 355.315939 -328.786583) (xy 355.305868 -328.786998)
			(xy 349.46082 -328.786998) (xy 349.450796 -328.787414) (xy 349.432272 -328.79508) (xy 349.418093 -328.809253)
			(xy 349.410418 -328.827774) (xy 349.41002 -328.837798) (xy 349.41002 -340.6648) (xy 349.410276 -340.672212)
			(xy 349.414541 -340.686408) (xy 349.418402 -340.69274) (xy 349.430785 -340.712297) (xy 349.450385 -340.754232)
			(xy 349.463715 -340.798559) (xy 349.470496 -340.844349) (xy 349.47098 -340.867492) (xy 349.47098 -341.264494)
			(xy 349.470514 -341.289482) (xy 349.462688 -341.338841) (xy 349.447227 -341.386366) (xy 349.424513 -341.430882)
			(xy 349.395108 -341.471291) (xy 349.377762 -341.489284) (xy 348.944146 -341.9229) (xy 351.983695 -341.9229)
			(xy 351.987864 -341.867274) (xy 352.000278 -341.812891) (xy 352.020658 -341.760965) (xy 352.04855 -341.712658)
			(xy 352.083331 -341.669047) (xy 352.124223 -341.631107) (xy 352.170314 -341.599686) (xy 352.220573 -341.575486)
			(xy 352.273878 -341.559047) (xy 352.329037 -341.550737) (xy 352.356928 -341.550244) (xy 352.38335 -341.550699)
			(xy 352.435665 -341.558151) (xy 352.486403 -341.572918) (xy 352.534547 -341.594702) (xy 352.579132 -341.623067)
			(xy 352.599498 -341.639906) (xy 352.606356 -341.646002) (xy 352.623374 -341.652098) (xy 352.707702 -341.652098)
			(xy 352.72472 -341.646002) (xy 352.731578 -341.639906) (xy 352.751944 -341.623067) (xy 352.79653 -341.594702)
			(xy 352.844674 -341.572915) (xy 352.895411 -341.558144) (xy 352.947726 -341.550684) (xy 353.00057 -341.550684)
			(xy 353.052885 -341.558144) (xy 353.103622 -341.572915) (xy 353.151766 -341.594702) (xy 353.196352 -341.623067)
			(xy 353.216718 -341.639906) (xy 353.223576 -341.646002) (xy 353.240594 -341.652098) (xy 353.324922 -341.652098)
			(xy 353.34194 -341.646002) (xy 353.348798 -341.639906) (xy 353.37117 -341.621476) (xy 353.420505 -341.591056)
			(xy 353.473954 -341.568638) (xy 353.50196 -341.561166) (xy 353.513644 -341.558372) (xy 353.531678 -341.542878)
			(xy 353.573334 -341.44712) (xy 353.572318 -341.423498) (xy 353.566476 -341.413084) (xy 353.554996 -341.391721)
			(xy 353.536944 -341.346707) (xy 353.524745 -341.299767) (xy 353.518595 -341.251659) (xy 353.518216 -341.22741)
			(xy 353.518683 -341.199835) (xy 353.526634 -341.145262) (xy 353.542359 -341.092402) (xy 353.565529 -341.042356)
			(xy 353.595661 -340.996167) (xy 353.632129 -340.954796) (xy 353.652836 -340.93658) (xy 353.660965 -340.928987)
			(xy 353.670312 -340.908828) (xy 353.67087 -340.897718) (xy 353.67087 -340.820502) (xy 353.670326 -340.809389)
			(xy 353.660972 -340.78923) (xy 353.652836 -340.78164) (xy 353.632148 -340.763403) (xy 353.595675 -340.722041)
			(xy 353.565539 -340.675857) (xy 353.542368 -340.625813) (xy 353.526647 -340.572955) (xy 353.518703 -340.518383)
			(xy 353.518216 -340.49081) (xy 353.518702 -340.463559) (xy 353.526458 -340.409611) (xy 353.541813 -340.357316)
			(xy 353.564455 -340.307739) (xy 353.593921 -340.261889) (xy 353.629612 -340.220698) (xy 353.670803 -340.185007)
			(xy 353.716653 -340.155541) (xy 353.76623 -340.132899) (xy 353.818525 -340.117544) (xy 353.872473 -340.109788)
			(xy 353.926975 -340.109788) (xy 353.980923 -340.117544) (xy 354.033218 -340.132899) (xy 354.082795 -340.155541)
			(xy 354.128645 -340.185007) (xy 354.169836 -340.220698) (xy 354.205527 -340.261889) (xy 354.234993 -340.307739)
			(xy 354.257635 -340.357316) (xy 354.27299 -340.409611) (xy 354.280746 -340.463559) (xy 354.281232 -340.49081)
			(xy 354.280693 -340.518382) (xy 354.272754 -340.572951) (xy 354.257043 -340.625809) (xy 354.233886 -340.675855)
			(xy 354.203767 -340.722046) (xy 354.167313 -340.763422) (xy 354.146612 -340.78164) (xy 354.138482 -340.789232)
			(xy 354.129133 -340.809391) (xy 354.128578 -340.820502) (xy 354.128578 -340.897718) (xy 354.129095 -340.908835)
			(xy 354.138467 -340.928995) (xy 354.146612 -340.93658) (xy 354.167319 -340.954795) (xy 354.203789 -340.996164)
			(xy 354.233922 -341.042353) (xy 354.257088 -341.0924) (xy 354.272805 -341.145261) (xy 354.280746 -341.199836)
			(xy 354.281232 -341.22741) (xy 354.280647 -341.255884) (xy 354.272167 -341.312198) (xy 354.255412 -341.366627)
			(xy 354.230754 -341.41796) (xy 354.19874 -341.465059) (xy 354.160082 -341.506877) (xy 354.115638 -341.542485)
			(xy 354.066396 -341.571092) (xy 354.013449 -341.592064) (xy 353.98583 -341.599012) (xy 353.9744 -341.601806)
			(xy 353.956112 -341.616792) (xy 353.912932 -341.712042) (xy 353.913694 -341.735664) (xy 353.919536 -341.746078)
			(xy 353.93354 -341.773417) (xy 353.953359 -341.831553) (xy 353.963382 -341.892151) (xy 353.963986 -341.922862)
			(xy 353.96353 -341.94948) (xy 353.955959 -342.002176) (xy 353.940964 -342.053257) (xy 353.918851 -342.101684)
			(xy 353.89007 -342.14647) (xy 353.855208 -342.186704) (xy 353.814975 -342.221567) (xy 353.770189 -342.250348)
			(xy 353.721762 -342.272461) (xy 353.670682 -342.287457) (xy 353.617986 -342.29503) (xy 353.591368 -342.29548)
			(xy 353.564946 -342.295022) (xy 353.512632 -342.287569) (xy 353.461894 -342.272803) (xy 353.41375 -342.25102)
			(xy 353.369164 -342.222656) (xy 353.348798 -342.205818) (xy 353.34194 -342.199722) (xy 353.324922 -342.193626)
			(xy 353.240594 -342.193626) (xy 353.223576 -342.199722) (xy 353.216718 -342.205818) (xy 353.196352 -342.222657)
			(xy 353.151766 -342.251022) (xy 353.103622 -342.272809) (xy 353.052885 -342.28758) (xy 353.00057 -342.29504)
			(xy 352.947726 -342.29504) (xy 352.895411 -342.28758) (xy 352.844674 -342.272809) (xy 352.79653 -342.251022)
			(xy 352.751944 -342.222657) (xy 352.731578 -342.205818) (xy 352.72472 -342.199722) (xy 352.707702 -342.193626)
			(xy 352.623374 -342.193626) (xy 352.606356 -342.199722) (xy 352.599498 -342.205818) (xy 352.579123 -342.222644)
			(xy 352.534537 -342.251004) (xy 352.486395 -342.272787) (xy 352.43566 -342.287557) (xy 352.383348 -342.295019)
			(xy 352.356928 -342.29548) (xy 352.329037 -342.295063) (xy 352.273878 -342.286753) (xy 352.220573 -342.270314)
			(xy 352.170314 -342.246114) (xy 352.124223 -342.214693) (xy 352.083331 -342.176753) (xy 352.04855 -342.133142)
			(xy 352.020658 -342.084835) (xy 352.000278 -342.032909) (xy 351.987864 -341.978526) (xy 351.983695 -341.9229)
			(xy 348.944146 -341.9229) (xy 348.174818 -342.692228) (xy 348.16801 -342.699574) (xy 348.160285 -342.718037)
			(xy 348.159832 -342.728042) (xy 348.159832 -342.821006) (xy 348.559372 -342.821006) (xy 348.563443 -342.765384)
			(xy 348.575569 -342.710947) (xy 348.595492 -342.658856) (xy 348.622788 -342.610221) (xy 348.656874 -342.566078)
			(xy 348.697023 -342.527369) (xy 348.742381 -342.494918) (xy 348.791981 -342.469417) (xy 348.844765 -342.45141)
			(xy 348.899608 -342.44128) (xy 348.955342 -342.439243) (xy 349.010779 -342.445343) (xy 349.064736 -342.459449)
			(xy 349.116065 -342.481261) (xy 349.163671 -342.510315) (xy 349.206539 -342.54599) (xy 349.243756 -342.587527)
			(xy 349.274529 -342.63404) (xy 349.298201 -342.684537) (xy 349.314269 -342.737944) (xy 349.322389 -342.79312)
			(xy 349.322898 -342.821006) (xy 349.322389 -342.848892) (xy 349.314269 -342.904068) (xy 349.298201 -342.957475)
			(xy 349.274529 -343.007972) (xy 349.243756 -343.054485) (xy 349.206539 -343.096022) (xy 349.163671 -343.131697)
			(xy 349.116065 -343.160751) (xy 349.064736 -343.182563) (xy 349.010779 -343.196669) (xy 348.955342 -343.202769)
			(xy 348.899608 -343.200732) (xy 348.844765 -343.190602) (xy 348.791981 -343.172595) (xy 348.742381 -343.147094)
			(xy 348.697023 -343.114643) (xy 348.656874 -343.075934) (xy 348.622788 -343.031791) (xy 348.595492 -342.983156)
			(xy 348.575569 -342.931065) (xy 348.563443 -342.876628) (xy 348.559372 -342.821006) (xy 348.159832 -342.821006)
			(xy 348.159832 -343.04351) (xy 348.160372 -343.053496) (xy 348.168091 -343.071922) (xy 348.174818 -343.079324)
			(xy 348.432628 -343.337134) (xy 348.444566 -343.343738) (xy 348.451424 -343.345516) (xy 348.47883 -343.352614)
			(xy 348.531327 -343.373804) (xy 348.580112 -343.402524) (xy 348.624113 -343.438145) (xy 348.662362 -343.479881)
			(xy 348.694018 -343.526815) (xy 348.718383 -343.577915) (xy 348.734923 -343.632057) (xy 348.743273 -343.68805)
			(xy 348.743778 -343.716356) (xy 348.743318 -343.74361) (xy 348.735566 -343.797564) (xy 348.720213 -343.849866)
			(xy 348.697573 -343.899449) (xy 348.668105 -343.945306) (xy 348.632411 -343.986501) (xy 348.591217 -344.022197)
			(xy 348.545362 -344.051666) (xy 348.495779 -344.074308) (xy 348.443478 -344.089663) (xy 348.389524 -344.097417)
			(xy 348.36227 -344.097864) (xy 348.333966 -344.097347) (xy 348.277981 -344.088977) (xy 348.223847 -344.072425)
			(xy 348.172754 -344.048055) (xy 348.125822 -344.016403) (xy 348.084084 -343.978162) (xy 348.048456 -343.934173)
			(xy 348.019719 -343.885402) (xy 347.998505 -343.832919) (xy 347.99143 -343.80551) (xy 347.989652 -343.798652)
			(xy 347.983048 -343.786714) (xy 347.617288 -343.420954) (xy 347.599989 -343.402935) (xy 347.57066 -343.362505)
			(xy 347.548013 -343.317987) (xy 347.532605 -343.270475) (xy 347.524817 -343.221138) (xy 347.524324 -343.196164)
			(xy 347.524324 -342.575388) (xy 347.524767 -342.550409) (xy 347.532544 -342.501062) (xy 347.547951 -342.45354)
			(xy 347.570608 -342.409017) (xy 347.599956 -342.368591) (xy 347.617288 -342.350598) (xy 347.86316 -342.104726)
			(xy 347.871515 -342.095456) (xy 347.878823 -342.071625) (xy 347.87713 -342.05926) (xy 347.859096 -341.964264)
			(xy 347.843348 -341.944706) (xy 347.831664 -341.939626) (xy 347.806391 -341.928166) (xy 347.759177 -341.899012)
			(xy 347.716685 -341.863324) (xy 347.679814 -341.821854) (xy 347.649341 -341.77548) (xy 347.625911 -341.725179)
			(xy 347.610017 -341.672013) (xy 347.601996 -341.617105) (xy 347.60154 -341.58936) (xy 347.602029 -341.56145)
			(xy 347.61017 -341.506227) (xy 347.626272 -341.45278) (xy 347.649991 -341.40225) (xy 347.680821 -341.355716)
			(xy 347.699076 -341.334598) (xy 347.705426 -341.327486) (xy 347.71203 -341.310214) (xy 347.71203 -341.223092)
			(xy 347.705426 -341.20582) (xy 347.699076 -341.198708) (xy 347.680799 -341.177608) (xy 347.649973 -341.131068)
			(xy 347.626258 -341.080534) (xy 347.610158 -341.027083) (xy 347.602018 -340.971857) (xy 347.60154 -340.943946)
			(xy 347.602026 -340.916695) (xy 347.609782 -340.862747) (xy 347.625137 -340.810452) (xy 347.647779 -340.760875)
			(xy 347.677245 -340.715025) (xy 347.712936 -340.673834) (xy 347.754127 -340.638143) (xy 347.799977 -340.608677)
			(xy 347.849554 -340.586035) (xy 347.901849 -340.57068) (xy 347.955797 -340.562924) (xy 348.010299 -340.562924)
			(xy 348.064247 -340.57068) (xy 348.116542 -340.586035) (xy 348.166119 -340.608677) (xy 348.211969 -340.638143)
			(xy 348.25316 -340.673834) (xy 348.288851 -340.715025) (xy 348.318317 -340.760875) (xy 348.340959 -340.810452)
			(xy 348.356314 -340.862747) (xy 348.36407 -340.916695) (xy 348.364556 -340.943946) (xy 348.364074 -340.971858)
			(xy 348.355945 -341.027088) (xy 348.339853 -341.080543) (xy 348.316143 -341.131082) (xy 348.285319 -341.177626)
			(xy 348.26702 -341.198708) (xy 348.26067 -341.20582) (xy 348.254066 -341.223092) (xy 348.254066 -341.310214)
			(xy 348.26067 -341.327486) (xy 348.26702 -341.334598) (xy 348.287208 -341.357941) (xy 348.320524 -341.409889)
			(xy 348.333314 -341.437976) (xy 348.338394 -341.44966) (xy 348.357952 -341.465408) (xy 348.452948 -341.483442)
			(xy 348.465315 -341.485192) (xy 348.489161 -341.477863) (xy 348.498414 -341.469472) (xy 348.820232 -341.147654)
			(xy 348.826921 -341.140246) (xy 348.834518 -341.12181) (xy 348.834964 -341.11184) (xy 348.834964 -341.001858)
			(xy 348.8309 -340.987888) (xy 348.826836 -340.981538) (xy 348.814473 -340.961977) (xy 348.794922 -340.920037)
			(xy 348.781655 -340.875707) (xy 348.774952 -340.829922) (xy 348.774512 -340.806786) (xy 348.774512 -328.773536)
			(xy 348.773981 -328.763545) (xy 348.766278 -328.745103) (xy 348.759526 -328.737722) (xy 348.359222 -328.337418)
			(xy 348.352386 -328.330016) (xy 348.344678 -328.311418) (xy 348.344236 -328.30135) (xy 348.344236 -326.689212)
			(xy 348.343813 -326.679142) (xy 348.336095 -326.660541) (xy 348.32925 -326.653144) (xy 345.510866 -323.83476)
			(xy 345.503468 -323.827912) (xy 345.48487 -323.820181) (xy 345.474798 -323.819774) (xy 341.158068 -323.819774)
			(xy 341.148063 -323.820267) (xy 341.129577 -323.827931) (xy 341.115428 -323.842082) (xy 341.107766 -323.860569)
			(xy 341.107268 -323.870574) (xy 341.107268 -336.415634) (xy 341.106807 -336.440624) (xy 341.098988 -336.489988)
			(xy 341.083534 -336.537517) (xy 341.060825 -336.58204) (xy 341.031423 -336.622456) (xy 341.01405 -336.640424)
			(xy 340.641674 -337.0128) (xy 343.707948 -337.0128) (xy 343.712115 -336.957185) (xy 343.724526 -336.902811)
			(xy 343.744901 -336.850895) (xy 343.772787 -336.802596) (xy 343.80756 -336.758992) (xy 343.848443 -336.721058)
			(xy 343.894524 -336.68964) (xy 343.944772 -336.665442) (xy 343.998066 -336.649003) (xy 344.053214 -336.640691)
			(xy 344.0811 -336.64017) (xy 344.107521 -336.640635) (xy 344.159836 -336.648084) (xy 344.210575 -336.662848)
			(xy 344.258719 -336.68463) (xy 344.303304 -336.712993) (xy 344.32367 -336.729832) (xy 344.330528 -336.735928)
			(xy 344.347546 -336.742024) (xy 344.431874 -336.742024) (xy 344.448892 -336.735928) (xy 344.45575 -336.729832)
			(xy 344.476116 -336.712993) (xy 344.520702 -336.684628) (xy 344.568846 -336.662841) (xy 344.619583 -336.64807)
			(xy 344.671898 -336.64061) (xy 344.724742 -336.64061) (xy 344.777057 -336.64807) (xy 344.827794 -336.662841)
			(xy 344.875938 -336.684628) (xy 344.920524 -336.712993) (xy 344.94089 -336.729832) (xy 344.947748 -336.735928)
			(xy 344.964766 -336.742024) (xy 345.049094 -336.742024) (xy 345.066112 -336.735928) (xy 345.07297 -336.729832)
			(xy 345.09535 -336.711413) (xy 345.144682 -336.680989) (xy 345.198128 -336.658566) (xy 345.226132 -336.651092)
			(xy 345.237816 -336.648298) (xy 345.25585 -336.632804) (xy 345.297506 -336.537046) (xy 345.29649 -336.513424)
			(xy 345.290648 -336.50301) (xy 345.279175 -336.481643) (xy 345.261122 -336.43663) (xy 345.248921 -336.389692)
			(xy 345.242769 -336.341585) (xy 345.242388 -336.317336) (xy 345.242883 -336.289763) (xy 345.25083 -336.235191)
			(xy 345.266549 -336.182332) (xy 345.289714 -336.132286) (xy 345.319841 -336.086096) (xy 345.356303 -336.044723)
			(xy 345.377008 -336.026506) (xy 345.385121 -336.018898) (xy 345.394478 -335.998751) (xy 345.395042 -335.987644)
			(xy 345.395042 -335.910428) (xy 345.394493 -335.899315) (xy 345.385143 -335.879156) (xy 345.377008 -335.871566)
			(xy 345.356279 -335.853374) (xy 345.31981 -335.812002) (xy 345.289679 -335.765808) (xy 345.266517 -335.715756)
			(xy 345.250804 -335.66289) (xy 345.24287 -335.608312) (xy 345.242388 -335.580736) (xy 345.242874 -335.553485)
			(xy 345.25063 -335.499537) (xy 345.265985 -335.447242) (xy 345.288627 -335.397665) (xy 345.318093 -335.351815)
			(xy 345.353784 -335.310624) (xy 345.394975 -335.274933) (xy 345.440825 -335.245467) (xy 345.490402 -335.222825)
			(xy 345.542697 -335.20747) (xy 345.596645 -335.199714) (xy 345.651147 -335.199714) (xy 345.705095 -335.20747)
			(xy 345.75739 -335.222825) (xy 345.806967 -335.245467) (xy 345.852817 -335.274933) (xy 345.894008 -335.310624)
			(xy 345.929699 -335.351815) (xy 345.959165 -335.397665) (xy 345.981807 -335.447242) (xy 345.997162 -335.499537)
			(xy 346.004918 -335.553485) (xy 346.005404 -335.580736) (xy 346.004893 -335.608309) (xy 345.996949 -335.66288)
			(xy 345.981233 -335.715739) (xy 345.958072 -335.765785) (xy 345.927947 -335.811976) (xy 345.891488 -335.853349)
			(xy 345.870784 -335.871566) (xy 345.862683 -335.879184) (xy 345.85332 -335.899324) (xy 345.85275 -335.910428)
			(xy 345.85275 -335.987644) (xy 345.853317 -335.998754) (xy 345.862655 -336.018914) (xy 345.870784 -336.026506)
			(xy 345.891498 -336.044714) (xy 345.927969 -336.086083) (xy 345.958101 -336.132273) (xy 345.981266 -336.182322)
			(xy 345.996982 -336.235185) (xy 346.00492 -336.289761) (xy 346.005404 -336.317336) (xy 346.004864 -336.345812)
			(xy 345.99638 -336.402129) (xy 345.979619 -336.45656) (xy 345.954956 -336.507895) (xy 345.922936 -336.554994)
			(xy 345.884272 -336.596812) (xy 345.839823 -336.632418) (xy 345.790575 -336.661023) (xy 345.737623 -336.681992)
			(xy 345.710002 -336.688938) (xy 345.698572 -336.691732) (xy 345.680284 -336.706718) (xy 345.637104 -336.801968)
			(xy 345.637866 -336.82559) (xy 345.643708 -336.836004) (xy 345.657683 -336.863356) (xy 345.677513 -336.921486)
			(xy 345.687548 -336.982079) (xy 345.688158 -337.012788) (xy 345.687632 -337.039402) (xy 345.680059 -337.092089)
			(xy 345.665066 -337.143162) (xy 345.642956 -337.191581) (xy 345.614182 -337.236361) (xy 345.579327 -337.27659)
			(xy 345.539103 -337.31145) (xy 345.494326 -337.340231) (xy 345.44591 -337.362347) (xy 345.39484 -337.377348)
			(xy 345.342154 -337.384929) (xy 345.31554 -337.385406) (xy 345.289117 -337.384982) (xy 345.2368 -337.377523)
			(xy 345.186061 -337.362751) (xy 345.137918 -337.340959) (xy 345.093334 -337.312587) (xy 345.07297 -337.295744)
			(xy 345.066112 -337.289648) (xy 345.049094 -337.283552) (xy 344.964766 -337.283552) (xy 344.947748 -337.289648)
			(xy 344.94089 -337.295744) (xy 344.920524 -337.312583) (xy 344.875938 -337.340948) (xy 344.827794 -337.362735)
			(xy 344.777057 -337.377506) (xy 344.724742 -337.384966) (xy 344.671898 -337.384966) (xy 344.619583 -337.377506)
			(xy 344.568846 -337.362735) (xy 344.520702 -337.340948) (xy 344.476116 -337.312583) (xy 344.45575 -337.295744)
			(xy 344.448892 -337.289648) (xy 344.431874 -337.283552) (xy 344.347546 -337.283552) (xy 344.330528 -337.289648)
			(xy 344.32367 -337.295744) (xy 344.303309 -337.312587) (xy 344.258718 -337.340944) (xy 344.210573 -337.362723)
			(xy 344.159835 -337.377489) (xy 344.107521 -337.384947) (xy 344.0811 -337.385406) (xy 344.053214 -337.384909)
			(xy 343.998066 -337.376597) (xy 343.944772 -337.360158) (xy 343.894524 -337.33596) (xy 343.848443 -337.304542)
			(xy 343.80756 -337.266608) (xy 343.772787 -337.223004) (xy 343.744901 -337.174705) (xy 343.724526 -337.122789)
			(xy 343.712115 -337.068415) (xy 343.707948 -337.0128) (xy 340.641674 -337.0128) (xy 340.206584 -337.44789)
			(xy 340.1999 -337.4553) (xy 340.192317 -337.473736) (xy 340.191852 -337.483704) (xy 340.191852 -337.603084)
			(xy 340.192347 -337.613488) (xy 340.200603 -337.632587) (xy 340.215763 -337.646838) (xy 340.22538 -337.650836)
			(xy 340.330536 -337.688682) (xy 340.36127 -337.6803) (xy 340.371684 -337.667854) (xy 340.389885 -337.646599)
			(xy 340.43145 -337.609133) (xy 340.478044 -337.578142) (xy 340.528665 -337.554293) (xy 340.582228 -337.538096)
			(xy 340.637583 -337.529899) (xy 340.665562 -337.529424) (xy 340.692814 -337.529885) (xy 340.746765 -337.537637)
			(xy 340.799063 -337.552988) (xy 340.848644 -337.575626) (xy 340.894498 -337.605091) (xy 340.935691 -337.640782)
			(xy 340.971386 -337.681972) (xy 341.000855 -337.727823) (xy 341.023499 -337.777401) (xy 341.038855 -337.829698)
			(xy 341.046613 -337.883648) (xy 341.046613 -337.938152) (xy 341.038855 -337.992102) (xy 341.023499 -338.044399)
			(xy 341.000855 -338.093977) (xy 340.971386 -338.139828) (xy 340.935691 -338.181018) (xy 340.894498 -338.216709)
			(xy 340.848644 -338.246174) (xy 340.799063 -338.268812) (xy 340.746765 -338.284163) (xy 340.692814 -338.291915)
			(xy 340.665562 -338.29244) (xy 340.637582 -338.291951) (xy 340.582222 -338.283775) (xy 340.528653 -338.26759)
			(xy 340.478028 -338.243745) (xy 340.431435 -338.21275) (xy 340.389876 -338.175275) (xy 340.371684 -338.15401)
			(xy 340.36127 -338.141564) (xy 340.330536 -338.133182) (xy 340.22538 -338.171028) (xy 340.215774 -338.175038)
			(xy 340.200634 -338.189294) (xy 340.192385 -338.208383) (xy 340.191852 -338.21878) (xy 340.191852 -338.418932)
			(xy 340.209378 -338.44484) (xy 340.22411 -338.450428) (xy 340.250664 -338.461252) (xy 340.300446 -338.48971)
			(xy 340.345407 -338.525298) (xy 340.384536 -338.567215) (xy 340.416949 -338.614517) (xy 340.441917 -338.666137)
			(xy 340.458878 -338.720913) (xy 340.467448 -338.777611) (xy 340.46795 -338.806282) (xy 340.467465 -338.833535)
			(xy 340.459711 -338.887487) (xy 340.444358 -338.939786) (xy 340.421719 -338.989369) (xy 340.392253 -339.035224)
			(xy 340.356563 -339.07642) (xy 340.315372 -339.112117) (xy 340.269521 -339.14159) (xy 340.219943 -339.164237)
			(xy 340.167646 -339.179599) (xy 340.113695 -339.187361) (xy 340.086442 -339.18779) (xy 340.058139 -339.187271)
			(xy 340.002155 -339.178898) (xy 339.948024 -339.162344) (xy 339.896932 -339.137973) (xy 339.850003 -339.10632)
			(xy 339.808266 -339.06808) (xy 339.772638 -339.024092) (xy 339.743901 -338.975323) (xy 339.722686 -338.922843)
			(xy 339.715602 -338.895436) (xy 339.713824 -338.888578) (xy 339.70722 -338.87664) (xy 339.649054 -338.818474)
			(xy 339.63171 -338.800483) (xy 339.602326 -338.760063) (xy 339.579627 -338.715545) (xy 339.564172 -338.668024)
			(xy 339.556342 -338.61867) (xy 339.555836 -338.593684) (xy 339.555836 -337.33105) (xy 339.556419 -337.303179)
			(xy 339.566143 -337.248292) (xy 339.585283 -337.19594) (xy 339.598762 -337.171538) (xy 339.60435 -337.16214)
			(xy 339.606636 -337.141058) (xy 339.57641 -337.048094) (xy 339.562186 -337.032346) (xy 339.55228 -337.027774)
			(xy 339.527346 -337.016184) (xy 339.480814 -336.986897) (xy 339.438971 -336.951228) (xy 339.402687 -336.909918)
			(xy 339.372713 -336.863825) (xy 339.349671 -336.813903) (xy 339.33404 -336.76119) (xy 339.326143 -336.706777)
			(xy 339.325712 -336.679286) (xy 339.326199 -336.651375) (xy 339.334336 -336.59615) (xy 339.350434 -336.5427)
			(xy 339.37415 -336.492166) (xy 339.404976 -336.445629) (xy 339.423248 -336.424524) (xy 339.429598 -336.417412)
			(xy 339.436202 -336.40014) (xy 339.436202 -336.313018) (xy 339.429598 -336.295746) (xy 339.423248 -336.288634)
			(xy 339.404971 -336.267534) (xy 339.374144 -336.220994) (xy 339.350427 -336.17046) (xy 339.334325 -336.117009)
			(xy 339.326181 -336.061783) (xy 339.325712 -336.033872) (xy 339.326198 -336.006621) (xy 339.333954 -335.952673)
			(xy 339.349309 -335.900378) (xy 339.371951 -335.850801) (xy 339.401417 -335.804951) (xy 339.437108 -335.76376)
			(xy 339.478299 -335.728069) (xy 339.524149 -335.698603) (xy 339.573726 -335.675961) (xy 339.626021 -335.660606)
			(xy 339.679969 -335.65285) (xy 339.734471 -335.65285) (xy 339.788419 -335.660606) (xy 339.840714 -335.675961)
			(xy 339.890291 -335.698603) (xy 339.936141 -335.728069) (xy 339.977332 -335.76376) (xy 340.013023 -335.804951)
			(xy 340.042489 -335.850801) (xy 340.065131 -335.900378) (xy 340.080486 -335.952673) (xy 340.088242 -336.006621)
			(xy 340.088728 -336.033872) (xy 340.088244 -336.061784) (xy 340.080111 -336.117011) (xy 340.064016 -336.170463)
			(xy 340.040301 -336.220999) (xy 340.009474 -336.267538) (xy 339.991192 -336.288634) (xy 339.984842 -336.295746)
			(xy 339.978238 -336.313018) (xy 339.978238 -336.40014) (xy 339.984842 -336.417412) (xy 339.991192 -336.424524)
			(xy 340.008814 -336.444815) (xy 340.038773 -336.489432) (xy 340.050882 -336.513424) (xy 340.056216 -336.524854)
			(xy 340.075774 -336.539332) (xy 340.169754 -336.555334) (xy 340.181883 -336.556647) (xy 340.205085 -336.549216)
			(xy 340.214204 -336.54111) (xy 340.45652 -336.298794) (xy 340.463201 -336.291383) (xy 340.470778 -336.272947)
			(xy 340.471252 -336.26298) (xy 340.471252 -323.870574) (xy 340.470827 -323.86056) (xy 340.463151 -323.84206)
			(xy 340.448978 -323.827908) (xy 340.430467 -323.820258) (xy 340.420452 -323.819774) (xy 332.877668 -323.819774)
			(xy 332.867663 -323.820267) (xy 332.849177 -323.827931) (xy 332.835028 -323.842082) (xy 332.827366 -323.860569)
			(xy 332.826868 -323.870574) (xy 332.826868 -336.474562) (xy 332.826404 -336.499551) (xy 332.818582 -336.548913)
			(xy 332.803125 -336.59644) (xy 332.780413 -336.640959) (xy 332.751009 -336.681371) (xy 332.73365 -336.699352)
			(xy 332.471002 -336.962) (xy 335.376748 -336.962) (xy 335.380915 -336.906385) (xy 335.393326 -336.852011)
			(xy 335.413701 -336.800095) (xy 335.441587 -336.751796) (xy 335.47636 -336.708192) (xy 335.517243 -336.670258)
			(xy 335.563324 -336.63884) (xy 335.613572 -336.614642) (xy 335.666866 -336.598203) (xy 335.722014 -336.589891)
			(xy 335.7499 -336.58937) (xy 335.776321 -336.589835) (xy 335.828636 -336.597284) (xy 335.879375 -336.612048)
			(xy 335.927519 -336.63383) (xy 335.972104 -336.662193) (xy 335.99247 -336.679032) (xy 335.999328 -336.685128)
			(xy 336.016346 -336.691224) (xy 336.100674 -336.691224) (xy 336.117692 -336.685128) (xy 336.12455 -336.679032)
			(xy 336.144916 -336.662193) (xy 336.189502 -336.633828) (xy 336.237646 -336.612041) (xy 336.288383 -336.59727)
			(xy 336.340698 -336.58981) (xy 336.393542 -336.58981) (xy 336.445857 -336.59727) (xy 336.496594 -336.612041)
			(xy 336.544738 -336.633828) (xy 336.589324 -336.662193) (xy 336.60969 -336.679032) (xy 336.616548 -336.685128)
			(xy 336.633566 -336.691224) (xy 336.717894 -336.691224) (xy 336.734912 -336.685128) (xy 336.74177 -336.679032)
			(xy 336.763705 -336.660961) (xy 336.811982 -336.630975) (xy 336.864242 -336.608646) (xy 336.89163 -336.601054)
			(xy 336.903314 -336.598006) (xy 336.921602 -336.582258) (xy 336.96148 -336.484722) (xy 336.959702 -336.460592)
			(xy 336.953606 -336.450432) (xy 336.940633 -336.428091) (xy 336.920214 -336.380636) (xy 336.906392 -336.330857)
			(xy 336.899422 -336.279667) (xy 336.898996 -336.253836) (xy 336.899488 -336.226262) (xy 336.907435 -336.171691)
			(xy 336.923155 -336.118831) (xy 336.94632 -336.068785) (xy 336.976448 -336.022595) (xy 337.012911 -335.981223)
			(xy 337.033616 -335.963006) (xy 337.04173 -335.955399) (xy 337.051086 -335.935251) (xy 337.05165 -335.924144)
			(xy 337.05165 -335.846928) (xy 337.051098 -335.835816) (xy 337.04175 -335.815656) (xy 337.033616 -335.808066)
			(xy 337.012888 -335.789873) (xy 336.976419 -335.748501) (xy 336.946288 -335.702307) (xy 336.923125 -335.652255)
			(xy 336.907413 -335.59939) (xy 336.899478 -335.544812) (xy 336.898996 -335.517236) (xy 336.899482 -335.489985)
			(xy 336.907238 -335.436037) (xy 336.922593 -335.383742) (xy 336.945235 -335.334165) (xy 336.974701 -335.288315)
			(xy 337.010392 -335.247124) (xy 337.051583 -335.211433) (xy 337.097433 -335.181967) (xy 337.14701 -335.159325)
			(xy 337.199305 -335.14397) (xy 337.253253 -335.136214) (xy 337.307755 -335.136214) (xy 337.361703 -335.14397)
			(xy 337.413998 -335.159325) (xy 337.463575 -335.181967) (xy 337.509425 -335.211433) (xy 337.550616 -335.247124)
			(xy 337.586307 -335.288315) (xy 337.615773 -335.334165) (xy 337.638415 -335.383742) (xy 337.65377 -335.436037)
			(xy 337.661526 -335.489985) (xy 337.662012 -335.517236) (xy 337.661498 -335.544809) (xy 337.653555 -335.599379)
			(xy 337.637839 -335.652238) (xy 337.614678 -335.702284) (xy 337.584554 -335.748475) (xy 337.548095 -335.789849)
			(xy 337.527392 -335.808066) (xy 337.519292 -335.815685) (xy 337.509928 -335.835824) (xy 337.509358 -335.846928)
			(xy 337.509358 -335.924144) (xy 337.509923 -335.935255) (xy 337.519261 -335.955415) (xy 337.527392 -335.963006)
			(xy 337.548108 -335.981212) (xy 337.584578 -336.022582) (xy 337.61471 -336.068773) (xy 337.637875 -336.118822)
			(xy 337.65359 -336.171685) (xy 337.661528 -336.226261) (xy 337.662012 -336.253836) (xy 337.661456 -336.282114)
			(xy 337.653115 -336.338051) (xy 337.636607 -336.392144) (xy 337.612293 -336.443206) (xy 337.580706 -336.490119)
			(xy 337.542539 -336.531855) (xy 337.498629 -336.567497) (xy 337.449937 -336.596266) (xy 337.397531 -336.61753)
			(xy 337.370166 -336.624676) (xy 337.358482 -336.62747) (xy 337.340194 -336.642964) (xy 337.298792 -336.739992)
			(xy 337.300316 -336.764122) (xy 337.306412 -336.774536) (xy 337.318417 -336.795967) (xy 337.337324 -336.841304)
			(xy 337.350114 -336.888731) (xy 337.356566 -336.937427) (xy 337.356958 -336.961988) (xy 337.356432 -336.988602)
			(xy 337.348859 -337.041289) (xy 337.333866 -337.092362) (xy 337.311756 -337.140781) (xy 337.282982 -337.185561)
			(xy 337.248127 -337.22579) (xy 337.207903 -337.26065) (xy 337.163126 -337.289431) (xy 337.11471 -337.311547)
			(xy 337.06364 -337.326548) (xy 337.010954 -337.334129) (xy 336.98434 -337.334606) (xy 336.957917 -337.334182)
			(xy 336.9056 -337.326723) (xy 336.854861 -337.311951) (xy 336.806718 -337.290159) (xy 336.762134 -337.261787)
			(xy 336.74177 -337.244944) (xy 336.734912 -337.238848) (xy 336.717894 -337.232752) (xy 336.633566 -337.232752)
			(xy 336.616548 -337.238848) (xy 336.60969 -337.244944) (xy 336.589324 -337.261783) (xy 336.544738 -337.290148)
			(xy 336.496594 -337.311935) (xy 336.445857 -337.326706) (xy 336.393542 -337.334166) (xy 336.340698 -337.334166)
			(xy 336.288383 -337.326706) (xy 336.237646 -337.311935) (xy 336.189502 -337.290148) (xy 336.144916 -337.261783)
			(xy 336.12455 -337.244944) (xy 336.117692 -337.238848) (xy 336.100674 -337.232752) (xy 336.016346 -337.232752)
			(xy 335.999328 -337.238848) (xy 335.99247 -337.244944) (xy 335.972109 -337.261787) (xy 335.927518 -337.290144)
			(xy 335.879373 -337.311923) (xy 335.828635 -337.326689) (xy 335.776321 -337.334147) (xy 335.7499 -337.334606)
			(xy 335.722014 -337.334109) (xy 335.666866 -337.325797) (xy 335.613572 -337.309358) (xy 335.563324 -337.28516)
			(xy 335.517243 -337.253742) (xy 335.47636 -337.215808) (xy 335.441587 -337.172204) (xy 335.413701 -337.123905)
			(xy 335.393326 -337.071989) (xy 335.380915 -337.017615) (xy 335.376748 -336.962) (xy 332.471002 -336.962)
			(xy 331.84719 -337.585812) (xy 331.840382 -337.593158) (xy 331.832656 -337.611621) (xy 331.832204 -337.621626)
			(xy 331.832204 -337.860132) (xy 331.952344 -337.860132) (xy 331.956415 -337.80451) (xy 331.968541 -337.750073)
			(xy 331.988464 -337.697982) (xy 332.01576 -337.649347) (xy 332.049846 -337.605204) (xy 332.089995 -337.566495)
			(xy 332.135353 -337.534044) (xy 332.184953 -337.508543) (xy 332.237737 -337.490536) (xy 332.29258 -337.480406)
			(xy 332.348314 -337.478369) (xy 332.403751 -337.484469) (xy 332.457708 -337.498575) (xy 332.509037 -337.520387)
			(xy 332.556643 -337.549441) (xy 332.599511 -337.585116) (xy 332.636728 -337.626653) (xy 332.667501 -337.673166)
			(xy 332.691173 -337.723663) (xy 332.707241 -337.77707) (xy 332.715361 -337.832246) (xy 332.71587 -337.860132)
			(xy 332.715361 -337.888018) (xy 332.707241 -337.943194) (xy 332.691173 -337.996601) (xy 332.667501 -338.047098)
			(xy 332.636728 -338.093611) (xy 332.599511 -338.135148) (xy 332.556643 -338.170823) (xy 332.509037 -338.199877)
			(xy 332.457708 -338.221689) (xy 332.403751 -338.235795) (xy 332.348314 -338.241895) (xy 332.29258 -338.239858)
			(xy 332.237737 -338.229728) (xy 332.184953 -338.211721) (xy 332.135353 -338.18622) (xy 332.089995 -338.153769)
			(xy 332.049846 -338.11506) (xy 332.01576 -338.070917) (xy 331.988464 -338.022282) (xy 331.968541 -337.970191)
			(xy 331.956415 -337.915754) (xy 331.952344 -337.860132) (xy 331.832204 -337.860132) (xy 331.832204 -338.359496)
			(xy 331.852016 -338.386166) (xy 331.868018 -338.390992) (xy 331.893624 -338.399399) (xy 331.942356 -338.422413)
			(xy 331.987364 -338.452058) (xy 332.027751 -338.487742) (xy 332.062713 -338.528756) (xy 332.091554 -338.574283)
			(xy 332.1137 -338.623416) (xy 332.128709 -338.675177) (xy 332.136284 -338.728535) (xy 332.13675 -338.755482)
			(xy 332.136265 -338.782735) (xy 332.128511 -338.836687) (xy 332.113158 -338.888986) (xy 332.090519 -338.938569)
			(xy 332.061053 -338.984424) (xy 332.025363 -339.02562) (xy 331.984172 -339.061317) (xy 331.938321 -339.09079)
			(xy 331.888743 -339.113437) (xy 331.836446 -339.128799) (xy 331.782495 -339.136561) (xy 331.755242 -339.13699)
			(xy 331.726939 -339.136471) (xy 331.670955 -339.128098) (xy 331.616824 -339.111544) (xy 331.565732 -339.087173)
			(xy 331.518803 -339.05552) (xy 331.477066 -339.01728) (xy 331.441438 -338.973292) (xy 331.412701 -338.924523)
			(xy 331.391486 -338.872043) (xy 331.384402 -338.844636) (xy 331.382624 -338.837778) (xy 331.37602 -338.82584)
			(xy 331.28966 -338.73948) (xy 331.272356 -338.721463) (xy 331.243017 -338.681036) (xy 331.220361 -338.636518)
			(xy 331.204946 -338.589005) (xy 331.197151 -338.539666) (xy 331.196696 -338.51469) (xy 331.196696 -337.468972)
			(xy 331.19714 -337.443994) (xy 331.204921 -337.39465) (xy 331.220332 -337.347132) (xy 331.242994 -337.302614)
			(xy 331.272348 -337.262194) (xy 331.28966 -337.244182) (xy 331.358748 -337.175094) (xy 331.365001 -337.168334)
			(xy 331.372607 -337.151579) (xy 331.373747 -337.133214) (xy 331.371448 -337.124294) (xy 331.34046 -337.024726)
			(xy 331.319886 -337.006184) (xy 331.305662 -337.00339) (xy 331.279768 -336.998069) (xy 331.229659 -336.981231)
			(xy 331.182353 -336.957637) (xy 331.138758 -336.927739) (xy 331.099708 -336.892108) (xy 331.06595 -336.851428)
			(xy 331.038131 -336.806477) (xy 331.016783 -336.758117) (xy 331.002317 -336.707272) (xy 330.995007 -336.654917)
			(xy 330.994512 -336.628486) (xy 330.994999 -336.600575) (xy 331.003136 -336.54535) (xy 331.019234 -336.4919)
			(xy 331.04295 -336.441366) (xy 331.073776 -336.394829) (xy 331.092048 -336.373724) (xy 331.098398 -336.366612)
			(xy 331.105002 -336.34934) (xy 331.105002 -336.262218) (xy 331.098398 -336.244946) (xy 331.092048 -336.237834)
			(xy 331.073771 -336.216734) (xy 331.042944 -336.170194) (xy 331.019227 -336.11966) (xy 331.003125 -336.066209)
			(xy 330.994981 -336.010983) (xy 330.994512 -335.983072) (xy 330.994998 -335.955821) (xy 331.002754 -335.901873)
			(xy 331.018109 -335.849578) (xy 331.040751 -335.800001) (xy 331.070217 -335.754151) (xy 331.105908 -335.71296)
			(xy 331.147099 -335.677269) (xy 331.192949 -335.647803) (xy 331.242526 -335.625161) (xy 331.294821 -335.609806)
			(xy 331.348769 -335.60205) (xy 331.403271 -335.60205) (xy 331.457219 -335.609806) (xy 331.509514 -335.625161)
			(xy 331.559091 -335.647803) (xy 331.604941 -335.677269) (xy 331.646132 -335.71296) (xy 331.681823 -335.754151)
			(xy 331.711289 -335.800001) (xy 331.733931 -335.849578) (xy 331.749286 -335.901873) (xy 331.757042 -335.955821)
			(xy 331.757528 -335.983072) (xy 331.757044 -336.010984) (xy 331.748911 -336.066211) (xy 331.732816 -336.119663)
			(xy 331.709101 -336.170199) (xy 331.678274 -336.216738) (xy 331.659992 -336.237834) (xy 331.653642 -336.244946)
			(xy 331.647038 -336.262218) (xy 331.647038 -336.34934) (xy 331.653642 -336.366612) (xy 331.659992 -336.373724)
			(xy 331.677067 -336.393383) (xy 331.706245 -336.43651) (xy 331.729275 -336.48321) (xy 331.745727 -336.532613)
			(xy 331.750924 -336.558128) (xy 331.753718 -336.572352) (xy 331.77226 -336.592926) (xy 331.871828 -336.623914)
			(xy 331.880742 -336.626202) (xy 331.899092 -336.625001) (xy 331.915858 -336.617446) (xy 331.922628 -336.611214)
			(xy 332.17612 -336.357722) (xy 332.182805 -336.350312) (xy 332.190392 -336.331877) (xy 332.190852 -336.321908)
			(xy 332.190852 -323.870574) (xy 332.190427 -323.86056) (xy 332.182751 -323.84206) (xy 332.168578 -323.827908)
			(xy 332.150067 -323.820258) (xy 332.140052 -323.819774) (xy 324.521068 -323.819774) (xy 324.511063 -323.820267)
			(xy 324.492577 -323.827931) (xy 324.478428 -323.842082) (xy 324.470766 -323.860569) (xy 324.470268 -323.870574)
			(xy 324.470268 -336.3341) (xy 324.469802 -336.359088) (xy 324.461974 -336.408446) (xy 324.446512 -336.45597)
			(xy 324.423798 -336.500485) (xy 324.394391 -336.540893) (xy 324.37705 -336.55889) (xy 323.95944 -336.9765)
			(xy 327.019125 -336.9765) (xy 327.023293 -336.920883) (xy 327.035704 -336.866508) (xy 327.056079 -336.81459)
			(xy 327.083965 -336.766288) (xy 327.118739 -336.722682) (xy 327.159622 -336.684746) (xy 327.205703 -336.653327)
			(xy 327.255953 -336.629126) (xy 327.309247 -336.612685) (xy 327.364397 -336.60437) (xy 327.392284 -336.603848)
			(xy 327.418705 -336.604327) (xy 327.471019 -336.611774) (xy 327.521757 -336.626535) (xy 327.569901 -336.648313)
			(xy 327.614488 -336.676673) (xy 327.634854 -336.69351) (xy 327.641712 -336.699606) (xy 327.65873 -336.705702)
			(xy 327.743058 -336.705702) (xy 327.760076 -336.699606) (xy 327.766934 -336.69351) (xy 327.7873 -336.676671)
			(xy 327.831886 -336.648306) (xy 327.88003 -336.626519) (xy 327.930767 -336.611748) (xy 327.983082 -336.604288)
			(xy 328.035926 -336.604288) (xy 328.088241 -336.611748) (xy 328.138978 -336.626519) (xy 328.187122 -336.648306)
			(xy 328.231708 -336.676671) (xy 328.252074 -336.69351) (xy 328.258932 -336.699606) (xy 328.27595 -336.705702)
			(xy 328.360278 -336.705702) (xy 328.377296 -336.699606) (xy 328.384154 -336.69351) (xy 328.406536 -336.675093)
			(xy 328.455867 -336.644668) (xy 328.509312 -336.622245) (xy 328.537316 -336.61477) (xy 328.549508 -336.611722)
			(xy 328.567796 -336.59572) (xy 328.607674 -336.495644) (xy 328.605134 -336.47126) (xy 328.59853 -336.460846)
			(xy 328.584049 -336.437615) (xy 328.561184 -336.387877) (xy 328.545663 -336.335382) (xy 328.537805 -336.281207)
			(xy 328.537316 -336.253836) (xy 328.537801 -336.226262) (xy 328.545749 -336.17169) (xy 328.56147 -336.11883)
			(xy 328.584636 -336.068784) (xy 328.614765 -336.022594) (xy 328.65123 -335.981222) (xy 328.671936 -335.963006)
			(xy 328.680053 -335.955402) (xy 328.689407 -335.935252) (xy 328.68997 -335.924144) (xy 328.68997 -335.846928)
			(xy 328.689412 -335.835817) (xy 328.680067 -335.815657) (xy 328.671936 -335.808066) (xy 328.651212 -335.789868)
			(xy 328.614742 -335.748498) (xy 328.58461 -335.702305) (xy 328.561446 -335.652254) (xy 328.545733 -335.599389)
			(xy 328.537798 -335.544812) (xy 328.537316 -335.517236) (xy 328.537802 -335.489985) (xy 328.545558 -335.436037)
			(xy 328.560913 -335.383742) (xy 328.583555 -335.334165) (xy 328.613021 -335.288315) (xy 328.648712 -335.247124)
			(xy 328.689903 -335.211433) (xy 328.735753 -335.181967) (xy 328.78533 -335.159325) (xy 328.837625 -335.14397)
			(xy 328.891573 -335.136214) (xy 328.946075 -335.136214) (xy 329.000023 -335.14397) (xy 329.052318 -335.159325)
			(xy 329.101895 -335.181967) (xy 329.147745 -335.211433) (xy 329.188936 -335.247124) (xy 329.224627 -335.288315)
			(xy 329.254093 -335.334165) (xy 329.276735 -335.383742) (xy 329.29209 -335.436037) (xy 329.299846 -335.489985)
			(xy 329.300332 -335.517236) (xy 329.299811 -335.544808) (xy 329.291868 -335.599378) (xy 329.276153 -335.652237)
			(xy 329.252994 -335.702283) (xy 329.222871 -335.748474) (xy 329.186414 -335.789848) (xy 329.165712 -335.808066)
			(xy 329.157615 -335.815688) (xy 329.148248 -335.835825) (xy 329.147678 -335.846928) (xy 329.147678 -335.924144)
			(xy 329.148236 -335.935256) (xy 329.157579 -335.955416) (xy 329.165712 -335.963006) (xy 329.186432 -335.981208)
			(xy 329.222901 -336.022579) (xy 329.253032 -336.068771) (xy 329.276196 -336.118821) (xy 329.29191 -336.171685)
			(xy 329.299848 -336.226261) (xy 329.300332 -336.253836) (xy 329.299861 -336.282294) (xy 329.291415 -336.338579)
			(xy 329.274699 -336.392985) (xy 329.250086 -336.444304) (xy 329.218122 -336.491396) (xy 329.179515 -336.533216)
			(xy 329.135124 -336.568837) (xy 329.085933 -336.597466) (xy 329.033035 -336.61847) (xy 329.005438 -336.625438)
			(xy 328.993246 -336.628232) (xy 328.974704 -336.64398) (xy 328.933556 -336.743548) (xy 328.935588 -336.767932)
			(xy 328.942192 -336.778346) (xy 328.955716 -336.800704) (xy 328.977062 -336.848398) (xy 328.991544 -336.898604)
			(xy 328.998881 -336.95034) (xy 328.999342 -336.976466) (xy 328.998834 -337.003082) (xy 328.991263 -337.055772)
			(xy 328.976271 -337.106849) (xy 328.954161 -337.155272) (xy 328.925386 -337.200056) (xy 328.89053 -337.240289)
			(xy 328.850303 -337.275151) (xy 328.805523 -337.303934) (xy 328.757104 -337.32605) (xy 328.706029 -337.341051)
			(xy 328.65334 -337.34863) (xy 328.626724 -337.349084) (xy 328.600304 -337.348593) (xy 328.54799 -337.341148)
			(xy 328.497253 -337.326389) (xy 328.449108 -337.304614) (xy 328.404521 -337.276257) (xy 328.384154 -337.259422)
			(xy 328.377296 -337.253326) (xy 328.360278 -337.24723) (xy 328.27595 -337.24723) (xy 328.258932 -337.253326)
			(xy 328.252074 -337.259422) (xy 328.231708 -337.276261) (xy 328.187122 -337.304626) (xy 328.138978 -337.326413)
			(xy 328.088241 -337.341184) (xy 328.035926 -337.348644) (xy 327.983082 -337.348644) (xy 327.930767 -337.341184)
			(xy 327.88003 -337.326413) (xy 327.831886 -337.304626) (xy 327.7873 -337.276261) (xy 327.766934 -337.259422)
			(xy 327.760076 -337.253326) (xy 327.743058 -337.24723) (xy 327.65873 -337.24723) (xy 327.641712 -337.253326)
			(xy 327.634854 -337.259422) (xy 327.614496 -337.27627) (xy 327.569905 -337.304626) (xy 327.521759 -337.326404)
			(xy 327.47102 -337.34117) (xy 327.418706 -337.348626) (xy 327.392284 -337.349084) (xy 327.364397 -337.34863)
			(xy 327.309247 -337.340315) (xy 327.255953 -337.323874) (xy 327.205703 -337.299673) (xy 327.159622 -337.268254)
			(xy 327.118739 -337.230318) (xy 327.083965 -337.186712) (xy 327.056079 -337.13841) (xy 327.035704 -337.086492)
			(xy 327.023293 -337.032117) (xy 327.019125 -336.9765) (xy 323.95944 -336.9765) (xy 323.483478 -337.452462)
			(xy 323.476669 -337.459807) (xy 323.468947 -337.47827) (xy 323.468492 -337.488276) (xy 323.468492 -337.87461)
			(xy 323.594728 -337.87461) (xy 323.598799 -337.818988) (xy 323.610925 -337.764551) (xy 323.630848 -337.71246)
			(xy 323.658144 -337.663825) (xy 323.69223 -337.619682) (xy 323.732379 -337.580973) (xy 323.777737 -337.548522)
			(xy 323.827337 -337.523021) (xy 323.880121 -337.505014) (xy 323.934964 -337.494884) (xy 323.990698 -337.492847)
			(xy 324.046135 -337.498947) (xy 324.100092 -337.513053) (xy 324.151421 -337.534865) (xy 324.199027 -337.563919)
			(xy 324.241895 -337.599594) (xy 324.279112 -337.641131) (xy 324.309885 -337.687644) (xy 324.333557 -337.738141)
			(xy 324.349625 -337.791548) (xy 324.357745 -337.846724) (xy 324.358254 -337.87461) (xy 324.357745 -337.902496)
			(xy 324.349625 -337.957672) (xy 324.333557 -338.011079) (xy 324.309885 -338.061576) (xy 324.279112 -338.108089)
			(xy 324.241895 -338.149626) (xy 324.199027 -338.185301) (xy 324.151421 -338.214355) (xy 324.100092 -338.236167)
			(xy 324.046135 -338.250273) (xy 323.990698 -338.256373) (xy 323.934964 -338.254336) (xy 323.880121 -338.244206)
			(xy 323.827337 -338.226199) (xy 323.777737 -338.200698) (xy 323.732379 -338.168247) (xy 323.69223 -338.129538)
			(xy 323.658144 -338.085395) (xy 323.630848 -338.03676) (xy 323.610925 -337.984669) (xy 323.598799 -337.930232)
			(xy 323.594728 -337.87461) (xy 323.468492 -337.87461) (xy 323.468492 -338.3915) (xy 323.473318 -338.396072)
			(xy 323.501703 -338.402377) (xy 323.556278 -338.422429) (xy 323.607179 -338.450531) (xy 323.653227 -338.48603)
			(xy 323.693355 -338.528105) (xy 323.726634 -338.575782) (xy 323.752294 -338.627956) (xy 323.76974 -338.68342)
			(xy 323.778568 -338.740889) (xy 323.779134 -338.76996) (xy 323.778674 -338.797215) (xy 323.770922 -338.851172)
			(xy 323.755569 -338.903476) (xy 323.732929 -338.953063) (xy 323.703463 -338.998923) (xy 323.66777 -339.040123)
			(xy 323.626576 -339.075823) (xy 323.580721 -339.105298) (xy 323.531138 -339.127946) (xy 323.478837 -339.143308)
			(xy 323.424881 -339.151069) (xy 323.397626 -339.151468) (xy 323.369324 -339.150948) (xy 323.313343 -339.142572)
			(xy 323.259214 -339.126017) (xy 323.208126 -339.101644) (xy 323.1612 -339.06999) (xy 323.119467 -339.031749)
			(xy 323.083843 -338.987761) (xy 323.05511 -338.938992) (xy 323.033899 -338.886512) (xy 323.026786 -338.859114)
			(xy 323.025008 -338.852256) (xy 323.018404 -338.840318) (xy 322.925948 -338.747862) (xy 322.908646 -338.729845)
			(xy 322.87931 -338.689417) (xy 322.856658 -338.644899) (xy 322.841246 -338.597386) (xy 322.833454 -338.548047)
			(xy 322.832984 -338.523072) (xy 322.832984 -337.335622) (xy 322.833425 -337.310643) (xy 322.841198 -337.261294)
			(xy 322.856603 -337.213771) (xy 322.87926 -337.169246) (xy 322.90861 -337.12882) (xy 322.925948 -337.110832)
			(xy 322.94068 -337.0961) (xy 322.947392 -337.088668) (xy 322.955019 -337.070174) (xy 322.955008 -337.050169)
			(xy 322.947359 -337.031683) (xy 322.94068 -337.024218) (xy 322.936108 -337.019392) (xy 322.924678 -337.012788)
			(xy 322.918328 -337.01101) (xy 322.891743 -337.003292) (xy 322.84097 -336.981235) (xy 322.793923 -336.952064)
			(xy 322.751592 -336.916392) (xy 322.714868 -336.874971) (xy 322.684523 -336.828673) (xy 322.661196 -336.778471)
			(xy 322.645378 -336.725422) (xy 322.637403 -336.670643) (xy 322.636896 -336.642964) (xy 322.637385 -336.615054)
			(xy 322.645524 -336.55983) (xy 322.661624 -336.506381) (xy 322.685341 -336.455849) (xy 322.716168 -336.409313)
			(xy 322.734432 -336.388202) (xy 322.740782 -336.38109) (xy 322.747386 -336.363818) (xy 322.747386 -336.276696)
			(xy 322.740782 -336.259424) (xy 322.734432 -336.252312) (xy 322.716152 -336.231213) (xy 322.685322 -336.184675)
			(xy 322.661602 -336.13414) (xy 322.645499 -336.080689) (xy 322.637357 -336.025462) (xy 322.636896 -335.99755)
			(xy 322.637382 -335.970299) (xy 322.645138 -335.916351) (xy 322.660493 -335.864056) (xy 322.683135 -335.814479)
			(xy 322.712601 -335.768629) (xy 322.748292 -335.727438) (xy 322.789483 -335.691747) (xy 322.835333 -335.662281)
			(xy 322.88491 -335.639639) (xy 322.937205 -335.624284) (xy 322.991153 -335.616528) (xy 323.045655 -335.616528)
			(xy 323.099603 -335.624284) (xy 323.151898 -335.639639) (xy 323.201475 -335.662281) (xy 323.247325 -335.691747)
			(xy 323.288516 -335.727438) (xy 323.324207 -335.768629) (xy 323.353673 -335.814479) (xy 323.376315 -335.864056)
			(xy 323.39167 -335.916351) (xy 323.399426 -335.970299) (xy 323.399912 -335.99755) (xy 323.399429 -336.025462)
			(xy 323.391299 -336.080691) (xy 323.375205 -336.134144) (xy 323.351492 -336.184681) (xy 323.320665 -336.231222)
			(xy 323.302376 -336.252312) (xy 323.296026 -336.259424) (xy 323.289422 -336.276696) (xy 323.289422 -336.363818)
			(xy 323.296026 -336.38109) (xy 323.302376 -336.388202) (xy 323.320564 -336.409274) (xy 323.351292 -336.455686)
			(xy 323.36359 -336.480658) (xy 323.368924 -336.491834) (xy 323.388736 -336.507074) (xy 323.482716 -336.52333)
			(xy 323.494883 -336.524769) (xy 323.518231 -336.517465) (xy 323.52742 -336.50936) (xy 323.81952 -336.21726)
			(xy 323.826196 -336.209848) (xy 323.83376 -336.191411) (xy 323.834252 -336.181446) (xy 323.834252 -323.870574)
			(xy 323.833827 -323.86056) (xy 323.826151 -323.84206) (xy 323.811978 -323.827908) (xy 323.793467 -323.820258)
			(xy 323.783452 -323.819774) (xy 316.16904 -323.819774) (xy 316.159012 -323.820186) (xy 316.140477 -323.827848)
			(xy 316.126285 -323.842021) (xy 316.118599 -323.860546) (xy 316.11824 -323.870574) (xy 316.11824 -336.496152)
			(xy 316.117777 -336.521141) (xy 316.109956 -336.570503) (xy 316.094498 -336.61803) (xy 316.071786 -336.662549)
			(xy 316.042381 -336.702961) (xy 316.025022 -336.720942) (xy 315.762364 -336.9836) (xy 318.663538 -336.9836)
			(xy 318.667705 -336.927983) (xy 318.680116 -336.873608) (xy 318.700492 -336.821691) (xy 318.728379 -336.77339)
			(xy 318.763153 -336.729785) (xy 318.804037 -336.69185) (xy 318.850119 -336.660432) (xy 318.900368 -336.636233)
			(xy 318.953664 -336.619793) (xy 319.008814 -336.611481) (xy 319.0367 -336.61096) (xy 319.063121 -336.611427)
			(xy 319.115436 -336.618876) (xy 319.166174 -336.63364) (xy 319.214319 -336.655421) (xy 319.258904 -336.683784)
			(xy 319.27927 -336.700622) (xy 319.286128 -336.706718) (xy 319.303146 -336.712814) (xy 319.387474 -336.712814)
			(xy 319.404492 -336.706718) (xy 319.41135 -336.700622) (xy 319.431716 -336.683783) (xy 319.476302 -336.655418)
			(xy 319.524446 -336.633631) (xy 319.575183 -336.61886) (xy 319.627498 -336.6114) (xy 319.680342 -336.6114)
			(xy 319.732657 -336.61886) (xy 319.783394 -336.633631) (xy 319.831538 -336.655418) (xy 319.876124 -336.683783)
			(xy 319.89649 -336.700622) (xy 319.903348 -336.706718) (xy 319.920366 -336.712814) (xy 320.004694 -336.712814)
			(xy 320.021712 -336.706718) (xy 320.02857 -336.700622) (xy 320.052017 -336.681287) (xy 320.103963 -336.649751)
			(xy 320.160337 -336.627059) (xy 320.18986 -336.61985) (xy 320.20256 -336.617056) (xy 320.221864 -336.600546)
			(xy 320.261234 -336.497422) (xy 320.257932 -336.472022) (xy 320.250566 -336.461608) (xy 320.233767 -336.437185)
			(xy 320.207124 -336.384235) (xy 320.188982 -336.327805) (xy 320.179776 -336.269249) (xy 320.179192 -336.239612)
			(xy 320.179669 -336.212038) (xy 320.187619 -336.157466) (xy 320.203342 -336.104606) (xy 320.22651 -336.05456)
			(xy 320.256641 -336.00837) (xy 320.293106 -335.966998) (xy 320.313812 -335.948782) (xy 320.321936 -335.941184)
			(xy 320.331287 -335.921029) (xy 320.331846 -335.90992) (xy 320.331846 -335.832704) (xy 320.331309 -335.82159)
			(xy 320.321951 -335.80143) (xy 320.313812 -335.793842) (xy 320.29312 -335.77561) (xy 320.256648 -335.734246)
			(xy 320.226513 -335.68806) (xy 320.203344 -335.638016) (xy 320.187623 -335.585157) (xy 320.17968 -335.530586)
			(xy 320.179192 -335.503012) (xy 320.179678 -335.475761) (xy 320.187434 -335.421813) (xy 320.202789 -335.369518)
			(xy 320.225431 -335.319941) (xy 320.254897 -335.274091) (xy 320.290588 -335.2329) (xy 320.331779 -335.197209)
			(xy 320.377629 -335.167743) (xy 320.427206 -335.145101) (xy 320.479501 -335.129746) (xy 320.533449 -335.12199)
			(xy 320.587951 -335.12199) (xy 320.641899 -335.129746) (xy 320.694194 -335.145101) (xy 320.743771 -335.167743)
			(xy 320.789621 -335.197209) (xy 320.830812 -335.2329) (xy 320.866503 -335.274091) (xy 320.895969 -335.319941)
			(xy 320.918611 -335.369518) (xy 320.933966 -335.421813) (xy 320.941722 -335.475761) (xy 320.942208 -335.503012)
			(xy 320.941679 -335.530584) (xy 320.933739 -335.585154) (xy 320.918026 -335.638013) (xy 320.894868 -335.688059)
			(xy 320.864747 -335.73425) (xy 320.82829 -335.775624) (xy 320.807588 -335.793842) (xy 320.799453 -335.80143)
			(xy 320.790109 -335.821592) (xy 320.789554 -335.832704) (xy 320.789554 -335.90992) (xy 320.790078 -335.921036)
			(xy 320.799446 -335.941195) (xy 320.807588 -335.948782) (xy 320.828291 -335.967002) (xy 320.864763 -336.008368)
			(xy 320.894896 -336.054556) (xy 320.918063 -336.104603) (xy 320.933781 -336.157464) (xy 320.941722 -336.212038)
			(xy 320.942208 -336.239612) (xy 320.941626 -336.268528) (xy 320.932909 -336.3257) (xy 320.915662 -336.380901)
			(xy 320.89028 -336.432865) (xy 320.857344 -336.480403) (xy 320.81761 -336.522424) (xy 320.771988 -336.557966)
			(xy 320.721524 -336.586213) (xy 320.667373 -336.606519) (xy 320.639186 -336.612992) (xy 320.62674 -336.615532)
			(xy 320.607182 -336.632042) (xy 320.566542 -336.734658) (xy 320.56959 -336.760058) (xy 320.576702 -336.770472)
			(xy 320.592505 -336.794045) (xy 320.617534 -336.844979) (xy 320.634565 -336.899114) (xy 320.643204 -336.955203)
			(xy 320.643758 -336.983578) (xy 320.643223 -337.010192) (xy 320.635651 -337.062878) (xy 320.620659 -337.113951)
			(xy 320.598551 -337.16237) (xy 320.569777 -337.20715) (xy 320.534924 -337.24738) (xy 320.4947 -337.28224)
			(xy 320.449924 -337.311021) (xy 320.401509 -337.333137) (xy 320.350439 -337.348138) (xy 320.297754 -337.355719)
			(xy 320.27114 -337.356196) (xy 320.244717 -337.355774) (xy 320.1924 -337.348316) (xy 320.141661 -337.333542)
			(xy 320.093517 -337.311751) (xy 320.048934 -337.283377) (xy 320.02857 -337.266534) (xy 320.021712 -337.260438)
			(xy 320.004694 -337.254342) (xy 319.920366 -337.254342) (xy 319.903348 -337.260438) (xy 319.89649 -337.266534)
			(xy 319.876124 -337.283373) (xy 319.831538 -337.311738) (xy 319.783394 -337.333525) (xy 319.732657 -337.348296)
			(xy 319.680342 -337.355756) (xy 319.627498 -337.355756) (xy 319.575183 -337.348296) (xy 319.524446 -337.333525)
			(xy 319.476302 -337.311738) (xy 319.431716 -337.283373) (xy 319.41135 -337.266534) (xy 319.404492 -337.260438)
			(xy 319.387474 -337.254342) (xy 319.303146 -337.254342) (xy 319.286128 -337.260438) (xy 319.27927 -337.266534)
			(xy 319.258907 -337.283376) (xy 319.214318 -337.311733) (xy 319.166172 -337.333512) (xy 319.115435 -337.348279)
			(xy 319.063121 -337.355737) (xy 319.0367 -337.356196) (xy 319.008814 -337.355719) (xy 318.953664 -337.347407)
			(xy 318.900368 -337.330967) (xy 318.850119 -337.306768) (xy 318.804037 -337.27535) (xy 318.763153 -337.237415)
			(xy 318.728379 -337.19381) (xy 318.700492 -337.145509) (xy 318.680116 -337.093592) (xy 318.667705 -337.039217)
			(xy 318.663538 -336.9836) (xy 315.762364 -336.9836) (xy 315.015372 -337.730592) (xy 315.00869 -337.738003)
			(xy 315.001109 -337.756438) (xy 315.00064 -337.766406) (xy 315.00064 -337.881722) (xy 315.239144 -337.881722)
			(xy 315.243215 -337.8261) (xy 315.255341 -337.771663) (xy 315.275264 -337.719572) (xy 315.30256 -337.670937)
			(xy 315.336646 -337.626794) (xy 315.376795 -337.588085) (xy 315.422153 -337.555634) (xy 315.471753 -337.530133)
			(xy 315.524537 -337.512126) (xy 315.57938 -337.501996) (xy 315.635114 -337.499959) (xy 315.690551 -337.506059)
			(xy 315.744508 -337.520165) (xy 315.795837 -337.541977) (xy 315.843443 -337.571031) (xy 315.886311 -337.606706)
			(xy 315.923528 -337.648243) (xy 315.954301 -337.694756) (xy 315.977973 -337.745253) (xy 315.994041 -337.79866)
			(xy 316.002161 -337.853836) (xy 316.00267 -337.881722) (xy 316.002161 -337.909608) (xy 315.994041 -337.964784)
			(xy 315.977973 -338.018191) (xy 315.954301 -338.068688) (xy 315.923528 -338.115201) (xy 315.886311 -338.156738)
			(xy 315.843443 -338.192413) (xy 315.795837 -338.221467) (xy 315.744508 -338.243279) (xy 315.690551 -338.257385)
			(xy 315.635114 -338.263485) (xy 315.57938 -338.261448) (xy 315.524537 -338.251318) (xy 315.471753 -338.233311)
			(xy 315.422153 -338.20781) (xy 315.376795 -338.175359) (xy 315.336646 -338.13665) (xy 315.30256 -338.092507)
			(xy 315.275264 -338.043872) (xy 315.255341 -337.991781) (xy 315.243215 -337.937344) (xy 315.239144 -337.881722)
			(xy 315.00064 -337.881722) (xy 315.00064 -338.265008) (xy 315.001097 -338.274887) (xy 315.008531 -338.293193)
			(xy 315.015118 -338.300568) (xy 315.015372 -338.300822) (xy 315.10732 -338.39277) (xy 315.112467 -338.397523)
			(xy 315.124704 -338.404336) (xy 315.13145 -338.406232) (xy 315.133736 -338.40674) (xy 315.160956 -338.413995)
			(xy 315.213055 -338.435418) (xy 315.261438 -338.464269) (xy 315.305052 -338.499921) (xy 315.34295 -338.541598)
			(xy 315.374308 -338.588394) (xy 315.398445 -338.639293) (xy 315.414834 -338.693188) (xy 315.423121 -338.748906)
			(xy 315.42355 -338.777072) (xy 315.423066 -338.804326) (xy 315.415313 -338.858279) (xy 315.399961 -338.910579)
			(xy 315.377322 -338.960163) (xy 315.347857 -339.00602) (xy 315.312166 -339.047217) (xy 315.270976 -339.082915)
			(xy 315.225124 -339.112388) (xy 315.175545 -339.135036) (xy 315.123247 -339.150398) (xy 315.069296 -339.158161)
			(xy 315.042042 -339.15858) (xy 315.013739 -339.158061) (xy 314.957756 -339.149688) (xy 314.903625 -339.133134)
			(xy 314.852534 -339.108763) (xy 314.805605 -339.077109) (xy 314.763869 -339.038869) (xy 314.728242 -338.994881)
			(xy 314.699506 -338.946111) (xy 314.678292 -338.893631) (xy 314.671202 -338.866226) (xy 314.669424 -338.859368)
			(xy 314.66282 -338.84743) (xy 314.457842 -338.642452) (xy 314.455302 -338.639912) (xy 314.455048 -338.639658)
			(xy 314.438792 -338.623402) (xy 314.42149 -338.605384) (xy 314.392154 -338.564956) (xy 314.3695 -338.520438)
			(xy 314.354086 -338.472926) (xy 314.346289 -338.423587) (xy 314.345828 -338.398612) (xy 314.345828 -337.632802)
			(xy 314.34627 -337.607823) (xy 314.354045 -337.558474) (xy 314.36945 -337.510952) (xy 314.392106 -337.466427)
			(xy 314.421454 -337.425999) (xy 314.438792 -337.408012) (xy 314.455048 -337.391756) (xy 314.455302 -337.391502)
			(xy 314.457842 -337.388962) (xy 314.649358 -337.197446) (xy 314.6552 -337.190588) (xy 314.661459 -337.180658)
			(xy 314.665047 -337.157488) (xy 314.662058 -337.146138) (xy 314.635134 -337.06054) (xy 314.631832 -337.052412)
			(xy 314.629568 -337.048195) (xy 314.623691 -337.040643) (xy 314.620148 -337.037426) (xy 314.614773 -337.033075)
			(xy 314.602279 -337.027161) (xy 314.59551 -337.025742) (xy 314.569419 -337.020576) (xy 314.51889 -337.003977)
			(xy 314.471152 -336.980526) (xy 314.427131 -336.950678) (xy 314.387678 -336.915009) (xy 314.353555 -336.874212)
			(xy 314.325424 -336.829074) (xy 314.303829 -336.780469) (xy 314.289187 -336.729337) (xy 314.281783 -336.676669)
			(xy 314.281312 -336.650076) (xy 314.2818 -336.622165) (xy 314.289938 -336.566941) (xy 314.306037 -336.513492)
			(xy 314.329754 -336.462959) (xy 314.360581 -336.416422) (xy 314.378848 -336.395314) (xy 314.385198 -336.388202)
			(xy 314.391802 -336.37093) (xy 314.391802 -336.283808) (xy 314.385198 -336.266536) (xy 314.378848 -336.259424)
			(xy 314.360571 -336.238323) (xy 314.329746 -336.191784) (xy 314.30603 -336.141249) (xy 314.289929 -336.087799)
			(xy 314.281787 -336.032573) (xy 314.281312 -336.004662) (xy 314.281798 -335.977411) (xy 314.289554 -335.923463)
			(xy 314.304909 -335.871168) (xy 314.327551 -335.821591) (xy 314.357017 -335.775741) (xy 314.392708 -335.73455)
			(xy 314.433899 -335.698859) (xy 314.479749 -335.669393) (xy 314.529326 -335.646751) (xy 314.581621 -335.631396)
			(xy 314.635569 -335.62364) (xy 314.690071 -335.62364) (xy 314.744019 -335.631396) (xy 314.796314 -335.646751)
			(xy 314.845891 -335.669393) (xy 314.891741 -335.698859) (xy 314.932932 -335.73455) (xy 314.968623 -335.775741)
			(xy 314.998089 -335.821591) (xy 315.020731 -335.871168) (xy 315.036086 -335.923463) (xy 315.043842 -335.977411)
			(xy 315.044328 -336.004662) (xy 315.043845 -336.032574) (xy 315.035713 -336.087802) (xy 315.019619 -336.141255)
			(xy 314.995905 -336.191791) (xy 314.965079 -336.238332) (xy 314.946792 -336.259424) (xy 314.940442 -336.266536)
			(xy 314.933838 -336.283808) (xy 314.933838 -336.37093) (xy 314.940442 -336.388202) (xy 314.946792 -336.395314)
			(xy 314.964141 -336.415301) (xy 314.99373 -336.459184) (xy 315.016967 -336.506737) (xy 315.033405 -336.557046)
			(xy 315.038486 -336.58302) (xy 315.040534 -336.592033) (xy 315.050068 -336.607849) (xy 315.064587 -336.619262)
			(xy 315.073284 -336.62239) (xy 315.158882 -336.649314) (xy 315.167809 -336.651701) (xy 315.186243 -336.650628)
			(xy 315.203097 -336.643084) (xy 315.209936 -336.636868) (xy 315.467492 -336.379312) (xy 315.474179 -336.371903)
			(xy 315.481767 -336.353467) (xy 315.482224 -336.343498) (xy 315.482224 -324.51675) (xy 315.481737 -324.506748)
			(xy 315.474114 -324.488252) (xy 315.460031 -324.474043) (xy 315.450982 -324.46976) (xy 315.436504 -324.463664)
			(xy 315.406532 -324.46976) (xy 314.515246 -325.361046) (xy 314.507847 -325.36789) (xy 314.489248 -325.375613)
			(xy 314.479178 -325.376032) (xy 314.474352 -325.376032) (xy 314.45581 -325.383652) (xy 311.61101 -328.228452)
			(xy 311.604171 -328.235853) (xy 311.596453 -328.254451) (xy 311.596024 -328.26452) (xy 311.596024 -335.070196)
			(xy 311.595602 -335.080267) (xy 311.587892 -335.098875) (xy 311.581038 -335.106264) (xy 311.242456 -335.444846)
			(xy 311.235058 -335.451691) (xy 311.216459 -335.459418) (xy 311.206388 -335.459832) (xy 305.060604 -335.459832)
			(xy 305.050585 -335.460251) (xy 305.032072 -335.467922) (xy 305.017906 -335.482095) (xy 305.010246 -335.500612)
			(xy 305.009804 -335.510632) (xy 305.009804 -336.927698) (xy 305.010341 -336.937686) (xy 305.018055 -336.956118)
			(xy 305.02479 -336.963512) (xy 306.396136 -338.334858) (xy 306.413438 -338.352875) (xy 306.442772 -338.393303)
			(xy 306.465423 -338.437822) (xy 306.480833 -338.485335) (xy 306.488622 -338.534673) (xy 306.4891 -338.559648)
			(xy 306.4891 -339.452712) (xy 315.99886 -339.452712) (xy 315.999363 -339.425238) (xy 316.007253 -339.37086)
			(xy 316.022869 -339.318178) (xy 316.04589 -339.268285) (xy 316.075837 -339.222215) (xy 316.093602 -339.201252)
			(xy 316.099698 -339.19414) (xy 316.106048 -339.177122) (xy 316.106048 -339.09127) (xy 316.099698 -339.074252)
			(xy 316.093602 -339.06714) (xy 316.075876 -339.046147) (xy 316.045945 -339.000074) (xy 316.022925 -338.950187)
			(xy 316.007291 -338.897517) (xy 315.999364 -338.84315) (xy 315.99886 -338.81568) (xy 315.999346 -338.788429)
			(xy 316.007102 -338.734481) (xy 316.022457 -338.682186) (xy 316.045099 -338.632609) (xy 316.074565 -338.586759)
			(xy 316.110256 -338.545568) (xy 316.151447 -338.509877) (xy 316.197297 -338.480411) (xy 316.246874 -338.457769)
			(xy 316.299169 -338.442414) (xy 316.353117 -338.434658) (xy 316.407619 -338.434658) (xy 316.461567 -338.442414)
			(xy 316.513862 -338.457769) (xy 316.563439 -338.480411) (xy 316.609289 -338.509877) (xy 316.65048 -338.545568)
			(xy 316.686171 -338.586759) (xy 316.715637 -338.632609) (xy 316.738279 -338.682186) (xy 316.753634 -338.734481)
			(xy 316.76139 -338.788429) (xy 316.761876 -338.81568) (xy 316.761384 -338.843154) (xy 316.753494 -338.897534)
			(xy 316.737876 -338.950217) (xy 316.714852 -339.000109) (xy 316.684901 -339.046178) (xy 316.667134 -339.06714)
			(xy 316.661038 -339.074252) (xy 316.654688 -339.09127) (xy 316.654688 -339.177122) (xy 316.661038 -339.19414)
			(xy 316.667134 -339.201252) (xy 316.684862 -339.222243) (xy 316.714791 -339.268318) (xy 316.73781 -339.318204)
			(xy 316.753444 -339.370875) (xy 316.761371 -339.425242) (xy 316.761876 -339.452712) (xy 316.76139 -339.479963)
			(xy 316.753634 -339.533911) (xy 316.738279 -339.586206) (xy 316.715637 -339.635783) (xy 316.686171 -339.681633)
			(xy 316.65048 -339.722824) (xy 316.609289 -339.758515) (xy 316.563439 -339.787981) (xy 316.513862 -339.810623)
			(xy 316.461567 -339.825978) (xy 316.407619 -339.833734) (xy 316.353117 -339.833734) (xy 316.299169 -339.825978)
			(xy 316.246874 -339.810623) (xy 316.197297 -339.787981) (xy 316.151447 -339.758515) (xy 316.110256 -339.722824)
			(xy 316.074565 -339.681633) (xy 316.045099 -339.635783) (xy 316.022457 -339.586206) (xy 316.007102 -339.533911)
			(xy 315.999346 -339.479963) (xy 315.99886 -339.452712) (xy 306.4891 -339.452712) (xy 306.4891 -348.296738)
			(xy 306.488655 -348.321715) (xy 306.480873 -348.371059) (xy 306.46546 -348.418576) (xy 306.442797 -348.463093)
			(xy 306.413442 -348.503511) (xy 306.396136 -348.521528) (xy 306.212964 -348.7047) (xy 309.013821 -348.7047)
			(xy 309.017989 -348.649082) (xy 309.0304 -348.594706) (xy 309.050776 -348.542788) (xy 309.078662 -348.494485)
			(xy 309.113436 -348.450879) (xy 309.154321 -348.412942) (xy 309.200403 -348.381523) (xy 309.250653 -348.357322)
			(xy 309.303948 -348.340881) (xy 309.359099 -348.332566) (xy 309.386986 -348.332044) (xy 309.413407 -348.332523)
			(xy 309.465721 -348.33997) (xy 309.516459 -348.354731) (xy 309.564603 -348.376509) (xy 309.60919 -348.404869)
			(xy 309.629556 -348.421706) (xy 309.636414 -348.427802) (xy 309.653432 -348.433898) (xy 309.73776 -348.433898)
			(xy 309.754778 -348.427802) (xy 309.761636 -348.421706) (xy 309.782002 -348.404867) (xy 309.826588 -348.376502)
			(xy 309.874732 -348.354715) (xy 309.925469 -348.339944) (xy 309.977784 -348.332484) (xy 310.030628 -348.332484)
			(xy 310.082943 -348.339944) (xy 310.13368 -348.354715) (xy 310.181824 -348.376502) (xy 310.22641 -348.404867)
			(xy 310.246776 -348.421706) (xy 310.253634 -348.427802) (xy 310.270652 -348.433898) (xy 310.35498 -348.433898)
			(xy 310.371998 -348.427802) (xy 310.378856 -348.421706) (xy 310.404711 -348.400478) (xy 310.462474 -348.366746)
			(xy 310.493664 -348.35465) (xy 310.504332 -348.35084) (xy 310.520334 -348.33433) (xy 310.553608 -348.23781)
			(xy 310.550814 -348.21495) (xy 310.544718 -348.205298) (xy 310.530854 -348.182405) (xy 310.509015 -348.133543)
			(xy 310.494215 -348.082109) (xy 310.486745 -348.029112) (xy 310.486298 -348.002352) (xy 310.4868 -347.974779)
			(xy 310.494745 -347.920208) (xy 310.510463 -347.867348) (xy 310.533626 -347.817302) (xy 310.563752 -347.771112)
			(xy 310.600214 -347.729739) (xy 310.620918 -347.711522) (xy 310.629025 -347.703909) (xy 310.638385 -347.683765)
			(xy 310.638952 -347.67266) (xy 310.638952 -347.595444) (xy 310.638391 -347.584333) (xy 310.629049 -347.564173)
			(xy 310.620918 -347.556582) (xy 310.600199 -347.53838) (xy 310.563728 -347.49701) (xy 310.533597 -347.450818)
			(xy 310.510432 -347.400768) (xy 310.494718 -347.347904) (xy 310.486781 -347.293327) (xy 310.486298 -347.265752)
			(xy 310.486784 -347.238501) (xy 310.49454 -347.184553) (xy 310.509895 -347.132258) (xy 310.532537 -347.082681)
			(xy 310.562003 -347.036831) (xy 310.597694 -346.99564) (xy 310.638885 -346.959949) (xy 310.684735 -346.930483)
			(xy 310.734312 -346.907841) (xy 310.786607 -346.892486) (xy 310.840555 -346.88473) (xy 310.895057 -346.88473)
			(xy 310.949005 -346.892486) (xy 311.0013 -346.907841) (xy 311.050877 -346.930483) (xy 311.096727 -346.959949)
			(xy 311.137918 -346.99564) (xy 311.173609 -347.036831) (xy 311.203075 -347.082681) (xy 311.225717 -347.132258)
			(xy 311.241072 -347.184553) (xy 311.248828 -347.238501) (xy 311.249314 -347.265752) (xy 311.24881 -347.293325)
			(xy 311.240865 -347.347896) (xy 311.225147 -347.400755) (xy 311.201984 -347.450801) (xy 311.171859 -347.496992)
			(xy 311.135398 -347.538365) (xy 311.114694 -347.556582) (xy 311.106587 -347.564195) (xy 311.097227 -347.584339)
			(xy 311.09666 -347.595444) (xy 311.09666 -347.67266) (xy 311.097215 -347.683772) (xy 311.106561 -347.703932)
			(xy 311.114694 -347.711522) (xy 311.135418 -347.729719) (xy 311.171887 -347.771091) (xy 311.202018 -347.817284)
			(xy 311.225182 -347.867334) (xy 311.240895 -347.920199) (xy 311.248831 -347.974776) (xy 311.249314 -348.002352)
			(xy 311.248909 -348.028552) (xy 311.241751 -348.08046) (xy 311.227549 -348.130898) (xy 311.206572 -348.178915)
			(xy 311.179215 -348.223605) (xy 311.145994 -348.264127) (xy 311.107534 -348.299715) (xy 311.064562 -348.3297)
			(xy 311.017888 -348.353515) (xy 310.993282 -348.362524) (xy 310.98236 -348.366334) (xy 310.966104 -348.38259)
			(xy 310.93156 -348.478602) (xy 310.933846 -348.501462) (xy 310.939942 -348.511368) (xy 310.95275 -348.533323)
			(xy 310.972985 -348.579949) (xy 310.98669 -348.628894) (xy 310.993609 -348.679248) (xy 310.994044 -348.704662)
			(xy 310.993531 -348.731278) (xy 310.98596 -348.783968) (xy 310.970968 -348.835044) (xy 310.94886 -348.883467)
			(xy 310.920085 -348.928251) (xy 310.885229 -348.968484) (xy 310.845002 -349.003346) (xy 310.800224 -349.032129)
			(xy 310.751805 -349.054246) (xy 310.700731 -349.069247) (xy 310.648042 -349.076826) (xy 310.621426 -349.07728)
			(xy 310.595006 -349.076788) (xy 310.542692 -349.069344) (xy 310.491955 -349.054585) (xy 310.44381 -349.03281)
			(xy 310.399223 -349.004453) (xy 310.378856 -348.987618) (xy 310.371998 -348.981522) (xy 310.35498 -348.975426)
			(xy 310.270652 -348.975426) (xy 310.253634 -348.981522) (xy 310.246776 -348.987618) (xy 310.22641 -349.004457)
			(xy 310.181824 -349.032822) (xy 310.13368 -349.054609) (xy 310.082943 -349.06938) (xy 310.030628 -349.07684)
			(xy 309.977784 -349.07684) (xy 309.925469 -349.06938) (xy 309.874732 -349.054609) (xy 309.826588 -349.032822)
			(xy 309.782002 -349.004457) (xy 309.761636 -348.987618) (xy 309.754778 -348.981522) (xy 309.73776 -348.975426)
			(xy 309.653432 -348.975426) (xy 309.636414 -348.981522) (xy 309.629556 -348.987618) (xy 309.609197 -349.004464)
			(xy 309.564606 -349.032821) (xy 309.51646 -349.0546) (xy 309.465722 -349.069365) (xy 309.413408 -349.076822)
			(xy 309.386986 -349.07728) (xy 309.359099 -349.076834) (xy 309.303948 -349.068519) (xy 309.250653 -349.052078)
			(xy 309.200403 -349.027877) (xy 309.154321 -348.996458) (xy 309.113436 -348.958521) (xy 309.078662 -348.914915)
			(xy 309.050776 -348.866612) (xy 309.0304 -348.814694) (xy 309.017989 -348.760318) (xy 309.013821 -348.7047)
			(xy 306.212964 -348.7047) (xy 305.868832 -349.048832) (xy 305.861847 -349.056426) (xy 305.854123 -349.075537)
			(xy 305.854594 -349.096144) (xy 305.858418 -349.105728) (xy 305.904138 -349.207074) (xy 305.931062 -349.223076)
			(xy 305.947064 -349.22206) (xy 305.971448 -349.221298) (xy 305.998697 -349.221787) (xy 306.052638 -349.229549)
			(xy 306.104926 -349.244908) (xy 306.154497 -349.267552) (xy 306.200341 -349.297019) (xy 306.241524 -349.33271)
			(xy 306.27721 -349.373898) (xy 306.306671 -349.419745) (xy 306.329309 -349.469319) (xy 306.344661 -349.521609)
			(xy 306.352416 -349.575551) (xy 306.352416 -349.630049) (xy 306.344661 -349.683991) (xy 306.329309 -349.736281)
			(xy 306.306671 -349.785855) (xy 306.27721 -349.831702) (xy 306.241524 -349.87289) (xy 306.200341 -349.908581)
			(xy 306.154497 -349.938048) (xy 306.104926 -349.960692) (xy 306.052638 -349.976051) (xy 305.998697 -349.983813)
			(xy 305.971448 -349.984314) (xy 305.943395 -349.98382) (xy 305.887893 -349.975601) (xy 305.834197 -349.959333)
			(xy 305.783466 -349.935369) (xy 305.736796 -349.904226) (xy 305.71567 -349.885762) (xy 305.70424 -349.875602)
			(xy 305.674776 -349.870776) (xy 305.57597 -349.914718) (xy 305.567184 -349.9191) (xy 305.553547 -349.9332)
			(xy 305.546209 -349.951391) (xy 305.545744 -349.9612) (xy 305.545744 -350.117156) (xy 305.546184 -350.12631)
			(xy 305.5527 -350.143426) (xy 305.564784 -350.157187) (xy 305.572668 -350.16186) (xy 305.598323 -350.176252)
			(xy 305.645265 -350.211697) (xy 305.686216 -350.253921) (xy 305.720209 -350.301926) (xy 305.746439 -350.354575)
			(xy 305.764286 -350.410623) (xy 305.773328 -350.468746) (xy 305.773836 -350.498156) (xy 305.773376 -350.525412)
			(xy 305.765624 -350.579369) (xy 305.750272 -350.631674) (xy 305.727633 -350.681261) (xy 305.698166 -350.727122)
			(xy 305.662473 -350.768322) (xy 305.62128 -350.804023) (xy 305.575424 -350.833498) (xy 305.525841 -350.856147)
			(xy 305.473539 -350.871509) (xy 305.419584 -350.879271) (xy 305.392328 -350.879664) (xy 305.364026 -350.879144)
			(xy 305.308045 -350.870769) (xy 305.253916 -350.854213) (xy 305.202828 -350.829841) (xy 305.155902 -350.798187)
			(xy 305.114169 -350.759946) (xy 305.078545 -350.715958) (xy 305.049812 -350.667188) (xy 305.028602 -350.614708)
			(xy 305.021488 -350.58731) (xy 305.01971 -350.580452) (xy 305.013106 -350.568514) (xy 305.0032 -350.558608)
			(xy 304.985897 -350.54059) (xy 304.95656 -350.500163) (xy 304.933905 -350.455645) (xy 304.918489 -350.408132)
			(xy 304.910691 -350.358794) (xy 304.910236 -350.333818) (xy 304.910236 -349.240094) (xy 304.910679 -349.215115)
			(xy 304.918455 -349.165767) (xy 304.933861 -349.118246) (xy 304.956519 -349.073723) (xy 304.985867 -349.033296)
			(xy 305.0032 -349.015304) (xy 305.092608 -348.92615) (xy 305.09941 -348.918667) (xy 305.107012 -348.899945)
			(xy 305.106828 -348.879739) (xy 305.103276 -348.87027) (xy 305.060604 -348.769178) (xy 305.034696 -348.752414)
			(xy 305.018948 -348.752668) (xy 305.013106 -348.752668) (xy 304.985854 -348.752205) (xy 304.931904 -348.744449)
			(xy 304.879608 -348.729093) (xy 304.83003 -348.70645) (xy 304.784179 -348.676981) (xy 304.742989 -348.641287)
			(xy 304.707298 -348.600094) (xy 304.677834 -348.55424) (xy 304.655195 -348.50466) (xy 304.639844 -348.452362)
			(xy 304.632093 -348.398412) (xy 304.631598 -348.37116) (xy 304.632087 -348.34325) (xy 304.640227 -348.288026)
			(xy 304.656327 -348.234578) (xy 304.680045 -348.184047) (xy 304.710872 -348.137511) (xy 304.729134 -348.116398)
			(xy 304.735484 -348.109286) (xy 304.742088 -348.092014) (xy 304.742088 -348.004892) (xy 304.735484 -347.98762)
			(xy 304.729134 -347.980508) (xy 304.710854 -347.959409) (xy 304.680024 -347.912871) (xy 304.656305 -347.862336)
			(xy 304.640202 -347.808885) (xy 304.632061 -347.753658) (xy 304.631598 -347.725746) (xy 304.632084 -347.698495)
			(xy 304.63984 -347.644547) (xy 304.655195 -347.592252) (xy 304.677837 -347.542675) (xy 304.707303 -347.496825)
			(xy 304.742994 -347.455634) (xy 304.784185 -347.419943) (xy 304.830035 -347.390477) (xy 304.879612 -347.367835)
			(xy 304.931907 -347.35248) (xy 304.985855 -347.344724) (xy 305.040357 -347.344724) (xy 305.094305 -347.35248)
			(xy 305.1466 -347.367835) (xy 305.196177 -347.390477) (xy 305.242027 -347.419943) (xy 305.283218 -347.455634)
			(xy 305.318909 -347.496825) (xy 305.348375 -347.542675) (xy 305.371017 -347.592252) (xy 305.386372 -347.644547)
			(xy 305.394128 -347.698495) (xy 305.394614 -347.725746) (xy 305.394132 -347.753658) (xy 305.386002 -347.808887)
			(xy 305.369909 -347.862341) (xy 305.346196 -347.912879) (xy 305.31537 -347.95942) (xy 305.297078 -347.980508)
			(xy 305.290728 -347.98762) (xy 305.284124 -348.004892) (xy 305.284124 -348.092014) (xy 305.290728 -348.109286)
			(xy 305.297078 -348.116398) (xy 305.315357 -348.137497) (xy 305.346185 -348.184036) (xy 305.369903 -348.234571)
			(xy 305.386004 -348.288022) (xy 305.394144 -348.343248) (xy 305.394614 -348.37116) (xy 305.394614 -348.377002)
			(xy 305.39436 -348.39275) (xy 305.411124 -348.418658) (xy 305.512216 -348.46133) (xy 305.521678 -348.464927)
			(xy 305.541905 -348.465132) (xy 305.56064 -348.457507) (xy 305.568096 -348.450662) (xy 305.838606 -348.179898)
			(xy 305.845416 -348.172552) (xy 305.853146 -348.15409) (xy 305.853592 -348.144084) (xy 305.853592 -338.712302)
			(xy 305.853055 -338.702315) (xy 305.845341 -338.683883) (xy 305.838606 -338.676488) (xy 304.46726 -337.305142)
			(xy 304.449958 -337.287125) (xy 304.420624 -337.246697) (xy 304.397974 -337.202178) (xy 304.382564 -337.154665)
			(xy 304.374775 -337.105327) (xy 304.374296 -337.080352) (xy 304.374296 -335.510632) (xy 304.373882 -335.500607)
			(xy 304.366218 -335.48208) (xy 304.352044 -335.467898) (xy 304.333521 -335.460224) (xy 304.323496 -335.459832)
			(xy 304.102008 -335.459832) (xy 304.091936 -335.459411) (xy 304.073327 -335.451702) (xy 304.06594 -335.444846)
			(xy 303.859438 -335.238344) (xy 303.852596 -335.230944) (xy 303.844876 -335.212346) (xy 303.844452 -335.202276)
			(xy 303.844452 -325.350632) (xy 303.843894 -325.339105) (xy 303.833828 -325.318363) (xy 303.825148 -325.310754)
			(xy 303.790567 -325.282647) (xy 303.726059 -325.221154) (xy 303.667334 -325.154118) (xy 303.614866 -325.082078)
			(xy 303.569079 -325.005619) (xy 303.530343 -324.925356) (xy 303.498971 -324.841939) (xy 303.475217 -324.756042)
			(xy 303.459272 -324.668359) (xy 303.451265 -324.579598) (xy 303.450752 -324.535038) (xy 303.45129 -324.488412)
			(xy 303.460056 -324.395573) (xy 303.477506 -324.303967) (xy 303.503485 -324.214407) (xy 303.537762 -324.127683)
			(xy 303.580036 -324.044563) (xy 303.629931 -323.965782) (xy 303.687007 -323.892037) (xy 303.718468 -323.85762)
			(xy 303.728882 -323.846698) (xy 303.733962 -323.81698) (xy 303.69129 -323.717412) (xy 303.687 -323.708565)
			(xy 303.673026 -323.694757) (xy 303.654881 -323.687229) (xy 303.645062 -323.686678) (xy 262.305038 -323.408294)
			(xy 262.286496 -323.415914) (xy 262.27913 -323.42328) (xy 261.599426 -324.102984) (xy 262.047228 -324.102984)
			(xy 262.04764 -324.075729) (xy 262.0554 -324.021774) (xy 262.07076 -323.969473) (xy 262.093407 -323.919891)
			(xy 262.12288 -323.874036) (xy 262.158579 -323.832842) (xy 262.199778 -323.797149) (xy 262.245636 -323.767682)
			(xy 262.295222 -323.745042) (xy 262.347525 -323.729689) (xy 262.401481 -323.721936) (xy 262.428736 -323.721476)
			(xy 262.457923 -323.722026) (xy 262.515615 -323.730929) (xy 262.57128 -323.748508) (xy 262.623622 -323.774352)
			(xy 262.671421 -323.80786) (xy 262.713565 -323.848251) (xy 262.731758 -323.871082) (xy 262.739886 -323.88175)
			(xy 262.763762 -323.892164) (xy 262.876792 -323.880226) (xy 262.898128 -323.86524) (xy 262.90397 -323.853048)
			(xy 262.915962 -323.829003) (xy 262.945644 -323.784216) (xy 262.981318 -323.744038) (xy 263.022276 -323.709263)
			(xy 263.067709 -323.680579) (xy 263.116717 -323.658554) (xy 263.168331 -323.643624) (xy 263.221529 -323.636083)
			(xy 263.248394 -323.635624) (xy 263.277413 -323.636205) (xy 263.334783 -323.644995) (xy 263.390159 -323.662371)
			(xy 263.442264 -323.687935) (xy 263.489897 -323.721095) (xy 263.531958 -323.761087) (xy 263.550146 -323.783706)
			(xy 263.55802 -323.793612) (xy 263.58088 -323.804026) (xy 263.689592 -323.797676) (xy 263.711182 -323.784722)
			(xy 263.717532 -323.774054) (xy 263.732422 -323.75023) (xy 263.768091 -323.706826) (xy 263.809739 -323.669121)
			(xy 263.856464 -323.637929) (xy 263.907257 -323.613925) (xy 263.961022 -323.597627) (xy 264.016594 -323.589388)
			(xy 264.044684 -323.588888) (xy 264.074105 -323.589449) (xy 264.132249 -323.598494) (xy 264.188315 -323.616358)
			(xy 264.240974 -323.642616) (xy 264.288978 -323.676646) (xy 264.33119 -323.717642) (xy 264.366608 -323.764632)
			(xy 264.38098 -323.79031) (xy 264.387584 -323.802502) (xy 264.410698 -323.816726) (xy 264.526776 -323.81952)
			(xy 264.550652 -323.806312) (xy 264.557764 -323.794374) (xy 264.572655 -323.770504) (xy 264.608307 -323.726987)
			(xy 264.649964 -323.689177) (xy 264.696721 -323.657895) (xy 264.747566 -323.633819) (xy 264.801395 -323.61747)
			(xy 264.857042 -323.609204) (xy 264.88517 -323.6087) (xy 264.912425 -323.609145) (xy 264.96638 -323.616899)
			(xy 265.018683 -323.632253) (xy 265.068268 -323.654894) (xy 265.114125 -323.684362) (xy 265.155323 -323.720056)
			(xy 265.19102 -323.761251) (xy 265.220492 -323.807106) (xy 265.243137 -323.856689) (xy 265.258495 -323.908991)
			(xy 265.266253 -323.962945) (xy 265.266253 -324.017455) (xy 265.258495 -324.071409) (xy 265.243137 -324.123711)
			(xy 265.220492 -324.173294) (xy 265.19102 -324.219149) (xy 265.155323 -324.260344) (xy 265.114125 -324.296038)
			(xy 265.068268 -324.325506) (xy 265.018683 -324.348147) (xy 264.96638 -324.363501) (xy 264.912425 -324.371255)
			(xy 264.88517 -324.371716) (xy 264.85575 -324.37111) (xy 264.797609 -324.362072) (xy 264.741544 -324.344217)
			(xy 264.688885 -324.317966) (xy 264.64088 -324.283943) (xy 264.598667 -324.242953) (xy 264.563247 -324.195969)
			(xy 264.548874 -324.170294) (xy 264.54227 -324.158102) (xy 264.519156 -324.143878) (xy 264.403078 -324.141084)
			(xy 264.379202 -324.154292) (xy 264.37209 -324.16623) (xy 264.355509 -324.192731) (xy 264.31513 -324.240447)
			(xy 264.267502 -324.280928) (xy 264.241026 -324.297548) (xy 264.229342 -324.30466) (xy 264.216388 -324.328028)
			(xy 264.218166 -324.443344) (xy 264.231882 -324.466458) (xy 264.24382 -324.473316) (xy 264.266861 -324.486704)
			(xy 264.309326 -324.518897) (xy 264.346909 -324.556676) (xy 264.378881 -324.599307) (xy 264.392156 -324.622414)
			(xy 264.397998 -324.633336) (xy 264.418064 -324.646798) (xy 264.523982 -324.66026) (xy 264.546588 -324.652132)
			(xy 264.555224 -324.642988) (xy 264.573309 -324.624411) (xy 264.61364 -324.591832) (xy 264.658014 -324.565019)
			(xy 264.705611 -324.544466) (xy 264.755555 -324.530551) (xy 264.806923 -324.523533) (xy 264.832846 -324.5231)
			(xy 264.860096 -324.523573) (xy 264.91404 -324.531335) (xy 264.96633 -324.546694) (xy 265.015902 -324.569339)
			(xy 265.061748 -324.598807) (xy 265.102934 -324.634499) (xy 265.138621 -324.675689) (xy 265.168083 -324.721538)
			(xy 265.190722 -324.771113) (xy 265.206075 -324.823405) (xy 265.21383 -324.87735) (xy 265.21383 -324.93185)
			(xy 265.206075 -324.985795) (xy 265.190722 -325.038087) (xy 265.168083 -325.087662) (xy 265.138621 -325.133511)
			(xy 265.102934 -325.174701) (xy 265.061748 -325.210393) (xy 265.015902 -325.239861) (xy 264.96633 -325.262506)
			(xy 264.91404 -325.277865) (xy 264.860096 -325.285627) (xy 264.832846 -325.286116) (xy 264.803734 -325.285528)
			(xy 264.746184 -325.276687) (xy 264.690646 -325.259203) (xy 264.638411 -325.233483) (xy 264.59069 -325.200123)
			(xy 264.548593 -325.159899) (xy 264.513098 -325.113745) (xy 264.498582 -325.088504) (xy 264.49274 -325.077582)
			(xy 264.472674 -325.06412) (xy 264.366756 -325.050658) (xy 264.34415 -325.058786) (xy 264.335514 -325.06793)
			(xy 264.317414 -325.086492) (xy 264.277086 -325.119071) (xy 264.232715 -325.145886) (xy 264.185121 -325.166442)
			(xy 264.13518 -325.18036) (xy 264.083814 -325.187383) (xy 264.057892 -325.187818) (xy 264.028871 -325.187269)
			(xy 263.971499 -325.178476) (xy 263.916122 -325.161094) (xy 263.864016 -325.135525) (xy 263.816384 -325.102358)
			(xy 263.774326 -325.062358) (xy 263.75614 -325.039736) (xy 263.748266 -325.02983) (xy 263.725406 -325.019416)
			(xy 263.616694 -325.025766) (xy 263.595104 -325.03872) (xy 263.588754 -325.049388) (xy 263.573888 -325.073228)
			(xy 263.538214 -325.11663) (xy 263.496561 -325.154333) (xy 263.449832 -325.185522) (xy 263.399035 -325.209523)
			(xy 263.345268 -325.225818) (xy 263.289693 -325.234055) (xy 263.261602 -325.234554) (xy 263.232415 -325.234004)
			(xy 263.174722 -325.225105) (xy 263.119055 -325.207528) (xy 263.066713 -325.181684) (xy 263.018913 -325.148174)
			(xy 262.976771 -325.10778) (xy 262.95858 -325.084948) (xy 262.950452 -325.07428) (xy 262.926576 -325.063866)
			(xy 262.813546 -325.075804) (xy 262.79221 -325.09079) (xy 262.786368 -325.102982) (xy 262.774361 -325.127019)
			(xy 262.744679 -325.171803) (xy 262.709007 -325.211981) (xy 262.66805 -325.246756) (xy 262.62262 -325.27544)
			(xy 262.573615 -325.297467) (xy 262.522004 -325.3124) (xy 262.468808 -325.319945) (xy 262.441944 -325.320406)
			(xy 262.414692 -325.319904) (xy 262.360742 -325.312153) (xy 262.308445 -325.296802) (xy 262.258865 -325.274165)
			(xy 262.213012 -325.244701) (xy 262.171818 -325.209011) (xy 262.136124 -325.167822) (xy 262.106656 -325.121972)
			(xy 262.084013 -325.072394) (xy 262.068656 -325.020099) (xy 262.060899 -324.96615) (xy 262.060436 -324.938898)
			(xy 262.060903 -324.910805) (xy 262.069132 -324.855226) (xy 262.085426 -324.801455) (xy 262.109433 -324.750656)
			(xy 262.140632 -324.70393) (xy 262.17835 -324.662286) (xy 262.221769 -324.626627) (xy 262.245602 -324.611746)
			(xy 262.257286 -324.604634) (xy 262.27024 -324.581266) (xy 262.268462 -324.46595) (xy 262.254746 -324.442836)
			(xy 262.242808 -324.435978) (xy 262.217786 -324.421427) (xy 262.172076 -324.385919) (xy 262.132259 -324.34391)
			(xy 262.099249 -324.296365) (xy 262.073805 -324.244377) (xy 262.05651 -324.189141) (xy 262.047764 -324.131924)
			(xy 262.047228 -324.102984) (xy 261.599426 -324.102984) (xy 259.474208 -326.228202) (xy 259.467361 -326.2356)
			(xy 259.459626 -326.254198) (xy 259.459222 -326.26427) (xy 259.459222 -343.361264) (xy 259.451856 -343.379552)
			(xy 259.446268 -343.38514) (xy 259.446268 -347.239844) (xy 259.446698 -347.249911) (xy 259.45442 -347.268507)
			(xy 259.461254 -347.275912) (xy 260.754876 -348.569534) (xy 262.668004 -348.569534) (xy 262.668004 -340.48319)
			(xy 262.668641 -340.458208) (xy 262.678379 -340.409202) (xy 262.697479 -340.363033) (xy 262.725209 -340.32147)
			(xy 262.742426 -340.303358) (xy 266.37996 -336.665824) (xy 266.386677 -336.658362) (xy 266.394253 -336.639788)
			(xy 266.394692 -336.629756) (xy 266.394692 -332.7654) (xy 266.395308 -332.740403) (xy 266.405115 -332.691378)
			(xy 266.424295 -332.645207) (xy 266.452109 -332.603662) (xy 266.469368 -332.585568) (xy 266.926568 -332.128368)
			(xy 266.944626 -332.111067) (xy 266.98618 -332.083252) (xy 267.032363 -332.064079) (xy 267.081398 -332.054284)
			(xy 267.1064 -332.053692) (xy 267.602208 -332.053692) (xy 267.631418 -332.026514) (xy 267.632688 -332.006194)
			(xy 267.634952 -331.977469) (xy 267.647083 -331.921142) (xy 267.667547 -331.86728) (xy 267.695879 -331.817108)
			(xy 267.731435 -331.771769) (xy 267.773406 -331.732292) (xy 267.820836 -331.699578) (xy 267.872647 -331.674368)
			(xy 267.927661 -331.657239) (xy 267.984625 -331.648578) (xy 268.013434 -331.648054) (xy 268.040694 -331.648596)
			(xy 268.094658 -331.656363) (xy 268.146967 -331.671733) (xy 268.196555 -331.694394) (xy 268.242412 -331.723883)
			(xy 268.283603 -331.759601) (xy 268.319289 -331.800819) (xy 268.348744 -331.846698) (xy 268.371368 -331.896303)
			(xy 268.386698 -331.948623) (xy 268.394424 -332.002594) (xy 268.394388 -332.057114) (xy 268.38659 -332.111074)
			(xy 268.37119 -332.163374) (xy 268.3485 -332.212948) (xy 268.318984 -332.258788) (xy 268.283243 -332.299958)
			(xy 268.242004 -332.335621) (xy 268.196109 -332.36505) (xy 268.146491 -332.387644) (xy 268.094161 -332.402945)
			(xy 268.040187 -332.41064) (xy 268.012926 -332.41107) (xy 268.002512 -332.41107) (xy 267.98397 -332.41869)
			(xy 267.914628 -332.488032) (xy 267.902944 -332.498954) (xy 267.901928 -332.49997) (xy 267.900658 -332.50124)
			(xy 267.893964 -332.508691) (xy 267.886328 -332.527183) (xy 267.886323 -332.54719) (xy 267.893949 -332.565687)
			(xy 267.900658 -332.573122) (xy 267.98397 -332.656434) (xy 268.002512 -332.664054) (xy 268.012926 -332.664054)
			(xy 268.040202 -332.664489) (xy 268.094205 -332.672191) (xy 268.146562 -332.687505) (xy 268.196204 -332.71012)
			(xy 268.242118 -332.739574) (xy 268.283371 -332.775267) (xy 268.319119 -332.816471) (xy 268.348635 -332.862346)
			(xy 268.371316 -332.911958) (xy 268.386701 -332.964294) (xy 268.394475 -333.018287) (xy 268.394942 -333.045562)
			(xy 268.394413 -333.072826) (xy 268.386654 -333.126798) (xy 268.37129 -333.179116) (xy 268.348633 -333.228714)
			(xy 268.319145 -333.27458) (xy 268.283427 -333.31578) (xy 268.242207 -333.351475) (xy 268.196324 -333.380937)
			(xy 268.146714 -333.403566) (xy 268.094387 -333.4189) (xy 268.04041 -333.426628) (xy 267.985883 -333.426592)
			(xy 267.931916 -333.418792) (xy 267.87961 -333.403388) (xy 267.83003 -333.380693) (xy 267.784186 -333.35117)
			(xy 267.743013 -333.31542) (xy 267.70735 -333.274173) (xy 267.677923 -333.228267) (xy 267.655332 -333.17864)
			(xy 267.640038 -333.126301) (xy 267.632351 -333.072318) (xy 267.631926 -333.045054) (xy 267.631926 -333.03464)
			(xy 267.624306 -333.016098) (xy 267.566648 -332.95844) (xy 267.559177 -332.951733) (xy 267.54061 -332.944151)
			(xy 267.53058 -332.943708) (xy 267.410946 -332.943708) (xy 267.4009 -332.944073) (xy 267.382304 -332.951665)
			(xy 267.374878 -332.95844) (xy 267.29944 -333.033878) (xy 267.292722 -333.04134) (xy 267.285146 -333.059914)
			(xy 267.284708 -333.069946) (xy 267.284708 -336.917792) (xy 267.284087 -336.942789) (xy 267.274281 -336.991814)
			(xy 267.255104 -337.037985) (xy 267.22729 -337.079529) (xy 267.210032 -337.097624) (xy 263.572498 -340.735158)
			(xy 263.565684 -340.742578) (xy 263.557949 -340.761162) (xy 263.557512 -340.771226) (xy 263.557512 -348.285054)
			(xy 263.557959 -348.295121) (xy 263.565664 -348.313719) (xy 263.572498 -348.321122) (xy 263.622536 -348.37116)
			(xy 271.357598 -348.37116) (xy 271.358065 -348.343248) (xy 271.366205 -348.288021) (xy 271.382307 -348.23457)
			(xy 271.406025 -348.184036) (xy 271.436855 -348.137497) (xy 271.455134 -348.116398) (xy 271.461484 -348.109286)
			(xy 271.468088 -348.092014) (xy 271.468088 -348.004892) (xy 271.461484 -347.98762) (xy 271.455134 -347.980508)
			(xy 271.436828 -347.959432) (xy 271.406007 -347.912886) (xy 271.382298 -347.862345) (xy 271.366208 -347.808889)
			(xy 271.35808 -347.753659) (xy 271.357598 -347.725746) (xy 271.358084 -347.698495) (xy 271.36584 -347.644547)
			(xy 271.381195 -347.592252) (xy 271.403837 -347.542675) (xy 271.433303 -347.496825) (xy 271.468994 -347.455634)
			(xy 271.510185 -347.419943) (xy 271.556035 -347.390477) (xy 271.605612 -347.367835) (xy 271.657907 -347.35248)
			(xy 271.711855 -347.344724) (xy 271.766357 -347.344724) (xy 271.820305 -347.35248) (xy 271.8726 -347.367835)
			(xy 271.922177 -347.390477) (xy 271.968027 -347.419943) (xy 272.009218 -347.455634) (xy 272.044909 -347.496825)
			(xy 272.074375 -347.542675) (xy 272.097017 -347.592252) (xy 272.112372 -347.644547) (xy 272.120128 -347.698495)
			(xy 272.120614 -347.725746) (xy 272.120148 -347.753658) (xy 272.112007 -347.808885) (xy 272.095905 -347.862336)
			(xy 272.072186 -347.91287) (xy 272.041357 -347.959409) (xy 272.023078 -347.980508) (xy 272.016728 -347.98762)
			(xy 272.010124 -348.004892) (xy 272.010124 -348.092014) (xy 272.016728 -348.109286) (xy 272.023078 -348.116398)
			(xy 272.041326 -348.137523) (xy 272.072158 -348.184054) (xy 272.09588 -348.234582) (xy 272.111983 -348.288028)
			(xy 272.120125 -348.34325) (xy 272.120614 -348.37116) (xy 272.120614 -348.377002) (xy 272.12036 -348.39275)
			(xy 272.137124 -348.418658) (xy 272.238216 -348.46133) (xy 272.24767 -348.464934) (xy 272.267889 -348.465103)
			(xy 272.286616 -348.457477) (xy 272.294096 -348.450662) (xy 272.539206 -348.205298) (xy 272.545947 -348.197908)
			(xy 272.553657 -348.179473) (xy 272.554192 -348.169484) (xy 272.554192 -334.901286) (xy 272.54962 -334.891634)
			(xy 272.53927 -334.867127) (xy 272.524662 -334.815977) (xy 272.517301 -334.763292) (xy 272.516854 -334.736694)
			(xy 272.517303 -334.709323) (xy 272.525123 -334.655143) (xy 272.540615 -334.602639) (xy 272.563461 -334.552892)
			(xy 272.59319 -334.506927) (xy 272.610834 -334.485996) (xy 272.61693 -334.478884) (xy 272.62328 -334.461866)
			(xy 272.62328 -334.376522) (xy 272.61693 -334.359504) (xy 272.610834 -334.352392) (xy 272.593187 -334.331464)
			(xy 272.563462 -334.285496) (xy 272.540617 -334.235749) (xy 272.525121 -334.183246) (xy 272.517292 -334.129066)
			(xy 272.517293 -334.074325) (xy 272.525122 -334.020145) (xy 272.54062 -333.967643) (xy 272.563466 -333.917896)
			(xy 272.593193 -333.871929) (xy 272.610834 -333.850996) (xy 272.61693 -333.843884) (xy 272.62328 -333.826866)
			(xy 272.62328 -333.741522) (xy 272.61693 -333.724504) (xy 272.610834 -333.717392) (xy 272.593187 -333.696464)
			(xy 272.563462 -333.650496) (xy 272.540617 -333.600749) (xy 272.525121 -333.548246) (xy 272.517292 -333.494066)
			(xy 272.517293 -333.439325) (xy 272.525122 -333.385145) (xy 272.54062 -333.332643) (xy 272.563466 -333.282896)
			(xy 272.593193 -333.236929) (xy 272.610834 -333.215996) (xy 272.61693 -333.208884) (xy 272.62328 -333.191866)
			(xy 272.62328 -333.106522) (xy 272.61693 -333.089504) (xy 272.610834 -333.082392) (xy 272.593187 -333.061464)
			(xy 272.563462 -333.015496) (xy 272.540617 -332.965749) (xy 272.525121 -332.913246) (xy 272.517292 -332.859066)
			(xy 272.517293 -332.804325) (xy 272.525122 -332.750145) (xy 272.54062 -332.697643) (xy 272.563466 -332.647896)
			(xy 272.593193 -332.601929) (xy 272.610834 -332.580996) (xy 272.61693 -332.573884) (xy 272.62328 -332.556866)
			(xy 272.62328 -332.471522) (xy 272.61693 -332.454504) (xy 272.610834 -332.447392) (xy 272.593187 -332.426464)
			(xy 272.563462 -332.380496) (xy 272.540617 -332.330749) (xy 272.525121 -332.278246) (xy 272.517292 -332.224066)
			(xy 272.517293 -332.169325) (xy 272.525122 -332.115145) (xy 272.54062 -332.062643) (xy 272.563466 -332.012896)
			(xy 272.593193 -331.966929) (xy 272.610834 -331.945996) (xy 272.61693 -331.938884) (xy 272.62328 -331.921866)
			(xy 272.62328 -331.836522) (xy 272.61693 -331.819504) (xy 272.610834 -331.812392) (xy 272.593187 -331.791464)
			(xy 272.563462 -331.745496) (xy 272.540617 -331.695749) (xy 272.525121 -331.643246) (xy 272.517292 -331.589066)
			(xy 272.517293 -331.534325) (xy 272.525122 -331.480145) (xy 272.54062 -331.427643) (xy 272.563466 -331.377896)
			(xy 272.593193 -331.331929) (xy 272.610834 -331.310996) (xy 272.61693 -331.303884) (xy 272.62328 -331.286866)
			(xy 272.62328 -331.201522) (xy 272.61693 -331.184504) (xy 272.610834 -331.177392) (xy 272.593187 -331.156464)
			(xy 272.563462 -331.110496) (xy 272.540617 -331.060749) (xy 272.525121 -331.008246) (xy 272.517292 -330.954066)
			(xy 272.517293 -330.899325) (xy 272.525122 -330.845145) (xy 272.54062 -330.792643) (xy 272.563466 -330.742896)
			(xy 272.593193 -330.696929) (xy 272.610834 -330.675996) (xy 272.61693 -330.668884) (xy 272.62328 -330.651866)
			(xy 272.62328 -330.566522) (xy 272.61693 -330.549504) (xy 272.610834 -330.542392) (xy 272.593183 -330.521469)
			(xy 272.563472 -330.475495) (xy 272.540638 -330.425745) (xy 272.525149 -330.373242) (xy 272.517325 -330.319064)
			(xy 272.516854 -330.291694) (xy 272.517372 -330.264444) (xy 272.525128 -330.2105) (xy 272.540482 -330.158208)
			(xy 272.563121 -330.108633) (xy 272.592585 -330.062785) (xy 272.628273 -330.021595) (xy 272.669459 -329.985904)
			(xy 272.715305 -329.956437) (xy 272.764878 -329.933794) (xy 272.817168 -329.918435) (xy 272.871112 -329.910674)
			(xy 272.898362 -329.910186) (xy 272.925731 -329.910678) (xy 272.979909 -329.91849) (xy 273.032412 -329.933973)
			(xy 273.082159 -329.956809) (xy 273.128127 -329.986528) (xy 273.14906 -330.004166) (xy 273.156172 -330.010262)
			(xy 273.17319 -330.016612) (xy 273.258534 -330.016612) (xy 273.275552 -330.010262) (xy 273.282664 -330.004166)
			(xy 273.303597 -329.986525) (xy 273.349565 -329.956801) (xy 273.399311 -329.933955) (xy 273.451813 -329.918459)
			(xy 273.505991 -329.91063) (xy 273.560733 -329.91063) (xy 273.614911 -329.918459) (xy 273.667413 -329.933955)
			(xy 273.717159 -329.956801) (xy 273.763127 -329.986525) (xy 273.78406 -330.004166) (xy 273.791172 -330.010262)
			(xy 273.80819 -330.016612) (xy 273.893534 -330.016612) (xy 273.910552 -330.010262) (xy 273.917664 -330.004166)
			(xy 273.938594 -329.986525) (xy 273.984568 -329.956815) (xy 274.034316 -329.93398) (xy 274.086817 -329.918489)
			(xy 274.140993 -329.91066) (xy 274.168362 -329.910186) (xy 274.195614 -329.910691) (xy 274.249563 -329.918442)
			(xy 274.30186 -329.933793) (xy 274.351439 -329.956431) (xy 274.397292 -329.985894) (xy 274.438485 -330.021584)
			(xy 274.474179 -330.062773) (xy 274.503648 -330.108622) (xy 274.526291 -330.158199) (xy 274.541648 -330.210494)
			(xy 274.549406 -330.264442) (xy 274.54987 -330.291694) (xy 274.549408 -330.319064) (xy 274.54159 -330.373244)
			(xy 274.526101 -330.425747) (xy 274.503258 -330.475494) (xy 274.473532 -330.521461) (xy 274.45589 -330.542392)
			(xy 274.449794 -330.549504) (xy 274.443444 -330.566522) (xy 274.443444 -330.651866) (xy 274.449794 -330.668884)
			(xy 274.45589 -330.675996) (xy 274.473524 -330.696934) (xy 274.503248 -330.742901) (xy 274.526093 -330.792647)
			(xy 274.541589 -330.845148) (xy 274.549417 -330.899325) (xy 274.549418 -330.954066) (xy 274.54159 -331.008243)
			(xy 274.526096 -331.060745) (xy 274.503252 -331.110491) (xy 274.47353 -331.156459) (xy 274.45589 -331.177392)
			(xy 274.449794 -331.184504) (xy 274.443444 -331.201522) (xy 274.443444 -331.286866) (xy 274.449794 -331.303884)
			(xy 274.45589 -331.310996) (xy 274.473524 -331.331934) (xy 274.503248 -331.377901) (xy 274.526093 -331.427647)
			(xy 274.541589 -331.480148) (xy 274.549417 -331.534325) (xy 274.549418 -331.589066) (xy 274.54159 -331.643243)
			(xy 274.526096 -331.695745) (xy 274.503252 -331.745491) (xy 274.47353 -331.791459) (xy 274.45589 -331.812392)
			(xy 274.449794 -331.819504) (xy 274.443444 -331.836522) (xy 274.443444 -331.921866) (xy 274.449794 -331.938884)
			(xy 274.45589 -331.945996) (xy 274.473524 -331.966934) (xy 274.503248 -332.012901) (xy 274.526093 -332.062647)
			(xy 274.541589 -332.115148) (xy 274.549417 -332.169325) (xy 274.549418 -332.224066) (xy 274.54159 -332.278243)
			(xy 274.526096 -332.330745) (xy 274.503252 -332.380491) (xy 274.47353 -332.426459) (xy 274.45589 -332.447392)
			(xy 274.449794 -332.454504) (xy 274.443444 -332.471522) (xy 274.443444 -332.556866) (xy 274.449794 -332.573884)
			(xy 274.45589 -332.580996) (xy 274.473524 -332.601934) (xy 274.503248 -332.647901) (xy 274.526093 -332.697647)
			(xy 274.541589 -332.750148) (xy 274.549417 -332.804325) (xy 274.549418 -332.859066) (xy 274.54159 -332.913243)
			(xy 274.526096 -332.965745) (xy 274.503252 -333.015491) (xy 274.47353 -333.061459) (xy 274.45589 -333.082392)
			(xy 274.449794 -333.089504) (xy 274.443444 -333.106522) (xy 274.443444 -333.191866) (xy 274.449794 -333.208884)
			(xy 274.45589 -333.215996) (xy 274.473524 -333.236934) (xy 274.503248 -333.282901) (xy 274.526093 -333.332647)
			(xy 274.541589 -333.385148) (xy 274.549417 -333.439325) (xy 274.549418 -333.494066) (xy 274.54159 -333.548243)
			(xy 274.526096 -333.600745) (xy 274.503252 -333.650491) (xy 274.47353 -333.696459) (xy 274.45589 -333.717392)
			(xy 274.449794 -333.724504) (xy 274.443444 -333.741522) (xy 274.443444 -333.826866) (xy 274.449794 -333.843884)
			(xy 274.45589 -333.850996) (xy 274.473524 -333.871934) (xy 274.503248 -333.917901) (xy 274.526093 -333.967647)
			(xy 274.541589 -334.020148) (xy 274.549417 -334.074325) (xy 274.549418 -334.129066) (xy 274.54159 -334.183243)
			(xy 274.526096 -334.235745) (xy 274.503252 -334.285491) (xy 274.47353 -334.331459) (xy 274.45589 -334.352392)
			(xy 274.449794 -334.359504) (xy 274.443444 -334.376522) (xy 274.443444 -334.461866) (xy 274.449794 -334.478884)
			(xy 274.45589 -334.485996) (xy 274.473539 -334.50692) (xy 274.50325 -334.552895) (xy 274.526084 -334.602644)
			(xy 274.541573 -334.655147) (xy 274.549398 -334.709324) (xy 274.54987 -334.736694) (xy 276.530054 -334.736694)
			(xy 276.530503 -334.709323) (xy 276.538323 -334.655143) (xy 276.553815 -334.602639) (xy 276.576661 -334.552892)
			(xy 276.60639 -334.506927) (xy 276.624034 -334.485996) (xy 276.63013 -334.478884) (xy 276.63648 -334.461866)
			(xy 276.63648 -334.376522) (xy 276.63013 -334.359504) (xy 276.624034 -334.352392) (xy 276.606387 -334.331464)
			(xy 276.576662 -334.285496) (xy 276.553817 -334.235749) (xy 276.538321 -334.183246) (xy 276.530492 -334.129066)
			(xy 276.530493 -334.074325) (xy 276.538322 -334.020145) (xy 276.55382 -333.967643) (xy 276.576666 -333.917896)
			(xy 276.606393 -333.871929) (xy 276.624034 -333.850996) (xy 276.63013 -333.843884) (xy 276.63648 -333.826866)
			(xy 276.63648 -333.741522) (xy 276.63013 -333.724504) (xy 276.624034 -333.717392) (xy 276.606387 -333.696464)
			(xy 276.576662 -333.650496) (xy 276.553817 -333.600749) (xy 276.538321 -333.548246) (xy 276.530492 -333.494066)
			(xy 276.530493 -333.439325) (xy 276.538322 -333.385145) (xy 276.55382 -333.332643) (xy 276.576666 -333.282896)
			(xy 276.606393 -333.236929) (xy 276.624034 -333.215996) (xy 276.63013 -333.208884) (xy 276.63648 -333.191866)
			(xy 276.63648 -333.106522) (xy 276.63013 -333.089504) (xy 276.624034 -333.082392) (xy 276.606387 -333.061464)
			(xy 276.576662 -333.015496) (xy 276.553817 -332.965749) (xy 276.538321 -332.913246) (xy 276.530492 -332.859066)
			(xy 276.530493 -332.804325) (xy 276.538322 -332.750145) (xy 276.55382 -332.697643) (xy 276.576666 -332.647896)
			(xy 276.606393 -332.601929) (xy 276.624034 -332.580996) (xy 276.63013 -332.573884) (xy 276.63648 -332.556866)
			(xy 276.63648 -332.471522) (xy 276.63013 -332.454504) (xy 276.624034 -332.447392) (xy 276.606387 -332.426464)
			(xy 276.576662 -332.380496) (xy 276.553817 -332.330749) (xy 276.538321 -332.278246) (xy 276.530492 -332.224066)
			(xy 276.530493 -332.169325) (xy 276.538322 -332.115145) (xy 276.55382 -332.062643) (xy 276.576666 -332.012896)
			(xy 276.606393 -331.966929) (xy 276.624034 -331.945996) (xy 276.63013 -331.938884) (xy 276.63648 -331.921866)
			(xy 276.63648 -331.836522) (xy 276.63013 -331.819504) (xy 276.624034 -331.812392) (xy 276.606387 -331.791464)
			(xy 276.576662 -331.745496) (xy 276.553817 -331.695749) (xy 276.538321 -331.643246) (xy 276.530492 -331.589066)
			(xy 276.530493 -331.534325) (xy 276.538322 -331.480145) (xy 276.55382 -331.427643) (xy 276.576666 -331.377896)
			(xy 276.606393 -331.331929) (xy 276.624034 -331.310996) (xy 276.63013 -331.303884) (xy 276.63648 -331.286866)
			(xy 276.63648 -331.201522) (xy 276.63013 -331.184504) (xy 276.624034 -331.177392) (xy 276.606387 -331.156464)
			(xy 276.576662 -331.110496) (xy 276.553817 -331.060749) (xy 276.538321 -331.008246) (xy 276.530492 -330.954066)
			(xy 276.530493 -330.899325) (xy 276.538322 -330.845145) (xy 276.55382 -330.792643) (xy 276.576666 -330.742896)
			(xy 276.606393 -330.696929) (xy 276.624034 -330.675996) (xy 276.63013 -330.668884) (xy 276.63648 -330.651866)
			(xy 276.63648 -330.566522) (xy 276.63013 -330.549504) (xy 276.624034 -330.542392) (xy 276.606383 -330.521469)
			(xy 276.576672 -330.475495) (xy 276.553838 -330.425745) (xy 276.538349 -330.373242) (xy 276.530525 -330.319064)
			(xy 276.530054 -330.291694) (xy 276.530572 -330.264444) (xy 276.538328 -330.2105) (xy 276.553682 -330.158208)
			(xy 276.576321 -330.108633) (xy 276.605785 -330.062785) (xy 276.641473 -330.021595) (xy 276.682659 -329.985904)
			(xy 276.728505 -329.956437) (xy 276.778078 -329.933794) (xy 276.830368 -329.918435) (xy 276.884312 -329.910674)
			(xy 276.911562 -329.910186) (xy 276.938931 -329.910678) (xy 276.993109 -329.91849) (xy 277.045612 -329.933973)
			(xy 277.095359 -329.956809) (xy 277.141327 -329.986528) (xy 277.16226 -330.004166) (xy 277.169372 -330.010262)
			(xy 277.18639 -330.016612) (xy 277.271734 -330.016612) (xy 277.288752 -330.010262) (xy 277.295864 -330.004166)
			(xy 277.316797 -329.986525) (xy 277.362765 -329.956801) (xy 277.412511 -329.933955) (xy 277.465013 -329.918459)
			(xy 277.519191 -329.91063) (xy 277.573933 -329.91063) (xy 277.628111 -329.918459) (xy 277.680613 -329.933955)
			(xy 277.730359 -329.956801) (xy 277.776327 -329.986525) (xy 277.79726 -330.004166) (xy 277.804372 -330.010262)
			(xy 277.82139 -330.016612) (xy 277.906734 -330.016612) (xy 277.923752 -330.010262) (xy 277.930864 -330.004166)
			(xy 277.951794 -329.986525) (xy 277.997768 -329.956815) (xy 278.047516 -329.93398) (xy 278.100017 -329.918489)
			(xy 278.154193 -329.91066) (xy 278.181562 -329.910186) (xy 278.208814 -329.910691) (xy 278.262763 -329.918442)
			(xy 278.31506 -329.933793) (xy 278.364639 -329.956431) (xy 278.410492 -329.985894) (xy 278.451685 -330.021584)
			(xy 278.487379 -330.062773) (xy 278.516848 -330.108622) (xy 278.539491 -330.158199) (xy 278.554848 -330.210494)
			(xy 278.562606 -330.264442) (xy 278.56307 -330.291694) (xy 278.562608 -330.319064) (xy 278.55479 -330.373244)
			(xy 278.539301 -330.425747) (xy 278.516458 -330.475494) (xy 278.486732 -330.521461) (xy 278.46909 -330.542392)
			(xy 278.462994 -330.549504) (xy 278.456644 -330.566522) (xy 278.456644 -330.651866) (xy 278.462994 -330.668884)
			(xy 278.46909 -330.675996) (xy 278.486724 -330.696934) (xy 278.516448 -330.742901) (xy 278.539293 -330.792647)
			(xy 278.554789 -330.845148) (xy 278.562617 -330.899325) (xy 278.562618 -330.954066) (xy 278.55479 -331.008243)
			(xy 278.539296 -331.060745) (xy 278.516452 -331.110491) (xy 278.48673 -331.156459) (xy 278.46909 -331.177392)
			(xy 278.462994 -331.184504) (xy 278.456644 -331.201522) (xy 278.456644 -331.286866) (xy 278.462994 -331.303884)
			(xy 278.46909 -331.310996) (xy 278.486724 -331.331934) (xy 278.516448 -331.377901) (xy 278.539293 -331.427647)
			(xy 278.554789 -331.480148) (xy 278.562617 -331.534325) (xy 278.562618 -331.589066) (xy 278.55479 -331.643243)
			(xy 278.539296 -331.695745) (xy 278.516452 -331.745491) (xy 278.48673 -331.791459) (xy 278.46909 -331.812392)
			(xy 278.462994 -331.819504) (xy 278.456644 -331.836522) (xy 278.456644 -331.921866) (xy 278.462994 -331.938884)
			(xy 278.46909 -331.945996) (xy 278.486724 -331.966934) (xy 278.516448 -332.012901) (xy 278.539293 -332.062647)
			(xy 278.554789 -332.115148) (xy 278.562617 -332.169325) (xy 278.562618 -332.224066) (xy 278.55479 -332.278243)
			(xy 278.539296 -332.330745) (xy 278.516452 -332.380491) (xy 278.48673 -332.426459) (xy 278.46909 -332.447392)
			(xy 278.462994 -332.454504) (xy 278.456644 -332.471522) (xy 278.456644 -332.556866) (xy 278.462994 -332.573884)
			(xy 278.46909 -332.580996) (xy 278.486724 -332.601934) (xy 278.516448 -332.647901) (xy 278.539293 -332.697647)
			(xy 278.554789 -332.750148) (xy 278.562617 -332.804325) (xy 278.562618 -332.859066) (xy 278.55479 -332.913243)
			(xy 278.539296 -332.965745) (xy 278.516452 -333.015491) (xy 278.48673 -333.061459) (xy 278.46909 -333.082392)
			(xy 278.462994 -333.089504) (xy 278.456644 -333.106522) (xy 278.456644 -333.191866) (xy 278.462994 -333.208884)
			(xy 278.46909 -333.215996) (xy 278.486724 -333.236934) (xy 278.516448 -333.282901) (xy 278.539293 -333.332647)
			(xy 278.554789 -333.385148) (xy 278.562617 -333.439325) (xy 278.562618 -333.494066) (xy 278.55479 -333.548243)
			(xy 278.539296 -333.600745) (xy 278.516452 -333.650491) (xy 278.48673 -333.696459) (xy 278.46909 -333.717392)
			(xy 278.462994 -333.724504) (xy 278.456644 -333.741522) (xy 278.456644 -333.826866) (xy 278.462994 -333.843884)
			(xy 278.46909 -333.850996) (xy 278.486724 -333.871934) (xy 278.516448 -333.917901) (xy 278.539293 -333.967647)
			(xy 278.554789 -334.020148) (xy 278.562617 -334.074325) (xy 278.562618 -334.129066) (xy 278.55479 -334.183243)
			(xy 278.539296 -334.235745) (xy 278.516452 -334.285491) (xy 278.48673 -334.331459) (xy 278.46909 -334.352392)
			(xy 278.462994 -334.359504) (xy 278.456644 -334.376522) (xy 278.456644 -334.461866) (xy 278.462994 -334.478884)
			(xy 278.46909 -334.485996) (xy 278.486739 -334.50692) (xy 278.51645 -334.552895) (xy 278.539284 -334.602644)
			(xy 278.554773 -334.655147) (xy 278.562598 -334.709324) (xy 278.56307 -334.736694) (xy 278.562639 -334.763948)
			(xy 278.554882 -334.817902) (xy 278.539525 -334.870203) (xy 278.51688 -334.919786) (xy 278.487409 -334.965641)
			(xy 278.451712 -335.006835) (xy 278.410515 -335.042528) (xy 278.364658 -335.071995) (xy 278.315073 -335.094636)
			(xy 278.262771 -335.109989) (xy 278.208816 -335.117741) (xy 278.181562 -335.118202) (xy 278.154193 -335.117699)
			(xy 278.100016 -335.10989) (xy 278.047513 -335.09441) (xy 277.997765 -335.071576) (xy 277.951797 -335.041859)
			(xy 277.930864 -335.024222) (xy 277.923752 -335.018126) (xy 277.906734 -335.011776) (xy 277.82139 -335.011776)
			(xy 277.804372 -335.018126) (xy 277.79726 -335.024222) (xy 277.776327 -335.041863) (xy 277.730359 -335.071587)
			(xy 277.680613 -335.094433) (xy 277.628111 -335.109929) (xy 277.573933 -335.117758) (xy 277.519191 -335.117758)
			(xy 277.465013 -335.109929) (xy 277.412511 -335.094433) (xy 277.362765 -335.071587) (xy 277.316797 -335.041863)
			(xy 277.295864 -335.024222) (xy 277.288752 -335.018126) (xy 277.271734 -335.011776) (xy 277.18639 -335.011776)
			(xy 277.169372 -335.018126) (xy 277.16226 -335.024222) (xy 277.141319 -335.04185) (xy 277.095348 -335.071563)
			(xy 277.045603 -335.0944) (xy 276.993104 -335.109894) (xy 276.93893 -335.117726) (xy 276.911562 -335.118202)
			(xy 276.88431 -335.117758) (xy 276.83036 -335.109996) (xy 276.778064 -335.094635) (xy 276.728486 -335.071989)
			(xy 276.682636 -335.042519) (xy 276.641446 -335.006823) (xy 276.605755 -334.965629) (xy 276.576289 -334.919775)
			(xy 276.553649 -334.870195) (xy 276.538295 -334.817897) (xy 276.530539 -334.763947) (xy 276.530054 -334.736694)
			(xy 274.54987 -334.736694) (xy 274.549439 -334.763948) (xy 274.541682 -334.817902) (xy 274.526325 -334.870203)
			(xy 274.50368 -334.919786) (xy 274.474209 -334.965641) (xy 274.438512 -335.006835) (xy 274.397315 -335.042528)
			(xy 274.351458 -335.071995) (xy 274.301873 -335.094636) (xy 274.249571 -335.109989) (xy 274.195616 -335.117741)
			(xy 274.168362 -335.118202) (xy 274.140993 -335.117699) (xy 274.086816 -335.10989) (xy 274.034313 -335.09441)
			(xy 273.984565 -335.071576) (xy 273.938597 -335.041859) (xy 273.917664 -335.024222) (xy 273.910552 -335.018126)
			(xy 273.893534 -335.011776) (xy 273.80819 -335.011776) (xy 273.791172 -335.018126) (xy 273.78406 -335.024222)
			(xy 273.763119 -335.04185) (xy 273.717148 -335.071563) (xy 273.667403 -335.0944) (xy 273.614904 -335.109894)
			(xy 273.56073 -335.117726) (xy 273.533362 -335.118202) (xy 273.508344 -335.117797) (xy 273.458739 -335.111249)
			(xy 273.410415 -335.098271) (xy 273.364204 -335.079085) (xy 273.342354 -335.066894) (xy 273.330416 -335.060036)
			(xy 273.303492 -335.060036) (xy 273.215354 -335.110836) (xy 273.207823 -335.115597) (xy 273.196318 -335.129183)
			(xy 273.190139 -335.145879) (xy 273.1897 -335.154778) (xy 273.1897 -348.322138) (xy 273.189213 -348.347113)
			(xy 273.181426 -348.396451) (xy 273.166019 -348.443964) (xy 273.14337 -348.488482) (xy 273.114037 -348.52891)
			(xy 273.096736 -348.546928) (xy 272.938964 -348.7047) (xy 275.739821 -348.7047) (xy 275.743989 -348.649082)
			(xy 275.7564 -348.594706) (xy 275.776776 -348.542788) (xy 275.804662 -348.494485) (xy 275.839436 -348.450879)
			(xy 275.880321 -348.412942) (xy 275.926403 -348.381523) (xy 275.976653 -348.357322) (xy 276.029948 -348.340881)
			(xy 276.085099 -348.332566) (xy 276.112986 -348.332044) (xy 276.139407 -348.332523) (xy 276.191721 -348.33997)
			(xy 276.242459 -348.354731) (xy 276.290603 -348.376509) (xy 276.33519 -348.404869) (xy 276.355556 -348.421706)
			(xy 276.362414 -348.427802) (xy 276.379432 -348.433898) (xy 276.46376 -348.433898) (xy 276.480778 -348.427802)
			(xy 276.487636 -348.421706) (xy 276.508002 -348.404867) (xy 276.552588 -348.376502) (xy 276.600732 -348.354715)
			(xy 276.651469 -348.339944) (xy 276.703784 -348.332484) (xy 276.756628 -348.332484) (xy 276.808943 -348.339944)
			(xy 276.85968 -348.354715) (xy 276.907824 -348.376502) (xy 276.95241 -348.404867) (xy 276.972776 -348.421706)
			(xy 276.979634 -348.427802) (xy 276.996652 -348.433898) (xy 277.08098 -348.433898) (xy 277.097998 -348.427802)
			(xy 277.104856 -348.421706) (xy 277.128853 -348.401962) (xy 277.182096 -348.369922) (xy 277.210774 -348.357952)
			(xy 277.221188 -348.353888) (xy 277.236428 -348.33814) (xy 277.269448 -348.244668) (xy 277.267416 -348.223078)
			(xy 277.261828 -348.213426) (xy 277.250031 -348.191825) (xy 277.231486 -348.146234) (xy 277.218961 -348.098636)
			(xy 277.212665 -348.049822) (xy 277.212298 -348.025212) (xy 277.212773 -347.997638) (xy 277.220723 -347.943065)
			(xy 277.236447 -347.890206) (xy 277.259615 -347.84016) (xy 277.289746 -347.79397) (xy 277.326212 -347.752598)
			(xy 277.346918 -347.734382) (xy 277.355043 -347.726785) (xy 277.364393 -347.706629) (xy 277.364952 -347.69552)
			(xy 277.364952 -347.618304) (xy 277.364413 -347.60719) (xy 277.355056 -347.587031) (xy 277.346918 -347.579442)
			(xy 277.326228 -347.561208) (xy 277.289755 -347.519845) (xy 277.25962 -347.47366) (xy 277.23645 -347.423616)
			(xy 277.22073 -347.370757) (xy 277.212786 -347.316185) (xy 277.212298 -347.288612) (xy 277.212784 -347.261361)
			(xy 277.22054 -347.207413) (xy 277.235895 -347.155118) (xy 277.258537 -347.105541) (xy 277.288003 -347.059691)
			(xy 277.323694 -347.0185) (xy 277.364885 -346.982809) (xy 277.410735 -346.953343) (xy 277.460312 -346.930701)
			(xy 277.512607 -346.915346) (xy 277.566555 -346.90759) (xy 277.621057 -346.90759) (xy 277.675005 -346.915346)
			(xy 277.7273 -346.930701) (xy 277.776877 -346.953343) (xy 277.822727 -346.982809) (xy 277.863918 -347.0185)
			(xy 277.899609 -347.059691) (xy 277.929075 -347.105541) (xy 277.951717 -347.155118) (xy 277.967072 -347.207413)
			(xy 277.974828 -347.261361) (xy 277.975314 -347.288612) (xy 277.974783 -347.316184) (xy 277.966843 -347.370754)
			(xy 277.951131 -347.423612) (xy 277.927973 -347.473658) (xy 277.897852 -347.51985) (xy 277.861396 -347.561224)
			(xy 277.840694 -347.579442) (xy 277.83256 -347.587031) (xy 277.823215 -347.607193) (xy 277.82266 -347.618304)
			(xy 277.82266 -347.69552) (xy 277.823182 -347.706636) (xy 277.832551 -347.726795) (xy 277.840694 -347.734382)
			(xy 277.861398 -347.7526) (xy 277.89787 -347.793967) (xy 277.928003 -347.840156) (xy 277.95117 -347.890202)
			(xy 277.966887 -347.943064) (xy 277.974828 -347.997638) (xy 277.975314 -348.025212) (xy 277.974776 -348.054113)
			(xy 277.966042 -348.111252) (xy 277.948791 -348.16642) (xy 277.923417 -348.218355) (xy 277.890501 -348.265869)
			(xy 277.850796 -348.307877) (xy 277.80521 -348.343415) (xy 277.755699 -348.37116) (xy 279.637998 -348.37116)
			(xy 279.638465 -348.343248) (xy 279.646605 -348.288021) (xy 279.662707 -348.23457) (xy 279.686425 -348.184036)
			(xy 279.717255 -348.137497) (xy 279.735534 -348.116398) (xy 279.741884 -348.109286) (xy 279.748488 -348.092014)
			(xy 279.748488 -348.004892) (xy 279.741884 -347.98762) (xy 279.735534 -347.980508) (xy 279.717228 -347.959432)
			(xy 279.686407 -347.912886) (xy 279.662698 -347.862345) (xy 279.646608 -347.808889) (xy 279.63848 -347.753659)
			(xy 279.637998 -347.725746) (xy 279.638484 -347.698495) (xy 279.64624 -347.644547) (xy 279.661595 -347.592252)
			(xy 279.684237 -347.542675) (xy 279.713703 -347.496825) (xy 279.749394 -347.455634) (xy 279.790585 -347.419943)
			(xy 279.836435 -347.390477) (xy 279.886012 -347.367835) (xy 279.938307 -347.35248) (xy 279.992255 -347.344724)
			(xy 280.046757 -347.344724) (xy 280.100705 -347.35248) (xy 280.153 -347.367835) (xy 280.202577 -347.390477)
			(xy 280.248427 -347.419943) (xy 280.289618 -347.455634) (xy 280.325309 -347.496825) (xy 280.354775 -347.542675)
			(xy 280.377417 -347.592252) (xy 280.392772 -347.644547) (xy 280.400528 -347.698495) (xy 280.401014 -347.725746)
			(xy 280.400548 -347.753658) (xy 280.392407 -347.808885) (xy 280.376305 -347.862336) (xy 280.352586 -347.91287)
			(xy 280.321757 -347.959409) (xy 280.303478 -347.980508) (xy 280.297128 -347.98762) (xy 280.290524 -348.004892)
			(xy 280.290524 -348.092014) (xy 280.297128 -348.109286) (xy 280.303478 -348.116398) (xy 280.32086 -348.136421)
			(xy 280.350462 -348.180412) (xy 280.373686 -348.228079) (xy 280.390083 -348.278503) (xy 280.399338 -348.330713)
			(xy 280.40076 -348.35719) (xy 280.401268 -348.37243) (xy 280.418794 -348.397068) (xy 280.519632 -348.436692)
			(xy 280.528971 -348.439908) (xy 280.548703 -348.439737) (xy 280.566916 -348.432141) (xy 280.574242 -348.425516)
			(xy 280.819606 -348.179898) (xy 280.826347 -348.172508) (xy 280.834057 -348.154073) (xy 280.834592 -348.144084)
			(xy 280.834592 -334.901286) (xy 280.83002 -334.891634) (xy 280.81967 -334.867127) (xy 280.805062 -334.815977)
			(xy 280.797701 -334.763292) (xy 280.797254 -334.736694) (xy 280.797703 -334.709323) (xy 280.805523 -334.655143)
			(xy 280.821015 -334.602639) (xy 280.843861 -334.552892) (xy 280.87359 -334.506927) (xy 280.891234 -334.485996)
			(xy 280.89733 -334.478884) (xy 280.90368 -334.461866) (xy 280.90368 -334.376522) (xy 280.89733 -334.359504)
			(xy 280.891234 -334.352392) (xy 280.873587 -334.331464) (xy 280.843862 -334.285496) (xy 280.821017 -334.235749)
			(xy 280.805521 -334.183246) (xy 280.797692 -334.129066) (xy 280.797693 -334.074325) (xy 280.805522 -334.020145)
			(xy 280.82102 -333.967643) (xy 280.843866 -333.917896) (xy 280.873593 -333.871929) (xy 280.891234 -333.850996)
			(xy 280.89733 -333.843884) (xy 280.90368 -333.826866) (xy 280.90368 -333.741522) (xy 280.89733 -333.724504)
			(xy 280.891234 -333.717392) (xy 280.873587 -333.696464) (xy 280.843862 -333.650496) (xy 280.821017 -333.600749)
			(xy 280.805521 -333.548246) (xy 280.797692 -333.494066) (xy 280.797693 -333.439325) (xy 280.805522 -333.385145)
			(xy 280.82102 -333.332643) (xy 280.843866 -333.282896) (xy 280.873593 -333.236929) (xy 280.891234 -333.215996)
			(xy 280.89733 -333.208884) (xy 280.90368 -333.191866) (xy 280.90368 -333.106522) (xy 280.89733 -333.089504)
			(xy 280.891234 -333.082392) (xy 280.873587 -333.061464) (xy 280.843862 -333.015496) (xy 280.821017 -332.965749)
			(xy 280.805521 -332.913246) (xy 280.797692 -332.859066) (xy 280.797693 -332.804325) (xy 280.805522 -332.750145)
			(xy 280.82102 -332.697643) (xy 280.843866 -332.647896) (xy 280.873593 -332.601929) (xy 280.891234 -332.580996)
			(xy 280.89733 -332.573884) (xy 280.90368 -332.556866) (xy 280.90368 -332.471522) (xy 280.89733 -332.454504)
			(xy 280.891234 -332.447392) (xy 280.873587 -332.426464) (xy 280.843862 -332.380496) (xy 280.821017 -332.330749)
			(xy 280.805521 -332.278246) (xy 280.797692 -332.224066) (xy 280.797693 -332.169325) (xy 280.805522 -332.115145)
			(xy 280.82102 -332.062643) (xy 280.843866 -332.012896) (xy 280.873593 -331.966929) (xy 280.891234 -331.945996)
			(xy 280.89733 -331.938884) (xy 280.90368 -331.921866) (xy 280.90368 -331.836522) (xy 280.89733 -331.819504)
			(xy 280.891234 -331.812392) (xy 280.873587 -331.791464) (xy 280.843862 -331.745496) (xy 280.821017 -331.695749)
			(xy 280.805521 -331.643246) (xy 280.797692 -331.589066) (xy 280.797693 -331.534325) (xy 280.805522 -331.480145)
			(xy 280.82102 -331.427643) (xy 280.843866 -331.377896) (xy 280.873593 -331.331929) (xy 280.891234 -331.310996)
			(xy 280.89733 -331.303884) (xy 280.90368 -331.286866) (xy 280.90368 -331.201522) (xy 280.89733 -331.184504)
			(xy 280.891234 -331.177392) (xy 280.873587 -331.156464) (xy 280.843862 -331.110496) (xy 280.821017 -331.060749)
			(xy 280.805521 -331.008246) (xy 280.797692 -330.954066) (xy 280.797693 -330.899325) (xy 280.805522 -330.845145)
			(xy 280.82102 -330.792643) (xy 280.843866 -330.742896) (xy 280.873593 -330.696929) (xy 280.891234 -330.675996)
			(xy 280.89733 -330.668884) (xy 280.90368 -330.651866) (xy 280.90368 -330.566522) (xy 280.89733 -330.549504)
			(xy 280.891234 -330.542392) (xy 280.873583 -330.521469) (xy 280.843872 -330.475495) (xy 280.821038 -330.425745)
			(xy 280.805549 -330.373242) (xy 280.797725 -330.319064) (xy 280.797254 -330.291694) (xy 280.797772 -330.264444)
			(xy 280.805528 -330.2105) (xy 280.820882 -330.158208) (xy 280.843521 -330.108633) (xy 280.872985 -330.062785)
			(xy 280.908673 -330.021595) (xy 280.949859 -329.985904) (xy 280.995705 -329.956437) (xy 281.045278 -329.933794)
			(xy 281.097568 -329.918435) (xy 281.151512 -329.910674) (xy 281.178762 -329.910186) (xy 281.206131 -329.910678)
			(xy 281.260309 -329.91849) (xy 281.312812 -329.933973) (xy 281.362559 -329.956809) (xy 281.408527 -329.986528)
			(xy 281.42946 -330.004166) (xy 281.436572 -330.010262) (xy 281.45359 -330.016612) (xy 281.538934 -330.016612)
			(xy 281.555952 -330.010262) (xy 281.563064 -330.004166) (xy 281.583997 -329.986525) (xy 281.629965 -329.956801)
			(xy 281.679711 -329.933955) (xy 281.732213 -329.918459) (xy 281.786391 -329.91063) (xy 281.841133 -329.91063)
			(xy 281.895311 -329.918459) (xy 281.947813 -329.933955) (xy 281.997559 -329.956801) (xy 282.043527 -329.986525)
			(xy 282.06446 -330.004166) (xy 282.071572 -330.010262) (xy 282.08859 -330.016612) (xy 282.173934 -330.016612)
			(xy 282.190952 -330.010262) (xy 282.198064 -330.004166) (xy 282.218994 -329.986525) (xy 282.264968 -329.956815)
			(xy 282.314716 -329.93398) (xy 282.367217 -329.918489) (xy 282.421393 -329.91066) (xy 282.448762 -329.910186)
			(xy 282.476014 -329.910691) (xy 282.529963 -329.918442) (xy 282.58226 -329.933793) (xy 282.631839 -329.956431)
			(xy 282.677692 -329.985894) (xy 282.718885 -330.021584) (xy 282.754579 -330.062773) (xy 282.784048 -330.108622)
			(xy 282.806691 -330.158199) (xy 282.822048 -330.210494) (xy 282.829806 -330.264442) (xy 282.83027 -330.291694)
			(xy 282.829808 -330.319064) (xy 282.82199 -330.373244) (xy 282.806501 -330.425747) (xy 282.783658 -330.475494)
			(xy 282.753932 -330.521461) (xy 282.73629 -330.542392) (xy 282.730194 -330.549504) (xy 282.723844 -330.566522)
			(xy 282.723844 -330.651866) (xy 282.730194 -330.668884) (xy 282.73629 -330.675996) (xy 282.753924 -330.696934)
			(xy 282.783648 -330.742901) (xy 282.806493 -330.792647) (xy 282.821989 -330.845148) (xy 282.829817 -330.899325)
			(xy 282.829818 -330.954066) (xy 282.82199 -331.008243) (xy 282.806496 -331.060745) (xy 282.783652 -331.110491)
			(xy 282.75393 -331.156459) (xy 282.73629 -331.177392) (xy 282.730194 -331.184504) (xy 282.723844 -331.201522)
			(xy 282.723844 -331.286866) (xy 282.730194 -331.303884) (xy 282.73629 -331.310996) (xy 282.753924 -331.331934)
			(xy 282.783648 -331.377901) (xy 282.806493 -331.427647) (xy 282.821989 -331.480148) (xy 282.829817 -331.534325)
			(xy 282.829818 -331.589066) (xy 282.82199 -331.643243) (xy 282.806496 -331.695745) (xy 282.783652 -331.745491)
			(xy 282.75393 -331.791459) (xy 282.73629 -331.812392) (xy 282.730194 -331.819504) (xy 282.723844 -331.836522)
			(xy 282.723844 -331.921866) (xy 282.730194 -331.938884) (xy 282.73629 -331.945996) (xy 282.753924 -331.966934)
			(xy 282.783648 -332.012901) (xy 282.806493 -332.062647) (xy 282.821989 -332.115148) (xy 282.829817 -332.169325)
			(xy 282.829818 -332.224066) (xy 282.82199 -332.278243) (xy 282.806496 -332.330745) (xy 282.783652 -332.380491)
			(xy 282.75393 -332.426459) (xy 282.73629 -332.447392) (xy 282.730194 -332.454504) (xy 282.723844 -332.471522)
			(xy 282.723844 -332.556866) (xy 282.730194 -332.573884) (xy 282.73629 -332.580996) (xy 282.753924 -332.601934)
			(xy 282.783648 -332.647901) (xy 282.806493 -332.697647) (xy 282.821989 -332.750148) (xy 282.829817 -332.804325)
			(xy 282.829818 -332.859066) (xy 282.82199 -332.913243) (xy 282.806496 -332.965745) (xy 282.783652 -333.015491)
			(xy 282.75393 -333.061459) (xy 282.73629 -333.082392) (xy 282.730194 -333.089504) (xy 282.723844 -333.106522)
			(xy 282.723844 -333.191866) (xy 282.730194 -333.208884) (xy 282.73629 -333.215996) (xy 282.753924 -333.236934)
			(xy 282.783648 -333.282901) (xy 282.806493 -333.332647) (xy 282.821989 -333.385148) (xy 282.829817 -333.439325)
			(xy 282.829818 -333.494066) (xy 282.82199 -333.548243) (xy 282.806496 -333.600745) (xy 282.783652 -333.650491)
			(xy 282.75393 -333.696459) (xy 282.73629 -333.717392) (xy 282.730194 -333.724504) (xy 282.723844 -333.741522)
			(xy 282.723844 -333.826866) (xy 282.730194 -333.843884) (xy 282.73629 -333.850996) (xy 282.753924 -333.871934)
			(xy 282.783648 -333.917901) (xy 282.806493 -333.967647) (xy 282.821989 -334.020148) (xy 282.829817 -334.074325)
			(xy 282.829818 -334.129066) (xy 282.82199 -334.183243) (xy 282.806496 -334.235745) (xy 282.783652 -334.285491)
			(xy 282.75393 -334.331459) (xy 282.73629 -334.352392) (xy 282.730194 -334.359504) (xy 282.723844 -334.376522)
			(xy 282.723844 -334.461866) (xy 282.730194 -334.478884) (xy 282.73629 -334.485996) (xy 282.753939 -334.50692)
			(xy 282.78365 -334.552895) (xy 282.806484 -334.602644) (xy 282.821973 -334.655147) (xy 282.829798 -334.709324)
			(xy 282.83027 -334.736694) (xy 284.810454 -334.736694) (xy 284.810903 -334.709323) (xy 284.818723 -334.655143)
			(xy 284.834215 -334.602639) (xy 284.857061 -334.552892) (xy 284.88679 -334.506927) (xy 284.904434 -334.485996)
			(xy 284.91053 -334.478884) (xy 284.91688 -334.461866) (xy 284.91688 -334.376522) (xy 284.91053 -334.359504)
			(xy 284.904434 -334.352392) (xy 284.886787 -334.331464) (xy 284.857062 -334.285496) (xy 284.834217 -334.235749)
			(xy 284.818721 -334.183246) (xy 284.810892 -334.129066) (xy 284.810893 -334.074325) (xy 284.818722 -334.020145)
			(xy 284.83422 -333.967643) (xy 284.857066 -333.917896) (xy 284.886793 -333.871929) (xy 284.904434 -333.850996)
			(xy 284.91053 -333.843884) (xy 284.91688 -333.826866) (xy 284.91688 -333.741522) (xy 284.91053 -333.724504)
			(xy 284.904434 -333.717392) (xy 284.886787 -333.696464) (xy 284.857062 -333.650496) (xy 284.834217 -333.600749)
			(xy 284.818721 -333.548246) (xy 284.810892 -333.494066) (xy 284.810893 -333.439325) (xy 284.818722 -333.385145)
			(xy 284.83422 -333.332643) (xy 284.857066 -333.282896) (xy 284.886793 -333.236929) (xy 284.904434 -333.215996)
			(xy 284.91053 -333.208884) (xy 284.91688 -333.191866) (xy 284.91688 -333.106522) (xy 284.91053 -333.089504)
			(xy 284.904434 -333.082392) (xy 284.886787 -333.061464) (xy 284.857062 -333.015496) (xy 284.834217 -332.965749)
			(xy 284.818721 -332.913246) (xy 284.810892 -332.859066) (xy 284.810893 -332.804325) (xy 284.818722 -332.750145)
			(xy 284.83422 -332.697643) (xy 284.857066 -332.647896) (xy 284.886793 -332.601929) (xy 284.904434 -332.580996)
			(xy 284.91053 -332.573884) (xy 284.91688 -332.556866) (xy 284.91688 -332.471522) (xy 284.91053 -332.454504)
			(xy 284.904434 -332.447392) (xy 284.886787 -332.426464) (xy 284.857062 -332.380496) (xy 284.834217 -332.330749)
			(xy 284.818721 -332.278246) (xy 284.810892 -332.224066) (xy 284.810893 -332.169325) (xy 284.818722 -332.115145)
			(xy 284.83422 -332.062643) (xy 284.857066 -332.012896) (xy 284.886793 -331.966929) (xy 284.904434 -331.945996)
			(xy 284.91053 -331.938884) (xy 284.91688 -331.921866) (xy 284.91688 -331.836522) (xy 284.91053 -331.819504)
			(xy 284.904434 -331.812392) (xy 284.886787 -331.791464) (xy 284.857062 -331.745496) (xy 284.834217 -331.695749)
			(xy 284.818721 -331.643246) (xy 284.810892 -331.589066) (xy 284.810893 -331.534325) (xy 284.818722 -331.480145)
			(xy 284.83422 -331.427643) (xy 284.857066 -331.377896) (xy 284.886793 -331.331929) (xy 284.904434 -331.310996)
			(xy 284.91053 -331.303884) (xy 284.91688 -331.286866) (xy 284.91688 -331.201522) (xy 284.91053 -331.184504)
			(xy 284.904434 -331.177392) (xy 284.886787 -331.156464) (xy 284.857062 -331.110496) (xy 284.834217 -331.060749)
			(xy 284.818721 -331.008246) (xy 284.810892 -330.954066) (xy 284.810893 -330.899325) (xy 284.818722 -330.845145)
			(xy 284.83422 -330.792643) (xy 284.857066 -330.742896) (xy 284.886793 -330.696929) (xy 284.904434 -330.675996)
			(xy 284.91053 -330.668884) (xy 284.91688 -330.651866) (xy 284.91688 -330.566522) (xy 284.91053 -330.549504)
			(xy 284.904434 -330.542392) (xy 284.886783 -330.521469) (xy 284.857072 -330.475495) (xy 284.834238 -330.425745)
			(xy 284.818749 -330.373242) (xy 284.810925 -330.319064) (xy 284.810454 -330.291694) (xy 284.810972 -330.264444)
			(xy 284.818728 -330.2105) (xy 284.834082 -330.158208) (xy 284.856721 -330.108633) (xy 284.886185 -330.062785)
			(xy 284.921873 -330.021595) (xy 284.963059 -329.985904) (xy 285.008905 -329.956437) (xy 285.058478 -329.933794)
			(xy 285.110768 -329.918435) (xy 285.164712 -329.910674) (xy 285.191962 -329.910186) (xy 285.219331 -329.910678)
			(xy 285.273509 -329.91849) (xy 285.326012 -329.933973) (xy 285.375759 -329.956809) (xy 285.421727 -329.986528)
			(xy 285.44266 -330.004166) (xy 285.449772 -330.010262) (xy 285.46679 -330.016612) (xy 285.552134 -330.016612)
			(xy 285.569152 -330.010262) (xy 285.576264 -330.004166) (xy 285.597197 -329.986525) (xy 285.643165 -329.956801)
			(xy 285.692911 -329.933955) (xy 285.745413 -329.918459) (xy 285.799591 -329.91063) (xy 285.854333 -329.91063)
			(xy 285.908511 -329.918459) (xy 285.961013 -329.933955) (xy 286.010759 -329.956801) (xy 286.056727 -329.986525)
			(xy 286.07766 -330.004166) (xy 286.084772 -330.010262) (xy 286.10179 -330.016612) (xy 286.187134 -330.016612)
			(xy 286.204152 -330.010262) (xy 286.211264 -330.004166) (xy 286.232194 -329.986525) (xy 286.278168 -329.956815)
			(xy 286.327916 -329.93398) (xy 286.380417 -329.918489) (xy 286.434593 -329.91066) (xy 286.461962 -329.910186)
			(xy 286.489214 -329.910691) (xy 286.543163 -329.918442) (xy 286.59546 -329.933793) (xy 286.645039 -329.956431)
			(xy 286.690892 -329.985894) (xy 286.732085 -330.021584) (xy 286.767779 -330.062773) (xy 286.797248 -330.108622)
			(xy 286.819891 -330.158199) (xy 286.835248 -330.210494) (xy 286.843006 -330.264442) (xy 286.84347 -330.291694)
			(xy 286.843008 -330.319064) (xy 286.83519 -330.373244) (xy 286.819701 -330.425747) (xy 286.796858 -330.475494)
			(xy 286.767132 -330.521461) (xy 286.74949 -330.542392) (xy 286.743394 -330.549504) (xy 286.737044 -330.566522)
			(xy 286.737044 -330.651866) (xy 286.743394 -330.668884) (xy 286.74949 -330.675996) (xy 286.767124 -330.696934)
			(xy 286.796848 -330.742901) (xy 286.819693 -330.792647) (xy 286.835189 -330.845148) (xy 286.843017 -330.899325)
			(xy 286.843018 -330.954066) (xy 286.83519 -331.008243) (xy 286.819696 -331.060745) (xy 286.796852 -331.110491)
			(xy 286.76713 -331.156459) (xy 286.74949 -331.177392) (xy 286.743394 -331.184504) (xy 286.737044 -331.201522)
			(xy 286.737044 -331.286866) (xy 286.743394 -331.303884) (xy 286.74949 -331.310996) (xy 286.767124 -331.331934)
			(xy 286.796848 -331.377901) (xy 286.819693 -331.427647) (xy 286.835189 -331.480148) (xy 286.843017 -331.534325)
			(xy 286.843018 -331.589066) (xy 286.83519 -331.643243) (xy 286.819696 -331.695745) (xy 286.796852 -331.745491)
			(xy 286.76713 -331.791459) (xy 286.74949 -331.812392) (xy 286.743394 -331.819504) (xy 286.737044 -331.836522)
			(xy 286.737044 -331.921866) (xy 286.743394 -331.938884) (xy 286.74949 -331.945996) (xy 286.767124 -331.966934)
			(xy 286.796848 -332.012901) (xy 286.819693 -332.062647) (xy 286.835189 -332.115148) (xy 286.843017 -332.169325)
			(xy 286.843018 -332.224066) (xy 286.83519 -332.278243) (xy 286.819696 -332.330745) (xy 286.796852 -332.380491)
			(xy 286.76713 -332.426459) (xy 286.74949 -332.447392) (xy 286.743394 -332.454504) (xy 286.737044 -332.471522)
			(xy 286.737044 -332.556866) (xy 286.743394 -332.573884) (xy 286.74949 -332.580996) (xy 286.767124 -332.601934)
			(xy 286.796848 -332.647901) (xy 286.819693 -332.697647) (xy 286.835189 -332.750148) (xy 286.843017 -332.804325)
			(xy 286.843018 -332.859066) (xy 286.83519 -332.913243) (xy 286.819696 -332.965745) (xy 286.796852 -333.015491)
			(xy 286.76713 -333.061459) (xy 286.74949 -333.082392) (xy 286.743394 -333.089504) (xy 286.737044 -333.106522)
			(xy 286.737044 -333.191866) (xy 286.743394 -333.208884) (xy 286.74949 -333.215996) (xy 286.767124 -333.236934)
			(xy 286.796848 -333.282901) (xy 286.819693 -333.332647) (xy 286.835189 -333.385148) (xy 286.843017 -333.439325)
			(xy 286.843018 -333.494066) (xy 286.83519 -333.548243) (xy 286.819696 -333.600745) (xy 286.796852 -333.650491)
			(xy 286.76713 -333.696459) (xy 286.74949 -333.717392) (xy 286.743394 -333.724504) (xy 286.737044 -333.741522)
			(xy 286.737044 -333.826866) (xy 286.743394 -333.843884) (xy 286.74949 -333.850996) (xy 286.767124 -333.871934)
			(xy 286.796848 -333.917901) (xy 286.819693 -333.967647) (xy 286.835189 -334.020148) (xy 286.843017 -334.074325)
			(xy 286.843018 -334.129066) (xy 286.83519 -334.183243) (xy 286.819696 -334.235745) (xy 286.796852 -334.285491)
			(xy 286.76713 -334.331459) (xy 286.74949 -334.352392) (xy 286.743394 -334.359504) (xy 286.737044 -334.376522)
			(xy 286.737044 -334.461866) (xy 286.743394 -334.478884) (xy 286.74949 -334.485996) (xy 286.767139 -334.50692)
			(xy 286.79685 -334.552895) (xy 286.819684 -334.602644) (xy 286.835173 -334.655147) (xy 286.842998 -334.709324)
			(xy 286.84347 -334.736694) (xy 286.843039 -334.763948) (xy 286.835282 -334.817902) (xy 286.819925 -334.870203)
			(xy 286.79728 -334.919786) (xy 286.767809 -334.965641) (xy 286.732112 -335.006835) (xy 286.690915 -335.042528)
			(xy 286.645058 -335.071995) (xy 286.595473 -335.094636) (xy 286.543171 -335.109989) (xy 286.489216 -335.117741)
			(xy 286.461962 -335.118202) (xy 286.434593 -335.117699) (xy 286.380416 -335.10989) (xy 286.327913 -335.09441)
			(xy 286.278165 -335.071576) (xy 286.232197 -335.041859) (xy 286.211264 -335.024222) (xy 286.204152 -335.018126)
			(xy 286.187134 -335.011776) (xy 286.10179 -335.011776) (xy 286.084772 -335.018126) (xy 286.07766 -335.024222)
			(xy 286.056727 -335.041863) (xy 286.010759 -335.071587) (xy 285.961013 -335.094433) (xy 285.908511 -335.109929)
			(xy 285.854333 -335.117758) (xy 285.799591 -335.117758) (xy 285.745413 -335.109929) (xy 285.692911 -335.094433)
			(xy 285.643165 -335.071587) (xy 285.597197 -335.041863) (xy 285.576264 -335.024222) (xy 285.569152 -335.018126)
			(xy 285.552134 -335.011776) (xy 285.46679 -335.011776) (xy 285.449772 -335.018126) (xy 285.44266 -335.024222)
			(xy 285.421719 -335.04185) (xy 285.375748 -335.071563) (xy 285.326003 -335.0944) (xy 285.273504 -335.109894)
			(xy 285.21933 -335.117726) (xy 285.191962 -335.118202) (xy 285.16471 -335.117758) (xy 285.11076 -335.109996)
			(xy 285.058464 -335.094635) (xy 285.008886 -335.071989) (xy 284.963036 -335.042519) (xy 284.921846 -335.006823)
			(xy 284.886155 -334.965629) (xy 284.856689 -334.919775) (xy 284.834049 -334.870195) (xy 284.818695 -334.817897)
			(xy 284.810939 -334.763947) (xy 284.810454 -334.736694) (xy 282.83027 -334.736694) (xy 282.829839 -334.763948)
			(xy 282.822082 -334.817902) (xy 282.806725 -334.870203) (xy 282.78408 -334.919786) (xy 282.754609 -334.965641)
			(xy 282.718912 -335.006835) (xy 282.677715 -335.042528) (xy 282.631858 -335.071995) (xy 282.582273 -335.094636)
			(xy 282.529971 -335.109989) (xy 282.476016 -335.117741) (xy 282.448762 -335.118202) (xy 282.421393 -335.117699)
			(xy 282.367216 -335.10989) (xy 282.314713 -335.09441) (xy 282.264965 -335.071576) (xy 282.218997 -335.041859)
			(xy 282.198064 -335.024222) (xy 282.190952 -335.018126) (xy 282.173934 -335.011776) (xy 282.08859 -335.011776)
			(xy 282.071572 -335.018126) (xy 282.06446 -335.024222) (xy 282.043519 -335.04185) (xy 281.997548 -335.071563)
			(xy 281.947803 -335.0944) (xy 281.895304 -335.109894) (xy 281.84113 -335.117726) (xy 281.813762 -335.118202)
			(xy 281.788744 -335.117797) (xy 281.739139 -335.111249) (xy 281.690815 -335.098271) (xy 281.644604 -335.079085)
			(xy 281.622754 -335.066894) (xy 281.610816 -335.060036) (xy 281.583892 -335.060036) (xy 281.495754 -335.110836)
			(xy 281.488223 -335.115597) (xy 281.476718 -335.129183) (xy 281.470539 -335.145879) (xy 281.4701 -335.154778)
			(xy 281.4701 -348.296738) (xy 281.469613 -348.321713) (xy 281.461826 -348.371051) (xy 281.446419 -348.418564)
			(xy 281.42377 -348.463082) (xy 281.394437 -348.50351) (xy 281.377136 -348.521528) (xy 281.193964 -348.7047)
			(xy 284.020221 -348.7047) (xy 284.024389 -348.649082) (xy 284.0368 -348.594706) (xy 284.057176 -348.542788)
			(xy 284.085062 -348.494485) (xy 284.119836 -348.450879) (xy 284.160721 -348.412942) (xy 284.206803 -348.381523)
			(xy 284.257053 -348.357322) (xy 284.310348 -348.340881) (xy 284.365499 -348.332566) (xy 284.393386 -348.332044)
			(xy 284.419807 -348.332523) (xy 284.472121 -348.33997) (xy 284.522859 -348.354731) (xy 284.571003 -348.376509)
			(xy 284.61559 -348.404869) (xy 284.635956 -348.421706) (xy 284.642814 -348.427802) (xy 284.659832 -348.433898)
			(xy 284.74416 -348.433898) (xy 284.761178 -348.427802) (xy 284.768036 -348.421706) (xy 284.788402 -348.404867)
			(xy 284.832988 -348.376502) (xy 284.881132 -348.354715) (xy 284.931869 -348.339944) (xy 284.984184 -348.332484)
			(xy 285.037028 -348.332484) (xy 285.089343 -348.339944) (xy 285.14008 -348.354715) (xy 285.188224 -348.376502)
			(xy 285.23281 -348.404867) (xy 285.253176 -348.421706) (xy 285.260034 -348.427802) (xy 285.277052 -348.433898)
			(xy 285.36138 -348.433898) (xy 285.378398 -348.427802) (xy 285.385256 -348.421706) (xy 285.403098 -348.4069)
			(xy 285.441797 -348.381362) (xy 285.483363 -348.360819) (xy 285.505144 -348.352872) (xy 285.516574 -348.348808)
			(xy 285.533084 -348.332044) (xy 285.565596 -348.232222) (xy 285.562294 -348.208854) (xy 285.555436 -348.198948)
			(xy 285.539474 -348.174897) (xy 285.514145 -348.123033) (xy 285.496913 -348.067945) (xy 285.488173 -348.010891)
			(xy 285.487618 -347.982032) (xy 285.488099 -347.954458) (xy 285.496048 -347.899886) (xy 285.511769 -347.847026)
			(xy 285.534936 -347.79698) (xy 285.565066 -347.75079) (xy 285.601532 -347.709418) (xy 285.622238 -347.691202)
			(xy 285.630357 -347.6836) (xy 285.63971 -347.663448) (xy 285.640272 -347.65234) (xy 285.640272 -347.575124)
			(xy 285.639716 -347.564013) (xy 285.63037 -347.543853) (xy 285.622238 -347.536262) (xy 285.601513 -347.518066)
			(xy 285.565042 -347.476695) (xy 285.534911 -347.430502) (xy 285.511747 -347.380451) (xy 285.496034 -347.327585)
			(xy 285.4881 -347.273008) (xy 285.487618 -347.245432) (xy 285.488104 -347.218181) (xy 285.49586 -347.164233)
			(xy 285.511215 -347.111938) (xy 285.533857 -347.062361) (xy 285.563323 -347.016511) (xy 285.599014 -346.97532)
			(xy 285.640205 -346.939629) (xy 285.686055 -346.910163) (xy 285.735632 -346.887521) (xy 285.787927 -346.872166)
			(xy 285.841875 -346.86441) (xy 285.896377 -346.86441) (xy 285.950325 -346.872166) (xy 286.00262 -346.887521)
			(xy 286.052197 -346.910163) (xy 286.098047 -346.939629) (xy 286.139238 -346.97532) (xy 286.174929 -347.016511)
			(xy 286.204395 -347.062361) (xy 286.227037 -347.111938) (xy 286.242392 -347.164233) (xy 286.250148 -347.218181)
			(xy 286.250634 -347.245432) (xy 286.250145 -347.273006) (xy 286.2422 -347.327579) (xy 286.226481 -347.380439)
			(xy 286.203316 -347.430486) (xy 286.173186 -347.476676) (xy 286.136721 -347.518047) (xy 286.116014 -347.536262)
			(xy 286.107919 -347.543886) (xy 286.098551 -347.564021) (xy 286.09798 -347.575124) (xy 286.09798 -347.65234)
			(xy 286.098484 -347.663458) (xy 286.107865 -347.683618) (xy 286.116014 -347.691202) (xy 286.136732 -347.709405)
			(xy 286.173201 -347.750776) (xy 286.203332 -347.796968) (xy 286.226497 -347.847017) (xy 286.242212 -347.899881)
			(xy 286.25015 -347.954457) (xy 286.250634 -347.982032) (xy 286.250151 -348.008525) (xy 286.242802 -348.061)
			(xy 286.228264 -348.111954) (xy 286.206817 -348.160406) (xy 286.178873 -348.205426) (xy 286.144969 -348.246146)
			(xy 286.105757 -348.281785) (xy 286.061993 -348.311655) (xy 286.014516 -348.335184) (xy 285.989522 -348.343982)
			(xy 285.978092 -348.347792) (xy 285.961328 -348.364556) (xy 285.959076 -348.37116) (xy 287.943798 -348.37116)
			(xy 287.944265 -348.343248) (xy 287.952405 -348.288021) (xy 287.968507 -348.23457) (xy 287.992225 -348.184036)
			(xy 288.023055 -348.137497) (xy 288.041334 -348.116398) (xy 288.047684 -348.109286) (xy 288.054288 -348.092014)
			(xy 288.054288 -348.004892) (xy 288.047684 -347.98762) (xy 288.041334 -347.980508) (xy 288.023028 -347.959432)
			(xy 287.992207 -347.912886) (xy 287.968498 -347.862345) (xy 287.952408 -347.808889) (xy 287.94428 -347.753659)
			(xy 287.943798 -347.725746) (xy 287.944284 -347.698495) (xy 287.95204 -347.644547) (xy 287.967395 -347.592252)
			(xy 287.990037 -347.542675) (xy 288.019503 -347.496825) (xy 288.055194 -347.455634) (xy 288.096385 -347.419943)
			(xy 288.142235 -347.390477) (xy 288.191812 -347.367835) (xy 288.244107 -347.35248) (xy 288.298055 -347.344724)
			(xy 288.352557 -347.344724) (xy 288.406505 -347.35248) (xy 288.4588 -347.367835) (xy 288.508377 -347.390477)
			(xy 288.554227 -347.419943) (xy 288.595418 -347.455634) (xy 288.631109 -347.496825) (xy 288.660575 -347.542675)
			(xy 288.683217 -347.592252) (xy 288.698572 -347.644547) (xy 288.706328 -347.698495) (xy 288.706814 -347.725746)
			(xy 288.706348 -347.753658) (xy 288.698207 -347.808885) (xy 288.682105 -347.862336) (xy 288.658386 -347.91287)
			(xy 288.627557 -347.959409) (xy 288.609278 -347.980508) (xy 288.602928 -347.98762) (xy 288.596324 -348.004892)
			(xy 288.596324 -348.092014) (xy 288.602928 -348.109286) (xy 288.609278 -348.116398) (xy 288.627526 -348.137523)
			(xy 288.658358 -348.184054) (xy 288.68208 -348.234582) (xy 288.698183 -348.288028) (xy 288.706325 -348.34325)
			(xy 288.706814 -348.37116) (xy 288.705798 -348.398084) (xy 288.704782 -348.414086) (xy 288.721038 -348.441264)
			(xy 288.82213 -348.487492) (xy 288.831698 -348.491366) (xy 288.852317 -348.491816) (xy 288.871433 -348.484072)
			(xy 288.879026 -348.477078) (xy 289.087052 -348.269052) (xy 289.09372 -348.261632) (xy 289.101303 -348.243202)
			(xy 289.101784 -348.233238) (xy 289.101784 -334.801464) (xy 289.103562 -334.768698) (xy 289.103816 -334.760316)
			(xy 289.103054 -334.736694) (xy 289.103503 -334.709323) (xy 289.111323 -334.655143) (xy 289.126815 -334.602639)
			(xy 289.149661 -334.552892) (xy 289.17939 -334.506927) (xy 289.197034 -334.485996) (xy 289.20313 -334.478884)
			(xy 289.20948 -334.461866) (xy 289.20948 -334.376522) (xy 289.20313 -334.359504) (xy 289.197034 -334.352392)
			(xy 289.179387 -334.331464) (xy 289.149662 -334.285496) (xy 289.126817 -334.235749) (xy 289.111321 -334.183246)
			(xy 289.103492 -334.129066) (xy 289.103493 -334.074325) (xy 289.111322 -334.020145) (xy 289.12682 -333.967643)
			(xy 289.149666 -333.917896) (xy 289.179393 -333.871929) (xy 289.197034 -333.850996) (xy 289.20313 -333.843884)
			(xy 289.20948 -333.826866) (xy 289.20948 -333.741522) (xy 289.20313 -333.724504) (xy 289.197034 -333.717392)
			(xy 289.179387 -333.696464) (xy 289.149662 -333.650496) (xy 289.126817 -333.600749) (xy 289.111321 -333.548246)
			(xy 289.103492 -333.494066) (xy 289.103493 -333.439325) (xy 289.111322 -333.385145) (xy 289.12682 -333.332643)
			(xy 289.149666 -333.282896) (xy 289.179393 -333.236929) (xy 289.197034 -333.215996) (xy 289.20313 -333.208884)
			(xy 289.20948 -333.191866) (xy 289.20948 -333.106522) (xy 289.20313 -333.089504) (xy 289.197034 -333.082392)
			(xy 289.179387 -333.061464) (xy 289.149662 -333.015496) (xy 289.126817 -332.965749) (xy 289.111321 -332.913246)
			(xy 289.103492 -332.859066) (xy 289.103493 -332.804325) (xy 289.111322 -332.750145) (xy 289.12682 -332.697643)
			(xy 289.149666 -332.647896) (xy 289.179393 -332.601929) (xy 289.197034 -332.580996) (xy 289.20313 -332.573884)
			(xy 289.20948 -332.556866) (xy 289.20948 -332.471522) (xy 289.20313 -332.454504) (xy 289.197034 -332.447392)
			(xy 289.179387 -332.426464) (xy 289.149662 -332.380496) (xy 289.126817 -332.330749) (xy 289.111321 -332.278246)
			(xy 289.103492 -332.224066) (xy 289.103493 -332.169325) (xy 289.111322 -332.115145) (xy 289.12682 -332.062643)
			(xy 289.149666 -332.012896) (xy 289.179393 -331.966929) (xy 289.197034 -331.945996) (xy 289.20313 -331.938884)
			(xy 289.20948 -331.921866) (xy 289.20948 -331.836522) (xy 289.20313 -331.819504) (xy 289.197034 -331.812392)
			(xy 289.179387 -331.791464) (xy 289.149662 -331.745496) (xy 289.126817 -331.695749) (xy 289.111321 -331.643246)
			(xy 289.103492 -331.589066) (xy 289.103493 -331.534325) (xy 289.111322 -331.480145) (xy 289.12682 -331.427643)
			(xy 289.149666 -331.377896) (xy 289.179393 -331.331929) (xy 289.197034 -331.310996) (xy 289.20313 -331.303884)
			(xy 289.20948 -331.286866) (xy 289.20948 -331.201522) (xy 289.20313 -331.184504) (xy 289.197034 -331.177392)
			(xy 289.179387 -331.156464) (xy 289.149662 -331.110496) (xy 289.126817 -331.060749) (xy 289.111321 -331.008246)
			(xy 289.103492 -330.954066) (xy 289.103493 -330.899325) (xy 289.111322 -330.845145) (xy 289.12682 -330.792643)
			(xy 289.149666 -330.742896) (xy 289.179393 -330.696929) (xy 289.197034 -330.675996) (xy 289.20313 -330.668884)
			(xy 289.20948 -330.651866) (xy 289.20948 -330.566522) (xy 289.20313 -330.549504) (xy 289.197034 -330.542392)
			(xy 289.179383 -330.521469) (xy 289.149672 -330.475495) (xy 289.126838 -330.425745) (xy 289.111349 -330.373242)
			(xy 289.103525 -330.319064) (xy 289.103054 -330.291694) (xy 289.103572 -330.264444) (xy 289.111328 -330.2105)
			(xy 289.126682 -330.158208) (xy 289.149321 -330.108633) (xy 289.178785 -330.062785) (xy 289.214473 -330.021595)
			(xy 289.255659 -329.985904) (xy 289.301505 -329.956437) (xy 289.351078 -329.933794) (xy 289.403368 -329.918435)
			(xy 289.457312 -329.910674) (xy 289.484562 -329.910186) (xy 289.511931 -329.910678) (xy 289.566109 -329.91849)
			(xy 289.618612 -329.933973) (xy 289.668359 -329.956809) (xy 289.714327 -329.986528) (xy 289.73526 -330.004166)
			(xy 289.742372 -330.010262) (xy 289.75939 -330.016612) (xy 289.844734 -330.016612) (xy 289.861752 -330.010262)
			(xy 289.868864 -330.004166) (xy 289.889797 -329.986525) (xy 289.935765 -329.956801) (xy 289.985511 -329.933955)
			(xy 290.038013 -329.918459) (xy 290.092191 -329.91063) (xy 290.146933 -329.91063) (xy 290.201111 -329.918459)
			(xy 290.253613 -329.933955) (xy 290.303359 -329.956801) (xy 290.349327 -329.986525) (xy 290.37026 -330.004166)
			(xy 290.377372 -330.010262) (xy 290.39439 -330.016612) (xy 290.479734 -330.016612) (xy 290.496752 -330.010262)
			(xy 290.503864 -330.004166) (xy 290.524794 -329.986525) (xy 290.570768 -329.956815) (xy 290.620516 -329.93398)
			(xy 290.673017 -329.918489) (xy 290.727193 -329.91066) (xy 290.754562 -329.910186) (xy 290.781814 -329.910691)
			(xy 290.835763 -329.918442) (xy 290.88806 -329.933793) (xy 290.937639 -329.956431) (xy 290.983492 -329.985894)
			(xy 291.024685 -330.021584) (xy 291.060379 -330.062773) (xy 291.089848 -330.108622) (xy 291.112491 -330.158199)
			(xy 291.127848 -330.210494) (xy 291.135606 -330.264442) (xy 291.13607 -330.291694) (xy 291.135608 -330.319064)
			(xy 291.12779 -330.373244) (xy 291.112301 -330.425747) (xy 291.089458 -330.475494) (xy 291.059732 -330.521461)
			(xy 291.04209 -330.542392) (xy 291.035994 -330.549504) (xy 291.029644 -330.566522) (xy 291.029644 -330.651866)
			(xy 291.035994 -330.668884) (xy 291.04209 -330.675996) (xy 291.059724 -330.696934) (xy 291.089448 -330.742901)
			(xy 291.112293 -330.792647) (xy 291.127789 -330.845148) (xy 291.135617 -330.899325) (xy 291.135618 -330.954066)
			(xy 291.12779 -331.008243) (xy 291.112296 -331.060745) (xy 291.089452 -331.110491) (xy 291.05973 -331.156459)
			(xy 291.04209 -331.177392) (xy 291.035994 -331.184504) (xy 291.029644 -331.201522) (xy 291.029644 -331.286866)
			(xy 291.035994 -331.303884) (xy 291.04209 -331.310996) (xy 291.059724 -331.331934) (xy 291.089448 -331.377901)
			(xy 291.112293 -331.427647) (xy 291.127789 -331.480148) (xy 291.135617 -331.534325) (xy 291.135618 -331.589066)
			(xy 291.12779 -331.643243) (xy 291.112296 -331.695745) (xy 291.089452 -331.745491) (xy 291.05973 -331.791459)
			(xy 291.04209 -331.812392) (xy 291.035994 -331.819504) (xy 291.029644 -331.836522) (xy 291.029644 -331.921866)
			(xy 291.035994 -331.938884) (xy 291.04209 -331.945996) (xy 291.059724 -331.966934) (xy 291.089448 -332.012901)
			(xy 291.112293 -332.062647) (xy 291.127789 -332.115148) (xy 291.135617 -332.169325) (xy 291.135618 -332.224066)
			(xy 291.12779 -332.278243) (xy 291.112296 -332.330745) (xy 291.089452 -332.380491) (xy 291.05973 -332.426459)
			(xy 291.04209 -332.447392) (xy 291.035994 -332.454504) (xy 291.029644 -332.471522) (xy 291.029644 -332.556866)
			(xy 291.035994 -332.573884) (xy 291.04209 -332.580996) (xy 291.059724 -332.601934) (xy 291.089448 -332.647901)
			(xy 291.112293 -332.697647) (xy 291.127789 -332.750148) (xy 291.135617 -332.804325) (xy 291.135618 -332.859066)
			(xy 291.12779 -332.913243) (xy 291.112296 -332.965745) (xy 291.089452 -333.015491) (xy 291.05973 -333.061459)
			(xy 291.04209 -333.082392) (xy 291.035994 -333.089504) (xy 291.029644 -333.106522) (xy 291.029644 -333.191866)
			(xy 291.035994 -333.208884) (xy 291.04209 -333.215996) (xy 291.059724 -333.236934) (xy 291.089448 -333.282901)
			(xy 291.112293 -333.332647) (xy 291.127789 -333.385148) (xy 291.135617 -333.439325) (xy 291.135618 -333.494066)
			(xy 291.12779 -333.548243) (xy 291.112296 -333.600745) (xy 291.089452 -333.650491) (xy 291.05973 -333.696459)
			(xy 291.04209 -333.717392) (xy 291.035994 -333.724504) (xy 291.029644 -333.741522) (xy 291.029644 -333.826866)
			(xy 291.035994 -333.843884) (xy 291.04209 -333.850996) (xy 291.059724 -333.871934) (xy 291.089448 -333.917901)
			(xy 291.112293 -333.967647) (xy 291.127789 -334.020148) (xy 291.135617 -334.074325) (xy 291.135618 -334.129066)
			(xy 291.12779 -334.183243) (xy 291.112296 -334.235745) (xy 291.089452 -334.285491) (xy 291.05973 -334.331459)
			(xy 291.04209 -334.352392) (xy 291.035994 -334.359504) (xy 291.029644 -334.376522) (xy 291.029644 -334.461866)
			(xy 291.035994 -334.478884) (xy 291.04209 -334.485996) (xy 291.059739 -334.50692) (xy 291.08945 -334.552895)
			(xy 291.112284 -334.602644) (xy 291.127773 -334.655147) (xy 291.135598 -334.709324) (xy 291.13607 -334.736694)
			(xy 293.116254 -334.736694) (xy 293.116703 -334.709323) (xy 293.124523 -334.655143) (xy 293.140015 -334.602639)
			(xy 293.162861 -334.552892) (xy 293.19259 -334.506927) (xy 293.210234 -334.485996) (xy 293.21633 -334.478884)
			(xy 293.22268 -334.461866) (xy 293.22268 -334.376522) (xy 293.21633 -334.359504) (xy 293.210234 -334.352392)
			(xy 293.192587 -334.331464) (xy 293.162862 -334.285496) (xy 293.140017 -334.235749) (xy 293.124521 -334.183246)
			(xy 293.116692 -334.129066) (xy 293.116693 -334.074325) (xy 293.124522 -334.020145) (xy 293.14002 -333.967643)
			(xy 293.162866 -333.917896) (xy 293.192593 -333.871929) (xy 293.210234 -333.850996) (xy 293.21633 -333.843884)
			(xy 293.22268 -333.826866) (xy 293.22268 -333.741522) (xy 293.21633 -333.724504) (xy 293.210234 -333.717392)
			(xy 293.192587 -333.696464) (xy 293.162862 -333.650496) (xy 293.140017 -333.600749) (xy 293.124521 -333.548246)
			(xy 293.116692 -333.494066) (xy 293.116693 -333.439325) (xy 293.124522 -333.385145) (xy 293.14002 -333.332643)
			(xy 293.162866 -333.282896) (xy 293.192593 -333.236929) (xy 293.210234 -333.215996) (xy 293.21633 -333.208884)
			(xy 293.22268 -333.191866) (xy 293.22268 -333.106522) (xy 293.21633 -333.089504) (xy 293.210234 -333.082392)
			(xy 293.192587 -333.061464) (xy 293.162862 -333.015496) (xy 293.140017 -332.965749) (xy 293.124521 -332.913246)
			(xy 293.116692 -332.859066) (xy 293.116693 -332.804325) (xy 293.124522 -332.750145) (xy 293.14002 -332.697643)
			(xy 293.162866 -332.647896) (xy 293.192593 -332.601929) (xy 293.210234 -332.580996) (xy 293.21633 -332.573884)
			(xy 293.22268 -332.556866) (xy 293.22268 -332.471522) (xy 293.21633 -332.454504) (xy 293.210234 -332.447392)
			(xy 293.192587 -332.426464) (xy 293.162862 -332.380496) (xy 293.140017 -332.330749) (xy 293.124521 -332.278246)
			(xy 293.116692 -332.224066) (xy 293.116693 -332.169325) (xy 293.124522 -332.115145) (xy 293.14002 -332.062643)
			(xy 293.162866 -332.012896) (xy 293.192593 -331.966929) (xy 293.210234 -331.945996) (xy 293.21633 -331.938884)
			(xy 293.22268 -331.921866) (xy 293.22268 -331.836522) (xy 293.21633 -331.819504) (xy 293.210234 -331.812392)
			(xy 293.192587 -331.791464) (xy 293.162862 -331.745496) (xy 293.140017 -331.695749) (xy 293.124521 -331.643246)
			(xy 293.116692 -331.589066) (xy 293.116693 -331.534325) (xy 293.124522 -331.480145) (xy 293.14002 -331.427643)
			(xy 293.162866 -331.377896) (xy 293.192593 -331.331929) (xy 293.210234 -331.310996) (xy 293.21633 -331.303884)
			(xy 293.22268 -331.286866) (xy 293.22268 -331.201522) (xy 293.21633 -331.184504) (xy 293.210234 -331.177392)
			(xy 293.192587 -331.156464) (xy 293.162862 -331.110496) (xy 293.140017 -331.060749) (xy 293.124521 -331.008246)
			(xy 293.116692 -330.954066) (xy 293.116693 -330.899325) (xy 293.124522 -330.845145) (xy 293.14002 -330.792643)
			(xy 293.162866 -330.742896) (xy 293.192593 -330.696929) (xy 293.210234 -330.675996) (xy 293.21633 -330.668884)
			(xy 293.22268 -330.651866) (xy 293.22268 -330.566522) (xy 293.21633 -330.549504) (xy 293.210234 -330.542392)
			(xy 293.192583 -330.521469) (xy 293.162872 -330.475495) (xy 293.140038 -330.425745) (xy 293.124549 -330.373242)
			(xy 293.116725 -330.319064) (xy 293.116254 -330.291694) (xy 293.116772 -330.264444) (xy 293.124528 -330.2105)
			(xy 293.139882 -330.158208) (xy 293.162521 -330.108633) (xy 293.191985 -330.062785) (xy 293.227673 -330.021595)
			(xy 293.268859 -329.985904) (xy 293.314705 -329.956437) (xy 293.364278 -329.933794) (xy 293.416568 -329.918435)
			(xy 293.470512 -329.910674) (xy 293.497762 -329.910186) (xy 293.525131 -329.910678) (xy 293.579309 -329.91849)
			(xy 293.631812 -329.933973) (xy 293.681559 -329.956809) (xy 293.727527 -329.986528) (xy 293.74846 -330.004166)
			(xy 293.755572 -330.010262) (xy 293.77259 -330.016612) (xy 293.857934 -330.016612) (xy 293.874952 -330.010262)
			(xy 293.882064 -330.004166) (xy 293.902997 -329.986525) (xy 293.948965 -329.956801) (xy 293.998711 -329.933955)
			(xy 294.051213 -329.918459) (xy 294.105391 -329.91063) (xy 294.160133 -329.91063) (xy 294.214311 -329.918459)
			(xy 294.266813 -329.933955) (xy 294.316559 -329.956801) (xy 294.362527 -329.986525) (xy 294.38346 -330.004166)
			(xy 294.390572 -330.010262) (xy 294.40759 -330.016612) (xy 294.492934 -330.016612) (xy 294.509952 -330.010262)
			(xy 294.517064 -330.004166) (xy 294.537994 -329.986525) (xy 294.583968 -329.956815) (xy 294.633716 -329.93398)
			(xy 294.686217 -329.918489) (xy 294.740393 -329.91066) (xy 294.767762 -329.910186) (xy 294.795014 -329.910691)
			(xy 294.848963 -329.918442) (xy 294.90126 -329.933793) (xy 294.950839 -329.956431) (xy 294.996692 -329.985894)
			(xy 295.037885 -330.021584) (xy 295.073579 -330.062773) (xy 295.103048 -330.108622) (xy 295.125691 -330.158199)
			(xy 295.141048 -330.210494) (xy 295.148806 -330.264442) (xy 295.14927 -330.291694) (xy 295.148808 -330.319064)
			(xy 295.14099 -330.373244) (xy 295.125501 -330.425747) (xy 295.102658 -330.475494) (xy 295.072932 -330.521461)
			(xy 295.05529 -330.542392) (xy 295.049194 -330.549504) (xy 295.042844 -330.566522) (xy 295.042844 -330.651866)
			(xy 295.049194 -330.668884) (xy 295.05529 -330.675996) (xy 295.072924 -330.696934) (xy 295.102648 -330.742901)
			(xy 295.125493 -330.792647) (xy 295.140989 -330.845148) (xy 295.148817 -330.899325) (xy 295.148818 -330.954066)
			(xy 295.14099 -331.008243) (xy 295.125496 -331.060745) (xy 295.102652 -331.110491) (xy 295.07293 -331.156459)
			(xy 295.05529 -331.177392) (xy 295.049194 -331.184504) (xy 295.042844 -331.201522) (xy 295.042844 -331.286866)
			(xy 295.049194 -331.303884) (xy 295.05529 -331.310996) (xy 295.072924 -331.331934) (xy 295.102648 -331.377901)
			(xy 295.125493 -331.427647) (xy 295.140989 -331.480148) (xy 295.148817 -331.534325) (xy 295.148818 -331.589066)
			(xy 295.14099 -331.643243) (xy 295.125496 -331.695745) (xy 295.102652 -331.745491) (xy 295.07293 -331.791459)
			(xy 295.05529 -331.812392) (xy 295.049194 -331.819504) (xy 295.042844 -331.836522) (xy 295.042844 -331.921866)
			(xy 295.049194 -331.938884) (xy 295.05529 -331.945996) (xy 295.072924 -331.966934) (xy 295.102648 -332.012901)
			(xy 295.125493 -332.062647) (xy 295.140989 -332.115148) (xy 295.148817 -332.169325) (xy 295.148818 -332.224066)
			(xy 295.14099 -332.278243) (xy 295.125496 -332.330745) (xy 295.102652 -332.380491) (xy 295.07293 -332.426459)
			(xy 295.05529 -332.447392) (xy 295.049194 -332.454504) (xy 295.042844 -332.471522) (xy 295.042844 -332.556866)
			(xy 295.049194 -332.573884) (xy 295.05529 -332.580996) (xy 295.072924 -332.601934) (xy 295.102648 -332.647901)
			(xy 295.125493 -332.697647) (xy 295.140989 -332.750148) (xy 295.148817 -332.804325) (xy 295.148818 -332.859066)
			(xy 295.14099 -332.913243) (xy 295.125496 -332.965745) (xy 295.102652 -333.015491) (xy 295.07293 -333.061459)
			(xy 295.05529 -333.082392) (xy 295.049194 -333.089504) (xy 295.042844 -333.106522) (xy 295.042844 -333.191866)
			(xy 295.049194 -333.208884) (xy 295.05529 -333.215996) (xy 295.072924 -333.236934) (xy 295.102648 -333.282901)
			(xy 295.125493 -333.332647) (xy 295.140989 -333.385148) (xy 295.148817 -333.439325) (xy 295.148818 -333.494066)
			(xy 295.14099 -333.548243) (xy 295.125496 -333.600745) (xy 295.102652 -333.650491) (xy 295.07293 -333.696459)
			(xy 295.05529 -333.717392) (xy 295.049194 -333.724504) (xy 295.042844 -333.741522) (xy 295.042844 -333.826866)
			(xy 295.049194 -333.843884) (xy 295.05529 -333.850996) (xy 295.072924 -333.871934) (xy 295.102648 -333.917901)
			(xy 295.125493 -333.967647) (xy 295.140989 -334.020148) (xy 295.148817 -334.074325) (xy 295.148818 -334.129066)
			(xy 295.14099 -334.183243) (xy 295.125496 -334.235745) (xy 295.102652 -334.285491) (xy 295.07293 -334.331459)
			(xy 295.05529 -334.352392) (xy 295.049194 -334.359504) (xy 295.042844 -334.376522) (xy 295.042844 -334.461866)
			(xy 295.049194 -334.478884) (xy 295.05529 -334.485996) (xy 295.072939 -334.50692) (xy 295.10265 -334.552895)
			(xy 295.125484 -334.602644) (xy 295.140973 -334.655147) (xy 295.148798 -334.709324) (xy 295.14927 -334.736694)
			(xy 295.148839 -334.763948) (xy 295.141082 -334.817902) (xy 295.125725 -334.870203) (xy 295.10308 -334.919786)
			(xy 295.073609 -334.965641) (xy 295.037912 -335.006835) (xy 294.996715 -335.042528) (xy 294.950858 -335.071995)
			(xy 294.901273 -335.094636) (xy 294.848971 -335.109989) (xy 294.795016 -335.117741) (xy 294.767762 -335.118202)
			(xy 294.740393 -335.117699) (xy 294.686216 -335.10989) (xy 294.633713 -335.09441) (xy 294.583965 -335.071576)
			(xy 294.537997 -335.041859) (xy 294.517064 -335.024222) (xy 294.509952 -335.018126) (xy 294.492934 -335.011776)
			(xy 294.40759 -335.011776) (xy 294.390572 -335.018126) (xy 294.38346 -335.024222) (xy 294.362527 -335.041863)
			(xy 294.316559 -335.071587) (xy 294.266813 -335.094433) (xy 294.214311 -335.109929) (xy 294.160133 -335.117758)
			(xy 294.105391 -335.117758) (xy 294.051213 -335.109929) (xy 293.998711 -335.094433) (xy 293.948965 -335.071587)
			(xy 293.902997 -335.041863) (xy 293.882064 -335.024222) (xy 293.874952 -335.018126) (xy 293.857934 -335.011776)
			(xy 293.77259 -335.011776) (xy 293.755572 -335.018126) (xy 293.74846 -335.024222) (xy 293.727519 -335.04185)
			(xy 293.681548 -335.071563) (xy 293.631803 -335.0944) (xy 293.579304 -335.109894) (xy 293.52513 -335.117726)
			(xy 293.497762 -335.118202) (xy 293.47051 -335.117758) (xy 293.41656 -335.109996) (xy 293.364264 -335.094635)
			(xy 293.314686 -335.071989) (xy 293.268836 -335.042519) (xy 293.227646 -335.006823) (xy 293.191955 -334.965629)
			(xy 293.162489 -334.919775) (xy 293.139849 -334.870195) (xy 293.124495 -334.817897) (xy 293.116739 -334.763947)
			(xy 293.116254 -334.736694) (xy 291.13607 -334.736694) (xy 291.135639 -334.763948) (xy 291.127882 -334.817902)
			(xy 291.112525 -334.870203) (xy 291.08988 -334.919786) (xy 291.060409 -334.965641) (xy 291.024712 -335.006835)
			(xy 290.983515 -335.042528) (xy 290.937658 -335.071995) (xy 290.888073 -335.094636) (xy 290.835771 -335.109989)
			(xy 290.781816 -335.117741) (xy 290.754562 -335.118202) (xy 290.727193 -335.117699) (xy 290.673016 -335.10989)
			(xy 290.620513 -335.09441) (xy 290.570765 -335.071576) (xy 290.524797 -335.041859) (xy 290.503864 -335.024222)
			(xy 290.496752 -335.018126) (xy 290.479734 -335.011776) (xy 290.39439 -335.011776) (xy 290.377372 -335.018126)
			(xy 290.37026 -335.024222) (xy 290.349319 -335.04185) (xy 290.303348 -335.071563) (xy 290.253603 -335.0944)
			(xy 290.201104 -335.109894) (xy 290.14693 -335.117726) (xy 290.119562 -335.118202) (xy 290.090086 -335.117623)
			(xy 290.031834 -335.108563) (xy 289.97567 -335.09065) (xy 289.92293 -335.064309) (xy 289.874871 -335.030169)
			(xy 289.85337 -335.009998) (xy 289.84604 -335.003457) (xy 289.827876 -334.996016) (xy 289.818064 -334.99552)
			(xy 289.764724 -334.99552) (xy 289.752786 -335.007966) (xy 289.745967 -335.015382) (xy 289.738235 -335.033969)
			(xy 289.7378 -335.044034) (xy 289.7378 -348.385892) (xy 289.737318 -348.410879) (xy 289.729484 -348.460235)
			(xy 289.714025 -348.507757) (xy 289.69132 -348.552275) (xy 289.66193 -348.592693) (xy 289.644582 -348.610682)
			(xy 289.550564 -348.7047) (xy 292.326021 -348.7047) (xy 292.330189 -348.649082) (xy 292.3426 -348.594706)
			(xy 292.362976 -348.542788) (xy 292.390862 -348.494485) (xy 292.425636 -348.450879) (xy 292.466521 -348.412942)
			(xy 292.512603 -348.381523) (xy 292.562853 -348.357322) (xy 292.616148 -348.340881) (xy 292.671299 -348.332566)
			(xy 292.699186 -348.332044) (xy 292.725607 -348.332523) (xy 292.777921 -348.33997) (xy 292.828659 -348.354731)
			(xy 292.876803 -348.376509) (xy 292.92139 -348.404869) (xy 292.941756 -348.421706) (xy 292.948614 -348.427802)
			(xy 292.965632 -348.433898) (xy 293.04996 -348.433898) (xy 293.066978 -348.427802) (xy 293.073836 -348.421706)
			(xy 293.094202 -348.404867) (xy 293.138788 -348.376502) (xy 293.186932 -348.354715) (xy 293.237669 -348.339944)
			(xy 293.289984 -348.332484) (xy 293.342828 -348.332484) (xy 293.395143 -348.339944) (xy 293.44588 -348.354715)
			(xy 293.494024 -348.376502) (xy 293.53861 -348.404867) (xy 293.558976 -348.421706) (xy 293.565834 -348.427802)
			(xy 293.582852 -348.433898) (xy 293.66718 -348.433898) (xy 293.684198 -348.427802) (xy 293.691056 -348.421706)
			(xy 293.716613 -348.400749) (xy 293.77359 -348.367271) (xy 293.80434 -348.355158) (xy 293.81577 -348.351094)
			(xy 293.83228 -348.33306) (xy 293.860982 -348.23019) (xy 293.856156 -348.206314) (xy 293.848536 -348.196662)
			(xy 293.832909 -348.17632) (xy 293.806631 -348.132266) (xy 293.786484 -348.085093) (xy 293.772831 -348.035647)
			(xy 293.765917 -347.984819) (xy 293.765478 -347.959172) (xy 293.766001 -347.9316) (xy 293.773943 -347.87703)
			(xy 293.789657 -347.824171) (xy 293.812816 -347.774125) (xy 293.842938 -347.727934) (xy 293.879396 -347.68656)
			(xy 293.900098 -347.668342) (xy 293.908193 -347.660718) (xy 293.91756 -347.640583) (xy 293.918132 -347.62948)
			(xy 293.918132 -347.552264) (xy 293.917622 -347.541147) (xy 293.908245 -347.520987) (xy 293.900098 -347.513402)
			(xy 293.879384 -347.495194) (xy 293.842914 -347.453824) (xy 293.812782 -347.407634) (xy 293.789617 -347.357585)
			(xy 293.773901 -347.304722) (xy 293.765963 -347.250147) (xy 293.765478 -347.222572) (xy 293.765964 -347.195321)
			(xy 293.77372 -347.141373) (xy 293.789075 -347.089078) (xy 293.811717 -347.039501) (xy 293.841183 -346.993651)
			(xy 293.876874 -346.95246) (xy 293.918065 -346.916769) (xy 293.963915 -346.887303) (xy 294.013492 -346.864661)
			(xy 294.065787 -346.849306) (xy 294.119735 -346.84155) (xy 294.174237 -346.84155) (xy 294.228185 -346.849306)
			(xy 294.28048 -346.864661) (xy 294.330057 -346.887303) (xy 294.375907 -346.916769) (xy 294.417098 -346.95246)
			(xy 294.452789 -346.993651) (xy 294.482255 -347.039501) (xy 294.504897 -347.089078) (xy 294.520252 -347.141373)
			(xy 294.528008 -347.195321) (xy 294.528494 -347.222572) (xy 294.528011 -347.250146) (xy 294.520062 -347.304718)
			(xy 294.504341 -347.357578) (xy 294.481174 -347.407624) (xy 294.451045 -347.453814) (xy 294.41458 -347.495186)
			(xy 294.393874 -347.513402) (xy 294.385755 -347.521004) (xy 294.376402 -347.541156) (xy 294.37584 -347.552264)
			(xy 294.37584 -347.62948) (xy 294.37639 -347.640592) (xy 294.38574 -347.660752) (xy 294.393874 -347.668342)
			(xy 294.414555 -347.686586) (xy 294.451029 -347.727947) (xy 294.481165 -347.77413) (xy 294.504337 -347.824172)
			(xy 294.520059 -347.877029) (xy 294.528005 -347.931599) (xy 294.528494 -347.959172) (xy 294.527984 -347.988496)
			(xy 294.518985 -348.046451) (xy 294.501226 -348.102346) (xy 294.475124 -348.154867) (xy 294.441295 -348.202776)
			(xy 294.400534 -348.244945) (xy 294.353802 -348.280382) (xy 294.302198 -348.308253) (xy 294.274748 -348.318582)
			(xy 294.263064 -348.3229) (xy 294.2463 -348.340426) (xy 294.237323 -348.37116) (xy 296.300398 -348.37116)
			(xy 296.300865 -348.343248) (xy 296.309005 -348.288021) (xy 296.325107 -348.23457) (xy 296.348825 -348.184036)
			(xy 296.379655 -348.137497) (xy 296.397934 -348.116398) (xy 296.404284 -348.109286) (xy 296.410888 -348.092014)
			(xy 296.410888 -348.004892) (xy 296.404284 -347.98762) (xy 296.397934 -347.980508) (xy 296.379628 -347.959432)
			(xy 296.348807 -347.912886) (xy 296.325098 -347.862345) (xy 296.309008 -347.808889) (xy 296.30088 -347.753659)
			(xy 296.300398 -347.725746) (xy 296.300884 -347.698495) (xy 296.30864 -347.644547) (xy 296.323995 -347.592252)
			(xy 296.346637 -347.542675) (xy 296.376103 -347.496825) (xy 296.411794 -347.455634) (xy 296.452985 -347.419943)
			(xy 296.498835 -347.390477) (xy 296.548412 -347.367835) (xy 296.600707 -347.35248) (xy 296.654655 -347.344724)
			(xy 296.709157 -347.344724) (xy 296.763105 -347.35248) (xy 296.8154 -347.367835) (xy 296.864977 -347.390477)
			(xy 296.910827 -347.419943) (xy 296.952018 -347.455634) (xy 296.987709 -347.496825) (xy 297.017175 -347.542675)
			(xy 297.039817 -347.592252) (xy 297.055172 -347.644547) (xy 297.062928 -347.698495) (xy 297.063414 -347.725746)
			(xy 297.062948 -347.753658) (xy 297.054807 -347.808885) (xy 297.038705 -347.862336) (xy 297.014986 -347.91287)
			(xy 296.984157 -347.959409) (xy 296.965878 -347.980508) (xy 296.959528 -347.98762) (xy 296.952924 -348.004892)
			(xy 296.952924 -348.092014) (xy 296.959528 -348.109286) (xy 296.965878 -348.116398) (xy 296.984126 -348.137523)
			(xy 297.014958 -348.184054) (xy 297.03868 -348.234582) (xy 297.054783 -348.288028) (xy 297.062925 -348.34325)
			(xy 297.063414 -348.37116) (xy 297.063414 -348.377002) (xy 297.06316 -348.39275) (xy 297.079924 -348.418658)
			(xy 297.181016 -348.46133) (xy 297.19047 -348.464934) (xy 297.210689 -348.465103) (xy 297.229416 -348.457477)
			(xy 297.236896 -348.450662) (xy 297.507406 -348.179898) (xy 297.514147 -348.172508) (xy 297.521857 -348.154073)
			(xy 297.522392 -348.144084) (xy 297.522392 -334.960722) (xy 297.522151 -334.953831) (xy 297.518414 -334.940565)
			(xy 297.515026 -334.93456) (xy 297.501905 -334.912092) (xy 297.481196 -334.86436) (xy 297.467173 -334.814256)
			(xy 297.460096 -334.762709) (xy 297.459654 -334.736694) (xy 297.460103 -334.709323) (xy 297.467923 -334.655143)
			(xy 297.483415 -334.602639) (xy 297.506261 -334.552892) (xy 297.53599 -334.506927) (xy 297.553634 -334.485996)
			(xy 297.55973 -334.478884) (xy 297.56608 -334.461866) (xy 297.56608 -334.376522) (xy 297.55973 -334.359504)
			(xy 297.553634 -334.352392) (xy 297.535987 -334.331464) (xy 297.506262 -334.285496) (xy 297.483417 -334.235749)
			(xy 297.467921 -334.183246) (xy 297.460092 -334.129066) (xy 297.460093 -334.074325) (xy 297.467922 -334.020145)
			(xy 297.48342 -333.967643) (xy 297.506266 -333.917896) (xy 297.535993 -333.871929) (xy 297.553634 -333.850996)
			(xy 297.55973 -333.843884) (xy 297.56608 -333.826866) (xy 297.56608 -333.741522) (xy 297.55973 -333.724504)
			(xy 297.553634 -333.717392) (xy 297.535987 -333.696464) (xy 297.506262 -333.650496) (xy 297.483417 -333.600749)
			(xy 297.467921 -333.548246) (xy 297.460092 -333.494066) (xy 297.460093 -333.439325) (xy 297.467922 -333.385145)
			(xy 297.48342 -333.332643) (xy 297.506266 -333.282896) (xy 297.535993 -333.236929) (xy 297.553634 -333.215996)
			(xy 297.55973 -333.208884) (xy 297.56608 -333.191866) (xy 297.56608 -333.106522) (xy 297.55973 -333.089504)
			(xy 297.553634 -333.082392) (xy 297.535987 -333.061464) (xy 297.506262 -333.015496) (xy 297.483417 -332.965749)
			(xy 297.467921 -332.913246) (xy 297.460092 -332.859066) (xy 297.460093 -332.804325) (xy 297.467922 -332.750145)
			(xy 297.48342 -332.697643) (xy 297.506266 -332.647896) (xy 297.535993 -332.601929) (xy 297.553634 -332.580996)
			(xy 297.55973 -332.573884) (xy 297.56608 -332.556866) (xy 297.56608 -332.471522) (xy 297.55973 -332.454504)
			(xy 297.553634 -332.447392) (xy 297.535987 -332.426464) (xy 297.506262 -332.380496) (xy 297.483417 -332.330749)
			(xy 297.467921 -332.278246) (xy 297.460092 -332.224066) (xy 297.460093 -332.169325) (xy 297.467922 -332.115145)
			(xy 297.48342 -332.062643) (xy 297.506266 -332.012896) (xy 297.535993 -331.966929) (xy 297.553634 -331.945996)
			(xy 297.55973 -331.938884) (xy 297.56608 -331.921866) (xy 297.56608 -331.836522) (xy 297.55973 -331.819504)
			(xy 297.553634 -331.812392) (xy 297.535987 -331.791464) (xy 297.506262 -331.745496) (xy 297.483417 -331.695749)
			(xy 297.467921 -331.643246) (xy 297.460092 -331.589066) (xy 297.460093 -331.534325) (xy 297.467922 -331.480145)
			(xy 297.48342 -331.427643) (xy 297.506266 -331.377896) (xy 297.535993 -331.331929) (xy 297.553634 -331.310996)
			(xy 297.55973 -331.303884) (xy 297.56608 -331.286866) (xy 297.56608 -331.201522) (xy 297.55973 -331.184504)
			(xy 297.553634 -331.177392) (xy 297.535987 -331.156464) (xy 297.506262 -331.110496) (xy 297.483417 -331.060749)
			(xy 297.467921 -331.008246) (xy 297.460092 -330.954066) (xy 297.460093 -330.899325) (xy 297.467922 -330.845145)
			(xy 297.48342 -330.792643) (xy 297.506266 -330.742896) (xy 297.535993 -330.696929) (xy 297.553634 -330.675996)
			(xy 297.55973 -330.668884) (xy 297.56608 -330.651866) (xy 297.56608 -330.566522) (xy 297.55973 -330.549504)
			(xy 297.553634 -330.542392) (xy 297.535983 -330.521469) (xy 297.506272 -330.475495) (xy 297.483438 -330.425745)
			(xy 297.467949 -330.373242) (xy 297.460125 -330.319064) (xy 297.459654 -330.291694) (xy 297.460172 -330.264444)
			(xy 297.467928 -330.2105) (xy 297.483282 -330.158208) (xy 297.505921 -330.108633) (xy 297.535385 -330.062785)
			(xy 297.571073 -330.021595) (xy 297.612259 -329.985904) (xy 297.658105 -329.956437) (xy 297.707678 -329.933794)
			(xy 297.759968 -329.918435) (xy 297.813912 -329.910674) (xy 297.841162 -329.910186) (xy 297.868531 -329.910678)
			(xy 297.922709 -329.91849) (xy 297.975212 -329.933973) (xy 298.024959 -329.956809) (xy 298.070927 -329.986528)
			(xy 298.09186 -330.004166) (xy 298.098972 -330.010262) (xy 298.11599 -330.016612) (xy 298.201334 -330.016612)
			(xy 298.218352 -330.010262) (xy 298.225464 -330.004166) (xy 298.246397 -329.986525) (xy 298.292365 -329.956801)
			(xy 298.342111 -329.933955) (xy 298.394613 -329.918459) (xy 298.448791 -329.91063) (xy 298.503533 -329.91063)
			(xy 298.557711 -329.918459) (xy 298.610213 -329.933955) (xy 298.659959 -329.956801) (xy 298.705927 -329.986525)
			(xy 298.72686 -330.004166) (xy 298.733972 -330.010262) (xy 298.75099 -330.016612) (xy 298.836334 -330.016612)
			(xy 298.853352 -330.010262) (xy 298.860464 -330.004166) (xy 298.881394 -329.986525) (xy 298.927368 -329.956815)
			(xy 298.977116 -329.93398) (xy 299.029617 -329.918489) (xy 299.083793 -329.91066) (xy 299.111162 -329.910186)
			(xy 299.138414 -329.910691) (xy 299.192363 -329.918442) (xy 299.24466 -329.933793) (xy 299.294239 -329.956431)
			(xy 299.340092 -329.985894) (xy 299.381285 -330.021584) (xy 299.416979 -330.062773) (xy 299.446448 -330.108622)
			(xy 299.469091 -330.158199) (xy 299.484448 -330.210494) (xy 299.492206 -330.264442) (xy 299.49267 -330.291694)
			(xy 299.492208 -330.319064) (xy 299.48439 -330.373244) (xy 299.468901 -330.425747) (xy 299.446058 -330.475494)
			(xy 299.416332 -330.521461) (xy 299.39869 -330.542392) (xy 299.392594 -330.549504) (xy 299.386244 -330.566522)
			(xy 299.386244 -330.651866) (xy 299.392594 -330.668884) (xy 299.39869 -330.675996) (xy 299.416324 -330.696934)
			(xy 299.446048 -330.742901) (xy 299.468893 -330.792647) (xy 299.484389 -330.845148) (xy 299.492217 -330.899325)
			(xy 299.492218 -330.954066) (xy 299.48439 -331.008243) (xy 299.468896 -331.060745) (xy 299.446052 -331.110491)
			(xy 299.41633 -331.156459) (xy 299.39869 -331.177392) (xy 299.392594 -331.184504) (xy 299.386244 -331.201522)
			(xy 299.386244 -331.286866) (xy 299.392594 -331.303884) (xy 299.39869 -331.310996) (xy 299.416324 -331.331934)
			(xy 299.446048 -331.377901) (xy 299.468893 -331.427647) (xy 299.484389 -331.480148) (xy 299.492217 -331.534325)
			(xy 299.492218 -331.589066) (xy 299.48439 -331.643243) (xy 299.468896 -331.695745) (xy 299.446052 -331.745491)
			(xy 299.41633 -331.791459) (xy 299.39869 -331.812392) (xy 299.392594 -331.819504) (xy 299.386244 -331.836522)
			(xy 299.386244 -331.921866) (xy 299.392594 -331.938884) (xy 299.39869 -331.945996) (xy 299.416324 -331.966934)
			(xy 299.446048 -332.012901) (xy 299.468893 -332.062647) (xy 299.484389 -332.115148) (xy 299.492217 -332.169325)
			(xy 299.492218 -332.224066) (xy 299.48439 -332.278243) (xy 299.468896 -332.330745) (xy 299.446052 -332.380491)
			(xy 299.41633 -332.426459) (xy 299.39869 -332.447392) (xy 299.392594 -332.454504) (xy 299.386244 -332.471522)
			(xy 299.386244 -332.556866) (xy 299.392594 -332.573884) (xy 299.39869 -332.580996) (xy 299.416324 -332.601934)
			(xy 299.446048 -332.647901) (xy 299.468893 -332.697647) (xy 299.484389 -332.750148) (xy 299.492217 -332.804325)
			(xy 299.492218 -332.859066) (xy 299.48439 -332.913243) (xy 299.468896 -332.965745) (xy 299.446052 -333.015491)
			(xy 299.41633 -333.061459) (xy 299.39869 -333.082392) (xy 299.392594 -333.089504) (xy 299.386244 -333.106522)
			(xy 299.386244 -333.191866) (xy 299.392594 -333.208884) (xy 299.39869 -333.215996) (xy 299.416324 -333.236934)
			(xy 299.446048 -333.282901) (xy 299.468893 -333.332647) (xy 299.484389 -333.385148) (xy 299.492217 -333.439325)
			(xy 299.492218 -333.494066) (xy 299.48439 -333.548243) (xy 299.468896 -333.600745) (xy 299.446052 -333.650491)
			(xy 299.41633 -333.696459) (xy 299.39869 -333.717392) (xy 299.392594 -333.724504) (xy 299.386244 -333.741522)
			(xy 299.386244 -333.826866) (xy 299.392594 -333.843884) (xy 299.39869 -333.850996) (xy 299.416324 -333.871934)
			(xy 299.446048 -333.917901) (xy 299.468893 -333.967647) (xy 299.484389 -334.020148) (xy 299.492217 -334.074325)
			(xy 299.492218 -334.129066) (xy 299.48439 -334.183243) (xy 299.468896 -334.235745) (xy 299.446052 -334.285491)
			(xy 299.41633 -334.331459) (xy 299.39869 -334.352392) (xy 299.392594 -334.359504) (xy 299.386244 -334.376522)
			(xy 299.386244 -334.461866) (xy 299.392594 -334.478884) (xy 299.39869 -334.485996) (xy 299.416339 -334.50692)
			(xy 299.44605 -334.552895) (xy 299.468884 -334.602644) (xy 299.484373 -334.655147) (xy 299.492198 -334.709324)
			(xy 299.49267 -334.736694) (xy 301.472854 -334.736694) (xy 301.473303 -334.709323) (xy 301.481123 -334.655143)
			(xy 301.496615 -334.602639) (xy 301.519461 -334.552892) (xy 301.54919 -334.506927) (xy 301.566834 -334.485996)
			(xy 301.57293 -334.478884) (xy 301.57928 -334.461866) (xy 301.57928 -334.376522) (xy 301.57293 -334.359504)
			(xy 301.566834 -334.352392) (xy 301.549187 -334.331464) (xy 301.519462 -334.285496) (xy 301.496617 -334.235749)
			(xy 301.481121 -334.183246) (xy 301.473292 -334.129066) (xy 301.473293 -334.074325) (xy 301.481122 -334.020145)
			(xy 301.49662 -333.967643) (xy 301.519466 -333.917896) (xy 301.549193 -333.871929) (xy 301.566834 -333.850996)
			(xy 301.57293 -333.843884) (xy 301.57928 -333.826866) (xy 301.57928 -333.741522) (xy 301.57293 -333.724504)
			(xy 301.566834 -333.717392) (xy 301.549187 -333.696464) (xy 301.519462 -333.650496) (xy 301.496617 -333.600749)
			(xy 301.481121 -333.548246) (xy 301.473292 -333.494066) (xy 301.473293 -333.439325) (xy 301.481122 -333.385145)
			(xy 301.49662 -333.332643) (xy 301.519466 -333.282896) (xy 301.549193 -333.236929) (xy 301.566834 -333.215996)
			(xy 301.57293 -333.208884) (xy 301.57928 -333.191866) (xy 301.57928 -333.106522) (xy 301.57293 -333.089504)
			(xy 301.566834 -333.082392) (xy 301.549187 -333.061464) (xy 301.519462 -333.015496) (xy 301.496617 -332.965749)
			(xy 301.481121 -332.913246) (xy 301.473292 -332.859066) (xy 301.473293 -332.804325) (xy 301.481122 -332.750145)
			(xy 301.49662 -332.697643) (xy 301.519466 -332.647896) (xy 301.549193 -332.601929) (xy 301.566834 -332.580996)
			(xy 301.57293 -332.573884) (xy 301.57928 -332.556866) (xy 301.57928 -332.471522) (xy 301.57293 -332.454504)
			(xy 301.566834 -332.447392) (xy 301.549187 -332.426464) (xy 301.519462 -332.380496) (xy 301.496617 -332.330749)
			(xy 301.481121 -332.278246) (xy 301.473292 -332.224066) (xy 301.473293 -332.169325) (xy 301.481122 -332.115145)
			(xy 301.49662 -332.062643) (xy 301.519466 -332.012896) (xy 301.549193 -331.966929) (xy 301.566834 -331.945996)
			(xy 301.57293 -331.938884) (xy 301.57928 -331.921866) (xy 301.57928 -331.836522) (xy 301.57293 -331.819504)
			(xy 301.566834 -331.812392) (xy 301.549187 -331.791464) (xy 301.519462 -331.745496) (xy 301.496617 -331.695749)
			(xy 301.481121 -331.643246) (xy 301.473292 -331.589066) (xy 301.473293 -331.534325) (xy 301.481122 -331.480145)
			(xy 301.49662 -331.427643) (xy 301.519466 -331.377896) (xy 301.549193 -331.331929) (xy 301.566834 -331.310996)
			(xy 301.57293 -331.303884) (xy 301.57928 -331.286866) (xy 301.57928 -331.201522) (xy 301.57293 -331.184504)
			(xy 301.566834 -331.177392) (xy 301.549187 -331.156464) (xy 301.519462 -331.110496) (xy 301.496617 -331.060749)
			(xy 301.481121 -331.008246) (xy 301.473292 -330.954066) (xy 301.473293 -330.899325) (xy 301.481122 -330.845145)
			(xy 301.49662 -330.792643) (xy 301.519466 -330.742896) (xy 301.549193 -330.696929) (xy 301.566834 -330.675996)
			(xy 301.57293 -330.668884) (xy 301.57928 -330.651866) (xy 301.57928 -330.566522) (xy 301.57293 -330.549504)
			(xy 301.566834 -330.542392) (xy 301.549183 -330.521469) (xy 301.519472 -330.475495) (xy 301.496638 -330.425745)
			(xy 301.481149 -330.373242) (xy 301.473325 -330.319064) (xy 301.472854 -330.291694) (xy 301.473372 -330.264444)
			(xy 301.481128 -330.2105) (xy 301.496482 -330.158208) (xy 301.519121 -330.108633) (xy 301.548585 -330.062785)
			(xy 301.584273 -330.021595) (xy 301.625459 -329.985904) (xy 301.671305 -329.956437) (xy 301.720878 -329.933794)
			(xy 301.773168 -329.918435) (xy 301.827112 -329.910674) (xy 301.854362 -329.910186) (xy 301.881731 -329.910678)
			(xy 301.935909 -329.91849) (xy 301.988412 -329.933973) (xy 302.038159 -329.956809) (xy 302.084127 -329.986528)
			(xy 302.10506 -330.004166) (xy 302.112172 -330.010262) (xy 302.12919 -330.016612) (xy 302.214534 -330.016612)
			(xy 302.231552 -330.010262) (xy 302.238664 -330.004166) (xy 302.259597 -329.986525) (xy 302.305565 -329.956801)
			(xy 302.355311 -329.933955) (xy 302.407813 -329.918459) (xy 302.461991 -329.91063) (xy 302.516733 -329.91063)
			(xy 302.570911 -329.918459) (xy 302.623413 -329.933955) (xy 302.673159 -329.956801) (xy 302.719127 -329.986525)
			(xy 302.74006 -330.004166) (xy 302.747172 -330.010262) (xy 302.76419 -330.016612) (xy 302.849534 -330.016612)
			(xy 302.866552 -330.010262) (xy 302.873664 -330.004166) (xy 302.894594 -329.986525) (xy 302.940568 -329.956815)
			(xy 302.990316 -329.93398) (xy 303.042817 -329.918489) (xy 303.096993 -329.91066) (xy 303.124362 -329.910186)
			(xy 303.151614 -329.910691) (xy 303.205563 -329.918442) (xy 303.25786 -329.933793) (xy 303.307439 -329.956431)
			(xy 303.353292 -329.985894) (xy 303.394485 -330.021584) (xy 303.430179 -330.062773) (xy 303.459648 -330.108622)
			(xy 303.482291 -330.158199) (xy 303.497648 -330.210494) (xy 303.505406 -330.264442) (xy 303.50587 -330.291694)
			(xy 303.505408 -330.319064) (xy 303.49759 -330.373244) (xy 303.482101 -330.425747) (xy 303.459258 -330.475494)
			(xy 303.429532 -330.521461) (xy 303.41189 -330.542392) (xy 303.405794 -330.549504) (xy 303.399444 -330.566522)
			(xy 303.399444 -330.651866) (xy 303.405794 -330.668884) (xy 303.41189 -330.675996) (xy 303.429524 -330.696934)
			(xy 303.459248 -330.742901) (xy 303.482093 -330.792647) (xy 303.497589 -330.845148) (xy 303.505417 -330.899325)
			(xy 303.505418 -330.954066) (xy 303.49759 -331.008243) (xy 303.482096 -331.060745) (xy 303.459252 -331.110491)
			(xy 303.42953 -331.156459) (xy 303.41189 -331.177392) (xy 303.405794 -331.184504) (xy 303.399444 -331.201522)
			(xy 303.399444 -331.286866) (xy 303.405794 -331.303884) (xy 303.41189 -331.310996) (xy 303.429524 -331.331934)
			(xy 303.459248 -331.377901) (xy 303.482093 -331.427647) (xy 303.497589 -331.480148) (xy 303.505417 -331.534325)
			(xy 303.505418 -331.589066) (xy 303.49759 -331.643243) (xy 303.482096 -331.695745) (xy 303.459252 -331.745491)
			(xy 303.42953 -331.791459) (xy 303.41189 -331.812392) (xy 303.405794 -331.819504) (xy 303.399444 -331.836522)
			(xy 303.399444 -331.921866) (xy 303.405794 -331.938884) (xy 303.41189 -331.945996) (xy 303.429524 -331.966934)
			(xy 303.459248 -332.012901) (xy 303.482093 -332.062647) (xy 303.497589 -332.115148) (xy 303.505417 -332.169325)
			(xy 303.505418 -332.224066) (xy 303.49759 -332.278243) (xy 303.482096 -332.330745) (xy 303.459252 -332.380491)
			(xy 303.42953 -332.426459) (xy 303.41189 -332.447392) (xy 303.405794 -332.454504) (xy 303.399444 -332.471522)
			(xy 303.399444 -332.556866) (xy 303.405794 -332.573884) (xy 303.41189 -332.580996) (xy 303.429524 -332.601934)
			(xy 303.459248 -332.647901) (xy 303.482093 -332.697647) (xy 303.497589 -332.750148) (xy 303.505417 -332.804325)
			(xy 303.505418 -332.859066) (xy 303.49759 -332.913243) (xy 303.482096 -332.965745) (xy 303.459252 -333.015491)
			(xy 303.42953 -333.061459) (xy 303.41189 -333.082392) (xy 303.405794 -333.089504) (xy 303.399444 -333.106522)
			(xy 303.399444 -333.191866) (xy 303.405794 -333.208884) (xy 303.41189 -333.215996) (xy 303.429524 -333.236934)
			(xy 303.459248 -333.282901) (xy 303.482093 -333.332647) (xy 303.497589 -333.385148) (xy 303.505417 -333.439325)
			(xy 303.505418 -333.494066) (xy 303.49759 -333.548243) (xy 303.482096 -333.600745) (xy 303.459252 -333.650491)
			(xy 303.42953 -333.696459) (xy 303.41189 -333.717392) (xy 303.405794 -333.724504) (xy 303.399444 -333.741522)
			(xy 303.399444 -333.826866) (xy 303.405794 -333.843884) (xy 303.41189 -333.850996) (xy 303.429524 -333.871934)
			(xy 303.459248 -333.917901) (xy 303.482093 -333.967647) (xy 303.497589 -334.020148) (xy 303.505417 -334.074325)
			(xy 303.505418 -334.129066) (xy 303.49759 -334.183243) (xy 303.482096 -334.235745) (xy 303.459252 -334.285491)
			(xy 303.42953 -334.331459) (xy 303.41189 -334.352392) (xy 303.405794 -334.359504) (xy 303.399444 -334.376522)
			(xy 303.399444 -334.461866) (xy 303.405794 -334.478884) (xy 303.41189 -334.485996) (xy 303.429539 -334.50692)
			(xy 303.45925 -334.552895) (xy 303.482084 -334.602644) (xy 303.497573 -334.655147) (xy 303.505398 -334.709324)
			(xy 303.50587 -334.736694) (xy 303.505439 -334.763948) (xy 303.497682 -334.817902) (xy 303.482325 -334.870203)
			(xy 303.45968 -334.919786) (xy 303.430209 -334.965641) (xy 303.394512 -335.006835) (xy 303.353315 -335.042528)
			(xy 303.307458 -335.071995) (xy 303.257873 -335.094636) (xy 303.205571 -335.109989) (xy 303.151616 -335.117741)
			(xy 303.124362 -335.118202) (xy 303.096993 -335.117699) (xy 303.042816 -335.10989) (xy 302.990313 -335.09441)
			(xy 302.940565 -335.071576) (xy 302.894597 -335.041859) (xy 302.873664 -335.024222) (xy 302.866552 -335.018126)
			(xy 302.849534 -335.011776) (xy 302.76419 -335.011776) (xy 302.747172 -335.018126) (xy 302.74006 -335.024222)
			(xy 302.719127 -335.041863) (xy 302.673159 -335.071587) (xy 302.623413 -335.094433) (xy 302.570911 -335.109929)
			(xy 302.516733 -335.117758) (xy 302.461991 -335.117758) (xy 302.407813 -335.109929) (xy 302.355311 -335.094433)
			(xy 302.305565 -335.071587) (xy 302.259597 -335.041863) (xy 302.238664 -335.024222) (xy 302.231552 -335.018126)
			(xy 302.214534 -335.011776) (xy 302.12919 -335.011776) (xy 302.112172 -335.018126) (xy 302.10506 -335.024222)
			(xy 302.084119 -335.04185) (xy 302.038148 -335.071563) (xy 301.988403 -335.0944) (xy 301.935904 -335.109894)
			(xy 301.88173 -335.117726) (xy 301.854362 -335.118202) (xy 301.82711 -335.117758) (xy 301.77316 -335.109996)
			(xy 301.720864 -335.094635) (xy 301.671286 -335.071989) (xy 301.625436 -335.042519) (xy 301.584246 -335.006823)
			(xy 301.548555 -334.965629) (xy 301.519089 -334.919775) (xy 301.496449 -334.870195) (xy 301.481095 -334.817897)
			(xy 301.473339 -334.763947) (xy 301.472854 -334.736694) (xy 299.49267 -334.736694) (xy 299.492239 -334.763948)
			(xy 299.484482 -334.817902) (xy 299.469125 -334.870203) (xy 299.44648 -334.919786) (xy 299.417009 -334.965641)
			(xy 299.381312 -335.006835) (xy 299.340115 -335.042528) (xy 299.294258 -335.071995) (xy 299.244673 -335.094636)
			(xy 299.192371 -335.109989) (xy 299.138416 -335.117741) (xy 299.111162 -335.118202) (xy 299.083793 -335.117699)
			(xy 299.029616 -335.10989) (xy 298.977113 -335.09441) (xy 298.927365 -335.071576) (xy 298.881397 -335.041859)
			(xy 298.860464 -335.024222) (xy 298.853352 -335.018126) (xy 298.836334 -335.011776) (xy 298.75099 -335.011776)
			(xy 298.733972 -335.018126) (xy 298.72686 -335.024222) (xy 298.705919 -335.04185) (xy 298.659948 -335.071563)
			(xy 298.610203 -335.0944) (xy 298.557704 -335.109894) (xy 298.50353 -335.117726) (xy 298.476162 -335.118202)
			(xy 298.446604 -335.11768) (xy 298.388194 -335.108583) (xy 298.331891 -335.090567) (xy 298.30522 -335.077816)
			(xy 298.293282 -335.07172) (xy 298.26712 -335.07299) (xy 298.18203 -335.125314) (xy 298.174832 -335.130105)
			(xy 298.163974 -335.143551) (xy 298.158231 -335.159852) (xy 298.1579 -335.168494) (xy 298.1579 -348.296738)
			(xy 298.157413 -348.321713) (xy 298.149626 -348.371051) (xy 298.134219 -348.418564) (xy 298.11157 -348.463082)
			(xy 298.082237 -348.50351) (xy 298.064936 -348.521528) (xy 297.881764 -348.7047) (xy 300.682621 -348.7047)
			(xy 300.686789 -348.649082) (xy 300.6992 -348.594706) (xy 300.719576 -348.542788) (xy 300.747462 -348.494485)
			(xy 300.782236 -348.450879) (xy 300.823121 -348.412942) (xy 300.869203 -348.381523) (xy 300.919453 -348.357322)
			(xy 300.972748 -348.340881) (xy 301.027899 -348.332566) (xy 301.055786 -348.332044) (xy 301.082207 -348.332523)
			(xy 301.134521 -348.33997) (xy 301.185259 -348.354731) (xy 301.233403 -348.376509) (xy 301.27799 -348.404869)
			(xy 301.298356 -348.421706) (xy 301.305214 -348.427802) (xy 301.322232 -348.433898) (xy 301.40656 -348.433898)
			(xy 301.423578 -348.427802) (xy 301.430436 -348.421706) (xy 301.450802 -348.404867) (xy 301.495388 -348.376502)
			(xy 301.543532 -348.354715) (xy 301.594269 -348.339944) (xy 301.646584 -348.332484) (xy 301.699428 -348.332484)
			(xy 301.751743 -348.339944) (xy 301.80248 -348.354715) (xy 301.850624 -348.376502) (xy 301.89521 -348.404867)
			(xy 301.915576 -348.421706) (xy 301.922434 -348.427802) (xy 301.939452 -348.433898) (xy 302.02378 -348.433898)
			(xy 302.040798 -348.427802) (xy 302.047656 -348.421706) (xy 302.072125 -348.40159) (xy 302.12653 -348.369155)
			(xy 302.15586 -348.35719) (xy 302.166782 -348.352872) (xy 302.182276 -348.336616) (xy 302.214026 -348.239842)
			(xy 302.211232 -348.21749) (xy 302.204882 -348.207584) (xy 302.190712 -348.184479) (xy 302.168299 -348.13513)
			(xy 302.153099 -348.083105) (xy 302.145418 -348.029452) (xy 302.144938 -348.002352) (xy 302.145426 -347.974778)
			(xy 302.153372 -347.920206) (xy 302.169092 -347.867346) (xy 302.192258 -347.817299) (xy 302.222387 -347.771109)
			(xy 302.258852 -347.729738) (xy 302.279558 -347.711522) (xy 302.287671 -347.703915) (xy 302.297026 -347.683767)
			(xy 302.297592 -347.67266) (xy 302.297592 -347.595444) (xy 302.297018 -347.584335) (xy 302.287684 -347.564176)
			(xy 302.279558 -347.556582) (xy 302.258827 -347.538393) (xy 302.22236 -347.497019) (xy 302.192231 -347.450824)
			(xy 302.169069 -347.400772) (xy 302.153357 -347.347906) (xy 302.145421 -347.293328) (xy 302.144938 -347.265752)
			(xy 302.145424 -347.238501) (xy 302.15318 -347.184553) (xy 302.168535 -347.132258) (xy 302.191177 -347.082681)
			(xy 302.220643 -347.036831) (xy 302.256334 -346.99564) (xy 302.297525 -346.959949) (xy 302.343375 -346.930483)
			(xy 302.392952 -346.907841) (xy 302.445247 -346.892486) (xy 302.499195 -346.88473) (xy 302.553697 -346.88473)
			(xy 302.607645 -346.892486) (xy 302.65994 -346.907841) (xy 302.709517 -346.930483) (xy 302.755367 -346.959949)
			(xy 302.796558 -346.99564) (xy 302.832249 -347.036831) (xy 302.861715 -347.082681) (xy 302.884357 -347.132258)
			(xy 302.899712 -347.184553) (xy 302.907468 -347.238501) (xy 302.907954 -347.265752) (xy 302.907471 -347.293326)
			(xy 302.899525 -347.347899) (xy 302.883804 -347.400759) (xy 302.860637 -347.450806) (xy 302.830507 -347.496995)
			(xy 302.794041 -347.538367) (xy 302.773334 -347.556582) (xy 302.765218 -347.564186) (xy 302.755865 -347.584337)
			(xy 302.7553 -347.595444) (xy 302.7553 -347.67266) (xy 302.755874 -347.683769) (xy 302.765208 -347.703928)
			(xy 302.773334 -347.711522) (xy 302.794066 -347.72971) (xy 302.830533 -347.771085) (xy 302.860662 -347.81728)
			(xy 302.883824 -347.867332) (xy 302.899536 -347.920198) (xy 302.907471 -347.974776) (xy 302.907954 -348.002352)
			(xy 302.907398 -348.031389) (xy 302.898589 -348.088791) (xy 302.881184 -348.144195) (xy 302.855582 -348.196322)
			(xy 302.822378 -348.243967) (xy 302.782336 -348.28603) (xy 302.736382 -348.321538) (xy 302.685578 -348.349673)
			(xy 302.658526 -348.360238) (xy 302.647604 -348.364302) (xy 302.631856 -348.380304) (xy 302.598582 -348.47657)
			(xy 302.601122 -348.498922) (xy 302.607218 -348.508828) (xy 302.620417 -348.530985) (xy 302.641215 -348.57818)
			(xy 302.655303 -348.627793) (xy 302.66241 -348.678875) (xy 302.662844 -348.704662) (xy 302.662331 -348.731278)
			(xy 302.65476 -348.783968) (xy 302.639768 -348.835044) (xy 302.61766 -348.883467) (xy 302.588885 -348.928251)
			(xy 302.554029 -348.968484) (xy 302.513802 -349.003346) (xy 302.469024 -349.032129) (xy 302.420605 -349.054246)
			(xy 302.369531 -349.069247) (xy 302.316842 -349.076826) (xy 302.290226 -349.07728) (xy 302.263806 -349.076788)
			(xy 302.211492 -349.069344) (xy 302.160755 -349.054585) (xy 302.11261 -349.03281) (xy 302.068023 -349.004453)
			(xy 302.047656 -348.987618) (xy 302.040798 -348.981522) (xy 302.02378 -348.975426) (xy 301.939452 -348.975426)
			(xy 301.922434 -348.981522) (xy 301.915576 -348.987618) (xy 301.89521 -349.004457) (xy 301.850624 -349.032822)
			(xy 301.80248 -349.054609) (xy 301.751743 -349.06938) (xy 301.699428 -349.07684) (xy 301.646584 -349.07684)
			(xy 301.594269 -349.06938) (xy 301.543532 -349.054609) (xy 301.495388 -349.032822) (xy 301.450802 -349.004457)
			(xy 301.430436 -348.987618) (xy 301.423578 -348.981522) (xy 301.40656 -348.975426) (xy 301.322232 -348.975426)
			(xy 301.305214 -348.981522) (xy 301.298356 -348.987618) (xy 301.277997 -349.004464) (xy 301.233406 -349.032821)
			(xy 301.18526 -349.0546) (xy 301.134522 -349.069365) (xy 301.082208 -349.076822) (xy 301.055786 -349.07728)
			(xy 301.027899 -349.076834) (xy 300.972748 -349.068519) (xy 300.919453 -349.052078) (xy 300.869203 -349.027877)
			(xy 300.823121 -348.996458) (xy 300.782236 -348.958521) (xy 300.747462 -348.914915) (xy 300.719576 -348.866612)
			(xy 300.6992 -348.814694) (xy 300.686789 -348.760318) (xy 300.682621 -348.7047) (xy 297.881764 -348.7047)
			(xy 297.537632 -349.048832) (xy 297.530734 -349.056483) (xy 297.523054 -349.075573) (xy 297.523444 -349.096146)
			(xy 297.527218 -349.105728) (xy 297.572938 -349.207074) (xy 297.599862 -349.223076) (xy 297.615864 -349.22206)
			(xy 297.640248 -349.221298) (xy 297.667497 -349.221775) (xy 297.721441 -349.229537) (xy 297.773731 -349.244897)
			(xy 297.823303 -349.267541) (xy 297.869148 -349.297009) (xy 297.910333 -349.332701) (xy 297.94602 -349.373891)
			(xy 297.975482 -349.41974) (xy 297.99812 -349.469314) (xy 298.013473 -349.521606) (xy 298.021228 -349.575551)
			(xy 298.021228 -349.630049) (xy 298.013473 -349.683994) (xy 297.99812 -349.736286) (xy 297.975482 -349.78586)
			(xy 297.94602 -349.831709) (xy 297.910333 -349.872899) (xy 297.869148 -349.908591) (xy 297.823303 -349.938059)
			(xy 297.773731 -349.960703) (xy 297.721441 -349.976063) (xy 297.667497 -349.983825) (xy 297.640248 -349.984314)
			(xy 297.613289 -349.983875) (xy 297.559908 -349.976276) (xy 297.508129 -349.961239) (xy 297.458983 -349.939061)
			(xy 297.413448 -349.910185) (xy 297.372433 -349.875187) (xy 297.354244 -349.855282) (xy 297.343576 -349.843344)
			(xy 297.31335 -349.835724) (xy 297.209464 -349.875094) (xy 297.19996 -349.879116) (xy 297.185021 -349.893326)
			(xy 297.176911 -349.912282) (xy 297.176444 -349.922592) (xy 297.176444 -350.114616) (xy 297.193462 -350.140016)
			(xy 297.20794 -350.145858) (xy 297.233619 -350.157173) (xy 297.28168 -350.186131) (xy 297.324985 -350.221813)
			(xy 297.3626 -350.263449) (xy 297.393715 -350.310143) (xy 297.417659 -350.36089) (xy 297.433916 -350.414594)
			(xy 297.442137 -350.4701) (xy 297.442636 -350.498156) (xy 297.442104 -350.525407) (xy 297.434354 -350.579354)
			(xy 297.419005 -350.631648) (xy 297.396369 -350.681226) (xy 297.366908 -350.727078) (xy 297.331222 -350.768271)
			(xy 297.290036 -350.803965) (xy 297.24419 -350.833435) (xy 297.194616 -350.856079) (xy 297.142324 -350.871438)
			(xy 297.088378 -350.879199) (xy 297.061128 -350.879664) (xy 297.032823 -350.879105) (xy 296.976833 -350.870764)
			(xy 296.922691 -350.854234) (xy 296.871591 -350.829876) (xy 296.824656 -350.798228) (xy 296.782919 -350.759985)
			(xy 296.747297 -350.715989) (xy 296.718576 -350.667208) (xy 296.697386 -350.614715) (xy 296.690288 -350.58731)
			(xy 296.68851 -350.580452) (xy 296.681906 -350.568514) (xy 296.6339 -350.520508) (xy 296.616573 -350.502511)
			(xy 296.587224 -350.462086) (xy 296.564565 -350.417564) (xy 296.549157 -350.370043) (xy 296.54138 -350.320696)
			(xy 296.540936 -350.295718) (xy 296.540936 -349.278194) (xy 296.541399 -349.253219) (xy 296.549194 -349.20388)
			(xy 296.564609 -349.156368) (xy 296.587262 -349.11185) (xy 296.616598 -349.071422) (xy 296.6339 -349.053404)
			(xy 296.761408 -348.92615) (xy 296.768216 -348.918665) (xy 296.775846 -348.899945) (xy 296.77566 -348.879731)
			(xy 296.772076 -348.87027) (xy 296.729404 -348.769178) (xy 296.703496 -348.752414) (xy 296.687748 -348.752668)
			(xy 296.681906 -348.752668) (xy 296.654651 -348.752239) (xy 296.600697 -348.744482) (xy 296.548396 -348.729124)
			(xy 296.498814 -348.70648) (xy 296.452958 -348.677009) (xy 296.411765 -348.641311) (xy 296.376071 -348.600114)
			(xy 296.346604 -348.554257) (xy 296.323964 -348.504672) (xy 296.308611 -348.452369) (xy 296.300859 -348.398415)
			(xy 296.300398 -348.37116) (xy 294.237323 -348.37116) (xy 294.216328 -348.443042) (xy 294.2209 -348.466918)
			(xy 294.228266 -348.47657) (xy 294.246588 -348.501214) (xy 294.275706 -348.555277) (xy 294.295563 -348.613383)
			(xy 294.305622 -348.673959) (xy 294.306244 -348.704662) (xy 294.305731 -348.731278) (xy 294.29816 -348.783968)
			(xy 294.283168 -348.835044) (xy 294.26106 -348.883467) (xy 294.232285 -348.928251) (xy 294.197429 -348.968484)
			(xy 294.157202 -349.003346) (xy 294.112424 -349.032129) (xy 294.064005 -349.054246) (xy 294.012931 -349.069247)
			(xy 293.960242 -349.076826) (xy 293.933626 -349.07728) (xy 293.907206 -349.076788) (xy 293.854892 -349.069344)
			(xy 293.804155 -349.054585) (xy 293.75601 -349.03281) (xy 293.711423 -349.004453) (xy 293.691056 -348.987618)
			(xy 293.684198 -348.981522) (xy 293.66718 -348.975426) (xy 293.582852 -348.975426) (xy 293.565834 -348.981522)
			(xy 293.558976 -348.987618) (xy 293.53861 -349.004457) (xy 293.494024 -349.032822) (xy 293.44588 -349.054609)
			(xy 293.395143 -349.06938) (xy 293.342828 -349.07684) (xy 293.289984 -349.07684) (xy 293.237669 -349.06938)
			(xy 293.186932 -349.054609) (xy 293.138788 -349.032822) (xy 293.094202 -349.004457) (xy 293.073836 -348.987618)
			(xy 293.066978 -348.981522) (xy 293.04996 -348.975426) (xy 292.965632 -348.975426) (xy 292.948614 -348.981522)
			(xy 292.941756 -348.987618) (xy 292.921397 -349.004464) (xy 292.876806 -349.032821) (xy 292.82866 -349.0546)
			(xy 292.777922 -349.069365) (xy 292.725608 -349.076822) (xy 292.699186 -349.07728) (xy 292.671299 -349.076834)
			(xy 292.616148 -349.068519) (xy 292.562853 -349.052078) (xy 292.512603 -349.027877) (xy 292.466521 -348.996458)
			(xy 292.425636 -348.958521) (xy 292.390862 -348.914915) (xy 292.362976 -348.866612) (xy 292.3426 -348.814694)
			(xy 292.330189 -348.760318) (xy 292.326021 -348.7047) (xy 289.550564 -348.7047) (xy 289.207448 -349.047816)
			(xy 289.200622 -349.055241) (xy 289.192897 -349.07385) (xy 289.192987 -349.093999) (xy 289.196526 -349.103442)
			(xy 289.238944 -349.204534) (xy 289.264598 -349.221552) (xy 289.280092 -349.221298) (xy 289.283648 -349.221298)
			(xy 289.310897 -349.221775) (xy 289.364841 -349.229537) (xy 289.417131 -349.244897) (xy 289.466703 -349.267541)
			(xy 289.512548 -349.297009) (xy 289.553733 -349.332701) (xy 289.58942 -349.373891) (xy 289.618882 -349.41974)
			(xy 289.64152 -349.469314) (xy 289.656873 -349.521606) (xy 289.664628 -349.575551) (xy 289.664628 -349.630049)
			(xy 289.656873 -349.683994) (xy 289.64152 -349.736286) (xy 289.618882 -349.78586) (xy 289.58942 -349.831709)
			(xy 289.553733 -349.872899) (xy 289.512548 -349.908591) (xy 289.466703 -349.938059) (xy 289.417131 -349.960703)
			(xy 289.364841 -349.976063) (xy 289.310897 -349.983825) (xy 289.283648 -349.984314) (xy 289.253642 -349.983784)
			(xy 289.194366 -349.974415) (xy 289.137287 -349.955883) (xy 289.083812 -349.928647) (xy 289.035258 -349.893376)
			(xy 289.013646 -349.872554) (xy 289.002724 -349.861378) (xy 288.972752 -349.855536) (xy 288.87166 -349.897192)
			(xy 288.862529 -349.901401) (xy 288.848298 -349.915583) (xy 288.840591 -349.934137) (xy 288.840164 -349.944182)
			(xy 288.840164 -350.122998) (xy 288.855912 -350.147636) (xy 288.86912 -350.153986) (xy 288.893137 -350.165957)
			(xy 288.937828 -350.19566) (xy 288.977916 -350.231335) (xy 289.012607 -350.272275) (xy 289.041218 -350.317674)
			(xy 289.063183 -350.366635) (xy 289.07807 -350.418191) (xy 289.085583 -350.471325) (xy 289.086036 -350.498156)
			(xy 289.085504 -350.525407) (xy 289.077754 -350.579354) (xy 289.062405 -350.631648) (xy 289.039769 -350.681226)
			(xy 289.010308 -350.727078) (xy 288.974622 -350.768271) (xy 288.933436 -350.803965) (xy 288.88759 -350.833435)
			(xy 288.838016 -350.856079) (xy 288.785724 -350.871438) (xy 288.731778 -350.879199) (xy 288.704528 -350.879664)
			(xy 288.676223 -350.879105) (xy 288.620233 -350.870764) (xy 288.566091 -350.854234) (xy 288.514991 -350.829876)
			(xy 288.468056 -350.798228) (xy 288.426319 -350.759985) (xy 288.390697 -350.715989) (xy 288.361976 -350.667208)
			(xy 288.340786 -350.614715) (xy 288.333688 -350.58731) (xy 288.33191 -350.580452) (xy 288.325306 -350.568514)
			(xy 288.29762 -350.540828) (xy 288.280306 -350.522819) (xy 288.250954 -350.482397) (xy 288.228293 -350.437878)
			(xy 288.212882 -350.39036) (xy 288.205101 -350.341016) (xy 288.204656 -350.316038) (xy 288.204656 -349.283274)
			(xy 288.205163 -349.2583) (xy 288.212947 -349.208964) (xy 288.22835 -349.161452) (xy 288.250994 -349.116933)
			(xy 288.280322 -349.076503) (xy 288.29762 -349.058484) (xy 288.431224 -348.92488) (xy 288.438192 -348.917286)
			(xy 288.445847 -348.898164) (xy 288.445428 -348.877571) (xy 288.441638 -348.867984) (xy 288.39541 -348.766892)
			(xy 288.368232 -348.750636) (xy 288.35223 -348.751652) (xy 288.325306 -348.752668) (xy 288.298051 -348.752239)
			(xy 288.244097 -348.744482) (xy 288.191796 -348.729124) (xy 288.142214 -348.70648) (xy 288.096358 -348.677009)
			(xy 288.055165 -348.641311) (xy 288.019471 -348.600114) (xy 287.990004 -348.554257) (xy 287.967364 -348.504672)
			(xy 287.952011 -348.452369) (xy 287.944259 -348.398415) (xy 287.943798 -348.37116) (xy 285.959076 -348.37116)
			(xy 285.927546 -348.463616) (xy 285.930594 -348.486984) (xy 285.937198 -348.497144) (xy 285.952118 -348.520284)
			(xy 285.975735 -348.570018) (xy 285.991787 -348.622682) (xy 285.999927 -348.677134) (xy 286.000444 -348.704662)
			(xy 285.999931 -348.731278) (xy 285.99236 -348.783968) (xy 285.977368 -348.835044) (xy 285.95526 -348.883467)
			(xy 285.926485 -348.928251) (xy 285.891629 -348.968484) (xy 285.851402 -349.003346) (xy 285.806624 -349.032129)
			(xy 285.758205 -349.054246) (xy 285.707131 -349.069247) (xy 285.654442 -349.076826) (xy 285.627826 -349.07728)
			(xy 285.601406 -349.076788) (xy 285.549092 -349.069344) (xy 285.498355 -349.054585) (xy 285.45021 -349.03281)
			(xy 285.405623 -349.004453) (xy 285.385256 -348.987618) (xy 285.378398 -348.981522) (xy 285.36138 -348.975426)
			(xy 285.277052 -348.975426) (xy 285.260034 -348.981522) (xy 285.253176 -348.987618) (xy 285.23281 -349.004457)
			(xy 285.188224 -349.032822) (xy 285.14008 -349.054609) (xy 285.089343 -349.06938) (xy 285.037028 -349.07684)
			(xy 284.984184 -349.07684) (xy 284.931869 -349.06938) (xy 284.881132 -349.054609) (xy 284.832988 -349.032822)
			(xy 284.788402 -349.004457) (xy 284.768036 -348.987618) (xy 284.761178 -348.981522) (xy 284.74416 -348.975426)
			(xy 284.659832 -348.975426) (xy 284.642814 -348.981522) (xy 284.635956 -348.987618) (xy 284.615597 -349.004464)
			(xy 284.571006 -349.032821) (xy 284.52286 -349.0546) (xy 284.472122 -349.069365) (xy 284.419808 -349.076822)
			(xy 284.393386 -349.07728) (xy 284.365499 -349.076834) (xy 284.310348 -349.068519) (xy 284.257053 -349.052078)
			(xy 284.206803 -349.027877) (xy 284.160721 -348.996458) (xy 284.119836 -348.958521) (xy 284.085062 -348.914915)
			(xy 284.057176 -348.866612) (xy 284.0368 -348.814694) (xy 284.024389 -348.760318) (xy 284.020221 -348.7047)
			(xy 281.193964 -348.7047) (xy 280.847292 -349.051372) (xy 280.840188 -349.059166) (xy 280.832478 -349.078773)
			(xy 280.833272 -349.099826) (xy 280.837386 -349.109538) (xy 280.886662 -349.21063) (xy 280.91511 -349.226124)
			(xy 280.931366 -349.224092) (xy 280.94294 -349.222763) (xy 280.966198 -349.221366) (xy 280.977848 -349.221298)
			(xy 281.005097 -349.221775) (xy 281.059041 -349.229537) (xy 281.111331 -349.244897) (xy 281.160903 -349.267541)
			(xy 281.206748 -349.297009) (xy 281.247933 -349.332701) (xy 281.28362 -349.373891) (xy 281.313082 -349.41974)
			(xy 281.33572 -349.469314) (xy 281.351073 -349.521606) (xy 281.358828 -349.575551) (xy 281.358828 -349.630049)
			(xy 281.351073 -349.683994) (xy 281.33572 -349.736286) (xy 281.313082 -349.78586) (xy 281.28362 -349.831709)
			(xy 281.247933 -349.872899) (xy 281.206748 -349.908591) (xy 281.160903 -349.938059) (xy 281.111331 -349.960703)
			(xy 281.059041 -349.976063) (xy 281.005097 -349.983825) (xy 280.977848 -349.984314) (xy 280.949796 -349.983817)
			(xy 280.894298 -349.975588) (xy 280.840605 -349.959316) (xy 280.789876 -349.935352) (xy 280.743205 -349.904214)
			(xy 280.72207 -349.885762) (xy 280.71064 -349.875602) (xy 280.681176 -349.870776) (xy 280.58237 -349.914718)
			(xy 280.573586 -349.919105) (xy 280.559947 -349.933205) (xy 280.552591 -349.951391) (xy 280.552144 -349.9612)
			(xy 280.552144 -350.117156) (xy 280.552558 -350.126322) (xy 280.55903 -350.143473) (xy 280.571151 -350.157225)
			(xy 280.579068 -350.16186) (xy 280.604739 -350.176225) (xy 280.651686 -350.211667) (xy 280.69264 -350.253893)
			(xy 280.726629 -350.301903) (xy 280.75285 -350.354559) (xy 280.77068 -350.410616) (xy 280.779697 -350.468744)
			(xy 280.780236 -350.498156) (xy 280.779704 -350.525407) (xy 280.771954 -350.579354) (xy 280.756605 -350.631648)
			(xy 280.733969 -350.681226) (xy 280.704508 -350.727078) (xy 280.668822 -350.768271) (xy 280.627636 -350.803965)
			(xy 280.58179 -350.833435) (xy 280.532216 -350.856079) (xy 280.479924 -350.871438) (xy 280.425978 -350.879199)
			(xy 280.398728 -350.879664) (xy 280.370423 -350.879105) (xy 280.314433 -350.870764) (xy 280.260291 -350.854234)
			(xy 280.209191 -350.829876) (xy 280.162256 -350.798228) (xy 280.120519 -350.759985) (xy 280.084897 -350.715989)
			(xy 280.056176 -350.667208) (xy 280.034986 -350.614715) (xy 280.027888 -350.58731) (xy 280.02611 -350.580452)
			(xy 280.019506 -350.568514) (xy 280.0096 -350.558608) (xy 279.992273 -350.540611) (xy 279.962924 -350.500186)
			(xy 279.940265 -350.455664) (xy 279.924857 -350.408143) (xy 279.91708 -350.358796) (xy 279.916636 -350.333818)
			(xy 279.916636 -349.214694) (xy 279.917099 -349.189719) (xy 279.924894 -349.14038) (xy 279.940309 -349.092868)
			(xy 279.962962 -349.04835) (xy 279.992298 -349.007922) (xy 280.0096 -348.989904) (xy 280.073862 -348.925896)
			(xy 280.080515 -348.918591) (xy 280.088108 -348.900368) (xy 280.088263 -348.880627) (xy 280.085038 -348.871286)
			(xy 280.045414 -348.770448) (xy 280.020776 -348.752922) (xy 280.005536 -348.752414) (xy 279.978953 -348.75101)
			(xy 279.926542 -348.741684) (xy 279.875937 -348.725162) (xy 279.82812 -348.701765) (xy 279.784021 -348.671947)
			(xy 279.744495 -348.636288) (xy 279.710311 -348.59548) (xy 279.682132 -348.550316) (xy 279.660506 -348.501672)
			(xy 279.645853 -348.450495) (xy 279.638458 -348.397777) (xy 279.637998 -348.37116) (xy 277.755699 -348.37116)
			(xy 277.754785 -348.371672) (xy 277.727918 -348.382336) (xy 277.717504 -348.3864) (xy 277.70201 -348.40164)
			(xy 277.667466 -348.494604) (xy 277.669244 -348.516194) (xy 277.674578 -348.5261) (xy 277.688923 -348.553648)
			(xy 277.709201 -348.612352) (xy 277.719452 -348.673608) (xy 277.720044 -348.704662) (xy 277.719531 -348.731278)
			(xy 277.71196 -348.783968) (xy 277.696968 -348.835044) (xy 277.67486 -348.883467) (xy 277.646085 -348.928251)
			(xy 277.611229 -348.968484) (xy 277.571002 -349.003346) (xy 277.526224 -349.032129) (xy 277.477805 -349.054246)
			(xy 277.426731 -349.069247) (xy 277.374042 -349.076826) (xy 277.347426 -349.07728) (xy 277.321006 -349.076788)
			(xy 277.268692 -349.069344) (xy 277.217955 -349.054585) (xy 277.16981 -349.03281) (xy 277.125223 -349.004453)
			(xy 277.104856 -348.987618) (xy 277.097998 -348.981522) (xy 277.08098 -348.975426) (xy 276.996652 -348.975426)
			(xy 276.979634 -348.981522) (xy 276.972776 -348.987618) (xy 276.95241 -349.004457) (xy 276.907824 -349.032822)
			(xy 276.85968 -349.054609) (xy 276.808943 -349.06938) (xy 276.756628 -349.07684) (xy 276.703784 -349.07684)
			(xy 276.651469 -349.06938) (xy 276.600732 -349.054609) (xy 276.552588 -349.032822) (xy 276.508002 -349.004457)
			(xy 276.487636 -348.987618) (xy 276.480778 -348.981522) (xy 276.46376 -348.975426) (xy 276.379432 -348.975426)
			(xy 276.362414 -348.981522) (xy 276.355556 -348.987618) (xy 276.335197 -349.004464) (xy 276.290606 -349.032821)
			(xy 276.24246 -349.0546) (xy 276.191722 -349.069365) (xy 276.139408 -349.076822) (xy 276.112986 -349.07728)
			(xy 276.085099 -349.076834) (xy 276.029948 -349.068519) (xy 275.976653 -349.052078) (xy 275.926403 -349.027877)
			(xy 275.880321 -348.996458) (xy 275.839436 -348.958521) (xy 275.804662 -348.914915) (xy 275.776776 -348.866612)
			(xy 275.7564 -348.814694) (xy 275.743989 -348.760318) (xy 275.739821 -348.7047) (xy 272.938964 -348.7047)
			(xy 272.594832 -349.048832) (xy 272.587934 -349.056483) (xy 272.580254 -349.075573) (xy 272.580644 -349.096146)
			(xy 272.584418 -349.105728) (xy 272.630138 -349.207074) (xy 272.657062 -349.223076) (xy 272.673064 -349.22206)
			(xy 272.697448 -349.221298) (xy 272.724695 -349.22183) (xy 272.778633 -349.229591) (xy 272.830918 -349.24495)
			(xy 272.880485 -349.267593) (xy 272.926325 -349.29706) (xy 272.967505 -349.33275) (xy 273.003187 -349.373938)
			(xy 273.032644 -349.419784) (xy 273.055277 -349.469355) (xy 273.070625 -349.521643) (xy 273.078376 -349.575583)
			(xy 273.078372 -349.630077) (xy 273.070612 -349.684016) (xy 273.055256 -349.736301) (xy 273.032615 -349.785869)
			(xy 273.003151 -349.83171) (xy 272.967462 -349.872892) (xy 272.926277 -349.908576) (xy 272.880432 -349.938035)
			(xy 272.830862 -349.960671) (xy 272.778575 -349.976021) (xy 272.724635 -349.983775) (xy 272.670141 -349.983773)
			(xy 272.616202 -349.976016) (xy 272.563916 -349.960662) (xy 272.514347 -349.938024) (xy 272.468504 -349.908562)
			(xy 272.427321 -349.872875) (xy 272.391635 -349.831691) (xy 272.362173 -349.785848) (xy 272.339536 -349.736279)
			(xy 272.324182 -349.683992) (xy 272.316427 -349.630053) (xy 272.31594 -349.602806) (xy 272.316702 -349.578422)
			(xy 272.317718 -349.56242) (xy 272.301716 -349.535496) (xy 272.20037 -349.489776) (xy 272.1908 -349.485911)
			(xy 272.170183 -349.485461) (xy 272.151069 -349.4932) (xy 272.143474 -349.50019) (xy 272.13433 -349.509334)
			(xy 272.12758 -349.516717) (xy 272.119874 -349.535158) (xy 272.119344 -349.545148) (xy 272.119344 -350.028764)
			(xy 272.11979 -350.03877) (xy 272.12752 -350.057233) (xy 272.13433 -350.064578) (xy 272.188686 -350.118934)
			(xy 272.200624 -350.125538) (xy 272.207482 -350.127316) (xy 272.234883 -350.134423) (xy 272.287364 -350.155632)
			(xy 272.336136 -350.184364) (xy 272.380125 -350.219988) (xy 272.418367 -350.261722) (xy 272.450021 -350.30865)
			(xy 272.474392 -350.35974) (xy 272.490946 -350.413871) (xy 272.499318 -350.469853) (xy 272.499836 -350.498156)
			(xy 272.499304 -350.525407) (xy 272.491554 -350.579354) (xy 272.476205 -350.631648) (xy 272.453569 -350.681226)
			(xy 272.424108 -350.727078) (xy 272.388422 -350.768271) (xy 272.347236 -350.803965) (xy 272.30139 -350.833435)
			(xy 272.251816 -350.856079) (xy 272.199524 -350.871438) (xy 272.145578 -350.879199) (xy 272.118328 -350.879664)
			(xy 272.090023 -350.879105) (xy 272.034033 -350.870764) (xy 271.979891 -350.854234) (xy 271.928791 -350.829876)
			(xy 271.881856 -350.798228) (xy 271.840119 -350.759985) (xy 271.804497 -350.715989) (xy 271.775776 -350.667208)
			(xy 271.754586 -350.614715) (xy 271.747488 -350.58731) (xy 271.74571 -350.580452) (xy 271.739106 -350.568514)
			(xy 271.5768 -350.406208) (xy 271.559473 -350.388211) (xy 271.530124 -350.347786) (xy 271.507465 -350.303264)
			(xy 271.492057 -350.255743) (xy 271.48428 -350.206396) (xy 271.483836 -350.181418) (xy 271.483836 -349.392494)
			(xy 271.484299 -349.367519) (xy 271.492094 -349.31818) (xy 271.507509 -349.270668) (xy 271.530162 -349.22615)
			(xy 271.559498 -349.185722) (xy 271.5768 -349.167704) (xy 271.818608 -348.92615) (xy 271.825416 -348.918665)
			(xy 271.833046 -348.899945) (xy 271.83286 -348.879731) (xy 271.829276 -348.87027) (xy 271.786604 -348.769178)
			(xy 271.760696 -348.752414) (xy 271.744948 -348.752668) (xy 271.739106 -348.752668) (xy 271.711851 -348.752239)
			(xy 271.657897 -348.744482) (xy 271.605596 -348.729124) (xy 271.556014 -348.70648) (xy 271.510158 -348.677009)
			(xy 271.468965 -348.641311) (xy 271.433271 -348.600114) (xy 271.403804 -348.554257) (xy 271.381164 -348.504672)
			(xy 271.365811 -348.452369) (xy 271.358059 -348.398415) (xy 271.357598 -348.37116) (xy 263.622536 -348.37116)
			(xy 266.425172 -351.173796) (xy 273.075146 -351.173796) (xy 273.075619 -351.146321) (xy 273.083512 -351.09194)
			(xy 273.099135 -351.039257) (xy 273.122163 -350.989365) (xy 273.152118 -350.943297) (xy 273.169888 -350.922336)
			(xy 273.175984 -350.915224) (xy 273.182334 -350.898206) (xy 273.182334 -350.812354) (xy 273.175984 -350.795336)
			(xy 273.169888 -350.788224) (xy 273.152152 -350.767239) (xy 273.122224 -350.721163) (xy 273.099206 -350.671275)
			(xy 273.083573 -350.618603) (xy 273.075649 -350.564235) (xy 273.075146 -350.536764) (xy 273.075632 -350.509513)
			(xy 273.083388 -350.455565) (xy 273.098743 -350.40327) (xy 273.121385 -350.353693) (xy 273.150851 -350.307843)
			(xy 273.186542 -350.266652) (xy 273.227733 -350.230961) (xy 273.273583 -350.201495) (xy 273.32316 -350.178853)
			(xy 273.375455 -350.163498) (xy 273.429403 -350.155742) (xy 273.483905 -350.155742) (xy 273.537853 -350.163498)
			(xy 273.590148 -350.178853) (xy 273.639725 -350.201495) (xy 273.685575 -350.230961) (xy 273.726766 -350.266652)
			(xy 273.762457 -350.307843) (xy 273.791923 -350.353693) (xy 273.814565 -350.40327) (xy 273.82992 -350.455565)
			(xy 273.837676 -350.509513) (xy 273.838162 -350.536764) (xy 273.837664 -350.564238) (xy 273.829776 -350.618618)
			(xy 273.820534 -350.649794) (xy 274.079462 -350.649794) (xy 274.079972 -350.622544) (xy 274.087729 -350.568599)
			(xy 274.103083 -350.516306) (xy 274.125723 -350.466731) (xy 274.155187 -350.420882) (xy 274.190876 -350.379693)
			(xy 274.232063 -350.344001) (xy 274.27791 -350.314534) (xy 274.327484 -350.291891) (xy 274.379775 -350.276534)
			(xy 274.43372 -350.268774) (xy 274.46097 -350.268286) (xy 274.486206 -350.268654) (xy 274.536241 -350.275281)
			(xy 274.584962 -350.288463) (xy 274.631512 -350.307967) (xy 274.653502 -350.320356) (xy 274.663154 -350.326198)
			(xy 274.685252 -350.32823) (xy 274.77974 -350.294702) (xy 274.795742 -350.279208) (xy 274.799806 -350.268794)
			(xy 274.810477 -350.242007) (xy 274.838768 -350.191764) (xy 274.874301 -350.146354) (xy 274.916266 -350.106811)
			(xy 274.963707 -350.074039) (xy 275.015542 -350.048783) (xy 275.070589 -350.03162) (xy 275.127592 -350.022941)
			(xy 275.156422 -350.022414) (xy 275.183675 -350.022857) (xy 275.237625 -350.030617) (xy 275.289922 -350.045977)
			(xy 275.339501 -350.068622) (xy 275.385352 -350.098092) (xy 275.426543 -350.133788) (xy 275.462234 -350.174983)
			(xy 275.491699 -350.220838) (xy 275.514339 -350.270419) (xy 275.52706 -350.313752) (xy 277.667974 -350.313752)
			(xy 277.668485 -350.286179) (xy 277.676429 -350.231609) (xy 277.692146 -350.17875) (xy 277.715308 -350.128704)
			(xy 277.745432 -350.082513) (xy 277.781891 -350.04114) (xy 277.802594 -350.022922) (xy 277.810697 -350.015306)
			(xy 277.82006 -349.995165) (xy 277.820628 -349.98406) (xy 277.820628 -349.906844) (xy 277.820075 -349.895732)
			(xy 277.810728 -349.875572) (xy 277.802594 -349.867982) (xy 277.78187 -349.849785) (xy 277.745401 -349.808413)
			(xy 277.71527 -349.76222) (xy 277.692107 -349.71217) (xy 277.676393 -349.659304) (xy 277.668457 -349.604728)
			(xy 277.667974 -349.577152) (xy 277.668433 -349.5499) (xy 277.676196 -349.495953) (xy 277.691556 -349.443659)
			(xy 277.714201 -349.394082) (xy 277.743671 -349.348233) (xy 277.779365 -349.307044) (xy 277.820557 -349.271353)
			(xy 277.866409 -349.241887) (xy 277.915987 -349.219245) (xy 277.968282 -349.203889) (xy 278.02223 -349.196131)
			(xy 278.049482 -349.195644) (xy 278.083772 -349.197168) (xy 278.093932 -349.198184) (xy 278.113236 -349.192088)
			(xy 278.183848 -349.132906) (xy 278.193246 -349.114872) (xy 278.194262 -349.104712) (xy 278.197203 -349.076538)
			(xy 278.210381 -349.021447) (xy 278.231563 -348.968911) (xy 278.260283 -348.920087) (xy 278.295909 -348.876047)
			(xy 278.337657 -348.837761) (xy 278.384609 -348.806072) (xy 278.435731 -348.781676) (xy 278.4899 -348.76511)
			(xy 278.545923 -348.756738) (xy 278.574246 -348.756224) (xy 278.592265 -348.756444) (xy 278.62814 -348.759879)
			(xy 278.645874 -348.763082) (xy 278.655272 -348.76486) (xy 278.674322 -348.76105) (xy 278.749506 -348.713298)
			(xy 278.760936 -348.69755) (xy 278.763222 -348.688152) (xy 278.770612 -348.661106) (xy 278.792243 -348.609379)
			(xy 278.821208 -348.561373) (xy 278.856884 -348.518122) (xy 278.898505 -348.480555) (xy 278.945173 -348.449481)
			(xy 278.995885 -348.425569) (xy 279.04955 -348.409333) (xy 279.105013 -348.401122) (xy 279.133046 -348.400624)
			(xy 279.1603 -348.401035) (xy 279.214252 -348.408799) (xy 279.26655 -348.424161) (xy 279.31613 -348.44681)
			(xy 279.361981 -348.476284) (xy 279.403172 -348.511983) (xy 279.438863 -348.553181) (xy 279.468327 -348.599039)
			(xy 279.490966 -348.648623) (xy 279.506318 -348.700924) (xy 279.51407 -348.754878) (xy 279.514554 -348.782132)
			(xy 279.514058 -348.809706) (xy 279.506114 -348.864278) (xy 279.490396 -348.917138) (xy 279.467232 -348.967184)
			(xy 279.437104 -349.013375) (xy 279.40064 -349.054746) (xy 279.379934 -349.072962) (xy 279.371827 -349.080574)
			(xy 279.362469 -349.100719) (xy 279.3619 -349.111824) (xy 279.3619 -349.18904) (xy 279.36243 -349.200154)
			(xy 279.371796 -349.220313) (xy 279.379934 -349.227902) (xy 279.40067 -349.246084) (xy 279.43713 -349.287461)
			(xy 279.467254 -349.333656) (xy 279.490413 -349.383707) (xy 279.506124 -349.436571) (xy 279.514061 -349.491146)
			(xy 279.514058 -349.546295) (xy 279.506115 -349.60087) (xy 279.490398 -349.653732) (xy 279.467234 -349.70378)
			(xy 279.437105 -349.749972) (xy 279.40064 -349.791345) (xy 279.379934 -349.809562) (xy 279.371827 -349.817174)
			(xy 279.362469 -349.837319) (xy 279.3619 -349.848424) (xy 279.3619 -349.92564) (xy 279.36243 -349.936754)
			(xy 279.371796 -349.956913) (xy 279.379934 -349.964502) (xy 279.400656 -349.982701) (xy 279.437124 -350.024073)
			(xy 279.467254 -350.070266) (xy 279.490418 -350.120316) (xy 279.506132 -350.17318) (xy 279.51407 -350.227757)
			(xy 279.514554 -350.255332) (xy 279.514052 -350.282582) (xy 279.506292 -350.336527) (xy 279.490936 -350.388818)
			(xy 279.468294 -350.438393) (xy 279.438829 -350.484241) (xy 279.403139 -350.525429) (xy 279.361952 -350.56112)
			(xy 279.316105 -350.590587) (xy 279.266531 -350.613231) (xy 279.21424 -350.628589) (xy 279.160296 -350.636351)
			(xy 279.133046 -350.63684) (xy 279.105193 -350.636246) (xy 279.050082 -350.62813) (xy 278.996735 -350.612092)
			(xy 278.946285 -350.588474) (xy 278.899801 -350.557776) (xy 278.858271 -350.52065) (xy 278.822576 -350.477884)
			(xy 278.793473 -350.430385) (xy 278.771581 -350.379161) (xy 278.763984 -350.35236) (xy 278.761698 -350.34347)
			(xy 278.75103 -350.32823) (xy 278.679148 -350.280478) (xy 278.661114 -350.276414) (xy 278.65197 -350.277684)
			(xy 278.638954 -350.279354) (xy 278.612769 -350.281133) (xy 278.599646 -350.28124) (xy 278.585497 -350.281141)
			(xy 278.557274 -350.27911) (xy 278.543258 -350.277176) (xy 278.533098 -350.275652) (xy 278.51354 -350.280478)
			(xy 278.439118 -350.336358) (xy 278.428958 -350.353884) (xy 278.427688 -350.364044) (xy 278.423627 -350.391202)
			(xy 278.408653 -350.444035) (xy 278.386259 -350.494175) (xy 278.356909 -350.540587) (xy 278.321209 -350.582312)
			(xy 278.279895 -350.618488) (xy 278.233823 -350.648368) (xy 278.183943 -350.671335) (xy 278.131286 -350.686914)
			(xy 278.076939 -350.694784) (xy 278.049482 -350.69526) (xy 278.022226 -350.694862) (xy 277.968271 -350.687101)
			(xy 277.915969 -350.67174) (xy 277.866385 -350.649092) (xy 277.82053 -350.619618) (xy 277.779336 -350.583917)
			(xy 277.743643 -350.542717) (xy 277.714176 -350.496857) (xy 277.691537 -350.447269) (xy 277.676185 -350.394965)
			(xy 277.668434 -350.341008) (xy 277.667974 -350.313752) (xy 275.52706 -350.313752) (xy 275.529692 -350.322718)
			(xy 275.537446 -350.376669) (xy 275.53793 -350.403922) (xy 275.53726 -350.435484) (xy 275.526876 -350.497749)
			(xy 275.506395 -350.557459) (xy 275.491956 -350.585532) (xy 275.48713 -350.594422) (xy 275.485098 -350.61398)
			(xy 275.510752 -350.702118) (xy 275.523198 -350.717612) (xy 275.532088 -350.722692) (xy 275.557211 -350.737205)
			(xy 275.603094 -350.772714) (xy 275.643068 -350.814763) (xy 275.676212 -350.862383) (xy 275.701759 -350.914474)
			(xy 275.71912 -350.969834) (xy 275.727895 -351.027185) (xy 275.72843 -351.056194) (xy 275.727944 -351.083445)
			(xy 275.720188 -351.137393) (xy 275.709499 -351.173796) (xy 281.355546 -351.173796) (xy 281.356019 -351.146321)
			(xy 281.363912 -351.09194) (xy 281.379535 -351.039257) (xy 281.402563 -350.989365) (xy 281.432518 -350.943297)
			(xy 281.450288 -350.922336) (xy 281.456384 -350.915224) (xy 281.462734 -350.898206) (xy 281.462734 -350.812354)
			(xy 281.456384 -350.795336) (xy 281.450288 -350.788224) (xy 281.432552 -350.767239) (xy 281.402624 -350.721163)
			(xy 281.379606 -350.671275) (xy 281.363973 -350.618603) (xy 281.356049 -350.564235) (xy 281.355546 -350.536764)
			(xy 281.356032 -350.509513) (xy 281.363788 -350.455565) (xy 281.379143 -350.40327) (xy 281.401785 -350.353693)
			(xy 281.431251 -350.307843) (xy 281.466942 -350.266652) (xy 281.508133 -350.230961) (xy 281.553983 -350.201495)
			(xy 281.60356 -350.178853) (xy 281.655855 -350.163498) (xy 281.709803 -350.155742) (xy 281.764305 -350.155742)
			(xy 281.818253 -350.163498) (xy 281.870548 -350.178853) (xy 281.920125 -350.201495) (xy 281.965975 -350.230961)
			(xy 282.007166 -350.266652) (xy 282.042857 -350.307843) (xy 282.072323 -350.353693) (xy 282.094965 -350.40327)
			(xy 282.11032 -350.455565) (xy 282.118076 -350.509513) (xy 282.118562 -350.536764) (xy 282.118064 -350.564238)
			(xy 282.110176 -350.618618) (xy 282.094559 -350.6713) (xy 282.071537 -350.721193) (xy 282.041587 -350.767262)
			(xy 282.02382 -350.788224) (xy 282.017724 -350.795336) (xy 282.011374 -350.812354) (xy 282.011374 -350.898206)
			(xy 282.017724 -350.915224) (xy 282.02382 -350.922336) (xy 282.041585 -350.943297) (xy 282.071509 -350.98938)
			(xy 282.094521 -351.039274) (xy 282.110147 -351.091951) (xy 282.118063 -351.146324) (xy 282.118562 -351.173796)
			(xy 282.118076 -351.201047) (xy 282.11032 -351.254995) (xy 282.094965 -351.30729) (xy 282.072323 -351.356867)
			(xy 282.042857 -351.402717) (xy 282.007166 -351.443908) (xy 281.965975 -351.479599) (xy 281.920125 -351.509065)
			(xy 281.870548 -351.531707) (xy 281.818253 -351.547062) (xy 281.764305 -351.554818) (xy 281.709803 -351.554818)
			(xy 281.655855 -351.547062) (xy 281.60356 -351.531707) (xy 281.553983 -351.509065) (xy 281.508133 -351.479599)
			(xy 281.466942 -351.443908) (xy 281.431251 -351.402717) (xy 281.401785 -351.356867) (xy 281.379143 -351.30729)
			(xy 281.363788 -351.254995) (xy 281.356032 -351.201047) (xy 281.355546 -351.173796) (xy 275.709499 -351.173796)
			(xy 275.704833 -351.189688) (xy 275.682191 -351.239265) (xy 275.652725 -351.285115) (xy 275.617034 -351.326306)
			(xy 275.575843 -351.361997) (xy 275.529993 -351.391463) (xy 275.480416 -351.414105) (xy 275.428121 -351.42946)
			(xy 275.374173 -351.437216) (xy 275.319671 -351.437216) (xy 275.265723 -351.42946) (xy 275.213428 -351.414105)
			(xy 275.163851 -351.391463) (xy 275.118001 -351.361997) (xy 275.07681 -351.326306) (xy 275.041119 -351.285115)
			(xy 275.011653 -351.239265) (xy 274.989011 -351.189688) (xy 274.973656 -351.137393) (xy 274.9659 -351.083445)
			(xy 274.965414 -351.056194) (xy 274.966085 -351.024632) (xy 274.976467 -350.962367) (xy 274.996949 -350.902657)
			(xy 275.011388 -350.874584) (xy 275.016214 -350.865694) (xy 275.018246 -350.846136) (xy 274.992592 -350.757998)
			(xy 274.980146 -350.742504) (xy 274.971256 -350.737424) (xy 274.96389 -350.73336) (xy 274.954238 -350.727518)
			(xy 274.93214 -350.725486) (xy 274.837652 -350.759014) (xy 274.82165 -350.774508) (xy 274.817586 -350.784922)
			(xy 274.807582 -350.810041) (xy 274.781505 -350.857404) (xy 274.74901 -350.900618) (xy 274.73021 -350.92005)
			(xy 274.723494 -350.92746) (xy 274.715768 -350.94588) (xy 274.715224 -350.955864) (xy 274.715224 -352.03384)
			(xy 274.715622 -352.043912) (xy 274.723361 -352.06251) (xy 274.73021 -352.069908) (xy 275.158962 -352.49866)
			(xy 275.166429 -352.505371) (xy 275.184999 -352.512951) (xy 275.19503 -352.513392) (xy 281.896312 -352.513392)
			(xy 281.906356 -352.513005) (xy 281.924952 -352.505428) (xy 281.93238 -352.49866) (xy 282.47213 -351.95891)
			(xy 282.478962 -351.951504) (xy 282.486686 -351.932909) (xy 282.487116 -351.922842) (xy 282.487116 -350.955864)
			(xy 282.486666 -350.945858) (xy 282.47894 -350.927394) (xy 282.47213 -350.92005) (xy 282.451245 -350.898433)
			(xy 282.415832 -350.84987) (xy 282.388475 -350.796352) (xy 282.369853 -350.739206) (xy 282.360425 -350.679846)
			(xy 282.359862 -350.649794) (xy 282.360372 -350.622544) (xy 282.368129 -350.568599) (xy 282.383483 -350.516306)
			(xy 282.406123 -350.466731) (xy 282.435587 -350.420882) (xy 282.471276 -350.379693) (xy 282.512463 -350.344001)
			(xy 282.55831 -350.314534) (xy 282.607884 -350.291891) (xy 282.660175 -350.276534) (xy 282.71412 -350.268774)
			(xy 282.74137 -350.268286) (xy 282.766606 -350.268654) (xy 282.816641 -350.275281) (xy 282.865362 -350.288463)
			(xy 282.911912 -350.307967) (xy 282.933902 -350.320356) (xy 282.943554 -350.326198) (xy 282.965652 -350.32823)
			(xy 283.06014 -350.294702) (xy 283.076142 -350.279208) (xy 283.080206 -350.268794) (xy 283.090877 -350.242007)
			(xy 283.119168 -350.191764) (xy 283.154701 -350.146354) (xy 283.196666 -350.106811) (xy 283.244107 -350.074039)
			(xy 283.295942 -350.048783) (xy 283.350989 -350.03162) (xy 283.407992 -350.022941) (xy 283.436822 -350.022414)
			(xy 283.464075 -350.022857) (xy 283.518025 -350.030617) (xy 283.570322 -350.045977) (xy 283.619901 -350.068622)
			(xy 283.665752 -350.098092) (xy 283.706943 -350.133788) (xy 283.742634 -350.174983) (xy 283.772099 -350.220838)
			(xy 283.794739 -350.270419) (xy 283.80746 -350.313752) (xy 285.948374 -350.313752) (xy 285.948885 -350.286179)
			(xy 285.956829 -350.231609) (xy 285.972546 -350.17875) (xy 285.995708 -350.128704) (xy 286.025832 -350.082513)
			(xy 286.062291 -350.04114) (xy 286.082994 -350.022922) (xy 286.091097 -350.015306) (xy 286.10046 -349.995165)
			(xy 286.101028 -349.98406) (xy 286.101028 -349.906844) (xy 286.100475 -349.895732) (xy 286.091128 -349.875572)
			(xy 286.082994 -349.867982) (xy 286.06227 -349.849785) (xy 286.025801 -349.808413) (xy 285.99567 -349.76222)
			(xy 285.972507 -349.71217) (xy 285.956793 -349.659304) (xy 285.948857 -349.604728) (xy 285.948374 -349.577152)
			(xy 285.948833 -349.5499) (xy 285.956596 -349.495953) (xy 285.971956 -349.443659) (xy 285.994601 -349.394082)
			(xy 286.024071 -349.348233) (xy 286.059765 -349.307044) (xy 286.100957 -349.271353) (xy 286.146809 -349.241887)
			(xy 286.196387 -349.219245) (xy 286.248682 -349.203889) (xy 286.30263 -349.196131) (xy 286.329882 -349.195644)
			(xy 286.364172 -349.197168) (xy 286.374332 -349.198184) (xy 286.393636 -349.192088) (xy 286.464248 -349.132906)
			(xy 286.473646 -349.114872) (xy 286.474662 -349.104712) (xy 286.477603 -349.076538) (xy 286.490781 -349.021447)
			(xy 286.511963 -348.968911) (xy 286.540683 -348.920087) (xy 286.576309 -348.876047) (xy 286.618057 -348.837761)
			(xy 286.665009 -348.806072) (xy 286.716131 -348.781676) (xy 286.7703 -348.76511) (xy 286.826323 -348.756738)
			(xy 286.854646 -348.756224) (xy 286.872665 -348.756444) (xy 286.90854 -348.759879) (xy 286.926274 -348.763082)
			(xy 286.935672 -348.76486) (xy 286.954722 -348.76105) (xy 287.029906 -348.713298) (xy 287.041336 -348.69755)
			(xy 287.043622 -348.688152) (xy 287.051012 -348.661106) (xy 287.072643 -348.609379) (xy 287.101608 -348.561373)
			(xy 287.137284 -348.518122) (xy 287.178905 -348.480555) (xy 287.225573 -348.449481) (xy 287.276285 -348.425569)
			(xy 287.32995 -348.409333) (xy 287.385413 -348.401122) (xy 287.413446 -348.400624) (xy 287.4407 -348.401035)
			(xy 287.494652 -348.408799) (xy 287.54695 -348.424161) (xy 287.59653 -348.44681) (xy 287.642381 -348.476284)
			(xy 287.683572 -348.511983) (xy 287.719263 -348.553181) (xy 287.748727 -348.599039) (xy 287.771366 -348.648623)
			(xy 287.786718 -348.700924) (xy 287.79447 -348.754878) (xy 287.794954 -348.782132) (xy 287.794458 -348.809706)
			(xy 287.786514 -348.864278) (xy 287.770796 -348.917138) (xy 287.747632 -348.967184) (xy 287.717504 -349.013375)
			(xy 287.68104 -349.054746) (xy 287.660334 -349.072962) (xy 287.652227 -349.080574) (xy 287.642869 -349.100719)
			(xy 287.6423 -349.111824) (xy 287.6423 -349.18904) (xy 287.64283 -349.200154) (xy 287.652196 -349.220313)
			(xy 287.660334 -349.227902) (xy 287.68107 -349.246084) (xy 287.71753 -349.287461) (xy 287.747654 -349.333656)
			(xy 287.770813 -349.383707) (xy 287.786524 -349.436571) (xy 287.794461 -349.491146) (xy 287.794458 -349.546295)
			(xy 287.786515 -349.60087) (xy 287.770798 -349.653732) (xy 287.747634 -349.70378) (xy 287.717505 -349.749972)
			(xy 287.68104 -349.791345) (xy 287.660334 -349.809562) (xy 287.652227 -349.817174) (xy 287.642869 -349.837319)
			(xy 287.6423 -349.848424) (xy 287.6423 -349.92564) (xy 287.64283 -349.936754) (xy 287.652196 -349.956913)
			(xy 287.660334 -349.964502) (xy 287.681056 -349.982701) (xy 287.717524 -350.024073) (xy 287.747654 -350.070266)
			(xy 287.770818 -350.120316) (xy 287.786532 -350.17318) (xy 287.79447 -350.227757) (xy 287.794954 -350.255332)
			(xy 287.794452 -350.282582) (xy 287.786692 -350.336527) (xy 287.771336 -350.388818) (xy 287.748694 -350.438393)
			(xy 287.719229 -350.484241) (xy 287.683539 -350.525429) (xy 287.642352 -350.56112) (xy 287.596505 -350.590587)
			(xy 287.546931 -350.613231) (xy 287.49464 -350.628589) (xy 287.440696 -350.636351) (xy 287.413446 -350.63684)
			(xy 287.385593 -350.636246) (xy 287.330482 -350.62813) (xy 287.277135 -350.612092) (xy 287.226685 -350.588474)
			(xy 287.180201 -350.557776) (xy 287.138671 -350.52065) (xy 287.102976 -350.477884) (xy 287.073873 -350.430385)
			(xy 287.051981 -350.379161) (xy 287.044384 -350.35236) (xy 287.042098 -350.34347) (xy 287.03143 -350.32823)
			(xy 286.959548 -350.280478) (xy 286.941514 -350.276414) (xy 286.93237 -350.277684) (xy 286.919354 -350.279354)
			(xy 286.893169 -350.281133) (xy 286.880046 -350.28124) (xy 286.865897 -350.281141) (xy 286.837674 -350.27911)
			(xy 286.823658 -350.277176) (xy 286.813498 -350.275652) (xy 286.79394 -350.280478) (xy 286.719518 -350.336358)
			(xy 286.709358 -350.353884) (xy 286.708088 -350.364044) (xy 286.704027 -350.391202) (xy 286.689053 -350.444035)
			(xy 286.666659 -350.494175) (xy 286.637309 -350.540587) (xy 286.601609 -350.582312) (xy 286.560295 -350.618488)
			(xy 286.514223 -350.648368) (xy 286.464343 -350.671335) (xy 286.411686 -350.686914) (xy 286.357339 -350.694784)
			(xy 286.329882 -350.69526) (xy 286.302626 -350.694862) (xy 286.248671 -350.687101) (xy 286.196369 -350.67174)
			(xy 286.146785 -350.649092) (xy 286.10093 -350.619618) (xy 286.059736 -350.583917) (xy 286.024043 -350.542717)
			(xy 285.994576 -350.496857) (xy 285.971937 -350.447269) (xy 285.956585 -350.394965) (xy 285.948834 -350.341008)
			(xy 285.948374 -350.313752) (xy 283.80746 -350.313752) (xy 283.810092 -350.322718) (xy 283.817846 -350.376669)
			(xy 283.81833 -350.403922) (xy 283.81766 -350.435484) (xy 283.807276 -350.497749) (xy 283.786795 -350.557459)
			(xy 283.772356 -350.585532) (xy 283.76753 -350.594422) (xy 283.765498 -350.61398) (xy 283.791152 -350.702118)
			(xy 283.803598 -350.717612) (xy 283.812488 -350.722692) (xy 283.837611 -350.737205) (xy 283.883494 -350.772714)
			(xy 283.923468 -350.814763) (xy 283.956612 -350.862383) (xy 283.982159 -350.914474) (xy 283.99952 -350.969834)
			(xy 284.008295 -351.027185) (xy 284.00883 -351.056194) (xy 284.008344 -351.083445) (xy 284.000588 -351.137393)
			(xy 283.989899 -351.173796) (xy 289.661346 -351.173796) (xy 289.661819 -351.146321) (xy 289.669712 -351.09194)
			(xy 289.685335 -351.039257) (xy 289.708363 -350.989365) (xy 289.738318 -350.943297) (xy 289.756088 -350.922336)
			(xy 289.762184 -350.915224) (xy 289.768534 -350.898206) (xy 289.768534 -350.812354) (xy 289.762184 -350.795336)
			(xy 289.756088 -350.788224) (xy 289.738352 -350.767239) (xy 289.708424 -350.721163) (xy 289.685406 -350.671275)
			(xy 289.669773 -350.618603) (xy 289.661849 -350.564235) (xy 289.661346 -350.536764) (xy 289.661832 -350.509513)
			(xy 289.669588 -350.455565) (xy 289.684943 -350.40327) (xy 289.707585 -350.353693) (xy 289.737051 -350.307843)
			(xy 289.772742 -350.266652) (xy 289.813933 -350.230961) (xy 289.859783 -350.201495) (xy 289.90936 -350.178853)
			(xy 289.961655 -350.163498) (xy 290.015603 -350.155742) (xy 290.070105 -350.155742) (xy 290.124053 -350.163498)
			(xy 290.176348 -350.178853) (xy 290.225925 -350.201495) (xy 290.271775 -350.230961) (xy 290.312966 -350.266652)
			(xy 290.348657 -350.307843) (xy 290.378123 -350.353693) (xy 290.400765 -350.40327) (xy 290.41612 -350.455565)
			(xy 290.423876 -350.509513) (xy 290.424362 -350.536764) (xy 290.423864 -350.564238) (xy 290.415976 -350.618618)
			(xy 290.400359 -350.6713) (xy 290.377337 -350.721193) (xy 290.347387 -350.767262) (xy 290.32962 -350.788224)
			(xy 290.323524 -350.795336) (xy 290.317174 -350.812354) (xy 290.317174 -350.898206) (xy 290.323524 -350.915224)
			(xy 290.32962 -350.922336) (xy 290.347385 -350.943297) (xy 290.377309 -350.98938) (xy 290.400321 -351.039274)
			(xy 290.415947 -351.091951) (xy 290.423863 -351.146324) (xy 290.424362 -351.173796) (xy 290.423876 -351.201047)
			(xy 290.41612 -351.254995) (xy 290.400765 -351.30729) (xy 290.378123 -351.356867) (xy 290.348657 -351.402717)
			(xy 290.312966 -351.443908) (xy 290.271775 -351.479599) (xy 290.225925 -351.509065) (xy 290.176348 -351.531707)
			(xy 290.124053 -351.547062) (xy 290.070105 -351.554818) (xy 290.015603 -351.554818) (xy 289.961655 -351.547062)
			(xy 289.90936 -351.531707) (xy 289.859783 -351.509065) (xy 289.813933 -351.479599) (xy 289.772742 -351.443908)
			(xy 289.737051 -351.402717) (xy 289.707585 -351.356867) (xy 289.684943 -351.30729) (xy 289.669588 -351.254995)
			(xy 289.661832 -351.201047) (xy 289.661346 -351.173796) (xy 283.989899 -351.173796) (xy 283.985233 -351.189688)
			(xy 283.962591 -351.239265) (xy 283.933125 -351.285115) (xy 283.897434 -351.326306) (xy 283.856243 -351.361997)
			(xy 283.810393 -351.391463) (xy 283.760816 -351.414105) (xy 283.708521 -351.42946) (xy 283.654573 -351.437216)
			(xy 283.600071 -351.437216) (xy 283.546123 -351.42946) (xy 283.493828 -351.414105) (xy 283.444251 -351.391463)
			(xy 283.398401 -351.361997) (xy 283.35721 -351.326306) (xy 283.321519 -351.285115) (xy 283.292053 -351.239265)
			(xy 283.269411 -351.189688) (xy 283.254056 -351.137393) (xy 283.2463 -351.083445) (xy 283.245814 -351.056194)
			(xy 283.246485 -351.024632) (xy 283.256867 -350.962367) (xy 283.277349 -350.902657) (xy 283.291788 -350.874584)
			(xy 283.296614 -350.865694) (xy 283.298646 -350.846136) (xy 283.272992 -350.757998) (xy 283.260546 -350.742504)
			(xy 283.251656 -350.737424) (xy 283.24429 -350.73336) (xy 283.234638 -350.727518) (xy 283.21254 -350.725486)
			(xy 283.118052 -350.759014) (xy 283.10205 -350.774508) (xy 283.097986 -350.784922) (xy 283.087982 -350.810041)
			(xy 283.061905 -350.857404) (xy 283.02941 -350.900618) (xy 283.01061 -350.92005) (xy 283.003894 -350.92746)
			(xy 282.996168 -350.94588) (xy 282.995624 -350.955864) (xy 282.995624 -351.922842) (xy 282.996021 -351.932915)
			(xy 283.003761 -351.951513) (xy 283.01061 -351.95891) (xy 283.55036 -352.49866) (xy 283.557828 -352.50537)
			(xy 283.576397 -352.51295) (xy 283.586428 -352.513392) (xy 290.275264 -352.513392) (xy 290.28531 -352.513033)
			(xy 290.303906 -352.505436) (xy 290.311332 -352.49866) (xy 290.77793 -352.032062) (xy 290.784783 -352.024673)
			(xy 290.792495 -352.006065) (xy 290.792916 -351.995994) (xy 290.792916 -350.955864) (xy 290.792466 -350.945858)
			(xy 290.78474 -350.927394) (xy 290.77793 -350.92005) (xy 290.757045 -350.898433) (xy 290.721632 -350.84987)
			(xy 290.694275 -350.796352) (xy 290.675653 -350.739206) (xy 290.666225 -350.679846) (xy 290.665662 -350.649794)
			(xy 290.666172 -350.622544) (xy 290.673929 -350.568599) (xy 290.689283 -350.516306) (xy 290.711923 -350.466731)
			(xy 290.741387 -350.420882) (xy 290.777076 -350.379693) (xy 290.818263 -350.344001) (xy 290.86411 -350.314534)
			(xy 290.913684 -350.291891) (xy 290.965975 -350.276534) (xy 291.01992 -350.268774) (xy 291.04717 -350.268286)
			(xy 291.072406 -350.268654) (xy 291.122441 -350.275281) (xy 291.171162 -350.288463) (xy 291.217712 -350.307967)
			(xy 291.239702 -350.320356) (xy 291.249354 -350.326198) (xy 291.271452 -350.32823) (xy 291.36594 -350.294702)
			(xy 291.381942 -350.279208) (xy 291.386006 -350.268794) (xy 291.396677 -350.242007) (xy 291.424968 -350.191764)
			(xy 291.460501 -350.146354) (xy 291.502466 -350.106811) (xy 291.549907 -350.074039) (xy 291.601742 -350.048783)
			(xy 291.656789 -350.03162) (xy 291.713792 -350.022941) (xy 291.742622 -350.022414) (xy 291.769875 -350.022857)
			(xy 291.823825 -350.030617) (xy 291.876122 -350.045977) (xy 291.925701 -350.068622) (xy 291.971552 -350.098092)
			(xy 292.012743 -350.133788) (xy 292.048434 -350.174983) (xy 292.077899 -350.220838) (xy 292.100539 -350.270419)
			(xy 292.11326 -350.313752) (xy 294.254174 -350.313752) (xy 294.254685 -350.286179) (xy 294.262629 -350.231609)
			(xy 294.278346 -350.17875) (xy 294.301508 -350.128704) (xy 294.331632 -350.082513) (xy 294.368091 -350.04114)
			(xy 294.388794 -350.022922) (xy 294.396897 -350.015306) (xy 294.40626 -349.995165) (xy 294.406828 -349.98406)
			(xy 294.406828 -349.906844) (xy 294.406275 -349.895732) (xy 294.396928 -349.875572) (xy 294.388794 -349.867982)
			(xy 294.36807 -349.849785) (xy 294.331601 -349.808413) (xy 294.30147 -349.76222) (xy 294.278307 -349.71217)
			(xy 294.262593 -349.659304) (xy 294.254657 -349.604728) (xy 294.254174 -349.577152) (xy 294.254633 -349.5499)
			(xy 294.262396 -349.495953) (xy 294.277756 -349.443659) (xy 294.300401 -349.394082) (xy 294.329871 -349.348233)
			(xy 294.365565 -349.307044) (xy 294.406757 -349.271353) (xy 294.452609 -349.241887) (xy 294.502187 -349.219245)
			(xy 294.554482 -349.203889) (xy 294.60843 -349.196131) (xy 294.635682 -349.195644) (xy 294.669972 -349.197168)
			(xy 294.680132 -349.198184) (xy 294.699436 -349.192088) (xy 294.770048 -349.132906) (xy 294.779446 -349.114872)
			(xy 294.780462 -349.104712) (xy 294.783403 -349.076538) (xy 294.796581 -349.021447) (xy 294.817763 -348.968911)
			(xy 294.846483 -348.920087) (xy 294.882109 -348.876047) (xy 294.923857 -348.837761) (xy 294.970809 -348.806072)
			(xy 295.021931 -348.781676) (xy 295.0761 -348.76511) (xy 295.132123 -348.756738) (xy 295.160446 -348.756224)
			(xy 295.178465 -348.756444) (xy 295.21434 -348.759879) (xy 295.232074 -348.763082) (xy 295.241472 -348.76486)
			(xy 295.260522 -348.76105) (xy 295.335706 -348.713298) (xy 295.347136 -348.69755) (xy 295.349422 -348.688152)
			(xy 295.356812 -348.661106) (xy 295.378443 -348.609379) (xy 295.407408 -348.561373) (xy 295.443084 -348.518122)
			(xy 295.484705 -348.480555) (xy 295.531373 -348.449481) (xy 295.582085 -348.425569) (xy 295.63575 -348.409333)
			(xy 295.691213 -348.401122) (xy 295.719246 -348.400624) (xy 295.7465 -348.401035) (xy 295.800452 -348.408799)
			(xy 295.85275 -348.424161) (xy 295.90233 -348.44681) (xy 295.948181 -348.476284) (xy 295.989372 -348.511983)
			(xy 296.025063 -348.553181) (xy 296.054527 -348.599039) (xy 296.077166 -348.648623) (xy 296.092518 -348.700924)
			(xy 296.10027 -348.754878) (xy 296.100754 -348.782132) (xy 296.100258 -348.809706) (xy 296.092314 -348.864278)
			(xy 296.076596 -348.917138) (xy 296.053432 -348.967184) (xy 296.023304 -349.013375) (xy 295.98684 -349.054746)
			(xy 295.966134 -349.072962) (xy 295.958027 -349.080574) (xy 295.948669 -349.100719) (xy 295.9481 -349.111824)
			(xy 295.9481 -349.18904) (xy 295.94863 -349.200154) (xy 295.957996 -349.220313) (xy 295.966134 -349.227902)
			(xy 295.98687 -349.246084) (xy 296.02333 -349.287461) (xy 296.053454 -349.333656) (xy 296.076613 -349.383707)
			(xy 296.092324 -349.436571) (xy 296.100261 -349.491146) (xy 296.100258 -349.546295) (xy 296.092315 -349.60087)
			(xy 296.076598 -349.653732) (xy 296.053434 -349.70378) (xy 296.023305 -349.749972) (xy 295.98684 -349.791345)
			(xy 295.966134 -349.809562) (xy 295.958027 -349.817174) (xy 295.948669 -349.837319) (xy 295.9481 -349.848424)
			(xy 295.9481 -349.92564) (xy 295.94863 -349.936754) (xy 295.957996 -349.956913) (xy 295.966134 -349.964502)
			(xy 295.986856 -349.982701) (xy 296.023324 -350.024073) (xy 296.053454 -350.070266) (xy 296.076618 -350.120316)
			(xy 296.092332 -350.17318) (xy 296.10027 -350.227757) (xy 296.100754 -350.255332) (xy 296.100252 -350.282582)
			(xy 296.092492 -350.336527) (xy 296.077136 -350.388818) (xy 296.054494 -350.438393) (xy 296.025029 -350.484241)
			(xy 295.989339 -350.525429) (xy 295.948152 -350.56112) (xy 295.902305 -350.590587) (xy 295.852731 -350.613231)
			(xy 295.80044 -350.628589) (xy 295.746496 -350.636351) (xy 295.719246 -350.63684) (xy 295.691393 -350.636246)
			(xy 295.636282 -350.62813) (xy 295.582935 -350.612092) (xy 295.532485 -350.588474) (xy 295.486001 -350.557776)
			(xy 295.444471 -350.52065) (xy 295.408776 -350.477884) (xy 295.379673 -350.430385) (xy 295.357781 -350.379161)
			(xy 295.350184 -350.35236) (xy 295.347898 -350.34347) (xy 295.33723 -350.32823) (xy 295.265348 -350.280478)
			(xy 295.247314 -350.276414) (xy 295.23817 -350.277684) (xy 295.225154 -350.279354) (xy 295.198969 -350.281133)
			(xy 295.185846 -350.28124) (xy 295.171697 -350.281141) (xy 295.143474 -350.27911) (xy 295.129458 -350.277176)
			(xy 295.119298 -350.275652) (xy 295.09974 -350.280478) (xy 295.025318 -350.336358) (xy 295.015158 -350.353884)
			(xy 295.013888 -350.364044) (xy 295.009827 -350.391202) (xy 294.994853 -350.444035) (xy 294.972459 -350.494175)
			(xy 294.943109 -350.540587) (xy 294.907409 -350.582312) (xy 294.866095 -350.618488) (xy 294.820023 -350.648368)
			(xy 294.770143 -350.671335) (xy 294.717486 -350.686914) (xy 294.663139 -350.694784) (xy 294.635682 -350.69526)
			(xy 294.608426 -350.694862) (xy 294.554471 -350.687101) (xy 294.502169 -350.67174) (xy 294.452585 -350.649092)
			(xy 294.40673 -350.619618) (xy 294.365536 -350.583917) (xy 294.329843 -350.542717) (xy 294.300376 -350.496857)
			(xy 294.277737 -350.447269) (xy 294.262385 -350.394965) (xy 294.254634 -350.341008) (xy 294.254174 -350.313752)
			(xy 292.11326 -350.313752) (xy 292.115892 -350.322718) (xy 292.123646 -350.376669) (xy 292.12413 -350.403922)
			(xy 292.12346 -350.435484) (xy 292.113076 -350.497749) (xy 292.092595 -350.557459) (xy 292.078156 -350.585532)
			(xy 292.07333 -350.594422) (xy 292.071298 -350.61398) (xy 292.096952 -350.702118) (xy 292.109398 -350.717612)
			(xy 292.118288 -350.722692) (xy 292.143411 -350.737205) (xy 292.189294 -350.772714) (xy 292.229268 -350.814763)
			(xy 292.262412 -350.862383) (xy 292.287959 -350.914474) (xy 292.30532 -350.969834) (xy 292.314095 -351.027185)
			(xy 292.31463 -351.056194) (xy 292.314144 -351.083445) (xy 292.306388 -351.137393) (xy 292.295699 -351.173796)
			(xy 298.017946 -351.173796) (xy 298.018419 -351.146321) (xy 298.026312 -351.09194) (xy 298.041935 -351.039257)
			(xy 298.064963 -350.989365) (xy 298.094918 -350.943297) (xy 298.112688 -350.922336) (xy 298.118784 -350.915224)
			(xy 298.125134 -350.898206) (xy 298.125134 -350.812354) (xy 298.118784 -350.795336) (xy 298.112688 -350.788224)
			(xy 298.094952 -350.767239) (xy 298.065024 -350.721163) (xy 298.042006 -350.671275) (xy 298.026373 -350.618603)
			(xy 298.018449 -350.564235) (xy 298.017946 -350.536764) (xy 298.018432 -350.509513) (xy 298.026188 -350.455565)
			(xy 298.041543 -350.40327) (xy 298.064185 -350.353693) (xy 298.093651 -350.307843) (xy 298.129342 -350.266652)
			(xy 298.170533 -350.230961) (xy 298.216383 -350.201495) (xy 298.26596 -350.178853) (xy 298.318255 -350.163498)
			(xy 298.372203 -350.155742) (xy 298.426705 -350.155742) (xy 298.480653 -350.163498) (xy 298.532948 -350.178853)
			(xy 298.582525 -350.201495) (xy 298.628375 -350.230961) (xy 298.669566 -350.266652) (xy 298.705257 -350.307843)
			(xy 298.734723 -350.353693) (xy 298.757365 -350.40327) (xy 298.77272 -350.455565) (xy 298.780476 -350.509513)
			(xy 298.780962 -350.536764) (xy 298.780464 -350.564238) (xy 298.772576 -350.618618) (xy 298.756959 -350.6713)
			(xy 298.733937 -350.721193) (xy 298.703987 -350.767262) (xy 298.68622 -350.788224) (xy 298.680124 -350.795336)
			(xy 298.673774 -350.812354) (xy 298.673774 -350.898206) (xy 298.680124 -350.915224) (xy 298.68622 -350.922336)
			(xy 298.703985 -350.943297) (xy 298.733909 -350.98938) (xy 298.756921 -351.039274) (xy 298.772547 -351.091951)
			(xy 298.780463 -351.146324) (xy 298.780962 -351.173796) (xy 298.780476 -351.201047) (xy 298.77272 -351.254995)
			(xy 298.757365 -351.30729) (xy 298.734723 -351.356867) (xy 298.705257 -351.402717) (xy 298.669566 -351.443908)
			(xy 298.628375 -351.479599) (xy 298.582525 -351.509065) (xy 298.532948 -351.531707) (xy 298.480653 -351.547062)
			(xy 298.426705 -351.554818) (xy 298.372203 -351.554818) (xy 298.318255 -351.547062) (xy 298.26596 -351.531707)
			(xy 298.216383 -351.509065) (xy 298.170533 -351.479599) (xy 298.129342 -351.443908) (xy 298.093651 -351.402717)
			(xy 298.064185 -351.356867) (xy 298.041543 -351.30729) (xy 298.026188 -351.254995) (xy 298.018432 -351.201047)
			(xy 298.017946 -351.173796) (xy 292.295699 -351.173796) (xy 292.291033 -351.189688) (xy 292.268391 -351.239265)
			(xy 292.238925 -351.285115) (xy 292.203234 -351.326306) (xy 292.162043 -351.361997) (xy 292.116193 -351.391463)
			(xy 292.066616 -351.414105) (xy 292.014321 -351.42946) (xy 291.960373 -351.437216) (xy 291.905871 -351.437216)
			(xy 291.851923 -351.42946) (xy 291.799628 -351.414105) (xy 291.750051 -351.391463) (xy 291.704201 -351.361997)
			(xy 291.66301 -351.326306) (xy 291.627319 -351.285115) (xy 291.597853 -351.239265) (xy 291.575211 -351.189688)
			(xy 291.559856 -351.137393) (xy 291.5521 -351.083445) (xy 291.551614 -351.056194) (xy 291.552285 -351.024632)
			(xy 291.562667 -350.962367) (xy 291.583149 -350.902657) (xy 291.597588 -350.874584) (xy 291.602414 -350.865694)
			(xy 291.604446 -350.846136) (xy 291.578792 -350.757998) (xy 291.566346 -350.742504) (xy 291.557456 -350.737424)
			(xy 291.55009 -350.73336) (xy 291.540438 -350.727518) (xy 291.51834 -350.725486) (xy 291.423852 -350.759014)
			(xy 291.40785 -350.774508) (xy 291.403786 -350.784922) (xy 291.393782 -350.810041) (xy 291.367705 -350.857404)
			(xy 291.33521 -350.900618) (xy 291.31641 -350.92005) (xy 291.309694 -350.92746) (xy 291.301968 -350.94588)
			(xy 291.301424 -350.955864) (xy 291.301424 -351.995994) (xy 291.301846 -352.006064) (xy 291.309568 -352.024662)
			(xy 291.31641 -352.032062) (xy 291.757608 -352.47326) (xy 291.765094 -352.479948) (xy 291.78365 -352.487541)
			(xy 291.793676 -352.487992) (xy 298.488608 -352.487992) (xy 298.498651 -352.487603) (xy 298.517247 -352.480028)
			(xy 298.524676 -352.47326) (xy 299.13453 -351.863406) (xy 299.141364 -351.856002) (xy 299.149087 -351.837406)
			(xy 299.149516 -351.827338) (xy 299.149516 -350.955864) (xy 299.149066 -350.945858) (xy 299.14134 -350.927394)
			(xy 299.13453 -350.92005) (xy 299.113645 -350.898433) (xy 299.078232 -350.84987) (xy 299.050875 -350.796352)
			(xy 299.032253 -350.739206) (xy 299.022825 -350.679846) (xy 299.022262 -350.649794) (xy 299.022772 -350.622544)
			(xy 299.030529 -350.568599) (xy 299.045883 -350.516306) (xy 299.068523 -350.466731) (xy 299.097987 -350.420882)
			(xy 299.133676 -350.379693) (xy 299.174863 -350.344001) (xy 299.22071 -350.314534) (xy 299.270284 -350.291891)
			(xy 299.322575 -350.276534) (xy 299.37652 -350.268774) (xy 299.40377 -350.268286) (xy 299.429006 -350.268654)
			(xy 299.479041 -350.275281) (xy 299.527762 -350.288463) (xy 299.574312 -350.307967) (xy 299.596302 -350.320356)
			(xy 299.605954 -350.326198) (xy 299.628052 -350.32823) (xy 299.72254 -350.294702) (xy 299.738542 -350.279208)
			(xy 299.742606 -350.268794) (xy 299.753277 -350.242007) (xy 299.781568 -350.191764) (xy 299.817101 -350.146354)
			(xy 299.859066 -350.106811) (xy 299.906507 -350.074039) (xy 299.958342 -350.048783) (xy 300.013389 -350.03162)
			(xy 300.070392 -350.022941) (xy 300.099222 -350.022414) (xy 300.126475 -350.022857) (xy 300.180425 -350.030617)
			(xy 300.232722 -350.045977) (xy 300.282301 -350.068622) (xy 300.328152 -350.098092) (xy 300.369343 -350.133788)
			(xy 300.405034 -350.174983) (xy 300.434499 -350.220838) (xy 300.457139 -350.270419) (xy 300.46986 -350.313752)
			(xy 302.610774 -350.313752) (xy 302.611285 -350.286179) (xy 302.619229 -350.231609) (xy 302.634946 -350.17875)
			(xy 302.658108 -350.128704) (xy 302.688232 -350.082513) (xy 302.724691 -350.04114) (xy 302.745394 -350.022922)
			(xy 302.753497 -350.015306) (xy 302.76286 -349.995165) (xy 302.763428 -349.98406) (xy 302.763428 -349.906844)
			(xy 302.762875 -349.895732) (xy 302.753528 -349.875572) (xy 302.745394 -349.867982) (xy 302.72467 -349.849785)
			(xy 302.688201 -349.808413) (xy 302.65807 -349.76222) (xy 302.634907 -349.71217) (xy 302.619193 -349.659304)
			(xy 302.611257 -349.604728) (xy 302.610774 -349.577152) (xy 302.611233 -349.5499) (xy 302.618996 -349.495953)
			(xy 302.634356 -349.443659) (xy 302.657001 -349.394082) (xy 302.686471 -349.348233) (xy 302.722165 -349.307044)
			(xy 302.763357 -349.271353) (xy 302.809209 -349.241887) (xy 302.858787 -349.219245) (xy 302.911082 -349.203889)
			(xy 302.96503 -349.196131) (xy 302.992282 -349.195644) (xy 303.026572 -349.197168) (xy 303.036732 -349.198184)
			(xy 303.056036 -349.192088) (xy 303.126648 -349.132906) (xy 303.136046 -349.114872) (xy 303.137062 -349.104712)
			(xy 303.140003 -349.076538) (xy 303.153181 -349.021447) (xy 303.174363 -348.968911) (xy 303.203083 -348.920087)
			(xy 303.238709 -348.876047) (xy 303.280457 -348.837761) (xy 303.327409 -348.806072) (xy 303.378531 -348.781676)
			(xy 303.4327 -348.76511) (xy 303.488723 -348.756738) (xy 303.517046 -348.756224) (xy 303.535065 -348.756444)
			(xy 303.57094 -348.759879) (xy 303.588674 -348.763082) (xy 303.598072 -348.76486) (xy 303.617122 -348.76105)
			(xy 303.692306 -348.713298) (xy 303.703736 -348.69755) (xy 303.706022 -348.688152) (xy 303.713412 -348.661106)
			(xy 303.735043 -348.609379) (xy 303.764008 -348.561373) (xy 303.799684 -348.518122) (xy 303.841305 -348.480555)
			(xy 303.887973 -348.449481) (xy 303.938685 -348.425569) (xy 303.99235 -348.409333) (xy 304.047813 -348.401122)
			(xy 304.075846 -348.400624) (xy 304.1031 -348.401035) (xy 304.157052 -348.408799) (xy 304.20935 -348.424161)
			(xy 304.25893 -348.44681) (xy 304.304781 -348.476284) (xy 304.345972 -348.511983) (xy 304.381663 -348.553181)
			(xy 304.411127 -348.599039) (xy 304.433766 -348.648623) (xy 304.449118 -348.700924) (xy 304.45687 -348.754878)
			(xy 304.457354 -348.782132) (xy 304.456858 -348.809706) (xy 304.448914 -348.864278) (xy 304.433196 -348.917138)
			(xy 304.410032 -348.967184) (xy 304.379904 -349.013375) (xy 304.34344 -349.054746) (xy 304.322734 -349.072962)
			(xy 304.314627 -349.080574) (xy 304.305269 -349.100719) (xy 304.3047 -349.111824) (xy 304.3047 -349.18904)
			(xy 304.30523 -349.200154) (xy 304.314596 -349.220313) (xy 304.322734 -349.227902) (xy 304.34347 -349.246084)
			(xy 304.37993 -349.287461) (xy 304.410054 -349.333656) (xy 304.433213 -349.383707) (xy 304.448924 -349.436571)
			(xy 304.456861 -349.491146) (xy 304.456858 -349.546295) (xy 304.448915 -349.60087) (xy 304.433198 -349.653732)
			(xy 304.410034 -349.70378) (xy 304.379905 -349.749972) (xy 304.34344 -349.791345) (xy 304.322734 -349.809562)
			(xy 304.314627 -349.817174) (xy 304.305269 -349.837319) (xy 304.3047 -349.848424) (xy 304.3047 -349.92564)
			(xy 304.30523 -349.936754) (xy 304.314596 -349.956913) (xy 304.322734 -349.964502) (xy 304.343456 -349.982701)
			(xy 304.379924 -350.024073) (xy 304.410054 -350.070266) (xy 304.433218 -350.120316) (xy 304.448932 -350.17318)
			(xy 304.45687 -350.227757) (xy 304.457354 -350.255332) (xy 304.456852 -350.282582) (xy 304.449092 -350.336527)
			(xy 304.433736 -350.388818) (xy 304.411094 -350.438393) (xy 304.381629 -350.484241) (xy 304.345939 -350.525429)
			(xy 304.304752 -350.56112) (xy 304.258905 -350.590587) (xy 304.209331 -350.613231) (xy 304.15704 -350.628589)
			(xy 304.103096 -350.636351) (xy 304.075846 -350.63684) (xy 304.047993 -350.636246) (xy 303.992882 -350.62813)
			(xy 303.939535 -350.612092) (xy 303.889085 -350.588474) (xy 303.842601 -350.557776) (xy 303.801071 -350.52065)
			(xy 303.765376 -350.477884) (xy 303.736273 -350.430385) (xy 303.714381 -350.379161) (xy 303.706784 -350.35236)
			(xy 303.704498 -350.34347) (xy 303.69383 -350.32823) (xy 303.621948 -350.280478) (xy 303.603914 -350.276414)
			(xy 303.59477 -350.277684) (xy 303.581754 -350.279354) (xy 303.555569 -350.281133) (xy 303.542446 -350.28124)
			(xy 303.528297 -350.281141) (xy 303.500074 -350.27911) (xy 303.486058 -350.277176) (xy 303.475898 -350.275652)
			(xy 303.45634 -350.280478) (xy 303.381918 -350.336358) (xy 303.371758 -350.353884) (xy 303.370488 -350.364044)
			(xy 303.366427 -350.391202) (xy 303.351453 -350.444035) (xy 303.329059 -350.494175) (xy 303.299709 -350.540587)
			(xy 303.264009 -350.582312) (xy 303.222695 -350.618488) (xy 303.176623 -350.648368) (xy 303.126743 -350.671335)
			(xy 303.074086 -350.686914) (xy 303.019739 -350.694784) (xy 302.992282 -350.69526) (xy 302.965026 -350.694862)
			(xy 302.911071 -350.687101) (xy 302.858769 -350.67174) (xy 302.809185 -350.649092) (xy 302.76333 -350.619618)
			(xy 302.722136 -350.583917) (xy 302.686443 -350.542717) (xy 302.656976 -350.496857) (xy 302.634337 -350.447269)
			(xy 302.618985 -350.394965) (xy 302.611234 -350.341008) (xy 302.610774 -350.313752) (xy 300.46986 -350.313752)
			(xy 300.472492 -350.322718) (xy 300.480246 -350.376669) (xy 300.48073 -350.403922) (xy 300.48006 -350.435484)
			(xy 300.469676 -350.497749) (xy 300.449195 -350.557459) (xy 300.434756 -350.585532) (xy 300.42993 -350.594422)
			(xy 300.427898 -350.61398) (xy 300.453552 -350.702118) (xy 300.465998 -350.717612) (xy 300.474888 -350.722692)
			(xy 300.500011 -350.737205) (xy 300.545894 -350.772714) (xy 300.585868 -350.814763) (xy 300.619012 -350.862383)
			(xy 300.644559 -350.914474) (xy 300.66192 -350.969834) (xy 300.670695 -351.027185) (xy 300.67123 -351.056194)
			(xy 300.670744 -351.083445) (xy 300.662988 -351.137393) (xy 300.652299 -351.173796) (xy 306.349146 -351.173796)
			(xy 306.349619 -351.146321) (xy 306.357512 -351.09194) (xy 306.373135 -351.039257) (xy 306.396163 -350.989365)
			(xy 306.426118 -350.943297) (xy 306.443888 -350.922336) (xy 306.449984 -350.915224) (xy 306.456334 -350.898206)
			(xy 306.456334 -350.812354) (xy 306.449984 -350.795336) (xy 306.443888 -350.788224) (xy 306.426152 -350.767239)
			(xy 306.396224 -350.721163) (xy 306.373206 -350.671275) (xy 306.357573 -350.618603) (xy 306.349649 -350.564235)
			(xy 306.349146 -350.536764) (xy 306.349632 -350.509513) (xy 306.357388 -350.455565) (xy 306.372743 -350.40327)
			(xy 306.395385 -350.353693) (xy 306.424851 -350.307843) (xy 306.460542 -350.266652) (xy 306.501733 -350.230961)
			(xy 306.547583 -350.201495) (xy 306.59716 -350.178853) (xy 306.649455 -350.163498) (xy 306.703403 -350.155742)
			(xy 306.757905 -350.155742) (xy 306.811853 -350.163498) (xy 306.864148 -350.178853) (xy 306.913725 -350.201495)
			(xy 306.959575 -350.230961) (xy 307.000766 -350.266652) (xy 307.036457 -350.307843) (xy 307.065923 -350.353693)
			(xy 307.088565 -350.40327) (xy 307.10392 -350.455565) (xy 307.111676 -350.509513) (xy 307.112162 -350.536764)
			(xy 307.111664 -350.564238) (xy 307.103776 -350.618618) (xy 307.088159 -350.6713) (xy 307.065137 -350.721193)
			(xy 307.035187 -350.767262) (xy 307.01742 -350.788224) (xy 307.011324 -350.795336) (xy 307.004974 -350.812354)
			(xy 307.004974 -350.898206) (xy 307.011324 -350.915224) (xy 307.01742 -350.922336) (xy 307.035185 -350.943297)
			(xy 307.065109 -350.98938) (xy 307.088121 -351.039274) (xy 307.103747 -351.091951) (xy 307.111663 -351.146324)
			(xy 307.112162 -351.173796) (xy 307.111676 -351.201047) (xy 307.10392 -351.254995) (xy 307.088565 -351.30729)
			(xy 307.065923 -351.356867) (xy 307.036457 -351.402717) (xy 307.000766 -351.443908) (xy 306.959575 -351.479599)
			(xy 306.913725 -351.509065) (xy 306.864148 -351.531707) (xy 306.811853 -351.547062) (xy 306.757905 -351.554818)
			(xy 306.703403 -351.554818) (xy 306.649455 -351.547062) (xy 306.59716 -351.531707) (xy 306.547583 -351.509065)
			(xy 306.501733 -351.479599) (xy 306.460542 -351.443908) (xy 306.424851 -351.402717) (xy 306.395385 -351.356867)
			(xy 306.372743 -351.30729) (xy 306.357388 -351.254995) (xy 306.349632 -351.201047) (xy 306.349146 -351.173796)
			(xy 300.652299 -351.173796) (xy 300.647633 -351.189688) (xy 300.624991 -351.239265) (xy 300.595525 -351.285115)
			(xy 300.559834 -351.326306) (xy 300.518643 -351.361997) (xy 300.472793 -351.391463) (xy 300.423216 -351.414105)
			(xy 300.370921 -351.42946) (xy 300.316973 -351.437216) (xy 300.262471 -351.437216) (xy 300.208523 -351.42946)
			(xy 300.156228 -351.414105) (xy 300.106651 -351.391463) (xy 300.060801 -351.361997) (xy 300.01961 -351.326306)
			(xy 299.983919 -351.285115) (xy 299.954453 -351.239265) (xy 299.931811 -351.189688) (xy 299.916456 -351.137393)
			(xy 299.9087 -351.083445) (xy 299.908214 -351.056194) (xy 299.908885 -351.024632) (xy 299.919267 -350.962367)
			(xy 299.939749 -350.902657) (xy 299.954188 -350.874584) (xy 299.959014 -350.865694) (xy 299.961046 -350.846136)
			(xy 299.935392 -350.757998) (xy 299.922946 -350.742504) (xy 299.914056 -350.737424) (xy 299.90669 -350.73336)
			(xy 299.897038 -350.727518) (xy 299.87494 -350.725486) (xy 299.780452 -350.759014) (xy 299.76445 -350.774508)
			(xy 299.760386 -350.784922) (xy 299.750382 -350.810041) (xy 299.724305 -350.857404) (xy 299.69181 -350.900618)
			(xy 299.67301 -350.92005) (xy 299.666294 -350.92746) (xy 299.658568 -350.94588) (xy 299.658024 -350.955864)
			(xy 299.658024 -351.827338) (xy 299.658423 -351.83741) (xy 299.666161 -351.856008) (xy 299.67301 -351.863406)
			(xy 300.117764 -352.30816) (xy 300.125231 -352.314872) (xy 300.143801 -352.322451) (xy 300.153832 -352.322892)
			(xy 302.5394 -352.322892) (xy 302.564397 -352.323508) (xy 302.613422 -352.333315) (xy 302.659593 -352.352495)
			(xy 302.701138 -352.380309) (xy 302.719232 -352.397568) (xy 308.243224 -357.92156) (xy 308.250704 -357.928255)
			(xy 308.269264 -357.935844) (xy 308.279292 -357.936292) (xy 313.104022 -357.936292) (xy 313.129422 -357.919528)
			(xy 313.135264 -357.90505) (xy 313.138644 -357.895624) (xy 313.138652 -357.87562) (xy 313.131042 -357.85712)
			(xy 313.124342 -357.849678) (xy 312.972704 -357.69804) (xy 312.965248 -357.691314) (xy 312.946669 -357.683743)
			(xy 312.936636 -357.683308) (xy 308.8132 -357.683308) (xy 308.788203 -357.682692) (xy 308.739178 -357.672885)
			(xy 308.693007 -357.653705) (xy 308.651462 -357.625891) (xy 308.633368 -357.608632) (xy 306.194968 -355.170232)
			(xy 306.177667 -355.152174) (xy 306.149852 -355.11062) (xy 306.130679 -355.064437) (xy 306.120884 -355.015402)
			(xy 306.120292 -354.9904) (xy 306.120292 -353.24923) (xy 306.120927 -353.224234) (xy 306.130728 -353.17521)
			(xy 306.149902 -353.129039) (xy 306.177712 -353.087493) (xy 306.194968 -353.069398) (xy 307.46573 -351.798636)
			(xy 307.472551 -351.791221) (xy 307.480281 -351.772633) (xy 307.480716 -351.762568) (xy 307.480716 -350.955864)
			(xy 307.480266 -350.945858) (xy 307.47254 -350.927394) (xy 307.46573 -350.92005) (xy 307.444845 -350.898433)
			(xy 307.409432 -350.84987) (xy 307.382075 -350.796352) (xy 307.363453 -350.739206) (xy 307.354025 -350.679846)
			(xy 307.353462 -350.649794) (xy 307.353972 -350.622544) (xy 307.361729 -350.568599) (xy 307.377083 -350.516306)
			(xy 307.399723 -350.466731) (xy 307.429187 -350.420882) (xy 307.464876 -350.379693) (xy 307.506063 -350.344001)
			(xy 307.55191 -350.314534) (xy 307.601484 -350.291891) (xy 307.653775 -350.276534) (xy 307.70772 -350.268774)
			(xy 307.73497 -350.268286) (xy 307.760206 -350.268654) (xy 307.810241 -350.275281) (xy 307.858962 -350.288463)
			(xy 307.905512 -350.307967) (xy 307.927502 -350.320356) (xy 307.937154 -350.326198) (xy 307.959252 -350.32823)
			(xy 308.05374 -350.294702) (xy 308.069742 -350.279208) (xy 308.073806 -350.268794) (xy 308.084477 -350.242007)
			(xy 308.112768 -350.191764) (xy 308.148301 -350.146354) (xy 308.190266 -350.106811) (xy 308.237707 -350.074039)
			(xy 308.289542 -350.048783) (xy 308.344589 -350.03162) (xy 308.401592 -350.022941) (xy 308.430422 -350.022414)
			(xy 308.457675 -350.022857) (xy 308.511625 -350.030617) (xy 308.563922 -350.045977) (xy 308.613501 -350.068622)
			(xy 308.659352 -350.098092) (xy 308.700543 -350.133788) (xy 308.736234 -350.174983) (xy 308.765699 -350.220838)
			(xy 308.788339 -350.270419) (xy 308.80106 -350.313752) (xy 310.941974 -350.313752) (xy 310.942485 -350.286179)
			(xy 310.950429 -350.231609) (xy 310.966146 -350.17875) (xy 310.989308 -350.128704) (xy 311.019432 -350.082513)
			(xy 311.055891 -350.04114) (xy 311.076594 -350.022922) (xy 311.084697 -350.015306) (xy 311.09406 -349.995165)
			(xy 311.094628 -349.98406) (xy 311.094628 -349.906844) (xy 311.094075 -349.895732) (xy 311.084728 -349.875572)
			(xy 311.076594 -349.867982) (xy 311.05587 -349.849785) (xy 311.019401 -349.808413) (xy 310.98927 -349.76222)
			(xy 310.966107 -349.71217) (xy 310.950393 -349.659304) (xy 310.942457 -349.604728) (xy 310.941974 -349.577152)
			(xy 310.942433 -349.5499) (xy 310.950196 -349.495953) (xy 310.965556 -349.443659) (xy 310.988201 -349.394082)
			(xy 311.017671 -349.348233) (xy 311.053365 -349.307044) (xy 311.094557 -349.271353) (xy 311.140409 -349.241887)
			(xy 311.189987 -349.219245) (xy 311.242282 -349.203889) (xy 311.29623 -349.196131) (xy 311.323482 -349.195644)
			(xy 311.357772 -349.197168) (xy 311.367932 -349.198184) (xy 311.387236 -349.192088) (xy 311.457848 -349.132906)
			(xy 311.467246 -349.114872) (xy 311.468262 -349.104712) (xy 311.471203 -349.076538) (xy 311.484381 -349.021447)
			(xy 311.505563 -348.968911) (xy 311.534283 -348.920087) (xy 311.569909 -348.876047) (xy 311.611657 -348.837761)
			(xy 311.658609 -348.806072) (xy 311.709731 -348.781676) (xy 311.7639 -348.76511) (xy 311.819923 -348.756738)
			(xy 311.848246 -348.756224) (xy 311.866265 -348.756444) (xy 311.90214 -348.759879) (xy 311.919874 -348.763082)
			(xy 311.929272 -348.76486) (xy 311.948322 -348.76105) (xy 312.023506 -348.713298) (xy 312.034936 -348.69755)
			(xy 312.037222 -348.688152) (xy 312.044612 -348.661106) (xy 312.066243 -348.609379) (xy 312.095208 -348.561373)
			(xy 312.130884 -348.518122) (xy 312.172505 -348.480555) (xy 312.219173 -348.449481) (xy 312.269885 -348.425569)
			(xy 312.32355 -348.409333) (xy 312.379013 -348.401122) (xy 312.407046 -348.400624) (xy 312.4343 -348.401035)
			(xy 312.488252 -348.408799) (xy 312.54055 -348.424161) (xy 312.59013 -348.44681) (xy 312.635981 -348.476284)
			(xy 312.677172 -348.511983) (xy 312.712863 -348.553181) (xy 312.742327 -348.599039) (xy 312.764966 -348.648623)
			(xy 312.780318 -348.700924) (xy 312.78807 -348.754878) (xy 312.788554 -348.782132) (xy 312.788058 -348.809706)
			(xy 312.780114 -348.864278) (xy 312.764396 -348.917138) (xy 312.741232 -348.967184) (xy 312.711104 -349.013375)
			(xy 312.67464 -349.054746) (xy 312.653934 -349.072962) (xy 312.645827 -349.080574) (xy 312.636469 -349.100719)
			(xy 312.6359 -349.111824) (xy 312.6359 -349.18904) (xy 312.63643 -349.200154) (xy 312.645796 -349.220313)
			(xy 312.653934 -349.227902) (xy 312.67467 -349.246084) (xy 312.71113 -349.287461) (xy 312.741254 -349.333656)
			(xy 312.764413 -349.383707) (xy 312.780124 -349.436571) (xy 312.788061 -349.491146) (xy 312.788058 -349.546295)
			(xy 312.780115 -349.60087) (xy 312.764398 -349.653732) (xy 312.741234 -349.70378) (xy 312.711105 -349.749972)
			(xy 312.67464 -349.791345) (xy 312.653934 -349.809562) (xy 312.645827 -349.817174) (xy 312.636469 -349.837319)
			(xy 312.6359 -349.848424) (xy 312.6359 -349.92564) (xy 312.63643 -349.936754) (xy 312.645796 -349.956913)
			(xy 312.653934 -349.964502) (xy 312.674656 -349.982701) (xy 312.711124 -350.024073) (xy 312.741254 -350.070266)
			(xy 312.764418 -350.120316) (xy 312.780132 -350.17318) (xy 312.78807 -350.227757) (xy 312.788554 -350.255332)
			(xy 312.788052 -350.282582) (xy 312.780292 -350.336527) (xy 312.764936 -350.388818) (xy 312.742294 -350.438393)
			(xy 312.712829 -350.484241) (xy 312.677139 -350.525429) (xy 312.635952 -350.56112) (xy 312.590105 -350.590587)
			(xy 312.540531 -350.613231) (xy 312.48824 -350.628589) (xy 312.434296 -350.636351) (xy 312.407046 -350.63684)
			(xy 312.379193 -350.636246) (xy 312.324082 -350.62813) (xy 312.270735 -350.612092) (xy 312.220285 -350.588474)
			(xy 312.173801 -350.557776) (xy 312.132271 -350.52065) (xy 312.096576 -350.477884) (xy 312.067473 -350.430385)
			(xy 312.045581 -350.379161) (xy 312.037984 -350.35236) (xy 312.035698 -350.34347) (xy 312.02503 -350.32823)
			(xy 311.953148 -350.280478) (xy 311.935114 -350.276414) (xy 311.92597 -350.277684) (xy 311.912954 -350.279354)
			(xy 311.886769 -350.281133) (xy 311.873646 -350.28124) (xy 311.859497 -350.281141) (xy 311.831274 -350.27911)
			(xy 311.817258 -350.277176) (xy 311.807098 -350.275652) (xy 311.78754 -350.280478) (xy 311.713118 -350.336358)
			(xy 311.702958 -350.353884) (xy 311.701688 -350.364044) (xy 311.697627 -350.391202) (xy 311.682653 -350.444035)
			(xy 311.660259 -350.494175) (xy 311.630909 -350.540587) (xy 311.595209 -350.582312) (xy 311.553895 -350.618488)
			(xy 311.507823 -350.648368) (xy 311.457943 -350.671335) (xy 311.405286 -350.686914) (xy 311.350939 -350.694784)
			(xy 311.323482 -350.69526) (xy 311.296226 -350.694862) (xy 311.242271 -350.687101) (xy 311.189969 -350.67174)
			(xy 311.140385 -350.649092) (xy 311.09453 -350.619618) (xy 311.053336 -350.583917) (xy 311.017643 -350.542717)
			(xy 310.988176 -350.496857) (xy 310.965537 -350.447269) (xy 310.950185 -350.394965) (xy 310.942434 -350.341008)
			(xy 310.941974 -350.313752) (xy 308.80106 -350.313752) (xy 308.803692 -350.322718) (xy 308.811446 -350.376669)
			(xy 308.81193 -350.403922) (xy 308.81126 -350.435484) (xy 308.800876 -350.497749) (xy 308.780395 -350.557459)
			(xy 308.765956 -350.585532) (xy 308.76113 -350.594422) (xy 308.759098 -350.61398) (xy 308.784752 -350.702118)
			(xy 308.797198 -350.717612) (xy 308.806088 -350.722692) (xy 308.831211 -350.737205) (xy 308.877094 -350.772714)
			(xy 308.917068 -350.814763) (xy 308.950212 -350.862383) (xy 308.975759 -350.914474) (xy 308.99312 -350.969834)
			(xy 309.001895 -351.027185) (xy 309.00243 -351.056194) (xy 309.001944 -351.083445) (xy 308.994188 -351.137393)
			(xy 308.978833 -351.189688) (xy 308.956191 -351.239265) (xy 308.926725 -351.285115) (xy 308.891034 -351.326306)
			(xy 308.849843 -351.361997) (xy 308.803993 -351.391463) (xy 308.754416 -351.414105) (xy 308.702121 -351.42946)
			(xy 308.648173 -351.437216) (xy 308.593671 -351.437216) (xy 308.539723 -351.42946) (xy 308.487428 -351.414105)
			(xy 308.437851 -351.391463) (xy 308.392001 -351.361997) (xy 308.35081 -351.326306) (xy 308.315119 -351.285115)
			(xy 308.285653 -351.239265) (xy 308.263011 -351.189688) (xy 308.247656 -351.137393) (xy 308.2399 -351.083445)
			(xy 308.239414 -351.056194) (xy 308.240085 -351.024632) (xy 308.250467 -350.962367) (xy 308.270949 -350.902657)
			(xy 308.285388 -350.874584) (xy 308.290214 -350.865694) (xy 308.292246 -350.846136) (xy 308.266592 -350.757998)
			(xy 308.254146 -350.742504) (xy 308.245256 -350.737424) (xy 308.23789 -350.73336) (xy 308.228238 -350.727518)
			(xy 308.20614 -350.725486) (xy 308.111652 -350.759014) (xy 308.09565 -350.774508) (xy 308.091586 -350.784922)
			(xy 308.081582 -350.810041) (xy 308.055505 -350.857404) (xy 308.02301 -350.900618) (xy 308.00421 -350.92005)
			(xy 307.997494 -350.92746) (xy 307.989768 -350.94588) (xy 307.989224 -350.955864) (xy 307.989224 -351.762568)
			(xy 307.98966 -351.772636) (xy 307.997373 -351.791234) (xy 308.00421 -351.798636) (xy 308.310534 -352.10496)
			(xy 308.318011 -352.111659) (xy 308.336574 -352.119246) (xy 308.346602 -352.119692) (xy 308.559708 -352.119692)
			(xy 308.569751 -352.119303) (xy 308.588347 -352.111728) (xy 308.595776 -352.10496) (xy 309.319168 -351.381568)
			(xy 309.337226 -351.364267) (xy 309.37878 -351.336452) (xy 309.424963 -351.317279) (xy 309.473998 -351.307484)
			(xy 309.499 -351.306892) (xy 313.207654 -351.306892) (xy 313.2177 -351.306527) (xy 313.236296 -351.298935)
			(xy 313.243722 -351.29216) (xy 313.969654 -350.566228) (xy 313.976468 -350.558807) (xy 313.984204 -350.540224)
			(xy 313.98464 -350.53016) (xy 313.98464 -342.763602) (xy 313.985274 -342.73862) (xy 313.995011 -342.689613)
			(xy 314.014111 -342.643443) (xy 314.041844 -342.601881) (xy 314.059062 -342.58377) (xy 316.246764 -340.396068)
			(xy 316.264824 -340.378769) (xy 316.306377 -340.350953) (xy 316.352559 -340.33178) (xy 316.401594 -340.321984)
			(xy 316.426596 -340.321392) (xy 316.946026 -340.321392) (xy 316.95607 -340.321012) (xy 316.974666 -340.31343)
			(xy 316.982094 -340.30666) (xy 317.115444 -340.17331) (xy 317.122166 -340.165851) (xy 317.12974 -340.147275)
			(xy 317.130176 -340.137242) (xy 317.130176 -339.23478) (xy 317.129716 -339.224811) (xy 317.122129 -339.206376)
			(xy 317.115444 -339.198966) (xy 317.094569 -339.17734) (xy 317.059154 -339.128779) (xy 317.031795 -339.075264)
			(xy 317.01317 -339.01812) (xy 317.00374 -338.958761) (xy 317.003176 -338.92871) (xy 317.003688 -338.90146)
			(xy 317.011442 -338.847514) (xy 317.026795 -338.795221) (xy 317.049434 -338.745645) (xy 317.078898 -338.699795)
			(xy 317.114587 -338.658605) (xy 317.155774 -338.622913) (xy 317.201622 -338.593447) (xy 317.251196 -338.570804)
			(xy 317.303488 -338.555448) (xy 317.357434 -338.547689) (xy 317.384684 -338.547202) (xy 317.409921 -338.547562)
			(xy 317.459956 -338.554191) (xy 317.508676 -338.567375) (xy 317.555227 -338.586882) (xy 317.577216 -338.599272)
			(xy 317.586868 -338.605114) (xy 317.608966 -338.607146) (xy 317.703454 -338.573618) (xy 317.719456 -338.558124)
			(xy 317.72352 -338.54771) (xy 317.734188 -338.520921) (xy 317.762478 -338.470677) (xy 317.798011 -338.425266)
			(xy 317.839977 -338.385723) (xy 317.887418 -338.352951) (xy 317.939254 -338.327695) (xy 317.994301 -338.310533)
			(xy 318.051306 -338.301856) (xy 318.080136 -338.30133) (xy 318.107392 -338.301722) (xy 318.161347 -338.309484)
			(xy 318.213649 -338.324847) (xy 318.263231 -338.347496) (xy 318.309086 -338.376972) (xy 318.35028 -338.412673)
			(xy 318.385973 -338.453873) (xy 318.415439 -338.499734) (xy 318.438079 -338.549321) (xy 318.450802 -338.592668)
			(xy 320.591688 -338.592668) (xy 320.592205 -338.565095) (xy 320.600147 -338.510525) (xy 320.615863 -338.457666)
			(xy 320.639023 -338.40762) (xy 320.669146 -338.361429) (xy 320.705605 -338.320056) (xy 320.726308 -338.301838)
			(xy 320.734406 -338.294217) (xy 320.743771 -338.27408) (xy 320.744342 -338.262976) (xy 320.744342 -338.18576)
			(xy 320.743831 -338.174643) (xy 320.734454 -338.154484) (xy 320.726308 -338.146898) (xy 320.705594 -338.12869)
			(xy 320.669124 -338.08732) (xy 320.638992 -338.04113) (xy 320.615826 -337.991082) (xy 320.600111 -337.938218)
			(xy 320.592172 -337.883643) (xy 320.591688 -337.856068) (xy 320.592148 -337.828816) (xy 320.599909 -337.774868)
			(xy 320.615268 -337.722573) (xy 320.637912 -337.672996) (xy 320.667382 -337.627146) (xy 320.703076 -337.585956)
			(xy 320.744268 -337.550265) (xy 320.79012 -337.520799) (xy 320.839699 -337.498158) (xy 320.891995 -337.482803)
			(xy 320.945944 -337.475046) (xy 320.973196 -337.47456) (xy 321.007486 -337.476084) (xy 321.017646 -337.4771)
			(xy 321.03695 -337.471004) (xy 321.107562 -337.411822) (xy 321.11696 -337.393788) (xy 321.117976 -337.383628)
			(xy 321.120916 -337.355454) (xy 321.134093 -337.300362) (xy 321.155274 -337.247825) (xy 321.183994 -337.199)
			(xy 321.21962 -337.154959) (xy 321.261368 -337.116673) (xy 321.30832 -337.084984) (xy 321.359444 -337.060588)
			(xy 321.413613 -337.044023) (xy 321.469637 -337.035653) (xy 321.49796 -337.03514) (xy 321.515979 -337.035357)
			(xy 321.551854 -337.038794) (xy 321.569588 -337.041998) (xy 321.578986 -337.043776) (xy 321.598036 -337.039966)
			(xy 321.67322 -336.992214) (xy 321.68465 -336.976466) (xy 321.686936 -336.967068) (xy 321.694324 -336.940021)
			(xy 321.715954 -336.888293) (xy 321.744918 -336.840287) (xy 321.780595 -336.797034) (xy 321.822215 -336.759467)
			(xy 321.868884 -336.728393) (xy 321.919597 -336.704481) (xy 321.973263 -336.688246) (xy 322.028726 -336.680037)
			(xy 322.05676 -336.67954) (xy 322.084014 -336.679993) (xy 322.137968 -336.687745) (xy 322.190269 -336.703099)
			(xy 322.239852 -336.72574) (xy 322.285708 -336.755208) (xy 322.326902 -336.790904) (xy 322.362596 -336.832099)
			(xy 322.392064 -336.877955) (xy 322.414704 -336.927539) (xy 322.430056 -336.97984) (xy 322.437808 -337.033794)
			(xy 322.438268 -337.061048) (xy 322.437778 -337.088622) (xy 322.429832 -337.143194) (xy 322.414112 -337.196054)
			(xy 322.390947 -337.2461) (xy 322.360818 -337.29229) (xy 322.324354 -337.333662) (xy 322.303648 -337.351878)
			(xy 322.295536 -337.359486) (xy 322.28618 -337.379634) (xy 322.285614 -337.39074) (xy 322.285614 -337.467956)
			(xy 322.286186 -337.479066) (xy 322.295521 -337.499225) (xy 322.303648 -337.506818) (xy 322.324404 -337.52498)
			(xy 322.360872 -337.566356) (xy 322.391002 -337.612553) (xy 322.414166 -337.662607) (xy 322.42988 -337.715475)
			(xy 322.437818 -337.770054) (xy 322.437813 -337.825208) (xy 322.429867 -337.879786) (xy 322.414144 -337.932651)
			(xy 322.390972 -337.982701) (xy 322.360834 -338.028893) (xy 322.324359 -338.070264) (xy 322.303648 -338.088478)
			(xy 322.295536 -338.096086) (xy 322.28618 -338.116234) (xy 322.285614 -338.12734) (xy 322.285614 -338.204556)
			(xy 322.286186 -338.215666) (xy 322.295521 -338.235825) (xy 322.303648 -338.243418) (xy 322.324381 -338.261605)
			(xy 322.360847 -338.30298) (xy 322.390975 -338.349176) (xy 322.414137 -338.399228) (xy 322.429849 -338.452094)
			(xy 322.437785 -338.506672) (xy 322.438268 -338.534248) (xy 322.437867 -338.561502) (xy 322.430103 -338.615455)
			(xy 322.414739 -338.667754) (xy 322.39209 -338.717334) (xy 322.362615 -338.763186) (xy 322.326914 -338.804377)
			(xy 322.285715 -338.840068) (xy 322.239857 -338.869532) (xy 322.190271 -338.89217) (xy 322.137969 -338.907521)
			(xy 322.084014 -338.915273) (xy 322.05676 -338.915756) (xy 322.028902 -338.915302) (xy 321.973782 -338.907171)
			(xy 321.920428 -338.891118) (xy 321.869973 -338.867483) (xy 321.823488 -338.836768) (xy 321.781959 -338.799624)
			(xy 321.746268 -338.75684) (xy 321.717172 -338.709324) (xy 321.695289 -338.658085) (xy 321.687698 -338.631276)
			(xy 321.685412 -338.622386) (xy 321.674744 -338.607146) (xy 321.602862 -338.559394) (xy 321.584828 -338.55533)
			(xy 321.575684 -338.5566) (xy 321.562667 -338.558269) (xy 321.536483 -338.560049) (xy 321.52336 -338.560156)
			(xy 321.509211 -338.560066) (xy 321.480988 -338.558029) (xy 321.466972 -338.556092) (xy 321.456812 -338.554568)
			(xy 321.437254 -338.559394) (xy 321.362832 -338.615274) (xy 321.352672 -338.6328) (xy 321.351402 -338.64296)
			(xy 321.34734 -338.670118) (xy 321.332364 -338.72295) (xy 321.30997 -338.773089) (xy 321.280619 -338.8195)
			(xy 321.244919 -338.861224) (xy 321.203606 -338.8974) (xy 321.157534 -338.92728) (xy 321.107655 -338.950248)
			(xy 321.054999 -338.965828) (xy 321.000653 -338.973699) (xy 320.973196 -338.974176) (xy 320.945942 -338.973748)
			(xy 320.891988 -338.96599) (xy 320.839687 -338.950632) (xy 320.790105 -338.927986) (xy 320.74425 -338.898515)
			(xy 320.703057 -338.862818) (xy 320.667363 -338.821621) (xy 320.637896 -338.775763) (xy 320.615256 -338.726179)
			(xy 320.599902 -338.673877) (xy 320.592149 -338.619922) (xy 320.591688 -338.592668) (xy 318.450802 -338.592668)
			(xy 318.453431 -338.601625) (xy 318.461184 -338.655582) (xy 318.461644 -338.682838) (xy 318.460991 -338.714401)
			(xy 318.450602 -338.776667) (xy 318.430113 -338.836376) (xy 318.41567 -338.864448) (xy 318.410844 -338.873338)
			(xy 318.408812 -338.892896) (xy 318.434466 -338.981034) (xy 318.446912 -338.996528) (xy 318.455802 -339.001608)
			(xy 318.480891 -339.016175) (xy 318.526773 -339.051676) (xy 318.566749 -339.093717) (xy 318.599895 -339.141327)
			(xy 318.625448 -339.193409) (xy 318.642817 -339.24876) (xy 318.651603 -339.306104) (xy 318.652144 -339.33511)
			(xy 318.651658 -339.362361) (xy 318.643902 -339.416309) (xy 318.635301 -339.4456) (xy 324.354444 -339.4456)
			(xy 324.35492 -339.418125) (xy 324.362812 -339.363744) (xy 324.378434 -339.311061) (xy 324.401462 -339.261169)
			(xy 324.431417 -339.215101) (xy 324.449186 -339.19414) (xy 324.455282 -339.187028) (xy 324.461632 -339.17001)
			(xy 324.461632 -339.084158) (xy 324.455282 -339.06714) (xy 324.449186 -339.060028) (xy 324.431452 -339.039042)
			(xy 324.401523 -338.992966) (xy 324.378505 -338.943078) (xy 324.362872 -338.890407) (xy 324.354947 -338.836039)
			(xy 324.354444 -338.808568) (xy 324.35493 -338.781317) (xy 324.362686 -338.727369) (xy 324.378041 -338.675074)
			(xy 324.400683 -338.625497) (xy 324.430149 -338.579647) (xy 324.46584 -338.538456) (xy 324.507031 -338.502765)
			(xy 324.552881 -338.473299) (xy 324.602458 -338.450657) (xy 324.654753 -338.435302) (xy 324.708701 -338.427546)
			(xy 324.763203 -338.427546) (xy 324.817151 -338.435302) (xy 324.869446 -338.450657) (xy 324.919023 -338.473299)
			(xy 324.964873 -338.502765) (xy 325.006064 -338.538456) (xy 325.041755 -338.579647) (xy 325.071221 -338.625497)
			(xy 325.093863 -338.675074) (xy 325.109218 -338.727369) (xy 325.116974 -338.781317) (xy 325.11746 -338.808568)
			(xy 325.116965 -338.836042) (xy 325.109076 -338.890422) (xy 325.093459 -338.943105) (xy 325.070436 -338.992998)
			(xy 325.040485 -339.039066) (xy 325.022718 -339.060028) (xy 325.016622 -339.06714) (xy 325.010272 -339.084158)
			(xy 325.010272 -339.17001) (xy 325.016622 -339.187028) (xy 325.022718 -339.19414) (xy 325.040484 -339.2151)
			(xy 325.070408 -339.261183) (xy 325.09342 -339.311077) (xy 325.109046 -339.363755) (xy 325.116961 -339.418127)
			(xy 325.11746 -339.4456) (xy 325.116974 -339.472851) (xy 325.109218 -339.526799) (xy 325.093863 -339.579094)
			(xy 325.071221 -339.628671) (xy 325.041755 -339.674521) (xy 325.006064 -339.715712) (xy 324.964873 -339.751403)
			(xy 324.919023 -339.780869) (xy 324.869446 -339.803511) (xy 324.817151 -339.818866) (xy 324.763203 -339.826622)
			(xy 324.708701 -339.826622) (xy 324.654753 -339.818866) (xy 324.602458 -339.803511) (xy 324.552881 -339.780869)
			(xy 324.507031 -339.751403) (xy 324.46584 -339.715712) (xy 324.430149 -339.674521) (xy 324.400683 -339.628671)
			(xy 324.378041 -339.579094) (xy 324.362686 -339.526799) (xy 324.35493 -339.472851) (xy 324.354444 -339.4456)
			(xy 318.635301 -339.4456) (xy 318.628547 -339.468604) (xy 318.605905 -339.518181) (xy 318.576439 -339.564031)
			(xy 318.540748 -339.605222) (xy 318.499557 -339.640913) (xy 318.453707 -339.670379) (xy 318.40413 -339.693021)
			(xy 318.351835 -339.708376) (xy 318.297887 -339.716132) (xy 318.243385 -339.716132) (xy 318.189437 -339.708376)
			(xy 318.137142 -339.693021) (xy 318.087565 -339.670379) (xy 318.041715 -339.640913) (xy 318.000524 -339.605222)
			(xy 317.964833 -339.564031) (xy 317.935367 -339.518181) (xy 317.912725 -339.468604) (xy 317.89737 -339.416309)
			(xy 317.889614 -339.362361) (xy 317.889128 -339.33511) (xy 317.889764 -339.303546) (xy 317.900161 -339.24128)
			(xy 317.920656 -339.181572) (xy 317.935102 -339.1535) (xy 317.939928 -339.14461) (xy 317.94196 -339.125052)
			(xy 317.916306 -339.036914) (xy 317.90386 -339.02142) (xy 317.89497 -339.01634) (xy 317.887604 -339.012276)
			(xy 317.877952 -339.006434) (xy 317.855854 -339.004402) (xy 317.761366 -339.03793) (xy 317.745364 -339.053424)
			(xy 317.7413 -339.063838) (xy 317.731297 -339.088958) (xy 317.705219 -339.136321) (xy 317.672725 -339.179534)
			(xy 317.653924 -339.198966) (xy 317.647245 -339.206377) (xy 317.63967 -339.224814) (xy 317.639192 -339.23478)
			(xy 317.639192 -340.137242) (xy 317.639541 -340.14729) (xy 317.647142 -340.165887) (xy 317.653924 -340.17331)
			(xy 318.030606 -340.549992) (xy 318.038089 -340.556683) (xy 318.056647 -340.564273) (xy 318.066674 -340.564724)
			(xy 318.528446 -340.564724) (xy 318.538494 -340.564373) (xy 318.557091 -340.556773) (xy 318.564514 -340.549992)
			(xy 318.787526 -340.32698) (xy 318.805614 -340.309715) (xy 318.847162 -340.281908) (xy 318.893335 -340.262737)
			(xy 318.942361 -340.25294) (xy 318.967358 -340.252304) (xy 320.923666 -340.252304) (xy 320.948661 -340.252966)
			(xy 320.997682 -340.262763) (xy 321.043852 -340.281929) (xy 321.0854 -340.309729) (xy 321.103498 -340.32698)
			(xy 321.542918 -340.7664) (xy 321.550396 -340.773097) (xy 321.568958 -340.780684) (xy 321.578986 -340.781132)
			(xy 325.068438 -340.781132) (xy 325.078485 -340.780774) (xy 325.097082 -340.773179) (xy 325.104506 -340.7664)
			(xy 325.471028 -340.399878) (xy 325.477717 -340.392393) (xy 325.48531 -340.373837) (xy 325.48576 -340.36381)
			(xy 325.48576 -339.227668) (xy 325.485311 -339.217698) (xy 325.477716 -339.199263) (xy 325.471028 -339.191854)
			(xy 325.450145 -339.170236) (xy 325.414731 -339.121673) (xy 325.387375 -339.068156) (xy 325.368751 -339.01101)
			(xy 325.359323 -338.95165) (xy 325.35876 -338.921598) (xy 325.359276 -338.894348) (xy 325.367032 -338.840403)
			(xy 325.382386 -338.788111) (xy 325.405025 -338.738536) (xy 325.434488 -338.692687) (xy 325.470176 -338.651498)
			(xy 325.511363 -338.615806) (xy 325.557209 -338.586339) (xy 325.606783 -338.563696) (xy 325.659074 -338.548338)
			(xy 325.713018 -338.540578) (xy 325.740268 -338.54009) (xy 325.765504 -338.540458) (xy 325.815539 -338.547085)
			(xy 325.86426 -338.560267) (xy 325.91081 -338.579771) (xy 325.9328 -338.59216) (xy 325.942452 -338.598002)
			(xy 325.96455 -338.600034) (xy 326.059038 -338.566506) (xy 326.07504 -338.551012) (xy 326.079104 -338.540598)
			(xy 326.089779 -338.513812) (xy 326.118069 -338.46357) (xy 326.153601 -338.418159) (xy 326.195566 -338.378617)
			(xy 326.243007 -338.345844) (xy 326.294841 -338.320588) (xy 326.349887 -338.303424) (xy 326.40689 -338.294745)
			(xy 326.43572 -338.294218) (xy 326.462975 -338.294636) (xy 326.516928 -338.302397) (xy 326.569229 -338.317757)
			(xy 326.618811 -338.340403) (xy 326.664665 -338.369876) (xy 326.705858 -338.405574) (xy 326.741552 -338.446772)
			(xy 326.771019 -338.49263) (xy 326.793659 -338.542214) (xy 326.806382 -338.585556) (xy 328.947272 -338.585556)
			(xy 328.947786 -338.557983) (xy 328.95573 -338.503413) (xy 328.971446 -338.450554) (xy 328.994607 -338.400509)
			(xy 329.024731 -338.354318) (xy 329.061189 -338.312944) (xy 329.081892 -338.294726) (xy 329.089993 -338.287108)
			(xy 329.099357 -338.266968) (xy 329.099926 -338.255864) (xy 329.099926 -338.178648) (xy 329.099371 -338.167536)
			(xy 329.090026 -338.147376) (xy 329.081892 -338.139786) (xy 329.061169 -338.121587) (xy 329.0247 -338.080216)
			(xy 328.99457 -338.034023) (xy 328.971406 -337.983973) (xy 328.955692 -337.931108) (xy 328.947756 -337.876531)
			(xy 328.947272 -337.848956) (xy 328.947737 -337.821705) (xy 328.955499 -337.767757) (xy 328.970859 -337.715463)
			(xy 328.993503 -337.665887) (xy 329.022972 -337.620038) (xy 329.058666 -337.578849) (xy 329.099857 -337.543158)
			(xy 329.145708 -337.513692) (xy 329.195286 -337.49105) (xy 329.247581 -337.475694) (xy 329.301529 -337.467935)
			(xy 329.32878 -337.467448) (xy 329.36307 -337.468972) (xy 329.37323 -337.469988) (xy 329.392534 -337.463892)
			(xy 329.463146 -337.40471) (xy 329.472544 -337.386676) (xy 329.47356 -337.376516) (xy 329.476506 -337.348343)
			(xy 329.489684 -337.293252) (xy 329.510865 -337.240716) (xy 329.539585 -337.191892) (xy 329.57521 -337.147852)
			(xy 329.616957 -337.109566) (xy 329.663909 -337.077877) (xy 329.715031 -337.05348) (xy 329.769199 -337.036914)
			(xy 329.825221 -337.028542) (xy 329.853544 -337.028028) (xy 329.871563 -337.028248) (xy 329.907438 -337.031683)
			(xy 329.925172 -337.034886) (xy 329.93457 -337.036664) (xy 329.95362 -337.032854) (xy 330.028804 -336.985102)
			(xy 330.040234 -336.969354) (xy 330.04252 -336.959956) (xy 330.049915 -336.932911) (xy 330.071545 -336.881184)
			(xy 330.100509 -336.833179) (xy 330.136185 -336.789927) (xy 330.177804 -336.75236) (xy 330.224472 -336.721286)
			(xy 330.275184 -336.697373) (xy 330.328848 -336.681137) (xy 330.384311 -336.672927) (xy 330.412344 -336.672428)
			(xy 330.439598 -336.672837) (xy 330.49355 -336.6806) (xy 330.545849 -336.695963) (xy 330.595428 -336.718612)
			(xy 330.64128 -336.748086) (xy 330.682471 -336.783786) (xy 330.718162 -336.824984) (xy 330.747627 -336.870842)
			(xy 330.770265 -336.920426) (xy 330.785617 -336.972728) (xy 330.793369 -337.026682) (xy 330.793852 -337.053936)
			(xy 330.793359 -337.08151) (xy 330.785414 -337.136082) (xy 330.769696 -337.188942) (xy 330.746531 -337.238989)
			(xy 330.716403 -337.285179) (xy 330.679938 -337.32655) (xy 330.659232 -337.344766) (xy 330.651122 -337.352376)
			(xy 330.641766 -337.372522) (xy 330.641198 -337.383628) (xy 330.641198 -337.460844) (xy 330.641782 -337.471952)
			(xy 330.651109 -337.492111) (xy 330.659232 -337.499706) (xy 330.679972 -337.517883) (xy 330.716433 -337.559261)
			(xy 330.746556 -337.605457) (xy 330.769715 -337.655508) (xy 330.785426 -337.708373) (xy 330.793363 -337.762948)
			(xy 330.79336 -337.818098) (xy 330.785416 -337.872673) (xy 330.769699 -337.925535) (xy 330.746534 -337.975584)
			(xy 330.716404 -338.021776) (xy 330.679939 -338.06315) (xy 330.659232 -338.081366) (xy 330.651122 -338.088976)
			(xy 330.641766 -338.109122) (xy 330.641198 -338.120228) (xy 330.641198 -338.197444) (xy 330.641782 -338.208552)
			(xy 330.651109 -338.228711) (xy 330.659232 -338.236306) (xy 330.679956 -338.254503) (xy 330.716424 -338.295876)
			(xy 330.746553 -338.342069) (xy 330.769717 -338.392119) (xy 330.785431 -338.444984) (xy 330.793368 -338.499561)
			(xy 330.793852 -338.527136) (xy 330.793356 -338.554386) (xy 330.785596 -338.608331) (xy 330.770238 -338.660623)
			(xy 330.747596 -338.710197) (xy 330.71813 -338.756046) (xy 330.68244 -338.797234) (xy 330.641252 -338.832925)
			(xy 330.595405 -338.862392) (xy 330.545831 -338.885035) (xy 330.493539 -338.900394) (xy 330.439594 -338.908155)
			(xy 330.412344 -338.908644) (xy 330.384492 -338.908049) (xy 330.329381 -338.899932) (xy 330.276034 -338.883895)
			(xy 330.225583 -338.860277) (xy 330.1791 -338.829579) (xy 330.13757 -338.792453) (xy 330.101875 -338.749687)
			(xy 330.072772 -338.702188) (xy 330.050879 -338.650965) (xy 330.043282 -338.624164) (xy 330.040996 -338.615274)
			(xy 330.030328 -338.600034) (xy 329.958446 -338.552282) (xy 329.940412 -338.548218) (xy 329.931268 -338.549488)
			(xy 329.918252 -338.551158) (xy 329.892067 -338.552937) (xy 329.878944 -338.553044) (xy 329.864795 -338.552945)
			(xy 329.836572 -338.550914) (xy 329.822556 -338.54898) (xy 329.812396 -338.547456) (xy 329.792838 -338.552282)
			(xy 329.718416 -338.608162) (xy 329.708256 -338.625688) (xy 329.706986 -338.635848) (xy 329.70293 -338.663007)
			(xy 329.687955 -338.71584) (xy 329.665561 -338.76598) (xy 329.63621 -338.812392) (xy 329.600509 -338.854117)
			(xy 329.559195 -338.890293) (xy 329.513122 -338.920173) (xy 329.463242 -338.94314) (xy 329.410584 -338.958719)
			(xy 329.356237 -338.966588) (xy 329.32878 -338.967064) (xy 329.301525 -338.966664) (xy 329.247569 -338.958903)
			(xy 329.195267 -338.943542) (xy 329.145684 -338.920894) (xy 329.099829 -338.89142) (xy 329.058635 -338.855719)
			(xy 329.022942 -338.81452) (xy 328.993475 -338.76866) (xy 328.970836 -338.719073) (xy 328.955484 -338.666768)
			(xy 328.947732 -338.612811) (xy 328.947272 -338.585556) (xy 326.806382 -338.585556) (xy 326.809013 -338.594517)
			(xy 326.816767 -338.648471) (xy 326.817228 -338.675726) (xy 326.81656 -338.707288) (xy 326.806176 -338.769553)
			(xy 326.785693 -338.829263) (xy 326.771254 -338.857336) (xy 326.766428 -338.866226) (xy 326.764396 -338.885784)
			(xy 326.79005 -338.973922) (xy 326.802496 -338.989416) (xy 326.811386 -338.994496) (xy 326.83651 -339.009007)
			(xy 326.882393 -339.044516) (xy 326.922368 -339.086566) (xy 326.955511 -339.134186) (xy 326.981058 -339.186277)
			(xy 326.998419 -339.241637) (xy 327.007193 -339.298989) (xy 327.007728 -339.327998) (xy 327.007242 -339.355249)
			(xy 326.999486 -339.409197) (xy 326.993048 -339.431122) (xy 332.71206 -339.431122) (xy 332.712569 -339.403648)
			(xy 332.720457 -339.34927) (xy 332.736072 -339.296588) (xy 332.759092 -339.246695) (xy 332.789037 -339.200625)
			(xy 332.806802 -339.179662) (xy 332.812898 -339.17255) (xy 332.819248 -339.155532) (xy 332.819248 -339.06968)
			(xy 332.812898 -339.052662) (xy 332.806802 -339.04555) (xy 332.789034 -339.024591) (xy 332.75911 -338.978509)
			(xy 332.736098 -338.928613) (xy 332.720473 -338.875936) (xy 332.712558 -338.821563) (xy 332.71206 -338.79409)
			(xy 332.712546 -338.766839) (xy 332.720302 -338.712891) (xy 332.735657 -338.660596) (xy 332.758299 -338.611019)
			(xy 332.787765 -338.565169) (xy 332.823456 -338.523978) (xy 332.864647 -338.488287) (xy 332.910497 -338.458821)
			(xy 332.960074 -338.436179) (xy 333.012369 -338.420824) (xy 333.066317 -338.413068) (xy 333.120819 -338.413068)
			(xy 333.174767 -338.420824) (xy 333.227062 -338.436179) (xy 333.276639 -338.458821) (xy 333.322489 -338.488287)
			(xy 333.36368 -338.523978) (xy 333.399371 -338.565169) (xy 333.428837 -338.611019) (xy 333.451479 -338.660596)
			(xy 333.466834 -338.712891) (xy 333.47459 -338.766839) (xy 333.475076 -338.79409) (xy 333.47459 -338.821565)
			(xy 333.466699 -338.875945) (xy 333.451079 -338.928627) (xy 333.428054 -338.97852) (xy 333.398102 -339.024588)
			(xy 333.380334 -339.04555) (xy 333.374238 -339.052662) (xy 333.367888 -339.06968) (xy 333.367888 -339.155532)
			(xy 333.374238 -339.17255) (xy 333.380334 -339.179662) (xy 333.398066 -339.20065) (xy 333.427995 -339.246725)
			(xy 333.451013 -339.296613) (xy 333.466646 -339.349284) (xy 333.474572 -339.403651) (xy 333.475076 -339.431122)
			(xy 333.47459 -339.458373) (xy 333.466834 -339.512321) (xy 333.451479 -339.564616) (xy 333.428837 -339.614193)
			(xy 333.399371 -339.660043) (xy 333.36368 -339.701234) (xy 333.322489 -339.736925) (xy 333.276639 -339.766391)
			(xy 333.227062 -339.789033) (xy 333.174767 -339.804388) (xy 333.120819 -339.812144) (xy 333.066317 -339.812144)
			(xy 333.012369 -339.804388) (xy 332.960074 -339.789033) (xy 332.910497 -339.766391) (xy 332.864647 -339.736925)
			(xy 332.823456 -339.701234) (xy 332.787765 -339.660043) (xy 332.758299 -339.614193) (xy 332.735657 -339.564616)
			(xy 332.720302 -339.512321) (xy 332.712546 -339.458373) (xy 332.71206 -339.431122) (xy 326.993048 -339.431122)
			(xy 326.984131 -339.461492) (xy 326.961489 -339.511069) (xy 326.932023 -339.556919) (xy 326.896332 -339.59811)
			(xy 326.855141 -339.633801) (xy 326.809291 -339.663267) (xy 326.759714 -339.685909) (xy 326.707419 -339.701264)
			(xy 326.653471 -339.70902) (xy 326.598969 -339.70902) (xy 326.545021 -339.701264) (xy 326.492726 -339.685909)
			(xy 326.443149 -339.663267) (xy 326.397299 -339.633801) (xy 326.356108 -339.59811) (xy 326.320417 -339.556919)
			(xy 326.290951 -339.511069) (xy 326.268309 -339.461492) (xy 326.252954 -339.409197) (xy 326.245198 -339.355249)
			(xy 326.244712 -339.327998) (xy 326.245385 -339.296436) (xy 326.255766 -339.234171) (xy 326.276247 -339.174461)
			(xy 326.290686 -339.146388) (xy 326.295512 -339.137498) (xy 326.297544 -339.11794) (xy 326.27189 -339.029802)
			(xy 326.259444 -339.014308) (xy 326.250554 -339.009228) (xy 326.243188 -339.005164) (xy 326.233536 -338.999322)
			(xy 326.211438 -338.99729) (xy 326.11695 -339.030818) (xy 326.100948 -339.046312) (xy 326.096884 -339.056726)
			(xy 326.086881 -339.081845) (xy 326.060804 -339.129209) (xy 326.028309 -339.172422) (xy 326.009508 -339.191854)
			(xy 326.002832 -339.199267) (xy 325.995255 -339.217703) (xy 325.994776 -339.227668) (xy 325.994776 -340.364826)
			(xy 325.995138 -340.374873) (xy 326.00273 -340.39347) (xy 326.009508 -340.400894) (xy 326.401684 -340.79307)
			(xy 326.409099 -340.799891) (xy 326.427687 -340.807623) (xy 326.437752 -340.808056) (xy 333.296768 -340.808056)
			(xy 333.306837 -340.807625) (xy 333.325435 -340.79991) (xy 333.332836 -340.79307) (xy 333.828644 -340.297262)
			(xy 333.835343 -340.289785) (xy 333.84293 -340.271222) (xy 333.843376 -340.261194) (xy 333.843376 -339.21319)
			(xy 333.842911 -339.203222) (xy 333.835327 -339.184786) (xy 333.828644 -339.177376) (xy 333.807726 -339.15579)
			(xy 333.772317 -339.107218) (xy 333.744966 -339.053693) (xy 333.726351 -338.99654) (xy 333.716933 -338.937174)
			(xy 333.716376 -338.90712) (xy 333.716874 -338.879868) (xy 333.724628 -338.82592) (xy 333.73998 -338.773623)
			(xy 333.762619 -338.724044) (xy 333.792084 -338.678192) (xy 333.827774 -338.636999) (xy 333.868963 -338.601305)
			(xy 333.914813 -338.571837) (xy 333.96439 -338.549193) (xy 334.016684 -338.533835) (xy 334.070632 -338.526076)
			(xy 334.097884 -338.525612) (xy 334.123121 -338.52597) (xy 334.173156 -338.5326) (xy 334.221876 -338.545784)
			(xy 334.268427 -338.565292) (xy 334.290416 -338.577682) (xy 334.300068 -338.583524) (xy 334.322166 -338.585556)
			(xy 334.416654 -338.552028) (xy 334.432656 -338.536534) (xy 334.43672 -338.52612) (xy 334.447394 -338.499334)
			(xy 334.475682 -338.449089) (xy 334.511214 -338.403678) (xy 334.553179 -338.364135) (xy 334.60062 -338.331361)
			(xy 334.652455 -338.306106) (xy 334.707502 -338.288944) (xy 334.764506 -338.280266) (xy 334.793336 -338.27974)
			(xy 334.820592 -338.280122) (xy 334.874548 -338.287885) (xy 334.926851 -338.303248) (xy 334.976434 -338.325898)
			(xy 335.02229 -338.355374) (xy 335.063483 -338.391076) (xy 335.099176 -338.432278) (xy 335.128642 -338.47814)
			(xy 335.151282 -338.527728) (xy 335.164005 -338.571078) (xy 337.304888 -338.571078) (xy 337.305412 -338.543506)
			(xy 337.313353 -338.488935) (xy 337.329067 -338.436077) (xy 337.352226 -338.386031) (xy 337.382348 -338.33984)
			(xy 337.418806 -338.298466) (xy 337.439508 -338.280248) (xy 337.447602 -338.272623) (xy 337.456969 -338.252489)
			(xy 337.457542 -338.241386) (xy 337.457542 -338.16417) (xy 337.457025 -338.153053) (xy 337.447652 -338.132894)
			(xy 337.439508 -338.125308) (xy 337.418799 -338.107094) (xy 337.382328 -338.065726) (xy 337.352196 -338.019537)
			(xy 337.329029 -337.969489) (xy 337.313313 -337.916627) (xy 337.305373 -337.862053) (xy 337.304888 -337.834478)
			(xy 337.305357 -337.807226) (xy 337.313117 -337.753278) (xy 337.328474 -337.700983) (xy 337.351118 -337.651406)
			(xy 337.380586 -337.605556) (xy 337.416279 -337.564366) (xy 337.457471 -337.528675) (xy 337.503322 -337.499209)
			(xy 337.5529 -337.476568) (xy 337.605196 -337.461213) (xy 337.659144 -337.453456) (xy 337.686396 -337.45297)
			(xy 337.720686 -337.454494) (xy 337.730846 -337.45551) (xy 337.75015 -337.449414) (xy 337.820762 -337.390232)
			(xy 337.83016 -337.372198) (xy 337.831176 -337.362038) (xy 337.834125 -337.333865) (xy 337.8473 -337.278773)
			(xy 337.86848 -337.226236) (xy 337.897198 -337.177411) (xy 337.932823 -337.13337) (xy 337.974571 -337.095084)
			(xy 338.021522 -337.063394) (xy 338.072645 -337.038998) (xy 338.126814 -337.022433) (xy 338.182837 -337.014063)
			(xy 338.21116 -337.01355) (xy 338.229179 -337.013767) (xy 338.265054 -337.017204) (xy 338.282788 -337.020408)
			(xy 338.292186 -337.022186) (xy 338.311236 -337.018376) (xy 338.38642 -336.970624) (xy 338.39785 -336.954876)
			(xy 338.400136 -336.945478) (xy 338.407531 -336.918433) (xy 338.429159 -336.866705) (xy 338.458122 -336.818698)
			(xy 338.493798 -336.775445) (xy 338.535417 -336.737878) (xy 338.582086 -336.706803) (xy 338.632798 -336.682891)
			(xy 338.686463 -336.666656) (xy 338.741926 -336.658447) (xy 338.76996 -336.65795) (xy 338.797208 -336.658515)
			(xy 338.851151 -336.666265) (xy 338.903442 -336.681613) (xy 338.953016 -336.704247) (xy 338.998864 -336.733705)
			(xy 339.040054 -336.769388) (xy 339.075746 -336.81057) (xy 339.105214 -336.856412) (xy 339.127858 -336.905981)
			(xy 339.143217 -336.958269) (xy 339.150979 -337.01221) (xy 339.151468 -337.039458) (xy 339.150985 -337.067032)
			(xy 339.143037 -337.121605) (xy 339.127316 -337.174465) (xy 339.10415 -337.224511) (xy 339.07402 -337.270701)
			(xy 339.037554 -337.312072) (xy 339.016848 -337.330288) (xy 339.008731 -337.337892) (xy 338.999378 -337.358043)
			(xy 338.998814 -337.36915) (xy 338.998814 -337.446366) (xy 338.999381 -337.457476) (xy 339.00872 -337.477635)
			(xy 339.016848 -337.485228) (xy 339.037514 -337.503488) (xy 339.073982 -337.544852) (xy 339.104114 -337.591035)
			(xy 339.127281 -337.641077) (xy 339.143001 -337.693932) (xy 339.150945 -337.748501) (xy 339.150949 -337.803645)
			(xy 339.143012 -337.858215) (xy 339.1273 -337.911073) (xy 339.10414 -337.961117) (xy 339.074015 -338.007305)
			(xy 339.037553 -338.048674) (xy 339.016848 -338.066888) (xy 339.008731 -338.074492) (xy 338.999378 -338.094643)
			(xy 338.998814 -338.10575) (xy 338.998814 -338.182966) (xy 338.999381 -338.194076) (xy 339.00872 -338.214235)
			(xy 339.016848 -338.221828) (xy 339.037586 -338.24001) (xy 339.074052 -338.281386) (xy 339.104179 -338.327583)
			(xy 339.12734 -338.377636) (xy 339.143051 -338.430503) (xy 339.150985 -338.485082) (xy 339.151468 -338.512658)
			(xy 339.151006 -338.539912) (xy 339.143253 -338.593865) (xy 339.1279 -338.646165) (xy 339.10526 -338.695748)
			(xy 339.075793 -338.741603) (xy 339.040099 -338.782797) (xy 338.998905 -338.818491) (xy 338.953049 -338.847959)
			(xy 338.903467 -338.8706) (xy 338.851167 -338.885953) (xy 338.797214 -338.893705) (xy 338.76996 -338.894166)
			(xy 338.742102 -338.893704) (xy 338.686983 -338.885574) (xy 338.63363 -338.869521) (xy 338.583175 -338.845887)
			(xy 338.53669 -338.815173) (xy 338.495161 -338.77803) (xy 338.45947 -338.735247) (xy 338.430373 -338.687732)
			(xy 338.40849 -338.636494) (xy 338.400898 -338.609686) (xy 338.398612 -338.600796) (xy 338.387944 -338.585556)
			(xy 338.316062 -338.537804) (xy 338.298028 -338.53374) (xy 338.288884 -338.53501) (xy 338.275867 -338.536679)
			(xy 338.249683 -338.538459) (xy 338.23656 -338.538566) (xy 338.222411 -338.538477) (xy 338.194188 -338.53644)
			(xy 338.180172 -338.534502) (xy 338.170012 -338.532978) (xy 338.150454 -338.537804) (xy 338.076032 -338.593684)
			(xy 338.065872 -338.61121) (xy 338.064602 -338.62137) (xy 338.060548 -338.648529) (xy 338.045571 -338.701361)
			(xy 338.023175 -338.7515) (xy 337.993824 -338.797911) (xy 337.958122 -338.839635) (xy 337.916809 -338.875811)
			(xy 337.870736 -338.905691) (xy 337.820856 -338.928658) (xy 337.768199 -338.944238) (xy 337.713853 -338.952109)
			(xy 337.686396 -338.952586) (xy 337.659142 -338.952148) (xy 337.605189 -338.94439) (xy 337.552889 -338.929033)
			(xy 337.503308 -338.906388) (xy 337.457454 -338.876918) (xy 337.41626 -338.841221) (xy 337.380567 -338.800026)
			(xy 337.3511 -338.754169) (xy 337.328458 -338.704586) (xy 337.313104 -338.652285) (xy 337.30535 -338.598332)
			(xy 337.304888 -338.571078) (xy 335.164005 -338.571078) (xy 335.166633 -338.580034) (xy 335.174384 -338.633992)
			(xy 335.174844 -338.661248) (xy 335.174195 -338.692811) (xy 335.163804 -338.755077) (xy 335.143314 -338.814786)
			(xy 335.12887 -338.842858) (xy 335.124044 -338.851748) (xy 335.122012 -338.871306) (xy 335.147666 -338.959444)
			(xy 335.160112 -338.974938) (xy 335.169002 -338.980018) (xy 335.194096 -338.994578) (xy 335.239978 -339.03008)
			(xy 335.279953 -339.072122) (xy 335.313099 -339.119734) (xy 335.338651 -339.171817) (xy 335.356019 -339.227169)
			(xy 335.364803 -339.284513) (xy 335.365344 -339.31352) (xy 335.364858 -339.340771) (xy 335.357102 -339.394719)
			(xy 335.341747 -339.447014) (xy 335.325804 -339.481922) (xy 341.04326 -339.481922) (xy 341.043769 -339.454448)
			(xy 341.051657 -339.40007) (xy 341.067272 -339.347388) (xy 341.090292 -339.297495) (xy 341.120237 -339.251425)
			(xy 341.138002 -339.230462) (xy 341.144098 -339.22335) (xy 341.150448 -339.206332) (xy 341.150448 -339.12048)
			(xy 341.144098 -339.103462) (xy 341.138002 -339.09635) (xy 341.120234 -339.075391) (xy 341.09031 -339.029309)
			(xy 341.067298 -338.979413) (xy 341.051673 -338.926736) (xy 341.043758 -338.872363) (xy 341.04326 -338.84489)
			(xy 341.043746 -338.817639) (xy 341.051502 -338.763691) (xy 341.066857 -338.711396) (xy 341.089499 -338.661819)
			(xy 341.118965 -338.615969) (xy 341.154656 -338.574778) (xy 341.195847 -338.539087) (xy 341.241697 -338.509621)
			(xy 341.291274 -338.486979) (xy 341.343569 -338.471624) (xy 341.397517 -338.463868) (xy 341.452019 -338.463868)
			(xy 341.505967 -338.471624) (xy 341.558262 -338.486979) (xy 341.607839 -338.509621) (xy 341.653689 -338.539087)
			(xy 341.69488 -338.574778) (xy 341.730571 -338.615969) (xy 341.760037 -338.661819) (xy 341.782679 -338.711396)
			(xy 341.798034 -338.763691) (xy 341.80579 -338.817639) (xy 341.806276 -338.84489) (xy 341.80579 -338.872365)
			(xy 341.797899 -338.926745) (xy 341.782279 -338.979427) (xy 341.759254 -339.02932) (xy 341.729302 -339.075388)
			(xy 341.711534 -339.09635) (xy 341.705438 -339.103462) (xy 341.699088 -339.12048) (xy 341.699088 -339.206332)
			(xy 341.705438 -339.22335) (xy 341.711534 -339.230462) (xy 341.729266 -339.25145) (xy 341.759195 -339.297525)
			(xy 341.782213 -339.347413) (xy 341.797846 -339.400084) (xy 341.805772 -339.454451) (xy 341.806276 -339.481922)
			(xy 341.80579 -339.509173) (xy 341.798034 -339.563121) (xy 341.782679 -339.615416) (xy 341.760037 -339.664993)
			(xy 341.730571 -339.710843) (xy 341.69488 -339.752034) (xy 341.653689 -339.787725) (xy 341.607839 -339.817191)
			(xy 341.558262 -339.839833) (xy 341.505967 -339.855188) (xy 341.452019 -339.862944) (xy 341.397517 -339.862944)
			(xy 341.343569 -339.855188) (xy 341.291274 -339.839833) (xy 341.241697 -339.817191) (xy 341.195847 -339.787725)
			(xy 341.154656 -339.752034) (xy 341.118965 -339.710843) (xy 341.089499 -339.664993) (xy 341.066857 -339.615416)
			(xy 341.051502 -339.563121) (xy 341.043746 -339.509173) (xy 341.04326 -339.481922) (xy 335.325804 -339.481922)
			(xy 335.319105 -339.496591) (xy 335.289639 -339.542441) (xy 335.253948 -339.583632) (xy 335.212757 -339.619323)
			(xy 335.166907 -339.648789) (xy 335.11733 -339.671431) (xy 335.065035 -339.686786) (xy 335.011087 -339.694542)
			(xy 334.956585 -339.694542) (xy 334.902637 -339.686786) (xy 334.850342 -339.671431) (xy 334.800765 -339.648789)
			(xy 334.754915 -339.619323) (xy 334.713724 -339.583632) (xy 334.678033 -339.542441) (xy 334.648567 -339.496591)
			(xy 334.625925 -339.447014) (xy 334.61057 -339.394719) (xy 334.602814 -339.340771) (xy 334.602328 -339.31352)
			(xy 334.602968 -339.281956) (xy 334.613363 -339.21969) (xy 334.633857 -339.159982) (xy 334.648302 -339.13191)
			(xy 334.653128 -339.12302) (xy 334.65516 -339.103462) (xy 334.629506 -339.015324) (xy 334.61706 -338.99983)
			(xy 334.60817 -338.99475) (xy 334.600804 -338.990686) (xy 334.591152 -338.984844) (xy 334.569054 -338.982812)
			(xy 334.474566 -339.01634) (xy 334.458564 -339.031834) (xy 334.4545 -339.042248) (xy 334.4445 -339.067369)
			(xy 334.418421 -339.114732) (xy 334.385925 -339.157945) (xy 334.367124 -339.177376) (xy 334.36044 -339.184784)
			(xy 334.352868 -339.203223) (xy 334.352392 -339.21319) (xy 334.352392 -340.261194) (xy 334.352766 -340.271239)
			(xy 334.36035 -340.289837) (xy 334.367124 -340.297262) (xy 334.862932 -340.79307) (xy 334.870331 -340.799912)
			(xy 334.888931 -340.807632) (xy 334.899 -340.808056) (xy 341.805768 -340.808056) (xy 341.815837 -340.807625)
			(xy 341.834435 -340.79991) (xy 341.841836 -340.79307) (xy 342.159844 -340.475062) (xy 342.166543 -340.467585)
			(xy 342.17413 -340.449022) (xy 342.174576 -340.438994) (xy 342.174576 -339.26399) (xy 342.174111 -339.254022)
			(xy 342.166527 -339.235586) (xy 342.159844 -339.228176) (xy 342.138926 -339.20659) (xy 342.103517 -339.158018)
			(xy 342.076166 -339.104493) (xy 342.057551 -339.04734) (xy 342.048133 -338.987974) (xy 342.047576 -338.95792)
			(xy 342.048074 -338.930668) (xy 342.055828 -338.87672) (xy 342.07118 -338.824423) (xy 342.093819 -338.774844)
			(xy 342.123284 -338.728992) (xy 342.158974 -338.687799) (xy 342.200163 -338.652105) (xy 342.246013 -338.622637)
			(xy 342.29559 -338.599993) (xy 342.347884 -338.584635) (xy 342.401832 -338.576876) (xy 342.429084 -338.576412)
			(xy 342.454321 -338.57677) (xy 342.504356 -338.5834) (xy 342.553076 -338.596584) (xy 342.599627 -338.616092)
			(xy 342.621616 -338.628482) (xy 342.631268 -338.634324) (xy 342.653366 -338.636356) (xy 342.747854 -338.602828)
			(xy 342.763856 -338.587334) (xy 342.76792 -338.57692) (xy 342.778594 -338.550134) (xy 342.806882 -338.499889)
			(xy 342.842414 -338.454478) (xy 342.884379 -338.414935) (xy 342.93182 -338.382161) (xy 342.983655 -338.356906)
			(xy 343.038702 -338.339744) (xy 343.095706 -338.331066) (xy 343.124536 -338.33054) (xy 343.151792 -338.330922)
			(xy 343.205748 -338.338685) (xy 343.258051 -338.354048) (xy 343.307634 -338.376698) (xy 343.35349 -338.406174)
			(xy 343.394683 -338.441876) (xy 343.430376 -338.483078) (xy 343.459842 -338.52894) (xy 343.482482 -338.578528)
			(xy 343.497833 -338.630834) (xy 343.505584 -338.684792) (xy 343.506044 -338.712048) (xy 343.505395 -338.743611)
			(xy 343.495004 -338.805877) (xy 343.474514 -338.865586) (xy 343.46007 -338.893658) (xy 343.455244 -338.902548)
			(xy 343.453212 -338.922106) (xy 343.478866 -339.010244) (xy 343.491312 -339.025738) (xy 343.500202 -339.030818)
			(xy 343.525296 -339.045378) (xy 343.571178 -339.08088) (xy 343.611153 -339.122922) (xy 343.644299 -339.170534)
			(xy 343.669851 -339.222617) (xy 343.687219 -339.277969) (xy 343.696003 -339.335313) (xy 343.696435 -339.358478)
			(xy 345.636088 -339.358478) (xy 345.636612 -339.330906) (xy 345.644553 -339.276335) (xy 345.660267 -339.223477)
			(xy 345.683426 -339.173431) (xy 345.713548 -339.12724) (xy 345.750006 -339.085866) (xy 345.770708 -339.067648)
			(xy 345.778802 -339.060023) (xy 345.788169 -339.039889) (xy 345.788742 -339.028786) (xy 345.788742 -338.95157)
			(xy 345.788225 -338.940453) (xy 345.778852 -338.920294) (xy 345.770708 -338.912708) (xy 345.74998 -338.894516)
			(xy 345.713516 -338.853142) (xy 345.683389 -338.806949) (xy 345.660227 -338.756899) (xy 345.644513 -338.704036)
			(xy 345.636575 -338.649461) (xy 345.636577 -338.594311) (xy 345.644519 -338.539737) (xy 345.660237 -338.486874)
			(xy 345.683403 -338.436826) (xy 345.713533 -338.390635) (xy 345.750001 -338.349264) (xy 345.770708 -338.331048)
			(xy 345.778802 -338.323423) (xy 345.788169 -338.303289) (xy 345.788742 -338.292186) (xy 345.788742 -338.21497)
			(xy 345.788225 -338.203853) (xy 345.778852 -338.183694) (xy 345.770708 -338.176108) (xy 345.749999 -338.157894)
			(xy 345.713528 -338.116526) (xy 345.683396 -338.070337) (xy 345.660229 -338.020289) (xy 345.644513 -337.967427)
			(xy 345.636573 -337.912853) (xy 345.636088 -337.885278) (xy 345.636557 -337.858026) (xy 345.644317 -337.804078)
			(xy 345.659674 -337.751783) (xy 345.682318 -337.702206) (xy 345.711786 -337.656356) (xy 345.747479 -337.615166)
			(xy 345.788671 -337.579475) (xy 345.834522 -337.550009) (xy 345.8841 -337.527368) (xy 345.936396 -337.512013)
			(xy 345.990344 -337.504256) (xy 346.017596 -337.50377) (xy 346.051886 -337.505294) (xy 346.062046 -337.50631)
			(xy 346.08135 -337.500214) (xy 346.151962 -337.441032) (xy 346.16136 -337.422998) (xy 346.162376 -337.412838)
			(xy 346.165325 -337.384665) (xy 346.1785 -337.329573) (xy 346.19968 -337.277036) (xy 346.228398 -337.228211)
			(xy 346.264023 -337.18417) (xy 346.305771 -337.145884) (xy 346.352722 -337.114194) (xy 346.403845 -337.089798)
			(xy 346.458014 -337.073233) (xy 346.514037 -337.064863) (xy 346.54236 -337.06435) (xy 346.569608 -337.064915)
			(xy 346.623551 -337.072665) (xy 346.675842 -337.088013) (xy 346.725416 -337.110647) (xy 346.771264 -337.140105)
			(xy 346.812454 -337.175788) (xy 346.848146 -337.21697) (xy 346.877614 -337.262812) (xy 346.900258 -337.312381)
			(xy 346.915617 -337.364669) (xy 346.923379 -337.41861) (xy 346.923868 -337.445858) (xy 346.923337 -337.473719)
			(xy 346.915242 -337.528849) (xy 346.899218 -337.582216) (xy 346.875606 -337.632687) (xy 346.844907 -337.679189)
			(xy 346.807773 -337.720733) (xy 346.786708 -337.738974) (xy 346.777564 -337.746594) (xy 346.767912 -337.767676)
			(xy 346.771468 -337.871562) (xy 346.78239 -337.892136) (xy 346.792042 -337.899248) (xy 346.8126 -337.914661)
			(xy 346.849734 -337.950174) (xy 346.881765 -337.990351) (xy 346.908113 -338.034465) (xy 346.9283 -338.081715)
			(xy 346.941963 -338.131248) (xy 346.948852 -338.182167) (xy 346.949268 -338.207858) (xy 346.948732 -338.236774)
			(xy 346.940008 -338.293945) (xy 346.922755 -338.349144) (xy 346.897366 -338.401106) (xy 346.864425 -338.448641)
			(xy 346.824687 -338.490658) (xy 346.802202 -338.508848) (xy 346.793423 -338.516394) (xy 346.783249 -338.537165)
			(xy 346.782644 -338.548726) (xy 346.782644 -338.62899) (xy 346.783205 -338.64056) (xy 346.793405 -338.661331)
			(xy 346.802202 -338.668868) (xy 346.822945 -338.68567) (xy 346.860078 -338.724016) (xy 346.891503 -338.767164)
			(xy 346.916606 -338.814272) (xy 346.934896 -338.864419) (xy 346.946016 -338.916626) (xy 346.94975 -338.969874)
			(xy 346.946024 -339.023123) (xy 346.93491 -339.075332) (xy 346.916627 -339.125481) (xy 346.891531 -339.172592)
			(xy 346.860112 -339.215745) (xy 346.822984 -339.254096) (xy 346.802202 -339.270848) (xy 346.793423 -339.278394)
			(xy 346.783249 -339.299165) (xy 346.782644 -339.310726) (xy 346.782644 -339.39099) (xy 346.783205 -339.40256)
			(xy 346.793405 -339.423331) (xy 346.802202 -339.430868) (xy 346.824671 -339.449077) (xy 346.864407 -339.491093)
			(xy 346.897347 -339.538624) (xy 346.922738 -339.590582) (xy 346.939998 -339.645776) (xy 346.948731 -339.702943)
			(xy 346.949268 -339.731858) (xy 346.948806 -339.759112) (xy 346.941053 -339.813065) (xy 346.9257 -339.865365)
			(xy 346.90306 -339.914948) (xy 346.873593 -339.960803) (xy 346.837899 -340.001997) (xy 346.796705 -340.037691)
			(xy 346.750849 -340.067159) (xy 346.701267 -340.0898) (xy 346.648967 -340.105153) (xy 346.595014 -340.112905)
			(xy 346.56776 -340.113366) (xy 346.539022 -340.112852) (xy 346.482198 -340.104211) (xy 346.427313 -340.087145)
			(xy 346.375608 -340.06204) (xy 346.328253 -340.029464) (xy 346.28632 -339.990155) (xy 346.250757 -339.945001)
			(xy 346.222368 -339.895024) (xy 346.201796 -339.841355) (xy 346.195142 -339.813392) (xy 346.192856 -339.80374)
			(xy 346.182188 -339.787738) (xy 346.10802 -339.737446) (xy 346.089224 -339.733382) (xy 346.079318 -339.734906)
			(xy 346.063998 -339.737279) (xy 346.033098 -339.739824) (xy 346.017596 -339.739986) (xy 345.990342 -339.739548)
			(xy 345.936389 -339.73179) (xy 345.884089 -339.716433) (xy 345.834508 -339.693788) (xy 345.788654 -339.664318)
			(xy 345.74746 -339.628621) (xy 345.711767 -339.587426) (xy 345.6823 -339.541569) (xy 345.659658 -339.491986)
			(xy 345.644304 -339.439685) (xy 345.63655 -339.385732) (xy 345.636088 -339.358478) (xy 343.696435 -339.358478)
			(xy 343.696544 -339.36432) (xy 343.696058 -339.391571) (xy 343.688302 -339.445519) (xy 343.672947 -339.497814)
			(xy 343.650305 -339.547391) (xy 343.620839 -339.593241) (xy 343.585148 -339.634432) (xy 343.543957 -339.670123)
			(xy 343.498107 -339.699589) (xy 343.44853 -339.722231) (xy 343.396235 -339.737586) (xy 343.342287 -339.745342)
			(xy 343.287785 -339.745342) (xy 343.233837 -339.737586) (xy 343.181542 -339.722231) (xy 343.131965 -339.699589)
			(xy 343.086115 -339.670123) (xy 343.044924 -339.634432) (xy 343.009233 -339.593241) (xy 342.979767 -339.547391)
			(xy 342.957125 -339.497814) (xy 342.94177 -339.445519) (xy 342.934014 -339.391571) (xy 342.933528 -339.36432)
			(xy 342.934168 -339.332756) (xy 342.944563 -339.27049) (xy 342.965057 -339.210782) (xy 342.979502 -339.18271)
			(xy 342.984328 -339.17382) (xy 342.98636 -339.154262) (xy 342.960706 -339.066124) (xy 342.94826 -339.05063)
			(xy 342.93937 -339.04555) (xy 342.932004 -339.041486) (xy 342.922352 -339.035644) (xy 342.900254 -339.033612)
			(xy 342.805766 -339.06714) (xy 342.789764 -339.082634) (xy 342.7857 -339.093048) (xy 342.7757 -339.118169)
			(xy 342.749621 -339.165532) (xy 342.717125 -339.208745) (xy 342.698324 -339.228176) (xy 342.69164 -339.235584)
			(xy 342.684068 -339.254023) (xy 342.683592 -339.26399) (xy 342.683592 -340.416642) (xy 342.683941 -340.42669)
			(xy 342.691542 -340.445287) (xy 342.698324 -340.45271) (xy 345.541092 -343.295478) (xy 345.558329 -343.31359)
			(xy 345.586143 -343.355129) (xy 345.605322 -343.401295) (xy 345.615127 -343.450315) (xy 345.615768 -343.47531)
			(xy 345.615768 -344.391996) (xy 349.319088 -344.391996) (xy 349.319575 -344.364521) (xy 349.327467 -344.310142)
			(xy 349.343087 -344.25746) (xy 349.366112 -344.207567) (xy 349.396063 -344.161498) (xy 349.41383 -344.140536)
			(xy 349.419926 -344.133424) (xy 349.426276 -344.116406) (xy 349.426276 -344.030554) (xy 349.419926 -344.013536)
			(xy 349.41383 -344.006424) (xy 349.396085 -343.985446) (xy 349.36616 -343.939368) (xy 349.343145 -343.889477)
			(xy 349.327514 -343.836804) (xy 349.319591 -343.782435) (xy 349.319088 -343.754964) (xy 349.319574 -343.727713)
			(xy 349.32733 -343.673765) (xy 349.342685 -343.62147) (xy 349.365327 -343.571893) (xy 349.394793 -343.526043)
			(xy 349.430484 -343.484852) (xy 349.471675 -343.449161) (xy 349.517525 -343.419695) (xy 349.567102 -343.397053)
			(xy 349.619397 -343.381698) (xy 349.673345 -343.373942) (xy 349.727847 -343.373942) (xy 349.781795 -343.381698)
			(xy 349.83409 -343.397053) (xy 349.883667 -343.419695) (xy 349.929517 -343.449161) (xy 349.970708 -343.484852)
			(xy 350.006399 -343.526043) (xy 350.035865 -343.571893) (xy 350.058507 -343.62147) (xy 350.073862 -343.673765)
			(xy 350.081618 -343.727713) (xy 350.082104 -343.754964) (xy 350.081596 -343.782438) (xy 350.073709 -343.836816)
			(xy 350.058094 -343.889498) (xy 350.035074 -343.939392) (xy 350.005127 -343.985461) (xy 349.987362 -344.006424)
			(xy 349.981266 -344.013536) (xy 349.974916 -344.030554) (xy 349.974916 -344.116406) (xy 349.981266 -344.133424)
			(xy 349.987362 -344.140536) (xy 350.005133 -344.161492) (xy 350.035055 -344.207576) (xy 350.058065 -344.257472)
			(xy 350.07369 -344.31015) (xy 350.081605 -344.364523) (xy 350.082104 -344.391996) (xy 350.081618 -344.419247)
			(xy 350.073862 -344.473195) (xy 350.058507 -344.52549) (xy 350.035865 -344.575067) (xy 350.006399 -344.620917)
			(xy 349.970708 -344.662108) (xy 349.929517 -344.697799) (xy 349.883667 -344.727265) (xy 349.83409 -344.749907)
			(xy 349.781795 -344.765262) (xy 349.727847 -344.773018) (xy 349.673345 -344.773018) (xy 349.619397 -344.765262)
			(xy 349.567102 -344.749907) (xy 349.517525 -344.727265) (xy 349.471675 -344.697799) (xy 349.430484 -344.662108)
			(xy 349.394793 -344.620917) (xy 349.365327 -344.575067) (xy 349.342685 -344.52549) (xy 349.32733 -344.473195)
			(xy 349.319574 -344.419247) (xy 349.319088 -344.391996) (xy 345.615768 -344.391996) (xy 345.615768 -344.745818)
			(xy 345.616136 -344.755864) (xy 345.623724 -344.774461) (xy 345.6305 -344.781886) (xy 346.721684 -345.87307)
			(xy 346.729099 -345.879891) (xy 346.747687 -345.887623) (xy 346.757752 -345.888056) (xy 349.679768 -345.888056)
			(xy 349.689837 -345.887625) (xy 349.708435 -345.87991) (xy 349.715836 -345.87307) (xy 350.29902 -345.289886)
			(xy 350.305705 -345.282398) (xy 350.313301 -345.263844) (xy 350.313752 -345.253818) (xy 350.313752 -344.004646)
			(xy 350.314064 -343.986416) (xy 350.319296 -343.950334) (xy 350.324166 -343.932764) (xy 350.325525 -343.927805)
			(xy 350.326418 -343.917564) (xy 350.325944 -343.912444) (xy 350.324742 -343.901371) (xy 350.32347 -343.879132)
			(xy 350.323404 -343.867994) (xy 350.32385 -343.84074) (xy 350.331608 -343.786788) (xy 350.346965 -343.734489)
			(xy 350.369609 -343.684908) (xy 350.399079 -343.639055) (xy 350.434775 -343.597862) (xy 350.475969 -343.562168)
			(xy 350.521824 -343.532701) (xy 350.571406 -343.510059) (xy 350.623706 -343.494704) (xy 350.677658 -343.486949)
			(xy 350.704912 -343.486486) (xy 350.730147 -343.48688) (xy 350.780181 -343.493499) (xy 350.828902 -343.506673)
			(xy 350.875454 -343.526171) (xy 350.897444 -343.538556) (xy 350.907096 -343.544398) (xy 350.929194 -343.54643)
			(xy 351.023682 -343.512902) (xy 351.039684 -343.497408) (xy 351.043748 -343.486994) (xy 351.054468 -343.460228)
			(xy 351.082752 -343.409987) (xy 351.118279 -343.364577) (xy 351.160237 -343.325035) (xy 351.207671 -343.29226)
			(xy 351.259499 -343.267) (xy 351.314539 -343.249831) (xy 351.371536 -343.241145) (xy 351.400364 -343.240614)
			(xy 351.427617 -343.241089) (xy 351.481569 -343.248842) (xy 351.533868 -343.264194) (xy 351.583449 -343.286834)
			(xy 351.629303 -343.3163) (xy 351.670497 -343.351993) (xy 351.706191 -343.393185) (xy 351.735659 -343.439039)
			(xy 351.758301 -343.488619) (xy 351.771024 -343.531952) (xy 353.911916 -343.531952) (xy 353.912412 -343.504378)
			(xy 353.920357 -343.449807) (xy 353.936076 -343.396947) (xy 353.95924 -343.346901) (xy 353.989368 -343.300711)
			(xy 354.025831 -343.259338) (xy 354.046536 -343.241122) (xy 354.054646 -343.233512) (xy 354.064004 -343.213366)
			(xy 354.06457 -343.20226) (xy 354.06457 -343.125044) (xy 354.064003 -343.113934) (xy 354.054665 -343.093775)
			(xy 354.046536 -343.086182) (xy 354.02582 -343.067976) (xy 353.989349 -343.026607) (xy 353.959216 -342.980416)
			(xy 353.936051 -342.930367) (xy 353.920336 -342.877503) (xy 353.912399 -342.822927) (xy 353.911916 -342.795352)
			(xy 353.912333 -342.768098) (xy 353.920097 -342.714147) (xy 353.935459 -342.66185) (xy 353.958108 -342.612271)
			(xy 353.987581 -342.566419) (xy 354.02328 -342.525229) (xy 354.064477 -342.489538) (xy 354.110334 -342.460073)
			(xy 354.159917 -342.437434) (xy 354.212217 -342.422082) (xy 354.26617 -342.414328) (xy 354.293424 -342.413844)
			(xy 354.327714 -342.415368) (xy 354.337874 -342.416384) (xy 354.357178 -342.410288) (xy 354.42779 -342.351106)
			(xy 354.437188 -342.333072) (xy 354.438204 -342.322912) (xy 354.441103 -342.294733) (xy 354.454284 -342.239638)
			(xy 354.475469 -342.1871) (xy 354.504193 -342.138273) (xy 354.539824 -342.094232) (xy 354.581577 -342.055946)
			(xy 354.628534 -342.024258) (xy 354.679662 -341.999864) (xy 354.733836 -341.983302) (xy 354.789863 -341.974935)
			(xy 354.818188 -341.974424) (xy 354.836208 -341.974638) (xy 354.872082 -341.978077) (xy 354.889816 -341.981282)
			(xy 354.899214 -341.98306) (xy 354.918264 -341.97925) (xy 354.993448 -341.931498) (xy 355.004878 -341.91575)
			(xy 355.007164 -341.906352) (xy 355.014516 -341.879294) (xy 355.03615 -341.827565) (xy 355.065119 -341.779558)
			(xy 355.1008 -341.736305) (xy 355.142425 -341.698739) (xy 355.189099 -341.667666) (xy 355.239816 -341.643757)
			(xy 355.293486 -341.627525) (xy 355.348953 -341.619319) (xy 355.376988 -341.618824) (xy 355.404242 -341.619267)
			(xy 355.458195 -341.627023) (xy 355.510496 -341.642379) (xy 355.560078 -341.665022) (xy 355.605932 -341.694492)
			(xy 355.647126 -341.730188) (xy 355.68282 -341.771384) (xy 355.712287 -341.81724) (xy 355.734928 -341.866823)
			(xy 355.750282 -341.919124) (xy 355.758035 -341.973078) (xy 355.758496 -342.000332) (xy 355.757985 -342.027905)
			(xy 355.750042 -342.082476) (xy 355.734326 -342.135335) (xy 355.711164 -342.185381) (xy 355.68104 -342.231572)
			(xy 355.64458 -342.272945) (xy 355.623876 -342.291162) (xy 355.615776 -342.298781) (xy 355.606412 -342.31892)
			(xy 355.605842 -342.330024) (xy 355.605842 -342.40724) (xy 355.606358 -342.418356) (xy 355.615732 -342.438515)
			(xy 355.623876 -342.446102) (xy 355.644614 -342.464282) (xy 355.68108 -342.505657) (xy 355.711208 -342.551852)
			(xy 355.734371 -342.601903) (xy 355.750085 -342.654768) (xy 355.758023 -342.709345) (xy 355.75802 -342.764496)
			(xy 355.750076 -342.819072) (xy 355.734356 -342.871935) (xy 355.711188 -342.921984) (xy 355.681055 -342.968176)
			(xy 355.644585 -343.009547) (xy 355.623876 -343.027762) (xy 355.615776 -343.035381) (xy 355.606412 -343.05552)
			(xy 355.605842 -343.066624) (xy 355.605842 -343.14384) (xy 355.606358 -343.154956) (xy 355.615732 -343.175115)
			(xy 355.623876 -343.182702) (xy 355.644587 -343.200914) (xy 355.681058 -343.242282) (xy 355.711191 -343.288471)
			(xy 355.734357 -343.338519) (xy 355.750073 -343.391382) (xy 355.758012 -343.445957) (xy 355.758496 -343.473532)
			(xy 355.758052 -343.500785) (xy 355.750291 -343.554734) (xy 355.734931 -343.607031) (xy 355.712285 -343.656609)
			(xy 355.682814 -343.70246) (xy 355.647119 -343.74365) (xy 355.605924 -343.779341) (xy 355.56007 -343.808806)
			(xy 355.510489 -343.831446) (xy 355.458191 -343.8468) (xy 355.404241 -343.854555) (xy 355.376988 -343.85504)
			(xy 355.349134 -343.854498) (xy 355.29402 -343.846374) (xy 355.240672 -343.830329) (xy 355.190221 -343.806703)
			(xy 355.143738 -343.775999) (xy 355.102208 -343.738867) (xy 355.066514 -343.696095) (xy 355.037413 -343.648591)
			(xy 355.015522 -343.597363) (xy 355.007926 -343.57056) (xy 355.00564 -343.56167) (xy 354.994972 -343.54643)
			(xy 354.92309 -343.498678) (xy 354.905056 -343.494614) (xy 354.895912 -343.495884) (xy 354.882895 -343.49755)
			(xy 354.856711 -343.499332) (xy 354.843588 -343.49944) (xy 354.829439 -343.499347) (xy 354.801216 -343.497312)
			(xy 354.7872 -343.495376) (xy 354.77704 -343.493852) (xy 354.757482 -343.498678) (xy 354.68306 -343.554558)
			(xy 354.6729 -343.572084) (xy 354.67163 -343.582244) (xy 354.667529 -343.609395) (xy 354.652557 -343.662224)
			(xy 354.630166 -343.712362) (xy 354.60082 -343.758772) (xy 354.565124 -343.800496) (xy 354.523816 -343.836673)
			(xy 354.477749 -343.866554) (xy 354.427874 -343.889524) (xy 354.375221 -343.905107) (xy 354.320879 -343.912981)
			(xy 354.293424 -343.91346) (xy 354.26617 -343.913022) (xy 354.212215 -343.905267) (xy 354.159914 -343.889912)
			(xy 354.110331 -343.867269) (xy 354.064475 -343.837799) (xy 354.023281 -343.802102) (xy 353.987587 -343.760906)
			(xy 353.95812 -343.715048) (xy 353.93548 -343.665464) (xy 353.920128 -343.613161) (xy 353.912376 -343.559206)
			(xy 353.911916 -343.531952) (xy 351.771024 -343.531952) (xy 351.773656 -343.540918) (xy 351.78141 -343.594869)
			(xy 351.781872 -343.622122) (xy 351.781209 -343.653685) (xy 351.770824 -343.71595) (xy 351.750339 -343.775659)
			(xy 351.735898 -343.803732) (xy 351.731072 -343.812622) (xy 351.72904 -343.83218) (xy 351.754694 -343.920318)
			(xy 351.76714 -343.935812) (xy 351.77603 -343.940892) (xy 351.801163 -343.955389) (xy 351.847044 -343.990902)
			(xy 351.887016 -344.032955) (xy 351.920157 -344.080578) (xy 351.945703 -344.132671) (xy 351.963063 -344.188032)
			(xy 351.971837 -344.245384) (xy 351.972372 -344.274394) (xy 351.971886 -344.301645) (xy 351.96413 -344.355593)
			(xy 351.948775 -344.407888) (xy 351.926133 -344.457465) (xy 351.896667 -344.503315) (xy 351.860976 -344.544506)
			(xy 351.819785 -344.580197) (xy 351.773935 -344.609663) (xy 351.724358 -344.632305) (xy 351.672063 -344.64766)
			(xy 351.618115 -344.655416) (xy 351.563613 -344.655416) (xy 351.509665 -344.64766) (xy 351.45737 -344.632305)
			(xy 351.407793 -344.609663) (xy 351.361943 -344.580197) (xy 351.320752 -344.544506) (xy 351.285061 -344.503315)
			(xy 351.255595 -344.457465) (xy 351.232953 -344.407888) (xy 351.217598 -344.355593) (xy 351.209842 -344.301645)
			(xy 351.209356 -344.274394) (xy 351.210022 -344.242831) (xy 351.220406 -344.180566) (xy 351.240889 -344.120857)
			(xy 351.25533 -344.092784) (xy 351.260156 -344.083894) (xy 351.262188 -344.064336) (xy 351.236534 -343.976198)
			(xy 351.224088 -343.960704) (xy 351.215198 -343.955624) (xy 351.207832 -343.95156) (xy 351.19818 -343.945718)
			(xy 351.176082 -343.943686) (xy 351.081594 -343.977214) (xy 351.065592 -343.992708) (xy 351.061528 -344.003122)
			(xy 351.052027 -344.026991) (xy 351.027561 -344.072166) (xy 350.997255 -344.113649) (xy 350.961655 -344.150689)
			(xy 350.921407 -344.182617) (xy 350.877238 -344.208854) (xy 350.853756 -344.219276) (xy 350.839532 -344.225372)
			(xy 350.822768 -344.250772) (xy 350.822768 -345.38031) (xy 350.822141 -345.405306) (xy 350.812334 -345.45433)
			(xy 350.793158 -345.5005) (xy 350.765348 -345.542046) (xy 350.748092 -345.560142) (xy 349.986092 -346.322142)
			(xy 349.967997 -346.339381) (xy 349.926433 -346.367119) (xy 349.880258 -346.386222) (xy 349.831245 -346.395957)
			(xy 349.80626 -346.396564) (xy 346.63126 -346.396564) (xy 346.606276 -346.395955) (xy 346.557269 -346.38621)
			(xy 346.511099 -346.367102) (xy 346.469538 -346.339363) (xy 346.451428 -346.322142) (xy 345.181428 -345.052142)
			(xy 345.164156 -345.03406) (xy 345.136348 -344.992511) (xy 345.117178 -344.946336) (xy 345.107385 -344.897308)
			(xy 345.106752 -344.87231) (xy 345.106752 -343.601802) (xy 345.106368 -343.591758) (xy 345.09879 -343.573161)
			(xy 345.09202 -343.565734) (xy 342.476074 -340.950042) (xy 342.468713 -340.943273) (xy 342.450251 -340.935626)
			(xy 342.430269 -340.935626) (xy 342.411807 -340.943273) (xy 342.404446 -340.950042) (xy 342.112092 -341.242142)
			(xy 342.093997 -341.259381) (xy 342.052433 -341.287119) (xy 342.006258 -341.306222) (xy 341.957245 -341.315957)
			(xy 341.93226 -341.316564) (xy 334.772508 -341.316564) (xy 334.747526 -341.315925) (xy 334.698519 -341.30619)
			(xy 334.65235 -341.28709) (xy 334.610788 -341.25936) (xy 334.592676 -341.242142) (xy 334.133698 -340.783418)
			(xy 334.126337 -340.776649) (xy 334.107875 -340.769002) (xy 334.087893 -340.769002) (xy 334.069431 -340.776649)
			(xy 334.06207 -340.783418) (xy 333.603092 -341.242142) (xy 333.584997 -341.259381) (xy 333.543433 -341.287119)
			(xy 333.497258 -341.306222) (xy 333.448245 -341.315957) (xy 333.42326 -341.316564) (xy 326.31126 -341.316564)
			(xy 326.286276 -341.315955) (xy 326.237269 -341.30621) (xy 326.191099 -341.287102) (xy 326.149538 -341.259363)
			(xy 326.131428 -341.242142) (xy 325.775574 -340.886542) (xy 325.768213 -340.879773) (xy 325.749751 -340.872126)
			(xy 325.729769 -340.872126) (xy 325.711307 -340.879773) (xy 325.703946 -340.886542) (xy 325.374762 -341.215472)
			(xy 325.356672 -341.232734) (xy 325.315126 -341.260545) (xy 325.268953 -341.279716) (xy 325.219927 -341.289513)
			(xy 325.19493 -341.290148) (xy 321.452494 -341.290148) (xy 321.427497 -341.289524) (xy 321.378474 -341.279717)
			(xy 321.332303 -341.26054) (xy 321.290757 -341.232729) (xy 321.272662 -341.215472) (xy 320.833242 -340.776052)
			(xy 320.825772 -340.769344) (xy 320.807204 -340.761762) (xy 320.797174 -340.76132) (xy 319.09385 -340.76132)
			(xy 319.083804 -340.761684) (xy 319.065208 -340.769277) (xy 319.057782 -340.776052) (xy 318.83477 -340.999064)
			(xy 318.816675 -341.016321) (xy 318.775131 -341.044133) (xy 318.728959 -341.063306) (xy 318.679935 -341.073104)
			(xy 318.654938 -341.07374) (xy 317.940182 -341.07374) (xy 317.915185 -341.073126) (xy 317.86616 -341.063316)
			(xy 317.81999 -341.044136) (xy 317.778445 -341.016322) (xy 317.76035 -340.999064) (xy 317.420498 -340.659466)
			(xy 317.413137 -340.652697) (xy 317.394675 -340.64505) (xy 317.374693 -340.64505) (xy 317.356231 -340.652697)
			(xy 317.34887 -340.659466) (xy 317.25235 -340.755732) (xy 317.234284 -340.773025) (xy 317.192733 -340.800841)
			(xy 317.146553 -340.820017) (xy 317.097519 -340.829814) (xy 317.072518 -340.830408) (xy 316.553088 -340.830408)
			(xy 316.543044 -340.830795) (xy 316.524448 -340.838372) (xy 316.51702 -340.84514) (xy 314.508134 -342.854026)
			(xy 314.501295 -342.861427) (xy 314.493574 -342.880025) (xy 314.493148 -342.890094) (xy 314.493148 -350.656652)
			(xy 314.49255 -350.681636) (xy 314.482803 -350.730645) (xy 314.463691 -350.776814) (xy 314.435949 -350.818374)
			(xy 314.418726 -350.836484) (xy 313.513978 -351.741232) (xy 313.495875 -351.75848) (xy 313.454334 -351.786295)
			(xy 313.408165 -351.805471) (xy 313.359142 -351.815271) (xy 313.334146 -351.815908) (xy 309.625492 -351.815908)
			(xy 309.615449 -351.816297) (xy 309.596853 -351.823872) (xy 309.589424 -351.83064) (xy 308.866032 -352.554032)
			(xy 308.847974 -352.571333) (xy 308.80642 -352.599148) (xy 308.760237 -352.618321) (xy 308.711202 -352.628116)
			(xy 308.6862 -352.628708) (xy 308.22011 -352.628708) (xy 308.195113 -352.628086) (xy 308.146089 -352.61828)
			(xy 308.099917 -352.599103) (xy 308.058373 -352.57129) (xy 308.040278 -352.554032) (xy 307.770784 -352.284792)
			(xy 307.763423 -352.278023) (xy 307.744961 -352.270376) (xy 307.724979 -352.270376) (xy 307.706517 -352.278023)
			(xy 307.699156 -352.284792) (xy 306.64404 -353.339654) (xy 306.637332 -353.347124) (xy 306.629751 -353.365692)
			(xy 306.629308 -353.375722) (xy 306.629308 -353.59975) (xy 307.212492 -353.59975) (xy 307.213002 -353.572498)
			(xy 307.220752 -353.518549) (xy 307.236102 -353.466252) (xy 307.258738 -353.416672) (xy 307.288201 -353.370819)
			(xy 307.32389 -353.329626) (xy 307.365079 -353.293931) (xy 307.410928 -353.264462) (xy 307.460505 -353.241819)
			(xy 307.5128 -353.226463) (xy 307.566748 -353.218705) (xy 307.594 -353.218242) (xy 307.624051 -353.218811)
			(xy 307.683409 -353.228247) (xy 307.740554 -353.24687) (xy 307.794074 -353.274219) (xy 307.842646 -353.309619)
			(xy 307.864256 -353.33051) (xy 307.871661 -353.337232) (xy 307.890085 -353.344953) (xy 307.90007 -353.345496)
			(xy 308.324758 -353.345496) (xy 308.334828 -353.345076) (xy 308.353428 -353.337355) (xy 308.360826 -353.33051)
			(xy 309.471568 -352.219768) (xy 309.489626 -352.202467) (xy 309.53118 -352.174652) (xy 309.577363 -352.155479)
			(xy 309.626398 -352.145684) (xy 309.6514 -352.145092) (xy 313.919108 -352.145092) (xy 313.929151 -352.144703)
			(xy 313.947747 -352.137128) (xy 313.955176 -352.13036) (xy 314.805568 -351.279968) (xy 314.823626 -351.262667)
			(xy 314.86518 -351.234852) (xy 314.911363 -351.215679) (xy 314.960398 -351.205884) (xy 314.9854 -351.205292)
			(xy 318.156336 -351.205292) (xy 318.166381 -351.204918) (xy 318.184977 -351.197332) (xy 318.192404 -351.19056)
			(xy 325.487284 -343.89568) (xy 325.50539 -343.878435) (xy 325.546931 -343.850624) (xy 325.593099 -343.831448)
			(xy 325.642121 -343.821644) (xy 325.667116 -343.821004) (xy 342.513412 -343.821004) (xy 342.538408 -343.821638)
			(xy 342.58743 -343.831444) (xy 342.633601 -343.850618) (xy 342.675147 -343.878425) (xy 342.693244 -343.89568)
			(xy 346.390976 -347.593412) (xy 346.398444 -347.600123) (xy 346.417013 -347.607704) (xy 346.427044 -347.608144)
			(xy 353.018852 -347.608144) (xy 353.028899 -347.607791) (xy 353.047496 -347.600192) (xy 353.05492 -347.593412)
			(xy 356.219252 -344.42908) (xy 356.225944 -344.421598) (xy 356.233535 -344.403039) (xy 356.233984 -344.393012)
			(xy 356.233984 -335.433924) (xy 356.234617 -335.408928) (xy 356.244419 -335.359904) (xy 356.263594 -335.313733)
			(xy 356.291403 -335.272187) (xy 356.30866 -335.254092) (xy 358.819704 -332.743048) (xy 358.826417 -332.735582)
			(xy 358.833994 -332.717011) (xy 358.834436 -332.70698) (xy 358.834436 -331.244956) (xy 358.835102 -331.219961)
			(xy 358.844897 -331.17094) (xy 358.864061 -331.124769) (xy 358.891861 -331.083221) (xy 358.909112 -331.065124)
			(xy 360.05262 -329.921616) (xy 360.059335 -329.914152) (xy 360.066914 -329.89558) (xy 360.067352 -329.885548)
			(xy 360.067352 -327.854564) (xy 360.06699 -327.844517) (xy 360.059391 -327.825924) (xy 360.04519 -327.811718)
			(xy 360.026599 -327.804113) (xy 360.016552 -327.803764) (xy 359.50398 -327.803764) (xy 359.49401 -327.804213)
			(xy 359.475574 -327.811807) (xy 359.468166 -327.818496) (xy 359.446546 -327.839378) (xy 359.397983 -327.87479)
			(xy 359.344466 -327.902147) (xy 359.287321 -327.92077) (xy 359.227962 -327.9302) (xy 359.19791 -327.930764)
			(xy 359.170655 -327.930335) (xy 359.116701 -327.922578) (xy 359.0644 -327.907221) (xy 359.014817 -327.884577)
			(xy 358.968961 -327.855106) (xy 358.927768 -327.819408) (xy 358.892074 -327.778211) (xy 358.862607 -327.732353)
			(xy 358.839967 -327.682768) (xy 358.824614 -327.630466) (xy 358.816862 -327.576511) (xy 358.816402 -327.549256)
			(xy 358.816826 -327.523162) (xy 358.823949 -327.471461) (xy 358.838057 -327.421216) (xy 358.858886 -327.373364)
			(xy 358.886046 -327.328799) (xy 358.919031 -327.288355) (xy 358.957223 -327.252788) (xy 358.999909 -327.222762)
			(xy 359.022904 -327.21042) (xy 359.035604 -327.203816) (xy 359.050336 -327.179686) (xy 359.05059 -327.060814)
			(xy 359.035858 -327.036684) (xy 359.023158 -327.03008) (xy 359.000315 -327.017653) (xy 358.957915 -326.987547)
			(xy 358.919996 -326.951962) (xy 358.88726 -326.911557) (xy 358.860314 -326.867082) (xy 358.839657 -326.819359)
			(xy 358.825671 -326.769274) (xy 358.818616 -326.717753) (xy 358.81818 -326.691752) (xy 358.818671 -326.664491)
			(xy 358.82644 -326.610524) (xy 358.841813 -326.558214) (xy 358.864476 -326.508624) (xy 358.893968 -326.462766)
			(xy 358.929688 -326.421574) (xy 358.970908 -326.385886) (xy 359.01679 -326.356431) (xy 359.066397 -326.333807)
			(xy 359.11872 -326.318476) (xy 359.172692 -326.31075) (xy 359.227215 -326.310786) (xy 359.281177 -326.318584)
			(xy 359.33348 -326.333985) (xy 359.383057 -326.356675) (xy 359.428899 -326.386191) (xy 359.470072 -326.421934)
			(xy 359.505737 -326.463173) (xy 359.535168 -326.509071) (xy 359.557765 -326.55869) (xy 359.573068 -326.611021)
			(xy 359.580765 -326.664998) (xy 359.581196 -326.69226) (xy 359.581196 -326.702674) (xy 359.588816 -326.721216)
			(xy 359.715562 -326.847962) (xy 359.722986 -326.854773) (xy 359.741567 -326.862511) (xy 359.75163 -326.862948)
			(xy 360.385106 -326.862948) (xy 360.410089 -326.863575) (xy 360.459096 -326.873313) (xy 360.505266 -326.892416)
			(xy 360.546827 -326.920151) (xy 360.564938 -326.93737) (xy 360.882692 -327.255124) (xy 360.899951 -327.273217)
			(xy 360.927761 -327.314763) (xy 360.946933 -327.360935) (xy 360.956732 -327.409959) (xy 360.957368 -327.434956)
			(xy 360.957368 -330.170028) (xy 360.956752 -330.195025) (xy 360.946941 -330.244049) (xy 360.927762 -330.290219)
			(xy 360.899949 -330.331765) (xy 360.882692 -330.34986) (xy 359.739184 -331.493368) (xy 359.732476 -331.500838)
			(xy 359.724893 -331.519406) (xy 359.724452 -331.529436) (xy 359.724452 -332.99146) (xy 359.723799 -333.016455)
			(xy 359.714001 -333.065477) (xy 359.694833 -333.111648) (xy 359.667029 -333.153195) (xy 359.649776 -333.171292)
			(xy 357.138732 -335.682336) (xy 357.132031 -335.689811) (xy 357.124446 -335.708375) (xy 357.124 -335.718404)
			(xy 357.124 -344.677492) (xy 357.123381 -344.702489) (xy 357.113575 -344.751514) (xy 357.094397 -344.797685)
			(xy 357.066583 -344.83923) (xy 357.049324 -344.857324) (xy 353.483164 -348.423484) (xy 353.465075 -348.440747)
			(xy 353.423528 -348.468557) (xy 353.377355 -348.487728) (xy 353.328329 -348.497525) (xy 353.303332 -348.49816)
			(xy 346.142564 -348.49816) (xy 346.11757 -348.49749) (xy 346.068548 -348.487697) (xy 346.022377 -348.468534)
			(xy 345.98083 -348.440735) (xy 345.962732 -348.423484) (xy 342.265 -344.725752) (xy 342.25751 -344.71907)
			(xy 342.238957 -344.711473) (xy 342.228932 -344.71102) (xy 325.951596 -344.71102) (xy 325.941553 -344.711408)
			(xy 325.922956 -344.718984) (xy 325.915528 -344.725752) (xy 321.167322 -349.473958) (xy 327.06208 -349.473958)
			(xy 327.06208 -349.389262) (xy 327.070131 -349.304948) (xy 327.08616 -349.221782) (xy 327.110021 -349.140515)
			(xy 327.1415 -349.061885) (xy 327.180311 -348.986604) (xy 327.226101 -348.915352) (xy 327.278457 -348.848776)
			(xy 327.336905 -348.787478) (xy 327.400915 -348.732013) (xy 327.469907 -348.682884) (xy 327.543257 -348.640535)
			(xy 327.6203 -348.605351) (xy 327.700339 -348.577649) (xy 327.782648 -348.557681) (xy 327.866483 -348.545628)
			(xy 327.951084 -348.541598) (xy 328.035685 -348.545628) (xy 328.11952 -348.557681) (xy 328.201829 -348.577649)
			(xy 328.281868 -348.605351) (xy 328.358911 -348.640535) (xy 328.432261 -348.682884) (xy 328.501253 -348.732013)
			(xy 328.565263 -348.787478) (xy 328.623711 -348.848776) (xy 328.676067 -348.915352) (xy 328.721857 -348.986604)
			(xy 328.760668 -349.061885) (xy 328.792147 -349.140515) (xy 328.816008 -349.221782) (xy 328.832037 -349.304948)
			(xy 328.840088 -349.389262) (xy 328.840592 -349.43161) (xy 328.840088 -349.473958) (xy 334.52206 -349.473958)
			(xy 334.52206 -349.389262) (xy 334.530111 -349.304948) (xy 334.54614 -349.221782) (xy 334.570001 -349.140515)
			(xy 334.60148 -349.061885) (xy 334.640291 -348.986604) (xy 334.686081 -348.915352) (xy 334.738437 -348.848776)
			(xy 334.796885 -348.787478) (xy 334.860895 -348.732013) (xy 334.929887 -348.682884) (xy 335.003237 -348.640535)
			(xy 335.08028 -348.605351) (xy 335.160319 -348.577649) (xy 335.242628 -348.557681) (xy 335.326463 -348.545628)
			(xy 335.411064 -348.541598) (xy 335.495665 -348.545628) (xy 335.5795 -348.557681) (xy 335.661809 -348.577649)
			(xy 335.741848 -348.605351) (xy 335.818891 -348.640535) (xy 335.892241 -348.682884) (xy 335.961233 -348.732013)
			(xy 336.025243 -348.787478) (xy 336.083691 -348.848776) (xy 336.136047 -348.915352) (xy 336.181837 -348.986604)
			(xy 336.220648 -349.061885) (xy 336.252127 -349.140515) (xy 336.275988 -349.221782) (xy 336.292017 -349.304948)
			(xy 336.300068 -349.389262) (xy 336.300572 -349.43161) (xy 336.300068 -349.473958) (xy 336.292017 -349.558272)
			(xy 336.275988 -349.641438) (xy 336.252127 -349.722705) (xy 336.220648 -349.801335) (xy 336.181837 -349.876616)
			(xy 336.136047 -349.947868) (xy 336.083691 -350.014444) (xy 336.025243 -350.075742) (xy 335.961233 -350.131207)
			(xy 335.892241 -350.180336) (xy 335.818891 -350.222685) (xy 335.741848 -350.257869) (xy 335.661809 -350.285571)
			(xy 335.5795 -350.305539) (xy 335.495665 -350.317592) (xy 335.411064 -350.321623) (xy 335.326463 -350.317592)
			(xy 335.242628 -350.305539) (xy 335.160319 -350.285571) (xy 335.08028 -350.257869) (xy 335.003237 -350.222685)
			(xy 334.929887 -350.180336) (xy 334.860895 -350.131207) (xy 334.796885 -350.075742) (xy 334.738437 -350.014444)
			(xy 334.686081 -349.947868) (xy 334.640291 -349.876616) (xy 334.60148 -349.801335) (xy 334.570001 -349.722705)
			(xy 334.54614 -349.641438) (xy 334.530111 -349.558272) (xy 334.52206 -349.473958) (xy 328.840088 -349.473958)
			(xy 328.832037 -349.558272) (xy 328.816008 -349.641438) (xy 328.792147 -349.722705) (xy 328.760668 -349.801335)
			(xy 328.721857 -349.876616) (xy 328.676067 -349.947868) (xy 328.623711 -350.014444) (xy 328.565263 -350.075742)
			(xy 328.501253 -350.131207) (xy 328.432261 -350.180336) (xy 328.358911 -350.222685) (xy 328.281868 -350.257869)
			(xy 328.201829 -350.285571) (xy 328.11952 -350.305539) (xy 328.035685 -350.317592) (xy 327.951084 -350.321623)
			(xy 327.866483 -350.317592) (xy 327.782648 -350.305539) (xy 327.700339 -350.285571) (xy 327.6203 -350.257869)
			(xy 327.543257 -350.222685) (xy 327.469907 -350.180336) (xy 327.400915 -350.131207) (xy 327.336905 -350.075742)
			(xy 327.278457 -350.014444) (xy 327.226101 -349.947868) (xy 327.180311 -349.876616) (xy 327.1415 -349.801335)
			(xy 327.110021 -349.722705) (xy 327.08616 -349.641438) (xy 327.070131 -349.558272) (xy 327.06208 -349.473958)
			(xy 321.167322 -349.473958) (xy 318.6672 -351.97408) (xy 327.06208 -351.97408) (xy 327.06208 -351.889384)
			(xy 327.070131 -351.80507) (xy 327.08616 -351.721904) (xy 327.110021 -351.640637) (xy 327.1415 -351.562007)
			(xy 327.180311 -351.486726) (xy 327.226101 -351.415474) (xy 327.278457 -351.348898) (xy 327.336905 -351.2876)
			(xy 327.400915 -351.232135) (xy 327.469907 -351.183006) (xy 327.543257 -351.140657) (xy 327.6203 -351.105473)
			(xy 327.700339 -351.077771) (xy 327.782648 -351.057803) (xy 327.866483 -351.04575) (xy 327.951084 -351.04172)
			(xy 328.035685 -351.04575) (xy 328.11952 -351.057803) (xy 328.201829 -351.077771) (xy 328.281868 -351.105473)
			(xy 328.358911 -351.140657) (xy 328.432261 -351.183006) (xy 328.501253 -351.232135) (xy 328.565263 -351.2876)
			(xy 328.623711 -351.348898) (xy 328.676067 -351.415474) (xy 328.721857 -351.486726) (xy 328.760668 -351.562007)
			(xy 328.792147 -351.640637) (xy 328.816008 -351.721904) (xy 328.832037 -351.80507) (xy 328.840088 -351.889384)
			(xy 328.840592 -351.931732) (xy 328.840088 -351.97408) (xy 334.52206 -351.97408) (xy 334.52206 -351.889384)
			(xy 334.530111 -351.80507) (xy 334.54614 -351.721904) (xy 334.570001 -351.640637) (xy 334.60148 -351.562007)
			(xy 334.640291 -351.486726) (xy 334.686081 -351.415474) (xy 334.738437 -351.348898) (xy 334.796885 -351.2876)
			(xy 334.860895 -351.232135) (xy 334.929887 -351.183006) (xy 335.003237 -351.140657) (xy 335.08028 -351.105473)
			(xy 335.160319 -351.077771) (xy 335.242628 -351.057803) (xy 335.326463 -351.04575) (xy 335.411064 -351.04172)
			(xy 335.495665 -351.04575) (xy 335.5795 -351.057803) (xy 335.661809 -351.077771) (xy 335.741848 -351.105473)
			(xy 335.818891 -351.140657) (xy 335.892241 -351.183006) (xy 335.961233 -351.232135) (xy 336.025243 -351.2876)
			(xy 336.083691 -351.348898) (xy 336.136047 -351.415474) (xy 336.181837 -351.486726) (xy 336.220648 -351.562007)
			(xy 336.252127 -351.640637) (xy 336.275988 -351.721904) (xy 336.292017 -351.80507) (xy 336.300068 -351.889384)
			(xy 336.300572 -351.931732) (xy 336.300068 -351.97408) (xy 336.292017 -352.058394) (xy 336.275988 -352.14156)
			(xy 336.252127 -352.222827) (xy 336.220648 -352.301457) (xy 336.181837 -352.376738) (xy 336.136047 -352.44799)
			(xy 336.083691 -352.514566) (xy 336.025243 -352.575864) (xy 335.961233 -352.631329) (xy 335.892241 -352.680458)
			(xy 335.818891 -352.722807) (xy 335.741848 -352.757991) (xy 335.661809 -352.785693) (xy 335.5795 -352.805661)
			(xy 335.495665 -352.817714) (xy 335.411064 -352.821745) (xy 335.326463 -352.817714) (xy 335.242628 -352.805661)
			(xy 335.160319 -352.785693) (xy 335.08028 -352.757991) (xy 335.003237 -352.722807) (xy 334.929887 -352.680458)
			(xy 334.860895 -352.631329) (xy 334.796885 -352.575864) (xy 334.738437 -352.514566) (xy 334.686081 -352.44799)
			(xy 334.640291 -352.376738) (xy 334.60148 -352.301457) (xy 334.570001 -352.222827) (xy 334.54614 -352.14156)
			(xy 334.530111 -352.058394) (xy 334.52206 -351.97408) (xy 328.840088 -351.97408) (xy 328.832037 -352.058394)
			(xy 328.816008 -352.14156) (xy 328.792147 -352.222827) (xy 328.760668 -352.301457) (xy 328.721857 -352.376738)
			(xy 328.676067 -352.44799) (xy 328.623711 -352.514566) (xy 328.565263 -352.575864) (xy 328.501253 -352.631329)
			(xy 328.432261 -352.680458) (xy 328.358911 -352.722807) (xy 328.281868 -352.757991) (xy 328.201829 -352.785693)
			(xy 328.11952 -352.805661) (xy 328.035685 -352.817714) (xy 327.951084 -352.821745) (xy 327.866483 -352.817714)
			(xy 327.782648 -352.805661) (xy 327.700339 -352.785693) (xy 327.6203 -352.757991) (xy 327.543257 -352.722807)
			(xy 327.469907 -352.680458) (xy 327.400915 -352.631329) (xy 327.336905 -352.575864) (xy 327.278457 -352.514566)
			(xy 327.226101 -352.44799) (xy 327.180311 -352.376738) (xy 327.1415 -352.301457) (xy 327.110021 -352.222827)
			(xy 327.08616 -352.14156) (xy 327.070131 -352.058394) (xy 327.06208 -351.97408) (xy 318.6672 -351.97408)
			(xy 318.620648 -352.020632) (xy 318.602583 -352.037926) (xy 318.561031 -352.065742) (xy 318.514851 -352.084917)
			(xy 318.465817 -352.094714) (xy 318.440816 -352.095308) (xy 315.26988 -352.095308) (xy 315.259836 -352.095691)
			(xy 315.24124 -352.103271) (xy 315.233812 -352.11004) (xy 314.952126 -352.39198) (xy 314.94603 -352.398579)
			(xy 314.938504 -352.414877) (xy 314.937084 -352.432773) (xy 314.939172 -352.44151) (xy 314.966604 -352.540062)
			(xy 314.986162 -352.559112) (xy 314.999878 -352.562414) (xy 315.027166 -352.569626) (xy 315.079415 -352.590971)
			(xy 315.127949 -352.619782) (xy 315.171709 -352.655428) (xy 315.209739 -352.697133) (xy 315.24121 -352.743986)
			(xy 315.265434 -352.794964) (xy 315.281884 -352.848954) (xy 315.290199 -352.90478) (xy 315.290708 -352.933)
			(xy 315.290222 -352.960251) (xy 315.28837 -352.973132) (xy 339.357462 -352.973132) (xy 339.357989 -352.944427)
			(xy 339.366594 -352.887665) (xy 339.3836 -352.832831) (xy 339.408623 -352.781161) (xy 339.4411 -352.73382)
			(xy 339.480298 -352.691874) (xy 339.502496 -352.673666) (xy 339.511894 -352.6663) (xy 339.5218 -352.645726)
			(xy 339.5218 -352.542348) (xy 339.511894 -352.521774) (xy 339.502496 -352.514408) (xy 339.480306 -352.496237)
			(xy 339.441174 -352.454308) (xy 339.408755 -352.406996) (xy 339.383781 -352.355366) (xy 339.366812 -352.30058)
			(xy 339.358231 -352.243873) (xy 339.357716 -352.215196) (xy 339.358226 -352.186279) (xy 339.366956 -352.129107)
			(xy 339.384215 -352.073908) (xy 339.409608 -352.021946) (xy 339.442553 -351.974412) (xy 339.482296 -351.932396)
			(xy 339.504782 -351.914206) (xy 339.513551 -351.906651) (xy 339.523727 -351.885887) (xy 339.52434 -351.874328)
			(xy 339.52434 -351.794064) (xy 339.523754 -351.782498) (xy 339.513572 -351.761725) (xy 339.504782 -351.754186)
			(xy 339.482288 -351.736007) (xy 339.442554 -351.693985) (xy 339.409617 -351.646447) (xy 339.384231 -351.594483)
			(xy 339.366977 -351.539284) (xy 339.35825 -351.482113) (xy 339.357716 -351.453196) (xy 339.358152 -351.425942)
			(xy 339.36591 -351.371989) (xy 339.381268 -351.319689) (xy 339.403912 -351.270107) (xy 339.433383 -351.224253)
			(xy 339.46908 -351.18306) (xy 339.510275 -351.147366) (xy 339.556132 -351.117899) (xy 339.605715 -351.095258)
			(xy 339.658016 -351.079904) (xy 339.71197 -351.07215) (xy 339.739224 -351.071688) (xy 339.768141 -351.072228)
			(xy 339.825312 -351.080948) (xy 339.880512 -351.098199) (xy 339.932475 -351.123587) (xy 339.980009 -351.156528)
			(xy 340.022025 -351.196269) (xy 340.040214 -351.218754) (xy 340.047765 -351.227527) (xy 340.068532 -351.237702)
			(xy 340.080092 -351.238312) (xy 340.160356 -351.238312) (xy 340.17192 -351.237712) (xy 340.192691 -351.227538)
			(xy 340.200234 -351.218754) (xy 340.216987 -351.197971) (xy 340.255341 -351.160841) (xy 340.298495 -351.129419)
			(xy 340.345609 -351.10432) (xy 340.395761 -351.086034) (xy 340.447972 -351.074917) (xy 340.501224 -351.071187)
			(xy 340.554476 -351.074917) (xy 340.606687 -351.086034) (xy 340.656839 -351.10432) (xy 340.703953 -351.129419)
			(xy 340.747107 -351.160841) (xy 340.785461 -351.197971) (xy 340.802214 -351.218754) (xy 340.809765 -351.227527)
			(xy 340.830532 -351.237702) (xy 340.842092 -351.238312) (xy 340.922356 -351.238312) (xy 340.93392 -351.237712)
			(xy 340.954691 -351.227538) (xy 340.962234 -351.218754) (xy 340.978987 -351.197971) (xy 341.017341 -351.160841)
			(xy 341.060495 -351.129419) (xy 341.107609 -351.10432) (xy 341.157761 -351.086034) (xy 341.209972 -351.074917)
			(xy 341.263224 -351.071187) (xy 341.316476 -351.074917) (xy 341.368687 -351.086034) (xy 341.418839 -351.10432)
			(xy 341.465953 -351.129419) (xy 341.509107 -351.160841) (xy 341.547461 -351.197971) (xy 341.564214 -351.218754)
			(xy 341.571765 -351.227527) (xy 341.592532 -351.237702) (xy 341.604092 -351.238312) (xy 341.684356 -351.238312)
			(xy 341.69592 -351.237712) (xy 341.716691 -351.227538) (xy 341.724234 -351.218754) (xy 341.740987 -351.197971)
			(xy 341.779341 -351.160841) (xy 341.822495 -351.129419) (xy 341.869609 -351.10432) (xy 341.919761 -351.086034)
			(xy 341.971972 -351.074917) (xy 342.025224 -351.071187) (xy 342.078476 -351.074917) (xy 342.130687 -351.086034)
			(xy 342.180839 -351.10432) (xy 342.227953 -351.129419) (xy 342.271107 -351.160841) (xy 342.309461 -351.197971)
			(xy 342.326214 -351.218754) (xy 342.333765 -351.227527) (xy 342.354532 -351.237702) (xy 342.366092 -351.238312)
			(xy 342.446356 -351.238312) (xy 342.45792 -351.237712) (xy 342.478691 -351.227538) (xy 342.486234 -351.218754)
			(xy 342.504394 -351.196245) (xy 342.546422 -351.156513) (xy 342.593963 -351.123579) (xy 342.645931 -351.098195)
			(xy 342.701133 -351.080944) (xy 342.758306 -351.07222) (xy 342.787224 -351.071688) (xy 342.813553 -351.072133)
			(xy 342.865711 -351.07936) (xy 342.916378 -351.093701) (xy 342.964587 -351.114883) (xy 343.009419 -351.142502)
			(xy 343.050021 -351.176032) (xy 343.068148 -351.195132) (xy 343.075006 -351.202752) (xy 343.09304 -351.211134)
			(xy 343.184734 -351.215452) (xy 343.203276 -351.208848) (xy 343.210896 -351.20199) (xy 343.231996 -351.183769)
			(xy 343.278502 -351.153026) (xy 343.328986 -351.129378) (xy 343.382374 -351.113327) (xy 343.43753 -351.105215)
			(xy 343.465404 -351.104708) (xy 343.492658 -351.105152) (xy 343.54661 -351.11291) (xy 343.598909 -351.128267)
			(xy 343.648491 -351.150911) (xy 343.694344 -351.180381) (xy 343.735537 -351.216077) (xy 343.771231 -351.257272)
			(xy 343.800699 -351.303127) (xy 343.82334 -351.352709) (xy 343.838695 -351.405009) (xy 343.84645 -351.458962)
			(xy 343.846912 -351.486216) (xy 343.846367 -351.515132) (xy 343.837648 -351.572304) (xy 343.820398 -351.627503)
			(xy 343.795011 -351.679466) (xy 343.762071 -351.727) (xy 343.722331 -351.769016) (xy 343.699846 -351.787206)
			(xy 343.691077 -351.79476) (xy 343.680899 -351.815525) (xy 343.680288 -351.827084) (xy 343.680288 -351.907348)
			(xy 343.680892 -351.918911) (xy 343.691063 -351.939683) (xy 343.699846 -351.947226) (xy 343.722352 -351.965391)
			(xy 343.762083 -352.007417) (xy 343.795018 -352.054958) (xy 343.820402 -352.106924) (xy 343.837654 -352.162126)
			(xy 343.846379 -352.219299) (xy 343.846912 -352.248216) (xy 343.846392 -352.276921) (xy 343.837781 -352.333682)
			(xy 343.820772 -352.388515) (xy 343.795747 -352.440184) (xy 343.763271 -352.487526) (xy 343.724074 -352.529473)
			(xy 343.701878 -352.547682) (xy 343.69248 -352.555048) (xy 343.682574 -352.575622) (xy 343.682574 -352.679)
			(xy 343.69248 -352.699574) (xy 343.701878 -352.70694) (xy 343.724038 -352.725146) (xy 343.763173 -352.767067)
			(xy 343.795596 -352.814372) (xy 343.820576 -352.865995) (xy 343.837551 -352.920775) (xy 343.846139 -352.977477)
			(xy 343.846658 -353.006152) (xy 343.846172 -353.033403) (xy 343.838416 -353.087351) (xy 343.823061 -353.139646)
			(xy 343.800419 -353.189223) (xy 343.770953 -353.235073) (xy 343.735262 -353.276264) (xy 343.694071 -353.311955)
			(xy 343.648221 -353.341421) (xy 343.598644 -353.364063) (xy 343.546349 -353.379418) (xy 343.492401 -353.387174)
			(xy 343.437899 -353.387174) (xy 343.383951 -353.379418) (xy 343.331656 -353.364063) (xy 343.282079 -353.341421)
			(xy 343.236229 -353.311955) (xy 343.195038 -353.276264) (xy 343.159347 -353.235073) (xy 343.129881 -353.189223)
			(xy 343.107239 -353.139646) (xy 343.091884 -353.087351) (xy 343.084128 -353.033403) (xy 343.083642 -353.006152)
			(xy 343.08419 -352.977448) (xy 343.092792 -352.920687) (xy 343.109794 -352.865854) (xy 343.134813 -352.814184)
			(xy 343.167286 -352.766842) (xy 343.20648 -352.724895) (xy 343.228676 -352.706686) (xy 343.238074 -352.69932)
			(xy 343.24798 -352.678746) (xy 343.24798 -352.575368) (xy 343.238074 -352.554794) (xy 343.228676 -352.547428)
			(xy 343.216925 -352.537922) (xy 343.194803 -352.517321) (xy 343.18448 -352.50628) (xy 343.177622 -352.49866)
			(xy 343.159588 -352.490278) (xy 343.067894 -352.48596) (xy 343.049352 -352.492564) (xy 343.041732 -352.499422)
			(xy 343.020373 -352.517836) (xy 342.973249 -352.548808) (xy 342.92208 -352.572511) (xy 342.895174 -352.580956)
			(xy 342.882474 -352.584766) (xy 342.864186 -352.603562) (xy 342.834722 -352.713036) (xy 342.841072 -352.738436)
			(xy 342.850216 -352.748342) (xy 342.869675 -352.769691) (xy 342.902554 -352.817185) (xy 342.927894 -352.869094)
			(xy 342.945115 -352.924231) (xy 342.953825 -352.981334) (xy 342.954356 -353.010216) (xy 342.953837 -353.037465)
			(xy 342.94608 -353.09141) (xy 342.930725 -353.143701) (xy 342.908086 -353.193275) (xy 342.878622 -353.239123)
			(xy 342.842934 -353.280312) (xy 342.801748 -353.316003) (xy 342.755903 -353.34547) (xy 342.706331 -353.368114)
			(xy 342.654041 -353.383473) (xy 342.600097 -353.391235) (xy 342.572848 -353.391724) (xy 342.545478 -353.391248)
			(xy 342.491298 -353.383436) (xy 342.438795 -353.36795) (xy 342.389048 -353.34511) (xy 342.343081 -353.315386)
			(xy 342.32215 -353.297744) (xy 342.315038 -353.291648) (xy 342.29802 -353.285298) (xy 342.212676 -353.285298)
			(xy 342.195658 -353.291648) (xy 342.188546 -353.297744) (xy 342.167613 -353.315385) (xy 342.121645 -353.345109)
			(xy 342.071899 -353.367955) (xy 342.019397 -353.383451) (xy 341.965219 -353.39128) (xy 341.910477 -353.39128)
			(xy 341.856299 -353.383451) (xy 341.803797 -353.367955) (xy 341.754051 -353.345109) (xy 341.708083 -353.315385)
			(xy 341.68715 -353.297744) (xy 341.680038 -353.291648) (xy 341.66302 -353.285298) (xy 341.577676 -353.285298)
			(xy 341.560658 -353.291648) (xy 341.553546 -353.297744) (xy 341.532613 -353.315385) (xy 341.486645 -353.345109)
			(xy 341.436899 -353.367955) (xy 341.384397 -353.383451) (xy 341.330219 -353.39128) (xy 341.275477 -353.39128)
			(xy 341.221299 -353.383451) (xy 341.168797 -353.367955) (xy 341.119051 -353.345109) (xy 341.073083 -353.315385)
			(xy 341.05215 -353.297744) (xy 341.045038 -353.291648) (xy 341.02802 -353.285298) (xy 340.942676 -353.285298)
			(xy 340.925658 -353.291648) (xy 340.918546 -353.297744) (xy 340.897613 -353.315382) (xy 340.85164 -353.345093)
			(xy 340.801893 -353.367928) (xy 340.749392 -353.38342) (xy 340.695217 -353.391249) (xy 340.667848 -353.391724)
			(xy 340.640597 -353.3912) (xy 340.586649 -353.38345) (xy 340.534353 -353.368101) (xy 340.484774 -353.345465)
			(xy 340.438922 -353.316004) (xy 340.397729 -353.280316) (xy 340.362035 -353.239129) (xy 340.332566 -353.193282)
			(xy 340.309921 -353.143707) (xy 340.294564 -353.091413) (xy 340.286804 -353.037467) (xy 340.28634 -353.010216)
			(xy 340.286927 -352.979985) (xy 340.296473 -352.920281) (xy 340.315313 -352.86283) (xy 340.342975 -352.809067)
			(xy 340.378769 -352.760338) (xy 340.399878 -352.73869) (xy 340.409022 -352.729546) (xy 340.416642 -352.704908)
			(xy 340.393782 -352.595688) (xy 340.377018 -352.57613) (xy 340.364826 -352.571558) (xy 340.340772 -352.561862)
			(xy 340.295307 -352.536913) (xy 340.253633 -352.506045) (xy 340.216515 -352.469825) (xy 340.200234 -352.449638)
			(xy 340.192664 -352.440885) (xy 340.171911 -352.430699) (xy 340.160356 -352.43008) (xy 340.080092 -352.43008)
			(xy 340.068525 -352.430653) (xy 340.047754 -352.440847) (xy 340.040214 -352.449638) (xy 340.025838 -352.467546)
			(xy 339.993492 -352.500146) (xy 339.975698 -352.514662) (xy 339.9663 -352.522028) (xy 339.956394 -352.542602)
			(xy 339.956394 -352.64598) (xy 339.9663 -352.666554) (xy 339.975698 -352.67392) (xy 339.997852 -352.692132)
			(xy 340.036987 -352.734053) (xy 340.06941 -352.781356) (xy 340.094391 -352.832978) (xy 340.111367 -352.887756)
			(xy 340.119957 -352.944458) (xy 340.120478 -352.973132) (xy 340.119992 -353.000383) (xy 340.112236 -353.054331)
			(xy 340.096881 -353.106626) (xy 340.074239 -353.156203) (xy 340.044773 -353.202053) (xy 340.009082 -353.243244)
			(xy 339.967891 -353.278935) (xy 339.922041 -353.308401) (xy 339.872464 -353.331043) (xy 339.820169 -353.346398)
			(xy 339.766221 -353.354154) (xy 339.711719 -353.354154) (xy 339.657771 -353.346398) (xy 339.605476 -353.331043)
			(xy 339.555899 -353.308401) (xy 339.510049 -353.278935) (xy 339.468858 -353.243244) (xy 339.433167 -353.202053)
			(xy 339.403701 -353.156203) (xy 339.381059 -353.106626) (xy 339.365704 -353.054331) (xy 339.357948 -353.000383)
			(xy 339.357462 -352.973132) (xy 315.28837 -352.973132) (xy 315.282466 -353.014199) (xy 315.267111 -353.066494)
			(xy 315.244469 -353.116071) (xy 315.215003 -353.161921) (xy 315.179312 -353.203112) (xy 315.138121 -353.238803)
			(xy 315.092271 -353.268269) (xy 315.042694 -353.290911) (xy 314.990399 -353.306266) (xy 314.936451 -353.314022)
			(xy 314.9092 -353.314508) (xy 314.882179 -353.313979) (xy 314.828678 -353.306366) (xy 314.776786 -353.291277)
			(xy 314.727543 -353.269016) (xy 314.681935 -353.240027) (xy 314.640876 -353.204892) (xy 314.605186 -353.164313)
			(xy 314.575581 -353.119103) (xy 314.552653 -353.070167) (xy 314.536861 -353.018485) (xy 314.528522 -352.965092)
			(xy 314.527692 -352.93808) (xy 314.527692 -352.928174) (xy 314.519818 -352.909886) (xy 314.51296 -352.903028)
			(xy 314.505594 -352.896188) (xy 314.487061 -352.888446) (xy 314.466977 -352.888446) (xy 314.448444 -352.896188)
			(xy 314.441078 -352.903028) (xy 314.38342 -352.960432) (xy 314.365299 -352.97766) (xy 314.323764 -353.005479)
			(xy 314.277601 -353.02466) (xy 314.228582 -353.034467) (xy 314.203588 -353.035108) (xy 314.154312 -353.035108)
			(xy 314.144648 -353.035454) (xy 314.126662 -353.042526) (xy 314.112567 -353.055748) (xy 314.108084 -353.064318)
			(xy 314.096146 -353.09048) (xy 314.092651 -353.098776) (xy 314.09116 -353.116705) (xy 314.09599 -353.134035)
			(xy 314.100972 -353.141534) (xy 314.117961 -353.166057) (xy 314.14491 -353.219278) (xy 314.16325 -353.276044)
			(xy 314.172532 -353.334972) (xy 314.173108 -353.3648) (xy 314.172622 -353.392051) (xy 314.164866 -353.445999)
			(xy 314.149511 -353.498294) (xy 314.126869 -353.547871) (xy 314.097403 -353.593721) (xy 314.061712 -353.634912)
			(xy 314.020521 -353.670603) (xy 313.974671 -353.700069) (xy 313.925094 -353.722711) (xy 313.872799 -353.738066)
			(xy 313.818851 -353.745822) (xy 313.764349 -353.745822) (xy 313.710401 -353.738066) (xy 313.658106 -353.722711)
			(xy 313.608529 -353.700069) (xy 313.562679 -353.670603) (xy 313.521488 -353.634912) (xy 313.485797 -353.593721)
			(xy 313.456331 -353.547871) (xy 313.433689 -353.498294) (xy 313.418334 -353.445999) (xy 313.410578 -353.392051)
			(xy 313.410092 -353.3648) (xy 313.410718 -353.33348) (xy 313.420923 -353.271678) (xy 313.441078 -353.212369)
			(xy 313.455304 -353.18446) (xy 313.461654 -353.172522) (xy 313.461146 -353.146106) (xy 313.40933 -353.059746)
			(xy 313.404542 -353.052437) (xy 313.391066 -353.041337) (xy 313.374626 -353.035457) (xy 313.365896 -353.035108)
			(xy 312.526426 -353.035108) (xy 312.517405 -353.035434) (xy 312.500469 -353.041653) (xy 312.48672 -353.053335)
			(xy 312.481976 -353.061016) (xy 312.431938 -353.150678) (xy 312.4327 -353.17811) (xy 312.439812 -353.189794)
			(xy 312.453288 -353.212485) (xy 312.474567 -353.260778) (xy 312.488983 -353.311544) (xy 312.496261 -353.363813)
			(xy 312.496708 -353.3902) (xy 312.496222 -353.417451) (xy 312.488466 -353.471399) (xy 312.473111 -353.523694)
			(xy 312.450469 -353.573271) (xy 312.421003 -353.619121) (xy 312.385312 -353.660312) (xy 312.344121 -353.696003)
			(xy 312.298271 -353.725469) (xy 312.248694 -353.748111) (xy 312.196399 -353.763466) (xy 312.142451 -353.771222)
			(xy 312.087949 -353.771222) (xy 312.034001 -353.763466) (xy 311.981706 -353.748111) (xy 311.932129 -353.725469)
			(xy 311.886279 -353.696003) (xy 311.845088 -353.660312) (xy 311.809397 -353.619121) (xy 311.779931 -353.573271)
			(xy 311.757289 -353.523694) (xy 311.741934 -353.471399) (xy 311.734178 -353.417451) (xy 311.733692 -353.3902)
			(xy 311.734139 -353.363813) (xy 311.741423 -353.311545) (xy 311.755837 -353.260778) (xy 311.777107 -353.212481)
			(xy 311.790588 -353.189794) (xy 311.7977 -353.17811) (xy 311.798462 -353.150678) (xy 311.748424 -353.061016)
			(xy 311.743694 -353.053319) (xy 311.72996 -353.041606) (xy 311.713002 -353.035418) (xy 311.703974 -353.035108)
			(xy 309.93588 -353.035108) (xy 309.925836 -353.035491) (xy 309.90724 -353.043071) (xy 309.899812 -353.04984)
			(xy 309.891938 -353.057714) (xy 309.886175 -353.063902) (xy 309.878768 -353.079092) (xy 309.876743 -353.09587)
			(xy 309.878222 -353.104196) (xy 309.898796 -353.200462) (xy 309.915306 -353.219766) (xy 309.927498 -353.224338)
			(xy 309.954149 -353.235142) (xy 310.004153 -353.263541) (xy 310.049331 -353.29912) (xy 310.08866 -353.341073)
			(xy 310.121251 -353.388451) (xy 310.146367 -353.440182) (xy 310.163438 -353.495095) (xy 310.172079 -353.551947)
			(xy 310.172608 -353.5807) (xy 310.172122 -353.607951) (xy 310.164366 -353.661899) (xy 310.149011 -353.714194)
			(xy 310.126369 -353.763771) (xy 310.096903 -353.809621) (xy 310.061212 -353.850812) (xy 310.020021 -353.886503)
			(xy 309.974171 -353.915969) (xy 309.924594 -353.938611) (xy 309.889212 -353.949) (xy 310.564782 -353.949)
			(xy 310.568853 -353.893378) (xy 310.580979 -353.838941) (xy 310.600902 -353.78685) (xy 310.628198 -353.738215)
			(xy 310.662284 -353.694072) (xy 310.702433 -353.655363) (xy 310.747791 -353.622912) (xy 310.797391 -353.597411)
			(xy 310.850175 -353.579404) (xy 310.905018 -353.569274) (xy 310.960752 -353.567237) (xy 311.016189 -353.573337)
			(xy 311.070146 -353.587443) (xy 311.121475 -353.609255) (xy 311.169081 -353.638309) (xy 311.211949 -353.673984)
			(xy 311.249166 -353.715521) (xy 311.279939 -353.762034) (xy 311.303611 -353.812531) (xy 311.319679 -353.865938)
			(xy 311.327799 -353.921114) (xy 311.328308 -353.949) (xy 311.327799 -353.976886) (xy 311.319679 -354.032062)
			(xy 311.303611 -354.085469) (xy 311.279939 -354.135966) (xy 311.249166 -354.182479) (xy 311.211949 -354.224016)
			(xy 311.169081 -354.259691) (xy 311.121475 -354.288745) (xy 311.070146 -354.310557) (xy 311.016189 -354.324663)
			(xy 310.960752 -354.330763) (xy 310.905018 -354.328726) (xy 310.850175 -354.318596) (xy 310.797391 -354.300589)
			(xy 310.747791 -354.275088) (xy 310.702433 -354.242637) (xy 310.662284 -354.203928) (xy 310.628198 -354.159785)
			(xy 310.600902 -354.11115) (xy 310.580979 -354.059059) (xy 310.568853 -354.004622) (xy 310.564782 -353.949)
			(xy 309.889212 -353.949) (xy 309.872299 -353.953966) (xy 309.818351 -353.961722) (xy 309.7911 -353.962208)
			(xy 309.762344 -353.961643) (xy 309.705481 -353.953037) (xy 309.650555 -353.93599) (xy 309.598812 -353.910889)
			(xy 309.551424 -353.878303) (xy 309.509466 -353.83897) (xy 309.473891 -353.793783) (xy 309.445504 -353.743767)
			(xy 309.434738 -353.717098) (xy 309.430166 -353.704906) (xy 309.410862 -353.688396) (xy 309.314596 -353.667822)
			(xy 309.302013 -353.665881) (xy 309.277624 -353.673074) (xy 309.268114 -353.681538) (xy 308.467252 -354.4824)
			(xy 312.977782 -354.4824) (xy 312.981853 -354.426778) (xy 312.993979 -354.372341) (xy 313.013902 -354.32025)
			(xy 313.041198 -354.271615) (xy 313.075284 -354.227472) (xy 313.115433 -354.188763) (xy 313.160791 -354.156312)
			(xy 313.210391 -354.130811) (xy 313.263175 -354.112804) (xy 313.318018 -354.102674) (xy 313.373752 -354.100637)
			(xy 313.429189 -354.106737) (xy 313.483146 -354.120843) (xy 313.534475 -354.142655) (xy 313.582081 -354.171709)
			(xy 313.624949 -354.207384) (xy 313.662166 -354.248921) (xy 313.692939 -354.295434) (xy 313.716611 -354.345931)
			(xy 313.732679 -354.399338) (xy 313.740799 -354.454514) (xy 313.740844 -354.457) (xy 314.120782 -354.457)
			(xy 314.124853 -354.401378) (xy 314.136979 -354.346941) (xy 314.156902 -354.29485) (xy 314.184198 -354.246215)
			(xy 314.218284 -354.202072) (xy 314.258433 -354.163363) (xy 314.303791 -354.130912) (xy 314.353391 -354.105411)
			(xy 314.406175 -354.087404) (xy 314.461018 -354.077274) (xy 314.516752 -354.075237) (xy 314.572189 -354.081337)
			(xy 314.626146 -354.095443) (xy 314.677475 -354.117255) (xy 314.725081 -354.146309) (xy 314.767949 -354.181984)
			(xy 314.805166 -354.223521) (xy 314.835939 -354.270034) (xy 314.859611 -354.320531) (xy 314.875679 -354.373938)
			(xy 314.883799 -354.429114) (xy 314.884308 -354.457) (xy 314.883799 -354.484886) (xy 314.875679 -354.540062)
			(xy 314.859611 -354.593469) (xy 314.835939 -354.643966) (xy 314.805166 -354.690479) (xy 314.767949 -354.732016)
			(xy 314.725081 -354.767691) (xy 314.677475 -354.796745) (xy 314.626146 -354.818557) (xy 314.572189 -354.832663)
			(xy 314.516752 -354.838763) (xy 314.461018 -354.836726) (xy 314.406175 -354.826596) (xy 314.353391 -354.808589)
			(xy 314.303791 -354.783088) (xy 314.258433 -354.750637) (xy 314.218284 -354.711928) (xy 314.184198 -354.667785)
			(xy 314.156902 -354.61915) (xy 314.136979 -354.567059) (xy 314.124853 -354.512622) (xy 314.120782 -354.457)
			(xy 313.740844 -354.457) (xy 313.741308 -354.4824) (xy 313.740799 -354.510286) (xy 313.732679 -354.565462)
			(xy 313.716611 -354.618869) (xy 313.692939 -354.669366) (xy 313.662166 -354.715879) (xy 313.624949 -354.757416)
			(xy 313.582081 -354.793091) (xy 313.534475 -354.822145) (xy 313.483146 -354.843957) (xy 313.429189 -354.858063)
			(xy 313.373752 -354.864163) (xy 313.318018 -354.862126) (xy 313.263175 -354.851996) (xy 313.210391 -354.833989)
			(xy 313.160791 -354.808488) (xy 313.115433 -354.776037) (xy 313.075284 -354.737328) (xy 313.041198 -354.693185)
			(xy 313.013902 -354.64455) (xy 312.993979 -354.592459) (xy 312.981853 -354.538022) (xy 312.977782 -354.4824)
			(xy 308.467252 -354.4824) (xy 308.38902 -354.560632) (xy 308.370899 -354.57786) (xy 308.329364 -354.605679)
			(xy 308.283201 -354.62486) (xy 308.234182 -354.634667) (xy 308.209188 -354.635308) (xy 307.91912 -354.635308)
			(xy 307.909137 -354.635698) (xy 307.890676 -354.643295) (xy 307.883306 -354.65004) (xy 307.861703 -354.67094)
			(xy 307.813137 -354.706353) (xy 307.759616 -354.733707) (xy 307.702466 -354.752326) (xy 307.643103 -354.761748)
			(xy 307.61305 -354.762308) (xy 307.585798 -354.761798) (xy 307.531849 -354.754048) (xy 307.479552 -354.738698)
			(xy 307.429972 -354.716062) (xy 307.384119 -354.686599) (xy 307.342926 -354.65091) (xy 307.307231 -354.609721)
			(xy 307.277762 -354.563872) (xy 307.255119 -354.514295) (xy 307.239763 -354.462) (xy 307.232005 -354.408052)
			(xy 307.231542 -354.3808) (xy 307.232092 -354.351613) (xy 307.240992 -354.29392) (xy 307.258568 -354.238254)
			(xy 307.284413 -354.185911) (xy 307.317922 -354.138112) (xy 307.358316 -354.095969) (xy 307.381148 -354.077778)
			(xy 307.391054 -354.070412) (xy 307.401468 -354.048568) (xy 307.398674 -353.941888) (xy 307.387244 -353.920552)
			(xy 307.377084 -353.913694) (xy 307.355646 -353.898378) (xy 307.316848 -353.862732) (xy 307.283322 -353.822087)
			(xy 307.255704 -353.777219) (xy 307.234519 -353.728978) (xy 307.220171 -353.678281) (xy 307.212932 -353.626094)
			(xy 307.212492 -353.59975) (xy 306.629308 -353.59975) (xy 306.629308 -354.863908) (xy 306.629697 -354.873951)
			(xy 306.637272 -354.892547) (xy 306.64404 -354.899976) (xy 307.064664 -355.3206) (xy 309.370982 -355.3206)
			(xy 309.375053 -355.264978) (xy 309.387179 -355.210541) (xy 309.407102 -355.15845) (xy 309.434398 -355.109815)
			(xy 309.468484 -355.065672) (xy 309.508633 -355.026963) (xy 309.553991 -354.994512) (xy 309.603591 -354.969011)
			(xy 309.656375 -354.951004) (xy 309.711218 -354.940874) (xy 309.766952 -354.938837) (xy 309.822389 -354.944937)
			(xy 309.876346 -354.959043) (xy 309.927675 -354.980855) (xy 309.975281 -355.009909) (xy 310.018149 -355.045584)
			(xy 310.055366 -355.087121) (xy 310.086139 -355.133634) (xy 310.109811 -355.184131) (xy 310.125879 -355.237538)
			(xy 310.133999 -355.292714) (xy 310.134508 -355.3206) (xy 310.133999 -355.348486) (xy 310.125879 -355.403662)
			(xy 310.109811 -355.457069) (xy 310.086139 -355.507566) (xy 310.055366 -355.554079) (xy 310.018149 -355.595616)
			(xy 309.975281 -355.631291) (xy 309.927675 -355.660345) (xy 309.876346 -355.682157) (xy 309.822389 -355.696263)
			(xy 309.766952 -355.702363) (xy 309.711218 -355.700326) (xy 309.656375 -355.690196) (xy 309.603591 -355.672189)
			(xy 309.553991 -355.646688) (xy 309.508633 -355.614237) (xy 309.468484 -355.575528) (xy 309.434398 -355.531385)
			(xy 309.407102 -355.48275) (xy 309.387179 -355.430659) (xy 309.375053 -355.376222) (xy 309.370982 -355.3206)
			(xy 307.064664 -355.3206) (xy 308.903624 -357.15956) (xy 308.911104 -357.166255) (xy 308.929664 -357.173844)
			(xy 308.939692 -357.174292) (xy 311.30494 -357.174292) (xy 311.314815 -357.17384) (xy 311.333119 -357.166427)
			(xy 311.347286 -357.152668) (xy 311.351676 -357.143812) (xy 311.394856 -357.044244) (xy 311.389776 -357.014526)
			(xy 311.379362 -357.00335) (xy 311.360177 -356.982029) (xy 311.327707 -356.934752) (xy 311.302681 -356.883147)
			(xy 311.285661 -356.828377) (xy 311.277031 -356.771676) (xy 311.276492 -356.743) (xy 311.276951 -356.715741)
			(xy 311.284719 -356.66178) (xy 311.300083 -356.609473) (xy 311.32273 -356.559882) (xy 311.352201 -356.514016)
			(xy 311.387896 -356.472809) (xy 311.429088 -356.437097) (xy 311.451752 -356.421944) (xy 311.458716 -356.417088)
			(xy 311.469237 -356.40378) (xy 311.474803 -356.387754) (xy 311.47512 -356.379272) (xy 311.47512 -356.293928)
			(xy 311.474753 -356.285453) (xy 311.469183 -356.269441) (xy 311.458706 -356.256113) (xy 311.451752 -356.251256)
			(xy 311.429108 -356.236075) (xy 311.387909 -356.200374) (xy 311.352211 -356.159174) (xy 311.322739 -356.113312)
			(xy 311.300094 -356.063724) (xy 311.284736 -356.011417) (xy 311.276978 -355.957457) (xy 311.276492 -355.9302)
			(xy 311.276978 -355.902949) (xy 311.284734 -355.849001) (xy 311.300089 -355.796706) (xy 311.322731 -355.747129)
			(xy 311.352197 -355.701279) (xy 311.387888 -355.660088) (xy 311.429079 -355.624397) (xy 311.474929 -355.594931)
			(xy 311.524506 -355.572289) (xy 311.576801 -355.556934) (xy 311.630749 -355.549178) (xy 311.685251 -355.549178)
			(xy 311.739199 -355.556934) (xy 311.791494 -355.572289) (xy 311.841071 -355.594931) (xy 311.886921 -355.624397)
			(xy 311.928112 -355.660088) (xy 311.963803 -355.701279) (xy 311.993269 -355.747129) (xy 312.015911 -355.796706)
			(xy 312.025276 -355.8286) (xy 314.196982 -355.8286) (xy 314.201053 -355.772978) (xy 314.213179 -355.718541)
			(xy 314.233102 -355.66645) (xy 314.260398 -355.617815) (xy 314.294484 -355.573672) (xy 314.334633 -355.534963)
			(xy 314.379991 -355.502512) (xy 314.429591 -355.477011) (xy 314.482375 -355.459004) (xy 314.537218 -355.448874)
			(xy 314.592952 -355.446837) (xy 314.648389 -355.452937) (xy 314.702346 -355.467043) (xy 314.753675 -355.488855)
			(xy 314.801281 -355.517909) (xy 314.844149 -355.553584) (xy 314.881366 -355.595121) (xy 314.912139 -355.641634)
			(xy 314.935811 -355.692131) (xy 314.951879 -355.745538) (xy 314.959999 -355.800714) (xy 314.960508 -355.8286)
			(xy 314.959999 -355.856486) (xy 314.951879 -355.911662) (xy 314.935811 -355.965069) (xy 314.912139 -356.015566)
			(xy 314.881366 -356.062079) (xy 314.844149 -356.103616) (xy 314.801281 -356.139291) (xy 314.753675 -356.168345)
			(xy 314.702346 -356.190157) (xy 314.648389 -356.204263) (xy 314.592952 -356.210363) (xy 314.537218 -356.208326)
			(xy 314.482375 -356.198196) (xy 314.429591 -356.180189) (xy 314.379991 -356.154688) (xy 314.334633 -356.122237)
			(xy 314.294484 -356.083528) (xy 314.260398 -356.039385) (xy 314.233102 -355.99075) (xy 314.213179 -355.938659)
			(xy 314.201053 -355.884222) (xy 314.196982 -355.8286) (xy 312.025276 -355.8286) (xy 312.031266 -355.849001)
			(xy 312.039022 -355.902949) (xy 312.039508 -355.9302) (xy 312.039049 -355.957459) (xy 312.031281 -356.01142)
			(xy 312.015917 -356.063727) (xy 311.99327 -356.113318) (xy 311.963799 -356.159184) (xy 311.928104 -356.200391)
			(xy 311.886912 -356.236103) (xy 311.864248 -356.251256) (xy 311.857284 -356.256112) (xy 311.846763 -356.26942)
			(xy 311.841197 -356.285446) (xy 311.84088 -356.293928) (xy 311.84088 -356.379272) (xy 311.841247 -356.387747)
			(xy 311.846817 -356.403759) (xy 311.857294 -356.417087) (xy 311.864248 -356.421944) (xy 311.886892 -356.437125)
			(xy 311.928091 -356.472826) (xy 311.963789 -356.514026) (xy 311.993261 -356.559888) (xy 312.015906 -356.609476)
			(xy 312.031264 -356.661783) (xy 312.039022 -356.715743) (xy 312.039055 -356.7176) (xy 313.282582 -356.7176)
			(xy 313.286653 -356.661978) (xy 313.298779 -356.607541) (xy 313.318702 -356.55545) (xy 313.345998 -356.506815)
			(xy 313.380084 -356.462672) (xy 313.420233 -356.423963) (xy 313.465591 -356.391512) (xy 313.515191 -356.366011)
			(xy 313.567975 -356.348004) (xy 313.622818 -356.337874) (xy 313.678552 -356.335837) (xy 313.733989 -356.341937)
			(xy 313.787946 -356.356043) (xy 313.839275 -356.377855) (xy 313.886881 -356.406909) (xy 313.929749 -356.442584)
			(xy 313.966966 -356.484121) (xy 313.997739 -356.530634) (xy 314.021411 -356.581131) (xy 314.037479 -356.634538)
			(xy 314.045599 -356.689714) (xy 314.046108 -356.7176) (xy 314.045599 -356.745486) (xy 314.037479 -356.800662)
			(xy 314.021411 -356.854069) (xy 313.997739 -356.904566) (xy 313.966966 -356.951079) (xy 313.929749 -356.992616)
			(xy 313.886881 -357.028291) (xy 313.839275 -357.057345) (xy 313.787946 -357.079157) (xy 313.733989 -357.093263)
			(xy 313.678552 -357.099363) (xy 313.622818 -357.097326) (xy 313.567975 -357.087196) (xy 313.515191 -357.069189)
			(xy 313.465591 -357.043688) (xy 313.420233 -357.011237) (xy 313.380084 -356.972528) (xy 313.345998 -356.928385)
			(xy 313.318702 -356.87975) (xy 313.298779 -356.827659) (xy 313.286653 -356.773222) (xy 313.282582 -356.7176)
			(xy 312.039055 -356.7176) (xy 312.039508 -356.743) (xy 312.038947 -356.771677) (xy 312.030331 -356.82838)
			(xy 312.013323 -356.883155) (xy 311.988308 -356.934766) (xy 311.955847 -356.982051) (xy 311.936638 -357.00335)
			(xy 311.926224 -357.014526) (xy 311.921144 -357.044244) (xy 311.964324 -357.143812) (xy 311.96865 -357.152714)
			(xy 311.98282 -357.166511) (xy 312.001168 -357.173892) (xy 312.01106 -357.174292) (xy 313.063128 -357.174292)
			(xy 313.088126 -357.174891) (xy 313.137152 -357.184704) (xy 313.183323 -357.203888) (xy 313.224866 -357.231707)
			(xy 313.24296 -357.248968) (xy 315.547756 -359.553764) (xy 315.565028 -359.571846) (xy 315.592837 -359.613394)
			(xy 315.612007 -359.65957) (xy 315.621799 -359.708598) (xy 315.622432 -359.733596) (xy 315.622432 -360.489246)
			(xy 315.621776 -360.514241) (xy 315.61198 -360.563263) (xy 315.592812 -360.609434) (xy 315.565009 -360.650981)
			(xy 315.547756 -360.669078) (xy 315.021722 -361.195112) (xy 315.014356 -361.217464) (xy 315.01588 -361.229402)
			(xy 315.017442 -361.24198) (xy 315.019095 -361.267274) (xy 315.019182 -361.279948) (xy 315.018696 -361.307199)
			(xy 315.01094 -361.361147) (xy 314.995585 -361.413442) (xy 314.972943 -361.463019) (xy 314.943477 -361.508869)
			(xy 314.907786 -361.55006) (xy 314.866595 -361.585751) (xy 314.820745 -361.615217) (xy 314.771168 -361.637859)
			(xy 314.718873 -361.653214) (xy 314.664925 -361.66097) (xy 314.610423 -361.66097) (xy 314.556475 -361.653214)
			(xy 314.50418 -361.637859) (xy 314.454603 -361.615217) (xy 314.408753 -361.585751) (xy 314.367562 -361.55006)
			(xy 314.331871 -361.508869) (xy 314.302405 -361.463019) (xy 314.279763 -361.413442) (xy 314.264408 -361.361147)
			(xy 314.256652 -361.307199) (xy 314.256166 -361.279948) (xy 314.256668 -361.252832) (xy 314.264355 -361.199147)
			(xy 314.279567 -361.147091) (xy 314.301998 -361.097715) (xy 314.331195 -361.052012) (xy 314.36657 -361.010905)
			(xy 314.407409 -360.975221) (xy 314.452891 -360.945681) (xy 314.502097 -360.922879) (xy 314.554036 -360.907275)
			(xy 314.580778 -360.902758) (xy 314.588906 -360.901488) (xy 314.60313 -360.894376) (xy 314.680092 -360.817414)
			(xy 314.685902 -360.811092) (xy 314.693384 -360.795654) (xy 314.695361 -360.778612) (xy 314.693808 -360.77017)
			(xy 314.671456 -360.673142) (xy 314.654438 -360.653838) (xy 314.641738 -360.64952) (xy 314.617148 -360.640507)
			(xy 314.570525 -360.616649) (xy 314.527604 -360.586636) (xy 314.489192 -360.551034) (xy 314.456013 -360.510511)
			(xy 314.42869 -360.46583) (xy 314.407737 -360.417831) (xy 314.393548 -360.367416) (xy 314.38639 -360.315535)
			(xy 314.38596 -360.289348) (xy 314.386555 -360.259298) (xy 314.395984 -360.199941) (xy 314.4146 -360.142796)
			(xy 314.441944 -360.089275) (xy 314.477339 -360.040703) (xy 314.498228 -360.019092) (xy 314.504875 -360.011656)
			(xy 314.51247 -359.993238) (xy 314.51296 -359.983278) (xy 314.51296 -359.864152) (xy 314.5126 -359.854105)
			(xy 314.505005 -359.835509) (xy 314.498228 -359.828084) (xy 313.130184 -358.46004) (xy 313.122701 -358.453349)
			(xy 313.104143 -358.445758) (xy 313.094116 -358.445308) (xy 308.1528 -358.445308) (xy 308.127803 -358.444692)
			(xy 308.078778 -358.434885) (xy 308.032607 -358.415705) (xy 307.991062 -358.387891) (xy 307.972968 -358.370632)
			(xy 302.448976 -352.84664) (xy 302.441496 -352.839945) (xy 302.422936 -352.832356) (xy 302.412908 -352.831908)
			(xy 300.02734 -352.831908) (xy 300.002344 -352.831267) (xy 299.953321 -352.821467) (xy 299.907149 -352.802296)
			(xy 299.865604 -352.774488) (xy 299.847508 -352.757232) (xy 299.439584 -352.349562) (xy 299.432223 -352.342793)
			(xy 299.413761 -352.335146) (xy 299.393779 -352.335146) (xy 299.375317 -352.342793) (xy 299.367956 -352.349562)
			(xy 298.794932 -352.922332) (xy 298.776874 -352.939633) (xy 298.73532 -352.967448) (xy 298.689137 -352.986621)
			(xy 298.640102 -352.996416) (xy 298.6151 -352.997008) (xy 291.667184 -352.997008) (xy 291.642186 -352.996402)
			(xy 291.593161 -352.986591) (xy 291.54699 -352.967409) (xy 291.505446 -352.939592) (xy 291.487352 -352.922332)
			(xy 291.082984 -352.518218) (xy 291.075623 -352.511449) (xy 291.057161 -352.503802) (xy 291.037179 -352.503802)
			(xy 291.018717 -352.511449) (xy 291.011356 -352.518218) (xy 290.581588 -352.947732) (xy 290.563481 -352.964975)
			(xy 290.521941 -352.992791) (xy 290.475773 -353.011968) (xy 290.426752 -353.02177) (xy 290.401756 -353.022408)
			(xy 283.459936 -353.022408) (xy 283.43494 -353.021769) (xy 283.385916 -353.011969) (xy 283.339745 -352.992796)
			(xy 283.2982 -352.964988) (xy 283.280104 -352.947732) (xy 282.777184 -352.445066) (xy 282.769823 -352.438297)
			(xy 282.751361 -352.43065) (xy 282.731379 -352.43065) (xy 282.712917 -352.438297) (xy 282.705556 -352.445066)
			(xy 282.202636 -352.947732) (xy 282.184576 -352.965031) (xy 282.143023 -352.992847) (xy 282.096841 -353.01202)
			(xy 282.047806 -353.021816) (xy 282.022804 -353.022408) (xy 275.068538 -353.022408) (xy 275.043542 -353.021768)
			(xy 274.994518 -353.011968) (xy 274.948347 -352.992796) (xy 274.906802 -352.964988) (xy 274.888706 -352.947732)
			(xy 274.281138 -352.340164) (xy 274.26393 -352.322042) (xy 274.236187 -352.280486) (xy 274.217076 -352.23432)
			(xy 274.20733 -352.185315) (xy 274.206716 -352.160332) (xy 274.206716 -350.955864) (xy 274.206266 -350.945858)
			(xy 274.19854 -350.927394) (xy 274.19173 -350.92005) (xy 274.170845 -350.898433) (xy 274.135432 -350.84987)
			(xy 274.108075 -350.796352) (xy 274.089453 -350.739206) (xy 274.080025 -350.679846) (xy 274.079462 -350.649794)
			(xy 273.820534 -350.649794) (xy 273.814159 -350.6713) (xy 273.791137 -350.721193) (xy 273.761187 -350.767262)
			(xy 273.74342 -350.788224) (xy 273.737324 -350.795336) (xy 273.730974 -350.812354) (xy 273.730974 -350.898206)
			(xy 273.737324 -350.915224) (xy 273.74342 -350.922336) (xy 273.761185 -350.943297) (xy 273.791109 -350.98938)
			(xy 273.814121 -351.039274) (xy 273.829747 -351.091951) (xy 273.837663 -351.146324) (xy 273.838162 -351.173796)
			(xy 273.837676 -351.201047) (xy 273.82992 -351.254995) (xy 273.814565 -351.30729) (xy 273.791923 -351.356867)
			(xy 273.762457 -351.402717) (xy 273.726766 -351.443908) (xy 273.685575 -351.479599) (xy 273.639725 -351.509065)
			(xy 273.590148 -351.531707) (xy 273.537853 -351.547062) (xy 273.483905 -351.554818) (xy 273.429403 -351.554818)
			(xy 273.375455 -351.547062) (xy 273.32316 -351.531707) (xy 273.273583 -351.509065) (xy 273.227733 -351.479599)
			(xy 273.186542 -351.443908) (xy 273.150851 -351.402717) (xy 273.121385 -351.356867) (xy 273.098743 -351.30729)
			(xy 273.083388 -351.254995) (xy 273.075632 -351.201047) (xy 273.075146 -351.173796) (xy 266.425172 -351.173796)
			(xy 266.960604 -351.709228) (xy 266.968095 -351.715909) (xy 266.986647 -351.723507) (xy 266.996672 -351.72396)
			(xy 270.901668 -351.72396) (xy 270.926664 -351.724605) (xy 270.975687 -351.734405) (xy 271.021857 -351.753575)
			(xy 271.063404 -351.781381) (xy 271.0815 -351.798636) (xy 273.993864 -354.711) (xy 302.969166 -354.711)
			(xy 302.973237 -354.655378) (xy 302.985363 -354.600941) (xy 303.005286 -354.54885) (xy 303.032582 -354.500215)
			(xy 303.066668 -354.456072) (xy 303.106817 -354.417363) (xy 303.152175 -354.384912) (xy 303.201775 -354.359411)
			(xy 303.254559 -354.341404) (xy 303.309402 -354.331274) (xy 303.365136 -354.329237) (xy 303.420573 -354.335337)
			(xy 303.47453 -354.349443) (xy 303.525859 -354.371255) (xy 303.573465 -354.400309) (xy 303.616333 -354.435984)
			(xy 303.65355 -354.477521) (xy 303.684323 -354.524034) (xy 303.707995 -354.574531) (xy 303.724063 -354.627938)
			(xy 303.732183 -354.683114) (xy 303.732692 -354.711) (xy 303.732183 -354.738886) (xy 303.724063 -354.794062)
			(xy 303.707995 -354.847469) (xy 303.684323 -354.897966) (xy 303.65355 -354.944479) (xy 303.616333 -354.986016)
			(xy 303.573465 -355.021691) (xy 303.525859 -355.050745) (xy 303.47453 -355.072557) (xy 303.420573 -355.086663)
			(xy 303.365136 -355.092763) (xy 303.309402 -355.090726) (xy 303.254559 -355.080596) (xy 303.201775 -355.062589)
			(xy 303.152175 -355.037088) (xy 303.106817 -355.004637) (xy 303.066668 -354.965928) (xy 303.032582 -354.921785)
			(xy 303.005286 -354.87315) (xy 302.985363 -354.821059) (xy 302.973237 -354.766622) (xy 302.969166 -354.711)
			(xy 273.993864 -354.711) (xy 274.562062 -355.279198) (xy 285.984442 -355.279198) (xy 285.984854 -355.251943)
			(xy 285.992612 -355.197987) (xy 286.007971 -355.145686) (xy 286.030617 -355.096102) (xy 286.06009 -355.050247)
			(xy 286.095789 -355.009053) (xy 286.136988 -354.973359) (xy 286.182848 -354.943892) (xy 286.232434 -354.921253)
			(xy 286.284738 -354.905901) (xy 286.338695 -354.89815) (xy 286.36595 -354.89769) (xy 286.393319 -354.898188)
			(xy 286.447497 -354.905998) (xy 286.499999 -354.92148) (xy 286.549747 -354.944315) (xy 286.595715 -354.974032)
			(xy 286.616648 -354.99167) (xy 286.62376 -354.997766) (xy 286.640778 -355.004116) (xy 286.726122 -355.004116)
			(xy 286.74314 -354.997766) (xy 286.750252 -354.99167) (xy 286.771185 -354.974029) (xy 286.817153 -354.944305)
			(xy 286.866899 -354.921459) (xy 286.919401 -354.905963) (xy 286.973579 -354.898134) (xy 287.028321 -354.898134)
			(xy 287.082499 -354.905963) (xy 287.135001 -354.921459) (xy 287.184747 -354.944305) (xy 287.230715 -354.974029)
			(xy 287.251648 -354.99167) (xy 287.25876 -354.997766) (xy 287.275778 -355.004116) (xy 287.361122 -355.004116)
			(xy 287.37814 -354.997766) (xy 287.385252 -354.99167) (xy 287.406185 -354.974029) (xy 287.452153 -354.944305)
			(xy 287.501899 -354.921459) (xy 287.554401 -354.905963) (xy 287.608579 -354.898134) (xy 287.663321 -354.898134)
			(xy 287.717499 -354.905963) (xy 287.770001 -354.921459) (xy 287.819747 -354.944305) (xy 287.865715 -354.974029)
			(xy 287.886648 -354.99167) (xy 287.89376 -354.997766) (xy 287.910778 -355.004116) (xy 287.996122 -355.004116)
			(xy 288.01314 -354.997766) (xy 288.020252 -354.99167) (xy 288.041185 -354.974029) (xy 288.087153 -354.944305)
			(xy 288.136899 -354.921459) (xy 288.189401 -354.905963) (xy 288.243579 -354.898134) (xy 288.298321 -354.898134)
			(xy 288.352499 -354.905963) (xy 288.405001 -354.921459) (xy 288.454747 -354.944305) (xy 288.500715 -354.974029)
			(xy 288.521648 -354.99167) (xy 288.52876 -354.997766) (xy 288.545778 -355.004116) (xy 288.631122 -355.004116)
			(xy 288.64814 -354.997766) (xy 288.655252 -354.99167) (xy 288.676187 -354.974035) (xy 288.72216 -354.944324)
			(xy 288.771907 -354.921488) (xy 288.824406 -354.905995) (xy 288.878581 -354.898165) (xy 288.90595 -354.89769)
			(xy 288.933202 -354.898202) (xy 288.987151 -354.905952) (xy 289.039447 -354.921302) (xy 289.089027 -354.943938)
			(xy 289.134881 -354.973401) (xy 289.176074 -355.009089) (xy 289.211768 -355.050278) (xy 289.241237 -355.096127)
			(xy 289.26388 -355.145704) (xy 289.279237 -355.197999) (xy 289.286994 -355.251947) (xy 289.287458 -355.279198)
			(xy 289.286959 -355.307902) (xy 289.278357 -355.364663) (xy 289.261346 -355.419494) (xy 289.236312 -355.471157)
			(xy 289.203819 -355.518485) (xy 289.184588 -355.539802) (xy 289.17773 -355.547168) (xy 289.170618 -355.565202)
			(xy 289.172142 -355.65588) (xy 289.179508 -355.67366) (xy 289.18662 -355.680772) (xy 289.207284 -355.702351)
			(xy 289.242299 -355.750757) (xy 289.269336 -355.804033) (xy 289.285509 -355.854) (xy 302.893982 -355.854)
			(xy 302.898053 -355.798378) (xy 302.910179 -355.743941) (xy 302.930102 -355.69185) (xy 302.957398 -355.643215)
			(xy 302.991484 -355.599072) (xy 303.031633 -355.560363) (xy 303.076991 -355.527912) (xy 303.126591 -355.502411)
			(xy 303.179375 -355.484404) (xy 303.234218 -355.474274) (xy 303.289952 -355.472237) (xy 303.345389 -355.478337)
			(xy 303.399346 -355.492443) (xy 303.450675 -355.514255) (xy 303.498281 -355.543309) (xy 303.541149 -355.578984)
			(xy 303.578366 -355.620521) (xy 303.609139 -355.667034) (xy 303.632811 -355.717531) (xy 303.648879 -355.770938)
			(xy 303.656999 -355.826114) (xy 303.657508 -355.854) (xy 303.656999 -355.881886) (xy 303.648879 -355.937062)
			(xy 303.632811 -355.990469) (xy 303.609139 -356.040966) (xy 303.578366 -356.087479) (xy 303.541149 -356.129016)
			(xy 303.498281 -356.164691) (xy 303.450675 -356.193745) (xy 303.399346 -356.215557) (xy 303.345389 -356.229663)
			(xy 303.289952 -356.235763) (xy 303.234218 -356.233726) (xy 303.179375 -356.223596) (xy 303.126591 -356.205589)
			(xy 303.076991 -356.180088) (xy 303.031633 -356.147637) (xy 302.991484 -356.108928) (xy 302.957398 -356.064785)
			(xy 302.930102 -356.01615) (xy 302.910179 -355.964059) (xy 302.898053 -355.909622) (xy 302.893982 -355.854)
			(xy 289.285509 -355.854) (xy 289.287734 -355.860873) (xy 289.297042 -355.919886) (xy 289.297618 -355.949758)
			(xy 289.297147 -355.977128) (xy 289.289334 -356.031308) (xy 289.273847 -356.083812) (xy 289.251006 -356.133559)
			(xy 289.22128 -356.179525) (xy 289.203638 -356.200456) (xy 289.197542 -356.207568) (xy 289.191192 -356.224586)
			(xy 289.191192 -356.30993) (xy 289.197542 -356.326948) (xy 289.203638 -356.33406) (xy 289.221278 -356.354991)
			(xy 289.250989 -356.400965) (xy 289.273824 -356.450713) (xy 289.289315 -356.503213) (xy 289.297144 -356.557389)
			(xy 289.297618 -356.584758) (xy 289.297106 -356.612009) (xy 289.289355 -356.665958) (xy 289.274004 -356.718254)
			(xy 289.251368 -356.767834) (xy 289.221905 -356.813687) (xy 289.186216 -356.854879) (xy 289.145028 -356.890574)
			(xy 289.099179 -356.920043) (xy 289.049603 -356.942686) (xy 288.997309 -356.958044) (xy 288.943361 -356.965802)
			(xy 288.91611 -356.966266) (xy 288.88874 -356.965802) (xy 288.83456 -356.957985) (xy 288.782057 -356.942496)
			(xy 288.73231 -356.919654) (xy 288.686343 -356.889928) (xy 288.665412 -356.872286) (xy 288.6583 -356.86619)
			(xy 288.641282 -356.85984) (xy 288.555938 -356.85984) (xy 288.53892 -356.86619) (xy 288.531808 -356.872286)
			(xy 288.510875 -356.889927) (xy 288.464907 -356.919651) (xy 288.415161 -356.942497) (xy 288.362659 -356.957993)
			(xy 288.308481 -356.965822) (xy 288.253739 -356.965822) (xy 288.199561 -356.957993) (xy 288.147059 -356.942497)
			(xy 288.097313 -356.919651) (xy 288.051345 -356.889927) (xy 288.030412 -356.872286) (xy 288.0233 -356.86619)
			(xy 288.006282 -356.85984) (xy 287.920938 -356.85984) (xy 287.90392 -356.86619) (xy 287.896808 -356.872286)
			(xy 287.875875 -356.889927) (xy 287.829907 -356.919651) (xy 287.780161 -356.942497) (xy 287.727659 -356.957993)
			(xy 287.673481 -356.965822) (xy 287.618739 -356.965822) (xy 287.564561 -356.957993) (xy 287.512059 -356.942497)
			(xy 287.462313 -356.919651) (xy 287.416345 -356.889927) (xy 287.395412 -356.872286) (xy 287.3883 -356.86619)
			(xy 287.371282 -356.85984) (xy 287.285938 -356.85984) (xy 287.26892 -356.86619) (xy 287.261808 -356.872286)
			(xy 287.240875 -356.889927) (xy 287.194907 -356.919651) (xy 287.145161 -356.942497) (xy 287.092659 -356.957993)
			(xy 287.038481 -356.965822) (xy 286.983739 -356.965822) (xy 286.929561 -356.957993) (xy 286.877059 -356.942497)
			(xy 286.827313 -356.919651) (xy 286.781345 -356.889927) (xy 286.760412 -356.872286) (xy 286.7533 -356.86619)
			(xy 286.736282 -356.85984) (xy 286.650938 -356.85984) (xy 286.63392 -356.86619) (xy 286.626808 -356.872286)
			(xy 286.605882 -356.889933) (xy 286.559908 -356.919644) (xy 286.510159 -356.942479) (xy 286.457657 -356.957968)
			(xy 286.40348 -356.965793) (xy 286.37611 -356.966266) (xy 286.348855 -356.965835) (xy 286.294901 -356.958079)
			(xy 286.2426 -356.942722) (xy 286.193017 -356.920077) (xy 286.147162 -356.890606) (xy 286.105968 -356.854909)
			(xy 286.070274 -356.813712) (xy 286.040807 -356.767855) (xy 286.018167 -356.71827) (xy 286.002815 -356.665967)
			(xy 285.995062 -356.612013) (xy 285.994602 -356.584758) (xy 285.995102 -356.557389) (xy 286.002911 -356.503211)
			(xy 286.018392 -356.450709) (xy 286.041227 -356.400961) (xy 286.070944 -356.354993) (xy 286.088582 -356.33406)
			(xy 286.094678 -356.326948) (xy 286.101028 -356.30993) (xy 286.101028 -356.224586) (xy 286.094678 -356.207568)
			(xy 286.088582 -356.200456) (xy 286.070953 -356.179516) (xy 286.04124 -356.133545) (xy 286.018403 -356.0838)
			(xy 286.002909 -356.031301) (xy 285.995078 -355.977127) (xy 285.994602 -355.949758) (xy 285.995146 -355.921055)
			(xy 286.003739 -355.864297) (xy 286.020739 -355.809467) (xy 286.045764 -355.757803) (xy 286.078246 -355.710473)
			(xy 286.097472 -355.689154) (xy 286.10433 -355.681788) (xy 286.111442 -355.663754) (xy 286.109918 -355.573076)
			(xy 286.102552 -355.555296) (xy 286.09544 -355.548184) (xy 286.074796 -355.526587) (xy 286.03978 -355.478185)
			(xy 286.01274 -355.424914) (xy 285.994337 -355.368078) (xy 285.985022 -355.309068) (xy 285.984442 -355.279198)
			(xy 274.562062 -355.279198) (xy 276.279864 -356.997) (xy 302.986946 -356.997) (xy 302.991017 -356.941378)
			(xy 303.003143 -356.886941) (xy 303.023066 -356.83485) (xy 303.050362 -356.786215) (xy 303.084448 -356.742072)
			(xy 303.124597 -356.703363) (xy 303.169955 -356.670912) (xy 303.219555 -356.645411) (xy 303.272339 -356.627404)
			(xy 303.327182 -356.617274) (xy 303.382916 -356.615237) (xy 303.438353 -356.621337) (xy 303.49231 -356.635443)
			(xy 303.543639 -356.657255) (xy 303.591245 -356.686309) (xy 303.634113 -356.721984) (xy 303.67133 -356.763521)
			(xy 303.702103 -356.810034) (xy 303.725775 -356.860531) (xy 303.741843 -356.913938) (xy 303.749963 -356.969114)
			(xy 303.750472 -356.997) (xy 303.749963 -357.024886) (xy 303.741843 -357.080062) (xy 303.725775 -357.133469)
			(xy 303.702103 -357.183966) (xy 303.67133 -357.230479) (xy 303.634113 -357.272016) (xy 303.591245 -357.307691)
			(xy 303.543639 -357.336745) (xy 303.49231 -357.358557) (xy 303.438353 -357.372663) (xy 303.382916 -357.378763)
			(xy 303.327182 -357.376726) (xy 303.272339 -357.366596) (xy 303.219555 -357.348589) (xy 303.169955 -357.323088)
			(xy 303.124597 -357.290637) (xy 303.084448 -357.251928) (xy 303.050362 -357.207785) (xy 303.023066 -357.15915)
			(xy 303.003143 -357.107059) (xy 302.991017 -357.052622) (xy 302.986946 -356.997) (xy 276.279864 -356.997)
			(xy 276.775926 -357.493062) (xy 305.065174 -357.493062) (xy 305.069245 -357.43744) (xy 305.081371 -357.383003)
			(xy 305.101294 -357.330912) (xy 305.12859 -357.282277) (xy 305.162676 -357.238134) (xy 305.202825 -357.199425)
			(xy 305.248183 -357.166974) (xy 305.297783 -357.141473) (xy 305.350567 -357.123466) (xy 305.40541 -357.113336)
			(xy 305.461144 -357.111299) (xy 305.516581 -357.117399) (xy 305.570538 -357.131505) (xy 305.621867 -357.153317)
			(xy 305.669473 -357.182371) (xy 305.712341 -357.218046) (xy 305.749558 -357.259583) (xy 305.780331 -357.306096)
			(xy 305.804003 -357.356593) (xy 305.820071 -357.41) (xy 305.828191 -357.465176) (xy 305.8287 -357.493062)
			(xy 305.828191 -357.520948) (xy 305.820071 -357.576124) (xy 305.804003 -357.629531) (xy 305.780331 -357.680028)
			(xy 305.749558 -357.726541) (xy 305.712341 -357.768078) (xy 305.669473 -357.803753) (xy 305.621867 -357.832807)
			(xy 305.570538 -357.854619) (xy 305.516581 -357.868725) (xy 305.461144 -357.874825) (xy 305.40541 -357.872788)
			(xy 305.350567 -357.862658) (xy 305.297783 -357.844651) (xy 305.248183 -357.81915) (xy 305.202825 -357.786699)
			(xy 305.162676 -357.74799) (xy 305.12859 -357.703847) (xy 305.101294 -357.655212) (xy 305.081371 -357.603121)
			(xy 305.069245 -357.548684) (xy 305.065174 -357.493062) (xy 276.775926 -357.493062) (xy 278.094878 -358.812014)
			(xy 295.410886 -358.812014) (xy 295.410886 -358.727318) (xy 295.418937 -358.643004) (xy 295.434966 -358.559838)
			(xy 295.458827 -358.478571) (xy 295.490306 -358.399941) (xy 295.529117 -358.32466) (xy 295.574907 -358.253408)
			(xy 295.627263 -358.186832) (xy 295.685711 -358.125534) (xy 295.749721 -358.070069) (xy 295.818713 -358.02094)
			(xy 295.892063 -357.978591) (xy 295.969106 -357.943407) (xy 296.049145 -357.915705) (xy 296.131454 -357.895737)
			(xy 296.215289 -357.883684) (xy 296.29989 -357.879654) (xy 296.384491 -357.883684) (xy 296.468326 -357.895737)
			(xy 296.550635 -357.915705) (xy 296.630674 -357.943407) (xy 296.707717 -357.978591) (xy 296.781067 -358.02094)
			(xy 296.850059 -358.070069) (xy 296.914069 -358.125534) (xy 296.927862 -358.14) (xy 302.875948 -358.14)
			(xy 302.880019 -358.084378) (xy 302.892145 -358.029941) (xy 302.912068 -357.97785) (xy 302.939364 -357.929215)
			(xy 302.97345 -357.885072) (xy 303.013599 -357.846363) (xy 303.058957 -357.813912) (xy 303.108557 -357.788411)
			(xy 303.161341 -357.770404) (xy 303.216184 -357.760274) (xy 303.271918 -357.758237) (xy 303.327355 -357.764337)
			(xy 303.381312 -357.778443) (xy 303.432641 -357.800255) (xy 303.480247 -357.829309) (xy 303.523115 -357.864984)
			(xy 303.560332 -357.906521) (xy 303.591105 -357.953034) (xy 303.614777 -358.003531) (xy 303.630845 -358.056938)
			(xy 303.638965 -358.112114) (xy 303.639474 -358.14) (xy 303.638965 -358.167886) (xy 303.630845 -358.223062)
			(xy 303.614777 -358.276469) (xy 303.591105 -358.326966) (xy 303.560332 -358.373479) (xy 303.523115 -358.415016)
			(xy 303.480247 -358.450691) (xy 303.432641 -358.479745) (xy 303.381312 -358.501557) (xy 303.327355 -358.515663)
			(xy 303.271918 -358.521763) (xy 303.216184 -358.519726) (xy 303.161341 -358.509596) (xy 303.108557 -358.491589)
			(xy 303.058957 -358.466088) (xy 303.013599 -358.433637) (xy 302.97345 -358.394928) (xy 302.939364 -358.350785)
			(xy 302.912068 -358.30215) (xy 302.892145 -358.250059) (xy 302.880019 -358.195622) (xy 302.875948 -358.14)
			(xy 296.927862 -358.14) (xy 296.972517 -358.186832) (xy 297.024873 -358.253408) (xy 297.070663 -358.32466)
			(xy 297.109474 -358.399941) (xy 297.140953 -358.478571) (xy 297.164814 -358.559838) (xy 297.180843 -358.643004)
			(xy 297.188894 -358.727318) (xy 297.189322 -358.763316) (xy 305.14366 -358.763316) (xy 305.147731 -358.707694)
			(xy 305.159857 -358.653257) (xy 305.17978 -358.601166) (xy 305.207076 -358.552531) (xy 305.241162 -358.508388)
			(xy 305.281311 -358.469679) (xy 305.326669 -358.437228) (xy 305.376269 -358.411727) (xy 305.429053 -358.39372)
			(xy 305.483896 -358.38359) (xy 305.53963 -358.381553) (xy 305.595067 -358.387653) (xy 305.649024 -358.401759)
			(xy 305.700353 -358.423571) (xy 305.747959 -358.452625) (xy 305.790827 -358.4883) (xy 305.828044 -358.529837)
			(xy 305.858817 -358.57635) (xy 305.882489 -358.626847) (xy 305.898557 -358.680254) (xy 305.906677 -358.73543)
			(xy 305.907186 -358.763316) (xy 305.906677 -358.791202) (xy 305.898557 -358.846378) (xy 305.882489 -358.899785)
			(xy 305.858817 -358.950282) (xy 305.828044 -358.996795) (xy 305.790827 -359.038332) (xy 305.747959 -359.074007)
			(xy 305.700353 -359.103061) (xy 305.649024 -359.124873) (xy 305.595067 -359.138979) (xy 305.53963 -359.145079)
			(xy 305.483896 -359.143042) (xy 305.429053 -359.132912) (xy 305.376269 -359.114905) (xy 305.326669 -359.089404)
			(xy 305.281311 -359.056953) (xy 305.241162 -359.018244) (xy 305.207076 -358.974101) (xy 305.17978 -358.925466)
			(xy 305.159857 -358.873375) (xy 305.147731 -358.818938) (xy 305.14366 -358.763316) (xy 297.189322 -358.763316)
			(xy 297.189398 -358.769666) (xy 297.188894 -358.812014) (xy 297.180843 -358.896328) (xy 297.164814 -358.979494)
			(xy 297.140953 -359.060761) (xy 297.109474 -359.139391) (xy 297.070663 -359.214672) (xy 297.026752 -359.283)
			(xy 302.893982 -359.283) (xy 302.898053 -359.227378) (xy 302.910179 -359.172941) (xy 302.930102 -359.12085)
			(xy 302.957398 -359.072215) (xy 302.991484 -359.028072) (xy 303.031633 -358.989363) (xy 303.076991 -358.956912)
			(xy 303.126591 -358.931411) (xy 303.179375 -358.913404) (xy 303.234218 -358.903274) (xy 303.289952 -358.901237)
			(xy 303.345389 -358.907337) (xy 303.399346 -358.921443) (xy 303.450675 -358.943255) (xy 303.498281 -358.972309)
			(xy 303.541149 -359.007984) (xy 303.578366 -359.049521) (xy 303.609139 -359.096034) (xy 303.632811 -359.146531)
			(xy 303.648879 -359.199938) (xy 303.656999 -359.255114) (xy 303.657508 -359.283) (xy 303.656999 -359.310886)
			(xy 303.648879 -359.366062) (xy 303.632811 -359.419469) (xy 303.609139 -359.469966) (xy 303.578366 -359.516479)
			(xy 303.541149 -359.558016) (xy 303.498281 -359.593691) (xy 303.450675 -359.622745) (xy 303.399346 -359.644557)
			(xy 303.345389 -359.658663) (xy 303.289952 -359.664763) (xy 303.234218 -359.662726) (xy 303.179375 -359.652596)
			(xy 303.126591 -359.634589) (xy 303.076991 -359.609088) (xy 303.031633 -359.576637) (xy 302.991484 -359.537928)
			(xy 302.957398 -359.493785) (xy 302.930102 -359.44515) (xy 302.910179 -359.393059) (xy 302.898053 -359.338622)
			(xy 302.893982 -359.283) (xy 297.026752 -359.283) (xy 297.024873 -359.285924) (xy 296.972517 -359.3525)
			(xy 296.914069 -359.413798) (xy 296.850059 -359.469263) (xy 296.781067 -359.518392) (xy 296.707717 -359.560741)
			(xy 296.630674 -359.595925) (xy 296.550635 -359.623627) (xy 296.468326 -359.643595) (xy 296.384491 -359.655648)
			(xy 296.29989 -359.659679) (xy 296.215289 -359.655648) (xy 296.131454 -359.643595) (xy 296.049145 -359.623627)
			(xy 295.969106 -359.595925) (xy 295.892063 -359.560741) (xy 295.818713 -359.518392) (xy 295.749721 -359.469263)
			(xy 295.685711 -359.413798) (xy 295.627263 -359.3525) (xy 295.574907 -359.285924) (xy 295.529117 -359.214672)
			(xy 295.490306 -359.139391) (xy 295.458827 -359.060761) (xy 295.434966 -358.979494) (xy 295.418937 -358.896328)
			(xy 295.410886 -358.812014) (xy 278.094878 -358.812014) (xy 279.312624 -360.02976) (xy 305.24145 -360.02976)
			(xy 305.245521 -359.974138) (xy 305.257647 -359.919701) (xy 305.27757 -359.86761) (xy 305.304866 -359.818975)
			(xy 305.338952 -359.774832) (xy 305.379101 -359.736123) (xy 305.424459 -359.703672) (xy 305.474059 -359.678171)
			(xy 305.526843 -359.660164) (xy 305.581686 -359.650034) (xy 305.63742 -359.647997) (xy 305.692857 -359.654097)
			(xy 305.746814 -359.668203) (xy 305.798143 -359.690015) (xy 305.845749 -359.719069) (xy 305.888617 -359.754744)
			(xy 305.925834 -359.796281) (xy 305.956607 -359.842794) (xy 305.980279 -359.893291) (xy 305.996347 -359.946698)
			(xy 306.004467 -360.001874) (xy 306.004976 -360.02976) (xy 306.004467 -360.057646) (xy 305.996347 -360.112822)
			(xy 305.980279 -360.166229) (xy 305.956607 -360.216726) (xy 305.925834 -360.263239) (xy 305.888617 -360.304776)
			(xy 305.845749 -360.340451) (xy 305.798143 -360.369505) (xy 305.746814 -360.391317) (xy 305.703533 -360.402632)
			(xy 313.480448 -360.402632) (xy 313.484519 -360.34701) (xy 313.496645 -360.292573) (xy 313.516568 -360.240482)
			(xy 313.543864 -360.191847) (xy 313.57795 -360.147704) (xy 313.618099 -360.108995) (xy 313.663457 -360.076544)
			(xy 313.713057 -360.051043) (xy 313.765841 -360.033036) (xy 313.820684 -360.022906) (xy 313.876418 -360.020869)
			(xy 313.931855 -360.026969) (xy 313.985812 -360.041075) (xy 314.037141 -360.062887) (xy 314.084747 -360.091941)
			(xy 314.127615 -360.127616) (xy 314.164832 -360.169153) (xy 314.195605 -360.215666) (xy 314.219277 -360.266163)
			(xy 314.235345 -360.31957) (xy 314.243465 -360.374746) (xy 314.243974 -360.402632) (xy 314.243465 -360.430518)
			(xy 314.235345 -360.485694) (xy 314.219277 -360.539101) (xy 314.195605 -360.589598) (xy 314.164832 -360.636111)
			(xy 314.127615 -360.677648) (xy 314.084747 -360.713323) (xy 314.037141 -360.742377) (xy 313.985812 -360.764189)
			(xy 313.931855 -360.778295) (xy 313.876418 -360.784395) (xy 313.820684 -360.782358) (xy 313.765841 -360.772228)
			(xy 313.713057 -360.754221) (xy 313.663457 -360.72872) (xy 313.618099 -360.696269) (xy 313.57795 -360.65756)
			(xy 313.543864 -360.613417) (xy 313.516568 -360.564782) (xy 313.496645 -360.512691) (xy 313.484519 -360.458254)
			(xy 313.480448 -360.402632) (xy 305.703533 -360.402632) (xy 305.692857 -360.405423) (xy 305.63742 -360.411523)
			(xy 305.581686 -360.409486) (xy 305.526843 -360.399356) (xy 305.474059 -360.381349) (xy 305.424459 -360.355848)
			(xy 305.379101 -360.323397) (xy 305.338952 -360.284688) (xy 305.304866 -360.240545) (xy 305.27757 -360.19191)
			(xy 305.257647 -360.139819) (xy 305.245521 -360.085382) (xy 305.24145 -360.02976) (xy 279.312624 -360.02976)
			(xy 280.848816 -361.565952) (xy 285.209742 -361.565952) (xy 285.21011 -361.538696) (xy 285.217875 -361.484739)
			(xy 285.23324 -361.432436) (xy 285.255892 -361.382852) (xy 285.285369 -361.336997) (xy 285.321073 -361.295803)
			(xy 285.362276 -361.26011) (xy 285.408138 -361.230645) (xy 285.457728 -361.208006) (xy 285.510035 -361.192654)
			(xy 285.563994 -361.184903) (xy 285.59125 -361.184444) (xy 285.61862 -361.184929) (xy 285.672798 -361.19274)
			(xy 285.725302 -361.208224) (xy 285.775049 -361.231062) (xy 285.821016 -361.260784) (xy 285.841948 -361.278424)
			(xy 285.84906 -361.28452) (xy 285.866078 -361.29087) (xy 285.951422 -361.29087) (xy 285.96844 -361.28452)
			(xy 285.975552 -361.278424) (xy 285.996494 -361.260798) (xy 286.042464 -361.231083) (xy 286.092209 -361.208244)
			(xy 286.144707 -361.19275) (xy 286.198881 -361.184919) (xy 286.22625 -361.184444) (xy 286.252898 -361.184913)
			(xy 286.305674 -361.192349) (xy 286.356902 -361.207056) (xy 286.405586 -361.228747) (xy 286.450777 -361.257001)
			(xy 286.491599 -361.291268) (xy 286.527255 -361.330882) (xy 286.557053 -361.375071) (xy 286.56915 -361.39882)
			(xy 286.57423 -361.409234) (xy 286.592264 -361.423458) (xy 286.692594 -361.446064) (xy 286.714946 -361.44073)
			(xy 286.72409 -361.433618) (xy 286.744487 -361.417796) (xy 286.788733 -361.391204) (xy 286.836157 -361.370812)
			(xy 286.885894 -361.356991) (xy 286.937039 -361.349993) (xy 286.96285 -361.349544) (xy 286.99022 -361.350029)
			(xy 287.044398 -361.35784) (xy 287.096902 -361.373324) (xy 287.146649 -361.396162) (xy 287.192616 -361.425884)
			(xy 287.213548 -361.443524) (xy 287.22066 -361.44962) (xy 287.237678 -361.45597) (xy 287.323022 -361.45597)
			(xy 287.34004 -361.44962) (xy 287.347152 -361.443524) (xy 287.368085 -361.425883) (xy 287.414053 -361.396159)
			(xy 287.463799 -361.373313) (xy 287.516301 -361.357817) (xy 287.570479 -361.349988) (xy 287.625221 -361.349988)
			(xy 287.679399 -361.357817) (xy 287.731901 -361.373313) (xy 287.781647 -361.396159) (xy 287.827615 -361.425883)
			(xy 287.848548 -361.443524) (xy 287.85566 -361.44962) (xy 287.872678 -361.45597) (xy 287.958022 -361.45597)
			(xy 287.97504 -361.44962) (xy 287.982152 -361.443524) (xy 288.003085 -361.425883) (xy 288.049053 -361.396159)
			(xy 288.098799 -361.373313) (xy 288.151301 -361.357817) (xy 288.205479 -361.349988) (xy 288.260221 -361.349988)
			(xy 288.314399 -361.357817) (xy 288.366901 -361.373313) (xy 288.416647 -361.396159) (xy 288.462615 -361.425883)
			(xy 288.483548 -361.443524) (xy 288.49066 -361.44962) (xy 288.507678 -361.45597) (xy 288.593022 -361.45597)
			(xy 288.61004 -361.44962) (xy 288.617152 -361.443524) (xy 288.638094 -361.425898) (xy 288.684064 -361.396183)
			(xy 288.733809 -361.373344) (xy 288.786307 -361.35785) (xy 288.840481 -361.350019) (xy 288.86785 -361.349544)
			(xy 288.893663 -361.35) (xy 288.944816 -361.356964) (xy 288.994561 -361.370771) (xy 289.041985 -361.391168)
			(xy 289.086222 -361.417781) (xy 289.10661 -361.433618) (xy 289.115754 -361.44073) (xy 289.138106 -361.446064)
			(xy 289.238436 -361.423458) (xy 289.25647 -361.409234) (xy 289.26155 -361.39882) (xy 289.273615 -361.375051)
			(xy 289.303402 -361.330844) (xy 289.339054 -361.291217) (xy 289.379878 -361.256941) (xy 289.425077 -361.228684)
			(xy 289.473771 -361.206996) (xy 289.525011 -361.192301) (xy 289.577797 -361.184885) (xy 289.60445 -361.184444)
			(xy 289.63182 -361.184929) (xy 289.685998 -361.19274) (xy 289.738502 -361.208224) (xy 289.788249 -361.231062)
			(xy 289.834216 -361.260784) (xy 289.855148 -361.278424) (xy 289.86226 -361.28452) (xy 289.879278 -361.29087)
			(xy 289.964622 -361.29087) (xy 289.98164 -361.28452) (xy 289.988752 -361.278424) (xy 290.009694 -361.260798)
			(xy 290.055664 -361.231083) (xy 290.105409 -361.208244) (xy 290.157907 -361.19275) (xy 290.212081 -361.184919)
			(xy 290.23945 -361.184444) (xy 290.265295 -361.184875) (xy 290.316511 -361.19186) (xy 290.366315 -361.205696)
			(xy 290.413795 -361.226128) (xy 290.458082 -361.252783) (xy 290.498365 -361.285173) (xy 290.533907 -361.322705)
			(xy 290.54933 -361.343448) (xy 290.556442 -361.353354) (xy 290.57727 -361.364276) (xy 290.682934 -361.366816)
			(xy 290.70427 -361.356656) (xy 290.71189 -361.347004) (xy 290.73011 -361.324759) (xy 290.772036 -361.285413)
			(xy 290.819395 -361.25281) (xy 290.871113 -361.227688) (xy 290.926017 -361.210617) (xy 290.982862 -361.201984)
			(xy 291.01161 -361.201462) (xy 291.03886 -361.201968) (xy 291.092806 -361.209725) (xy 291.145098 -361.22508)
			(xy 291.194673 -361.24772) (xy 291.240522 -361.277185) (xy 291.28086 -361.312136) (xy 295.410886 -361.312136)
			(xy 295.410886 -361.22744) (xy 295.418937 -361.143126) (xy 295.434966 -361.05996) (xy 295.458827 -360.978693)
			(xy 295.490306 -360.900063) (xy 295.529117 -360.824782) (xy 295.574907 -360.75353) (xy 295.627263 -360.686954)
			(xy 295.685711 -360.625656) (xy 295.749721 -360.570191) (xy 295.818713 -360.521062) (xy 295.892063 -360.478713)
			(xy 295.969106 -360.443529) (xy 296.049145 -360.415827) (xy 296.131454 -360.395859) (xy 296.215289 -360.383806)
			(xy 296.29989 -360.379776) (xy 296.384491 -360.383806) (xy 296.468326 -360.395859) (xy 296.550635 -360.415827)
			(xy 296.630674 -360.443529) (xy 296.707717 -360.478713) (xy 296.781067 -360.521062) (xy 296.850059 -360.570191)
			(xy 296.914069 -360.625656) (xy 296.917448 -360.6292) (xy 301.369982 -360.6292) (xy 301.374053 -360.573578)
			(xy 301.386179 -360.519141) (xy 301.406102 -360.46705) (xy 301.433398 -360.418415) (xy 301.467484 -360.374272)
			(xy 301.507633 -360.335563) (xy 301.552991 -360.303112) (xy 301.602591 -360.277611) (xy 301.655375 -360.259604)
			(xy 301.710218 -360.249474) (xy 301.765952 -360.247437) (xy 301.821389 -360.253537) (xy 301.875346 -360.267643)
			(xy 301.926675 -360.289455) (xy 301.974281 -360.318509) (xy 302.017149 -360.354184) (xy 302.054366 -360.395721)
			(xy 302.085139 -360.442234) (xy 302.108811 -360.492731) (xy 302.124879 -360.546138) (xy 302.132999 -360.601314)
			(xy 302.133508 -360.6292) (xy 302.132999 -360.657086) (xy 302.124879 -360.712262) (xy 302.108811 -360.765669)
			(xy 302.085139 -360.816166) (xy 302.054366 -360.862679) (xy 302.017149 -360.904216) (xy 301.974281 -360.939891)
			(xy 301.926675 -360.968945) (xy 301.875346 -360.990757) (xy 301.821389 -361.004863) (xy 301.765952 -361.010963)
			(xy 301.710218 -361.008926) (xy 301.655375 -360.998796) (xy 301.602591 -360.980789) (xy 301.552991 -360.955288)
			(xy 301.507633 -360.922837) (xy 301.467484 -360.884128) (xy 301.433398 -360.839985) (xy 301.406102 -360.79135)
			(xy 301.386179 -360.739259) (xy 301.374053 -360.684822) (xy 301.369982 -360.6292) (xy 296.917448 -360.6292)
			(xy 296.972517 -360.686954) (xy 297.024873 -360.75353) (xy 297.070663 -360.824782) (xy 297.109474 -360.900063)
			(xy 297.140953 -360.978693) (xy 297.164814 -361.05996) (xy 297.180843 -361.143126) (xy 297.188894 -361.22744)
			(xy 297.189398 -361.269788) (xy 297.188894 -361.312136) (xy 297.180843 -361.39645) (xy 297.176959 -361.4166)
			(xy 300.099982 -361.4166) (xy 300.104053 -361.360978) (xy 300.116179 -361.306541) (xy 300.136102 -361.25445)
			(xy 300.163398 -361.205815) (xy 300.197484 -361.161672) (xy 300.237633 -361.122963) (xy 300.282991 -361.090512)
			(xy 300.332591 -361.065011) (xy 300.385375 -361.047004) (xy 300.440218 -361.036874) (xy 300.495952 -361.034837)
			(xy 300.551389 -361.040937) (xy 300.605346 -361.055043) (xy 300.619364 -361.061) (xy 304.113182 -361.061)
			(xy 304.117253 -361.005378) (xy 304.129379 -360.950941) (xy 304.149302 -360.89885) (xy 304.176598 -360.850215)
			(xy 304.210684 -360.806072) (xy 304.250833 -360.767363) (xy 304.296191 -360.734912) (xy 304.345791 -360.709411)
			(xy 304.398575 -360.691404) (xy 304.453418 -360.681274) (xy 304.509152 -360.679237) (xy 304.564589 -360.685337)
			(xy 304.618546 -360.699443) (xy 304.669875 -360.721255) (xy 304.717481 -360.750309) (xy 304.760349 -360.785984)
			(xy 304.797566 -360.827521) (xy 304.828339 -360.874034) (xy 304.852011 -360.924531) (xy 304.868079 -360.977938)
			(xy 304.876199 -361.033114) (xy 304.876708 -361.061) (xy 304.876199 -361.088886) (xy 304.868079 -361.144062)
			(xy 304.852011 -361.197469) (xy 304.828339 -361.247966) (xy 304.797566 -361.294479) (xy 304.790103 -361.302808)
			(xy 305.2097 -361.302808) (xy 305.213771 -361.247186) (xy 305.225897 -361.192749) (xy 305.24582 -361.140658)
			(xy 305.273116 -361.092023) (xy 305.307202 -361.04788) (xy 305.347351 -361.009171) (xy 305.392709 -360.97672)
			(xy 305.442309 -360.951219) (xy 305.495093 -360.933212) (xy 305.549936 -360.923082) (xy 305.60567 -360.921045)
			(xy 305.661107 -360.927145) (xy 305.715064 -360.941251) (xy 305.766393 -360.963063) (xy 305.813999 -360.992117)
			(xy 305.856867 -361.027792) (xy 305.894084 -361.069329) (xy 305.924857 -361.115842) (xy 305.948529 -361.166339)
			(xy 305.964597 -361.219746) (xy 305.972717 -361.274922) (xy 305.973226 -361.302808) (xy 305.972717 -361.330694)
			(xy 305.964597 -361.38587) (xy 305.948529 -361.439277) (xy 305.924857 -361.489774) (xy 305.894084 -361.536287)
			(xy 305.856867 -361.577824) (xy 305.813999 -361.613499) (xy 305.766393 -361.642553) (xy 305.715064 -361.664365)
			(xy 305.661107 -361.678471) (xy 305.60567 -361.684571) (xy 305.549936 -361.682534) (xy 305.495093 -361.672404)
			(xy 305.442309 -361.654397) (xy 305.392709 -361.628896) (xy 305.347351 -361.596445) (xy 305.307202 -361.557736)
			(xy 305.273116 -361.513593) (xy 305.24582 -361.464958) (xy 305.225897 -361.412867) (xy 305.213771 -361.35843)
			(xy 305.2097 -361.302808) (xy 304.790103 -361.302808) (xy 304.760349 -361.336016) (xy 304.717481 -361.371691)
			(xy 304.669875 -361.400745) (xy 304.618546 -361.422557) (xy 304.564589 -361.436663) (xy 304.509152 -361.442763)
			(xy 304.453418 -361.440726) (xy 304.398575 -361.430596) (xy 304.345791 -361.412589) (xy 304.296191 -361.387088)
			(xy 304.250833 -361.354637) (xy 304.210684 -361.315928) (xy 304.176598 -361.271785) (xy 304.149302 -361.22315)
			(xy 304.129379 -361.171059) (xy 304.117253 -361.116622) (xy 304.113182 -361.061) (xy 300.619364 -361.061)
			(xy 300.656675 -361.076855) (xy 300.704281 -361.105909) (xy 300.747149 -361.141584) (xy 300.784366 -361.183121)
			(xy 300.815139 -361.229634) (xy 300.838811 -361.280131) (xy 300.854879 -361.333538) (xy 300.862999 -361.388714)
			(xy 300.863508 -361.4166) (xy 300.862999 -361.444486) (xy 300.854879 -361.499662) (xy 300.838811 -361.553069)
			(xy 300.815139 -361.603566) (xy 300.784366 -361.650079) (xy 300.747149 -361.691616) (xy 300.741881 -361.696)
			(xy 302.893982 -361.696) (xy 302.898053 -361.640378) (xy 302.910179 -361.585941) (xy 302.930102 -361.53385)
			(xy 302.957398 -361.485215) (xy 302.991484 -361.441072) (xy 303.031633 -361.402363) (xy 303.076991 -361.369912)
			(xy 303.126591 -361.344411) (xy 303.179375 -361.326404) (xy 303.234218 -361.316274) (xy 303.289952 -361.314237)
			(xy 303.345389 -361.320337) (xy 303.399346 -361.334443) (xy 303.450675 -361.356255) (xy 303.498281 -361.385309)
			(xy 303.541149 -361.420984) (xy 303.578366 -361.462521) (xy 303.609139 -361.509034) (xy 303.632811 -361.559531)
			(xy 303.648879 -361.612938) (xy 303.656999 -361.668114) (xy 303.657508 -361.696) (xy 303.656999 -361.723886)
			(xy 303.648879 -361.779062) (xy 303.632811 -361.832469) (xy 303.609139 -361.882966) (xy 303.578366 -361.929479)
			(xy 303.541149 -361.971016) (xy 303.498281 -362.006691) (xy 303.450675 -362.035745) (xy 303.399346 -362.057557)
			(xy 303.345389 -362.071663) (xy 303.289952 -362.077763) (xy 303.234218 -362.075726) (xy 303.179375 -362.065596)
			(xy 303.126591 -362.047589) (xy 303.076991 -362.022088) (xy 303.031633 -361.989637) (xy 302.991484 -361.950928)
			(xy 302.957398 -361.906785) (xy 302.930102 -361.85815) (xy 302.910179 -361.806059) (xy 302.898053 -361.751622)
			(xy 302.893982 -361.696) (xy 300.741881 -361.696) (xy 300.704281 -361.727291) (xy 300.656675 -361.756345)
			(xy 300.605346 -361.778157) (xy 300.551389 -361.792263) (xy 300.495952 -361.798363) (xy 300.440218 -361.796326)
			(xy 300.385375 -361.786196) (xy 300.332591 -361.768189) (xy 300.282991 -361.742688) (xy 300.237633 -361.710237)
			(xy 300.197484 -361.671528) (xy 300.163398 -361.627385) (xy 300.136102 -361.57875) (xy 300.116179 -361.526659)
			(xy 300.104053 -361.472222) (xy 300.099982 -361.4166) (xy 297.176959 -361.4166) (xy 297.164814 -361.479616)
			(xy 297.140953 -361.560883) (xy 297.109474 -361.639513) (xy 297.070663 -361.714794) (xy 297.024873 -361.786046)
			(xy 296.972517 -361.852622) (xy 296.914069 -361.91392) (xy 296.850059 -361.969385) (xy 296.781067 -362.018514)
			(xy 296.707717 -362.060863) (xy 296.630674 -362.096047) (xy 296.550635 -362.123749) (xy 296.468326 -362.143717)
			(xy 296.384491 -362.15577) (xy 296.29989 -362.159801) (xy 296.215289 -362.15577) (xy 296.131454 -362.143717)
			(xy 296.049145 -362.123749) (xy 295.969106 -362.096047) (xy 295.892063 -362.060863) (xy 295.818713 -362.018514)
			(xy 295.749721 -361.969385) (xy 295.685711 -361.91392) (xy 295.627263 -361.852622) (xy 295.574907 -361.786046)
			(xy 295.529117 -361.714794) (xy 295.490306 -361.639513) (xy 295.458827 -361.560883) (xy 295.434966 -361.479616)
			(xy 295.418937 -361.39645) (xy 295.410886 -361.312136) (xy 291.28086 -361.312136) (xy 291.281712 -361.312874)
			(xy 291.317403 -361.354062) (xy 291.34687 -361.399909) (xy 291.369513 -361.449483) (xy 291.38487 -361.501775)
			(xy 291.39263 -361.55572) (xy 291.393118 -361.58297) (xy 291.3926 -361.612245) (xy 291.383625 -361.670104)
			(xy 291.365911 -361.725911) (xy 291.339876 -361.778355) (xy 291.306131 -361.826203) (xy 291.286184 -361.847638)
			(xy 291.279072 -361.855004) (xy 291.27196 -361.873546) (xy 291.27323 -361.965494) (xy 291.281104 -361.983782)
			(xy 291.28847 -361.990894) (xy 291.30629 -362.008912) (xy 291.33752 -362.048822) (xy 291.36319 -362.092515)
			(xy 291.38285 -362.139223) (xy 291.393562 -362.1786) (xy 302.131982 -362.1786) (xy 302.136053 -362.122978)
			(xy 302.148179 -362.068541) (xy 302.168102 -362.01645) (xy 302.195398 -361.967815) (xy 302.229484 -361.923672)
			(xy 302.269633 -361.884963) (xy 302.314991 -361.852512) (xy 302.364591 -361.827011) (xy 302.417375 -361.809004)
			(xy 302.472218 -361.798874) (xy 302.527952 -361.796837) (xy 302.583389 -361.802937) (xy 302.637346 -361.817043)
			(xy 302.688675 -361.838855) (xy 302.736281 -361.867909) (xy 302.779149 -361.903584) (xy 302.816366 -361.945121)
			(xy 302.847139 -361.991634) (xy 302.870811 -362.042131) (xy 302.886879 -362.095538) (xy 302.894999 -362.150714)
			(xy 302.895508 -362.1786) (xy 302.894999 -362.206486) (xy 302.886879 -362.261662) (xy 302.870811 -362.315069)
			(xy 302.847139 -362.365566) (xy 302.816366 -362.412079) (xy 302.779149 -362.453616) (xy 302.736281 -362.489291)
			(xy 302.688675 -362.518345) (xy 302.637346 -362.540157) (xy 302.583389 -362.554263) (xy 302.527952 -362.560363)
			(xy 302.472218 -362.558326) (xy 302.417375 -362.548196) (xy 302.364591 -362.530189) (xy 302.314991 -362.504688)
			(xy 302.269633 -362.472237) (xy 302.229484 -362.433528) (xy 302.195398 -362.389385) (xy 302.168102 -362.34075)
			(xy 302.148179 -362.288659) (xy 302.136053 -362.234222) (xy 302.131982 -362.1786) (xy 291.393562 -362.1786)
			(xy 291.396152 -362.188122) (xy 291.402863 -362.238352) (xy 291.403278 -362.26369) (xy 291.402811 -362.29106)
			(xy 291.394995 -362.34524) (xy 291.379506 -362.397743) (xy 291.356664 -362.44749) (xy 291.326939 -362.493456)
			(xy 291.309298 -362.514388) (xy 291.303202 -362.5215) (xy 291.296852 -362.538518) (xy 291.296852 -362.623862)
			(xy 291.303202 -362.64088) (xy 291.309298 -362.647992) (xy 291.326928 -362.668933) (xy 291.356651 -362.7149)
			(xy 291.379496 -362.764645) (xy 291.394992 -362.817146) (xy 291.39815 -362.839) (xy 300.582582 -362.839)
			(xy 300.586653 -362.783378) (xy 300.598779 -362.728941) (xy 300.618702 -362.67685) (xy 300.645998 -362.628215)
			(xy 300.680084 -362.584072) (xy 300.720233 -362.545363) (xy 300.765591 -362.512912) (xy 300.815191 -362.487411)
			(xy 300.867975 -362.469404) (xy 300.922818 -362.459274) (xy 300.978552 -362.457237) (xy 301.033989 -362.463337)
			(xy 301.087946 -362.477443) (xy 301.139275 -362.499255) (xy 301.186881 -362.528309) (xy 301.227533 -362.56214)
			(xy 305.030376 -362.56214) (xy 305.034447 -362.506518) (xy 305.046573 -362.452081) (xy 305.066496 -362.39999)
			(xy 305.093792 -362.351355) (xy 305.127878 -362.307212) (xy 305.168027 -362.268503) (xy 305.213385 -362.236052)
			(xy 305.262985 -362.210551) (xy 305.315769 -362.192544) (xy 305.370612 -362.182414) (xy 305.426346 -362.180377)
			(xy 305.481783 -362.186477) (xy 305.53574 -362.200583) (xy 305.587069 -362.222395) (xy 305.634675 -362.251449)
			(xy 305.677543 -362.287124) (xy 305.71476 -362.328661) (xy 305.745533 -362.375174) (xy 305.769205 -362.425671)
			(xy 305.785273 -362.479078) (xy 305.793393 -362.534254) (xy 305.793902 -362.56214) (xy 305.793393 -362.590026)
			(xy 305.785273 -362.645202) (xy 305.769205 -362.698609) (xy 305.745533 -362.749106) (xy 305.71476 -362.795619)
			(xy 305.677543 -362.837156) (xy 305.634675 -362.872831) (xy 305.587069 -362.901885) (xy 305.53574 -362.923697)
			(xy 305.481783 -362.937803) (xy 305.426346 -362.943903) (xy 305.370612 -362.941866) (xy 305.315769 -362.931736)
			(xy 305.262985 -362.913729) (xy 305.213385 -362.888228) (xy 305.168027 -362.855777) (xy 305.127878 -362.817068)
			(xy 305.093792 -362.772925) (xy 305.066496 -362.72429) (xy 305.046573 -362.672199) (xy 305.034447 -362.617762)
			(xy 305.030376 -362.56214) (xy 301.227533 -362.56214) (xy 301.229749 -362.563984) (xy 301.266966 -362.605521)
			(xy 301.297739 -362.652034) (xy 301.321411 -362.702531) (xy 301.337479 -362.755938) (xy 301.345599 -362.811114)
			(xy 301.346108 -362.839) (xy 301.345599 -362.866886) (xy 301.337479 -362.922062) (xy 301.321411 -362.975469)
			(xy 301.297739 -363.025966) (xy 301.266966 -363.072479) (xy 301.229749 -363.114016) (xy 301.186881 -363.149691)
			(xy 301.139275 -363.178745) (xy 301.087946 -363.200557) (xy 301.033989 -363.214663) (xy 300.978552 -363.220763)
			(xy 300.922818 -363.218726) (xy 300.867975 -363.208596) (xy 300.815191 -363.190589) (xy 300.765591 -363.165088)
			(xy 300.720233 -363.132637) (xy 300.680084 -363.093928) (xy 300.645998 -363.049785) (xy 300.618702 -363.00115)
			(xy 300.598779 -362.949059) (xy 300.586653 -362.894622) (xy 300.582582 -362.839) (xy 291.39815 -362.839)
			(xy 291.402821 -362.871323) (xy 291.402822 -362.926062) (xy 291.394995 -362.98024) (xy 291.379501 -363.032741)
			(xy 291.356658 -363.082487) (xy 291.326937 -363.128455) (xy 291.309298 -363.149388) (xy 291.303202 -363.1565)
			(xy 291.296852 -363.173518) (xy 291.296852 -363.258862) (xy 291.303202 -363.27588) (xy 291.309298 -363.282992)
			(xy 291.326928 -363.303933) (xy 291.356651 -363.3499) (xy 291.379496 -363.399645) (xy 291.394992 -363.452146)
			(xy 291.402821 -363.506323) (xy 291.402822 -363.561062) (xy 291.394995 -363.61524) (xy 291.379501 -363.667741)
			(xy 291.356658 -363.717487) (xy 291.326937 -363.763455) (xy 291.309298 -363.784388) (xy 291.303202 -363.7915)
			(xy 291.296852 -363.808518) (xy 291.296852 -363.846872) (xy 305.046632 -363.846872) (xy 305.050703 -363.79125)
			(xy 305.062829 -363.736813) (xy 305.082752 -363.684722) (xy 305.110048 -363.636087) (xy 305.144134 -363.591944)
			(xy 305.184283 -363.553235) (xy 305.229641 -363.520784) (xy 305.279241 -363.495283) (xy 305.332025 -363.477276)
			(xy 305.386868 -363.467146) (xy 305.442602 -363.465109) (xy 305.498039 -363.471209) (xy 305.551996 -363.485315)
			(xy 305.603325 -363.507127) (xy 305.650931 -363.536181) (xy 305.693799 -363.571856) (xy 305.731016 -363.613393)
			(xy 305.761789 -363.659906) (xy 305.785461 -363.710403) (xy 305.801529 -363.76381) (xy 305.809649 -363.818986)
			(xy 305.810158 -363.846872) (xy 305.809649 -363.874758) (xy 305.801529 -363.929934) (xy 305.785461 -363.983341)
			(xy 305.761789 -364.033838) (xy 305.731016 -364.080351) (xy 305.693799 -364.121888) (xy 305.650931 -364.157563)
			(xy 305.603325 -364.186617) (xy 305.551996 -364.208429) (xy 305.498039 -364.222535) (xy 305.442602 -364.228635)
			(xy 305.386868 -364.226598) (xy 305.332025 -364.216468) (xy 305.279241 -364.198461) (xy 305.229641 -364.17296)
			(xy 305.184283 -364.140509) (xy 305.144134 -364.1018) (xy 305.110048 -364.057657) (xy 305.082752 -364.009022)
			(xy 305.062829 -363.956931) (xy 305.050703 -363.902494) (xy 305.046632 -363.846872) (xy 291.296852 -363.846872)
			(xy 291.296852 -363.893862) (xy 291.303202 -363.91088) (xy 291.309298 -363.917992) (xy 291.326946 -363.938917)
			(xy 291.356657 -363.984891) (xy 291.379491 -364.034641) (xy 291.39498 -364.087143) (xy 291.402805 -364.14132)
			(xy 291.403278 -364.16869) (xy 291.402835 -364.195944) (xy 291.395079 -364.249897) (xy 291.379723 -364.302197)
			(xy 291.357079 -364.351779) (xy 291.327609 -364.397634) (xy 291.291913 -364.438828) (xy 291.250718 -364.474521)
			(xy 291.204862 -364.503989) (xy 291.155278 -364.52663) (xy 291.102978 -364.541983) (xy 291.049024 -364.549737)
			(xy 291.02177 -364.550198) (xy 290.995926 -364.549734) (xy 290.944713 -364.542753) (xy 290.89491 -364.528922)
			(xy 290.847431 -364.508494) (xy 290.803143 -364.481845) (xy 290.762859 -364.44946) (xy 290.727315 -364.411934)
			(xy 290.71189 -364.391194) (xy 290.704778 -364.381288) (xy 290.68395 -364.370366) (xy 290.578286 -364.367826)
			(xy 290.55695 -364.377986) (xy 290.54933 -364.387638) (xy 290.531166 -364.40993) (xy 290.489227 -364.449271)
			(xy 290.441856 -364.481868) (xy 290.390127 -364.506981) (xy 290.335214 -364.524042) (xy 290.278361 -364.532664)
			(xy 290.24961 -364.53318) (xy 290.22224 -364.532713) (xy 290.168061 -364.524896) (xy 290.115557 -364.509408)
			(xy 290.06581 -364.486566) (xy 290.019844 -364.456841) (xy 289.998912 -364.4392) (xy 289.9918 -364.433104)
			(xy 289.974782 -364.426754) (xy 289.889438 -364.426754) (xy 289.87242 -364.433104) (xy 289.865308 -364.4392)
			(xy 289.844384 -364.456849) (xy 289.798409 -364.486559) (xy 289.748659 -364.509393) (xy 289.696157 -364.524882)
			(xy 289.64198 -364.532707) (xy 289.61461 -364.53318) (xy 289.587035 -364.532714) (xy 289.532462 -364.524763)
			(xy 289.479602 -364.509038) (xy 289.429556 -364.485868) (xy 289.383366 -364.455735) (xy 289.341996 -364.419267)
			(xy 289.32378 -364.39856) (xy 289.316188 -364.390431) (xy 289.296028 -364.381084) (xy 289.284918 -364.380526)
			(xy 289.207702 -364.380526) (xy 289.196589 -364.381071) (xy 289.17643 -364.390425) (xy 289.16884 -364.39856)
			(xy 289.150602 -364.419247) (xy 289.10924 -364.455721) (xy 289.063056 -364.485857) (xy 289.013013 -364.509027)
			(xy 288.960155 -364.524748) (xy 288.905583 -364.532693) (xy 288.87801 -364.53318) (xy 288.85064 -364.532713)
			(xy 288.796461 -364.524896) (xy 288.743957 -364.509408) (xy 288.69421 -364.486566) (xy 288.648244 -364.456841)
			(xy 288.627312 -364.4392) (xy 288.6202 -364.433104) (xy 288.603182 -364.426754) (xy 288.517838 -364.426754)
			(xy 288.50082 -364.433104) (xy 288.493708 -364.4392) (xy 288.472775 -364.456841) (xy 288.426807 -364.486565)
			(xy 288.377061 -364.509411) (xy 288.324559 -364.524907) (xy 288.270381 -364.532736) (xy 288.215639 -364.532736)
			(xy 288.161461 -364.524907) (xy 288.108959 -364.509411) (xy 288.059213 -364.486565) (xy 288.013245 -364.456841)
			(xy 287.992312 -364.4392) (xy 287.9852 -364.433104) (xy 287.968182 -364.426754) (xy 287.882838 -364.426754)
			(xy 287.86582 -364.433104) (xy 287.858708 -364.4392) (xy 287.837775 -364.456841) (xy 287.791807 -364.486565)
			(xy 287.742061 -364.509411) (xy 287.689559 -364.524907) (xy 287.635381 -364.532736) (xy 287.580639 -364.532736)
			(xy 287.526461 -364.524907) (xy 287.473959 -364.509411) (xy 287.424213 -364.486565) (xy 287.378245 -364.456841)
			(xy 287.357312 -364.4392) (xy 287.3502 -364.433104) (xy 287.333182 -364.426754) (xy 287.247838 -364.426754)
			(xy 287.23082 -364.433104) (xy 287.223708 -364.4392) (xy 287.202784 -364.456849) (xy 287.156809 -364.486559)
			(xy 287.107059 -364.509393) (xy 287.054557 -364.524882) (xy 287.00038 -364.532707) (xy 286.97301 -364.53318)
			(xy 286.945435 -364.532714) (xy 286.890862 -364.524763) (xy 286.838002 -364.509038) (xy 286.787956 -364.485868)
			(xy 286.741766 -364.455735) (xy 286.700396 -364.419267) (xy 286.68218 -364.39856) (xy 286.674588 -364.390431)
			(xy 286.654428 -364.381084) (xy 286.643318 -364.380526) (xy 286.566102 -364.380526) (xy 286.554989 -364.381071)
			(xy 286.53483 -364.390425) (xy 286.52724 -364.39856) (xy 286.509002 -364.419247) (xy 286.46764 -364.455721)
			(xy 286.421456 -364.485857) (xy 286.371413 -364.509027) (xy 286.318555 -364.524748) (xy 286.263983 -364.532693)
			(xy 286.23641 -364.53318) (xy 286.20904 -364.532713) (xy 286.154861 -364.524896) (xy 286.102357 -364.509408)
			(xy 286.05261 -364.486566) (xy 286.006644 -364.456841) (xy 285.985712 -364.4392) (xy 285.9786 -364.433104)
			(xy 285.961582 -364.426754) (xy 285.876238 -364.426754) (xy 285.85922 -364.433104) (xy 285.852108 -364.4392)
			(xy 285.831184 -364.456849) (xy 285.785209 -364.486559) (xy 285.735459 -364.509393) (xy 285.682957 -364.524882)
			(xy 285.62878 -364.532707) (xy 285.60141 -364.53318) (xy 285.574156 -364.532735) (xy 285.520203 -364.524979)
			(xy 285.467903 -364.509623) (xy 285.418321 -364.486979) (xy 285.372467 -364.45751) (xy 285.331273 -364.421814)
			(xy 285.295579 -364.380619) (xy 285.266112 -364.334763) (xy 285.243471 -364.28518) (xy 285.228117 -364.232879)
			(xy 285.220363 -364.178926) (xy 285.219902 -364.151672) (xy 285.220351 -364.124301) (xy 285.228173 -364.070121)
			(xy 285.243666 -364.017618) (xy 285.266511 -363.967871) (xy 285.296239 -363.921905) (xy 285.313882 -363.900974)
			(xy 285.319978 -363.893862) (xy 285.326328 -363.876844) (xy 285.326328 -363.7915) (xy 285.319978 -363.774482)
			(xy 285.313882 -363.76737) (xy 285.296216 -363.746459) (xy 285.266496 -363.700486) (xy 285.243655 -363.650736)
			(xy 285.228162 -363.598231) (xy 285.220337 -363.54405) (xy 285.22034 -363.489308) (xy 285.228171 -363.435128)
			(xy 285.243669 -363.382625) (xy 285.266516 -363.332877) (xy 285.296241 -363.286908) (xy 285.313882 -363.265974)
			(xy 285.319978 -363.258862) (xy 285.326328 -363.241844) (xy 285.326328 -363.1565) (xy 285.319978 -363.139482)
			(xy 285.313882 -363.13237) (xy 285.296216 -363.111459) (xy 285.266496 -363.065486) (xy 285.243655 -363.015736)
			(xy 285.228162 -362.963231) (xy 285.220337 -362.90905) (xy 285.22034 -362.854308) (xy 285.228171 -362.800128)
			(xy 285.243669 -362.747625) (xy 285.266516 -362.697877) (xy 285.296241 -362.651908) (xy 285.313882 -362.630974)
			(xy 285.319978 -362.623862) (xy 285.326328 -362.606844) (xy 285.326328 -362.5215) (xy 285.319978 -362.504482)
			(xy 285.313882 -362.49737) (xy 285.296259 -362.476425) (xy 285.266546 -362.430455) (xy 285.243707 -362.380711)
			(xy 285.228212 -362.328213) (xy 285.220379 -362.27404) (xy 285.219902 -362.246672) (xy 285.22044 -362.217398)
			(xy 285.22941 -362.159539) (xy 285.247118 -362.103732) (xy 285.273149 -362.051288) (xy 285.306891 -362.003439)
			(xy 285.326836 -361.982004) (xy 285.333948 -361.974638) (xy 285.34106 -361.956096) (xy 285.33979 -361.864148)
			(xy 285.331916 -361.84586) (xy 285.32455 -361.838748) (xy 285.306706 -361.820753) (xy 285.275478 -361.780839)
			(xy 285.24981 -361.73714) (xy 285.230155 -361.690428) (xy 285.216858 -361.641525) (xy 285.210153 -361.591291)
			(xy 285.209742 -361.565952) (xy 280.848816 -361.565952) (xy 283.925264 -364.6424) (xy 300.398432 -364.6424)
			(xy 300.402503 -364.586778) (xy 300.414629 -364.532341) (xy 300.434552 -364.48025) (xy 300.461848 -364.431615)
			(xy 300.495934 -364.387472) (xy 300.536083 -364.348763) (xy 300.581441 -364.316312) (xy 300.631041 -364.290811)
			(xy 300.683825 -364.272804) (xy 300.738668 -364.262674) (xy 300.794402 -364.260637) (xy 300.849839 -364.266737)
			(xy 300.903796 -364.280843) (xy 300.955125 -364.302655) (xy 301.002731 -364.331709) (xy 301.045599 -364.367384)
			(xy 301.082816 -364.408921) (xy 301.113589 -364.455434) (xy 301.137261 -364.505931) (xy 301.153329 -364.559338)
			(xy 301.161449 -364.614514) (xy 301.161958 -364.6424) (xy 301.161449 -364.670286) (xy 301.153329 -364.725462)
			(xy 301.137261 -364.778869) (xy 301.113589 -364.829366) (xy 301.082816 -364.875879) (xy 301.045599 -364.917416)
			(xy 301.002731 -364.953091) (xy 300.955125 -364.982145) (xy 300.903796 -365.003957) (xy 300.849839 -365.018063)
			(xy 300.794402 -365.024163) (xy 300.738668 -365.022126) (xy 300.683825 -365.011996) (xy 300.631041 -364.993989)
			(xy 300.581441 -364.968488) (xy 300.536083 -364.936037) (xy 300.495934 -364.897328) (xy 300.461848 -364.853185)
			(xy 300.434552 -364.80455) (xy 300.414629 -364.752459) (xy 300.402503 -364.698022) (xy 300.398432 -364.6424)
			(xy 283.925264 -364.6424) (xy 284.407864 -365.125) (xy 302.893982 -365.125) (xy 302.898053 -365.069378)
			(xy 302.910179 -365.014941) (xy 302.930102 -364.96285) (xy 302.957398 -364.914215) (xy 302.991484 -364.870072)
			(xy 303.031633 -364.831363) (xy 303.076991 -364.798912) (xy 303.126591 -364.773411) (xy 303.179375 -364.755404)
			(xy 303.234218 -364.745274) (xy 303.289952 -364.743237) (xy 303.345389 -364.749337) (xy 303.399346 -364.763443)
			(xy 303.450675 -364.785255) (xy 303.498281 -364.814309) (xy 303.541149 -364.849984) (xy 303.578366 -364.891521)
			(xy 303.609139 -364.938034) (xy 303.632811 -364.988531) (xy 303.648879 -365.041938) (xy 303.656999 -365.097114)
			(xy 303.657508 -365.125) (xy 305.190142 -365.125) (xy 305.194213 -365.069378) (xy 305.206339 -365.014941)
			(xy 305.226262 -364.96285) (xy 305.253558 -364.914215) (xy 305.287644 -364.870072) (xy 305.327793 -364.831363)
			(xy 305.373151 -364.798912) (xy 305.422751 -364.773411) (xy 305.475535 -364.755404) (xy 305.530378 -364.745274)
			(xy 305.586112 -364.743237) (xy 305.641549 -364.749337) (xy 305.695506 -364.763443) (xy 305.746835 -364.785255)
			(xy 305.794441 -364.814309) (xy 305.837309 -364.849984) (xy 305.874526 -364.891521) (xy 305.878979 -364.898251)
			(xy 306.984378 -364.898251) (xy 306.984378 -364.843749) (xy 306.992134 -364.789801) (xy 307.007489 -364.737506)
			(xy 307.030131 -364.687929) (xy 307.059597 -364.642079) (xy 307.095288 -364.600888) (xy 307.136479 -364.565197)
			(xy 307.182329 -364.535731) (xy 307.231906 -364.513089) (xy 307.284201 -364.497734) (xy 307.338149 -364.489978)
			(xy 307.3654 -364.489492) (xy 307.391858 -364.489953) (xy 307.444268 -364.497261) (xy 307.495166 -364.511736)
			(xy 307.543578 -364.533102) (xy 307.566314 -364.546642) (xy 307.579346 -364.554087) (xy 307.608341 -364.561787)
			(xy 307.638322 -364.56074) (xy 307.666709 -364.551035) (xy 307.691056 -364.533507) (xy 307.709267 -364.509668)
			(xy 307.719774 -364.481568) (xy 307.721254 -364.466632) (xy 307.723585 -364.437914) (xy 307.735709 -364.381591)
			(xy 307.756165 -364.327731) (xy 307.78449 -364.277561) (xy 307.820038 -364.232222) (xy 307.862001 -364.192745)
			(xy 307.909424 -364.160029) (xy 307.961228 -364.134817) (xy 308.016235 -364.117684) (xy 308.073193 -364.109019)
			(xy 308.102 -364.108492) (xy 308.129251 -364.108978) (xy 308.183199 -364.116734) (xy 308.235494 -364.132089)
			(xy 308.285071 -364.154731) (xy 308.330921 -364.184197) (xy 308.372112 -364.219888) (xy 308.407803 -364.261079)
			(xy 308.437269 -364.306929) (xy 308.459911 -364.356506) (xy 308.475266 -364.408801) (xy 308.483022 -364.462749)
			(xy 308.483022 -364.517251) (xy 308.475266 -364.571199) (xy 308.459911 -364.623494) (xy 308.437269 -364.673071)
			(xy 308.407803 -364.718921) (xy 308.386073 -364.744) (xy 309.370982 -364.744) (xy 309.375053 -364.688378)
			(xy 309.387179 -364.633941) (xy 309.407102 -364.58185) (xy 309.434398 -364.533215) (xy 309.468484 -364.489072)
			(xy 309.508633 -364.450363) (xy 309.553991 -364.417912) (xy 309.603591 -364.392411) (xy 309.656375 -364.374404)
			(xy 309.711218 -364.364274) (xy 309.766952 -364.362237) (xy 309.822389 -364.368337) (xy 309.876346 -364.382443)
			(xy 309.927675 -364.404255) (xy 309.975281 -364.433309) (xy 310.018149 -364.468984) (xy 310.055366 -364.510521)
			(xy 310.086139 -364.557034) (xy 310.109811 -364.607531) (xy 310.125879 -364.660938) (xy 310.133999 -364.716114)
			(xy 310.134508 -364.744) (xy 310.133999 -364.771886) (xy 310.125879 -364.827062) (xy 310.109811 -364.880469)
			(xy 310.086139 -364.930966) (xy 310.055366 -364.977479) (xy 310.0256 -365.0107) (xy 314.463682 -365.0107)
			(xy 314.467753 -364.955078) (xy 314.479879 -364.900641) (xy 314.499802 -364.84855) (xy 314.527098 -364.799915)
			(xy 314.561184 -364.755772) (xy 314.601333 -364.717063) (xy 314.646691 -364.684612) (xy 314.696291 -364.659111)
			(xy 314.749075 -364.641104) (xy 314.803918 -364.630974) (xy 314.859652 -364.628937) (xy 314.915089 -364.635037)
			(xy 314.969046 -364.649143) (xy 315.020375 -364.670955) (xy 315.067981 -364.700009) (xy 315.110849 -364.735684)
			(xy 315.148066 -364.777221) (xy 315.178839 -364.823734) (xy 315.202511 -364.874231) (xy 315.218579 -364.927638)
			(xy 315.226699 -364.982814) (xy 315.227208 -365.0107) (xy 315.226699 -365.038586) (xy 315.218579 -365.093762)
			(xy 315.202511 -365.147169) (xy 315.178839 -365.197666) (xy 315.148066 -365.244179) (xy 315.110849 -365.285716)
			(xy 315.067981 -365.321391) (xy 315.020375 -365.350445) (xy 314.969046 -365.372257) (xy 314.915089 -365.386363)
			(xy 314.859652 -365.392463) (xy 314.803918 -365.390426) (xy 314.749075 -365.380296) (xy 314.696291 -365.362289)
			(xy 314.646691 -365.336788) (xy 314.601333 -365.304337) (xy 314.561184 -365.265628) (xy 314.527098 -365.221485)
			(xy 314.499802 -365.17285) (xy 314.479879 -365.120759) (xy 314.467753 -365.066322) (xy 314.463682 -365.0107)
			(xy 310.0256 -365.0107) (xy 310.018149 -365.019016) (xy 309.975281 -365.054691) (xy 309.927675 -365.083745)
			(xy 309.876346 -365.105557) (xy 309.822389 -365.119663) (xy 309.766952 -365.125763) (xy 309.711218 -365.123726)
			(xy 309.656375 -365.113596) (xy 309.603591 -365.095589) (xy 309.553991 -365.070088) (xy 309.508633 -365.037637)
			(xy 309.468484 -364.998928) (xy 309.434398 -364.954785) (xy 309.407102 -364.90615) (xy 309.387179 -364.854059)
			(xy 309.375053 -364.799622) (xy 309.370982 -364.744) (xy 308.386073 -364.744) (xy 308.372112 -364.760112)
			(xy 308.330921 -364.795803) (xy 308.285071 -364.825269) (xy 308.235494 -364.847911) (xy 308.183199 -364.863266)
			(xy 308.129251 -364.871022) (xy 308.102 -364.871508) (xy 308.075542 -364.871047) (xy 308.023132 -364.863739)
			(xy 307.972234 -364.849264) (xy 307.923822 -364.827898) (xy 307.901086 -364.814358) (xy 307.888054 -364.806913)
			(xy 307.859059 -364.799213) (xy 307.829078 -364.80026) (xy 307.800691 -364.809965) (xy 307.776344 -364.827493)
			(xy 307.758133 -364.851332) (xy 307.747626 -364.879432) (xy 307.746146 -364.894368) (xy 307.743815 -364.923086)
			(xy 307.731691 -364.979409) (xy 307.711235 -365.033269) (xy 307.68291 -365.083439) (xy 307.647362 -365.128778)
			(xy 307.605399 -365.168255) (xy 307.557976 -365.200971) (xy 307.506172 -365.226183) (xy 307.451165 -365.243316)
			(xy 307.394207 -365.251981) (xy 307.3654 -365.252508) (xy 307.338149 -365.252022) (xy 307.284201 -365.244266)
			(xy 307.231906 -365.228911) (xy 307.182329 -365.206269) (xy 307.136479 -365.176803) (xy 307.095288 -365.141112)
			(xy 307.059597 -365.099921) (xy 307.030131 -365.054071) (xy 307.007489 -365.004494) (xy 306.992134 -364.952199)
			(xy 306.984378 -364.898251) (xy 305.878979 -364.898251) (xy 305.905299 -364.938034) (xy 305.928971 -364.988531)
			(xy 305.945039 -365.041938) (xy 305.953159 -365.097114) (xy 305.953668 -365.125) (xy 305.953159 -365.152886)
			(xy 305.945039 -365.208062) (xy 305.928971 -365.261469) (xy 305.905299 -365.311966) (xy 305.874526 -365.358479)
			(xy 305.837309 -365.400016) (xy 305.794441 -365.435691) (xy 305.746835 -365.464745) (xy 305.695506 -365.486557)
			(xy 305.641549 -365.500663) (xy 305.586112 -365.506763) (xy 305.530378 -365.504726) (xy 305.475535 -365.494596)
			(xy 305.422751 -365.476589) (xy 305.373151 -365.451088) (xy 305.327793 -365.418637) (xy 305.287644 -365.379928)
			(xy 305.253558 -365.335785) (xy 305.226262 -365.28715) (xy 305.206339 -365.235059) (xy 305.194213 -365.180622)
			(xy 305.190142 -365.125) (xy 303.657508 -365.125) (xy 303.656999 -365.152886) (xy 303.648879 -365.208062)
			(xy 303.632811 -365.261469) (xy 303.609139 -365.311966) (xy 303.578366 -365.358479) (xy 303.541149 -365.400016)
			(xy 303.498281 -365.435691) (xy 303.450675 -365.464745) (xy 303.399346 -365.486557) (xy 303.345389 -365.500663)
			(xy 303.289952 -365.506763) (xy 303.234218 -365.504726) (xy 303.179375 -365.494596) (xy 303.126591 -365.476589)
			(xy 303.076991 -365.451088) (xy 303.031633 -365.418637) (xy 302.991484 -365.379928) (xy 302.957398 -365.335785)
			(xy 302.930102 -365.28715) (xy 302.910179 -365.235059) (xy 302.898053 -365.180622) (xy 302.893982 -365.125)
			(xy 284.407864 -365.125) (xy 284.570424 -365.28756) (xy 284.577904 -365.294255) (xy 284.596464 -365.301844)
			(xy 284.606492 -365.302292) (xy 299.420788 -365.302292) (xy 299.445785 -365.302915) (xy 299.494809 -365.31272)
			(xy 299.54098 -365.331897) (xy 299.582525 -365.35971) (xy 299.60062 -365.376968) (xy 299.983652 -365.76)
			(xy 307.059582 -365.76) (xy 307.063653 -365.704378) (xy 307.075779 -365.649941) (xy 307.095702 -365.59785)
			(xy 307.122998 -365.549215) (xy 307.157084 -365.505072) (xy 307.197233 -365.466363) (xy 307.242591 -365.433912)
			(xy 307.292191 -365.408411) (xy 307.344975 -365.390404) (xy 307.399818 -365.380274) (xy 307.455552 -365.378237)
			(xy 307.510989 -365.384337) (xy 307.564946 -365.398443) (xy 307.616275 -365.420255) (xy 307.663881 -365.449309)
			(xy 307.706749 -365.484984) (xy 307.743966 -365.526521) (xy 307.774739 -365.573034) (xy 307.798411 -365.623531)
			(xy 307.814479 -365.676938) (xy 307.819227 -365.7092) (xy 308.202582 -365.7092) (xy 308.206653 -365.653578)
			(xy 308.218779 -365.599141) (xy 308.238702 -365.54705) (xy 308.265998 -365.498415) (xy 308.300084 -365.454272)
			(xy 308.340233 -365.415563) (xy 308.385591 -365.383112) (xy 308.435191 -365.357611) (xy 308.487975 -365.339604)
			(xy 308.542818 -365.329474) (xy 308.598552 -365.327437) (xy 308.653989 -365.333537) (xy 308.707946 -365.347643)
			(xy 308.759275 -365.369455) (xy 308.806881 -365.398509) (xy 308.849749 -365.434184) (xy 308.868579 -365.4552)
			(xy 309.96458 -365.4552) (xy 309.968651 -365.399578) (xy 309.980777 -365.345141) (xy 310.0007 -365.29305)
			(xy 310.027996 -365.244415) (xy 310.062082 -365.200272) (xy 310.102231 -365.161563) (xy 310.147589 -365.129112)
			(xy 310.197189 -365.103611) (xy 310.249973 -365.085604) (xy 310.304816 -365.075474) (xy 310.36055 -365.073437)
			(xy 310.415987 -365.079537) (xy 310.469944 -365.093643) (xy 310.521273 -365.115455) (xy 310.568879 -365.144509)
			(xy 310.611747 -365.180184) (xy 310.648964 -365.221721) (xy 310.679737 -365.268234) (xy 310.703409 -365.318731)
			(xy 310.719477 -365.372138) (xy 310.727597 -365.427314) (xy 310.728106 -365.4552) (xy 310.727597 -365.483086)
			(xy 310.719477 -365.538262) (xy 310.703409 -365.591669) (xy 310.679737 -365.642166) (xy 310.648964 -365.688679)
			(xy 310.611747 -365.730216) (xy 310.568879 -365.765891) (xy 310.521273 -365.794945) (xy 310.469944 -365.816757)
			(xy 310.415987 -365.830863) (xy 310.36055 -365.836963) (xy 310.304816 -365.834926) (xy 310.249973 -365.824796)
			(xy 310.197189 -365.806789) (xy 310.147589 -365.781288) (xy 310.102231 -365.748837) (xy 310.062082 -365.710128)
			(xy 310.027996 -365.665985) (xy 310.0007 -365.61735) (xy 309.980777 -365.565259) (xy 309.968651 -365.510822)
			(xy 309.96458 -365.4552) (xy 308.868579 -365.4552) (xy 308.886966 -365.475721) (xy 308.917739 -365.522234)
			(xy 308.941411 -365.572731) (xy 308.957479 -365.626138) (xy 308.965599 -365.681314) (xy 308.966108 -365.7092)
			(xy 308.965599 -365.737086) (xy 308.957479 -365.792262) (xy 308.941411 -365.845669) (xy 308.917739 -365.896166)
			(xy 308.886966 -365.942679) (xy 308.849749 -365.984216) (xy 308.806881 -366.019891) (xy 308.759275 -366.048945)
			(xy 308.707946 -366.070757) (xy 308.653989 -366.084863) (xy 308.598552 -366.090963) (xy 308.542818 -366.088926)
			(xy 308.487975 -366.078796) (xy 308.435191 -366.060789) (xy 308.385591 -366.035288) (xy 308.340233 -366.002837)
			(xy 308.300084 -365.964128) (xy 308.265998 -365.919985) (xy 308.238702 -365.87135) (xy 308.218779 -365.819259)
			(xy 308.206653 -365.764822) (xy 308.202582 -365.7092) (xy 307.819227 -365.7092) (xy 307.822599 -365.732114)
			(xy 307.823108 -365.76) (xy 307.822599 -365.787886) (xy 307.814479 -365.843062) (xy 307.798411 -365.896469)
			(xy 307.774739 -365.946966) (xy 307.743966 -365.993479) (xy 307.706749 -366.035016) (xy 307.663881 -366.070691)
			(xy 307.616275 -366.099745) (xy 307.564946 -366.121557) (xy 307.510989 -366.135663) (xy 307.455552 -366.141763)
			(xy 307.399818 -366.139726) (xy 307.344975 -366.129596) (xy 307.292191 -366.111589) (xy 307.242591 -366.086088)
			(xy 307.197233 -366.053637) (xy 307.157084 -366.014928) (xy 307.122998 -365.970785) (xy 307.095702 -365.92215)
			(xy 307.075779 -365.870059) (xy 307.063653 -365.815622) (xy 307.059582 -365.76) (xy 299.983652 -365.76)
			(xy 300.618652 -366.395) (xy 302.893982 -366.395) (xy 302.898053 -366.339378) (xy 302.910179 -366.284941)
			(xy 302.930102 -366.23285) (xy 302.957398 -366.184215) (xy 302.991484 -366.140072) (xy 303.031633 -366.101363)
			(xy 303.076991 -366.068912) (xy 303.126591 -366.043411) (xy 303.179375 -366.025404) (xy 303.234218 -366.015274)
			(xy 303.289952 -366.013237) (xy 303.345389 -366.019337) (xy 303.399346 -366.033443) (xy 303.450675 -366.055255)
			(xy 303.498281 -366.084309) (xy 303.541149 -366.119984) (xy 303.578366 -366.161521) (xy 303.609139 -366.208034)
			(xy 303.632811 -366.258531) (xy 303.63566 -366.268) (xy 311.951876 -366.268) (xy 311.955947 -366.212378)
			(xy 311.968073 -366.157941) (xy 311.987996 -366.10585) (xy 312.015292 -366.057215) (xy 312.049378 -366.013072)
			(xy 312.089527 -365.974363) (xy 312.134885 -365.941912) (xy 312.184485 -365.916411) (xy 312.237269 -365.898404)
			(xy 312.292112 -365.888274) (xy 312.347846 -365.886237) (xy 312.403283 -365.892337) (xy 312.45724 -365.906443)
			(xy 312.508569 -365.928255) (xy 312.556175 -365.957309) (xy 312.599043 -365.992984) (xy 312.63626 -366.034521)
			(xy 312.667033 -366.081034) (xy 312.690705 -366.131531) (xy 312.706773 -366.184938) (xy 312.714893 -366.240114)
			(xy 312.715402 -366.268) (xy 312.714893 -366.295886) (xy 312.706773 -366.351062) (xy 312.690705 -366.404469)
			(xy 312.667033 -366.454966) (xy 312.63626 -366.501479) (xy 312.599043 -366.543016) (xy 312.556175 -366.578691)
			(xy 312.508569 -366.607745) (xy 312.45724 -366.629557) (xy 312.403283 -366.643663) (xy 312.347846 -366.649763)
			(xy 312.292112 -366.647726) (xy 312.237269 -366.637596) (xy 312.184485 -366.619589) (xy 312.134885 -366.594088)
			(xy 312.089527 -366.561637) (xy 312.049378 -366.522928) (xy 312.015292 -366.478785) (xy 311.987996 -366.43015)
			(xy 311.968073 -366.378059) (xy 311.955947 -366.323622) (xy 311.951876 -366.268) (xy 303.63566 -366.268)
			(xy 303.648879 -366.311938) (xy 303.656999 -366.367114) (xy 303.657508 -366.395) (xy 303.656999 -366.422886)
			(xy 303.648879 -366.478062) (xy 303.632811 -366.531469) (xy 303.609139 -366.581966) (xy 303.578366 -366.628479)
			(xy 303.541149 -366.670016) (xy 303.498281 -366.705691) (xy 303.450675 -366.734745) (xy 303.399346 -366.756557)
			(xy 303.345389 -366.770663) (xy 303.289952 -366.776763) (xy 303.234218 -366.774726) (xy 303.179375 -366.764596)
			(xy 303.126591 -366.746589) (xy 303.076991 -366.721088) (xy 303.031633 -366.688637) (xy 302.991484 -366.649928)
			(xy 302.957398 -366.605785) (xy 302.930102 -366.55715) (xy 302.910179 -366.505059) (xy 302.898053 -366.450622)
			(xy 302.893982 -366.395) (xy 300.618652 -366.395) (xy 301.075852 -366.8522) (xy 311.072782 -366.8522)
			(xy 311.076853 -366.796578) (xy 311.088979 -366.742141) (xy 311.108902 -366.69005) (xy 311.136198 -366.641415)
			(xy 311.170284 -366.597272) (xy 311.210433 -366.558563) (xy 311.255791 -366.526112) (xy 311.305391 -366.500611)
			(xy 311.358175 -366.482604) (xy 311.413018 -366.472474) (xy 311.468752 -366.470437) (xy 311.524189 -366.476537)
			(xy 311.578146 -366.490643) (xy 311.629475 -366.512455) (xy 311.677081 -366.541509) (xy 311.719949 -366.577184)
			(xy 311.757166 -366.618721) (xy 311.787939 -366.665234) (xy 311.811611 -366.715731) (xy 311.827679 -366.769138)
			(xy 311.835799 -366.824314) (xy 311.836308 -366.8522) (xy 311.835799 -366.880086) (xy 311.827679 -366.935262)
			(xy 311.811611 -366.988669) (xy 311.787939 -367.039166) (xy 311.757166 -367.085679) (xy 311.719949 -367.127216)
			(xy 311.677081 -367.162891) (xy 311.629475 -367.191945) (xy 311.578146 -367.213757) (xy 311.524189 -367.227863)
			(xy 311.468752 -367.233963) (xy 311.413018 -367.231926) (xy 311.358175 -367.221796) (xy 311.305391 -367.203789)
			(xy 311.255791 -367.178288) (xy 311.210433 -367.145837) (xy 311.170284 -367.107128) (xy 311.136198 -367.062985)
			(xy 311.108902 -367.01435) (xy 311.088979 -366.962259) (xy 311.076853 -366.907822) (xy 311.072782 -366.8522)
			(xy 301.075852 -366.8522) (xy 301.888652 -367.665) (xy 302.893982 -367.665) (xy 302.898053 -367.609378)
			(xy 302.910179 -367.554941) (xy 302.930102 -367.50285) (xy 302.957398 -367.454215) (xy 302.991484 -367.410072)
			(xy 303.031633 -367.371363) (xy 303.076991 -367.338912) (xy 303.126591 -367.313411) (xy 303.179375 -367.295404)
			(xy 303.234218 -367.285274) (xy 303.289952 -367.283237) (xy 303.345389 -367.289337) (xy 303.399346 -367.303443)
			(xy 303.450675 -367.325255) (xy 303.498281 -367.354309) (xy 303.50536 -367.3602) (xy 310.183782 -367.3602)
			(xy 310.187853 -367.304578) (xy 310.199979 -367.250141) (xy 310.219902 -367.19805) (xy 310.247198 -367.149415)
			(xy 310.281284 -367.105272) (xy 310.321433 -367.066563) (xy 310.366791 -367.034112) (xy 310.416391 -367.008611)
			(xy 310.469175 -366.990604) (xy 310.524018 -366.980474) (xy 310.579752 -366.978437) (xy 310.635189 -366.984537)
			(xy 310.689146 -366.998643) (xy 310.740475 -367.020455) (xy 310.788081 -367.049509) (xy 310.830949 -367.085184)
			(xy 310.868166 -367.126721) (xy 310.898939 -367.173234) (xy 310.922611 -367.223731) (xy 310.938679 -367.277138)
			(xy 310.946799 -367.332314) (xy 310.947308 -367.3602) (xy 310.946799 -367.388086) (xy 310.938679 -367.443262)
			(xy 310.922611 -367.496669) (xy 310.898939 -367.547166) (xy 310.868166 -367.593679) (xy 310.830949 -367.635216)
			(xy 310.788081 -367.670891) (xy 310.740475 -367.699945) (xy 310.689146 -367.721757) (xy 310.635189 -367.735863)
			(xy 310.579752 -367.741963) (xy 310.524018 -367.739926) (xy 310.469175 -367.729796) (xy 310.416391 -367.711789)
			(xy 310.366791 -367.686288) (xy 310.321433 -367.653837) (xy 310.281284 -367.615128) (xy 310.247198 -367.570985)
			(xy 310.219902 -367.52235) (xy 310.199979 -367.470259) (xy 310.187853 -367.415822) (xy 310.183782 -367.3602)
			(xy 303.50536 -367.3602) (xy 303.541149 -367.389984) (xy 303.578366 -367.431521) (xy 303.609139 -367.478034)
			(xy 303.632811 -367.528531) (xy 303.648879 -367.581938) (xy 303.656999 -367.637114) (xy 303.657508 -367.665)
			(xy 303.656999 -367.692886) (xy 303.648879 -367.748062) (xy 303.632811 -367.801469) (xy 303.609139 -367.851966)
			(xy 303.578366 -367.898479) (xy 303.541149 -367.940016) (xy 303.498281 -367.975691) (xy 303.450675 -368.004745)
			(xy 303.399346 -368.026557) (xy 303.345389 -368.040663) (xy 303.289952 -368.046763) (xy 303.234218 -368.044726)
			(xy 303.179375 -368.034596) (xy 303.126591 -368.016589) (xy 303.076991 -367.991088) (xy 303.031633 -367.958637)
			(xy 302.991484 -367.919928) (xy 302.957398 -367.875785) (xy 302.930102 -367.82715) (xy 302.910179 -367.775059)
			(xy 302.898053 -367.720622) (xy 302.893982 -367.665) (xy 301.888652 -367.665) (xy 302.295052 -368.0714)
			(xy 309.548782 -368.0714) (xy 309.552853 -368.015778) (xy 309.564979 -367.961341) (xy 309.584902 -367.90925)
			(xy 309.612198 -367.860615) (xy 309.646284 -367.816472) (xy 309.686433 -367.777763) (xy 309.731791 -367.745312)
			(xy 309.781391 -367.719811) (xy 309.834175 -367.701804) (xy 309.889018 -367.691674) (xy 309.944752 -367.689637)
			(xy 310.000189 -367.695737) (xy 310.054146 -367.709843) (xy 310.105475 -367.731655) (xy 310.153081 -367.760709)
			(xy 310.195949 -367.796384) (xy 310.233166 -367.837921) (xy 310.263939 -367.884434) (xy 310.287611 -367.934931)
			(xy 310.303679 -367.988338) (xy 310.311799 -368.043514) (xy 310.312308 -368.0714) (xy 310.311799 -368.099286)
			(xy 310.303679 -368.154462) (xy 310.287611 -368.207869) (xy 310.263939 -368.258366) (xy 310.233166 -368.304879)
			(xy 310.195949 -368.346416) (xy 310.153081 -368.382091) (xy 310.105475 -368.411145) (xy 310.054146 -368.432957)
			(xy 310.000189 -368.447063) (xy 309.944752 -368.453163) (xy 309.889018 -368.451126) (xy 309.834175 -368.440996)
			(xy 309.781391 -368.422989) (xy 309.731791 -368.397488) (xy 309.686433 -368.365037) (xy 309.646284 -368.326328)
			(xy 309.612198 -368.282185) (xy 309.584902 -368.23355) (xy 309.564979 -368.181459) (xy 309.552853 -368.127022)
			(xy 309.548782 -368.0714) (xy 302.295052 -368.0714) (xy 302.914812 -368.69116) (xy 302.922296 -368.697849)
			(xy 302.940853 -368.705442) (xy 302.95088 -368.705892) (xy 312.59272 -368.705892) (xy 312.602764 -368.705509)
			(xy 312.62136 -368.697929) (xy 312.628788 -368.69116) (xy 316.26556 -365.054388) (xy 316.272249 -365.046904)
			(xy 316.279842 -365.028347) (xy 316.280292 -365.01832) (xy 316.280292 -357.098092) (xy 316.279903 -357.088049)
			(xy 316.272328 -357.069453) (xy 316.26556 -357.062024) (xy 316.081664 -356.878128) (xy 316.063122 -356.870508)
			(xy 316.052708 -356.870508) (xy 316.025431 -356.870079) (xy 315.971426 -356.862381) (xy 315.919067 -356.847069)
			(xy 315.869423 -356.824455) (xy 315.823506 -356.795001) (xy 315.782252 -356.759307) (xy 315.746504 -356.718101)
			(xy 315.716988 -356.672224) (xy 315.694309 -356.62261) (xy 315.678927 -356.570272) (xy 315.671157 -356.516276)
			(xy 315.670692 -356.489) (xy 315.671156 -356.461736) (xy 315.678919 -356.407762) (xy 315.694288 -356.355444)
			(xy 315.716949 -356.305847) (xy 315.746441 -356.259982) (xy 315.782162 -356.218782) (xy 315.823385 -356.183089)
			(xy 315.86927 -356.153627) (xy 315.918882 -356.130999) (xy 315.971211 -356.115665) (xy 316.025189 -356.107938)
			(xy 316.079718 -356.107974) (xy 316.133686 -356.115774) (xy 316.185994 -356.131177) (xy 316.235576 -356.153871)
			(xy 316.281422 -356.183393) (xy 316.322597 -356.219142) (xy 316.358264 -356.260389) (xy 316.387694 -356.306294)
			(xy 316.410289 -356.355921) (xy 316.425588 -356.408259) (xy 316.43328 -356.462243) (xy 316.433708 -356.489508)
			(xy 316.433708 -356.499922) (xy 316.441328 -356.518464) (xy 316.679834 -356.75697) (xy 316.687281 -356.763658)
			(xy 316.705777 -356.771254) (xy 316.725773 -356.771254) (xy 316.744269 -356.763658) (xy 316.751716 -356.75697)
			(xy 317.009272 -356.499414) (xy 317.016892 -356.480872) (xy 317.016892 -356.470458) (xy 317.017274 -356.44318)
			(xy 317.024979 -356.389173) (xy 317.040297 -356.336813) (xy 317.062917 -356.287169) (xy 317.092376 -356.241252)
			(xy 317.128075 -356.199999) (xy 317.169285 -356.164251) (xy 317.215166 -356.134736) (xy 317.264783 -356.112057)
			(xy 317.317124 -356.096676) (xy 317.371123 -356.088906) (xy 317.3984 -356.088442) (xy 317.425661 -356.089006)
			(xy 317.479627 -356.096768) (xy 317.531938 -356.112135) (xy 317.581529 -356.134793) (xy 317.627388 -356.164281)
			(xy 317.668582 -356.199998) (xy 317.704271 -356.241215) (xy 317.733729 -356.287094) (xy 317.756354 -356.3367)
			(xy 317.771686 -356.389021) (xy 317.779412 -356.442993) (xy 317.779376 -356.497515) (xy 317.771578 -356.551476)
			(xy 317.756176 -356.603777) (xy 317.733485 -356.653352) (xy 317.703966 -356.699192) (xy 317.668222 -356.740362)
			(xy 317.626981 -356.776024) (xy 317.581082 -356.80545) (xy 317.531462 -356.828042) (xy 317.47913 -356.84334)
			(xy 317.425153 -356.85103) (xy 317.397892 -356.851458) (xy 317.387478 -356.851458) (xy 317.368936 -356.859078)
			(xy 317.18504 -357.042974) (xy 317.178323 -357.050437) (xy 317.170747 -357.06901) (xy 317.170308 -357.079042)
			(xy 317.170308 -359.029) (xy 317.905382 -359.029) (xy 317.909453 -358.973378) (xy 317.921579 -358.918941)
			(xy 317.941502 -358.86685) (xy 317.968798 -358.818215) (xy 318.002884 -358.774072) (xy 318.043033 -358.735363)
			(xy 318.088391 -358.702912) (xy 318.137991 -358.677411) (xy 318.190775 -358.659404) (xy 318.245618 -358.649274)
			(xy 318.301352 -358.647237) (xy 318.356789 -358.653337) (xy 318.410746 -358.667443) (xy 318.462075 -358.689255)
			(xy 318.509681 -358.718309) (xy 318.552549 -358.753984) (xy 318.589766 -358.795521) (xy 318.620539 -358.842034)
			(xy 318.644211 -358.892531) (xy 318.660279 -358.945938) (xy 318.668399 -359.001114) (xy 318.668908 -359.029)
			(xy 318.668399 -359.056886) (xy 318.661737 -359.102152) (xy 335.533238 -359.102152) (xy 335.533763 -359.074042)
			(xy 335.542002 -359.018429) (xy 335.558308 -358.964625) (xy 335.582329 -358.913795) (xy 335.613546 -358.867038)
			(xy 335.632044 -358.845866) (xy 335.638648 -358.838754) (xy 335.645252 -358.82199) (xy 335.646522 -358.736138)
			(xy 335.640426 -358.71912) (xy 335.63433 -358.711754) (xy 335.61724 -358.690976) (xy 335.58848 -358.645509)
			(xy 335.566395 -358.596451) (xy 335.551422 -358.544777) (xy 335.54386 -358.491512) (xy 335.543398 -358.464612)
			(xy 335.543867 -358.437359) (xy 335.551622 -358.383408) (xy 335.566977 -358.33111) (xy 335.589618 -358.28153)
			(xy 335.619086 -358.235676) (xy 335.654779 -358.194483) (xy 335.695971 -358.158789) (xy 335.741824 -358.129321)
			(xy 335.791404 -358.106679) (xy 335.843702 -358.091323) (xy 335.897653 -358.083567) (xy 335.924906 -358.083104)
			(xy 335.953823 -358.083617) (xy 336.010995 -358.092347) (xy 336.066194 -358.109606) (xy 336.118155 -358.134998)
			(xy 336.165689 -358.167943) (xy 336.207706 -358.207684) (xy 336.225896 -358.23017) (xy 336.233452 -358.238937)
			(xy 336.254216 -358.249115) (xy 336.265774 -358.249728) (xy 336.346038 -358.249728) (xy 336.357605 -358.249147)
			(xy 336.378378 -358.238962) (xy 336.385916 -358.23017) (xy 336.402669 -358.209387) (xy 336.441023 -358.172257)
			(xy 336.484177 -358.140835) (xy 336.531291 -358.115736) (xy 336.581443 -358.09745) (xy 336.633654 -358.086333)
			(xy 336.686906 -358.082603) (xy 336.740158 -358.086333) (xy 336.792369 -358.09745) (xy 336.842521 -358.115736)
			(xy 336.889635 -358.140835) (xy 336.932789 -358.172257) (xy 336.971143 -358.209387) (xy 336.987896 -358.23017)
			(xy 336.995452 -358.238937) (xy 337.016216 -358.249115) (xy 337.027774 -358.249728) (xy 337.108038 -358.249728)
			(xy 337.119605 -358.249147) (xy 337.140378 -358.238962) (xy 337.147916 -358.23017) (xy 337.16609 -358.207673)
			(xy 337.208115 -358.16794) (xy 337.255653 -358.135003) (xy 337.307618 -358.109617) (xy 337.362818 -358.092364)
			(xy 337.419989 -358.083638) (xy 337.448906 -358.083104) (xy 337.477834 -358.083626) (xy 337.535025 -358.092383)
			(xy 337.590236 -358.109678) (xy 337.642201 -358.135116) (xy 337.689727 -358.168113) (xy 337.731722 -358.207911)
			(xy 337.749896 -358.230424) (xy 337.757262 -358.239568) (xy 337.777582 -358.249728) (xy 337.880452 -358.251252)
			(xy 337.90128 -358.2416) (xy 337.908646 -358.232456) (xy 337.915758 -358.224074) (xy 337.921854 -358.216962)
			(xy 337.928204 -358.199944) (xy 337.928204 -358.1146) (xy 337.921854 -358.097582) (xy 337.915758 -358.09047)
			(xy 337.898131 -358.069528) (xy 337.868419 -358.023557) (xy 337.845581 -357.973812) (xy 337.830087 -357.921314)
			(xy 337.822254 -357.86714) (xy 337.821778 -357.839772) (xy 337.822252 -357.812521) (xy 337.830012 -357.758573)
			(xy 337.84537 -357.706279) (xy 337.868013 -357.656703) (xy 337.897481 -357.610853) (xy 337.933174 -357.569664)
			(xy 337.974364 -357.533973) (xy 338.020215 -357.504506) (xy 338.069792 -357.481865) (xy 338.122087 -357.466509)
			(xy 338.176035 -357.458751) (xy 338.203286 -357.458264) (xy 338.232204 -357.458768) (xy 338.289377 -357.467497)
			(xy 338.344577 -357.484756) (xy 338.396539 -357.51015) (xy 338.444072 -357.543097) (xy 338.486087 -357.582842)
			(xy 338.504276 -357.60533) (xy 338.511847 -357.614082) (xy 338.532599 -357.62427) (xy 338.544154 -357.624888)
			(xy 338.624418 -357.624888) (xy 338.635988 -357.624332) (xy 338.656759 -357.614128) (xy 338.664296 -357.60533)
			(xy 338.681049 -357.584547) (xy 338.719403 -357.547417) (xy 338.762557 -357.515995) (xy 338.809671 -357.490896)
			(xy 338.859823 -357.47261) (xy 338.912034 -357.461493) (xy 338.965286 -357.457763) (xy 339.018538 -357.461493)
			(xy 339.070749 -357.47261) (xy 339.120901 -357.490896) (xy 339.168015 -357.515995) (xy 339.211169 -357.547417)
			(xy 339.249523 -357.584547) (xy 339.266276 -357.60533) (xy 339.273847 -357.614082) (xy 339.294599 -357.62427)
			(xy 339.306154 -357.624888) (xy 339.386418 -357.624888) (xy 339.397988 -357.624332) (xy 339.418759 -357.614128)
			(xy 339.426296 -357.60533) (xy 339.444497 -357.582855) (xy 339.486514 -357.543118) (xy 339.534046 -357.510177)
			(xy 339.586006 -357.484787) (xy 339.641202 -357.467529) (xy 339.69837 -357.458799) (xy 339.727286 -357.458264)
			(xy 339.754536 -357.458791) (xy 339.80848 -357.466545) (xy 339.860773 -357.481897) (xy 339.910348 -357.504534)
			(xy 339.956197 -357.533997) (xy 339.997386 -357.569684) (xy 340.033078 -357.610869) (xy 340.062545 -357.656715)
			(xy 340.085188 -357.706288) (xy 340.100546 -357.758579) (xy 340.108306 -357.812522) (xy 340.108794 -357.839772)
			(xy 340.108313 -357.867142) (xy 340.100499 -357.92132) (xy 340.085013 -357.973823) (xy 340.062175 -358.02357)
			(xy 340.032454 -358.069538) (xy 340.030165 -358.072254) (xy 340.314959 -358.072254) (xy 340.314959 -358.017746)
			(xy 340.322717 -357.963791) (xy 340.338075 -357.911491) (xy 340.360721 -357.861908) (xy 340.390192 -357.816054)
			(xy 340.42589 -357.77486) (xy 340.467087 -357.739167) (xy 340.512945 -357.709701) (xy 340.56253 -357.687061)
			(xy 340.614833 -357.671708) (xy 340.668787 -357.663956) (xy 340.696042 -357.663496) (xy 340.723411 -357.663997)
			(xy 340.777589 -357.671807) (xy 340.830091 -357.687288) (xy 340.879839 -357.710121) (xy 340.925807 -357.739838)
			(xy 340.94674 -357.757476) (xy 340.953852 -357.763572) (xy 340.97087 -357.769922) (xy 341.056214 -357.769922)
			(xy 341.073232 -357.763572) (xy 341.080344 -357.757476) (xy 341.101277 -357.739835) (xy 341.147245 -357.710111)
			(xy 341.196991 -357.687265) (xy 341.249493 -357.671769) (xy 341.303671 -357.66394) (xy 341.358413 -357.66394)
			(xy 341.412591 -357.671769) (xy 341.465093 -357.687265) (xy 341.514839 -357.710111) (xy 341.560807 -357.739835)
			(xy 341.58174 -357.757476) (xy 341.588852 -357.763572) (xy 341.60587 -357.769922) (xy 341.691214 -357.769922)
			(xy 341.708232 -357.763572) (xy 341.715344 -357.757476) (xy 341.736277 -357.739835) (xy 341.782245 -357.710111)
			(xy 341.831991 -357.687265) (xy 341.884493 -357.671769) (xy 341.938671 -357.66394) (xy 341.993413 -357.66394)
			(xy 342.047591 -357.671769) (xy 342.100093 -357.687265) (xy 342.149839 -357.710111) (xy 342.195807 -357.739835)
			(xy 342.21674 -357.757476) (xy 342.223852 -357.763572) (xy 342.24087 -357.769922) (xy 342.326214 -357.769922)
			(xy 342.343232 -357.763572) (xy 342.350344 -357.757476) (xy 342.371283 -357.739846) (xy 342.417254 -357.710134)
			(xy 342.467 -357.687296) (xy 342.519499 -357.671803) (xy 342.573673 -357.663972) (xy 342.601042 -357.663496)
			(xy 342.628292 -357.663977) (xy 342.682235 -357.671738) (xy 342.734526 -357.687097) (xy 342.784098 -357.709741)
			(xy 342.829944 -357.739209) (xy 342.871129 -357.7749) (xy 342.906817 -357.81609) (xy 342.936279 -357.861939)
			(xy 342.958918 -357.911514) (xy 342.974271 -357.963806) (xy 342.982026 -358.01775) (xy 342.982026 -358.07225)
			(xy 342.974271 -358.126194) (xy 342.958918 -358.178486) (xy 342.936279 -358.228061) (xy 342.906817 -358.27391)
			(xy 342.871129 -358.3151) (xy 342.829944 -358.350791) (xy 342.784098 -358.380259) (xy 342.734526 -358.402903)
			(xy 342.682235 -358.418262) (xy 342.628292 -358.426023) (xy 342.601042 -358.426512) (xy 342.573673 -358.426018)
			(xy 342.519495 -358.418207) (xy 342.466992 -358.402724) (xy 342.417245 -358.379888) (xy 342.371277 -358.35017)
			(xy 342.350344 -358.332532) (xy 342.343232 -358.326436) (xy 342.326214 -358.320086) (xy 342.24087 -358.320086)
			(xy 342.223852 -358.326436) (xy 342.21674 -358.332532) (xy 342.195807 -358.350173) (xy 342.149839 -358.379897)
			(xy 342.100093 -358.402743) (xy 342.047591 -358.418239) (xy 341.993413 -358.426068) (xy 341.938671 -358.426068)
			(xy 341.884493 -358.418239) (xy 341.831991 -358.402743) (xy 341.782245 -358.379897) (xy 341.736277 -358.350173)
			(xy 341.715344 -358.332532) (xy 341.708232 -358.326436) (xy 341.691214 -358.320086) (xy 341.60587 -358.320086)
			(xy 341.588852 -358.326436) (xy 341.58174 -358.332532) (xy 341.560807 -358.350173) (xy 341.514839 -358.379897)
			(xy 341.465093 -358.402743) (xy 341.412591 -358.418239) (xy 341.358413 -358.426068) (xy 341.303671 -358.426068)
			(xy 341.249493 -358.418239) (xy 341.196991 -358.402743) (xy 341.147245 -358.379897) (xy 341.101277 -358.350173)
			(xy 341.080344 -358.332532) (xy 341.073232 -358.326436) (xy 341.056214 -358.320086) (xy 340.97087 -358.320086)
			(xy 340.953852 -358.326436) (xy 340.94674 -358.332532) (xy 340.925808 -358.350171) (xy 340.879835 -358.379882)
			(xy 340.830087 -358.402717) (xy 340.777587 -358.418208) (xy 340.723411 -358.426037) (xy 340.696042 -358.426512)
			(xy 340.668787 -358.426044) (xy 340.614833 -358.418292) (xy 340.56253 -358.402939) (xy 340.512945 -358.380299)
			(xy 340.467087 -358.350833) (xy 340.42589 -358.31514) (xy 340.390192 -358.273946) (xy 340.360721 -358.228092)
			(xy 340.338075 -358.178509) (xy 340.322717 -358.126209) (xy 340.314959 -358.072254) (xy 340.030165 -358.072254)
			(xy 340.014814 -358.09047) (xy 340.008718 -358.097582) (xy 340.002368 -358.1146) (xy 340.002368 -358.199944)
			(xy 340.008718 -358.216962) (xy 340.014814 -358.224074) (xy 340.032457 -358.245003) (xy 340.062167 -358.290977)
			(xy 340.085002 -358.340725) (xy 340.100493 -358.393227) (xy 340.10832 -358.447403) (xy 340.108794 -358.474772)
			(xy 340.1083 -358.502884) (xy 340.100057 -358.558499) (xy 340.083744 -358.612304) (xy 340.059716 -358.663133)
			(xy 340.02849 -358.709888) (xy 340.009988 -358.731058) (xy 340.003384 -358.73817) (xy 339.99678 -358.754934)
			(xy 339.99551 -358.840786) (xy 340.001606 -358.857804) (xy 340.007702 -358.86517) (xy 340.024793 -358.885948)
			(xy 340.053555 -358.931414) (xy 340.075641 -358.980471) (xy 340.090613 -359.032146) (xy 340.098173 -359.085412)
			(xy 340.098634 -359.112312) (xy 340.098109 -359.141265) (xy 340.089351 -359.198505) (xy 340.072036 -359.253762)
			(xy 340.046565 -359.305765) (xy 340.013522 -359.353319) (xy 339.993986 -359.374694) (xy 339.987128 -359.38206)
			(xy 339.980016 -359.400348) (xy 339.981286 -359.491534) (xy 339.988906 -359.509568) (xy 339.996018 -359.51668)
			(xy 340.004582 -359.525305) (xy 340.020722 -359.543481) (xy 340.028276 -359.553002) (xy 340.035852 -359.561749)
			(xy 340.0566 -359.57194) (xy 340.068154 -359.57256) (xy 340.148418 -359.57256) (xy 340.159989 -359.572014)
			(xy 340.180761 -359.561803) (xy 340.188296 -359.553002) (xy 340.206705 -359.530327) (xy 340.249229 -359.490296)
			(xy 340.29736 -359.457215) (xy 340.323424 -359.444036) (xy 340.332822 -359.439464) (xy 340.346284 -359.423716)
			(xy 340.37524 -359.3338) (xy 340.373462 -359.313226) (xy 340.368382 -359.304082) (xy 340.353844 -359.27595)
			(xy 340.333234 -359.216076) (xy 340.322781 -359.153624) (xy 340.322154 -359.121964) (xy 340.322644 -359.094714)
			(xy 340.330405 -359.040768) (xy 340.345762 -358.988476) (xy 340.368405 -358.938901) (xy 340.397871 -358.893052)
			(xy 340.433562 -358.851864) (xy 340.474751 -358.816173) (xy 340.520599 -358.786706) (xy 340.570174 -358.764063)
			(xy 340.622466 -358.748705) (xy 340.676412 -358.740944) (xy 340.703662 -358.740456) (xy 340.731032 -358.740931)
			(xy 340.785211 -358.748744) (xy 340.837715 -358.764231) (xy 340.887462 -358.787071) (xy 340.933429 -358.816795)
			(xy 340.95436 -358.834436) (xy 340.961472 -358.840532) (xy 340.97849 -358.846882) (xy 341.063834 -358.846882)
			(xy 341.080852 -358.840532) (xy 341.087964 -358.834436) (xy 341.108897 -358.816795) (xy 341.154865 -358.787071)
			(xy 341.204611 -358.764225) (xy 341.257113 -358.748729) (xy 341.311291 -358.7409) (xy 341.366033 -358.7409)
			(xy 341.420211 -358.748729) (xy 341.472713 -358.764225) (xy 341.522459 -358.787071) (xy 341.568427 -358.816795)
			(xy 341.58936 -358.834436) (xy 341.596472 -358.840532) (xy 341.61349 -358.846882) (xy 341.698834 -358.846882)
			(xy 341.715852 -358.840532) (xy 341.722964 -358.834436) (xy 341.743897 -358.816795) (xy 341.789865 -358.787071)
			(xy 341.839611 -358.764225) (xy 341.892113 -358.748729) (xy 341.946291 -358.7409) (xy 342.001033 -358.7409)
			(xy 342.055211 -358.748729) (xy 342.107713 -358.764225) (xy 342.157459 -358.787071) (xy 342.203427 -358.816795)
			(xy 342.22436 -358.834436) (xy 342.231472 -358.840532) (xy 342.24849 -358.846882) (xy 342.333834 -358.846882)
			(xy 342.350852 -358.840532) (xy 342.357964 -358.834436) (xy 342.378903 -358.816806) (xy 342.424874 -358.787091)
			(xy 342.474619 -358.764253) (xy 342.527118 -358.74876) (xy 342.581293 -358.740931) (xy 342.608662 -358.740456)
			(xy 342.635912 -358.740991) (xy 342.689859 -358.748741) (xy 342.742153 -358.764091) (xy 342.791731 -358.786726)
			(xy 342.837582 -358.816187) (xy 342.878774 -358.851873) (xy 342.914469 -358.893058) (xy 342.943938 -358.938904)
			(xy 342.966583 -358.988477) (xy 342.981943 -359.040769) (xy 342.989704 -359.094714) (xy 342.99017 -359.121964)
			(xy 342.989735 -359.147938) (xy 342.982694 -359.199406) (xy 342.968738 -359.249444) (xy 342.948123 -359.297126)
			(xy 342.935052 -359.319576) (xy 342.929718 -359.328212) (xy 342.92667 -359.348278) (xy 342.949276 -359.43794)
			(xy 342.961214 -359.454196) (xy 342.970104 -359.45953) (xy 342.990317 -359.47195) (xy 343.027799 -359.501031)
			(xy 343.061396 -359.534525) (xy 343.076276 -359.553002) (xy 343.083852 -359.561749) (xy 343.1046 -359.57194)
			(xy 343.116154 -359.57256) (xy 343.196418 -359.57256) (xy 343.207989 -359.572014) (xy 343.228761 -359.561803)
			(xy 343.236296 -359.553002) (xy 343.243109 -359.544383) (xy 343.257596 -359.527862) (xy 343.265252 -359.519982)
			(xy 343.272364 -359.512616) (xy 343.279984 -359.494328) (xy 343.279984 -359.402888) (xy 343.272364 -359.3846)
			(xy 343.265252 -359.377234) (xy 343.244854 -359.3557) (xy 343.210314 -359.307482) (xy 343.183653 -359.254498)
			(xy 343.165516 -359.198027) (xy 343.156339 -359.139428) (xy 343.155778 -359.109772) (xy 343.156209 -359.0824)
			(xy 343.164032 -359.028219) (xy 343.179528 -358.975715) (xy 343.202379 -358.925968) (xy 343.232112 -358.880004)
			(xy 343.249758 -358.859074) (xy 343.255854 -358.851962) (xy 343.262204 -358.834944) (xy 343.262204 -358.7496)
			(xy 343.255854 -358.732582) (xy 343.249758 -358.72547) (xy 343.232089 -358.70456) (xy 343.202363 -358.658589)
			(xy 343.179517 -358.608839) (xy 343.164022 -358.556333) (xy 343.156195 -358.502151) (xy 343.156198 -358.447407)
			(xy 343.164031 -358.393225) (xy 343.179532 -358.340721) (xy 343.202383 -358.290974) (xy 343.232114 -358.245006)
			(xy 343.249758 -358.224074) (xy 343.255854 -358.216962) (xy 343.262204 -358.199944) (xy 343.262204 -358.1146)
			(xy 343.255854 -358.097582) (xy 343.249758 -358.09047) (xy 343.232131 -358.069528) (xy 343.202419 -358.023557)
			(xy 343.179581 -357.973812) (xy 343.164087 -357.921314) (xy 343.156254 -357.86714) (xy 343.155778 -357.839772)
			(xy 343.156252 -357.812521) (xy 343.164012 -357.758573) (xy 343.17937 -357.706279) (xy 343.202013 -357.656703)
			(xy 343.231481 -357.610853) (xy 343.267174 -357.569664) (xy 343.308364 -357.533973) (xy 343.354215 -357.504506)
			(xy 343.403792 -357.481865) (xy 343.456087 -357.466509) (xy 343.510035 -357.458751) (xy 343.537286 -357.458264)
			(xy 343.566204 -357.458768) (xy 343.623377 -357.467497) (xy 343.678577 -357.484756) (xy 343.730539 -357.51015)
			(xy 343.778072 -357.543097) (xy 343.820087 -357.582842) (xy 343.838276 -357.60533) (xy 343.845847 -357.614082)
			(xy 343.866599 -357.62427) (xy 343.878154 -357.624888) (xy 343.958418 -357.624888) (xy 343.969988 -357.624332)
			(xy 343.990759 -357.614128) (xy 343.998296 -357.60533) (xy 344.015049 -357.584547) (xy 344.053403 -357.547417)
			(xy 344.096557 -357.515995) (xy 344.143671 -357.490896) (xy 344.193823 -357.47261) (xy 344.246034 -357.461493)
			(xy 344.299286 -357.457763) (xy 344.352538 -357.461493) (xy 344.404749 -357.47261) (xy 344.454901 -357.490896)
			(xy 344.502015 -357.515995) (xy 344.545169 -357.547417) (xy 344.583523 -357.584547) (xy 344.600276 -357.60533)
			(xy 344.607847 -357.614082) (xy 344.628599 -357.62427) (xy 344.640154 -357.624888) (xy 344.720418 -357.624888)
			(xy 344.731988 -357.624332) (xy 344.752759 -357.614128) (xy 344.760296 -357.60533) (xy 344.778497 -357.582855)
			(xy 344.820514 -357.543118) (xy 344.868046 -357.510177) (xy 344.920006 -357.484787) (xy 344.975202 -357.467529)
			(xy 345.03237 -357.458799) (xy 345.061286 -357.458264) (xy 345.088536 -357.458791) (xy 345.14248 -357.466545)
			(xy 345.194773 -357.481897) (xy 345.244348 -357.504534) (xy 345.290197 -357.533997) (xy 345.331386 -357.569684)
			(xy 345.367078 -357.610869) (xy 345.396545 -357.656715) (xy 345.419188 -357.706288) (xy 345.434546 -357.758579)
			(xy 345.442306 -357.812522) (xy 345.442794 -357.839772) (xy 345.442313 -357.867142) (xy 345.434499 -357.92132)
			(xy 345.419013 -357.973823) (xy 345.396175 -358.02357) (xy 345.366454 -358.069538) (xy 345.348814 -358.09047)
			(xy 345.342718 -358.097582) (xy 345.336368 -358.1146) (xy 345.336368 -358.199944) (xy 345.342718 -358.216962)
			(xy 345.348814 -358.224074) (xy 345.366426 -358.24503) (xy 345.396148 -358.290995) (xy 345.418993 -358.340737)
			(xy 345.43449 -358.393235) (xy 345.44232 -358.44741) (xy 345.442323 -358.502148) (xy 345.434499 -358.556323)
			(xy 345.419008 -358.608823) (xy 345.396169 -358.658568) (xy 345.366451 -358.704536) (xy 345.348814 -358.72547)
			(xy 345.342718 -358.732582) (xy 345.336368 -358.7496) (xy 345.336368 -358.834944) (xy 345.342718 -358.851962)
			(xy 345.348814 -358.859074) (xy 345.366457 -358.880003) (xy 345.396167 -358.925977) (xy 345.419002 -358.975725)
			(xy 345.434493 -359.028227) (xy 345.44232 -359.082403) (xy 345.442794 -359.109772) (xy 345.442239 -359.139428)
			(xy 345.433051 -359.198023) (xy 345.414908 -359.254492) (xy 345.388247 -359.307474) (xy 345.35371 -359.355693)
			(xy 345.33332 -359.377234) (xy 345.326208 -359.3846) (xy 345.318588 -359.402888) (xy 345.318588 -359.494328)
			(xy 345.326208 -359.512616) (xy 345.33332 -359.519982) (xy 345.353721 -359.541514) (xy 345.388262 -359.589732)
			(xy 345.414922 -359.642716) (xy 345.433059 -359.699188) (xy 345.442234 -359.757787) (xy 345.442794 -359.787444)
			(xy 345.442363 -359.814697) (xy 345.4346 -359.868647) (xy 345.419239 -359.920944) (xy 345.396592 -359.970522)
			(xy 345.367119 -360.016373) (xy 345.331422 -360.057563) (xy 345.290227 -360.093254) (xy 345.244371 -360.122719)
			(xy 345.19479 -360.145359) (xy 345.142491 -360.160713) (xy 345.088539 -360.168467) (xy 345.061286 -360.168952)
			(xy 345.03237 -360.16839) (xy 344.975201 -360.159673) (xy 344.920002 -360.142424) (xy 344.86804 -360.117041)
			(xy 344.820505 -360.084104) (xy 344.778487 -360.044369) (xy 344.760296 -360.021886) (xy 344.752734 -360.013125)
			(xy 344.731975 -360.002942) (xy 344.720418 -360.002328) (xy 344.640154 -360.002328) (xy 344.628589 -360.00292)
			(xy 344.607817 -360.013098) (xy 344.600276 -360.021886) (xy 344.588084 -360.036618) (xy 344.581988 -360.04373)
			(xy 344.575638 -360.061256) (xy 344.576908 -360.147616) (xy 344.583766 -360.164888) (xy 344.59037 -360.171746)
			(xy 344.609168 -360.19302) (xy 344.640975 -360.240039) (xy 344.665456 -360.291255) (xy 344.682071 -360.345536)
			(xy 344.690451 -360.40168) (xy 344.690954 -360.430064) (xy 344.690388 -360.457312) (xy 344.682638 -360.511255)
			(xy 344.66729 -360.563545) (xy 344.644656 -360.613119) (xy 344.615198 -360.658967) (xy 344.579515 -360.700157)
			(xy 344.538333 -360.735849) (xy 344.492491 -360.765317) (xy 344.442922 -360.787961) (xy 344.390635 -360.803321)
			(xy 344.336694 -360.811083) (xy 344.309446 -360.811572) (xy 344.28053 -360.811031) (xy 344.223359 -360.802308)
			(xy 344.16816 -360.785056) (xy 344.116198 -360.759668) (xy 344.068664 -360.726728) (xy 344.026646 -360.68699)
			(xy 344.008456 -360.664506) (xy 344.000908 -360.65573) (xy 343.980139 -360.645554) (xy 343.968578 -360.644948)
			(xy 343.888314 -360.644948) (xy 343.876745 -360.64551) (xy 343.855973 -360.655709) (xy 343.848436 -360.664506)
			(xy 343.836244 -360.679492) (xy 343.830148 -360.68635) (xy 343.823798 -360.703876) (xy 343.824814 -360.789728)
			(xy 343.831418 -360.807) (xy 343.837768 -360.814112) (xy 343.856251 -360.835263) (xy 343.887441 -360.881978)
			(xy 343.911455 -360.932756) (xy 343.927775 -360.986503) (xy 343.936051 -361.04206) (xy 343.936574 -361.070144)
			(xy 343.936163 -361.097398) (xy 343.9284 -361.15135) (xy 343.913037 -361.203648) (xy 343.890388 -361.253228)
			(xy 343.860914 -361.29908) (xy 343.825215 -361.34027) (xy 343.784017 -361.375961) (xy 343.738159 -361.405426)
			(xy 343.688575 -361.428064) (xy 343.636274 -361.443416) (xy 343.58232 -361.451169) (xy 343.555066 -361.451652)
			(xy 343.52615 -361.451104) (xy 343.468979 -361.442384) (xy 343.41378 -361.425133) (xy 343.361818 -361.399747)
			(xy 343.314284 -361.366807) (xy 343.272267 -361.32707) (xy 343.254076 -361.304586) (xy 343.246522 -361.295816)
			(xy 343.225757 -361.285637) (xy 343.214198 -361.285028) (xy 343.133934 -361.285028) (xy 343.122367 -361.285608)
			(xy 343.101596 -361.295795) (xy 343.094056 -361.304586) (xy 343.077303 -361.325369) (xy 343.038949 -361.362499)
			(xy 342.995795 -361.393921) (xy 342.948681 -361.41902) (xy 342.898529 -361.437306) (xy 342.846318 -361.448423)
			(xy 342.793066 -361.452153) (xy 342.739814 -361.448423) (xy 342.687603 -361.437306) (xy 342.637451 -361.41902)
			(xy 342.590337 -361.393921) (xy 342.547183 -361.362499) (xy 342.508829 -361.325369) (xy 342.492076 -361.304586)
			(xy 342.484522 -361.295816) (xy 342.463757 -361.285637) (xy 342.452198 -361.285028) (xy 342.371934 -361.285028)
			(xy 342.360367 -361.285608) (xy 342.339596 -361.295795) (xy 342.332056 -361.304586) (xy 342.315303 -361.325369)
			(xy 342.276949 -361.362499) (xy 342.233795 -361.393921) (xy 342.186681 -361.41902) (xy 342.136529 -361.437306)
			(xy 342.084318 -361.448423) (xy 342.031066 -361.452153) (xy 341.977814 -361.448423) (xy 341.925603 -361.437306)
			(xy 341.875451 -361.41902) (xy 341.828337 -361.393921) (xy 341.785183 -361.362499) (xy 341.746829 -361.325369)
			(xy 341.730076 -361.304586) (xy 341.722522 -361.295816) (xy 341.701757 -361.285637) (xy 341.690198 -361.285028)
			(xy 341.609934 -361.285028) (xy 341.598367 -361.285608) (xy 341.577596 -361.295795) (xy 341.570056 -361.304586)
			(xy 341.553303 -361.325369) (xy 341.514949 -361.362499) (xy 341.471795 -361.393921) (xy 341.424681 -361.41902)
			(xy 341.374529 -361.437306) (xy 341.322318 -361.448423) (xy 341.269066 -361.452153) (xy 341.215814 -361.448423)
			(xy 341.163603 -361.437306) (xy 341.113451 -361.41902) (xy 341.066337 -361.393921) (xy 341.023183 -361.362499)
			(xy 340.984829 -361.325369) (xy 340.968076 -361.304586) (xy 340.960522 -361.295816) (xy 340.939757 -361.285637)
			(xy 340.928198 -361.285028) (xy 340.847934 -361.285028) (xy 340.836367 -361.285608) (xy 340.815596 -361.295795)
			(xy 340.808056 -361.304586) (xy 340.791303 -361.325369) (xy 340.752949 -361.362499) (xy 340.709795 -361.393921)
			(xy 340.662681 -361.41902) (xy 340.612529 -361.437306) (xy 340.560318 -361.448423) (xy 340.507066 -361.452153)
			(xy 340.453814 -361.448423) (xy 340.401603 -361.437306) (xy 340.351451 -361.41902) (xy 340.304337 -361.393921)
			(xy 340.261183 -361.362499) (xy 340.222829 -361.325369) (xy 340.206076 -361.304586) (xy 340.198522 -361.295816)
			(xy 340.177757 -361.285637) (xy 340.166198 -361.285028) (xy 340.085934 -361.285028) (xy 340.074367 -361.285608)
			(xy 340.053596 -361.295795) (xy 340.046056 -361.304586) (xy 340.029303 -361.325369) (xy 339.990949 -361.362499)
			(xy 339.947795 -361.393921) (xy 339.900681 -361.41902) (xy 339.850529 -361.437306) (xy 339.798318 -361.448423)
			(xy 339.745066 -361.452153) (xy 339.691814 -361.448423) (xy 339.639603 -361.437306) (xy 339.589451 -361.41902)
			(xy 339.542337 -361.393921) (xy 339.499183 -361.362499) (xy 339.460829 -361.325369) (xy 339.444076 -361.304586)
			(xy 339.436522 -361.295816) (xy 339.415757 -361.285637) (xy 339.404198 -361.285028) (xy 339.323934 -361.285028)
			(xy 339.312367 -361.285608) (xy 339.291596 -361.295795) (xy 339.284056 -361.304586) (xy 339.267303 -361.325369)
			(xy 339.228949 -361.362499) (xy 339.185795 -361.393921) (xy 339.138681 -361.41902) (xy 339.088529 -361.437306)
			(xy 339.036318 -361.448423) (xy 338.983066 -361.452153) (xy 338.929814 -361.448423) (xy 338.877603 -361.437306)
			(xy 338.827451 -361.41902) (xy 338.780337 -361.393921) (xy 338.737183 -361.362499) (xy 338.698829 -361.325369)
			(xy 338.682076 -361.304586) (xy 338.674522 -361.295816) (xy 338.653757 -361.285637) (xy 338.642198 -361.285028)
			(xy 338.561934 -361.285028) (xy 338.550367 -361.285608) (xy 338.529596 -361.295795) (xy 338.522056 -361.304586)
			(xy 338.503886 -361.327088) (xy 338.461863 -361.366822) (xy 338.414323 -361.39976) (xy 338.362358 -361.425145)
			(xy 338.307156 -361.442397) (xy 338.249983 -361.45112) (xy 338.221066 -361.451652) (xy 338.192139 -361.451095)
			(xy 338.134949 -361.442348) (xy 338.079737 -361.425061) (xy 338.027772 -361.399629) (xy 337.980246 -361.366638)
			(xy 337.93825 -361.326844) (xy 337.920076 -361.304332) (xy 337.91271 -361.295188) (xy 337.89239 -361.285028)
			(xy 337.78952 -361.283504) (xy 337.768692 -361.293156) (xy 337.761326 -361.3023) (xy 337.743109 -361.323664)
			(xy 337.701484 -361.361338) (xy 337.654786 -361.392503) (xy 337.604023 -361.416485) (xy 337.550294 -361.432766)
			(xy 337.494757 -361.440995) (xy 337.466686 -361.441492) (xy 337.437771 -361.440915) (xy 337.380603 -361.432199)
			(xy 337.325405 -361.414953) (xy 337.273443 -361.389572) (xy 337.225907 -361.356639) (xy 337.183888 -361.316907)
			(xy 337.165696 -361.294426) (xy 337.158144 -361.285654) (xy 337.137377 -361.275479) (xy 337.125818 -361.274868)
			(xy 337.045554 -361.274868) (xy 337.033987 -361.275446) (xy 337.013214 -361.285633) (xy 337.005676 -361.294426)
			(xy 336.988923 -361.315209) (xy 336.950569 -361.352339) (xy 336.907415 -361.383761) (xy 336.860301 -361.40886)
			(xy 336.810149 -361.427146) (xy 336.757938 -361.438263) (xy 336.704686 -361.441993) (xy 336.651434 -361.438263)
			(xy 336.599223 -361.427146) (xy 336.549071 -361.40886) (xy 336.501957 -361.383761) (xy 336.458803 -361.352339)
			(xy 336.420449 -361.315209) (xy 336.403696 -361.294426) (xy 336.396144 -361.285654) (xy 336.375377 -361.275479)
			(xy 336.363818 -361.274868) (xy 336.283554 -361.274868) (xy 336.271987 -361.275446) (xy 336.251214 -361.285633)
			(xy 336.243676 -361.294426) (xy 336.225505 -361.316926) (xy 336.18348 -361.356659) (xy 336.135941 -361.389596)
			(xy 336.083976 -361.414981) (xy 336.028775 -361.432234) (xy 335.971603 -361.440959) (xy 335.942686 -361.441492)
			(xy 335.915432 -361.441058) (xy 335.861479 -361.433299) (xy 335.80918 -361.41794) (xy 335.759598 -361.395295)
			(xy 335.713745 -361.365824) (xy 335.672552 -361.330127) (xy 335.636858 -361.288931) (xy 335.607391 -361.243075)
			(xy 335.584749 -361.193492) (xy 335.569395 -361.141191) (xy 335.56164 -361.087238) (xy 335.561178 -361.059984)
			(xy 335.561627 -361.032788) (xy 335.569312 -360.978943) (xy 335.584579 -360.926739) (xy 335.607118 -360.877238)
			(xy 335.63647 -360.831447) (xy 335.653888 -360.810556) (xy 335.659984 -360.803698) (xy 335.666334 -360.786172)
			(xy 335.665318 -360.70032) (xy 335.658714 -360.683048) (xy 335.652364 -360.675936) (xy 335.633861 -360.654801)
			(xy 335.602673 -360.608082) (xy 335.578663 -360.5573) (xy 335.562347 -360.50355) (xy 335.554077 -360.44799)
			(xy 335.553558 -360.419904) (xy 335.554016 -360.392735) (xy 335.561743 -360.338949) (xy 335.577025 -360.286804)
			(xy 335.599554 -360.237356) (xy 335.628874 -360.191607) (xy 335.646268 -360.17073) (xy 335.652364 -360.163618)
			(xy 335.658714 -360.146092) (xy 335.657444 -360.059732) (xy 335.650586 -360.04246) (xy 335.643982 -360.035602)
			(xy 335.625151 -360.014356) (xy 335.593351 -359.967329) (xy 335.568877 -359.916105) (xy 335.552269 -359.861819)
			(xy 335.543897 -359.805669) (xy 335.543398 -359.777284) (xy 335.543939 -359.748332) (xy 335.552696 -359.691093)
			(xy 335.570008 -359.635837) (xy 335.595475 -359.583834) (xy 335.628512 -359.536279) (xy 335.648046 -359.514902)
			(xy 335.654904 -359.507536) (xy 335.662016 -359.489248) (xy 335.660746 -359.398062) (xy 335.653126 -359.380028)
			(xy 335.646014 -359.372916) (xy 335.625019 -359.351305) (xy 335.589452 -359.302673) (xy 335.561974 -359.249053)
			(xy 335.54327 -359.191779) (xy 335.533803 -359.132277) (xy 335.533238 -359.102152) (xy 318.661737 -359.102152)
			(xy 318.660279 -359.112062) (xy 318.644211 -359.165469) (xy 318.620539 -359.215966) (xy 318.589766 -359.262479)
			(xy 318.552549 -359.304016) (xy 318.509681 -359.339691) (xy 318.462075 -359.368745) (xy 318.410746 -359.390557)
			(xy 318.356789 -359.404663) (xy 318.301352 -359.410763) (xy 318.245618 -359.408726) (xy 318.190775 -359.398596)
			(xy 318.137991 -359.380589) (xy 318.088391 -359.355088) (xy 318.043033 -359.322637) (xy 318.002884 -359.283928)
			(xy 317.968798 -359.239785) (xy 317.941502 -359.19115) (xy 317.921579 -359.139059) (xy 317.909453 -359.084622)
			(xy 317.905382 -359.029) (xy 317.170308 -359.029) (xy 317.170308 -359.918) (xy 319.046858 -359.918)
			(xy 319.050929 -359.862378) (xy 319.063055 -359.807941) (xy 319.082978 -359.75585) (xy 319.110274 -359.707215)
			(xy 319.14436 -359.663072) (xy 319.184509 -359.624363) (xy 319.229867 -359.591912) (xy 319.279467 -359.566411)
			(xy 319.332251 -359.548404) (xy 319.387094 -359.538274) (xy 319.442828 -359.536237) (xy 319.498265 -359.542337)
			(xy 319.552222 -359.556443) (xy 319.603551 -359.578255) (xy 319.651157 -359.607309) (xy 319.694025 -359.642984)
			(xy 319.731242 -359.684521) (xy 319.762015 -359.731034) (xy 319.785687 -359.781531) (xy 319.801755 -359.834938)
			(xy 319.809875 -359.890114) (xy 319.810384 -359.918) (xy 319.809875 -359.945886) (xy 319.801755 -360.001062)
			(xy 319.785687 -360.054469) (xy 319.762015 -360.104966) (xy 319.731242 -360.151479) (xy 319.694025 -360.193016)
			(xy 319.651157 -360.228691) (xy 319.603551 -360.257745) (xy 319.552222 -360.279557) (xy 319.498265 -360.293663)
			(xy 319.442828 -360.299763) (xy 319.387094 -360.297726) (xy 319.332251 -360.287596) (xy 319.279467 -360.269589)
			(xy 319.229867 -360.244088) (xy 319.184509 -360.211637) (xy 319.14436 -360.172928) (xy 319.110274 -360.128785)
			(xy 319.082978 -360.08015) (xy 319.063055 -360.028059) (xy 319.050929 -359.973622) (xy 319.046858 -359.918)
			(xy 317.170308 -359.918) (xy 317.170308 -360.361992) (xy 322.46265 -360.361992) (xy 322.466721 -360.30637)
			(xy 322.478847 -360.251933) (xy 322.49877 -360.199842) (xy 322.526066 -360.151207) (xy 322.560152 -360.107064)
			(xy 322.600301 -360.068355) (xy 322.645659 -360.035904) (xy 322.695259 -360.010403) (xy 322.748043 -359.992396)
			(xy 322.802886 -359.982266) (xy 322.85862 -359.980229) (xy 322.914057 -359.986329) (xy 322.968014 -360.000435)
			(xy 323.019343 -360.022247) (xy 323.066949 -360.051301) (xy 323.109817 -360.086976) (xy 323.147034 -360.128513)
			(xy 323.177807 -360.175026) (xy 323.201479 -360.225523) (xy 323.217547 -360.27893) (xy 323.225667 -360.334106)
			(xy 323.226176 -360.361992) (xy 323.225667 -360.389878) (xy 323.217547 -360.445054) (xy 323.201479 -360.498461)
			(xy 323.177807 -360.548958) (xy 323.147034 -360.595471) (xy 323.109817 -360.637008) (xy 323.066949 -360.672683)
			(xy 323.019343 -360.701737) (xy 322.968014 -360.723549) (xy 322.914057 -360.737655) (xy 322.85862 -360.743755)
			(xy 322.802886 -360.741718) (xy 322.748043 -360.731588) (xy 322.695259 -360.713581) (xy 322.645659 -360.68808)
			(xy 322.600301 -360.655629) (xy 322.560152 -360.61692) (xy 322.526066 -360.572777) (xy 322.49877 -360.524142)
			(xy 322.478847 -360.472051) (xy 322.466721 -360.417614) (xy 322.46265 -360.361992) (xy 317.170308 -360.361992)
			(xy 317.170308 -361.598718) (xy 321.434966 -361.598718) (xy 321.439037 -361.543096) (xy 321.451163 -361.488659)
			(xy 321.471086 -361.436568) (xy 321.498382 -361.387933) (xy 321.532468 -361.34379) (xy 321.572617 -361.305081)
			(xy 321.617975 -361.27263) (xy 321.667575 -361.247129) (xy 321.720359 -361.229122) (xy 321.775202 -361.218992)
			(xy 321.830936 -361.216955) (xy 321.886373 -361.223055) (xy 321.94033 -361.237161) (xy 321.991659 -361.258973)
			(xy 322.039265 -361.288027) (xy 322.082133 -361.323702) (xy 322.11935 -361.365239) (xy 322.150123 -361.411752)
			(xy 322.173795 -361.462249) (xy 322.175345 -361.4674) (xy 326.668382 -361.4674) (xy 326.672453 -361.411778)
			(xy 326.684579 -361.357341) (xy 326.704502 -361.30525) (xy 326.731798 -361.256615) (xy 326.765884 -361.212472)
			(xy 326.806033 -361.173763) (xy 326.851391 -361.141312) (xy 326.900991 -361.115811) (xy 326.953775 -361.097804)
			(xy 327.008618 -361.087674) (xy 327.064352 -361.085637) (xy 327.119789 -361.091737) (xy 327.173746 -361.105843)
			(xy 327.225075 -361.127655) (xy 327.240715 -361.1372) (xy 328.725782 -361.1372) (xy 328.729853 -361.081578)
			(xy 328.741979 -361.027141) (xy 328.761902 -360.97505) (xy 328.789198 -360.926415) (xy 328.823284 -360.882272)
			(xy 328.863433 -360.843563) (xy 328.908791 -360.811112) (xy 328.958391 -360.785611) (xy 329.011175 -360.767604)
			(xy 329.066018 -360.757474) (xy 329.121752 -360.755437) (xy 329.177189 -360.761537) (xy 329.231146 -360.775643)
			(xy 329.282475 -360.797455) (xy 329.330081 -360.826509) (xy 329.372949 -360.862184) (xy 329.410166 -360.903721)
			(xy 329.440939 -360.950234) (xy 329.464611 -361.000731) (xy 329.480679 -361.054138) (xy 329.488799 -361.109314)
			(xy 329.489308 -361.1372) (xy 330.021182 -361.1372) (xy 330.025253 -361.081578) (xy 330.037379 -361.027141)
			(xy 330.057302 -360.97505) (xy 330.084598 -360.926415) (xy 330.118684 -360.882272) (xy 330.158833 -360.843563)
			(xy 330.204191 -360.811112) (xy 330.253791 -360.785611) (xy 330.306575 -360.767604) (xy 330.361418 -360.757474)
			(xy 330.417152 -360.755437) (xy 330.472589 -360.761537) (xy 330.526546 -360.775643) (xy 330.577875 -360.797455)
			(xy 330.625481 -360.826509) (xy 330.668349 -360.862184) (xy 330.705566 -360.903721) (xy 330.736339 -360.950234)
			(xy 330.760011 -361.000731) (xy 330.776079 -361.054138) (xy 330.784199 -361.109314) (xy 330.784708 -361.1372)
			(xy 330.784199 -361.165086) (xy 330.776079 -361.220262) (xy 330.760011 -361.273669) (xy 330.736339 -361.324166)
			(xy 330.705566 -361.370679) (xy 330.668349 -361.412216) (xy 330.625481 -361.447891) (xy 330.577875 -361.476945)
			(xy 330.526546 -361.498757) (xy 330.472589 -361.512863) (xy 330.417152 -361.518963) (xy 330.361418 -361.516926)
			(xy 330.306575 -361.506796) (xy 330.253791 -361.488789) (xy 330.204191 -361.463288) (xy 330.158833 -361.430837)
			(xy 330.118684 -361.392128) (xy 330.084598 -361.347985) (xy 330.057302 -361.29935) (xy 330.037379 -361.247259)
			(xy 330.025253 -361.192822) (xy 330.021182 -361.1372) (xy 329.489308 -361.1372) (xy 329.488799 -361.165086)
			(xy 329.480679 -361.220262) (xy 329.464611 -361.273669) (xy 329.440939 -361.324166) (xy 329.410166 -361.370679)
			(xy 329.372949 -361.412216) (xy 329.330081 -361.447891) (xy 329.282475 -361.476945) (xy 329.231146 -361.498757)
			(xy 329.177189 -361.512863) (xy 329.121752 -361.518963) (xy 329.066018 -361.516926) (xy 329.011175 -361.506796)
			(xy 328.958391 -361.488789) (xy 328.908791 -361.463288) (xy 328.863433 -361.430837) (xy 328.823284 -361.392128)
			(xy 328.789198 -361.347985) (xy 328.761902 -361.29935) (xy 328.741979 -361.247259) (xy 328.729853 -361.192822)
			(xy 328.725782 -361.1372) (xy 327.240715 -361.1372) (xy 327.272681 -361.156709) (xy 327.315549 -361.192384)
			(xy 327.352766 -361.233921) (xy 327.383539 -361.280434) (xy 327.407211 -361.330931) (xy 327.423279 -361.384338)
			(xy 327.431399 -361.439514) (xy 327.431908 -361.4674) (xy 327.431399 -361.495286) (xy 327.423279 -361.550462)
			(xy 327.407211 -361.603869) (xy 327.383539 -361.654366) (xy 327.352766 -361.700879) (xy 327.315549 -361.742416)
			(xy 327.272681 -361.778091) (xy 327.225075 -361.807145) (xy 327.173746 -361.828957) (xy 327.119789 -361.843063)
			(xy 327.064352 -361.849163) (xy 327.008618 -361.847126) (xy 326.953775 -361.836996) (xy 326.900991 -361.818989)
			(xy 326.851391 -361.793488) (xy 326.806033 -361.761037) (xy 326.765884 -361.722328) (xy 326.731798 -361.678185)
			(xy 326.704502 -361.62955) (xy 326.684579 -361.577459) (xy 326.672453 -361.523022) (xy 326.668382 -361.4674)
			(xy 322.175345 -361.4674) (xy 322.189863 -361.515656) (xy 322.197983 -361.570832) (xy 322.198492 -361.598718)
			(xy 322.197983 -361.626604) (xy 322.189863 -361.68178) (xy 322.173795 -361.735187) (xy 322.150123 -361.785684)
			(xy 322.11935 -361.832197) (xy 322.082133 -361.873734) (xy 322.039265 -361.909409) (xy 321.991659 -361.938463)
			(xy 321.94033 -361.960275) (xy 321.886373 -361.974381) (xy 321.830936 -361.980481) (xy 321.775202 -361.978444)
			(xy 321.720359 -361.968314) (xy 321.667575 -361.950307) (xy 321.617975 -361.924806) (xy 321.572617 -361.892355)
			(xy 321.532468 -361.853646) (xy 321.498382 -361.809503) (xy 321.471086 -361.760868) (xy 321.451163 -361.708777)
			(xy 321.439037 -361.65434) (xy 321.434966 -361.598718) (xy 317.170308 -361.598718) (xy 317.170308 -362.788962)
			(xy 320.244722 -362.788962) (xy 320.248793 -362.73334) (xy 320.260919 -362.678903) (xy 320.280842 -362.626812)
			(xy 320.308138 -362.578177) (xy 320.342224 -362.534034) (xy 320.382373 -362.495325) (xy 320.427731 -362.462874)
			(xy 320.477331 -362.437373) (xy 320.530115 -362.419366) (xy 320.584958 -362.409236) (xy 320.640692 -362.407199)
			(xy 320.696129 -362.413299) (xy 320.750086 -362.427405) (xy 320.801415 -362.449217) (xy 320.849021 -362.478271)
			(xy 320.891889 -362.513946) (xy 320.929106 -362.555483) (xy 320.959879 -362.601996) (xy 320.963819 -362.6104)
			(xy 326.668382 -362.6104) (xy 326.672453 -362.554778) (xy 326.684579 -362.500341) (xy 326.704502 -362.44825)
			(xy 326.731798 -362.399615) (xy 326.765884 -362.355472) (xy 326.806033 -362.316763) (xy 326.851391 -362.284312)
			(xy 326.900991 -362.258811) (xy 326.953775 -362.240804) (xy 327.008618 -362.230674) (xy 327.064352 -362.228637)
			(xy 327.119789 -362.234737) (xy 327.173746 -362.248843) (xy 327.225075 -362.270655) (xy 327.272681 -362.299709)
			(xy 327.315549 -362.335384) (xy 327.352766 -362.376921) (xy 327.383539 -362.423434) (xy 327.407211 -362.473931)
			(xy 327.423279 -362.527338) (xy 327.431399 -362.582514) (xy 327.431908 -362.6104) (xy 327.431444 -362.6358)
			(xy 328.801982 -362.6358) (xy 328.806053 -362.580178) (xy 328.818179 -362.525741) (xy 328.838102 -362.47365)
			(xy 328.865398 -362.425015) (xy 328.899484 -362.380872) (xy 328.939633 -362.342163) (xy 328.984991 -362.309712)
			(xy 329.034591 -362.284211) (xy 329.087375 -362.266204) (xy 329.142218 -362.256074) (xy 329.197952 -362.254037)
			(xy 329.253389 -362.260137) (xy 329.307346 -362.274243) (xy 329.358675 -362.296055) (xy 329.406281 -362.325109)
			(xy 329.449149 -362.360784) (xy 329.486366 -362.402321) (xy 329.517139 -362.448834) (xy 329.540811 -362.499331)
			(xy 329.556879 -362.552738) (xy 329.564999 -362.607914) (xy 329.565508 -362.6358) (xy 330.300582 -362.6358)
			(xy 330.304653 -362.580178) (xy 330.316779 -362.525741) (xy 330.336702 -362.47365) (xy 330.363998 -362.425015)
			(xy 330.398084 -362.380872) (xy 330.438233 -362.342163) (xy 330.483591 -362.309712) (xy 330.533191 -362.284211)
			(xy 330.585975 -362.266204) (xy 330.640818 -362.256074) (xy 330.696552 -362.254037) (xy 330.751989 -362.260137)
			(xy 330.805946 -362.274243) (xy 330.857275 -362.296055) (xy 330.904881 -362.325109) (xy 330.947749 -362.360784)
			(xy 330.984966 -362.402321) (xy 331.015739 -362.448834) (xy 331.039411 -362.499331) (xy 331.055479 -362.552738)
			(xy 331.063599 -362.607914) (xy 331.064108 -362.6358) (xy 331.063599 -362.663686) (xy 331.055479 -362.718862)
			(xy 331.039411 -362.772269) (xy 331.015739 -362.822766) (xy 330.984966 -362.869279) (xy 330.947749 -362.910816)
			(xy 330.904881 -362.946491) (xy 330.857275 -362.975545) (xy 330.805946 -362.997357) (xy 330.751989 -363.011463)
			(xy 330.696552 -363.017563) (xy 330.640818 -363.015526) (xy 330.585975 -363.005396) (xy 330.533191 -362.987389)
			(xy 330.483591 -362.961888) (xy 330.438233 -362.929437) (xy 330.398084 -362.890728) (xy 330.363998 -362.846585)
			(xy 330.336702 -362.79795) (xy 330.316779 -362.745859) (xy 330.304653 -362.691422) (xy 330.300582 -362.6358)
			(xy 329.565508 -362.6358) (xy 329.564999 -362.663686) (xy 329.556879 -362.718862) (xy 329.540811 -362.772269)
			(xy 329.517139 -362.822766) (xy 329.486366 -362.869279) (xy 329.449149 -362.910816) (xy 329.406281 -362.946491)
			(xy 329.358675 -362.975545) (xy 329.307346 -362.997357) (xy 329.253389 -363.011463) (xy 329.197952 -363.017563)
			(xy 329.142218 -363.015526) (xy 329.087375 -363.005396) (xy 329.034591 -362.987389) (xy 328.984991 -362.961888)
			(xy 328.939633 -362.929437) (xy 328.899484 -362.890728) (xy 328.865398 -362.846585) (xy 328.838102 -362.79795)
			(xy 328.818179 -362.745859) (xy 328.806053 -362.691422) (xy 328.801982 -362.6358) (xy 327.431444 -362.6358)
			(xy 327.431399 -362.638286) (xy 327.423279 -362.693462) (xy 327.407211 -362.746869) (xy 327.383539 -362.797366)
			(xy 327.352766 -362.843879) (xy 327.315549 -362.885416) (xy 327.272681 -362.921091) (xy 327.225075 -362.950145)
			(xy 327.173746 -362.971957) (xy 327.119789 -362.986063) (xy 327.064352 -362.992163) (xy 327.008618 -362.990126)
			(xy 326.953775 -362.979996) (xy 326.900991 -362.961989) (xy 326.851391 -362.936488) (xy 326.806033 -362.904037)
			(xy 326.765884 -362.865328) (xy 326.731798 -362.821185) (xy 326.704502 -362.77255) (xy 326.684579 -362.720459)
			(xy 326.672453 -362.666022) (xy 326.668382 -362.6104) (xy 320.963819 -362.6104) (xy 320.983551 -362.652493)
			(xy 320.999619 -362.7059) (xy 321.007739 -362.761076) (xy 321.008248 -362.788962) (xy 321.007739 -362.816848)
			(xy 320.999619 -362.872024) (xy 320.983551 -362.925431) (xy 320.959879 -362.975928) (xy 320.929106 -363.022441)
			(xy 320.891889 -363.063978) (xy 320.849021 -363.099653) (xy 320.801415 -363.128707) (xy 320.750086 -363.150519)
			(xy 320.696129 -363.164625) (xy 320.640692 -363.170725) (xy 320.584958 -363.168688) (xy 320.530115 -363.158558)
			(xy 320.477331 -363.140551) (xy 320.427731 -363.11505) (xy 320.382373 -363.082599) (xy 320.342224 -363.04389)
			(xy 320.308138 -362.999747) (xy 320.280842 -362.951112) (xy 320.260919 -362.899021) (xy 320.248793 -362.844584)
			(xy 320.244722 -362.788962) (xy 317.170308 -362.788962) (xy 317.170308 -363.23905) (xy 318.698878 -363.23905)
			(xy 318.702949 -363.183428) (xy 318.715075 -363.128991) (xy 318.734998 -363.0769) (xy 318.762294 -363.028265)
			(xy 318.79638 -362.984122) (xy 318.836529 -362.945413) (xy 318.881887 -362.912962) (xy 318.931487 -362.887461)
			(xy 318.984271 -362.869454) (xy 319.039114 -362.859324) (xy 319.094848 -362.857287) (xy 319.150285 -362.863387)
			(xy 319.204242 -362.877493) (xy 319.255571 -362.899305) (xy 319.303177 -362.928359) (xy 319.346045 -362.964034)
			(xy 319.383262 -363.005571) (xy 319.414035 -363.052084) (xy 319.437707 -363.102581) (xy 319.453775 -363.155988)
			(xy 319.461895 -363.211164) (xy 319.462404 -363.23905) (xy 319.461895 -363.266936) (xy 319.453775 -363.322112)
			(xy 319.437707 -363.375519) (xy 319.414035 -363.426016) (xy 319.383262 -363.472529) (xy 319.346045 -363.514066)
			(xy 319.303177 -363.549741) (xy 319.255571 -363.578795) (xy 319.204242 -363.600607) (xy 319.150285 -363.614713)
			(xy 319.094848 -363.620813) (xy 319.039114 -363.618776) (xy 318.984271 -363.608646) (xy 318.931487 -363.590639)
			(xy 318.881887 -363.565138) (xy 318.836529 -363.532687) (xy 318.79638 -363.493978) (xy 318.762294 -363.449835)
			(xy 318.734998 -363.4012) (xy 318.715075 -363.349109) (xy 318.702949 -363.294672) (xy 318.698878 -363.23905)
			(xy 317.170308 -363.23905) (xy 317.170308 -363.755251) (xy 323.849978 -363.755251) (xy 323.849978 -363.700749)
			(xy 323.857734 -363.646801) (xy 323.873089 -363.594506) (xy 323.895731 -363.544929) (xy 323.925197 -363.499079)
			(xy 323.960888 -363.457888) (xy 324.002079 -363.422197) (xy 324.047929 -363.392731) (xy 324.097506 -363.370089)
			(xy 324.149801 -363.354734) (xy 324.203749 -363.346978) (xy 324.231 -363.346492) (xy 324.260231 -363.347055)
			(xy 324.318006 -363.355987) (xy 324.373743 -363.373627) (xy 324.426137 -363.399561) (xy 324.473962 -363.433183)
			(xy 324.5161 -363.473706) (xy 324.534276 -363.496606) (xy 324.542714 -363.507003) (xy 324.563918 -363.52334)
			(xy 324.588637 -363.533613) (xy 324.615175 -363.537118) (xy 324.641713 -363.533613) (xy 324.666432 -363.52334)
			(xy 324.687636 -363.507003) (xy 324.696074 -363.496606) (xy 324.714223 -363.473681) (xy 324.756356 -363.433141)
			(xy 324.804183 -363.399509) (xy 324.856584 -363.373571) (xy 324.912331 -363.355937) (xy 324.970115 -363.347019)
			(xy 324.99935 -363.346492) (xy 325.026605 -363.346952) (xy 325.080562 -363.354703) (xy 325.132865 -363.370055)
			(xy 325.182452 -363.392694) (xy 325.228311 -363.422161) (xy 325.26951 -363.457855) (xy 325.305209 -363.499049)
			(xy 325.334682 -363.544904) (xy 325.357328 -363.594488) (xy 325.372686 -363.64679) (xy 325.373406 -363.6518)
			(xy 326.693782 -363.6518) (xy 326.697853 -363.596178) (xy 326.709979 -363.541741) (xy 326.729902 -363.48965)
			(xy 326.757198 -363.441015) (xy 326.791284 -363.396872) (xy 326.831433 -363.358163) (xy 326.876791 -363.325712)
			(xy 326.926391 -363.300211) (xy 326.979175 -363.282204) (xy 327.034018 -363.272074) (xy 327.089752 -363.270037)
			(xy 327.145189 -363.276137) (xy 327.199146 -363.290243) (xy 327.250475 -363.312055) (xy 327.298081 -363.341109)
			(xy 327.340949 -363.376784) (xy 327.378166 -363.418321) (xy 327.408939 -363.464834) (xy 327.432611 -363.515331)
			(xy 327.448679 -363.568738) (xy 327.456799 -363.623914) (xy 327.457308 -363.6518) (xy 327.709782 -363.6518)
			(xy 327.713853 -363.596178) (xy 327.725979 -363.541741) (xy 327.745902 -363.48965) (xy 327.773198 -363.441015)
			(xy 327.807284 -363.396872) (xy 327.847433 -363.358163) (xy 327.892791 -363.325712) (xy 327.942391 -363.300211)
			(xy 327.995175 -363.282204) (xy 328.050018 -363.272074) (xy 328.105752 -363.270037) (xy 328.161189 -363.276137)
			(xy 328.215146 -363.290243) (xy 328.266475 -363.312055) (xy 328.314081 -363.341109) (xy 328.356949 -363.376784)
			(xy 328.394166 -363.418321) (xy 328.424939 -363.464834) (xy 328.448611 -363.515331) (xy 328.464679 -363.568738)
			(xy 328.472799 -363.623914) (xy 328.473308 -363.6518) (xy 328.472799 -363.679686) (xy 328.464679 -363.734862)
			(xy 328.448611 -363.788269) (xy 328.424939 -363.838766) (xy 328.394166 -363.885279) (xy 328.356949 -363.926816)
			(xy 328.314081 -363.962491) (xy 328.266475 -363.991545) (xy 328.215146 -364.013357) (xy 328.161189 -364.027463)
			(xy 328.105752 -364.033563) (xy 328.050018 -364.031526) (xy 327.995175 -364.021396) (xy 327.942391 -364.003389)
			(xy 327.892791 -363.977888) (xy 327.847433 -363.945437) (xy 327.807284 -363.906728) (xy 327.773198 -363.862585)
			(xy 327.745902 -363.81395) (xy 327.725979 -363.761859) (xy 327.713853 -363.707422) (xy 327.709782 -363.6518)
			(xy 327.457308 -363.6518) (xy 327.456799 -363.679686) (xy 327.448679 -363.734862) (xy 327.432611 -363.788269)
			(xy 327.408939 -363.838766) (xy 327.378166 -363.885279) (xy 327.340949 -363.926816) (xy 327.298081 -363.962491)
			(xy 327.250475 -363.991545) (xy 327.199146 -364.013357) (xy 327.145189 -364.027463) (xy 327.089752 -364.033563)
			(xy 327.034018 -364.031526) (xy 326.979175 -364.021396) (xy 326.926391 -364.003389) (xy 326.876791 -363.977888)
			(xy 326.831433 -363.945437) (xy 326.791284 -363.906728) (xy 326.757198 -363.862585) (xy 326.729902 -363.81395)
			(xy 326.709979 -363.761859) (xy 326.697853 -363.707422) (xy 326.693782 -363.6518) (xy 325.373406 -363.6518)
			(xy 325.380445 -363.700745) (xy 325.380445 -363.755255) (xy 325.372686 -363.80921) (xy 325.357328 -363.861512)
			(xy 325.334682 -363.911096) (xy 325.305209 -363.956951) (xy 325.26951 -363.998145) (xy 325.228311 -364.033839)
			(xy 325.182452 -364.063306) (xy 325.132865 -364.085945) (xy 325.080562 -364.101297) (xy 325.026605 -364.109048)
			(xy 324.99935 -364.109508) (xy 324.970118 -364.108981) (xy 324.912341 -364.100041) (xy 324.856604 -364.082395)
			(xy 324.80421 -364.056454) (xy 324.756385 -364.022825) (xy 324.714249 -363.982296) (xy 324.696074 -363.959394)
			(xy 324.687663 -363.948953) (xy 324.666477 -363.932535) (xy 324.641745 -363.922206) (xy 324.615175 -363.918682)
			(xy 324.588605 -363.922206) (xy 324.563873 -363.932535) (xy 324.542687 -363.948953) (xy 324.534276 -363.959394)
			(xy 324.516077 -363.982276) (xy 324.473954 -364.022814) (xy 324.426136 -364.056447) (xy 324.373744 -364.082387)
			(xy 324.318007 -364.100025) (xy 324.260231 -364.108949) (xy 324.231 -364.109508) (xy 324.203749 -364.109022)
			(xy 324.149801 -364.101266) (xy 324.097506 -364.085911) (xy 324.047929 -364.063269) (xy 324.002079 -364.033803)
			(xy 323.960888 -363.998112) (xy 323.925197 -363.956921) (xy 323.895731 -363.911071) (xy 323.873089 -363.861494)
			(xy 323.857734 -363.809199) (xy 323.849978 -363.755251) (xy 317.170308 -363.755251) (xy 317.170308 -364.363)
			(xy 318.794382 -364.363) (xy 318.798453 -364.307378) (xy 318.810579 -364.252941) (xy 318.830502 -364.20085)
			(xy 318.857798 -364.152215) (xy 318.891884 -364.108072) (xy 318.932033 -364.069363) (xy 318.977391 -364.036912)
			(xy 319.026991 -364.011411) (xy 319.079775 -363.993404) (xy 319.134618 -363.983274) (xy 319.190352 -363.981237)
			(xy 319.245789 -363.987337) (xy 319.299746 -364.001443) (xy 319.351075 -364.023255) (xy 319.398681 -364.052309)
			(xy 319.441549 -364.087984) (xy 319.478766 -364.129521) (xy 319.509539 -364.176034) (xy 319.533211 -364.226531)
			(xy 319.549279 -364.279938) (xy 319.557399 -364.335114) (xy 319.557908 -364.363) (xy 319.557399 -364.390886)
			(xy 319.549279 -364.446062) (xy 319.533211 -364.499469) (xy 319.509539 -364.549966) (xy 319.478766 -364.596479)
			(xy 319.441549 -364.638016) (xy 319.398681 -364.673691) (xy 319.351075 -364.702745) (xy 319.299746 -364.724557)
			(xy 319.245789 -364.738663) (xy 319.190352 -364.744763) (xy 319.134618 -364.742726) (xy 319.079775 -364.732596)
			(xy 319.026991 -364.714589) (xy 318.977391 -364.689088) (xy 318.932033 -364.656637) (xy 318.891884 -364.617928)
			(xy 318.857798 -364.573785) (xy 318.830502 -364.52515) (xy 318.810579 -364.473059) (xy 318.798453 -364.418622)
			(xy 318.794382 -364.363) (xy 317.170308 -364.363) (xy 317.170308 -365.3028) (xy 317.169692 -365.327797)
			(xy 317.159885 -365.376822) (xy 317.140705 -365.422993) (xy 317.112891 -365.464538) (xy 317.095632 -365.482632)
			(xy 313.057032 -369.521232) (xy 313.038974 -369.538533) (xy 312.99742 -369.566348) (xy 312.951237 -369.585521)
			(xy 312.902202 -369.595316) (xy 312.8772 -369.595908) (xy 302.6664 -369.595908) (xy 302.641403 -369.595292)
			(xy 302.592378 -369.585485) (xy 302.546207 -369.566305) (xy 302.504662 -369.538491) (xy 302.486568 -369.521232)
			(xy 299.172376 -366.20704) (xy 299.164896 -366.200345) (xy 299.146336 -366.192756) (xy 299.136308 -366.192308)
			(xy 284.322012 -366.192308) (xy 284.297015 -366.191685) (xy 284.247991 -366.18188) (xy 284.20182 -366.162703)
			(xy 284.160275 -366.13489) (xy 284.14218 -366.117632) (xy 270.653256 -352.628708) (xy 270.645786 -352.622)
			(xy 270.627218 -352.61442) (xy 270.617188 -352.613976) (xy 266.712192 -352.613976) (xy 266.687196 -352.613345)
			(xy 266.638173 -352.603539) (xy 266.592002 -352.584364) (xy 266.550456 -352.556555) (xy 266.53236 -352.5393)
			(xy 262.742426 -348.749366) (xy 262.725217 -348.731245) (xy 262.697474 -348.689689) (xy 262.678364 -348.643522)
			(xy 262.668618 -348.594517) (xy 262.668004 -348.569534) (xy 260.754876 -348.569534) (xy 268.306804 -356.121462)
			(xy 268.314201 -356.128312) (xy 268.332799 -356.136051) (xy 268.342872 -356.136448) (xy 272.181574 -356.136448)
			(xy 272.191637 -356.136886) (xy 272.210217 -356.144625) (xy 272.217642 -356.151434) (xy 274.659598 -358.59339)
			(xy 274.677378 -358.60101) (xy 274.687538 -358.601264) (xy 274.711497 -358.602148) (xy 274.758732 -358.610354)
			(xy 274.804159 -358.625679) (xy 274.846713 -358.647762) (xy 274.885395 -358.676085) (xy 274.902676 -358.692704)
			(xy 282.690824 -366.480852) (xy 282.698237 -366.487527) (xy 282.716673 -366.495092) (xy 282.726638 -366.495584)
			(xy 291.782246 -366.495584) (xy 291.808131 -366.496143) (xy 291.85919 -366.504699) (xy 291.883846 -366.512602)
			(xy 291.89172 -366.515396) (xy 292.072314 -366.515396) (xy 292.082383 -366.515822) (xy 292.100984 -366.523539)
			(xy 292.108382 -366.530382) (xy 293.037514 -367.459514) (xy 293.044909 -367.466368) (xy 293.063508 -367.47411)
			(xy 293.073582 -367.4745) (xy 294.234616 -367.4745) (xy 294.24717 -367.473855) (xy 294.269301 -367.461997)
			(xy 294.27678 -367.451894) (xy 294.330882 -367.371122) (xy 294.333422 -367.34623) (xy 294.328596 -367.334292)
			(xy 294.319511 -367.311203) (xy 294.306725 -367.263263) (xy 294.300279 -367.214066) (xy 294.299894 -367.189258)
			(xy 294.300383 -367.162009) (xy 294.308144 -367.108066) (xy 294.323503 -367.055776) (xy 294.346146 -367.006204)
			(xy 294.375614 -366.960359) (xy 294.411305 -366.919174) (xy 294.452495 -366.883487) (xy 294.498343 -366.854025)
			(xy 294.547917 -366.831387) (xy 294.600209 -366.816035) (xy 294.654153 -366.80828) (xy 294.681402 -366.80775)
			(xy 294.70908 -366.808245) (xy 294.763854 -366.816251) (xy 294.816894 -366.832094) (xy 294.867086 -366.855441)
			(xy 294.913373 -366.885802) (xy 294.954783 -366.922537) (xy 294.972994 -366.943386) (xy 294.982138 -366.954054)
			(xy 295.007792 -366.963198) (xy 295.122346 -366.9411) (xy 295.142666 -366.923066) (xy 295.146984 -366.909858)
			(xy 295.155785 -366.884844) (xy 295.179326 -366.837329) (xy 295.209215 -366.793528) (xy 295.244877 -366.754284)
			(xy 295.285627 -366.720352) (xy 295.330679 -366.692385) (xy 295.379168 -366.670921) (xy 295.43016 -366.656373)
			(xy 295.482675 -366.64902) (xy 295.509188 -366.648492) (xy 295.536441 -366.648955) (xy 295.590394 -366.65671)
			(xy 295.642693 -366.672065) (xy 295.692275 -366.694707) (xy 295.738129 -366.724175) (xy 295.779323 -366.759868)
			(xy 295.815018 -366.801061) (xy 295.844487 -366.846915) (xy 295.867131 -366.896496) (xy 295.882487 -366.948795)
			(xy 295.890245 -367.002747) (xy 295.890696 -367.03) (xy 295.890127 -367.060124) (xy 295.880655 -367.119623)
			(xy 295.861946 -367.176893) (xy 295.834466 -367.230509) (xy 295.798898 -367.279137) (xy 295.77792 -367.300764)
			(xy 295.766998 -367.311686) (xy 295.760902 -367.341912) (xy 295.802558 -367.443004) (xy 295.80677 -367.45213)
			(xy 295.820952 -367.466351) (xy 295.839506 -367.474041) (xy 295.849548 -367.4745) (xy 299.36948 -367.4745)
			(xy 299.379544 -367.474938) (xy 299.398127 -367.482673) (xy 299.405548 -367.489486) (xy 301.623222 -369.70716)
			(xy 301.630592 -369.713903) (xy 301.649054 -369.721494) (xy 301.659036 -369.721892) (xy 317.964312 -369.721892)
		)
		(stroke
			(width 0)
			(type solid)
		)
		(fill yes)
		(layer "In2.Cu")
		(net "GND")
	)
	(gr_poly
		(pts
			(xy 25.667716 -366.573562) (xy 25.677784 -366.573135) (xy 25.696381 -366.565412) (xy 25.703784 -366.558576)
			(xy 25.835102 -366.427258) (xy 25.848317 -366.414656) (xy 25.878656 -366.394343) (xy 25.912369 -366.380326)
			(xy 25.948166 -366.373144) (xy 25.96642 -366.372648) (xy 28.07081 -366.372648) (xy 28.075382 -366.371886)
			(xy 28.104474 -366.367015) (xy 28.163235 -366.361801) (xy 28.19273 -366.361472) (xy 31.155386 -366.361472)
			(xy 31.184881 -366.361806) (xy 31.243641 -366.367019) (xy 31.272734 -366.371886) (xy 31.277306 -366.372648)
			(xy 32.756094 -366.372648) (xy 32.766164 -366.372225) (xy 32.784765 -366.364506) (xy 32.792162 -366.357662)
			(xy 34.343086 -364.806738) (xy 34.349924 -364.799337) (xy 34.357638 -364.780738) (xy 34.358072 -364.77067)
			(xy 34.358072 -364.08995) (xy 34.357444 -364.077242) (xy 34.345441 -364.054845) (xy 34.335212 -364.047278)
			(xy 34.312845 -364.032087) (xy 34.272225 -363.996401) (xy 34.23705 -363.95534) (xy 34.208022 -363.909725)
			(xy 34.185723 -363.860469) (xy 34.170599 -363.808559) (xy 34.162954 -363.755034) (xy 34.162492 -363.728)
			(xy 34.162978 -363.700749) (xy 34.170734 -363.646801) (xy 34.186089 -363.594506) (xy 34.208731 -363.544929)
			(xy 34.238197 -363.499079) (xy 34.273888 -363.457888) (xy 34.315079 -363.422197) (xy 34.360929 -363.392731)
			(xy 34.410506 -363.370089) (xy 34.462801 -363.354734) (xy 34.516749 -363.346978) (xy 34.571251 -363.346978)
			(xy 34.625199 -363.354734) (xy 34.677494 -363.370089) (xy 34.727071 -363.392731) (xy 34.772921 -363.422197)
			(xy 34.814112 -363.457888) (xy 34.849803 -363.499079) (xy 34.879269 -363.544929) (xy 34.901911 -363.594506)
			(xy 34.917266 -363.646801) (xy 34.925022 -363.700749) (xy 34.925508 -363.728) (xy 34.925037 -363.755034)
			(xy 34.917401 -363.80856) (xy 34.902283 -363.860472) (xy 34.879985 -363.909728) (xy 34.850955 -363.955341)
			(xy 34.815774 -363.996397) (xy 34.775147 -364.032074) (xy 34.752788 -364.047278) (xy 34.742568 -364.054849)
			(xy 34.730589 -364.077247) (xy 34.729928 -364.08995) (xy 34.729928 -364.868714) (xy 34.729488 -364.886975)
			(xy 34.722318 -364.922787) (xy 34.708295 -364.95651) (xy 34.68796 -364.986848) (xy 34.675318 -365.000032)
			(xy 33.791652 -365.883698) (xy 34.673284 -365.883698) (xy 34.677355 -365.828076) (xy 34.689481 -365.773639)
			(xy 34.709404 -365.721548) (xy 34.7367 -365.672913) (xy 34.770786 -365.62877) (xy 34.810935 -365.590061)
			(xy 34.856293 -365.55761) (xy 34.905893 -365.532109) (xy 34.958677 -365.514102) (xy 35.01352 -365.503972)
			(xy 35.069254 -365.501935) (xy 35.124691 -365.508035) (xy 35.178648 -365.522141) (xy 35.229977 -365.543953)
			(xy 35.277583 -365.573007) (xy 35.320451 -365.608682) (xy 35.357668 -365.650219) (xy 35.388441 -365.696732)
			(xy 35.412113 -365.747229) (xy 35.428181 -365.800636) (xy 35.436301 -365.855812) (xy 35.43681 -365.883698)
			(xy 35.436301 -365.911584) (xy 35.428181 -365.96676) (xy 35.412113 -366.020167) (xy 35.388441 -366.070664)
			(xy 35.357668 -366.117177) (xy 35.320451 -366.158714) (xy 35.277583 -366.194389) (xy 35.229977 -366.223443)
			(xy 35.178648 -366.245255) (xy 35.124691 -366.259361) (xy 35.069254 -366.265461) (xy 35.01352 -366.263424)
			(xy 34.958677 -366.253294) (xy 34.905893 -366.235287) (xy 34.856293 -366.209786) (xy 34.810935 -366.177335)
			(xy 34.770786 -366.138626) (xy 34.7367 -366.094483) (xy 34.709404 -366.045848) (xy 34.689481 -365.993757)
			(xy 34.677355 -365.93932) (xy 34.673284 -365.883698) (xy 33.791652 -365.883698) (xy 33.188402 -366.486948)
			(xy 33.181727 -366.49435) (xy 33.174141 -366.51276) (xy 33.174147 -366.532671) (xy 33.17748 -366.542066)
			(xy 33.183322 -366.556544) (xy 33.208976 -366.573562) (xy 33.476692 -366.573562) (xy 33.487804 -366.573009)
			(xy 33.50797 -366.563667) (xy 33.515554 -366.555528) (xy 33.533788 -366.534674) (xy 33.575245 -366.497933)
			(xy 33.621576 -366.467571) (xy 33.67181 -366.444222) (xy 33.72489 -366.428379) (xy 33.779703 -366.420373)
			(xy 33.835097 -366.420373) (xy 33.88991 -366.428379) (xy 33.94299 -366.444222) (xy 33.993224 -366.467571)
			(xy 34.039555 -366.497933) (xy 34.081012 -366.534674) (xy 34.099246 -366.555528) (xy 34.106836 -366.563664)
			(xy 34.126995 -366.573018) (xy 34.138108 -366.573562) (xy 36.719256 -366.573562) (xy 36.729321 -366.573128)
			(xy 36.747907 -366.565395) (xy 36.755324 -366.558576) (xy 37.12845 -366.185704) (xy 37.135303 -366.178308)
			(xy 37.143046 -366.15971) (xy 37.143436 -366.149636) (xy 37.143436 -366.119664) (xy 37.142784 -366.107115)
			(xy 37.130913 -366.085003) (xy 37.12083 -366.0775) (xy 37.098778 -366.06226) (xy 37.058771 -366.026585)
			(xy 37.024151 -365.985662) (xy 36.9956 -365.940295) (xy 36.97368 -365.891379) (xy 36.958823 -365.839877)
			(xy 36.95132 -365.786801) (xy 36.95132 -365.733199) (xy 36.958823 -365.680123) (xy 36.97368 -365.628621)
			(xy 36.9956 -365.579705) (xy 37.024151 -365.534338) (xy 37.058771 -365.493415) (xy 37.098778 -365.45774)
			(xy 37.12083 -365.4425) (xy 37.130894 -365.434985) (xy 37.142754 -365.412877) (xy 37.143436 -365.400336)
			(xy 37.143436 -365.060992) (xy 37.143134 -365.052886) (xy 37.13808 -365.037482) (xy 37.13353 -365.030766)
			(xy 37.113015 -365.00206) (xy 37.077469 -364.941108) (xy 37.048533 -364.876754) (xy 37.02653 -364.809713)
			(xy 37.011703 -364.740729) (xy 37.004216 -364.670567) (xy 37.003736 -364.635288) (xy 37.003736 -363.951266)
			(xy 37.004264 -363.913752) (xy 37.012667 -363.839197) (xy 37.029365 -363.766051) (xy 37.054147 -363.695235)
			(xy 37.086702 -363.627638) (xy 37.12662 -363.564111) (xy 37.173399 -363.505453) (xy 37.19957 -363.478572)
			(xy 37.550852 -363.12729) (xy 37.578143 -363.100757) (xy 37.637731 -363.053394) (xy 37.702314 -363.013107)
			(xy 37.771056 -362.980417) (xy 37.843067 -362.955749) (xy 37.917413 -362.939421) (xy 37.95522 -362.935012)
			(xy 37.967431 -362.933135) (xy 37.987947 -362.919423) (xy 37.994336 -362.90885) (xy 38.008874 -362.883636)
			(xy 38.0444 -362.837538) (xy 38.086512 -362.797366) (xy 38.134233 -362.764051) (xy 38.186457 -362.738365)
			(xy 38.241975 -362.720903) (xy 38.2995 -362.712069) (xy 38.3286 -362.711492) (xy 38.357436 -362.712019)
			(xy 38.414452 -362.72069) (xy 38.469516 -362.737836) (xy 38.521376 -362.763066) (xy 38.568853 -362.795807)
			(xy 38.610867 -362.835314) (xy 38.646464 -362.880689) (xy 38.661086 -362.905548) (xy 38.665801 -362.913199)
			(xy 38.679465 -362.924855) (xy 38.696303 -362.931103) (xy 38.705282 -362.931456) (xy 39.995094 -362.931456)
			(xy 40.034036 -362.931997) (xy 40.111393 -362.94104) (xy 40.187174 -362.959015) (xy 40.26035 -362.98568)
			(xy 40.329931 -363.020672) (xy 40.394971 -363.063516) (xy 40.425116 -363.088174) (xy 40.432113 -363.093627)
			(xy 40.448764 -363.09972) (xy 40.457628 -363.100112) (xy 41.133522 -363.100112) (xy 41.142478 -363.099765)
			(xy 41.159301 -363.093617) (xy 41.172999 -363.082075) (xy 41.177718 -363.074458) (xy 41.191364 -363.051423)
			(xy 41.224119 -363.00907) (xy 41.262477 -362.971717) (xy 41.305684 -362.940099) (xy 41.352891 -362.914838)
			(xy 41.403168 -362.89643) (xy 41.455525 -362.885239) (xy 41.508934 -362.881484) (xy 41.562343 -362.885239)
			(xy 41.6147 -362.89643) (xy 41.664977 -362.914838) (xy 41.712184 -362.940099) (xy 41.755391 -362.971717)
			(xy 41.793749 -363.00907) (xy 41.826504 -363.051423) (xy 41.84015 -363.074458) (xy 41.844883 -363.082067)
			(xy 41.858563 -363.093624) (xy 41.875391 -363.099753) (xy 41.884346 -363.100112) (xy 43.495722 -363.100112)
			(xy 43.504678 -363.099765) (xy 43.521501 -363.093617) (xy 43.535199 -363.082075) (xy 43.539918 -363.074458)
			(xy 43.553564 -363.051423) (xy 43.586319 -363.00907) (xy 43.624677 -362.971717) (xy 43.667884 -362.940099)
			(xy 43.715091 -362.914838) (xy 43.765368 -362.89643) (xy 43.817725 -362.885239) (xy 43.871134 -362.881484)
			(xy 43.924543 -362.885239) (xy 43.9769 -362.89643) (xy 44.027177 -362.914838) (xy 44.074384 -362.940099)
			(xy 44.117591 -362.971717) (xy 44.155949 -363.00907) (xy 44.188704 -363.051423) (xy 44.20235 -363.074458)
			(xy 44.207083 -363.082067) (xy 44.220763 -363.093624) (xy 44.237591 -363.099753) (xy 44.246546 -363.100112)
			(xy 46.035722 -363.100112) (xy 46.047697 -363.09946) (xy 46.069029 -363.088575) (xy 46.076616 -363.079284)
			(xy 46.132496 -363.003592) (xy 46.136306 -362.979716) (xy 46.13275 -362.968286) (xy 46.124586 -362.940483)
			(xy 46.115789 -362.883211) (xy 46.115224 -362.85424) (xy 46.1157 -362.826872) (xy 46.123532 -362.772698)
			(xy 46.139026 -362.7202) (xy 46.161865 -362.670455) (xy 46.191579 -362.624486) (xy 46.209204 -362.603542)
			(xy 46.209204 -362.603288) (xy 46.209458 -362.603288) (xy 46.215045 -362.596202) (xy 46.221288 -362.579285)
			(xy 46.22165 -362.570268) (xy 46.22165 -362.503212) (xy 46.221294 -362.494194) (xy 46.215054 -362.477272)
			(xy 46.209458 -362.470192) (xy 46.209204 -362.469938) (xy 46.191561 -362.449005) (xy 46.161833 -362.403036)
			(xy 46.138983 -362.353288) (xy 46.123483 -362.300784) (xy 46.11565 -362.246602) (xy 46.115645 -362.191858)
			(xy 46.12347 -362.137675) (xy 46.138962 -362.085169) (xy 46.161804 -362.035417) (xy 46.191525 -361.989443)
			(xy 46.209204 -361.968542) (xy 46.209204 -361.968288) (xy 46.209458 -361.968288) (xy 46.215045 -361.961202)
			(xy 46.221288 -361.944285) (xy 46.22165 -361.935268) (xy 46.22165 -361.868212) (xy 46.221294 -361.859194)
			(xy 46.215054 -361.842272) (xy 46.209458 -361.835192) (xy 46.209204 -361.834938) (xy 46.191561 -361.814005)
			(xy 46.161833 -361.768036) (xy 46.138983 -361.718288) (xy 46.123483 -361.665784) (xy 46.11565 -361.611602)
			(xy 46.115645 -361.556858) (xy 46.12347 -361.502675) (xy 46.138962 -361.450169) (xy 46.161804 -361.400417)
			(xy 46.191525 -361.354443) (xy 46.209204 -361.333542) (xy 46.209204 -361.333288) (xy 46.209458 -361.333288)
			(xy 46.215045 -361.326202) (xy 46.221288 -361.309285) (xy 46.22165 -361.300268) (xy 46.22165 -361.233212)
			(xy 46.221294 -361.224194) (xy 46.215054 -361.207272) (xy 46.209458 -361.200192) (xy 46.209204 -361.199938)
			(xy 46.191561 -361.179005) (xy 46.161833 -361.133036) (xy 46.138983 -361.083288) (xy 46.123483 -361.030784)
			(xy 46.11565 -360.976602) (xy 46.115645 -360.921858) (xy 46.12347 -360.867675) (xy 46.138962 -360.815169)
			(xy 46.161804 -360.765417) (xy 46.191525 -360.719443) (xy 46.209204 -360.698542) (xy 46.209204 -360.698288)
			(xy 46.209458 -360.698288) (xy 46.215045 -360.691202) (xy 46.221288 -360.674285) (xy 46.22165 -360.665268)
			(xy 46.22165 -360.598212) (xy 46.221294 -360.589194) (xy 46.215054 -360.572272) (xy 46.209458 -360.565192)
			(xy 46.209204 -360.564938) (xy 46.191561 -360.544005) (xy 46.161833 -360.498036) (xy 46.138983 -360.448288)
			(xy 46.123483 -360.395784) (xy 46.11565 -360.341602) (xy 46.115645 -360.286858) (xy 46.12347 -360.232675)
			(xy 46.138962 -360.180169) (xy 46.161804 -360.130417) (xy 46.191525 -360.084443) (xy 46.209204 -360.063542)
			(xy 46.209204 -360.063288) (xy 46.209458 -360.063288) (xy 46.215045 -360.056202) (xy 46.221288 -360.039285)
			(xy 46.22165 -360.030268) (xy 46.22165 -359.963212) (xy 46.221294 -359.954194) (xy 46.215054 -359.937272)
			(xy 46.209458 -359.930192) (xy 46.209204 -359.929938) (xy 46.191565 -359.909006) (xy 46.161847 -359.863038)
			(xy 46.139011 -359.81329) (xy 46.123529 -359.760787) (xy 46.115719 -359.706609) (xy 46.115224 -359.67924)
			(xy 46.115685 -359.651986) (xy 46.123437 -359.598033) (xy 46.13879 -359.545732) (xy 46.161431 -359.496149)
			(xy 46.190898 -359.450293) (xy 46.226592 -359.409098) (xy 46.267786 -359.373403) (xy 46.313642 -359.343935)
			(xy 46.363224 -359.321293) (xy 46.415525 -359.305939) (xy 46.469478 -359.298185) (xy 46.496732 -359.297732)
			(xy 46.524101 -359.298206) (xy 46.578277 -359.306035) (xy 46.630777 -359.321526) (xy 46.680524 -359.344363)
			(xy 46.726496 -359.374075) (xy 46.74743 -359.391712) (xy 46.747684 -359.391712) (xy 46.747684 -359.391966)
			(xy 46.754769 -359.397556) (xy 46.771686 -359.403808) (xy 46.780704 -359.404158) (xy 46.84776 -359.404158)
			(xy 46.85678 -359.403806) (xy 46.873709 -359.397575) (xy 46.88078 -359.391966) (xy 46.881034 -359.391712)
			(xy 46.901967 -359.374071) (xy 46.947935 -359.344347) (xy 46.997681 -359.321501) (xy 47.050183 -359.306005)
			(xy 47.104361 -359.298176) (xy 47.159103 -359.298176) (xy 47.213281 -359.306005) (xy 47.265783 -359.321501)
			(xy 47.315529 -359.344347) (xy 47.361497 -359.374071) (xy 47.38243 -359.391712) (xy 47.382684 -359.391712)
			(xy 47.382684 -359.391966) (xy 47.389769 -359.397556) (xy 47.406686 -359.403808) (xy 47.415704 -359.404158)
			(xy 47.48276 -359.404158) (xy 47.49178 -359.403806) (xy 47.508709 -359.397575) (xy 47.51578 -359.391966)
			(xy 47.516034 -359.391712) (xy 47.536966 -359.374071) (xy 47.582933 -359.344349) (xy 47.63268 -359.321509)
			(xy 47.685183 -359.306023) (xy 47.739362 -359.298209) (xy 47.766732 -359.297732) (xy 47.793562 -359.298183)
			(xy 47.846693 -359.305691) (xy 47.898248 -359.320569) (xy 47.94721 -359.342523) (xy 47.992614 -359.371121)
			(xy 48.033563 -359.405797) (xy 48.06925 -359.445869) (xy 48.098972 -359.490545) (xy 48.12214 -359.538944)
			(xy 48.1383 -359.590113) (xy 48.14316 -359.616502) (xy 48.144938 -359.627424) (xy 48.156876 -359.645458)
			(xy 48.240442 -359.697274) (xy 48.262032 -359.700068) (xy 48.272446 -359.69702) (xy 48.299366 -359.689407)
			(xy 48.35471 -359.681247) (xy 48.382682 -359.680764) (xy 48.41005 -359.681242) (xy 48.464221 -359.689077)
			(xy 48.516717 -359.704575) (xy 48.566458 -359.727418) (xy 48.612423 -359.757136) (xy 48.63338 -359.774744)
			(xy 48.633634 -359.774744) (xy 48.633634 -359.774998) (xy 48.640722 -359.780578) (xy 48.65764 -359.786809)
			(xy 48.666654 -359.78719) (xy 48.73371 -359.78719) (xy 48.742726 -359.786829) (xy 48.759639 -359.780578)
			(xy 48.76673 -359.774998) (xy 48.766984 -359.774744) (xy 48.787917 -359.757103) (xy 48.833885 -359.727379)
			(xy 48.883631 -359.704533) (xy 48.936133 -359.689037) (xy 48.990311 -359.681208) (xy 49.045053 -359.681208)
			(xy 49.099231 -359.689037) (xy 49.151733 -359.704533) (xy 49.201479 -359.727379) (xy 49.247447 -359.757103)
			(xy 49.26838 -359.774744) (xy 49.268634 -359.774744) (xy 49.268634 -359.774998) (xy 49.275722 -359.780578)
			(xy 49.29264 -359.786809) (xy 49.301654 -359.78719) (xy 49.36871 -359.78719) (xy 49.377726 -359.786829)
			(xy 49.394639 -359.780578) (xy 49.40173 -359.774998) (xy 49.401984 -359.774744) (xy 49.422917 -359.757103)
			(xy 49.468885 -359.727379) (xy 49.518631 -359.704533) (xy 49.571133 -359.689037) (xy 49.625311 -359.681208)
			(xy 49.680053 -359.681208) (xy 49.734231 -359.689037) (xy 49.786733 -359.704533) (xy 49.836479 -359.727379)
			(xy 49.882447 -359.757103) (xy 49.90338 -359.774744) (xy 49.903634 -359.774744) (xy 49.903634 -359.774998)
			(xy 49.910722 -359.780578) (xy 49.92764 -359.786809) (xy 49.936654 -359.78719) (xy 50.00371 -359.78719)
			(xy 50.012726 -359.786829) (xy 50.029639 -359.780578) (xy 50.03673 -359.774998) (xy 50.036984 -359.774744)
			(xy 50.057914 -359.757099) (xy 50.103879 -359.727368) (xy 50.153626 -359.70452) (xy 50.20613 -359.689026)
			(xy 50.260311 -359.681204) (xy 50.287682 -359.680764) (xy 50.288444 -359.680764) (xy 50.318217 -359.681379)
			(xy 50.377031 -359.690696) (xy 50.405538 -359.699306) (xy 50.415444 -359.702608) (xy 50.436526 -359.700576)
			(xy 50.519584 -359.655364) (xy 50.532284 -359.639108) (xy 50.535078 -359.628948) (xy 50.542721 -359.602236)
			(xy 50.564673 -359.551199) (xy 50.593793 -359.503884) (xy 50.629467 -359.461292) (xy 50.670939 -359.424323)
			(xy 50.717335 -359.393759) (xy 50.767672 -359.370245) (xy 50.820886 -359.35428) (xy 50.875853 -359.346199)
			(xy 50.903632 -359.345738) (xy 50.932525 -359.346272) (xy 50.98965 -359.354986) (xy 51.044809 -359.37221)
			(xy 51.096742 -359.39755) (xy 51.120802 -359.413556) (xy 51.128422 -359.41889) (xy 51.146964 -359.423462)
			(xy 51.22418 -359.413048) (xy 51.233387 -359.411355) (xy 51.249789 -359.402361) (xy 51.256184 -359.395522)
			(xy 51.274397 -359.374635) (xy 51.315827 -359.337831) (xy 51.36215 -359.307416) (xy 51.41239 -359.284029)
			(xy 51.465487 -359.268166) (xy 51.520322 -359.260159) (xy 51.54803 -359.259632) (xy 51.573984 -359.260065)
			(xy 51.625413 -359.267096) (xy 51.675413 -359.281038) (xy 51.723061 -359.301632) (xy 51.767474 -359.3285)
			(xy 51.807833 -359.361142) (xy 51.825906 -359.379774) (xy 51.825906 -359.380028) (xy 51.832849 -359.386727)
			(xy 51.850341 -359.394832) (xy 51.859942 -359.395776) (xy 51.930046 -359.399586) (xy 51.939676 -359.399754)
			(xy 51.957963 -359.39376) (xy 51.965606 -359.387902) (xy 51.986336 -359.370957) (xy 52.031649 -359.342436)
			(xy 52.080506 -359.320536) (xy 52.131948 -359.305689) (xy 52.184961 -359.298187) (xy 52.211732 -359.297732)
			(xy 52.239101 -359.298206) (xy 52.293277 -359.306035) (xy 52.345777 -359.321526) (xy 52.395524 -359.344363)
			(xy 52.441496 -359.374075) (xy 52.46243 -359.391712) (xy 52.462684 -359.391712) (xy 52.462684 -359.391966)
			(xy 52.469769 -359.397556) (xy 52.486686 -359.403808) (xy 52.495704 -359.404158) (xy 52.56276 -359.404158)
			(xy 52.57178 -359.403806) (xy 52.588709 -359.397575) (xy 52.59578 -359.391966) (xy 52.596034 -359.391712)
			(xy 52.616966 -359.374071) (xy 52.662933 -359.344349) (xy 52.71268 -359.321509) (xy 52.765183 -359.306023)
			(xy 52.819362 -359.298209) (xy 52.846732 -359.297732) (xy 52.873982 -359.298198) (xy 52.927928 -359.305958)
			(xy 52.980219 -359.321318) (xy 53.029793 -359.343963) (xy 53.075639 -359.373432) (xy 53.116825 -359.409126)
			(xy 53.152511 -359.450319) (xy 53.181972 -359.49617) (xy 53.204608 -359.545748) (xy 53.219957 -359.598043)
			(xy 53.227708 -359.65199) (xy 53.22824 -359.67924) (xy 53.22824 -359.679748) (xy 53.227738 -359.707633)
			(xy 53.21958 -359.762805) (xy 53.203476 -359.816201) (xy 53.179768 -359.866682) (xy 53.148962 -359.913173)
			(xy 53.130704 -359.934256) (xy 53.124354 -359.941114) (xy 53.117496 -359.958894) (xy 53.11775 -360.036364)
			(xy 53.118147 -360.045647) (xy 53.124785 -360.062985) (xy 53.130704 -360.070146) (xy 53.149118 -360.09127)
			(xy 53.18019 -360.137904) (xy 53.2041 -360.188584) (xy 53.220333 -360.242218) (xy 53.228541 -360.297651)
			(xy 53.229002 -360.32567) (xy 53.228541 -360.352924) (xy 53.220787 -360.406878) (xy 53.205434 -360.459179)
			(xy 53.182793 -360.508763) (xy 53.153326 -360.554619) (xy 53.117632 -360.595815) (xy 53.076438 -360.631511)
			(xy 53.030584 -360.660981) (xy 52.981002 -360.683625) (xy 52.928701 -360.698982) (xy 52.874748 -360.706739)
			(xy 52.847494 -360.707178) (xy 52.819383 -360.706678) (xy 52.763769 -360.698432) (xy 52.709966 -360.682119)
			(xy 52.659138 -360.658091) (xy 52.612382 -360.626869) (xy 52.591208 -360.608372) (xy 52.58435 -360.602276)
			(xy 52.567586 -360.595418) (xy 52.481734 -360.593894) (xy 52.464716 -360.599736) (xy 52.457604 -360.605832)
			(xy 52.436872 -360.622714) (xy 52.391582 -360.651126) (xy 52.342773 -360.672947) (xy 52.2914 -360.687751)
			(xy 52.238464 -360.69525) (xy 52.211732 -360.695748) (xy 52.185779 -360.695313) (xy 52.134353 -360.688277)
			(xy 52.084356 -360.67433) (xy 52.036713 -360.653732) (xy 51.992305 -360.626861) (xy 51.951951 -360.594215)
			(xy 51.933856 -360.575606) (xy 51.933856 -360.575352) (xy 51.92691 -360.56866) (xy 51.909417 -360.560571)
			(xy 51.89982 -360.559604) (xy 51.829716 -360.555794) (xy 51.820089 -360.555633) (xy 51.801809 -360.561636)
			(xy 51.794156 -360.567478) (xy 51.773425 -360.584422) (xy 51.728113 -360.61294) (xy 51.679254 -360.634836)
			(xy 51.627813 -360.649679) (xy 51.5748 -360.657176) (xy 51.54803 -360.657648) (xy 51.519138 -360.657111)
			(xy 51.462016 -360.648392) (xy 51.40686 -360.631163) (xy 51.354931 -360.605819) (xy 51.33086 -360.58983)
			(xy 51.32324 -360.584496) (xy 51.304698 -360.579924) (xy 51.227482 -360.590338) (xy 51.218269 -360.592021)
			(xy 51.20185 -360.601001) (xy 51.195478 -360.607864) (xy 51.17592 -360.629454) (xy 51.168894 -360.637395)
			(xy 51.161404 -360.657206) (xy 51.161442 -360.667808) (xy 51.166014 -360.753406) (xy 51.175666 -360.772456)
			(xy 51.183794 -360.77906) (xy 51.205199 -360.797276) (xy 51.242941 -360.838923) (xy 51.274163 -360.885658)
			(xy 51.298188 -360.936468) (xy 51.314498 -360.990254) (xy 51.322738 -361.045852) (xy 51.32324 -361.073954)
			(xy 51.32278 -361.10121) (xy 51.315029 -361.155168) (xy 51.299677 -361.207473) (xy 51.277038 -361.257061)
			(xy 51.247571 -361.302922) (xy 51.211878 -361.344123) (xy 51.170685 -361.379825) (xy 51.124829 -361.4093)
			(xy 51.075246 -361.43195) (xy 51.022944 -361.447312) (xy 50.968988 -361.455075) (xy 50.941732 -361.455462)
			(xy 50.941478 -361.455462) (xy 50.913618 -361.454929) (xy 50.858494 -361.446786) (xy 50.805134 -361.430735)
			(xy 50.77968 -361.419394) (xy 50.779426 -361.419394) (xy 50.769836 -361.415428) (xy 50.749116 -361.414775)
			(xy 50.739294 -361.418124) (xy 50.660554 -361.449112) (xy 50.646076 -361.46359) (xy 50.642012 -361.473496)
			(xy 50.630998 -361.4997) (xy 50.602344 -361.548788) (xy 50.566727 -361.593083) (xy 50.524935 -361.631607)
			(xy 50.477892 -361.663508) (xy 50.426639 -361.688079) (xy 50.372308 -361.704777) (xy 50.316101 -361.713233)
			(xy 50.287682 -361.71378) (xy 50.260313 -361.713307) (xy 50.206136 -361.70548) (xy 50.153634 -361.689991)
			(xy 50.103885 -361.667156) (xy 50.057911 -361.637445) (xy 50.036984 -361.6198) (xy 50.03673 -361.6198)
			(xy 50.03673 -361.619546) (xy 50.029646 -361.613952) (xy 50.012729 -361.607695) (xy 50.00371 -361.607354)
			(xy 49.936654 -361.607354) (xy 49.92764 -361.60772) (xy 49.910731 -361.613974) (xy 49.903634 -361.619546)
			(xy 49.90338 -361.6198) (xy 49.882447 -361.637441) (xy 49.836479 -361.667165) (xy 49.786733 -361.690011)
			(xy 49.734231 -361.705507) (xy 49.680053 -361.713336) (xy 49.625311 -361.713336) (xy 49.571133 -361.705507)
			(xy 49.518631 -361.690011) (xy 49.468885 -361.667165) (xy 49.422917 -361.637441) (xy 49.401984 -361.6198)
			(xy 49.40173 -361.6198) (xy 49.40173 -361.619546) (xy 49.394646 -361.613952) (xy 49.377729 -361.607695)
			(xy 49.36871 -361.607354) (xy 49.301654 -361.607354) (xy 49.29264 -361.60772) (xy 49.275731 -361.613974)
			(xy 49.268634 -361.619546) (xy 49.26838 -361.6198) (xy 49.247447 -361.637441) (xy 49.201479 -361.667165)
			(xy 49.151733 -361.690011) (xy 49.099231 -361.705507) (xy 49.045053 -361.713336) (xy 48.990311 -361.713336)
			(xy 48.936133 -361.705507) (xy 48.883631 -361.690011) (xy 48.833885 -361.667165) (xy 48.787917 -361.637441)
			(xy 48.766984 -361.6198) (xy 48.76673 -361.6198) (xy 48.76673 -361.619546) (xy 48.759646 -361.613952)
			(xy 48.742729 -361.607695) (xy 48.73371 -361.607354) (xy 48.666654 -361.607354) (xy 48.65764 -361.60772)
			(xy 48.640731 -361.613974) (xy 48.633634 -361.619546) (xy 48.63338 -361.6198) (xy 48.612448 -361.637441)
			(xy 48.566481 -361.667164) (xy 48.516734 -361.690005) (xy 48.464231 -361.705493) (xy 48.410052 -361.713308)
			(xy 48.382682 -361.71378) (xy 48.382174 -361.71378) (xy 48.358643 -361.713417) (xy 48.31194 -361.707599)
			(xy 48.266309 -361.696078) (xy 48.244252 -361.687872) (xy 48.243998 -361.687872) (xy 48.234846 -361.684729)
			(xy 48.215512 -361.684853) (xy 48.206406 -361.688126) (xy 48.14189 -361.714542) (xy 48.133061 -361.718582)
			(xy 48.119083 -361.732034) (xy 48.114712 -361.740704) (xy 48.102694 -361.766054) (xy 48.072345 -361.813236)
			(xy 48.05426 -361.834684) (xy 48.05426 -361.835192) (xy 48.054006 -361.835192) (xy 48.048419 -361.842278)
			(xy 48.042174 -361.859195) (xy 48.041814 -361.868212) (xy 48.041814 -361.935268) (xy 48.042168 -361.944286)
			(xy 48.048409 -361.961209) (xy 48.054006 -361.968288) (xy 48.05426 -361.968542) (xy 48.071901 -361.989473)
			(xy 48.101625 -362.03544) (xy 48.124465 -362.085187) (xy 48.139952 -362.137691) (xy 48.147765 -362.19187)
			(xy 48.14824 -362.21924) (xy 48.147752 -362.24649) (xy 48.139991 -362.300435) (xy 48.124632 -362.352727)
			(xy 48.101989 -362.402301) (xy 48.072522 -362.448149) (xy 48.036831 -362.489337) (xy 47.995643 -362.525027)
			(xy 47.949794 -362.554493) (xy 47.90022 -362.577135) (xy 47.847927 -362.592492) (xy 47.793982 -362.600252)
			(xy 47.766732 -362.600748) (xy 47.737254 -362.600202) (xy 47.678998 -362.591138) (xy 47.622831 -362.573221)
			(xy 47.570087 -362.546878) (xy 47.522024 -362.512735) (xy 47.50054 -362.492544) (xy 47.493212 -362.485998)
			(xy 47.475048 -362.478553) (xy 47.465234 -362.478066) (xy 47.43323 -362.478066) (xy 47.423417 -362.478561)
			(xy 47.40525 -362.485998) (xy 47.397924 -362.492544) (xy 47.390558 -362.499402) (xy 47.390558 -362.552742)
			(xy 47.391066 -362.562549) (xy 47.39852 -362.580699) (xy 47.405036 -362.588048) (xy 47.425211 -362.609547)
			(xy 47.459359 -362.657604) (xy 47.485707 -362.710344) (xy 47.503627 -362.766509) (xy 47.512691 -362.824763)
			(xy 47.51324 -362.85424) (xy 47.512683 -362.883212) (xy 47.503883 -362.940484) (xy 47.495714 -362.968286)
			(xy 47.492158 -362.979716) (xy 47.495968 -363.003592) (xy 47.551848 -363.079284) (xy 47.559451 -363.088545)
			(xy 47.58078 -363.099398) (xy 47.592742 -363.100112) (xy 134.955534 -363.100112) (xy 134.965602 -363.099683)
			(xy 134.984198 -363.091961) (xy 134.991602 -363.085126) (xy 137.219182 -360.857546) (xy 137.226583 -360.850707)
			(xy 137.245182 -360.842995) (xy 137.25525 -360.84256) (xy 149.237446 -360.84256) (xy 149.247512 -360.842127)
			(xy 149.2661 -360.834397) (xy 149.273514 -360.827574) (xy 151.109426 -358.991662) (xy 151.116275 -358.984265)
			(xy 151.124007 -358.965666) (xy 151.124412 -358.955594) (xy 151.124412 -331.58811) (xy 151.123991 -331.578039)
			(xy 151.116281 -331.55943) (xy 151.109426 -331.552042) (xy 149.290786 -329.733402) (xy 149.283387 -329.726558)
			(xy 149.264789 -329.718828) (xy 149.254718 -329.718416) (xy 120.044464 -329.718416) (xy 120.019874 -329.717956)
			(xy 119.971301 -329.710255) (xy 119.924531 -329.695048) (xy 119.880716 -329.672709) (xy 119.840937 -329.643791)
			(xy 119.82323 -329.626722) (xy 119.573548 -329.37704) (xy 119.570457 -329.374041) (xy 119.563428 -329.369066)
			(xy 119.559578 -329.367134) (xy 119.554404 -329.364871) (xy 119.54338 -329.36243) (xy 119.537734 -329.362308)
			(xy 119.451882 -329.362308) (xy 119.441813 -329.361882) (xy 119.423212 -329.354164) (xy 119.415814 -329.347322)
			(xy 116.181378 -326.112886) (xy 116.174266 -326.10552) (xy 116.142262 -326.073516) (xy 116.134851 -326.066836)
			(xy 116.116415 -326.059265) (xy 116.106448 -326.058784) (xy 109.960156 -326.058784) (xy 109.950192 -326.059266)
			(xy 109.93176 -326.066846) (xy 109.924342 -326.073516) (xy 109.914944 -326.082914) (xy 109.909318 -326.088153)
			(xy 109.895759 -326.095381) (xy 109.888274 -326.097138) (xy 109.876844 -326.099932) (xy 107.071414 -328.905362)
			(xy 107.064013 -328.912199) (xy 107.045414 -328.919908) (xy 107.035346 -328.920348) (xy 101.577648 -328.920348)
			(xy 101.567624 -328.92076) (xy 101.549099 -328.928423) (xy 101.534923 -328.942599) (xy 101.52726 -328.961124)
			(xy 101.526848 -328.971148) (xy 101.526848 -335.839816) (xy 101.526365 -335.864768) (xy 101.518572 -335.91406)
			(xy 101.503164 -335.961526) (xy 101.48052 -336.005998) (xy 101.451199 -336.046379) (xy 101.433884 -336.064352)
			(xy 100.353622 -337.144614) (xy 100.348034 -337.151218) (xy 100.344853 -337.155941) (xy 100.340497 -337.166459)
			(xy 100.339398 -337.172046) (xy 100.338636 -337.180682) (xy 100.338636 -339.54085) (xy 100.339398 -339.549486)
			(xy 100.340527 -339.555064) (xy 100.344889 -339.565571) (xy 100.348034 -339.570314) (xy 100.353622 -339.576918)
			(xy 101.230684 -340.45398) (xy 101.247966 -340.47198) (xy 101.27727 -340.512364) (xy 101.299905 -340.55683)
			(xy 101.315316 -340.604287) (xy 101.323124 -340.653568) (xy 101.323648 -340.678516) (xy 101.323648 -341.669116)
			(xy 101.323165 -341.694068) (xy 101.315372 -341.74336) (xy 101.299964 -341.790826) (xy 101.27732 -341.835298)
			(xy 101.247999 -341.875679) (xy 101.230684 -341.893652) (xy 101.196636 -341.9277) (xy 104.047047 -341.9277)
			(xy 104.051215 -341.872088) (xy 104.063623 -341.817718) (xy 104.083996 -341.765805) (xy 104.111879 -341.717508)
			(xy 104.146648 -341.673905) (xy 104.187526 -341.635971) (xy 104.233602 -341.604553) (xy 104.283845 -341.580353)
			(xy 104.337134 -341.56391) (xy 104.392278 -341.555594) (xy 104.420162 -341.55507) (xy 104.446585 -341.555499)
			(xy 104.498901 -341.562957) (xy 104.54964 -341.577729) (xy 104.597784 -341.599519) (xy 104.642367 -341.62789)
			(xy 104.662732 -341.644732) (xy 104.66959 -341.650574) (xy 104.686608 -341.656924) (xy 104.770936 -341.656924)
			(xy 104.787954 -341.650574) (xy 104.794812 -341.644732) (xy 104.815178 -341.627893) (xy 104.859764 -341.599528)
			(xy 104.907908 -341.577741) (xy 104.958645 -341.56297) (xy 105.01096 -341.55551) (xy 105.063804 -341.55551)
			(xy 105.116119 -341.56297) (xy 105.166856 -341.577741) (xy 105.215 -341.599528) (xy 105.259586 -341.627893)
			(xy 105.279952 -341.644732) (xy 105.28681 -341.650574) (xy 105.303828 -341.656924) (xy 105.388156 -341.656924)
			(xy 105.405174 -341.650574) (xy 105.412032 -341.644732) (xy 105.432821 -341.627549) (xy 105.478409 -341.598732)
			(xy 105.527679 -341.576798) (xy 105.55351 -341.56904) (xy 105.553764 -341.56904) (xy 105.564805 -341.565251)
			(xy 105.58214 -341.549661) (xy 105.587038 -341.539068) (xy 105.61701 -341.464138) (xy 105.620746 -341.453059)
			(xy 105.618904 -341.429777) (xy 105.613454 -341.419434) (xy 105.601097 -341.397777) (xy 105.581621 -341.351876)
			(xy 105.568438 -341.303789) (xy 105.561785 -341.254373) (xy 105.561384 -341.229442) (xy 105.561878 -341.201799)
			(xy 105.570036 -341.14712) (xy 105.586179 -341.094244) (xy 105.609954 -341.044332) (xy 105.640839 -340.998478)
			(xy 105.678156 -340.957688) (xy 105.699306 -340.939882) (xy 105.707746 -340.932298) (xy 105.717501 -340.911844)
			(xy 105.718102 -340.900512) (xy 105.718102 -340.821772) (xy 105.717457 -340.810454) (xy 105.707701 -340.790021)
			(xy 105.699306 -340.782402) (xy 105.67818 -340.76457) (xy 105.640866 -340.723783) (xy 105.609982 -340.677933)
			(xy 105.586205 -340.628027) (xy 105.570056 -340.575157) (xy 105.561888 -340.520482) (xy 105.561384 -340.492842)
			(xy 105.561905 -340.464957) (xy 105.570217 -340.40981) (xy 105.586655 -340.356518) (xy 105.610853 -340.306272)
			(xy 105.642269 -340.260193) (xy 105.680202 -340.219311) (xy 105.723804 -340.184539) (xy 105.772102 -340.156654)
			(xy 105.824017 -340.136279) (xy 105.878388 -340.123869) (xy 105.934002 -340.119702) (xy 105.989616 -340.123869)
			(xy 106.043987 -340.136279) (xy 106.095902 -340.156654) (xy 106.1442 -340.184539) (xy 106.187802 -340.219311)
			(xy 106.225735 -340.260193) (xy 106.257151 -340.306272) (xy 106.281349 -340.356518) (xy 106.297787 -340.40981)
			(xy 106.306099 -340.464957) (xy 106.30662 -340.492842) (xy 106.306114 -340.520484) (xy 106.297958 -340.575163)
			(xy 106.281817 -340.628039) (xy 106.258045 -340.677951) (xy 106.227162 -340.723805) (xy 106.189847 -340.764596)
			(xy 106.168698 -340.782402) (xy 106.160266 -340.789993) (xy 106.150507 -340.810442) (xy 106.149902 -340.821772)
			(xy 106.149902 -340.900512) (xy 106.150554 -340.91183) (xy 106.160305 -340.932263) (xy 106.168698 -340.939882)
			(xy 106.189817 -340.957721) (xy 106.227132 -340.998508) (xy 106.258017 -341.044356) (xy 106.281795 -341.09426)
			(xy 106.297945 -341.147129) (xy 106.306114 -341.201802) (xy 106.30662 -341.229442) (xy 106.306104 -341.256283)
			(xy 106.298407 -341.30941) (xy 106.283166 -341.360883) (xy 106.260695 -341.409636) (xy 106.23146 -341.454658)
			(xy 106.196065 -341.495019) (xy 106.155245 -341.529882) (xy 106.109843 -341.558525) (xy 106.060801 -341.580356)
			(xy 106.035094 -341.58809) (xy 106.03484 -341.58809) (xy 106.023794 -341.591867) (xy 106.00646 -341.607465)
			(xy 106.001566 -341.618062) (xy 105.971594 -341.692992) (xy 105.967839 -341.704066) (xy 105.969694 -341.727353)
			(xy 105.97515 -341.737696) (xy 105.98752 -341.759346) (xy 106.006992 -341.805249) (xy 106.020171 -341.853339)
			(xy 106.026821 -341.902757) (xy 106.02722 -341.927688) (xy 106.026755 -341.954305) (xy 106.01918 -342.006999)
			(xy 106.004184 -342.058078) (xy 105.98207 -342.106502) (xy 105.95329 -342.151287) (xy 105.91843 -342.19152)
			(xy 105.878198 -342.226382) (xy 105.833415 -342.255163) (xy 105.784991 -342.277279) (xy 105.733912 -342.292277)
			(xy 105.681219 -342.299854) (xy 105.654602 -342.300306) (xy 105.62818 -342.299846) (xy 105.575865 -342.292396)
			(xy 105.525127 -342.277632) (xy 105.476982 -342.255848) (xy 105.432397 -342.227483) (xy 105.412032 -342.210644)
			(xy 105.405174 -342.204802) (xy 105.388156 -342.198452) (xy 105.303828 -342.198452) (xy 105.28681 -342.204802)
			(xy 105.279952 -342.210644) (xy 105.259586 -342.227483) (xy 105.215 -342.255848) (xy 105.166856 -342.277635)
			(xy 105.116119 -342.292406) (xy 105.063804 -342.299866) (xy 105.01096 -342.299866) (xy 104.958645 -342.292406)
			(xy 104.907908 -342.277635) (xy 104.859764 -342.255848) (xy 104.815178 -342.227483) (xy 104.794812 -342.210644)
			(xy 104.787954 -342.204802) (xy 104.770936 -342.198452) (xy 104.686608 -342.198452) (xy 104.66959 -342.204802)
			(xy 104.662732 -342.210644) (xy 104.642348 -342.227458) (xy 104.597764 -342.255819) (xy 104.549624 -342.277604)
			(xy 104.498891 -342.292377) (xy 104.446582 -342.299842) (xy 104.420162 -342.300306) (xy 104.392278 -342.299806)
			(xy 104.337134 -342.29149) (xy 104.283845 -342.275047) (xy 104.233602 -342.250847) (xy 104.187526 -342.219429)
			(xy 104.146648 -342.181495) (xy 104.111879 -342.137892) (xy 104.083996 -342.089595) (xy 104.063623 -342.037682)
			(xy 104.051215 -341.983312) (xy 104.047047 -341.9277) (xy 101.196636 -341.9277) (xy 100.424234 -342.700102)
			(xy 100.418646 -342.706706) (xy 100.415463 -342.711428) (xy 100.411104 -342.721945) (xy 100.41001 -342.727534)
			(xy 100.409248 -342.73617) (xy 100.409248 -342.825832) (xy 100.622606 -342.825832) (xy 100.626677 -342.77021)
			(xy 100.638803 -342.715773) (xy 100.658726 -342.663682) (xy 100.686022 -342.615047) (xy 100.720108 -342.570904)
			(xy 100.760257 -342.532195) (xy 100.805615 -342.499744) (xy 100.855215 -342.474243) (xy 100.907999 -342.456236)
			(xy 100.962842 -342.446106) (xy 101.018576 -342.444069) (xy 101.074013 -342.450169) (xy 101.12797 -342.464275)
			(xy 101.179299 -342.486087) (xy 101.226905 -342.515141) (xy 101.269773 -342.550816) (xy 101.30699 -342.592353)
			(xy 101.337763 -342.638866) (xy 101.361435 -342.689363) (xy 101.377503 -342.74277) (xy 101.385623 -342.797946)
			(xy 101.386132 -342.825832) (xy 101.385623 -342.853718) (xy 101.377503 -342.908894) (xy 101.361435 -342.962301)
			(xy 101.337763 -343.012798) (xy 101.30699 -343.059311) (xy 101.269773 -343.100848) (xy 101.226905 -343.136523)
			(xy 101.179299 -343.165577) (xy 101.12797 -343.187389) (xy 101.074013 -343.201495) (xy 101.018576 -343.207595)
			(xy 100.962842 -343.205558) (xy 100.907999 -343.195428) (xy 100.855215 -343.177421) (xy 100.805615 -343.15192)
			(xy 100.760257 -343.119469) (xy 100.720108 -343.08076) (xy 100.686022 -343.036617) (xy 100.658726 -342.987982)
			(xy 100.638803 -342.935891) (xy 100.626677 -342.881454) (xy 100.622606 -342.825832) (xy 100.409248 -342.825832)
			(xy 100.409248 -343.234264) (xy 100.41001 -343.2429) (xy 100.41114 -343.248477) (xy 100.415506 -343.258982)
			(xy 100.418646 -343.263728) (xy 100.424234 -343.270332) (xy 100.490782 -343.33688) (xy 100.493358 -343.33939)
			(xy 100.499093 -343.343727) (xy 100.502212 -343.345516) (xy 100.5078 -343.348564) (xy 100.514658 -343.350342)
			(xy 100.542067 -343.357437) (xy 100.594569 -343.378621) (xy 100.643361 -343.407338) (xy 100.687367 -343.442957)
			(xy 100.72562 -343.484694) (xy 100.757279 -343.53163) (xy 100.781646 -343.582733) (xy 100.798186 -343.636878)
			(xy 100.806534 -343.692874) (xy 100.807012 -343.721182) (xy 100.80655 -343.748436) (xy 100.798795 -343.802389)
			(xy 100.783441 -343.854689) (xy 100.760799 -343.904272) (xy 100.731332 -343.950127) (xy 100.695638 -343.991323)
			(xy 100.654445 -344.027019) (xy 100.608591 -344.056489) (xy 100.55901 -344.079133) (xy 100.50671 -344.09449)
			(xy 100.452758 -344.102248) (xy 100.425504 -344.10269) (xy 100.397203 -344.102168) (xy 100.341223 -344.09379)
			(xy 100.287096 -344.077233) (xy 100.236009 -344.05286) (xy 100.189084 -344.021206) (xy 100.147352 -343.982965)
			(xy 100.111728 -343.938979) (xy 100.082995 -343.890211) (xy 100.061782 -343.837733) (xy 100.054664 -343.810336)
			(xy 100.052886 -343.803478) (xy 100.049838 -343.79789) (xy 100.048041 -343.794776) (xy 100.043708 -343.789038)
			(xy 100.041202 -343.78646) (xy 99.866704 -343.611962) (xy 99.84942 -343.593963) (xy 99.820112 -343.55358)
			(xy 99.797471 -343.509114) (xy 99.782055 -343.461657) (xy 99.774241 -343.412375) (xy 99.77374 -343.387426)
			(xy 99.77374 -342.583008) (xy 99.774229 -342.558058) (xy 99.782032 -342.508772) (xy 99.797448 -342.461313)
			(xy 99.820098 -342.41685) (xy 99.849423 -342.376476) (xy 99.866704 -342.358472) (xy 100.07092 -342.154256)
			(xy 100.071428 -342.153748) (xy 100.079048 -342.145874) (xy 100.084846 -342.139118) (xy 100.091728 -342.122711)
			(xy 100.092552 -342.104938) (xy 100.090224 -342.096344) (xy 100.057966 -342.007952) (xy 100.055285 -342.00111)
			(xy 100.046635 -341.989238) (xy 100.040948 -341.984584) (xy 100.02901 -341.975694) (xy 100.021898 -341.975186)
			(xy 99.993222 -341.972811) (xy 99.937008 -341.960529) (xy 99.883275 -341.939949) (xy 99.833238 -341.91154)
			(xy 99.788031 -341.875943) (xy 99.748678 -341.833965) (xy 99.71607 -341.786557) (xy 99.690946 -341.734793)
			(xy 99.673874 -341.679844) (xy 99.665241 -341.622956) (xy 99.664774 -341.594186) (xy 99.665261 -341.566276)
			(xy 99.673399 -341.511051) (xy 99.689499 -341.457603) (xy 99.713218 -341.407071) (xy 99.744048 -341.360537)
			(xy 99.76231 -341.339424) (xy 99.76866 -341.332312) (xy 99.771962 -341.323676) (xy 99.773504 -341.319328)
			(xy 99.775162 -341.310254) (xy 99.775264 -341.305642) (xy 99.775264 -341.237316) (xy 99.775166 -341.232703)
			(xy 99.773509 -341.223628) (xy 99.771962 -341.219282) (xy 99.76866 -341.210646) (xy 99.76231 -341.203534)
			(xy 99.74403 -341.182435) (xy 99.713198 -341.135897) (xy 99.689477 -341.085363) (xy 99.673372 -341.031912)
			(xy 99.665228 -340.976684) (xy 99.664774 -340.948772) (xy 99.66526 -340.921521) (xy 99.673016 -340.867573)
			(xy 99.688371 -340.815278) (xy 99.711013 -340.765701) (xy 99.740479 -340.719851) (xy 99.77617 -340.67866)
			(xy 99.817361 -340.642969) (xy 99.863211 -340.613503) (xy 99.912788 -340.590861) (xy 99.965083 -340.575506)
			(xy 100.019031 -340.56775) (xy 100.073533 -340.56775) (xy 100.127481 -340.575506) (xy 100.179776 -340.590861)
			(xy 100.229353 -340.613503) (xy 100.275203 -340.642969) (xy 100.316394 -340.67866) (xy 100.352085 -340.719851)
			(xy 100.381551 -340.765701) (xy 100.404193 -340.815278) (xy 100.419548 -340.867573) (xy 100.427304 -340.921521)
			(xy 100.42779 -340.948772) (xy 100.427306 -340.976684) (xy 100.419175 -341.031912) (xy 100.403081 -341.085366)
			(xy 100.37937 -341.135904) (xy 100.348546 -341.182446) (xy 100.330254 -341.203534) (xy 100.323904 -341.210646)
			(xy 100.320602 -341.219282) (xy 100.319055 -341.223629) (xy 100.317387 -341.232703) (xy 100.3173 -341.237316)
			(xy 100.3173 -341.305642) (xy 100.317403 -341.310254) (xy 100.319068 -341.319325) (xy 100.320602 -341.323676)
			(xy 100.323904 -341.332312) (xy 100.330254 -341.339424) (xy 100.350429 -341.362818) (xy 100.383731 -341.414846)
			(xy 100.408233 -341.471551) (xy 100.4233 -341.531458) (xy 100.42652 -341.562182) (xy 100.42652 -341.56269)
			(xy 100.427403 -341.56976) (xy 100.432568 -341.583032) (xy 100.43668 -341.588852) (xy 100.440998 -341.594694)
			(xy 100.452682 -341.60333) (xy 100.471986 -341.610442) (xy 100.549202 -341.638382) (xy 100.56128 -341.641188)
			(xy 100.585573 -341.636415) (xy 100.595684 -341.629238) (xy 100.599494 -341.625682) (xy 100.673154 -341.552022)
			(xy 100.678742 -341.545418) (xy 100.681928 -341.540697) (xy 100.686293 -341.530181) (xy 100.687378 -341.52459)
			(xy 100.68814 -341.515954) (xy 100.68814 -340.831678) (xy 100.687378 -340.823042) (xy 100.686252 -340.817464)
			(xy 100.681892 -340.806954) (xy 100.678742 -340.802214) (xy 100.673154 -340.79561) (xy 99.796092 -339.918548)
			(xy 99.77881 -339.900548) (xy 99.749504 -339.860164) (xy 99.726867 -339.815698) (xy 99.711453 -339.768242)
			(xy 99.703641 -339.71896) (xy 99.703128 -339.694012) (xy 99.703128 -337.02752) (xy 99.703616 -337.00257)
			(xy 99.711417 -336.953282) (xy 99.726832 -336.905822) (xy 99.74948 -336.861357) (xy 99.778804 -336.820981)
			(xy 99.796092 -336.802984) (xy 100.879148 -335.719928) (xy 100.884235 -335.713578) (xy 100.890454 -335.698552)
			(xy 100.89134 -335.690464) (xy 100.89134 -328.735436) (xy 100.890904 -328.725372) (xy 100.883166 -328.70679)
			(xy 100.876354 -328.699368) (xy 95.962724 -323.785738) (xy 95.955323 -323.778899) (xy 95.936725 -323.771187)
			(xy 95.926656 -323.770752) (xy 93.221048 -323.770752) (xy 93.21103 -323.771231) (xy 93.192514 -323.77888)
			(xy 93.178334 -323.793033) (xy 93.17065 -323.811535) (xy 93.170248 -323.821552) (xy 93.170248 -332.263242)
			(xy 93.169763 -332.288193) (xy 93.161966 -332.337483) (xy 93.146555 -332.384947) (xy 93.123909 -332.429415)
			(xy 93.094586 -332.469794) (xy 93.077284 -332.487778) (xy 92.045282 -333.51978) (xy 92.039694 -333.526384)
			(xy 92.036506 -333.531104) (xy 92.032139 -333.54162) (xy 92.031058 -333.547212) (xy 92.030296 -333.555848)
			(xy 92.030296 -334.65135) (xy 92.031058 -334.659986) (xy 92.032185 -334.665564) (xy 92.036545 -334.676074)
			(xy 92.039694 -334.680814) (xy 92.045282 -334.687418) (xy 92.874084 -335.51622) (xy 92.891369 -335.534218)
			(xy 92.920681 -335.574601) (xy 92.943325 -335.619067) (xy 92.958745 -335.666523) (xy 92.966562 -335.715807)
			(xy 92.967048 -335.740756) (xy 92.967048 -336.708242) (xy 92.966563 -336.733193) (xy 92.958766 -336.782483)
			(xy 92.943355 -336.829947) (xy 92.920709 -336.874415) (xy 92.891386 -336.914794) (xy 92.874084 -336.932778)
			(xy 92.789262 -337.0176) (xy 95.771147 -337.0176) (xy 95.775316 -336.961981) (xy 95.787728 -336.907605)
			(xy 95.808105 -336.855686) (xy 95.835994 -336.807385) (xy 95.870771 -336.76378) (xy 95.911658 -336.725845)
			(xy 95.957743 -336.694429) (xy 96.007996 -336.670233) (xy 96.061294 -336.653797) (xy 96.116447 -336.645488)
			(xy 96.144334 -336.644996) (xy 96.170756 -336.645435) (xy 96.223073 -336.65289) (xy 96.273811 -336.667659)
			(xy 96.321955 -336.689447) (xy 96.366539 -336.717817) (xy 96.386904 -336.734658) (xy 96.393762 -336.7405)
			(xy 96.41078 -336.74685) (xy 96.495108 -336.74685) (xy 96.512126 -336.7405) (xy 96.518984 -336.734658)
			(xy 96.53935 -336.717819) (xy 96.583936 -336.689454) (xy 96.63208 -336.667667) (xy 96.682817 -336.652896)
			(xy 96.735132 -336.645436) (xy 96.787976 -336.645436) (xy 96.840291 -336.652896) (xy 96.891028 -336.667667)
			(xy 96.939172 -336.689454) (xy 96.983758 -336.717819) (xy 97.004124 -336.734658) (xy 97.010982 -336.7405)
			(xy 97.028 -336.74685) (xy 97.112328 -336.74685) (xy 97.129346 -336.7405) (xy 97.136204 -336.734658)
			(xy 97.157001 -336.717486) (xy 97.202585 -336.688665) (xy 97.251853 -336.666726) (xy 97.277682 -336.658966)
			(xy 97.277936 -336.658966) (xy 97.288984 -336.655196) (xy 97.306315 -336.639591) (xy 97.31121 -336.628994)
			(xy 97.341182 -336.554064) (xy 97.344904 -336.542981) (xy 97.343072 -336.519703) (xy 97.337626 -336.50936)
			(xy 97.325246 -336.487715) (xy 97.305774 -336.441811) (xy 97.292598 -336.393719) (xy 97.285952 -336.3443)
			(xy 97.285556 -336.319368) (xy 97.286078 -336.291727) (xy 97.294232 -336.237048) (xy 97.31037 -336.184174)
			(xy 97.33414 -336.134262) (xy 97.365019 -336.088407) (xy 97.402331 -336.047615) (xy 97.423478 -336.029808)
			(xy 97.431902 -336.022209) (xy 97.441666 -336.001766) (xy 97.442274 -335.990438) (xy 97.442274 -335.911698)
			(xy 97.441624 -335.90038) (xy 97.431873 -335.879946) (xy 97.423478 -335.872328) (xy 97.402359 -335.854489)
			(xy 97.365045 -335.813702) (xy 97.334161 -335.767854) (xy 97.310383 -335.717949) (xy 97.294232 -335.665081)
			(xy 97.286062 -335.610408) (xy 97.285556 -335.582768) (xy 97.286077 -335.554883) (xy 97.294389 -335.499736)
			(xy 97.310827 -335.446444) (xy 97.335025 -335.396198) (xy 97.366441 -335.350119) (xy 97.404374 -335.309237)
			(xy 97.447976 -335.274465) (xy 97.496274 -335.24658) (xy 97.548189 -335.226205) (xy 97.60256 -335.213795)
			(xy 97.658174 -335.209628) (xy 97.713788 -335.213795) (xy 97.768159 -335.226205) (xy 97.820074 -335.24658)
			(xy 97.868372 -335.274465) (xy 97.911974 -335.309237) (xy 97.949907 -335.350119) (xy 97.981323 -335.396198)
			(xy 98.005521 -335.446444) (xy 98.021959 -335.499736) (xy 98.030271 -335.554883) (xy 98.030792 -335.582768)
			(xy 98.030314 -335.610411) (xy 98.022154 -335.665092) (xy 98.006008 -335.717969) (xy 97.98223 -335.767881)
			(xy 97.951342 -335.813734) (xy 97.914021 -335.854523) (xy 97.89287 -335.872328) (xy 97.884438 -335.87992)
			(xy 97.874676 -335.900368) (xy 97.874074 -335.911698) (xy 97.874074 -335.990438) (xy 97.874688 -336.001761)
			(xy 97.884463 -336.022195) (xy 97.89287 -336.029808) (xy 97.914017 -336.047616) (xy 97.951326 -336.088411)
			(xy 97.982205 -336.134266) (xy 98.005978 -336.184177) (xy 98.022124 -336.23705) (xy 98.030288 -336.291726)
			(xy 98.030792 -336.319368) (xy 98.030319 -336.346211) (xy 98.022619 -336.399341) (xy 98.007372 -336.450816)
			(xy 97.984896 -336.499569) (xy 97.955655 -336.544593) (xy 97.920256 -336.584953) (xy 97.879429 -336.619815)
			(xy 97.834023 -336.648456) (xy 97.784975 -336.670284) (xy 97.759266 -336.678016) (xy 97.759012 -336.678016)
			(xy 97.747956 -336.68177) (xy 97.730626 -336.697384) (xy 97.725738 -336.707988) (xy 97.695766 -336.782918)
			(xy 97.691997 -336.793989) (xy 97.693862 -336.817279) (xy 97.699322 -336.827622) (xy 97.711699 -336.849268)
			(xy 97.731171 -336.895173) (xy 97.744348 -336.943264) (xy 97.750995 -336.992682) (xy 97.751392 -337.017614)
			(xy 97.750979 -337.044233) (xy 97.7434 -337.09693) (xy 97.728399 -337.148011) (xy 97.70628 -337.196438)
			(xy 97.677495 -337.241224) (xy 97.642629 -337.281457) (xy 97.602392 -337.316319) (xy 97.557603 -337.345099)
			(xy 97.509174 -337.367213) (xy 97.458091 -337.382208) (xy 97.405393 -337.389782) (xy 97.378774 -337.390232)
			(xy 97.352352 -337.389782) (xy 97.300037 -337.382329) (xy 97.249298 -337.367562) (xy 97.201154 -337.345776)
			(xy 97.156569 -337.31741) (xy 97.136204 -337.30057) (xy 97.129346 -337.294728) (xy 97.112328 -337.288378)
			(xy 97.028 -337.288378) (xy 97.010982 -337.294728) (xy 97.004124 -337.30057) (xy 96.983758 -337.317409)
			(xy 96.939172 -337.345774) (xy 96.891028 -337.367561) (xy 96.840291 -337.382332) (xy 96.787976 -337.389792)
			(xy 96.735132 -337.389792) (xy 96.682817 -337.382332) (xy 96.63208 -337.367561) (xy 96.583936 -337.345774)
			(xy 96.53935 -337.317409) (xy 96.518984 -337.30057) (xy 96.512126 -337.294728) (xy 96.495108 -337.288378)
			(xy 96.41078 -337.288378) (xy 96.393762 -337.294728) (xy 96.386904 -337.30057) (xy 96.366533 -337.317402)
			(xy 96.321945 -337.345759) (xy 96.273802 -337.36754) (xy 96.223066 -337.382309) (xy 96.170755 -337.38977)
			(xy 96.144334 -337.390232) (xy 96.116447 -337.389712) (xy 96.061294 -337.381403) (xy 96.007996 -337.364967)
			(xy 95.957743 -337.340771) (xy 95.911658 -337.309355) (xy 95.870771 -337.27142) (xy 95.835994 -337.227815)
			(xy 95.808105 -337.179514) (xy 95.787728 -337.127595) (xy 95.775316 -337.073219) (xy 95.771147 -337.0176)
			(xy 92.789262 -337.0176) (xy 92.172282 -337.63458) (xy 92.166694 -337.641184) (xy 92.163506 -337.645904)
			(xy 92.159139 -337.65642) (xy 92.158058 -337.662012) (xy 92.157296 -337.670648) (xy 92.157296 -337.915758)
			(xy 92.346778 -337.915758) (xy 92.350849 -337.860136) (xy 92.362975 -337.805699) (xy 92.382898 -337.753608)
			(xy 92.410194 -337.704973) (xy 92.44428 -337.66083) (xy 92.484429 -337.622121) (xy 92.529787 -337.58967)
			(xy 92.579387 -337.564169) (xy 92.632171 -337.546162) (xy 92.687014 -337.536032) (xy 92.742748 -337.533995)
			(xy 92.798185 -337.540095) (xy 92.852142 -337.554201) (xy 92.903471 -337.576013) (xy 92.951077 -337.605067)
			(xy 92.993945 -337.640742) (xy 93.031162 -337.682279) (xy 93.061935 -337.728792) (xy 93.085607 -337.779289)
			(xy 93.101675 -337.832696) (xy 93.109795 -337.887872) (xy 93.110304 -337.915758) (xy 93.109795 -337.943644)
			(xy 93.101675 -337.99882) (xy 93.085607 -338.052227) (xy 93.061935 -338.102724) (xy 93.031162 -338.149237)
			(xy 92.993945 -338.190774) (xy 92.951077 -338.226449) (xy 92.903471 -338.255503) (xy 92.852142 -338.277315)
			(xy 92.798185 -338.291421) (xy 92.742748 -338.297521) (xy 92.687014 -338.295484) (xy 92.632171 -338.285354)
			(xy 92.579387 -338.267347) (xy 92.529787 -338.241846) (xy 92.484429 -338.209395) (xy 92.44428 -338.170686)
			(xy 92.410194 -338.126543) (xy 92.382898 -338.077908) (xy 92.362975 -338.025817) (xy 92.350849 -337.97138)
			(xy 92.346778 -337.915758) (xy 92.157296 -337.915758) (xy 92.157296 -338.348066) (xy 92.158058 -338.356702)
			(xy 92.159187 -338.362279) (xy 92.163549 -338.372787) (xy 92.166694 -338.37753) (xy 92.172282 -338.384134)
			(xy 92.214954 -338.426806) (xy 92.217529 -338.429316) (xy 92.223264 -338.433654) (xy 92.226384 -338.435442)
			(xy 92.231972 -338.43849) (xy 92.23883 -338.440268) (xy 92.26624 -338.447361) (xy 92.318743 -338.468543)
			(xy 92.367536 -338.497259) (xy 92.411543 -338.532878) (xy 92.449797 -338.574615) (xy 92.481455 -338.621552)
			(xy 92.505821 -338.672656) (xy 92.522359 -338.726803) (xy 92.530704 -338.7828) (xy 92.531184 -338.811108)
			(xy 92.53072 -338.83836) (xy 92.522962 -338.892309) (xy 92.507605 -338.944604) (xy 92.484962 -338.994182)
			(xy 92.455493 -339.040032) (xy 92.419799 -339.081222) (xy 92.378606 -339.116912) (xy 92.332754 -339.146377)
			(xy 92.283174 -339.169016) (xy 92.230877 -339.184369) (xy 92.176928 -339.192122) (xy 92.149676 -339.192616)
			(xy 92.121375 -339.192092) (xy 92.065397 -339.183711) (xy 92.011272 -339.167152) (xy 91.960187 -339.142778)
			(xy 91.913265 -339.111123) (xy 91.871533 -339.072884) (xy 91.83591 -339.028898) (xy 91.807176 -338.980132)
			(xy 91.785963 -338.927656) (xy 91.778836 -338.900262) (xy 91.777058 -338.893404) (xy 91.77401 -338.887816)
			(xy 91.772212 -338.884703) (xy 91.767877 -338.878967) (xy 91.765374 -338.876386) (xy 91.614752 -338.725764)
			(xy 91.597466 -338.707766) (xy 91.568153 -338.667384) (xy 91.545509 -338.622919) (xy 91.530089 -338.575461)
			(xy 91.522274 -338.526178) (xy 91.521788 -338.501228) (xy 91.521788 -337.517486) (xy 91.522245 -337.492532)
			(xy 91.53004 -337.443237) (xy 91.54545 -337.395768) (xy 91.568097 -337.351294) (xy 91.597423 -337.310911)
			(xy 91.614752 -337.29295) (xy 91.693746 -337.213956) (xy 91.701842 -337.204273) (xy 91.708227 -337.179888)
			(xy 91.705938 -337.167474) (xy 91.685872 -337.0834) (xy 91.683941 -337.076279) (xy 91.676586 -337.063496)
			(xy 91.671394 -337.058254) (xy 91.66717 -337.054484) (xy 91.657425 -337.048722) (xy 91.65209 -337.046824)
			(xy 91.626927 -337.038127) (xy 91.579102 -337.014736) (xy 91.534995 -336.984921) (xy 91.495463 -336.949263)
			(xy 91.461273 -336.908453) (xy 91.433091 -336.863285) (xy 91.411464 -336.814637) (xy 91.396813 -336.763454)
			(xy 91.389421 -336.710731) (xy 91.388946 -336.684112) (xy 91.389431 -336.656201) (xy 91.397565 -336.600974)
			(xy 91.413662 -336.547523) (xy 91.437377 -336.496988) (xy 91.468203 -336.450449) (xy 91.486482 -336.42935)
			(xy 91.492832 -336.422238) (xy 91.496134 -336.413602) (xy 91.497679 -336.409255) (xy 91.499343 -336.400181)
			(xy 91.499436 -336.395568) (xy 91.499436 -336.327242) (xy 91.499332 -336.322631) (xy 91.497665 -336.313559)
			(xy 91.496134 -336.309208) (xy 91.492832 -336.300572) (xy 91.486482 -336.29346) (xy 91.468207 -336.272359)
			(xy 91.437387 -336.225818) (xy 91.413677 -336.175283) (xy 91.397584 -336.121833) (xy 91.389451 -336.066608)
			(xy 91.388946 -336.038698) (xy 91.389432 -336.011447) (xy 91.397188 -335.957499) (xy 91.412543 -335.905204)
			(xy 91.435185 -335.855627) (xy 91.464651 -335.809777) (xy 91.500342 -335.768586) (xy 91.541533 -335.732895)
			(xy 91.587383 -335.703429) (xy 91.63696 -335.680787) (xy 91.689255 -335.665432) (xy 91.743203 -335.657676)
			(xy 91.797705 -335.657676) (xy 91.851653 -335.665432) (xy 91.903948 -335.680787) (xy 91.953525 -335.703429)
			(xy 91.999375 -335.732895) (xy 92.040566 -335.768586) (xy 92.076257 -335.809777) (xy 92.105723 -335.855627)
			(xy 92.128365 -335.905204) (xy 92.14372 -335.957499) (xy 92.151476 -336.011447) (xy 92.151962 -336.038698)
			(xy 92.151476 -336.066609) (xy 92.143341 -336.121835) (xy 92.127244 -336.175286) (xy 92.103528 -336.22582)
			(xy 92.072701 -336.272358) (xy 92.054426 -336.29346) (xy 92.048076 -336.300572) (xy 92.044774 -336.309208)
			(xy 92.04323 -336.313556) (xy 92.041567 -336.322629) (xy 92.041472 -336.327242) (xy 92.041472 -336.395568)
			(xy 92.041577 -336.400179) (xy 92.043246 -336.40925) (xy 92.044774 -336.413602) (xy 92.048076 -336.422238)
			(xy 92.054426 -336.42935) (xy 92.071751 -336.44934) (xy 92.101303 -336.493216) (xy 92.124522 -336.540747)
			(xy 92.133166 -336.565748) (xy 92.133166 -336.566256) (xy 92.13342 -336.56651) (xy 92.135605 -336.572394)
			(xy 92.14241 -336.582935) (xy 92.146882 -336.587338) (xy 92.151454 -336.591656) (xy 92.16263 -336.597752)
			(xy 92.257118 -336.620104) (xy 92.269038 -336.621487) (xy 92.291947 -336.614451) (xy 92.30106 -336.606642)
			(xy 92.319348 -336.588354) (xy 92.324439 -336.582005) (xy 92.330665 -336.56698) (xy 92.33154 -336.55889)
			(xy 92.33154 -335.893918) (xy 92.330778 -335.885282) (xy 92.329656 -335.879702) (xy 92.325303 -335.869187)
			(xy 92.322142 -335.864454) (xy 92.316554 -335.85785) (xy 91.487752 -335.029048) (xy 91.470467 -335.01105)
			(xy 91.441156 -334.970667) (xy 91.418514 -334.926202) (xy 91.403097 -334.878744) (xy 91.395284 -334.829461)
			(xy 91.394788 -334.804512) (xy 91.394788 -333.402686) (xy 91.395245 -333.377732) (xy 91.40304 -333.328437)
			(xy 91.41845 -333.280968) (xy 91.441097 -333.236494) (xy 91.470423 -333.196111) (xy 91.487752 -333.17815)
			(xy 92.522548 -332.143354) (xy 92.527639 -332.137005) (xy 92.533865 -332.12198) (xy 92.53474 -332.11389)
			(xy 92.53474 -323.821552) (xy 92.534244 -323.811548) (xy 92.526578 -323.793066) (xy 92.512428 -323.778918)
			(xy 92.493944 -323.771254) (xy 92.48394 -323.770752) (xy 84.940648 -323.770752) (xy 84.93063 -323.771231)
			(xy 84.912114 -323.77888) (xy 84.897934 -323.793033) (xy 84.89025 -323.811535) (xy 84.889848 -323.821552)
			(xy 84.889848 -332.237842) (xy 84.889363 -332.262793) (xy 84.881566 -332.312083) (xy 84.866155 -332.359547)
			(xy 84.843509 -332.404015) (xy 84.814186 -332.444394) (xy 84.796884 -332.462378) (xy 83.632802 -333.62646)
			(xy 83.627214 -333.633064) (xy 83.624023 -333.637783) (xy 83.61965 -333.648298) (xy 83.618578 -333.653892)
			(xy 83.617816 -333.662528) (xy 83.617816 -334.49133) (xy 83.618578 -334.499966) (xy 83.619704 -334.505545)
			(xy 83.624062 -334.516056) (xy 83.627214 -334.520794) (xy 83.632802 -334.527398) (xy 84.593684 -335.48828)
			(xy 84.610966 -335.50628) (xy 84.64027 -335.546664) (xy 84.662905 -335.59113) (xy 84.678316 -335.638587)
			(xy 84.686124 -335.687868) (xy 84.686648 -335.712816) (xy 84.686648 -336.682842) (xy 84.686163 -336.707793)
			(xy 84.678366 -336.757083) (xy 84.662955 -336.804547) (xy 84.640309 -336.849015) (xy 84.610986 -336.889394)
			(xy 84.593684 -336.907378) (xy 84.534262 -336.9668) (xy 87.439947 -336.9668) (xy 87.444116 -336.911181)
			(xy 87.456528 -336.856805) (xy 87.476905 -336.804886) (xy 87.504794 -336.756585) (xy 87.539571 -336.71298)
			(xy 87.580458 -336.675045) (xy 87.626543 -336.643629) (xy 87.676796 -336.619433) (xy 87.730094 -336.602997)
			(xy 87.785247 -336.594688) (xy 87.813134 -336.594196) (xy 87.839556 -336.594635) (xy 87.891873 -336.60209)
			(xy 87.942611 -336.616859) (xy 87.990755 -336.638647) (xy 88.035339 -336.667017) (xy 88.055704 -336.683858)
			(xy 88.062562 -336.6897) (xy 88.07958 -336.69605) (xy 88.163908 -336.69605) (xy 88.180926 -336.6897)
			(xy 88.187784 -336.683858) (xy 88.20815 -336.667019) (xy 88.252736 -336.638654) (xy 88.30088 -336.616867)
			(xy 88.351617 -336.602096) (xy 88.403932 -336.594636) (xy 88.456776 -336.594636) (xy 88.509091 -336.602096)
			(xy 88.559828 -336.616867) (xy 88.607972 -336.638654) (xy 88.652558 -336.667019) (xy 88.672924 -336.683858)
			(xy 88.679782 -336.6897) (xy 88.6968 -336.69605) (xy 88.781128 -336.69605) (xy 88.798146 -336.6897)
			(xy 88.805004 -336.683858) (xy 88.825835 -336.666667) (xy 88.871508 -336.637844) (xy 88.920863 -336.615915)
			(xy 88.946736 -336.608166) (xy 88.95842 -336.604864) (xy 88.9762 -336.588608) (xy 89.009474 -336.501232)
			(xy 89.01313 -336.489877) (xy 89.010739 -336.46617) (xy 89.004902 -336.455766) (xy 88.99112 -336.43326)
			(xy 88.969376 -336.385174) (xy 88.954635 -336.334501) (xy 88.947192 -336.282255) (xy 88.946736 -336.255868)
			(xy 88.947229 -336.228225) (xy 88.955384 -336.173544) (xy 88.971527 -336.120668) (xy 88.995301 -336.070755)
			(xy 89.026187 -336.024902) (xy 89.063507 -335.984113) (xy 89.084658 -335.966308) (xy 89.093079 -335.958705)
			(xy 89.102846 -335.938266) (xy 89.103454 -335.926938) (xy 89.103454 -335.848198) (xy 89.102811 -335.836879)
			(xy 89.093055 -335.816445) (xy 89.084658 -335.808828) (xy 89.063534 -335.790994) (xy 89.026222 -335.750205)
			(xy 88.995339 -335.704356) (xy 88.971562 -335.65445) (xy 88.955412 -335.601581) (xy 88.947242 -335.546908)
			(xy 88.946736 -335.519268) (xy 88.947257 -335.491383) (xy 88.955569 -335.436236) (xy 88.972007 -335.382944)
			(xy 88.996205 -335.332698) (xy 89.027621 -335.286619) (xy 89.065554 -335.245737) (xy 89.109156 -335.210965)
			(xy 89.157454 -335.18308) (xy 89.209369 -335.162705) (xy 89.26374 -335.150295) (xy 89.319354 -335.146128)
			(xy 89.374968 -335.150295) (xy 89.429339 -335.162705) (xy 89.481254 -335.18308) (xy 89.529552 -335.210965)
			(xy 89.573154 -335.245737) (xy 89.611087 -335.286619) (xy 89.642503 -335.332698) (xy 89.666701 -335.382944)
			(xy 89.683139 -335.436236) (xy 89.691451 -335.491383) (xy 89.691972 -335.519268) (xy 89.691502 -335.546912)
			(xy 89.683341 -335.601593) (xy 89.667194 -335.65447) (xy 89.643415 -335.704382) (xy 89.612525 -335.750235)
			(xy 89.575202 -335.791023) (xy 89.55405 -335.808828) (xy 89.545615 -335.816417) (xy 89.535855 -335.836867)
			(xy 89.535254 -335.848198) (xy 89.535254 -335.926938) (xy 89.535874 -335.93826) (xy 89.545645 -335.958694)
			(xy 89.55405 -335.966308) (xy 89.575192 -335.984121) (xy 89.612503 -336.024914) (xy 89.643384 -336.070768)
			(xy 89.667157 -336.120678) (xy 89.683303 -336.17355) (xy 89.691468 -336.228227) (xy 89.691972 -336.255868)
			(xy 89.69155 -336.282722) (xy 89.683817 -336.335871) (xy 89.668536 -336.38736) (xy 89.646023 -336.436122)
			(xy 89.616744 -336.481149) (xy 89.581306 -336.521506) (xy 89.540442 -336.55636) (xy 89.494998 -336.584987)
			(xy 89.445917 -336.606796) (xy 89.420192 -336.614516) (xy 89.408508 -336.617818) (xy 89.390728 -336.634074)
			(xy 89.357454 -336.72145) (xy 89.353819 -336.732809) (xy 89.356199 -336.75651) (xy 89.362026 -336.766916)
			(xy 89.375793 -336.789431) (xy 89.397542 -336.837513) (xy 89.412288 -336.888183) (xy 89.419734 -336.940428)
			(xy 89.420192 -336.966814) (xy 89.419779 -336.993433) (xy 89.4122 -337.04613) (xy 89.397199 -337.097211)
			(xy 89.37508 -337.145638) (xy 89.346295 -337.190424) (xy 89.311429 -337.230657) (xy 89.271192 -337.265519)
			(xy 89.226403 -337.294299) (xy 89.177974 -337.316413) (xy 89.126891 -337.331408) (xy 89.074193 -337.338982)
			(xy 89.047574 -337.339432) (xy 89.021152 -337.338982) (xy 88.968837 -337.331529) (xy 88.918098 -337.316762)
			(xy 88.869954 -337.294976) (xy 88.825369 -337.26661) (xy 88.805004 -337.24977) (xy 88.798146 -337.243928)
			(xy 88.781128 -337.237578) (xy 88.6968 -337.237578) (xy 88.679782 -337.243928) (xy 88.672924 -337.24977)
			(xy 88.652558 -337.266609) (xy 88.607972 -337.294974) (xy 88.559828 -337.316761) (xy 88.509091 -337.331532)
			(xy 88.456776 -337.338992) (xy 88.403932 -337.338992) (xy 88.351617 -337.331532) (xy 88.30088 -337.316761)
			(xy 88.252736 -337.294974) (xy 88.20815 -337.266609) (xy 88.187784 -337.24977) (xy 88.180926 -337.243928)
			(xy 88.163908 -337.237578) (xy 88.07958 -337.237578) (xy 88.062562 -337.243928) (xy 88.055704 -337.24977)
			(xy 88.035333 -337.266602) (xy 87.990745 -337.294959) (xy 87.942602 -337.31674) (xy 87.891866 -337.331509)
			(xy 87.839555 -337.33897) (xy 87.813134 -337.339432) (xy 87.785247 -337.338912) (xy 87.730094 -337.330603)
			(xy 87.676796 -337.314167) (xy 87.626543 -337.289971) (xy 87.580458 -337.258555) (xy 87.539571 -337.22062)
			(xy 87.504794 -337.177015) (xy 87.476905 -337.128714) (xy 87.456528 -337.076795) (xy 87.444116 -337.022419)
			(xy 87.439947 -336.9668) (xy 84.534262 -336.9668) (xy 83.922362 -337.5787) (xy 83.916774 -337.585304)
			(xy 83.913589 -337.590025) (xy 83.909227 -337.600542) (xy 83.908138 -337.606132) (xy 83.907376 -337.614768)
			(xy 83.907376 -337.864958) (xy 84.015578 -337.864958) (xy 84.019649 -337.809336) (xy 84.031775 -337.754899)
			(xy 84.051698 -337.702808) (xy 84.078994 -337.654173) (xy 84.11308 -337.61003) (xy 84.153229 -337.571321)
			(xy 84.198587 -337.53887) (xy 84.248187 -337.513369) (xy 84.300971 -337.495362) (xy 84.355814 -337.485232)
			(xy 84.411548 -337.483195) (xy 84.466985 -337.489295) (xy 84.520942 -337.503401) (xy 84.572271 -337.525213)
			(xy 84.619877 -337.554267) (xy 84.662745 -337.589942) (xy 84.699962 -337.631479) (xy 84.730735 -337.677992)
			(xy 84.754407 -337.728489) (xy 84.770475 -337.781896) (xy 84.778595 -337.837072) (xy 84.779104 -337.864958)
			(xy 84.778595 -337.892844) (xy 84.770475 -337.94802) (xy 84.754407 -338.001427) (xy 84.730735 -338.051924)
			(xy 84.699962 -338.098437) (xy 84.662745 -338.139974) (xy 84.619877 -338.175649) (xy 84.572271 -338.204703)
			(xy 84.520942 -338.226515) (xy 84.466985 -338.240621) (xy 84.411548 -338.246721) (xy 84.355814 -338.244684)
			(xy 84.300971 -338.234554) (xy 84.248187 -338.216547) (xy 84.198587 -338.191046) (xy 84.153229 -338.158595)
			(xy 84.11308 -338.119886) (xy 84.078994 -338.075743) (xy 84.051698 -338.027108) (xy 84.031775 -337.975017)
			(xy 84.019649 -337.92058) (xy 84.015578 -337.864958) (xy 83.907376 -337.864958) (xy 83.907376 -338.351368)
			(xy 83.907708 -338.359263) (xy 83.912623 -338.374271) (xy 83.917028 -338.380832) (xy 83.921346 -338.387182)
			(xy 83.933792 -338.39658) (xy 83.94192 -338.399374) (xy 83.966677 -338.408311) (xy 84.013661 -338.432031)
			(xy 84.05694 -338.461985) (xy 84.095691 -338.497602) (xy 84.129178 -338.538207) (xy 84.156768 -338.58303)
			(xy 84.177935 -338.631219) (xy 84.192277 -338.68186) (xy 84.199524 -338.733992) (xy 84.199984 -338.760308)
			(xy 84.19952 -338.78756) (xy 84.191762 -338.841509) (xy 84.176405 -338.893804) (xy 84.153762 -338.943382)
			(xy 84.124293 -338.989232) (xy 84.088599 -339.030422) (xy 84.047406 -339.066112) (xy 84.001554 -339.095577)
			(xy 83.951974 -339.118216) (xy 83.899677 -339.133569) (xy 83.845728 -339.141322) (xy 83.818476 -339.141816)
			(xy 83.790175 -339.141292) (xy 83.734197 -339.132911) (xy 83.680072 -339.116352) (xy 83.628987 -339.091978)
			(xy 83.582065 -339.060323) (xy 83.540333 -339.022084) (xy 83.50471 -338.978098) (xy 83.475976 -338.929332)
			(xy 83.454763 -338.876856) (xy 83.447636 -338.849462) (xy 83.445858 -338.842604) (xy 83.44281 -338.83727)
			(xy 83.434682 -338.826348) (xy 83.418934 -338.810346) (xy 83.364832 -338.756244) (xy 83.347548 -338.738245)
			(xy 83.318239 -338.697862) (xy 83.295599 -338.653396) (xy 83.280184 -338.605939) (xy 83.272372 -338.556657)
			(xy 83.271868 -338.531708) (xy 83.271868 -337.461606) (xy 83.272357 -337.436656) (xy 83.280161 -337.387371)
			(xy 83.295579 -337.339913) (xy 83.31823 -337.295451) (xy 83.347557 -337.255079) (xy 83.364832 -337.23707)
			(xy 83.421728 -337.180174) (xy 83.424621 -337.17725) (xy 83.429482 -337.170615) (xy 83.43138 -337.166966)
			(xy 83.43265 -337.164172) (xy 83.435872 -337.15577) (xy 83.436771 -337.13781) (xy 83.434428 -337.12912)
			(xy 83.407758 -337.043014) (xy 83.405507 -337.036594) (xy 83.398164 -337.025145) (xy 83.39328 -337.020408)
			(xy 83.3882 -337.015582) (xy 83.375246 -337.009486) (xy 83.368642 -337.008216) (xy 83.342761 -337.002882)
			(xy 83.29268 -336.986022) (xy 83.245405 -336.962412) (xy 83.20184 -336.932504) (xy 83.16282 -336.89687)
			(xy 83.129091 -336.856192) (xy 83.101299 -336.811249) (xy 83.079975 -336.762899) (xy 83.065528 -336.71207)
			(xy 83.058234 -336.659733) (xy 83.057746 -336.633312) (xy 83.058231 -336.605401) (xy 83.066365 -336.550174)
			(xy 83.082462 -336.496723) (xy 83.106177 -336.446188) (xy 83.137003 -336.399649) (xy 83.155282 -336.37855)
			(xy 83.161632 -336.371438) (xy 83.164934 -336.362802) (xy 83.166479 -336.358455) (xy 83.168143 -336.349381)
			(xy 83.168236 -336.344768) (xy 83.168236 -336.276442) (xy 83.168132 -336.271831) (xy 83.166465 -336.262759)
			(xy 83.164934 -336.258408) (xy 83.161632 -336.249772) (xy 83.155282 -336.24266) (xy 83.137007 -336.221559)
			(xy 83.106187 -336.175018) (xy 83.082477 -336.124483) (xy 83.066384 -336.071033) (xy 83.058251 -336.015808)
			(xy 83.057746 -335.987898) (xy 83.058232 -335.960647) (xy 83.065988 -335.906699) (xy 83.081343 -335.854404)
			(xy 83.103985 -335.804827) (xy 83.133451 -335.758977) (xy 83.169142 -335.717786) (xy 83.210333 -335.682095)
			(xy 83.256183 -335.652629) (xy 83.30576 -335.629987) (xy 83.358055 -335.614632) (xy 83.412003 -335.606876)
			(xy 83.466505 -335.606876) (xy 83.520453 -335.614632) (xy 83.572748 -335.629987) (xy 83.622325 -335.652629)
			(xy 83.668175 -335.682095) (xy 83.709366 -335.717786) (xy 83.745057 -335.758977) (xy 83.774523 -335.804827)
			(xy 83.797165 -335.854404) (xy 83.81252 -335.906699) (xy 83.820276 -335.960647) (xy 83.820762 -335.987898)
			(xy 83.820276 -336.015809) (xy 83.812141 -336.071035) (xy 83.796044 -336.124486) (xy 83.772328 -336.17502)
			(xy 83.741501 -336.221558) (xy 83.723226 -336.24266) (xy 83.716876 -336.249772) (xy 83.713574 -336.258408)
			(xy 83.71203 -336.262756) (xy 83.710367 -336.271829) (xy 83.710272 -336.276442) (xy 83.710272 -336.344768)
			(xy 83.710377 -336.349379) (xy 83.712046 -336.35845) (xy 83.713574 -336.362802) (xy 83.716876 -336.371438)
			(xy 83.723226 -336.37855) (xy 83.740241 -336.398178) (xy 83.76936 -336.441193) (xy 83.792382 -336.487757)
			(xy 83.808882 -336.537011) (xy 83.814158 -336.562446) (xy 83.814158 -336.563208) (xy 83.815665 -336.569867)
			(xy 83.82172 -336.582098) (xy 83.826096 -336.587338) (xy 83.830668 -336.592418) (xy 83.842352 -336.599784)
			(xy 83.935062 -336.628486) (xy 83.943954 -336.630828) (xy 83.962297 -336.629729) (xy 83.97908 -336.622248)
			(xy 83.985862 -336.61604) (xy 84.038948 -336.562954) (xy 84.044039 -336.556605) (xy 84.050265 -336.54158)
			(xy 84.05114 -336.53349) (xy 84.05114 -335.865978) (xy 84.050378 -335.857342) (xy 84.049252 -335.851764)
			(xy 84.044892 -335.841254) (xy 84.041742 -335.836514) (xy 84.036154 -335.82991) (xy 83.075272 -334.869028)
			(xy 83.057987 -334.85103) (xy 83.028677 -334.810648) (xy 83.006036 -334.766182) (xy 82.990621 -334.718724)
			(xy 82.982811 -334.669441) (xy 82.982308 -334.644492) (xy 82.982308 -333.509366) (xy 82.982767 -333.484413)
			(xy 82.990564 -333.435119) (xy 83.005978 -333.387653) (xy 83.028628 -333.343182) (xy 83.057956 -333.302803)
			(xy 83.075272 -333.28483) (xy 84.242148 -332.117954) (xy 84.247239 -332.111605) (xy 84.253465 -332.09658)
			(xy 84.25434 -332.08849) (xy 84.25434 -323.821552) (xy 84.253844 -323.811548) (xy 84.246178 -323.793066)
			(xy 84.232028 -323.778918) (xy 84.213544 -323.771254) (xy 84.20354 -323.770752) (xy 76.587604 -323.770752)
			(xy 76.577592 -323.771239) (xy 76.559091 -323.778896) (xy 76.544925 -323.793047) (xy 76.537249 -323.811541)
			(xy 76.536804 -323.821552) (xy 76.536804 -332.219808) (xy 76.536347 -332.244762) (xy 76.528553 -332.294058)
			(xy 76.513143 -332.341527) (xy 76.490496 -332.386001) (xy 76.46117 -332.426384) (xy 76.44384 -332.444344)
			(xy 75.327002 -333.561182) (xy 75.321414 -333.567786) (xy 75.318225 -333.572506) (xy 75.313856 -333.583022)
			(xy 75.312778 -333.588614) (xy 75.312016 -333.59725) (xy 75.312016 -334.20431) (xy 75.312778 -334.212946)
			(xy 75.313902 -334.218526) (xy 75.318257 -334.229039) (xy 75.321414 -334.233774) (xy 75.327002 -334.240378)
			(xy 76.237084 -335.15046) (xy 76.254367 -335.168459) (xy 76.283674 -335.208843) (xy 76.306312 -335.253309)
			(xy 76.321726 -335.300766) (xy 76.329537 -335.350048) (xy 76.330048 -335.374996) (xy 76.330048 -336.668364)
			(xy 76.329562 -336.693315) (xy 76.321762 -336.742603) (xy 76.306348 -336.790064) (xy 76.2837 -336.83453)
			(xy 76.254376 -336.874906) (xy 76.237084 -336.8929) (xy 76.148684 -336.9813) (xy 79.082325 -336.9813)
			(xy 79.086494 -336.92568) (xy 79.098906 -336.871302) (xy 79.119284 -336.819381) (xy 79.147173 -336.771078)
			(xy 79.18195 -336.727471) (xy 79.222838 -336.689534) (xy 79.268923 -336.658115) (xy 79.319177 -336.633917)
			(xy 79.372476 -336.617478) (xy 79.42763 -336.609168) (xy 79.455518 -336.608674) (xy 79.48194 -336.609127)
			(xy 79.534255 -336.616579) (xy 79.584994 -336.631346) (xy 79.633138 -336.65313) (xy 79.677723 -336.681496)
			(xy 79.698088 -336.698336) (xy 79.704946 -336.704178) (xy 79.721964 -336.710528) (xy 79.806292 -336.710528)
			(xy 79.82331 -336.704178) (xy 79.830168 -336.698336) (xy 79.850534 -336.681497) (xy 79.89512 -336.653132)
			(xy 79.943264 -336.631345) (xy 79.994001 -336.616574) (xy 80.046316 -336.609114) (xy 80.09916 -336.609114)
			(xy 80.151475 -336.616574) (xy 80.202212 -336.631345) (xy 80.250356 -336.653132) (xy 80.294942 -336.681497)
			(xy 80.315308 -336.698336) (xy 80.322166 -336.704178) (xy 80.339184 -336.710528) (xy 80.423512 -336.710528)
			(xy 80.44053 -336.704178) (xy 80.447388 -336.698336) (xy 80.471196 -336.678767) (xy 80.523961 -336.646931)
			(xy 80.581236 -336.624189) (xy 80.611218 -336.617056) (xy 80.62341 -336.614516) (xy 80.642968 -336.598006)
			(xy 80.683354 -336.495136) (xy 80.680306 -336.470244) (xy 80.67294 -336.459576) (xy 80.657025 -336.435937)
			(xy 80.631775 -336.384853) (xy 80.614606 -336.330517) (xy 80.60592 -336.2742) (xy 80.605376 -336.245708)
			(xy 80.605919 -336.218067) (xy 80.614067 -336.16339) (xy 80.630201 -336.110515) (xy 80.653967 -336.060603)
			(xy 80.684843 -336.014748) (xy 80.722152 -335.973956) (xy 80.743298 -335.956148) (xy 80.751752 -335.948578)
			(xy 80.761499 -335.928113) (xy 80.762094 -335.916778) (xy 80.762094 -335.838038) (xy 80.761415 -335.826724)
			(xy 80.751684 -335.80629) (xy 80.743298 -335.798668) (xy 80.722154 -335.780857) (xy 80.684841 -335.740064)
			(xy 80.65396 -335.694211) (xy 80.630186 -335.6443) (xy 80.614041 -335.591427) (xy 80.605878 -335.53675)
			(xy 80.605376 -335.509108) (xy 80.605897 -335.481223) (xy 80.614209 -335.426076) (xy 80.630647 -335.372784)
			(xy 80.654845 -335.322538) (xy 80.686261 -335.276459) (xy 80.724194 -335.235577) (xy 80.767796 -335.200805)
			(xy 80.816094 -335.17292) (xy 80.868009 -335.152545) (xy 80.92238 -335.140135) (xy 80.977994 -335.135968)
			(xy 81.033608 -335.140135) (xy 81.087979 -335.152545) (xy 81.139894 -335.17292) (xy 81.188192 -335.200805)
			(xy 81.231794 -335.235577) (xy 81.269727 -335.276459) (xy 81.301143 -335.322538) (xy 81.325341 -335.372784)
			(xy 81.341779 -335.426076) (xy 81.350091 -335.481223) (xy 81.350612 -335.509108) (xy 81.350085 -335.536749)
			(xy 81.341934 -335.591428) (xy 81.325797 -335.644303) (xy 81.302029 -335.694215) (xy 81.27115 -335.74007)
			(xy 81.233837 -335.780861) (xy 81.21269 -335.798668) (xy 81.204272 -335.806272) (xy 81.194506 -335.826711)
			(xy 81.193894 -335.838038) (xy 81.193894 -335.916778) (xy 81.194568 -335.928093) (xy 81.204304 -335.948526)
			(xy 81.21269 -335.956148) (xy 81.23386 -335.973929) (xy 81.271167 -336.014731) (xy 81.302043 -336.060591)
			(xy 81.325812 -336.110507) (xy 81.341952 -336.163384) (xy 81.350111 -336.218065) (xy 81.350612 -336.245708)
			(xy 81.350052 -336.273832) (xy 81.34161 -336.329444) (xy 81.324904 -336.383154) (xy 81.300313 -336.433743)
			(xy 81.268398 -336.48006) (xy 81.229882 -336.521053) (xy 81.185641 -336.55579) (xy 81.136681 -336.583482)
			(xy 81.084115 -336.603499) (xy 81.056734 -336.609944) (xy 81.044542 -336.612484) (xy 81.024984 -336.628994)
			(xy 80.984598 -336.731864) (xy 80.987646 -336.756756) (xy 80.995012 -336.767424) (xy 81.010922 -336.791067)
			(xy 81.036174 -336.842149) (xy 81.053345 -336.896483) (xy 81.062032 -336.9528) (xy 81.062576 -336.981292)
			(xy 81.062158 -337.007912) (xy 81.054582 -337.060609) (xy 81.039583 -337.111691) (xy 81.017466 -337.160119)
			(xy 80.988681 -337.204906) (xy 80.953816 -337.24514) (xy 80.913578 -337.280002) (xy 80.868789 -337.308782)
			(xy 80.820359 -337.330895) (xy 80.769275 -337.345889) (xy 80.716578 -337.353461) (xy 80.689958 -337.35391)
			(xy 80.663535 -337.353474) (xy 80.611219 -337.346019) (xy 80.56048 -337.331248) (xy 80.512336 -337.30946)
			(xy 80.467753 -337.28109) (xy 80.447388 -337.264248) (xy 80.44053 -337.258406) (xy 80.423512 -337.252056)
			(xy 80.339184 -337.252056) (xy 80.322166 -337.258406) (xy 80.315308 -337.264248) (xy 80.294942 -337.281087)
			(xy 80.250356 -337.309452) (xy 80.202212 -337.331239) (xy 80.151475 -337.34601) (xy 80.09916 -337.35347)
			(xy 80.046316 -337.35347) (xy 79.994001 -337.34601) (xy 79.943264 -337.331239) (xy 79.89512 -337.309452)
			(xy 79.850534 -337.281087) (xy 79.830168 -337.264248) (xy 79.82331 -337.258406) (xy 79.806292 -337.252056)
			(xy 79.721964 -337.252056) (xy 79.704946 -337.258406) (xy 79.698088 -337.264248) (xy 79.67772 -337.281084)
			(xy 79.633132 -337.309441) (xy 79.584988 -337.331221) (xy 79.534252 -337.34599) (xy 79.481939 -337.35345)
			(xy 79.455518 -337.35391) (xy 79.42763 -337.353432) (xy 79.372476 -337.345122) (xy 79.319177 -337.328683)
			(xy 79.268923 -337.304485) (xy 79.222838 -337.273066) (xy 79.18195 -337.235129) (xy 79.147173 -337.191522)
			(xy 79.119284 -337.143219) (xy 79.098906 -337.091298) (xy 79.086494 -337.03692) (xy 79.082325 -336.9813)
			(xy 76.148684 -336.9813) (xy 75.489562 -337.640422) (xy 75.483974 -337.647026) (xy 75.480791 -337.651748)
			(xy 75.476434 -337.662266) (xy 75.475338 -337.667854) (xy 75.474576 -337.67649) (xy 75.474576 -337.879436)
			(xy 75.657962 -337.879436) (xy 75.662033 -337.823814) (xy 75.674159 -337.769377) (xy 75.694082 -337.717286)
			(xy 75.721378 -337.668651) (xy 75.755464 -337.624508) (xy 75.795613 -337.585799) (xy 75.840971 -337.553348)
			(xy 75.890571 -337.527847) (xy 75.943355 -337.50984) (xy 75.998198 -337.49971) (xy 76.053932 -337.497673)
			(xy 76.109369 -337.503773) (xy 76.163326 -337.517879) (xy 76.214655 -337.539691) (xy 76.262261 -337.568745)
			(xy 76.305129 -337.60442) (xy 76.342346 -337.645957) (xy 76.373119 -337.69247) (xy 76.396791 -337.742967)
			(xy 76.412859 -337.796374) (xy 76.420979 -337.85155) (xy 76.421488 -337.879436) (xy 76.420979 -337.907322)
			(xy 76.412859 -337.962498) (xy 76.396791 -338.015905) (xy 76.373119 -338.066402) (xy 76.342346 -338.112915)
			(xy 76.305129 -338.154452) (xy 76.262261 -338.190127) (xy 76.214655 -338.219181) (xy 76.163326 -338.240993)
			(xy 76.109369 -338.255099) (xy 76.053932 -338.261199) (xy 75.998198 -338.259162) (xy 75.943355 -338.249032)
			(xy 75.890571 -338.231025) (xy 75.840971 -338.205524) (xy 75.795613 -338.173073) (xy 75.755464 -338.134364)
			(xy 75.721378 -338.090221) (xy 75.694082 -338.041586) (xy 75.674159 -337.989495) (xy 75.662033 -337.935058)
			(xy 75.657962 -337.879436) (xy 75.474576 -337.879436) (xy 75.474576 -338.31784) (xy 75.475338 -338.326476)
			(xy 75.476466 -338.332053) (xy 75.48083 -338.34256) (xy 75.483974 -338.347304) (xy 75.489562 -338.353908)
			(xy 75.519534 -338.38388) (xy 75.521058 -338.385658) (xy 75.52309 -338.387436) (xy 75.534012 -338.395818)
			(xy 75.548998 -338.403438) (xy 75.554586 -338.404962) (xy 75.581654 -338.41233) (xy 75.63343 -338.43392)
			(xy 75.681487 -338.462859) (xy 75.724788 -338.498523) (xy 75.762399 -338.540143) (xy 75.793511 -338.586823)
			(xy 75.817452 -338.637554) (xy 75.833706 -338.691245) (xy 75.841923 -338.746737) (xy 75.842368 -338.774786)
			(xy 75.841906 -338.802038) (xy 75.83415 -338.855989) (xy 75.818795 -338.908286) (xy 75.796153 -338.957865)
			(xy 75.766684 -339.003717) (xy 75.73099 -339.044908) (xy 75.689797 -339.0806) (xy 75.643943 -339.110065)
			(xy 75.594362 -339.132704) (xy 75.542063 -339.148056) (xy 75.488113 -339.155807) (xy 75.46086 -339.156294)
			(xy 75.432556 -339.155776) (xy 75.37657 -339.147405) (xy 75.322436 -339.130853) (xy 75.271342 -339.106484)
			(xy 75.224411 -339.074831) (xy 75.182671 -339.036592) (xy 75.147041 -338.992604) (xy 75.118301 -338.943834)
			(xy 75.097084 -338.891352) (xy 75.09002 -338.86394) (xy 75.088242 -338.857082) (xy 75.085194 -338.851494)
			(xy 75.083399 -338.848378) (xy 75.07907 -338.842637) (xy 75.076558 -338.840064) (xy 74.932032 -338.695538)
			(xy 74.914748 -338.677539) (xy 74.885441 -338.637156) (xy 74.862801 -338.59269) (xy 74.847387 -338.545233)
			(xy 74.839576 -338.495951) (xy 74.839068 -338.471002) (xy 74.839068 -337.523328) (xy 74.839555 -337.498378)
			(xy 74.847356 -337.44909) (xy 74.862772 -337.40163) (xy 74.885421 -337.357166) (xy 74.914747 -337.316792)
			(xy 74.932032 -337.298792) (xy 75.041252 -337.189572) (xy 75.04737 -337.182935) (xy 75.054911 -337.166547)
			(xy 75.056322 -337.148563) (xy 75.054206 -337.139788) (xy 75.042268 -337.09737) (xy 75.042268 -337.096862)
			(xy 75.030076 -337.05419) (xy 75.028026 -337.047906) (xy 75.021216 -337.036582) (xy 75.016614 -337.031838)
			(xy 75.012024 -337.027595) (xy 75.00123 -337.0213) (xy 74.995278 -337.019392) (xy 74.992992 -337.018884)
			(xy 74.965547 -337.011799) (xy 74.912972 -336.990623) (xy 74.864108 -336.961903) (xy 74.820031 -336.926269)
			(xy 74.781711 -336.884506) (xy 74.749991 -336.837533) (xy 74.72557 -336.786385) (xy 74.708985 -336.732186)
			(xy 74.7006 -336.67613) (xy 74.70013 -336.64779) (xy 74.700617 -336.619879) (xy 74.708753 -336.564654)
			(xy 74.724852 -336.511204) (xy 74.748568 -336.460671) (xy 74.779395 -336.414133) (xy 74.797666 -336.393028)
			(xy 74.804016 -336.385916) (xy 74.807318 -336.37728) (xy 74.808861 -336.372932) (xy 74.810522 -336.363858)
			(xy 74.81062 -336.359246) (xy 74.81062 -336.29092) (xy 74.810523 -336.286307) (xy 74.808869 -336.277231)
			(xy 74.807318 -336.272886) (xy 74.804016 -336.26425) (xy 74.797666 -336.257138) (xy 74.779393 -336.236036)
			(xy 74.748577 -336.189495) (xy 74.724871 -336.138959) (xy 74.708782 -336.085509) (xy 74.700652 -336.030286)
			(xy 74.70013 -336.002376) (xy 74.700616 -335.975125) (xy 74.708372 -335.921177) (xy 74.723727 -335.868882)
			(xy 74.746369 -335.819305) (xy 74.775835 -335.773455) (xy 74.811526 -335.732264) (xy 74.852717 -335.696573)
			(xy 74.898567 -335.667107) (xy 74.948144 -335.644465) (xy 75.000439 -335.62911) (xy 75.054387 -335.621354)
			(xy 75.108889 -335.621354) (xy 75.162837 -335.62911) (xy 75.215132 -335.644465) (xy 75.264709 -335.667107)
			(xy 75.310559 -335.696573) (xy 75.35175 -335.732264) (xy 75.387441 -335.773455) (xy 75.416907 -335.819305)
			(xy 75.439549 -335.868882) (xy 75.454904 -335.921177) (xy 75.46266 -335.975125) (xy 75.463146 -336.002376)
			(xy 75.462662 -336.030288) (xy 75.454529 -336.085515) (xy 75.438434 -336.138967) (xy 75.414719 -336.189503)
			(xy 75.383893 -336.236043) (xy 75.36561 -336.257138) (xy 75.35926 -336.26425) (xy 75.355958 -336.272886)
			(xy 75.354412 -336.277233) (xy 75.352746 -336.286307) (xy 75.352656 -336.29092) (xy 75.352656 -336.359246)
			(xy 75.352759 -336.363858) (xy 75.354423 -336.37293) (xy 75.355958 -336.37728) (xy 75.35926 -336.385916)
			(xy 75.36561 -336.393028) (xy 75.386249 -336.416925) (xy 75.420132 -336.470202) (xy 75.444779 -336.528333)
			(xy 75.452732 -336.55889) (xy 75.452732 -336.559144) (xy 75.45324 -336.56143) (xy 75.454745 -336.566177)
			(xy 75.459359 -336.575) (xy 75.462384 -336.578956) (xy 75.467496 -336.584951) (xy 75.480562 -336.593738)
			(xy 75.488038 -336.596228) (xy 75.53071 -336.60842) (xy 75.531218 -336.60842) (xy 75.573636 -336.620358)
			(xy 75.582412 -336.622502) (xy 75.600413 -336.621127) (xy 75.6168 -336.613551) (xy 75.62342 -336.607404)
			(xy 75.682348 -336.548476) (xy 75.687441 -336.542128) (xy 75.693675 -336.527103) (xy 75.69454 -336.519012)
			(xy 75.69454 -335.528158) (xy 75.693778 -335.519522) (xy 75.69265 -335.513944) (xy 75.688287 -335.503437)
			(xy 75.685142 -335.498694) (xy 75.679554 -335.49209) (xy 74.769472 -334.582008) (xy 74.752188 -334.56401)
			(xy 74.722881 -334.523627) (xy 74.700243 -334.47916) (xy 74.684831 -334.431703) (xy 74.677023 -334.38242)
			(xy 74.676508 -334.357472) (xy 74.676508 -333.444088) (xy 74.676965 -333.419134) (xy 74.68476 -333.369839)
			(xy 74.700171 -333.32237) (xy 74.722819 -333.277897) (xy 74.752146 -333.237515) (xy 74.769472 -333.219552)
			(xy 75.889104 -332.09992) (xy 75.894185 -332.093567) (xy 75.900395 -332.078541) (xy 75.901296 -332.070456)
			(xy 75.901296 -323.821552) (xy 75.9008 -323.811551) (xy 75.893131 -323.793076) (xy 75.87898 -323.778939)
			(xy 75.860497 -323.77129) (xy 75.850496 -323.770752) (xy 68.29933 -323.770752) (xy 68.293321 -323.770921)
			(xy 68.281639 -323.773746) (xy 68.276216 -323.77634) (xy 68.272741 -323.778179) (xy 68.266362 -323.782772)
			(xy 68.263516 -323.785484) (xy 68.196206 -323.852794) (xy 68.191126 -323.85889) (xy 68.18765 -323.863797)
			(xy 68.182892 -323.874835) (xy 68.181728 -323.880734) (xy 68.18122 -323.888862) (xy 68.18122 -332.259432)
			(xy 68.180761 -332.284386) (xy 68.172965 -332.33368) (xy 68.157552 -332.381147) (xy 68.134904 -332.425619)
			(xy 68.105578 -332.466) (xy 68.088256 -332.483968) (xy 67.018662 -333.553562) (xy 67.013074 -333.560166)
			(xy 67.009886 -333.564886) (xy 67.005516 -333.575402) (xy 67.004438 -333.580994) (xy 67.003676 -333.58963)
			(xy 67.003676 -334.76819) (xy 67.004438 -334.776826) (xy 67.005562 -334.782406) (xy 67.009917 -334.792919)
			(xy 67.013074 -334.797654) (xy 67.018662 -334.804258) (xy 67.885056 -335.670652) (xy 67.902341 -335.68865)
			(xy 67.931651 -335.729033) (xy 67.954292 -335.773499) (xy 67.969709 -335.820956) (xy 67.977522 -335.870239)
			(xy 67.97802 -335.895188) (xy 67.97802 -336.704432) (xy 67.977561 -336.729386) (xy 67.969765 -336.77868)
			(xy 67.954352 -336.826147) (xy 67.931704 -336.870619) (xy 67.902378 -336.911) (xy 67.885056 -336.928968)
			(xy 67.825624 -336.9884) (xy 70.726737 -336.9884) (xy 70.730906 -336.93278) (xy 70.743318 -336.878402)
			(xy 70.763696 -336.826482) (xy 70.791586 -336.778179) (xy 70.826364 -336.734573) (xy 70.867252 -336.696638)
			(xy 70.913338 -336.66522) (xy 70.963593 -336.641023) (xy 71.016892 -336.624587) (xy 71.072046 -336.616279)
			(xy 71.099934 -336.615786) (xy 71.126356 -336.616227) (xy 71.178672 -336.623682) (xy 71.229411 -336.638451)
			(xy 71.277555 -336.660238) (xy 71.322139 -336.688607) (xy 71.342504 -336.705448) (xy 71.349362 -336.71129)
			(xy 71.36638 -336.71764) (xy 71.450708 -336.71764) (xy 71.467726 -336.71129) (xy 71.474584 -336.705448)
			(xy 71.49495 -336.688609) (xy 71.539536 -336.660244) (xy 71.58768 -336.638457) (xy 71.638417 -336.623686)
			(xy 71.690732 -336.616226) (xy 71.743576 -336.616226) (xy 71.795891 -336.623686) (xy 71.846628 -336.638457)
			(xy 71.894772 -336.660244) (xy 71.939358 -336.688609) (xy 71.959724 -336.705448) (xy 71.966582 -336.71129)
			(xy 71.9836 -336.71764) (xy 72.067928 -336.71764) (xy 72.084946 -336.71129) (xy 72.091804 -336.705448)
			(xy 72.114863 -336.686472) (xy 72.165817 -336.655339) (xy 72.221092 -336.632749) (xy 72.250046 -336.625438)
			(xy 72.262238 -336.622644) (xy 72.281288 -336.606134) (xy 72.320658 -336.503772) (xy 72.31761 -336.47888)
			(xy 72.310244 -336.468466) (xy 72.294537 -336.444928) (xy 72.269667 -336.3941) (xy 72.252765 -336.340098)
			(xy 72.244219 -336.284161) (xy 72.243696 -336.255868) (xy 72.244204 -336.228226) (xy 72.252358 -336.173546)
			(xy 72.268498 -336.120671) (xy 72.292271 -336.070759) (xy 72.323153 -336.024905) (xy 72.360469 -335.984114)
			(xy 72.381618 -335.966308) (xy 72.390048 -335.958715) (xy 72.399807 -335.938267) (xy 72.400414 -335.926938)
			(xy 72.400414 -335.848198) (xy 72.399784 -335.836877) (xy 72.390021 -335.816442) (xy 72.381618 -335.808828)
			(xy 72.360486 -335.791003) (xy 72.323176 -335.750211) (xy 72.292295 -335.70436) (xy 72.26852 -335.654452)
			(xy 72.252371 -335.601583) (xy 72.244202 -335.546908) (xy 72.243696 -335.519268) (xy 72.244217 -335.491383)
			(xy 72.252529 -335.436236) (xy 72.268967 -335.382944) (xy 72.293165 -335.332698) (xy 72.324581 -335.286619)
			(xy 72.362514 -335.245737) (xy 72.406116 -335.210965) (xy 72.454414 -335.18308) (xy 72.506329 -335.162705)
			(xy 72.5607 -335.150295) (xy 72.616314 -335.146128) (xy 72.671928 -335.150295) (xy 72.726299 -335.162705)
			(xy 72.778214 -335.18308) (xy 72.826512 -335.210965) (xy 72.870114 -335.245737) (xy 72.908047 -335.286619)
			(xy 72.939463 -335.332698) (xy 72.963661 -335.382944) (xy 72.980099 -335.436236) (xy 72.988411 -335.491383)
			(xy 72.988932 -335.519268) (xy 72.98844 -335.546911) (xy 72.98028 -335.60159) (xy 72.964136 -335.654466)
			(xy 72.940361 -335.704377) (xy 72.909477 -335.750231) (xy 72.872159 -335.791022) (xy 72.85101 -335.808828)
			(xy 72.842568 -335.81641) (xy 72.832814 -335.836866) (xy 72.832214 -335.848198) (xy 72.832214 -335.926938)
			(xy 72.832848 -335.938258) (xy 72.842611 -335.958691) (xy 72.85101 -335.966308) (xy 72.872144 -335.98413)
			(xy 72.909457 -336.024921) (xy 72.94034 -336.070772) (xy 72.964115 -336.12068) (xy 72.980263 -336.173551)
			(xy 72.988428 -336.228227) (xy 72.988932 -336.255868) (xy 72.988393 -336.283672) (xy 72.980133 -336.338664)
			(xy 72.963792 -336.391817) (xy 72.939733 -336.441952) (xy 72.90849 -336.487954) (xy 72.870758 -336.528802)
			(xy 72.827373 -336.563589) (xy 72.779301 -336.591541) (xy 72.727608 -336.612039) (xy 72.700642 -336.618834)
			(xy 72.68845 -336.621628) (xy 72.6694 -336.638138) (xy 72.63003 -336.7405) (xy 72.633078 -336.765392)
			(xy 72.640444 -336.775806) (xy 72.65615 -336.799345) (xy 72.681017 -336.850173) (xy 72.697919 -336.904175)
			(xy 72.706468 -336.960111) (xy 72.706992 -336.988404) (xy 72.706569 -337.015023) (xy 72.698992 -337.067719)
			(xy 72.683992 -337.118801) (xy 72.661875 -337.167227) (xy 72.633091 -337.212013) (xy 72.598225 -337.252247)
			(xy 72.557989 -337.287109) (xy 72.513201 -337.315889) (xy 72.464773 -337.338002) (xy 72.41369 -337.352998)
			(xy 72.360993 -337.360572) (xy 72.334374 -337.361022) (xy 72.307952 -337.360574) (xy 72.255636 -337.353121)
			(xy 72.204898 -337.338353) (xy 72.156754 -337.316568) (xy 72.112169 -337.2882) (xy 72.091804 -337.27136)
			(xy 72.084946 -337.265518) (xy 72.067928 -337.259168) (xy 71.9836 -337.259168) (xy 71.966582 -337.265518)
			(xy 71.959724 -337.27136) (xy 71.939358 -337.288199) (xy 71.894772 -337.316564) (xy 71.846628 -337.338351)
			(xy 71.795891 -337.353122) (xy 71.743576 -337.360582) (xy 71.690732 -337.360582) (xy 71.638417 -337.353122)
			(xy 71.58768 -337.338351) (xy 71.539536 -337.316564) (xy 71.49495 -337.288199) (xy 71.474584 -337.27136)
			(xy 71.467726 -337.265518) (xy 71.450708 -337.259168) (xy 71.36638 -337.259168) (xy 71.349362 -337.265518)
			(xy 71.342504 -337.27136) (xy 71.322132 -337.28819) (xy 71.277545 -337.316548) (xy 71.229401 -337.338329)
			(xy 71.178666 -337.353099) (xy 71.126355 -337.36056) (xy 71.099934 -337.361022) (xy 71.072046 -337.360521)
			(xy 71.016892 -337.352213) (xy 70.963593 -337.335777) (xy 70.913338 -337.31158) (xy 70.867252 -337.280162)
			(xy 70.826364 -337.242227) (xy 70.791586 -337.198621) (xy 70.763696 -337.150318) (xy 70.743318 -337.098398)
			(xy 70.730906 -337.04402) (xy 70.726737 -336.9884) (xy 67.825624 -336.9884) (xy 67.078606 -337.735418)
			(xy 67.073018 -337.742022) (xy 67.069833 -337.746743) (xy 67.065471 -337.75726) (xy 67.064382 -337.76285)
			(xy 67.06362 -337.771486) (xy 67.06362 -337.886548) (xy 67.302378 -337.886548) (xy 67.306449 -337.830926)
			(xy 67.318575 -337.776489) (xy 67.338498 -337.724398) (xy 67.365794 -337.675763) (xy 67.39988 -337.63162)
			(xy 67.440029 -337.592911) (xy 67.485387 -337.56046) (xy 67.534987 -337.534959) (xy 67.587771 -337.516952)
			(xy 67.642614 -337.506822) (xy 67.698348 -337.504785) (xy 67.753785 -337.510885) (xy 67.807742 -337.524991)
			(xy 67.859071 -337.546803) (xy 67.906677 -337.575857) (xy 67.949545 -337.611532) (xy 67.986762 -337.653069)
			(xy 68.017535 -337.699582) (xy 68.041207 -337.750079) (xy 68.057275 -337.803486) (xy 68.065395 -337.858662)
			(xy 68.065904 -337.886548) (xy 68.065395 -337.914434) (xy 68.057275 -337.96961) (xy 68.041207 -338.023017)
			(xy 68.017535 -338.073514) (xy 67.986762 -338.120027) (xy 67.949545 -338.161564) (xy 67.906677 -338.197239)
			(xy 67.859071 -338.226293) (xy 67.807742 -338.248105) (xy 67.753785 -338.262211) (xy 67.698348 -338.268311)
			(xy 67.642614 -338.266274) (xy 67.587771 -338.256144) (xy 67.534987 -338.238137) (xy 67.485387 -338.212636)
			(xy 67.440029 -338.180185) (xy 67.39988 -338.141476) (xy 67.365794 -338.097333) (xy 67.338498 -338.048698)
			(xy 67.318575 -337.996607) (xy 67.306449 -337.94217) (xy 67.302378 -337.886548) (xy 67.06362 -337.886548)
			(xy 67.06362 -338.26958) (xy 67.064382 -338.278216) (xy 67.065503 -338.283797) (xy 67.069853 -338.294313)
			(xy 67.073018 -338.299044) (xy 67.078606 -338.305648) (xy 67.170554 -338.397596) (xy 67.173129 -338.400106)
			(xy 67.178863 -338.404446) (xy 67.181984 -338.406232) (xy 67.187572 -338.40928) (xy 67.19443 -338.411058)
			(xy 67.22184 -338.418151) (xy 67.274344 -338.439333) (xy 67.323138 -338.468049) (xy 67.367146 -338.503667)
			(xy 67.405401 -338.545404) (xy 67.43706 -338.592341) (xy 67.461427 -338.643445) (xy 67.477966 -338.697592)
			(xy 67.486313 -338.75359) (xy 67.486784 -338.781898) (xy 67.486321 -338.80915) (xy 67.478564 -338.8631)
			(xy 67.463208 -338.915397) (xy 67.440565 -338.964976) (xy 67.411097 -339.010827) (xy 67.375403 -339.052018)
			(xy 67.33421 -339.08771) (xy 67.288356 -339.117176) (xy 67.238776 -339.139816) (xy 67.186479 -339.155169)
			(xy 67.132528 -339.162922) (xy 67.105276 -339.163406) (xy 67.076975 -339.162882) (xy 67.020998 -339.154501)
			(xy 66.966873 -339.137942) (xy 66.915789 -339.113567) (xy 66.868867 -339.081912) (xy 66.827137 -339.043672)
			(xy 66.791514 -338.999687) (xy 66.762781 -338.95092) (xy 66.741569 -338.898444) (xy 66.734436 -338.871052)
			(xy 66.732658 -338.864194) (xy 66.72961 -338.858606) (xy 66.727811 -338.855493) (xy 66.723476 -338.849758)
			(xy 66.720974 -338.847176) (xy 66.521076 -338.647278) (xy 66.503788 -338.629281) (xy 66.474471 -338.5889)
			(xy 66.451823 -338.544435) (xy 66.436401 -338.496977) (xy 66.428582 -338.447692) (xy 66.428112 -338.422742)
			(xy 66.428112 -337.618324) (xy 66.428599 -337.593373) (xy 66.4364 -337.544085) (xy 66.451814 -337.496624)
			(xy 66.47446 -337.452158) (xy 66.503783 -337.41178) (xy 66.521076 -337.393788) (xy 66.712846 -337.202018)
			(xy 66.71906 -337.195184) (xy 66.726574 -337.178326) (xy 66.727639 -337.1599) (xy 66.725292 -337.150964)
			(xy 66.706496 -337.092036) (xy 66.698114 -337.065112) (xy 66.695825 -337.058609) (xy 66.688355 -337.047027)
			(xy 66.683382 -337.042252) (xy 66.678048 -337.03768) (xy 66.665602 -337.031584) (xy 66.65849 -337.030314)
			(xy 66.632418 -337.025153) (xy 66.581923 -337.008566) (xy 66.534219 -336.985132) (xy 66.49023 -336.955304)
			(xy 66.450806 -336.91966) (xy 66.41671 -336.878888) (xy 66.388603 -336.833779) (xy 66.367029 -336.785206)
			(xy 66.352405 -336.734109) (xy 66.345015 -336.681476) (xy 66.344546 -336.654902) (xy 66.345032 -336.626991)
			(xy 66.353167 -336.571765) (xy 66.369265 -336.518314) (xy 66.392981 -336.467781) (xy 66.423808 -336.421243)
			(xy 66.442082 -336.40014) (xy 66.448432 -336.393028) (xy 66.451734 -336.384392) (xy 66.453278 -336.380044)
			(xy 66.45494 -336.370971) (xy 66.455036 -336.366358) (xy 66.455036 -336.298032) (xy 66.454931 -336.293421)
			(xy 66.453263 -336.28435) (xy 66.451734 -336.279998) (xy 66.448432 -336.271362) (xy 66.442082 -336.26425)
			(xy 66.423808 -336.243149) (xy 66.392989 -336.196608) (xy 66.36928 -336.146073) (xy 66.353189 -336.092623)
			(xy 66.345057 -336.037398) (xy 66.344546 -336.009488) (xy 66.344625 -335.99675) (xy 66.346279 -335.971329)
			(xy 66.347848 -335.958688) (xy 66.352178 -335.930467) (xy 66.368127 -335.875649) (xy 66.392066 -335.823818)
			(xy 66.423462 -335.776134) (xy 66.461611 -335.733659) (xy 66.505664 -335.697344) (xy 66.554636 -335.667998)
			(xy 66.607435 -335.646276) (xy 66.66288 -335.632664) (xy 66.691256 -335.629504) (xy 66.703956 -335.626456)
			(xy 66.710306 -335.623916) (xy 66.73723 -335.604358) (xy 66.739262 -335.602834) (xy 66.743845 -335.598885)
			(xy 66.751161 -335.589256) (xy 66.75374 -335.583784) (xy 66.769234 -335.543144) (xy 66.782188 -335.50987)
			(xy 66.783729 -335.505522) (xy 66.785385 -335.496448) (xy 66.78549 -335.491836) (xy 66.78549 -335.491582)
			(xy 66.785162 -335.482976) (xy 66.779461 -335.466736) (xy 66.774314 -335.459832) (xy 66.77152 -335.456276)
			(xy 66.461132 -335.145888) (xy 66.443845 -335.12789) (xy 66.414531 -335.087508) (xy 66.391885 -335.043043)
			(xy 66.376463 -334.995586) (xy 66.368645 -334.946302) (xy 66.368168 -334.921352) (xy 66.368168 -333.436468)
			(xy 66.368652 -333.411516) (xy 66.376448 -333.362226) (xy 66.391858 -333.314762) (xy 66.414504 -333.270293)
			(xy 66.443828 -333.229914) (xy 66.461132 -333.211932) (xy 67.53352 -332.139544) (xy 67.538603 -332.133192)
			(xy 67.544818 -332.118167) (xy 67.545712 -332.11008) (xy 67.545712 -324.744842) (xy 67.545458 -324.741794)
			(xy 67.545458 -324.740778) (xy 67.543819 -324.726363) (xy 67.53353 -324.699252) (xy 67.51604 -324.676123)
			(xy 67.492757 -324.658838) (xy 67.465557 -324.648788) (xy 67.436629 -324.646784) (xy 67.408302 -324.652986)
			(xy 67.382858 -324.666894) (xy 67.37223 -324.67677) (xy 66.093848 -325.955152) (xy 66.091139 -325.958001)
			(xy 66.08654 -325.964376) (xy 66.084704 -325.967852) (xy 66.082122 -325.973279) (xy 66.0793 -325.984959)
			(xy 66.079116 -325.990966) (xy 66.079116 -334.320388) (xy 66.078696 -334.33046) (xy 66.070986 -334.349069)
			(xy 66.06413 -334.356456) (xy 65.080642 -335.339944) (xy 65.073243 -335.346787) (xy 65.054644 -335.35451)
			(xy 65.044574 -335.35493) (xy 65.000124 -335.35493) (xy 64.995247 -335.355028) (xy 64.985659 -335.35682)
			(xy 64.981074 -335.358486) (xy 64.97193 -335.362296) (xy 64.9478 -335.386426) (xy 64.940405 -335.39328)
			(xy 64.921806 -335.401026) (xy 64.911732 -335.401412) (xy 58.878978 -335.401412) (xy 58.868909 -335.400985)
			(xy 58.850309 -335.393267) (xy 58.84291 -335.386426) (xy 58.811414 -335.35493) (xy 58.808874 -335.35493)
			(xy 58.532776 -335.078832) (xy 58.525364 -335.072148) (xy 58.506931 -335.064551) (xy 58.486993 -335.064551)
			(xy 58.46856 -335.072148) (xy 58.461148 -335.078832) (xy 58.202322 -335.337658) (xy 58.196734 -335.344262)
			(xy 58.193548 -335.348983) (xy 58.189181 -335.359499) (xy 58.188098 -335.36509) (xy 58.187336 -335.373726)
			(xy 58.187336 -336.63255) (xy 58.188098 -336.641186) (xy 58.189227 -336.646764) (xy 58.193589 -336.657271)
			(xy 58.196734 -336.662014) (xy 58.202322 -336.668618) (xy 59.574684 -338.04098) (xy 59.591966 -338.05898)
			(xy 59.62127 -338.099364) (xy 59.643905 -338.14383) (xy 59.659316 -338.191287) (xy 59.667124 -338.240568)
			(xy 59.667648 -338.265516) (xy 59.667648 -339.457538) (xy 68.062094 -339.457538) (xy 68.062604 -339.430064)
			(xy 68.070491 -339.375686) (xy 68.086105 -339.323004) (xy 68.109124 -339.273111) (xy 68.139071 -339.227041)
			(xy 68.156836 -339.206078) (xy 68.15709 -339.205824) (xy 68.162672 -339.198734) (xy 68.168922 -339.18182)
			(xy 68.169282 -339.172804) (xy 68.169282 -339.10524) (xy 68.16891 -339.096225) (xy 68.162673 -339.079307)
			(xy 68.15709 -339.07222) (xy 68.156582 -339.071712) (xy 68.138855 -339.05076) (xy 68.108972 -339.004729)
			(xy 68.086005 -338.954885) (xy 68.070429 -338.902261) (xy 68.062566 -338.847946) (xy 68.062094 -338.820506)
			(xy 68.06258 -338.793255) (xy 68.070336 -338.739307) (xy 68.085691 -338.687012) (xy 68.108333 -338.637435)
			(xy 68.137799 -338.591585) (xy 68.17349 -338.550394) (xy 68.214681 -338.514703) (xy 68.260531 -338.485237)
			(xy 68.310108 -338.462595) (xy 68.362403 -338.44724) (xy 68.416351 -338.439484) (xy 68.470853 -338.439484)
			(xy 68.524801 -338.44724) (xy 68.577096 -338.462595) (xy 68.626673 -338.485237) (xy 68.672523 -338.514703)
			(xy 68.713714 -338.550394) (xy 68.749405 -338.591585) (xy 68.778871 -338.637435) (xy 68.801513 -338.687012)
			(xy 68.816868 -338.739307) (xy 68.824624 -338.793255) (xy 68.82511 -338.820506) (xy 68.824625 -338.847981)
			(xy 68.816732 -338.90236) (xy 68.801112 -338.955042) (xy 68.778087 -339.004935) (xy 68.748135 -339.051004)
			(xy 68.730368 -339.071966) (xy 68.730114 -339.07222) (xy 68.724514 -339.079298) (xy 68.718275 -339.096221)
			(xy 68.717922 -339.10524) (xy 68.717922 -339.172804) (xy 68.718272 -339.181822) (xy 68.724524 -339.198739)
			(xy 68.730114 -339.205824) (xy 68.730622 -339.206332) (xy 68.74837 -339.227266) (xy 68.77825 -339.273303)
			(xy 68.801213 -339.323151) (xy 68.816784 -339.375779) (xy 68.824641 -339.430096) (xy 68.82511 -339.457538)
			(xy 68.824624 -339.484789) (xy 68.816868 -339.538737) (xy 68.801513 -339.591032) (xy 68.778871 -339.640609)
			(xy 68.749405 -339.686459) (xy 68.713714 -339.72765) (xy 68.672523 -339.763341) (xy 68.626673 -339.792807)
			(xy 68.577096 -339.815449) (xy 68.524801 -339.830804) (xy 68.470853 -339.83856) (xy 68.416351 -339.83856)
			(xy 68.362403 -339.830804) (xy 68.310108 -339.815449) (xy 68.260531 -339.792807) (xy 68.214681 -339.763341)
			(xy 68.17349 -339.72765) (xy 68.137799 -339.686459) (xy 68.108333 -339.640609) (xy 68.085691 -339.591032)
			(xy 68.070336 -339.538737) (xy 68.06258 -339.484789) (xy 68.062094 -339.457538) (xy 59.667648 -339.457538)
			(xy 59.667648 -348.301818) (xy 59.667165 -348.32677) (xy 59.659371 -348.376062) (xy 59.643963 -348.423528)
			(xy 59.621319 -348.467999) (xy 59.591998 -348.508381) (xy 59.574684 -348.526354) (xy 59.391538 -348.7095)
			(xy 62.192321 -348.7095) (xy 62.19649 -348.653877) (xy 62.208903 -348.599498) (xy 62.229282 -348.547575)
			(xy 62.257173 -348.49927) (xy 62.291952 -348.455662) (xy 62.332842 -348.417725) (xy 62.37893 -348.386307)
			(xy 62.429187 -348.362108) (xy 62.482488 -348.345671) (xy 62.537645 -348.337363) (xy 62.565534 -348.33687)
			(xy 62.591956 -348.337315) (xy 62.644272 -348.344769) (xy 62.69501 -348.359538) (xy 62.743154 -348.381324)
			(xy 62.787739 -348.409692) (xy 62.808104 -348.426532) (xy 62.814962 -348.432374) (xy 62.83198 -348.438724)
			(xy 62.916308 -348.438724) (xy 62.933326 -348.432374) (xy 62.940184 -348.426532) (xy 62.96055 -348.409693)
			(xy 63.005136 -348.381328) (xy 63.05328 -348.359541) (xy 63.104017 -348.34477) (xy 63.156332 -348.33731)
			(xy 63.209176 -348.33731) (xy 63.261491 -348.34477) (xy 63.312228 -348.359541) (xy 63.360372 -348.381328)
			(xy 63.404958 -348.409693) (xy 63.425324 -348.426532) (xy 63.432182 -348.432374) (xy 63.4492 -348.438724)
			(xy 63.533528 -348.438724) (xy 63.550546 -348.432374) (xy 63.557404 -348.426532) (xy 63.575177 -348.411793)
			(xy 63.613713 -348.386357) (xy 63.655099 -348.365882) (xy 63.676784 -348.357952) (xy 63.677038 -348.357952)
			(xy 63.687058 -348.353786) (xy 63.702581 -348.338649) (xy 63.70701 -348.328742) (xy 63.739268 -348.246192)
			(xy 63.737998 -348.224094) (xy 63.732664 -348.214188) (xy 63.718927 -348.187081) (xy 63.699447 -348.129523)
			(xy 63.689577 -348.069565) (xy 63.688976 -348.039182) (xy 63.688976 -348.038928) (xy 63.689463 -348.011285)
			(xy 63.697623 -347.956605) (xy 63.713768 -347.903729) (xy 63.737544 -347.853818) (xy 63.76843 -347.807964)
			(xy 63.805748 -347.767174) (xy 63.826898 -347.749368) (xy 63.835343 -347.741789) (xy 63.845095 -347.721331)
			(xy 63.845694 -347.709998) (xy 63.845694 -347.631258) (xy 63.84506 -347.619938) (xy 63.835297 -347.599505)
			(xy 63.826898 -347.591888) (xy 63.805763 -347.574066) (xy 63.76845 -347.533276) (xy 63.737567 -347.487424)
			(xy 63.713792 -347.437516) (xy 63.697645 -347.384645) (xy 63.689479 -347.329969) (xy 63.688976 -347.302328)
			(xy 63.689497 -347.274443) (xy 63.697809 -347.219296) (xy 63.714247 -347.166004) (xy 63.738445 -347.115758)
			(xy 63.769861 -347.069679) (xy 63.807794 -347.028797) (xy 63.851396 -346.994025) (xy 63.899694 -346.96614)
			(xy 63.951609 -346.945765) (xy 64.00598 -346.933355) (xy 64.061594 -346.929188) (xy 64.117208 -346.933355)
			(xy 64.171579 -346.945765) (xy 64.223494 -346.96614) (xy 64.271792 -346.994025) (xy 64.315394 -347.028797)
			(xy 64.353327 -347.069679) (xy 64.384743 -347.115758) (xy 64.408941 -347.166004) (xy 64.425379 -347.219296)
			(xy 64.433691 -347.274443) (xy 64.434212 -347.302328) (xy 64.433699 -347.32997) (xy 64.425545 -347.384649)
			(xy 64.409406 -347.437524) (xy 64.385634 -347.487436) (xy 64.354753 -347.533291) (xy 64.317438 -347.574082)
			(xy 64.29629 -347.591888) (xy 64.287863 -347.599484) (xy 64.278102 -347.619929) (xy 64.277494 -347.631258)
			(xy 64.277494 -347.709998) (xy 64.278157 -347.721314) (xy 64.2879 -347.741747) (xy 64.29629 -347.749368)
			(xy 64.31747 -347.767139) (xy 64.354776 -347.807942) (xy 64.385651 -347.853805) (xy 64.409418 -347.903723)
			(xy 64.425556 -347.956602) (xy 64.433713 -348.011284) (xy 64.434212 -348.038928) (xy 64.433698 -348.067675)
			(xy 64.424872 -348.124486) (xy 64.407417 -348.179265) (xy 64.381749 -348.23071) (xy 64.348478 -348.277598)
			(xy 64.308395 -348.318815) (xy 64.262453 -348.35338) (xy 64.211743 -348.380472) (xy 64.184784 -348.390464)
			(xy 64.18453 -348.390464) (xy 64.174519 -348.394649) (xy 64.15899 -348.409771) (xy 64.154558 -348.419674)
			(xy 64.1223 -348.502224) (xy 64.12357 -348.524322) (xy 64.128904 -348.534228) (xy 64.142644 -348.561333)
			(xy 64.162124 -348.618892) (xy 64.171992 -348.678851) (xy 64.172592 -348.709234) (xy 64.172592 -348.709488)
			(xy 64.172155 -348.736107) (xy 64.164579 -348.788802) (xy 64.149581 -348.839884) (xy 64.127466 -348.88831)
			(xy 64.098683 -348.933096) (xy 64.06382 -348.97333) (xy 64.023585 -349.008192) (xy 63.978798 -349.036973)
			(xy 63.93037 -349.059086) (xy 63.879289 -349.074082) (xy 63.826593 -349.081656) (xy 63.799974 -349.082106)
			(xy 63.773552 -349.081662) (xy 63.721236 -349.074208) (xy 63.670497 -349.05944) (xy 63.622353 -349.037653)
			(xy 63.577769 -349.009285) (xy 63.557404 -348.992444) (xy 63.550546 -348.986602) (xy 63.533528 -348.980252)
			(xy 63.4492 -348.980252) (xy 63.432182 -348.986602) (xy 63.425324 -348.992444) (xy 63.404958 -349.009283)
			(xy 63.360372 -349.037648) (xy 63.312228 -349.059435) (xy 63.261491 -349.074206) (xy 63.209176 -349.081666)
			(xy 63.156332 -349.081666) (xy 63.104017 -349.074206) (xy 63.05328 -349.059435) (xy 63.005136 -349.037648)
			(xy 62.96055 -349.009283) (xy 62.940184 -348.992444) (xy 62.933326 -348.986602) (xy 62.916308 -348.980252)
			(xy 62.83198 -348.980252) (xy 62.814962 -348.986602) (xy 62.808104 -348.992444) (xy 62.78773 -349.009272)
			(xy 62.743143 -349.03763) (xy 62.695001 -349.059412) (xy 62.644266 -349.074182) (xy 62.591954 -349.081644)
			(xy 62.565534 -349.082106) (xy 62.537645 -349.081637) (xy 62.482488 -349.073329) (xy 62.429187 -349.056892)
			(xy 62.37893 -349.032693) (xy 62.332842 -349.001275) (xy 62.291952 -348.963338) (xy 62.257173 -348.91973)
			(xy 62.229282 -348.871425) (xy 62.208903 -348.819502) (xy 62.19649 -348.765123) (xy 62.192321 -348.7095)
			(xy 59.391538 -348.7095) (xy 59.04738 -349.053658) (xy 59.042197 -349.059296) (xy 59.035101 -349.072858)
			(xy 59.03341 -349.080328) (xy 59.032253 -349.087988) (xy 59.034075 -349.103365) (xy 59.036966 -349.110554)
			(xy 59.076082 -349.197168) (xy 59.081951 -349.208379) (xy 59.10207 -349.223678) (xy 59.114436 -349.226378)
			(xy 59.125612 -349.226886) (xy 59.125866 -349.226886) (xy 59.149996 -349.226124) (xy 59.175544 -349.226532)
			(xy 59.226183 -349.233347) (xy 59.275461 -349.246855) (xy 59.322496 -349.266815) (xy 59.366449 -349.292871)
			(xy 59.386724 -349.30842) (xy 59.408891 -349.326617) (xy 59.448032 -349.368534) (xy 59.480455 -349.415839)
			(xy 59.505429 -349.467466) (xy 59.522391 -349.52225) (xy 59.530959 -349.578957) (xy 59.531504 -349.607632)
			(xy 59.531016 -349.634882) (xy 59.523256 -349.688826) (xy 59.507898 -349.741116) (xy 59.485255 -349.790689)
			(xy 59.455788 -349.836535) (xy 59.420096 -349.877722) (xy 59.378907 -349.913409) (xy 59.333058 -349.942872)
			(xy 59.283483 -349.96551) (xy 59.23119 -349.980863) (xy 59.177246 -349.988619) (xy 59.149996 -349.98914)
			(xy 59.122975 -349.98867) (xy 59.069473 -349.981044) (xy 59.017583 -349.965944) (xy 58.968342 -349.943674)
			(xy 58.922737 -349.914678) (xy 58.88168 -349.879536) (xy 58.845992 -349.838953) (xy 58.816388 -349.793741)
			(xy 58.793461 -349.744803) (xy 58.777668 -349.693119) (xy 58.769326 -349.639724) (xy 58.768488 -349.612712)
			(xy 58.768488 -349.607632) (xy 58.769081 -349.5777) (xy 58.778432 -349.518572) (xy 58.796881 -349.461622)
			(xy 58.80989 -349.434658) (xy 58.8137 -349.424752) (xy 58.819034 -349.404432) (xy 58.818796 -349.39748)
			(xy 58.815064 -349.384086) (xy 58.811668 -349.378016) (xy 58.80989 -349.375222) (xy 58.801762 -349.366078)
			(xy 58.79846 -349.363538) (xy 58.798206 -349.363284) (xy 58.79264 -349.359432) (xy 58.780022 -349.354544)
			(xy 58.773314 -349.353632) (xy 58.770266 -349.353378) (xy 58.764678 -349.353886) (xy 58.755638 -349.354898)
			(xy 58.739102 -349.362446) (xy 58.73242 -349.368618) (xy 58.612278 -349.48876) (xy 58.60669 -349.495364)
			(xy 58.603501 -349.500083) (xy 58.599129 -349.510599) (xy 58.598054 -349.516192) (xy 58.597292 -349.524828)
			(xy 58.597292 -350.058736) (xy 58.598054 -350.067372) (xy 58.59918 -350.072951) (xy 58.603537 -350.083462)
			(xy 58.60669 -350.0882) (xy 58.612278 -350.094804) (xy 58.633106 -350.115632) (xy 58.635956 -350.118339)
			(xy 58.642334 -350.122934) (xy 58.645806 -350.124776) (xy 58.659014 -350.131634) (xy 58.664602 -350.133158)
			(xy 58.691669 -350.140527) (xy 58.743444 -350.162118) (xy 58.791499 -350.191058) (xy 58.834798 -350.226722)
			(xy 58.872409 -350.268343) (xy 58.90352 -350.315022) (xy 58.92746 -350.365753) (xy 58.943713 -350.419443)
			(xy 58.95193 -350.474934) (xy 58.952384 -350.502982) (xy 58.951922 -350.530235) (xy 58.944167 -350.584187)
			(xy 58.928812 -350.636485) (xy 58.90617 -350.686066) (xy 58.876702 -350.73192) (xy 58.841008 -350.773113)
			(xy 58.799815 -350.808806) (xy 58.753961 -350.838273) (xy 58.70438 -350.860914) (xy 58.652081 -350.876268)
			(xy 58.598129 -350.884022) (xy 58.570876 -350.88449) (xy 58.542576 -350.883966) (xy 58.486599 -350.875585)
			(xy 58.432475 -350.859025) (xy 58.381392 -350.83465) (xy 58.334471 -350.802995) (xy 58.292742 -350.764755)
			(xy 58.257121 -350.720768) (xy 58.22839 -350.672002) (xy 58.20718 -350.619525) (xy 58.200036 -350.592136)
			(xy 58.198258 -350.585278) (xy 58.19521 -350.57969) (xy 58.193415 -350.576574) (xy 58.189087 -350.570832)
			(xy 58.186574 -350.56826) (xy 58.054748 -350.436434) (xy 58.037464 -350.418436) (xy 58.008155 -350.378053)
			(xy 57.985515 -350.333587) (xy 57.970101 -350.286129) (xy 57.96229 -350.236847) (xy 57.961784 -350.211898)
			(xy 57.961784 -349.371666) (xy 57.962243 -349.346713) (xy 57.97004 -349.297419) (xy 57.985453 -349.249952)
			(xy 58.008101 -349.20548) (xy 58.037428 -349.165099) (xy 58.054748 -349.14713) (xy 58.270902 -348.930976)
			(xy 58.275543 -348.925997) (xy 58.282241 -348.914153) (xy 58.28411 -348.907608) (xy 58.284364 -348.907608)
			(xy 58.286084 -348.899462) (xy 58.284798 -348.882872) (xy 58.281824 -348.875096) (xy 58.26379 -348.832678)
			(xy 58.243978 -348.785688) (xy 58.240977 -348.780054) (xy 58.232619 -348.770409) (xy 58.227468 -348.766638)
			(xy 58.218832 -348.761304) (xy 58.204862 -348.757494) (xy 58.191654 -348.757494) (xy 58.164405 -348.757005)
			(xy 58.110463 -348.749243) (xy 58.058175 -348.733883) (xy 58.008605 -348.71124) (xy 57.962761 -348.681772)
			(xy 57.921577 -348.64608) (xy 57.885892 -348.604891) (xy 57.856432 -348.559043) (xy 57.833796 -348.509469)
			(xy 57.818445 -348.457178) (xy 57.810691 -348.403235) (xy 57.810146 -348.375986) (xy 57.810633 -348.348075)
			(xy 57.818771 -348.292851) (xy 57.83487 -348.239401) (xy 57.858587 -348.188869) (xy 57.889416 -348.142333)
			(xy 57.907682 -348.121224) (xy 57.914032 -348.114112) (xy 57.917334 -348.105476) (xy 57.918877 -348.101128)
			(xy 57.920536 -348.092054) (xy 57.920636 -348.087442) (xy 57.920636 -348.019116) (xy 57.920539 -348.014503)
			(xy 57.918884 -348.005427) (xy 57.917334 -348.001082) (xy 57.914032 -347.992446) (xy 57.907682 -347.985334)
			(xy 57.889403 -347.964234) (xy 57.858574 -347.917695) (xy 57.834854 -347.867161) (xy 57.818751 -347.813711)
			(xy 57.810607 -347.758484) (xy 57.810146 -347.730572) (xy 57.810632 -347.703321) (xy 57.818388 -347.649373)
			(xy 57.833743 -347.597078) (xy 57.856385 -347.547501) (xy 57.885851 -347.501651) (xy 57.921542 -347.46046)
			(xy 57.962733 -347.424769) (xy 58.008583 -347.395303) (xy 58.05816 -347.372661) (xy 58.110455 -347.357306)
			(xy 58.164403 -347.34955) (xy 58.218905 -347.34955) (xy 58.272853 -347.357306) (xy 58.325148 -347.372661)
			(xy 58.374725 -347.395303) (xy 58.420575 -347.424769) (xy 58.461766 -347.46046) (xy 58.497457 -347.501651)
			(xy 58.526923 -347.547501) (xy 58.549565 -347.597078) (xy 58.56492 -347.649373) (xy 58.572676 -347.703321)
			(xy 58.573162 -347.730572) (xy 58.572678 -347.758484) (xy 58.564546 -347.813712) (xy 58.548452 -347.867165)
			(xy 58.524739 -347.917701) (xy 58.493913 -347.964242) (xy 58.475626 -347.985334) (xy 58.469276 -347.992446)
			(xy 58.465974 -348.001082) (xy 58.464428 -348.005429) (xy 58.46276 -348.014503) (xy 58.462672 -348.019116)
			(xy 58.462672 -348.087442) (xy 58.462775 -348.092054) (xy 58.464439 -348.101126) (xy 58.465974 -348.105476)
			(xy 58.469276 -348.114112) (xy 58.475626 -348.121224) (xy 58.493901 -348.142325) (xy 58.524723 -348.188865)
			(xy 58.548434 -348.2394) (xy 58.564529 -348.29285) (xy 58.572665 -348.348075) (xy 58.573162 -348.375986)
			(xy 58.573162 -348.382844) (xy 58.573548 -348.392372) (xy 58.580492 -348.410117) (xy 58.59344 -348.424098)
			(xy 58.601864 -348.428564) (xy 58.637424 -348.44355) (xy 58.690764 -348.466156) (xy 58.698864 -348.469215)
			(xy 58.716136 -348.470251) (xy 58.724546 -348.468188) (xy 58.730735 -348.466243) (xy 58.741922 -348.459683)
			(xy 58.746644 -348.455234) (xy 59.020202 -348.181676) (xy 59.025133 -348.175326) (xy 59.031213 -348.160452)
			(xy 59.03214 -348.152466) (xy 59.03214 -338.418678) (xy 59.031378 -338.410042) (xy 59.030252 -338.404464)
			(xy 59.025892 -338.393954) (xy 59.022742 -338.389214) (xy 59.017154 -338.38261) (xy 57.644792 -337.010248)
			(xy 57.62751 -336.992248) (xy 57.598204 -336.951864) (xy 57.575567 -336.907398) (xy 57.560153 -336.859942)
			(xy 57.552341 -336.81066) (xy 57.551828 -336.785712) (xy 57.551828 -335.220564) (xy 57.552312 -335.195612)
			(xy 57.560108 -335.146321) (xy 57.575517 -335.098857) (xy 57.598161 -335.054386) (xy 57.627483 -335.014005)
			(xy 57.644792 -334.996028) (xy 58.011568 -334.629252) (xy 58.018259 -334.62184) (xy 58.02587 -334.603401)
			(xy 58.025881 -334.583453) (xy 58.018289 -334.565006) (xy 58.011568 -334.557624) (xy 57.590182 -334.136238)
			(xy 57.583337 -334.12884) (xy 57.575612 -334.110241) (xy 57.575196 -334.10017) (xy 57.575196 -326.607932)
			(xy 57.575632 -326.597867) (xy 57.583363 -326.57928) (xy 57.590182 -326.571864) (xy 59.191144 -324.970902)
			(xy 59.196131 -324.965403) (xy 59.202976 -324.952237) (xy 59.204606 -324.944994) (xy 59.205622 -324.935342)
			(xy 59.205622 -323.787516) (xy 59.205523 -323.782639) (xy 59.203728 -323.773052) (xy 59.202066 -323.768466)
			(xy 59.198256 -323.759322) (xy 59.188096 -323.749162) (xy 59.18708 -323.7484) (xy 59.180508 -323.742614)
			(xy 59.164532 -323.735477) (xy 59.155838 -323.73443) (xy 39.351204 -323.590412) (xy 17.674336 -323.590412)
			(xy 17.669446 -323.59055) (xy 17.659854 -323.592471) (xy 17.655286 -323.594222) (xy 17.645634 -323.598032)
			(xy 17.638014 -323.598032) (xy 17.619472 -323.605652) (xy 15.578836 -325.646288) (xy 15.571984 -325.653684)
			(xy 15.564239 -325.672282) (xy 15.56385 -325.682356) (xy 15.56385 -333.780638) (xy 16.980408 -333.780638)
			(xy 16.980883 -333.753664) (xy 16.988466 -333.700252) (xy 17.003501 -333.648441) (xy 17.025687 -333.599266)
			(xy 17.054581 -333.553708) (xy 17.089607 -333.512677) (xy 17.130066 -333.476992) (xy 17.17515 -333.447364)
			(xy 17.199356 -333.435452) (xy 17.207484 -333.431642) (xy 18.71345 -331.925676) (xy 18.720286 -331.918272)
			(xy 18.72801 -331.899676) (xy 18.728436 -331.889608) (xy 18.728436 -329.14463) (xy 18.729022 -329.11669)
			(xy 18.737776 -329.061498) (xy 18.755043 -329.008352) (xy 18.780398 -328.958554) (xy 18.813221 -328.913328)
			(xy 18.832576 -328.89317) (xy 23.361904 -324.363842) (xy 23.382054 -324.344425) (xy 23.42732 -324.311533)
			(xy 23.477171 -324.286118) (xy 23.53038 -324.268804) (xy 23.585641 -324.260017) (xy 23.613618 -324.259448)
			(xy 24.193246 -324.259448) (xy 24.201628 -324.256654) (xy 24.232841 -324.24612) (xy 24.297725 -324.234758)
			(xy 24.33066 -324.234048) (xy 24.357912 -324.234596) (xy 24.411861 -324.242348) (xy 24.464157 -324.257699)
			(xy 24.513737 -324.280336) (xy 24.55959 -324.3098) (xy 24.600782 -324.345489) (xy 24.636476 -324.386678)
			(xy 24.665944 -324.432528) (xy 24.688587 -324.482105) (xy 24.703944 -324.5344) (xy 24.711701 -324.588348)
			(xy 24.711701 -324.642852) (xy 24.703944 -324.6968) (xy 24.688587 -324.749095) (xy 24.665944 -324.798672)
			(xy 24.636476 -324.844522) (xy 24.600782 -324.885711) (xy 24.55959 -324.9214) (xy 24.513737 -324.950864)
			(xy 24.464157 -324.973501) (xy 24.411861 -324.988852) (xy 24.357912 -324.996604) (xy 24.33066 -324.997064)
			(xy 24.297727 -324.99634) (xy 24.232848 -324.984968) (xy 24.201628 -324.974458) (xy 24.193246 -324.971664)
			(xy 23.782274 -324.971664) (xy 23.772201 -324.972059) (xy 23.753602 -324.979799) (xy 23.746206 -324.98665)
			(xy 19.45513 -329.277472) (xy 19.448314 -329.284891) (xy 19.440579 -329.303476) (xy 19.440144 -329.31354)
			(xy 19.440144 -332.058518) (xy 19.439594 -332.08646) (xy 19.432336 -332.132178) (xy 20.688044 -332.132178)
			(xy 20.692115 -332.076556) (xy 20.704241 -332.022119) (xy 20.724164 -331.970028) (xy 20.75146 -331.921393)
			(xy 20.785546 -331.87725) (xy 20.825695 -331.838541) (xy 20.871053 -331.80609) (xy 20.920653 -331.780589)
			(xy 20.973437 -331.762582) (xy 21.02828 -331.752452) (xy 21.084014 -331.750415) (xy 21.139451 -331.756515)
			(xy 21.193408 -331.770621) (xy 21.244737 -331.792433) (xy 21.292343 -331.821487) (xy 21.335211 -331.857162)
			(xy 21.372428 -331.898699) (xy 21.403201 -331.945212) (xy 21.426873 -331.995709) (xy 21.442941 -332.049116)
			(xy 21.451061 -332.104292) (xy 21.45157 -332.132178) (xy 21.451061 -332.160064) (xy 21.442941 -332.21524)
			(xy 21.426873 -332.268647) (xy 21.403201 -332.319144) (xy 21.372428 -332.365657) (xy 21.335211 -332.407194)
			(xy 21.292343 -332.442869) (xy 21.244737 -332.471923) (xy 21.193408 -332.493735) (xy 21.139451 -332.507841)
			(xy 21.084014 -332.513941) (xy 21.02828 -332.511904) (xy 20.973437 -332.501774) (xy 20.920653 -332.483767)
			(xy 20.871053 -332.458266) (xy 20.825695 -332.425815) (xy 20.785546 -332.387106) (xy 20.75146 -332.342963)
			(xy 20.724164 -332.294328) (xy 20.704241 -332.242237) (xy 20.692115 -332.1878) (xy 20.688044 -332.132178)
			(xy 19.432336 -332.132178) (xy 19.430832 -332.141653) (xy 19.413557 -332.1948) (xy 19.388193 -332.244597)
			(xy 19.355363 -332.289822) (xy 19.336004 -332.309978) (xy 18.497804 -333.148178) (xy 20.705824 -333.148178)
			(xy 20.709895 -333.092556) (xy 20.722021 -333.038119) (xy 20.741944 -332.986028) (xy 20.76924 -332.937393)
			(xy 20.803326 -332.89325) (xy 20.843475 -332.854541) (xy 20.888833 -332.82209) (xy 20.938433 -332.796589)
			(xy 20.991217 -332.778582) (xy 21.04606 -332.768452) (xy 21.101794 -332.766415) (xy 21.157231 -332.772515)
			(xy 21.211188 -332.786621) (xy 21.262517 -332.808433) (xy 21.310123 -332.837487) (xy 21.352991 -332.873162)
			(xy 21.390208 -332.914699) (xy 21.420981 -332.961212) (xy 21.444653 -333.011709) (xy 21.460721 -333.065116)
			(xy 21.468841 -333.120292) (xy 21.46935 -333.148178) (xy 21.468841 -333.176064) (xy 21.460721 -333.23124)
			(xy 21.444653 -333.284647) (xy 21.420981 -333.335144) (xy 21.390208 -333.381657) (xy 21.352991 -333.423194)
			(xy 21.310123 -333.458869) (xy 21.262517 -333.487923) (xy 21.211188 -333.509735) (xy 21.157231 -333.523841)
			(xy 21.101794 -333.529941) (xy 21.04606 -333.527904) (xy 20.991217 -333.517774) (xy 20.938433 -333.499767)
			(xy 20.888833 -333.474266) (xy 20.843475 -333.441815) (xy 20.803326 -333.403106) (xy 20.76924 -333.358963)
			(xy 20.741944 -333.310328) (xy 20.722021 -333.258237) (xy 20.709895 -333.2038) (xy 20.705824 -333.148178)
			(xy 18.497804 -333.148178) (xy 17.710912 -333.93507) (xy 17.707102 -333.943198) (xy 17.695203 -333.967409)
			(xy 17.665561 -334.012482) (xy 17.629868 -334.052932) (xy 17.588833 -334.087953) (xy 17.543276 -334.116846)
			(xy 17.494105 -334.139036) (xy 17.442298 -334.15408) (xy 17.388889 -334.161679) (xy 17.361916 -334.162146)
			(xy 17.334667 -334.161607) (xy 17.280723 -334.153854) (xy 17.228432 -334.138502) (xy 17.178857 -334.115866)
			(xy 17.133009 -334.086405) (xy 17.091819 -334.050719) (xy 17.056127 -334.009535) (xy 17.02666 -333.96369)
			(xy 17.004016 -333.914119) (xy 16.988658 -333.86183) (xy 16.980897 -333.807887) (xy 16.980408 -333.780638)
			(xy 15.56385 -333.780638) (xy 15.56385 -334.041496) (xy 15.564274 -334.051565) (xy 15.571993 -334.070166)
			(xy 15.578836 -334.077564) (xy 18.593308 -337.092036) (xy 18.596356 -337.096608) (xy 22.281134 -342.611456)
			(xy 22.286789 -342.618631) (xy 22.301997 -342.628729) (xy 22.319785 -342.632836) (xy 22.328886 -342.63203)
			(xy 22.342094 -342.62949) (xy 22.346412 -342.627966) (xy 22.378372 -342.616592) (xy 22.445084 -342.604318)
			(xy 22.479 -342.603582) (xy 22.483318 -342.603582) (xy 22.509733 -342.604349) (xy 22.561957 -342.61242)
			(xy 22.612517 -342.627788) (xy 22.660399 -342.650144) (xy 22.704642 -342.679041) (xy 22.744359 -342.713898)
			(xy 22.778754 -342.754017) (xy 22.807136 -342.798592) (xy 22.828936 -342.846729) (xy 22.843717 -342.897464)
			(xy 22.851182 -342.949778) (xy 22.851618 -342.9762) (xy 22.851102 -343.004023) (xy 22.842824 -343.059049)
			(xy 22.826454 -343.112231) (xy 22.802355 -343.162387) (xy 22.771063 -343.2084) (xy 22.752558 -343.229184)
			(xy 22.746462 -343.235788) (xy 22.737572 -343.257632) (xy 22.734328 -343.268129) (xy 22.736158 -343.289999)
			(xy 22.741128 -343.299796) (xy 22.742906 -343.30259) (xy 23.923244 -345.06916) (xy 24.137366 -345.389708)
			(xy 24.137874 -345.39047) (xy 24.138128 -345.390978) (xy 24.139652 -345.39301) (xy 24.14302 -345.397013)
			(xy 24.151081 -345.403678) (xy 24.155654 -345.406218) (xy 24.16175 -345.40952) (xy 24.175974 -345.433396)
			(xy 24.175974 -345.447112) (xy 24.679656 -346.200984) (xy 24.698176 -346.229595) (xy 24.729119 -346.290322)
			(xy 24.752716 -346.354264) (xy 24.768639 -346.420534) (xy 24.776668 -346.488216) (xy 24.777192 -346.522294)
			(xy 24.777192 -347.249242) (xy 24.777739 -347.259598) (xy 24.786004 -347.278597) (xy 24.793194 -347.286072)
			(xy 24.82088 -347.311472) (xy 24.848312 -347.336872) (xy 24.855573 -347.343053) (xy 24.873327 -347.349967)
			(xy 24.882856 -347.350334) (xy 24.883618 -347.350334) (xy 24.886666 -347.35008) (xy 24.9174 -347.349064)
			(xy 24.917908 -347.349064) (xy 24.94515 -347.349564) (xy 24.999077 -347.357344) (xy 25.051348 -347.372717)
			(xy 25.100901 -347.39537) (xy 25.146728 -347.424841) (xy 25.187895 -347.460532) (xy 25.223567 -347.501717)
			(xy 25.253017 -347.547557) (xy 25.275646 -347.59712) (xy 25.290994 -347.649399) (xy 25.298749 -347.703329)
			(xy 25.299162 -347.730572) (xy 25.298678 -347.758484) (xy 25.290546 -347.813712) (xy 25.274452 -347.867165)
			(xy 25.250739 -347.917701) (xy 25.219913 -347.964242) (xy 25.201626 -347.985334) (xy 25.195276 -347.992446)
			(xy 25.191974 -348.001082) (xy 25.190428 -348.005429) (xy 25.18876 -348.014503) (xy 25.188672 -348.019116)
			(xy 25.188672 -348.087442) (xy 25.188775 -348.092054) (xy 25.190439 -348.101126) (xy 25.191974 -348.105476)
			(xy 25.195276 -348.114112) (xy 25.201626 -348.121224) (xy 25.219901 -348.142325) (xy 25.250723 -348.188865)
			(xy 25.274434 -348.2394) (xy 25.290529 -348.29285) (xy 25.298665 -348.348075) (xy 25.299162 -348.375986)
			(xy 25.299162 -348.382844) (xy 25.299548 -348.392372) (xy 25.306492 -348.410117) (xy 25.31944 -348.424098)
			(xy 25.327864 -348.428564) (xy 25.363424 -348.44355) (xy 25.416764 -348.466156) (xy 25.424864 -348.469215)
			(xy 25.442136 -348.470251) (xy 25.450546 -348.468188) (xy 25.456735 -348.466243) (xy 25.467922 -348.459683)
			(xy 25.472644 -348.455234) (xy 25.746202 -348.181676) (xy 25.751133 -348.175326) (xy 25.757213 -348.160452)
			(xy 25.75814 -348.152466) (xy 25.75814 -334.965802) (xy 25.757886 -334.959706) (xy 25.757069 -334.954339)
			(xy 25.753479 -334.944094) (xy 25.750774 -334.939386) (xy 25.73765 -334.916919) (xy 25.716946 -334.869186)
			(xy 25.702925 -334.819081) (xy 25.695847 -334.767535) (xy 25.695402 -334.74152) (xy 25.695842 -334.715872)
			(xy 25.702755 -334.665044) (xy 25.716407 -334.615598) (xy 25.736551 -334.568423) (xy 25.762826 -334.524367)
			(xy 25.77846 -334.50403) (xy 25.783794 -334.497172) (xy 25.786588 -334.489298) (xy 25.787886 -334.485229)
			(xy 25.789288 -334.476804) (xy 25.789382 -334.472534) (xy 25.789382 -334.439768) (xy 25.800558 -334.439768)
			(xy 25.800558 -334.388968) (xy 25.800437 -334.38442) (xy 25.798782 -334.375474) (xy 25.797256 -334.371188)
			(xy 25.794208 -334.362806) (xy 25.788112 -334.355694) (xy 25.77072 -334.334817) (xy 25.741406 -334.289067)
			(xy 25.718885 -334.239618) (xy 25.703611 -334.187473) (xy 25.695894 -334.133688) (xy 25.695402 -334.10652)
			(xy 25.695842 -334.080872) (xy 25.702755 -334.030044) (xy 25.716407 -333.980598) (xy 25.736551 -333.933423)
			(xy 25.762826 -333.889367) (xy 25.77846 -333.86903) (xy 25.783794 -333.862172) (xy 25.786588 -333.854298)
			(xy 25.787886 -333.850229) (xy 25.789288 -333.841804) (xy 25.789382 -333.837534) (xy 25.789382 -333.804768)
			(xy 25.800558 -333.804768) (xy 25.800558 -333.753968) (xy 25.800437 -333.74942) (xy 25.798782 -333.740474)
			(xy 25.797256 -333.736188) (xy 25.794208 -333.727806) (xy 25.788112 -333.720694) (xy 25.77072 -333.699817)
			(xy 25.741406 -333.654067) (xy 25.718885 -333.604618) (xy 25.703611 -333.552473) (xy 25.695894 -333.498688)
			(xy 25.695402 -333.47152) (xy 25.695842 -333.445872) (xy 25.702755 -333.395044) (xy 25.716407 -333.345598)
			(xy 25.736551 -333.298423) (xy 25.762826 -333.254367) (xy 25.77846 -333.23403) (xy 25.783794 -333.227172)
			(xy 25.786588 -333.219298) (xy 25.787886 -333.215229) (xy 25.789288 -333.206804) (xy 25.789382 -333.202534)
			(xy 25.789382 -333.169768) (xy 25.800558 -333.169768) (xy 25.800558 -333.118968) (xy 25.800437 -333.11442)
			(xy 25.798782 -333.105474) (xy 25.797256 -333.101188) (xy 25.794208 -333.092806) (xy 25.788112 -333.085694)
			(xy 25.77072 -333.064817) (xy 25.741406 -333.019067) (xy 25.718885 -332.969618) (xy 25.703611 -332.917473)
			(xy 25.695894 -332.863688) (xy 25.695402 -332.83652) (xy 25.695842 -332.810872) (xy 25.702755 -332.760044)
			(xy 25.716407 -332.710598) (xy 25.736551 -332.663423) (xy 25.762826 -332.619367) (xy 25.77846 -332.59903)
			(xy 25.783794 -332.592172) (xy 25.786588 -332.584298) (xy 25.787886 -332.580229) (xy 25.789288 -332.571804)
			(xy 25.789382 -332.567534) (xy 25.789382 -332.534768) (xy 25.800558 -332.534768) (xy 25.800558 -332.483968)
			(xy 25.800437 -332.47942) (xy 25.798782 -332.470474) (xy 25.797256 -332.466188) (xy 25.794208 -332.457806)
			(xy 25.788112 -332.450694) (xy 25.77072 -332.429817) (xy 25.741406 -332.384067) (xy 25.718885 -332.334618)
			(xy 25.703611 -332.282473) (xy 25.695894 -332.228688) (xy 25.695402 -332.20152) (xy 25.695842 -332.175872)
			(xy 25.702755 -332.125044) (xy 25.716407 -332.075598) (xy 25.736551 -332.028423) (xy 25.762826 -331.984367)
			(xy 25.77846 -331.96403) (xy 25.783794 -331.957172) (xy 25.786588 -331.949298) (xy 25.787886 -331.945229)
			(xy 25.789288 -331.936804) (xy 25.789382 -331.932534) (xy 25.789382 -331.899768) (xy 25.800558 -331.899768)
			(xy 25.800558 -331.848968) (xy 25.800437 -331.84442) (xy 25.798782 -331.835474) (xy 25.797256 -331.831188)
			(xy 25.794208 -331.822806) (xy 25.788112 -331.815694) (xy 25.77072 -331.794817) (xy 25.741406 -331.749067)
			(xy 25.718885 -331.699618) (xy 25.703611 -331.647473) (xy 25.695894 -331.593688) (xy 25.695402 -331.56652)
			(xy 25.695842 -331.540872) (xy 25.702755 -331.490044) (xy 25.716407 -331.440598) (xy 25.736551 -331.393423)
			(xy 25.762826 -331.349367) (xy 25.77846 -331.32903) (xy 25.783794 -331.322172) (xy 25.786588 -331.314298)
			(xy 25.787886 -331.310229) (xy 25.789288 -331.301804) (xy 25.789382 -331.297534) (xy 25.789382 -331.264768)
			(xy 25.800558 -331.264768) (xy 25.800558 -331.213968) (xy 25.800437 -331.20942) (xy 25.798782 -331.200474)
			(xy 25.797256 -331.196188) (xy 25.794208 -331.187806) (xy 25.788112 -331.180694) (xy 25.77072 -331.159817)
			(xy 25.741406 -331.114067) (xy 25.718885 -331.064618) (xy 25.703611 -331.012473) (xy 25.695894 -330.958688)
			(xy 25.695402 -330.93152) (xy 25.695842 -330.905872) (xy 25.702755 -330.855044) (xy 25.716407 -330.805598)
			(xy 25.736551 -330.758423) (xy 25.762826 -330.714367) (xy 25.77846 -330.69403) (xy 25.783794 -330.687172)
			(xy 25.786588 -330.679298) (xy 25.787886 -330.675229) (xy 25.789288 -330.666804) (xy 25.789382 -330.662534)
			(xy 25.789382 -330.629768) (xy 25.800558 -330.629768) (xy 25.800558 -330.578968) (xy 25.800437 -330.57442)
			(xy 25.798782 -330.565474) (xy 25.797256 -330.561188) (xy 25.794208 -330.552806) (xy 25.788112 -330.545694)
			(xy 25.77072 -330.524817) (xy 25.741406 -330.479067) (xy 25.718885 -330.429618) (xy 25.703611 -330.377473)
			(xy 25.695894 -330.323688) (xy 25.695402 -330.29652) (xy 25.695864 -330.269266) (xy 25.703619 -330.215314)
			(xy 25.718973 -330.163014) (xy 25.741615 -330.113432) (xy 25.771082 -330.067577) (xy 25.806776 -330.026383)
			(xy 25.847969 -329.990688) (xy 25.893823 -329.961219) (xy 25.943405 -329.938577) (xy 25.995704 -329.923221)
			(xy 26.049656 -329.915465) (xy 26.07691 -329.915012) (xy 26.102559 -329.915447) (xy 26.153391 -329.922352)
			(xy 26.202843 -329.935997) (xy 26.250024 -329.956135) (xy 26.294086 -329.982405) (xy 26.3144 -329.99807)
			(xy 26.321258 -330.003404) (xy 26.329132 -330.006198) (xy 26.3332 -330.007502) (xy 26.341625 -330.008914)
			(xy 26.345896 -330.008992) (xy 26.378662 -330.008992) (xy 26.378662 -330.020168) (xy 26.429462 -330.020168)
			(xy 26.43401 -330.020045) (xy 26.442954 -330.018385) (xy 26.447242 -330.016866) (xy 26.455624 -330.013818)
			(xy 26.462736 -330.007722) (xy 26.483612 -329.990326) (xy 26.52936 -329.961003) (xy 26.578808 -329.938471)
			(xy 26.630953 -329.923188) (xy 26.68474 -329.915461) (xy 26.71191 -329.915012) (xy 26.737559 -329.915447)
			(xy 26.788391 -329.922352) (xy 26.837843 -329.935997) (xy 26.885024 -329.956135) (xy 26.929086 -329.982405)
			(xy 26.9494 -329.99807) (xy 26.956258 -330.003404) (xy 26.964132 -330.006198) (xy 26.9682 -330.007502)
			(xy 26.976625 -330.008914) (xy 26.980896 -330.008992) (xy 27.013662 -330.008992) (xy 27.013662 -330.020168)
			(xy 27.064462 -330.020168) (xy 27.06901 -330.020045) (xy 27.077954 -330.018385) (xy 27.082242 -330.016866)
			(xy 27.090624 -330.013818) (xy 27.097736 -330.007722) (xy 27.118612 -329.990326) (xy 27.16436 -329.961003)
			(xy 27.213808 -329.938471) (xy 27.265953 -329.923188) (xy 27.31974 -329.915461) (xy 27.34691 -329.915012)
			(xy 27.374162 -329.915476) (xy 27.428111 -329.923234) (xy 27.480406 -329.938591) (xy 27.529984 -329.961235)
			(xy 27.575834 -329.990703) (xy 27.617024 -330.026397) (xy 27.652715 -330.06759) (xy 27.68218 -330.113443)
			(xy 27.704819 -330.163022) (xy 27.720172 -330.215319) (xy 27.727926 -330.269268) (xy 27.728418 -330.29652)
			(xy 27.727982 -330.322169) (xy 27.721075 -330.372999) (xy 27.707427 -330.422449) (xy 27.687285 -330.469627)
			(xy 27.66101 -330.513685) (xy 27.64536 -330.53401) (xy 27.640026 -330.540868) (xy 27.637232 -330.548742)
			(xy 27.635931 -330.552811) (xy 27.634522 -330.561235) (xy 27.634438 -330.565506) (xy 27.634438 -330.598272)
			(xy 27.623262 -330.598272) (xy 27.623262 -330.649072) (xy 27.623386 -330.65362) (xy 27.625049 -330.662563)
			(xy 27.626564 -330.666852) (xy 27.629612 -330.675234) (xy 27.635708 -330.682346) (xy 27.653102 -330.703222)
			(xy 27.682422 -330.748972) (xy 27.70495 -330.79842) (xy 27.720231 -330.850565) (xy 27.727956 -330.904351)
			(xy 27.728418 -330.93152) (xy 27.727982 -330.957169) (xy 27.721075 -331.007999) (xy 27.707427 -331.057449)
			(xy 27.687285 -331.104627) (xy 27.66101 -331.148685) (xy 27.64536 -331.16901) (xy 27.640026 -331.175868)
			(xy 27.637232 -331.183742) (xy 27.635931 -331.187811) (xy 27.634522 -331.196235) (xy 27.634438 -331.200506)
			(xy 27.634438 -331.233272) (xy 27.623262 -331.233272) (xy 27.623262 -331.284072) (xy 27.623386 -331.28862)
			(xy 27.625049 -331.297563) (xy 27.626564 -331.301852) (xy 27.629612 -331.310234) (xy 27.635708 -331.317346)
			(xy 27.653102 -331.338222) (xy 27.682422 -331.383972) (xy 27.70495 -331.43342) (xy 27.720231 -331.485565)
			(xy 27.727956 -331.539351) (xy 27.728418 -331.56652) (xy 27.727982 -331.592169) (xy 27.721075 -331.642999)
			(xy 27.707427 -331.692449) (xy 27.687285 -331.739627) (xy 27.66101 -331.783685) (xy 27.64536 -331.80401)
			(xy 27.640026 -331.810868) (xy 27.637232 -331.818742) (xy 27.635931 -331.822811) (xy 27.634522 -331.831235)
			(xy 27.634438 -331.835506) (xy 27.634438 -331.868272) (xy 27.623262 -331.868272) (xy 27.623262 -331.919072)
			(xy 27.623386 -331.92362) (xy 27.625049 -331.932563) (xy 27.626564 -331.936852) (xy 27.629612 -331.945234)
			(xy 27.635708 -331.952346) (xy 27.653102 -331.973222) (xy 27.682422 -332.018972) (xy 27.70495 -332.06842)
			(xy 27.720231 -332.120565) (xy 27.727956 -332.174351) (xy 27.728418 -332.20152) (xy 27.727982 -332.227169)
			(xy 27.721075 -332.277999) (xy 27.707427 -332.327449) (xy 27.687285 -332.374627) (xy 27.66101 -332.418685)
			(xy 27.64536 -332.43901) (xy 27.640026 -332.445868) (xy 27.637232 -332.453742) (xy 27.635931 -332.457811)
			(xy 27.634522 -332.466235) (xy 27.634438 -332.470506) (xy 27.634438 -332.503272) (xy 27.623262 -332.503272)
			(xy 27.623262 -332.554072) (xy 27.623386 -332.55862) (xy 27.625049 -332.567563) (xy 27.626564 -332.571852)
			(xy 27.629612 -332.580234) (xy 27.635708 -332.587346) (xy 27.653102 -332.608222) (xy 27.682422 -332.653972)
			(xy 27.70495 -332.70342) (xy 27.720231 -332.755565) (xy 27.727956 -332.809351) (xy 27.728418 -332.83652)
			(xy 27.727982 -332.862169) (xy 27.721075 -332.912999) (xy 27.707427 -332.962449) (xy 27.687285 -333.009627)
			(xy 27.66101 -333.053685) (xy 27.64536 -333.07401) (xy 27.640026 -333.080868) (xy 27.637232 -333.088742)
			(xy 27.635931 -333.092811) (xy 27.634522 -333.101235) (xy 27.634438 -333.105506) (xy 27.634438 -333.138272)
			(xy 27.623262 -333.138272) (xy 27.623262 -333.189072) (xy 27.623386 -333.19362) (xy 27.625049 -333.202563)
			(xy 27.626564 -333.206852) (xy 27.629612 -333.215234) (xy 27.635708 -333.222346) (xy 27.653102 -333.243222)
			(xy 27.682422 -333.288972) (xy 27.70495 -333.33842) (xy 27.720231 -333.390565) (xy 27.727956 -333.444351)
			(xy 27.728418 -333.47152) (xy 27.727982 -333.497169) (xy 27.721075 -333.547999) (xy 27.707427 -333.597449)
			(xy 27.687285 -333.644627) (xy 27.66101 -333.688685) (xy 27.64536 -333.70901) (xy 27.640026 -333.715868)
			(xy 27.637232 -333.723742) (xy 27.635931 -333.727811) (xy 27.634522 -333.736235) (xy 27.634438 -333.740506)
			(xy 27.634438 -333.773272) (xy 27.623262 -333.773272) (xy 27.623262 -333.824072) (xy 27.623386 -333.82862)
			(xy 27.625049 -333.837563) (xy 27.626564 -333.841852) (xy 27.629612 -333.850234) (xy 27.635708 -333.857346)
			(xy 27.653102 -333.878222) (xy 27.682422 -333.923972) (xy 27.70495 -333.97342) (xy 27.720231 -334.025565)
			(xy 27.727956 -334.079351) (xy 27.728418 -334.10652) (xy 27.727982 -334.132169) (xy 27.721075 -334.182999)
			(xy 27.707427 -334.232449) (xy 27.687285 -334.279627) (xy 27.66101 -334.323685) (xy 27.64536 -334.34401)
			(xy 27.640026 -334.350868) (xy 27.637232 -334.358742) (xy 27.635931 -334.362811) (xy 27.634522 -334.371235)
			(xy 27.634438 -334.375506) (xy 27.634438 -334.408272) (xy 27.623262 -334.408272) (xy 27.623262 -334.459072)
			(xy 27.623386 -334.46362) (xy 27.625049 -334.472563) (xy 27.626564 -334.476852) (xy 27.629612 -334.485234)
			(xy 27.635708 -334.492346) (xy 27.653102 -334.513222) (xy 27.682422 -334.558972) (xy 27.70495 -334.60842)
			(xy 27.720231 -334.660565) (xy 27.727956 -334.714351) (xy 27.728418 -334.74152) (xy 29.708602 -334.74152)
			(xy 29.709079 -334.71415) (xy 29.716894 -334.659972) (xy 29.732381 -334.607469) (xy 29.75522 -334.557721)
			(xy 29.784942 -334.511754) (xy 29.802582 -334.490822) (xy 29.802836 -334.490568) (xy 29.808404 -334.483469)
			(xy 29.814661 -334.466562) (xy 29.815028 -334.457548) (xy 29.815028 -334.390492) (xy 29.814669 -334.381476)
			(xy 29.808422 -334.364559) (xy 29.802836 -334.357472) (xy 29.802582 -334.357472) (xy 29.802582 -334.357218)
			(xy 29.784963 -334.336269) (xy 29.755241 -334.290303) (xy 29.732397 -334.240559) (xy 29.716901 -334.18806)
			(xy 29.709071 -334.133884) (xy 29.709069 -334.079146) (xy 29.716894 -334.02497) (xy 29.732386 -333.972469)
			(xy 29.755226 -333.922724) (xy 29.784945 -333.876756) (xy 29.802582 -333.855822) (xy 29.802836 -333.855568)
			(xy 29.808404 -333.848469) (xy 29.814661 -333.831562) (xy 29.815028 -333.822548) (xy 29.815028 -333.755492)
			(xy 29.814669 -333.746476) (xy 29.808422 -333.729559) (xy 29.802836 -333.722472) (xy 29.802582 -333.722472)
			(xy 29.802582 -333.722218) (xy 29.784963 -333.701269) (xy 29.755241 -333.655303) (xy 29.732397 -333.605559)
			(xy 29.716901 -333.55306) (xy 29.709071 -333.498884) (xy 29.709069 -333.444146) (xy 29.716894 -333.38997)
			(xy 29.732386 -333.337469) (xy 29.755226 -333.287724) (xy 29.784945 -333.241756) (xy 29.802582 -333.220822)
			(xy 29.802836 -333.220568) (xy 29.808404 -333.213469) (xy 29.814661 -333.196562) (xy 29.815028 -333.187548)
			(xy 29.815028 -333.120492) (xy 29.814669 -333.111476) (xy 29.808422 -333.094559) (xy 29.802836 -333.087472)
			(xy 29.802582 -333.087472) (xy 29.802582 -333.087218) (xy 29.784963 -333.066269) (xy 29.755241 -333.020303)
			(xy 29.732397 -332.970559) (xy 29.716901 -332.91806) (xy 29.709071 -332.863884) (xy 29.709069 -332.809146)
			(xy 29.716894 -332.75497) (xy 29.732386 -332.702469) (xy 29.755226 -332.652724) (xy 29.784945 -332.606756)
			(xy 29.802582 -332.585822) (xy 29.802836 -332.585568) (xy 29.808404 -332.578469) (xy 29.814661 -332.561562)
			(xy 29.815028 -332.552548) (xy 29.815028 -332.485492) (xy 29.814669 -332.476476) (xy 29.808422 -332.459559)
			(xy 29.802836 -332.452472) (xy 29.802582 -332.452472) (xy 29.802582 -332.452218) (xy 29.784963 -332.431269)
			(xy 29.755241 -332.385303) (xy 29.732397 -332.335559) (xy 29.716901 -332.28306) (xy 29.709071 -332.228884)
			(xy 29.709069 -332.174146) (xy 29.716894 -332.11997) (xy 29.732386 -332.067469) (xy 29.755226 -332.017724)
			(xy 29.784945 -331.971756) (xy 29.802582 -331.950822) (xy 29.802836 -331.950568) (xy 29.808404 -331.943469)
			(xy 29.814661 -331.926562) (xy 29.815028 -331.917548) (xy 29.815028 -331.850492) (xy 29.814669 -331.841476)
			(xy 29.808422 -331.824559) (xy 29.802836 -331.817472) (xy 29.802582 -331.817472) (xy 29.802582 -331.817218)
			(xy 29.784963 -331.796269) (xy 29.755241 -331.750303) (xy 29.732397 -331.700559) (xy 29.716901 -331.64806)
			(xy 29.709071 -331.593884) (xy 29.709069 -331.539146) (xy 29.716894 -331.48497) (xy 29.732386 -331.432469)
			(xy 29.755226 -331.382724) (xy 29.784945 -331.336756) (xy 29.802582 -331.315822) (xy 29.802836 -331.315568)
			(xy 29.808404 -331.308469) (xy 29.814661 -331.291562) (xy 29.815028 -331.282548) (xy 29.815028 -331.215492)
			(xy 29.814669 -331.206476) (xy 29.808422 -331.189559) (xy 29.802836 -331.182472) (xy 29.802582 -331.182472)
			(xy 29.802582 -331.182218) (xy 29.784963 -331.161269) (xy 29.755241 -331.115303) (xy 29.732397 -331.065559)
			(xy 29.716901 -331.01306) (xy 29.709071 -330.958884) (xy 29.709069 -330.904146) (xy 29.716894 -330.84997)
			(xy 29.732386 -330.797469) (xy 29.755226 -330.747724) (xy 29.784945 -330.701756) (xy 29.802582 -330.680822)
			(xy 29.802836 -330.680568) (xy 29.808404 -330.673469) (xy 29.814661 -330.656562) (xy 29.815028 -330.647548)
			(xy 29.815028 -330.580492) (xy 29.814669 -330.571476) (xy 29.808422 -330.554559) (xy 29.802836 -330.547472)
			(xy 29.802582 -330.547472) (xy 29.802582 -330.547218) (xy 29.784935 -330.526292) (xy 29.755225 -330.480317)
			(xy 29.732391 -330.430568) (xy 29.716902 -330.378066) (xy 29.709075 -330.32389) (xy 29.708602 -330.29652)
			(xy 29.709074 -330.269267) (xy 29.716828 -330.215316) (xy 29.732182 -330.163018) (xy 29.754823 -330.113437)
			(xy 29.78429 -330.067583) (xy 29.819983 -330.02639) (xy 29.861175 -329.990696) (xy 29.907028 -329.961228)
			(xy 29.956608 -329.938586) (xy 30.008906 -329.923231) (xy 30.062857 -329.915475) (xy 30.09011 -329.915012)
			(xy 30.117481 -329.915469) (xy 30.17166 -329.923289) (xy 30.224163 -329.93878) (xy 30.27391 -329.961623)
			(xy 30.319877 -329.99135) (xy 30.340808 -330.008992) (xy 30.341062 -330.009246) (xy 30.348151 -330.014828)
			(xy 30.365066 -330.021076) (xy 30.374082 -330.021438) (xy 30.441138 -330.021438) (xy 30.450156 -330.021091)
			(xy 30.467072 -330.014836) (xy 30.474158 -330.009246) (xy 30.474158 -330.008992) (xy 30.474412 -330.008992)
			(xy 30.495345 -329.991351) (xy 30.541313 -329.961627) (xy 30.591059 -329.938781) (xy 30.643561 -329.923285)
			(xy 30.697739 -329.915456) (xy 30.752481 -329.915456) (xy 30.806659 -329.923285) (xy 30.859161 -329.938781)
			(xy 30.908907 -329.961627) (xy 30.954875 -329.991351) (xy 30.975808 -330.008992) (xy 30.976062 -330.009246)
			(xy 30.983151 -330.014828) (xy 31.000066 -330.021076) (xy 31.009082 -330.021438) (xy 31.076138 -330.021438)
			(xy 31.085156 -330.021091) (xy 31.102072 -330.014836) (xy 31.109158 -330.009246) (xy 31.109158 -330.008992)
			(xy 31.109412 -330.008992) (xy 31.130365 -329.991379) (xy 31.176332 -329.961664) (xy 31.226075 -329.938823)
			(xy 31.27857 -329.923326) (xy 31.332742 -329.91549) (xy 31.36011 -329.915012) (xy 31.387364 -329.915446)
			(xy 31.441317 -329.923204) (xy 31.493617 -329.938563) (xy 31.543198 -329.961208) (xy 31.589052 -329.990679)
			(xy 31.630246 -330.026376) (xy 31.665939 -330.067572) (xy 31.695406 -330.113428) (xy 31.718048 -330.163011)
			(xy 31.733402 -330.215312) (xy 31.741157 -330.269266) (xy 31.741618 -330.29652) (xy 31.741184 -330.323892)
			(xy 31.733361 -330.378073) (xy 31.717866 -330.430577) (xy 31.695017 -330.480324) (xy 31.665284 -330.526288)
			(xy 31.647638 -330.547218) (xy 31.647384 -330.547472) (xy 31.641801 -330.554561) (xy 31.635553 -330.571476)
			(xy 31.635192 -330.580492) (xy 31.635192 -330.647548) (xy 31.635576 -330.656562) (xy 31.641805 -330.673479)
			(xy 31.647384 -330.680568) (xy 31.647638 -330.680568) (xy 31.647638 -330.680822) (xy 31.6653 -330.701738)
			(xy 31.695026 -330.747708) (xy 31.717873 -330.797457) (xy 31.733369 -330.849962) (xy 31.741196 -330.904143)
			(xy 31.741194 -330.958887) (xy 31.733363 -331.013068) (xy 31.717862 -331.065571) (xy 31.695012 -331.115318)
			(xy 31.665282 -331.161286) (xy 31.647638 -331.182218) (xy 31.647384 -331.182472) (xy 31.641801 -331.189561)
			(xy 31.635553 -331.206476) (xy 31.635192 -331.215492) (xy 31.635192 -331.282548) (xy 31.635576 -331.291562)
			(xy 31.641805 -331.308479) (xy 31.647384 -331.315568) (xy 31.647638 -331.315568) (xy 31.647638 -331.315822)
			(xy 31.6653 -331.336738) (xy 31.695026 -331.382708) (xy 31.717873 -331.432457) (xy 31.733369 -331.484962)
			(xy 31.741196 -331.539143) (xy 31.741194 -331.593887) (xy 31.733363 -331.648068) (xy 31.717862 -331.700571)
			(xy 31.695012 -331.750318) (xy 31.665282 -331.796286) (xy 31.647638 -331.817218) (xy 31.647384 -331.817472)
			(xy 31.641801 -331.824561) (xy 31.635553 -331.841476) (xy 31.635192 -331.850492) (xy 31.635192 -331.917548)
			(xy 31.635576 -331.926562) (xy 31.641805 -331.943479) (xy 31.647384 -331.950568) (xy 31.647638 -331.950568)
			(xy 31.647638 -331.950822) (xy 31.6653 -331.971738) (xy 31.695026 -332.017708) (xy 31.717873 -332.067457)
			(xy 31.733369 -332.119962) (xy 31.741196 -332.174143) (xy 31.741194 -332.228887) (xy 31.733363 -332.283068)
			(xy 31.717862 -332.335571) (xy 31.695012 -332.385318) (xy 31.665282 -332.431286) (xy 31.647638 -332.452218)
			(xy 31.647384 -332.452472) (xy 31.641801 -332.459561) (xy 31.635553 -332.476476) (xy 31.635192 -332.485492)
			(xy 31.635192 -332.552548) (xy 31.635576 -332.561562) (xy 31.641805 -332.578479) (xy 31.647384 -332.585568)
			(xy 31.647638 -332.585568) (xy 31.647638 -332.585822) (xy 31.6653 -332.606738) (xy 31.695026 -332.652708)
			(xy 31.717873 -332.702457) (xy 31.733369 -332.754962) (xy 31.741196 -332.809143) (xy 31.741194 -332.863887)
			(xy 31.733363 -332.918068) (xy 31.717862 -332.970571) (xy 31.695012 -333.020318) (xy 31.665282 -333.066286)
			(xy 31.647638 -333.087218) (xy 31.647384 -333.087472) (xy 31.641801 -333.094561) (xy 31.635553 -333.111476)
			(xy 31.635192 -333.120492) (xy 31.635192 -333.187548) (xy 31.635576 -333.196562) (xy 31.641805 -333.213479)
			(xy 31.647384 -333.220568) (xy 31.647638 -333.220568) (xy 31.647638 -333.220822) (xy 31.6653 -333.241738)
			(xy 31.695026 -333.287708) (xy 31.717873 -333.337457) (xy 31.733369 -333.389962) (xy 31.741196 -333.444143)
			(xy 31.741194 -333.498887) (xy 31.733363 -333.553068) (xy 31.717862 -333.605571) (xy 31.695012 -333.655318)
			(xy 31.665282 -333.701286) (xy 31.647638 -333.722218) (xy 31.647384 -333.722472) (xy 31.641801 -333.729561)
			(xy 31.635553 -333.746476) (xy 31.635192 -333.755492) (xy 31.635192 -333.822548) (xy 31.635576 -333.831562)
			(xy 31.641805 -333.848479) (xy 31.647384 -333.855568) (xy 31.647638 -333.855568) (xy 31.647638 -333.855822)
			(xy 31.6653 -333.876738) (xy 31.695026 -333.922708) (xy 31.717873 -333.972457) (xy 31.733369 -334.024962)
			(xy 31.741196 -334.079143) (xy 31.741194 -334.133887) (xy 31.733363 -334.188068) (xy 31.717862 -334.240571)
			(xy 31.695012 -334.290318) (xy 31.665282 -334.336286) (xy 31.647638 -334.357218) (xy 31.647384 -334.357472)
			(xy 31.641801 -334.364561) (xy 31.635553 -334.381476) (xy 31.635192 -334.390492) (xy 31.635192 -334.457548)
			(xy 31.635576 -334.466562) (xy 31.641805 -334.483479) (xy 31.647384 -334.490568) (xy 31.647638 -334.490568)
			(xy 31.647638 -334.490822) (xy 31.66526 -334.511767) (xy 31.694973 -334.557737) (xy 31.717812 -334.607481)
			(xy 31.733307 -334.659979) (xy 31.741141 -334.714152) (xy 31.741618 -334.74152) (xy 31.741141 -334.768771)
			(xy 31.733382 -334.822719) (xy 31.718025 -334.875013) (xy 31.695382 -334.92459) (xy 31.665915 -334.97044)
			(xy 31.630222 -335.011629) (xy 31.589032 -335.047321) (xy 31.543181 -335.076787) (xy 31.493604 -335.099428)
			(xy 31.441309 -335.114784) (xy 31.387361 -335.122542) (xy 31.36011 -335.123028) (xy 31.332739 -335.122574)
			(xy 31.278559 -335.114756) (xy 31.226055 -335.099265) (xy 31.176308 -335.07642) (xy 31.130343 -335.046691)
			(xy 31.109412 -335.029048) (xy 31.109158 -335.028794) (xy 31.102059 -335.023225) (xy 31.085152 -335.016968)
			(xy 31.076138 -335.016602) (xy 31.009082 -335.016602) (xy 31.000064 -335.01695) (xy 30.983147 -335.023204)
			(xy 30.976062 -335.028794) (xy 30.975808 -335.029048) (xy 30.954875 -335.046689) (xy 30.908907 -335.076413)
			(xy 30.859161 -335.099259) (xy 30.806659 -335.114755) (xy 30.752481 -335.122584) (xy 30.697739 -335.122584)
			(xy 30.643561 -335.114755) (xy 30.591059 -335.099259) (xy 30.541313 -335.076413) (xy 30.495345 -335.046689)
			(xy 30.474412 -335.029048) (xy 30.474158 -335.028794) (xy 30.467059 -335.023225) (xy 30.450152 -335.016968)
			(xy 30.441138 -335.016602) (xy 30.374082 -335.016602) (xy 30.365064 -335.01695) (xy 30.348147 -335.023204)
			(xy 30.341062 -335.028794) (xy 30.341062 -335.029048) (xy 30.340808 -335.029048) (xy 30.319877 -335.046689)
			(xy 30.273905 -335.076402) (xy 30.224157 -335.099239) (xy 30.171656 -335.114729) (xy 30.117479 -335.122555)
			(xy 30.09011 -335.123028) (xy 30.06286 -335.122512) (xy 30.008914 -335.114758) (xy 29.956621 -335.099405)
			(xy 29.907046 -335.076767) (xy 29.861196 -335.047303) (xy 29.820006 -335.011615) (xy 29.784315 -334.970428)
			(xy 29.754848 -334.924581) (xy 29.732205 -334.875007) (xy 29.716849 -334.822715) (xy 29.70909 -334.76877)
			(xy 29.708602 -334.74152) (xy 27.728418 -334.74152) (xy 27.727931 -334.768771) (xy 27.720172 -334.822717)
			(xy 27.704815 -334.87501) (xy 27.682173 -334.924585) (xy 27.652707 -334.970434) (xy 27.617015 -335.011622)
			(xy 27.575826 -335.047313) (xy 27.529976 -335.076778) (xy 27.4804 -335.099419) (xy 27.428107 -335.114774)
			(xy 27.374161 -335.122532) (xy 27.34691 -335.123028) (xy 27.321263 -335.122587) (xy 27.270436 -335.115672)
			(xy 27.220992 -335.102017) (xy 27.17382 -335.081869) (xy 27.129768 -335.05559) (xy 27.10942 -335.03997)
			(xy 27.102562 -335.034636) (xy 27.094688 -335.031842) (xy 27.090619 -335.030546) (xy 27.082194 -335.029148)
			(xy 27.077924 -335.029048) (xy 27.045158 -335.029048) (xy 27.045158 -335.017872) (xy 26.994358 -335.017872)
			(xy 26.98981 -335.017994) (xy 26.980865 -335.019651) (xy 26.976578 -335.021174) (xy 26.968196 -335.024222)
			(xy 26.961084 -335.030318) (xy 26.940206 -335.047708) (xy 26.894455 -335.077018) (xy 26.845006 -335.099537)
			(xy 26.792862 -335.114808) (xy 26.739077 -335.122523) (xy 26.71191 -335.123028) (xy 26.711402 -335.123028)
			(xy 26.682697 -335.12253) (xy 26.625932 -335.113958) (xy 26.571097 -335.096963) (xy 26.545032 -335.084928)
			(xy 26.542746 -335.083658) (xy 26.54046 -335.082642) (xy 26.530046 -335.079848) (xy 26.519893 -335.077576)
			(xy 26.499308 -335.080465) (xy 26.490168 -335.085436) (xy 26.417778 -335.13014) (xy 26.407582 -335.13709)
			(xy 26.394949 -335.158255) (xy 26.393648 -335.170526) (xy 26.393648 -348.301818) (xy 26.393165 -348.32677)
			(xy 26.385371 -348.376062) (xy 26.369963 -348.423528) (xy 26.347319 -348.467999) (xy 26.317998 -348.508381)
			(xy 26.300684 -348.526354) (xy 26.117538 -348.7095) (xy 28.918321 -348.7095) (xy 28.92249 -348.653877)
			(xy 28.934903 -348.599498) (xy 28.955282 -348.547575) (xy 28.983173 -348.49927) (xy 29.017952 -348.455662)
			(xy 29.058842 -348.417725) (xy 29.10493 -348.386307) (xy 29.155187 -348.362108) (xy 29.208488 -348.345671)
			(xy 29.263645 -348.337363) (xy 29.291534 -348.33687) (xy 29.317956 -348.337315) (xy 29.370272 -348.344769)
			(xy 29.42101 -348.359538) (xy 29.469154 -348.381324) (xy 29.513739 -348.409692) (xy 29.534104 -348.426532)
			(xy 29.540962 -348.432374) (xy 29.55798 -348.438724) (xy 29.642308 -348.438724) (xy 29.659326 -348.432374)
			(xy 29.666184 -348.426532) (xy 29.68655 -348.409693) (xy 29.731136 -348.381328) (xy 29.77928 -348.359541)
			(xy 29.830017 -348.34477) (xy 29.882332 -348.33731) (xy 29.935176 -348.33731) (xy 29.987491 -348.34477)
			(xy 30.038228 -348.359541) (xy 30.086372 -348.381328) (xy 30.130958 -348.409693) (xy 30.151324 -348.426532)
			(xy 30.158182 -348.432374) (xy 30.1752 -348.438724) (xy 30.259528 -348.438724) (xy 30.276546 -348.432374)
			(xy 30.283404 -348.426532) (xy 30.304989 -348.408734) (xy 30.35245 -348.379119) (xy 30.403805 -348.356931)
			(xy 30.430724 -348.349316) (xy 30.44317 -348.346014) (xy 30.461204 -348.32925) (xy 30.49778 -348.22638)
			(xy 30.494224 -348.201488) (xy 30.486858 -348.191328) (xy 30.469611 -348.166737) (xy 30.442275 -348.113255)
			(xy 30.423672 -348.056145) (xy 30.414262 -347.996824) (xy 30.413706 -347.966792) (xy 30.413706 -347.966538)
			(xy 30.414196 -347.938964) (xy 30.422143 -347.884392) (xy 30.437863 -347.831533) (xy 30.461029 -347.781487)
			(xy 30.491157 -347.735297) (xy 30.527621 -347.693924) (xy 30.548326 -347.675708) (xy 30.556402 -347.668154)
			(xy 30.565755 -347.648142) (xy 30.56636 -347.6371) (xy 30.56636 -347.559376) (xy 30.565762 -347.54833)
			(xy 30.556419 -347.528308) (xy 30.548326 -347.520768) (xy 30.527601 -347.502571) (xy 30.491131 -347.4612)
			(xy 30.461 -347.415008) (xy 30.437836 -347.364957) (xy 30.422123 -347.312091) (xy 30.414188 -347.257514)
			(xy 30.413706 -347.229938) (xy 30.414192 -347.202687) (xy 30.421948 -347.148739) (xy 30.437303 -347.096444)
			(xy 30.459945 -347.046867) (xy 30.489411 -347.001017) (xy 30.525102 -346.959826) (xy 30.566293 -346.924135)
			(xy 30.612143 -346.894669) (xy 30.66172 -346.872027) (xy 30.714015 -346.856672) (xy 30.767963 -346.848916)
			(xy 30.822465 -346.848916) (xy 30.876413 -346.856672) (xy 30.928708 -346.872027) (xy 30.978285 -346.894669)
			(xy 31.024135 -346.924135) (xy 31.065326 -346.959826) (xy 31.101017 -347.001017) (xy 31.130483 -347.046867)
			(xy 31.153125 -347.096444) (xy 31.16848 -347.148739) (xy 31.176236 -347.202687) (xy 31.176722 -347.229938)
			(xy 31.176206 -347.257511) (xy 31.168263 -347.312081) (xy 31.152547 -347.36494) (xy 31.129386 -347.414986)
			(xy 31.099263 -347.461176) (xy 31.062805 -347.50255) (xy 31.042102 -347.520768) (xy 31.034041 -347.528336)
			(xy 31.024679 -347.548338) (xy 31.024068 -347.559376) (xy 31.024068 -347.6371) (xy 31.02467 -347.648146)
			(xy 31.034009 -347.668168) (xy 31.042102 -347.675708) (xy 31.062821 -347.693911) (xy 31.09929 -347.735282)
			(xy 31.129421 -347.781473) (xy 31.152586 -347.831523) (xy 31.168301 -347.884387) (xy 31.176238 -347.938963)
			(xy 31.176722 -347.966538) (xy 31.176251 -347.994643) (xy 31.167999 -348.050245) (xy 31.151678 -348.104034)
			(xy 31.127642 -348.154846) (xy 31.096411 -348.201583) (xy 31.058662 -348.243231) (xy 31.01521 -348.27889)
			(xy 30.966997 -348.307789) (xy 30.915065 -348.329301) (xy 30.887924 -348.336616) (xy 30.876191 -348.340398)
			(xy 30.857883 -348.356849) (xy 30.852872 -348.368112) (xy 30.84993 -348.375986) (xy 32.816546 -348.375986)
			(xy 32.817041 -348.348075) (xy 32.825177 -348.29285) (xy 32.841272 -348.2394) (xy 32.864984 -348.188865)
			(xy 32.895806 -348.142325) (xy 32.914082 -348.121224) (xy 32.919966 -348.114037) (xy 32.926625 -348.096719)
			(xy 32.927036 -348.087442) (xy 32.927036 -348.009718) (xy 32.920432 -347.992446) (xy 32.914082 -347.985334)
			(xy 32.895796 -347.964241) (xy 32.86497 -347.917701) (xy 32.841257 -347.867164) (xy 32.825162 -347.813712)
			(xy 32.81703 -347.758484) (xy 32.816546 -347.730572) (xy 32.817032 -347.703321) (xy 32.824788 -347.649373)
			(xy 32.840143 -347.597078) (xy 32.862785 -347.547501) (xy 32.892251 -347.501651) (xy 32.927942 -347.46046)
			(xy 32.969133 -347.424769) (xy 33.014983 -347.395303) (xy 33.06456 -347.372661) (xy 33.116855 -347.357306)
			(xy 33.170803 -347.34955) (xy 33.225305 -347.34955) (xy 33.279253 -347.357306) (xy 33.331548 -347.372661)
			(xy 33.381125 -347.395303) (xy 33.426975 -347.424769) (xy 33.468166 -347.46046) (xy 33.503857 -347.501651)
			(xy 33.533323 -347.547501) (xy 33.555965 -347.597078) (xy 33.57132 -347.649373) (xy 33.579076 -347.703321)
			(xy 33.579562 -347.730572) (xy 33.579099 -347.758484) (xy 33.570955 -347.81371) (xy 33.554852 -347.867161)
			(xy 33.531133 -347.917695) (xy 33.500305 -347.964234) (xy 33.482026 -347.985334) (xy 33.476118 -347.992504)
			(xy 33.469473 -348.009834) (xy 33.469072 -348.019116) (xy 33.469072 -348.09684) (xy 33.475676 -348.114112)
			(xy 33.482026 -348.121224) (xy 33.499383 -348.141268) (xy 33.528987 -348.185254) (xy 33.552215 -348.232916)
			(xy 33.568618 -348.283335) (xy 33.577881 -348.33554) (xy 33.579308 -348.362016) (xy 33.580138 -348.371856)
			(xy 33.588267 -348.389834) (xy 33.602556 -348.40344) (xy 33.611566 -348.407482) (xy 33.69818 -348.441518)
			(xy 33.70753 -348.444762) (xy 33.727303 -348.444519) (xy 33.745504 -348.436788) (xy 33.75279 -348.430088)
			(xy 34.023554 -348.159578) (xy 34.03039 -348.152174) (xy 34.038113 -348.133578) (xy 34.03854 -348.12351)
			(xy 34.03854 -334.965548) (xy 34.038365 -334.958588) (xy 34.034614 -334.945185) (xy 34.031174 -334.939132)
			(xy 34.018081 -334.916684) (xy 33.997381 -334.869019) (xy 33.983353 -334.818982) (xy 33.976258 -334.767503)
			(xy 33.975802 -334.74152) (xy 33.976279 -334.71415) (xy 33.984094 -334.659972) (xy 33.999581 -334.607469)
			(xy 34.02242 -334.557721) (xy 34.052142 -334.511754) (xy 34.069782 -334.490822) (xy 34.070036 -334.490568)
			(xy 34.075604 -334.483469) (xy 34.081861 -334.466562) (xy 34.082228 -334.457548) (xy 34.082228 -334.390492)
			(xy 34.081869 -334.381476) (xy 34.075622 -334.364559) (xy 34.070036 -334.357472) (xy 34.069782 -334.357472)
			(xy 34.069782 -334.357218) (xy 34.052163 -334.336269) (xy 34.022441 -334.290303) (xy 33.999597 -334.240559)
			(xy 33.984101 -334.18806) (xy 33.976271 -334.133884) (xy 33.976269 -334.079146) (xy 33.984094 -334.02497)
			(xy 33.999586 -333.972469) (xy 34.022426 -333.922724) (xy 34.052145 -333.876756) (xy 34.069782 -333.855822)
			(xy 34.070036 -333.855568) (xy 34.075604 -333.848469) (xy 34.081861 -333.831562) (xy 34.082228 -333.822548)
			(xy 34.082228 -333.755492) (xy 34.081869 -333.746476) (xy 34.075622 -333.729559) (xy 34.070036 -333.722472)
			(xy 34.069782 -333.722472) (xy 34.069782 -333.722218) (xy 34.052163 -333.701269) (xy 34.022441 -333.655303)
			(xy 33.999597 -333.605559) (xy 33.984101 -333.55306) (xy 33.976271 -333.498884) (xy 33.976269 -333.444146)
			(xy 33.984094 -333.38997) (xy 33.999586 -333.337469) (xy 34.022426 -333.287724) (xy 34.052145 -333.241756)
			(xy 34.069782 -333.220822) (xy 34.070036 -333.220568) (xy 34.075604 -333.213469) (xy 34.081861 -333.196562)
			(xy 34.082228 -333.187548) (xy 34.082228 -333.120492) (xy 34.081869 -333.111476) (xy 34.075622 -333.094559)
			(xy 34.070036 -333.087472) (xy 34.069782 -333.087472) (xy 34.069782 -333.087218) (xy 34.052163 -333.066269)
			(xy 34.022441 -333.020303) (xy 33.999597 -332.970559) (xy 33.984101 -332.91806) (xy 33.976271 -332.863884)
			(xy 33.976269 -332.809146) (xy 33.984094 -332.75497) (xy 33.999586 -332.702469) (xy 34.022426 -332.652724)
			(xy 34.052145 -332.606756) (xy 34.069782 -332.585822) (xy 34.070036 -332.585568) (xy 34.075604 -332.578469)
			(xy 34.081861 -332.561562) (xy 34.082228 -332.552548) (xy 34.082228 -332.485492) (xy 34.081869 -332.476476)
			(xy 34.075622 -332.459559) (xy 34.070036 -332.452472) (xy 34.069782 -332.452472) (xy 34.069782 -332.452218)
			(xy 34.052163 -332.431269) (xy 34.022441 -332.385303) (xy 33.999597 -332.335559) (xy 33.984101 -332.28306)
			(xy 33.976271 -332.228884) (xy 33.976269 -332.174146) (xy 33.984094 -332.11997) (xy 33.999586 -332.067469)
			(xy 34.022426 -332.017724) (xy 34.052145 -331.971756) (xy 34.069782 -331.950822) (xy 34.070036 -331.950568)
			(xy 34.075604 -331.943469) (xy 34.081861 -331.926562) (xy 34.082228 -331.917548) (xy 34.082228 -331.850492)
			(xy 34.081869 -331.841476) (xy 34.075622 -331.824559) (xy 34.070036 -331.817472) (xy 34.069782 -331.817472)
			(xy 34.069782 -331.817218) (xy 34.052163 -331.796269) (xy 34.022441 -331.750303) (xy 33.999597 -331.700559)
			(xy 33.984101 -331.64806) (xy 33.976271 -331.593884) (xy 33.976269 -331.539146) (xy 33.984094 -331.48497)
			(xy 33.999586 -331.432469) (xy 34.022426 -331.382724) (xy 34.052145 -331.336756) (xy 34.069782 -331.315822)
			(xy 34.070036 -331.315568) (xy 34.075604 -331.308469) (xy 34.081861 -331.291562) (xy 34.082228 -331.282548)
			(xy 34.082228 -331.215492) (xy 34.081869 -331.206476) (xy 34.075622 -331.189559) (xy 34.070036 -331.182472)
			(xy 34.069782 -331.182472) (xy 34.069782 -331.182218) (xy 34.052163 -331.161269) (xy 34.022441 -331.115303)
			(xy 33.999597 -331.065559) (xy 33.984101 -331.01306) (xy 33.976271 -330.958884) (xy 33.976269 -330.904146)
			(xy 33.984094 -330.84997) (xy 33.999586 -330.797469) (xy 34.022426 -330.747724) (xy 34.052145 -330.701756)
			(xy 34.069782 -330.680822) (xy 34.070036 -330.680568) (xy 34.075604 -330.673469) (xy 34.081861 -330.656562)
			(xy 34.082228 -330.647548) (xy 34.082228 -330.580492) (xy 34.081869 -330.571476) (xy 34.075622 -330.554559)
			(xy 34.070036 -330.547472) (xy 34.069782 -330.547472) (xy 34.069782 -330.547218) (xy 34.052135 -330.526292)
			(xy 34.022425 -330.480317) (xy 33.999591 -330.430568) (xy 33.984102 -330.378066) (xy 33.976275 -330.32389)
			(xy 33.975802 -330.29652) (xy 33.976274 -330.269267) (xy 33.984028 -330.215316) (xy 33.999382 -330.163018)
			(xy 34.022023 -330.113437) (xy 34.05149 -330.067583) (xy 34.087183 -330.02639) (xy 34.128375 -329.990696)
			(xy 34.174228 -329.961228) (xy 34.223808 -329.938586) (xy 34.276106 -329.923231) (xy 34.330057 -329.915475)
			(xy 34.35731 -329.915012) (xy 34.384681 -329.915469) (xy 34.43886 -329.923289) (xy 34.491363 -329.93878)
			(xy 34.54111 -329.961623) (xy 34.587077 -329.99135) (xy 34.608008 -330.008992) (xy 34.608262 -330.009246)
			(xy 34.615351 -330.014828) (xy 34.632266 -330.021076) (xy 34.641282 -330.021438) (xy 34.708338 -330.021438)
			(xy 34.717356 -330.021091) (xy 34.734272 -330.014836) (xy 34.741358 -330.009246) (xy 34.741358 -330.008992)
			(xy 34.741612 -330.008992) (xy 34.762545 -329.991351) (xy 34.808513 -329.961627) (xy 34.858259 -329.938781)
			(xy 34.910761 -329.923285) (xy 34.964939 -329.915456) (xy 35.019681 -329.915456) (xy 35.073859 -329.923285)
			(xy 35.126361 -329.938781) (xy 35.176107 -329.961627) (xy 35.222075 -329.991351) (xy 35.243008 -330.008992)
			(xy 35.243262 -330.009246) (xy 35.250351 -330.014828) (xy 35.267266 -330.021076) (xy 35.276282 -330.021438)
			(xy 35.343338 -330.021438) (xy 35.352356 -330.021091) (xy 35.369272 -330.014836) (xy 35.376358 -330.009246)
			(xy 35.376358 -330.008992) (xy 35.376612 -330.008992) (xy 35.397565 -329.991379) (xy 35.443532 -329.961664)
			(xy 35.493275 -329.938823) (xy 35.54577 -329.923326) (xy 35.599942 -329.91549) (xy 35.62731 -329.915012)
			(xy 35.654564 -329.915446) (xy 35.708517 -329.923204) (xy 35.760817 -329.938563) (xy 35.810398 -329.961208)
			(xy 35.856252 -329.990679) (xy 35.897446 -330.026376) (xy 35.933139 -330.067572) (xy 35.962606 -330.113428)
			(xy 35.985248 -330.163011) (xy 36.000602 -330.215312) (xy 36.008357 -330.269266) (xy 36.008818 -330.29652)
			(xy 36.008384 -330.323892) (xy 36.000561 -330.378073) (xy 35.985066 -330.430577) (xy 35.962217 -330.480324)
			(xy 35.932484 -330.526288) (xy 35.914838 -330.547218) (xy 35.914584 -330.547472) (xy 35.909001 -330.554561)
			(xy 35.902753 -330.571476) (xy 35.902392 -330.580492) (xy 35.902392 -330.647548) (xy 35.902776 -330.656562)
			(xy 35.909005 -330.673479) (xy 35.914584 -330.680568) (xy 35.914838 -330.680568) (xy 35.914838 -330.680822)
			(xy 35.9325 -330.701738) (xy 35.962226 -330.747708) (xy 35.985073 -330.797457) (xy 36.000569 -330.849962)
			(xy 36.008396 -330.904143) (xy 36.008394 -330.958887) (xy 36.000563 -331.013068) (xy 35.985062 -331.065571)
			(xy 35.962212 -331.115318) (xy 35.932482 -331.161286) (xy 35.914838 -331.182218) (xy 35.914584 -331.182472)
			(xy 35.909001 -331.189561) (xy 35.902753 -331.206476) (xy 35.902392 -331.215492) (xy 35.902392 -331.282548)
			(xy 35.902776 -331.291562) (xy 35.909005 -331.308479) (xy 35.914584 -331.315568) (xy 35.914838 -331.315568)
			(xy 35.914838 -331.315822) (xy 35.9325 -331.336738) (xy 35.962226 -331.382708) (xy 35.985073 -331.432457)
			(xy 36.000569 -331.484962) (xy 36.008396 -331.539143) (xy 36.008394 -331.593887) (xy 36.000563 -331.648068)
			(xy 35.985062 -331.700571) (xy 35.962212 -331.750318) (xy 35.932482 -331.796286) (xy 35.914838 -331.817218)
			(xy 35.914584 -331.817472) (xy 35.909001 -331.824561) (xy 35.902753 -331.841476) (xy 35.902392 -331.850492)
			(xy 35.902392 -331.917548) (xy 35.902776 -331.926562) (xy 35.909005 -331.943479) (xy 35.914584 -331.950568)
			(xy 35.914838 -331.950568) (xy 35.914838 -331.950822) (xy 35.9325 -331.971738) (xy 35.962226 -332.017708)
			(xy 35.985073 -332.067457) (xy 36.000569 -332.119962) (xy 36.008396 -332.174143) (xy 36.008394 -332.228887)
			(xy 36.000563 -332.283068) (xy 35.985062 -332.335571) (xy 35.962212 -332.385318) (xy 35.932482 -332.431286)
			(xy 35.914838 -332.452218) (xy 35.914584 -332.452472) (xy 35.909001 -332.459561) (xy 35.902753 -332.476476)
			(xy 35.902392 -332.485492) (xy 35.902392 -332.552548) (xy 35.902776 -332.561562) (xy 35.909005 -332.578479)
			(xy 35.914584 -332.585568) (xy 35.914838 -332.585568) (xy 35.914838 -332.585822) (xy 35.9325 -332.606738)
			(xy 35.962226 -332.652708) (xy 35.985073 -332.702457) (xy 36.000569 -332.754962) (xy 36.008396 -332.809143)
			(xy 36.008394 -332.863887) (xy 36.000563 -332.918068) (xy 35.985062 -332.970571) (xy 35.962212 -333.020318)
			(xy 35.932482 -333.066286) (xy 35.914838 -333.087218) (xy 35.914584 -333.087472) (xy 35.909001 -333.094561)
			(xy 35.902753 -333.111476) (xy 35.902392 -333.120492) (xy 35.902392 -333.187548) (xy 35.902776 -333.196562)
			(xy 35.909005 -333.213479) (xy 35.914584 -333.220568) (xy 35.914838 -333.220568) (xy 35.914838 -333.220822)
			(xy 35.9325 -333.241738) (xy 35.962226 -333.287708) (xy 35.985073 -333.337457) (xy 36.000569 -333.389962)
			(xy 36.008396 -333.444143) (xy 36.008394 -333.498887) (xy 36.000563 -333.553068) (xy 35.985062 -333.605571)
			(xy 35.962212 -333.655318) (xy 35.932482 -333.701286) (xy 35.914838 -333.722218) (xy 35.914584 -333.722472)
			(xy 35.909001 -333.729561) (xy 35.902753 -333.746476) (xy 35.902392 -333.755492) (xy 35.902392 -333.822548)
			(xy 35.902776 -333.831562) (xy 35.909005 -333.848479) (xy 35.914584 -333.855568) (xy 35.914838 -333.855568)
			(xy 35.914838 -333.855822) (xy 35.9325 -333.876738) (xy 35.962226 -333.922708) (xy 35.985073 -333.972457)
			(xy 36.000569 -334.024962) (xy 36.008396 -334.079143) (xy 36.008394 -334.133887) (xy 36.000563 -334.188068)
			(xy 35.985062 -334.240571) (xy 35.962212 -334.290318) (xy 35.932482 -334.336286) (xy 35.914838 -334.357218)
			(xy 35.914584 -334.357472) (xy 35.909001 -334.364561) (xy 35.902753 -334.381476) (xy 35.902392 -334.390492)
			(xy 35.902392 -334.457548) (xy 35.902776 -334.466562) (xy 35.909005 -334.483479) (xy 35.914584 -334.490568)
			(xy 35.914838 -334.490568) (xy 35.914838 -334.490822) (xy 35.93246 -334.511767) (xy 35.962173 -334.557737)
			(xy 35.985012 -334.607481) (xy 36.000507 -334.659979) (xy 36.008341 -334.714152) (xy 36.008818 -334.74152)
			(xy 37.989002 -334.74152) (xy 37.989479 -334.71415) (xy 37.997294 -334.659972) (xy 38.012781 -334.607469)
			(xy 38.03562 -334.557721) (xy 38.065342 -334.511754) (xy 38.082982 -334.490822) (xy 38.083236 -334.490568)
			(xy 38.088804 -334.483469) (xy 38.095061 -334.466562) (xy 38.095428 -334.457548) (xy 38.095428 -334.390492)
			(xy 38.095069 -334.381476) (xy 38.088822 -334.364559) (xy 38.083236 -334.357472) (xy 38.082982 -334.357472)
			(xy 38.082982 -334.357218) (xy 38.065363 -334.336269) (xy 38.035641 -334.290303) (xy 38.012797 -334.240559)
			(xy 37.997301 -334.18806) (xy 37.989471 -334.133884) (xy 37.989469 -334.079146) (xy 37.997294 -334.02497)
			(xy 38.012786 -333.972469) (xy 38.035626 -333.922724) (xy 38.065345 -333.876756) (xy 38.082982 -333.855822)
			(xy 38.083236 -333.855568) (xy 38.088804 -333.848469) (xy 38.095061 -333.831562) (xy 38.095428 -333.822548)
			(xy 38.095428 -333.755492) (xy 38.095069 -333.746476) (xy 38.088822 -333.729559) (xy 38.083236 -333.722472)
			(xy 38.082982 -333.722472) (xy 38.082982 -333.722218) (xy 38.065363 -333.701269) (xy 38.035641 -333.655303)
			(xy 38.012797 -333.605559) (xy 37.997301 -333.55306) (xy 37.989471 -333.498884) (xy 37.989469 -333.444146)
			(xy 37.997294 -333.38997) (xy 38.012786 -333.337469) (xy 38.035626 -333.287724) (xy 38.065345 -333.241756)
			(xy 38.082982 -333.220822) (xy 38.083236 -333.220568) (xy 38.088804 -333.213469) (xy 38.095061 -333.196562)
			(xy 38.095428 -333.187548) (xy 38.095428 -333.120492) (xy 38.095069 -333.111476) (xy 38.088822 -333.094559)
			(xy 38.083236 -333.087472) (xy 38.082982 -333.087472) (xy 38.082982 -333.087218) (xy 38.065363 -333.066269)
			(xy 38.035641 -333.020303) (xy 38.012797 -332.970559) (xy 37.997301 -332.91806) (xy 37.989471 -332.863884)
			(xy 37.989469 -332.809146) (xy 37.997294 -332.75497) (xy 38.012786 -332.702469) (xy 38.035626 -332.652724)
			(xy 38.065345 -332.606756) (xy 38.082982 -332.585822) (xy 38.083236 -332.585568) (xy 38.088804 -332.578469)
			(xy 38.095061 -332.561562) (xy 38.095428 -332.552548) (xy 38.095428 -332.485492) (xy 38.095069 -332.476476)
			(xy 38.088822 -332.459559) (xy 38.083236 -332.452472) (xy 38.082982 -332.452472) (xy 38.082982 -332.452218)
			(xy 38.065363 -332.431269) (xy 38.035641 -332.385303) (xy 38.012797 -332.335559) (xy 37.997301 -332.28306)
			(xy 37.989471 -332.228884) (xy 37.989469 -332.174146) (xy 37.997294 -332.11997) (xy 38.012786 -332.067469)
			(xy 38.035626 -332.017724) (xy 38.065345 -331.971756) (xy 38.082982 -331.950822) (xy 38.083236 -331.950568)
			(xy 38.088804 -331.943469) (xy 38.095061 -331.926562) (xy 38.095428 -331.917548) (xy 38.095428 -331.850492)
			(xy 38.095069 -331.841476) (xy 38.088822 -331.824559) (xy 38.083236 -331.817472) (xy 38.082982 -331.817472)
			(xy 38.082982 -331.817218) (xy 38.065363 -331.796269) (xy 38.035641 -331.750303) (xy 38.012797 -331.700559)
			(xy 37.997301 -331.64806) (xy 37.989471 -331.593884) (xy 37.989469 -331.539146) (xy 37.997294 -331.48497)
			(xy 38.012786 -331.432469) (xy 38.035626 -331.382724) (xy 38.065345 -331.336756) (xy 38.082982 -331.315822)
			(xy 38.083236 -331.315568) (xy 38.088804 -331.308469) (xy 38.095061 -331.291562) (xy 38.095428 -331.282548)
			(xy 38.095428 -331.215492) (xy 38.095069 -331.206476) (xy 38.088822 -331.189559) (xy 38.083236 -331.182472)
			(xy 38.082982 -331.182472) (xy 38.082982 -331.182218) (xy 38.065363 -331.161269) (xy 38.035641 -331.115303)
			(xy 38.012797 -331.065559) (xy 37.997301 -331.01306) (xy 37.989471 -330.958884) (xy 37.989469 -330.904146)
			(xy 37.997294 -330.84997) (xy 38.012786 -330.797469) (xy 38.035626 -330.747724) (xy 38.065345 -330.701756)
			(xy 38.082982 -330.680822) (xy 38.083236 -330.680568) (xy 38.088804 -330.673469) (xy 38.095061 -330.656562)
			(xy 38.095428 -330.647548) (xy 38.095428 -330.580492) (xy 38.095069 -330.571476) (xy 38.088822 -330.554559)
			(xy 38.083236 -330.547472) (xy 38.082982 -330.547472) (xy 38.082982 -330.547218) (xy 38.065335 -330.526292)
			(xy 38.035625 -330.480317) (xy 38.012791 -330.430568) (xy 37.997302 -330.378066) (xy 37.989475 -330.32389)
			(xy 37.989002 -330.29652) (xy 37.989474 -330.269267) (xy 37.997228 -330.215316) (xy 38.012582 -330.163018)
			(xy 38.035223 -330.113437) (xy 38.06469 -330.067583) (xy 38.100383 -330.02639) (xy 38.141575 -329.990696)
			(xy 38.187428 -329.961228) (xy 38.237008 -329.938586) (xy 38.289306 -329.923231) (xy 38.343257 -329.915475)
			(xy 38.37051 -329.915012) (xy 38.397881 -329.915469) (xy 38.45206 -329.923289) (xy 38.504563 -329.93878)
			(xy 38.55431 -329.961623) (xy 38.600277 -329.99135) (xy 38.621208 -330.008992) (xy 38.621462 -330.009246)
			(xy 38.628551 -330.014828) (xy 38.645466 -330.021076) (xy 38.654482 -330.021438) (xy 38.721538 -330.021438)
			(xy 38.730556 -330.021091) (xy 38.747472 -330.014836) (xy 38.754558 -330.009246) (xy 38.754558 -330.008992)
			(xy 38.754812 -330.008992) (xy 38.775745 -329.991351) (xy 38.821713 -329.961627) (xy 38.871459 -329.938781)
			(xy 38.923961 -329.923285) (xy 38.978139 -329.915456) (xy 39.032881 -329.915456) (xy 39.087059 -329.923285)
			(xy 39.139561 -329.938781) (xy 39.189307 -329.961627) (xy 39.235275 -329.991351) (xy 39.256208 -330.008992)
			(xy 39.256462 -330.009246) (xy 39.263551 -330.014828) (xy 39.280466 -330.021076) (xy 39.289482 -330.021438)
			(xy 39.356538 -330.021438) (xy 39.365556 -330.021091) (xy 39.382472 -330.014836) (xy 39.389558 -330.009246)
			(xy 39.389558 -330.008992) (xy 39.389812 -330.008992) (xy 39.410765 -329.991379) (xy 39.456732 -329.961664)
			(xy 39.506475 -329.938823) (xy 39.55897 -329.923326) (xy 39.613142 -329.91549) (xy 39.64051 -329.915012)
			(xy 39.667764 -329.915446) (xy 39.721717 -329.923204) (xy 39.774017 -329.938563) (xy 39.823598 -329.961208)
			(xy 39.869452 -329.990679) (xy 39.910646 -330.026376) (xy 39.946339 -330.067572) (xy 39.975806 -330.113428)
			(xy 39.998448 -330.163011) (xy 40.013802 -330.215312) (xy 40.021557 -330.269266) (xy 40.022018 -330.29652)
			(xy 40.021584 -330.323892) (xy 40.013761 -330.378073) (xy 39.998266 -330.430577) (xy 39.975417 -330.480324)
			(xy 39.945684 -330.526288) (xy 39.928038 -330.547218) (xy 39.927784 -330.547472) (xy 39.922201 -330.554561)
			(xy 39.915953 -330.571476) (xy 39.915592 -330.580492) (xy 39.915592 -330.647548) (xy 39.915976 -330.656562)
			(xy 39.922205 -330.673479) (xy 39.927784 -330.680568) (xy 39.928038 -330.680568) (xy 39.928038 -330.680822)
			(xy 39.9457 -330.701738) (xy 39.975426 -330.747708) (xy 39.998273 -330.797457) (xy 40.013769 -330.849962)
			(xy 40.021596 -330.904143) (xy 40.021594 -330.958887) (xy 40.013763 -331.013068) (xy 39.998262 -331.065571)
			(xy 39.975412 -331.115318) (xy 39.945682 -331.161286) (xy 39.928038 -331.182218) (xy 39.927784 -331.182472)
			(xy 39.922201 -331.189561) (xy 39.915953 -331.206476) (xy 39.915592 -331.215492) (xy 39.915592 -331.282548)
			(xy 39.915976 -331.291562) (xy 39.922205 -331.308479) (xy 39.927784 -331.315568) (xy 39.928038 -331.315568)
			(xy 39.928038 -331.315822) (xy 39.9457 -331.336738) (xy 39.975426 -331.382708) (xy 39.998273 -331.432457)
			(xy 40.013769 -331.484962) (xy 40.021596 -331.539143) (xy 40.021594 -331.593887) (xy 40.013763 -331.648068)
			(xy 39.998262 -331.700571) (xy 39.975412 -331.750318) (xy 39.945682 -331.796286) (xy 39.928038 -331.817218)
			(xy 39.927784 -331.817472) (xy 39.922201 -331.824561) (xy 39.915953 -331.841476) (xy 39.915592 -331.850492)
			(xy 39.915592 -331.917548) (xy 39.915976 -331.926562) (xy 39.922205 -331.943479) (xy 39.927784 -331.950568)
			(xy 39.928038 -331.950568) (xy 39.928038 -331.950822) (xy 39.9457 -331.971738) (xy 39.975426 -332.017708)
			(xy 39.998273 -332.067457) (xy 40.013769 -332.119962) (xy 40.021596 -332.174143) (xy 40.021594 -332.228887)
			(xy 40.013763 -332.283068) (xy 39.998262 -332.335571) (xy 39.975412 -332.385318) (xy 39.945682 -332.431286)
			(xy 39.928038 -332.452218) (xy 39.927784 -332.452472) (xy 39.922201 -332.459561) (xy 39.915953 -332.476476)
			(xy 39.915592 -332.485492) (xy 39.915592 -332.552548) (xy 39.915976 -332.561562) (xy 39.922205 -332.578479)
			(xy 39.927784 -332.585568) (xy 39.928038 -332.585568) (xy 39.928038 -332.585822) (xy 39.9457 -332.606738)
			(xy 39.975426 -332.652708) (xy 39.998273 -332.702457) (xy 40.013769 -332.754962) (xy 40.021596 -332.809143)
			(xy 40.021594 -332.863887) (xy 40.013763 -332.918068) (xy 39.998262 -332.970571) (xy 39.975412 -333.020318)
			(xy 39.945682 -333.066286) (xy 39.928038 -333.087218) (xy 39.927784 -333.087472) (xy 39.922201 -333.094561)
			(xy 39.915953 -333.111476) (xy 39.915592 -333.120492) (xy 39.915592 -333.187548) (xy 39.915976 -333.196562)
			(xy 39.922205 -333.213479) (xy 39.927784 -333.220568) (xy 39.928038 -333.220568) (xy 39.928038 -333.220822)
			(xy 39.9457 -333.241738) (xy 39.975426 -333.287708) (xy 39.998273 -333.337457) (xy 40.013769 -333.389962)
			(xy 40.021596 -333.444143) (xy 40.021594 -333.498887) (xy 40.013763 -333.553068) (xy 39.998262 -333.605571)
			(xy 39.975412 -333.655318) (xy 39.945682 -333.701286) (xy 39.928038 -333.722218) (xy 39.927784 -333.722472)
			(xy 39.922201 -333.729561) (xy 39.915953 -333.746476) (xy 39.915592 -333.755492) (xy 39.915592 -333.822548)
			(xy 39.915976 -333.831562) (xy 39.922205 -333.848479) (xy 39.927784 -333.855568) (xy 39.928038 -333.855568)
			(xy 39.928038 -333.855822) (xy 39.9457 -333.876738) (xy 39.975426 -333.922708) (xy 39.998273 -333.972457)
			(xy 40.013769 -334.024962) (xy 40.021596 -334.079143) (xy 40.021594 -334.133887) (xy 40.013763 -334.188068)
			(xy 39.998262 -334.240571) (xy 39.975412 -334.290318) (xy 39.945682 -334.336286) (xy 39.928038 -334.357218)
			(xy 39.927784 -334.357472) (xy 39.922201 -334.364561) (xy 39.915953 -334.381476) (xy 39.915592 -334.390492)
			(xy 39.915592 -334.457548) (xy 39.915976 -334.466562) (xy 39.922205 -334.483479) (xy 39.927784 -334.490568)
			(xy 39.928038 -334.490568) (xy 39.928038 -334.490822) (xy 39.94566 -334.511767) (xy 39.975373 -334.557737)
			(xy 39.998212 -334.607481) (xy 40.013707 -334.659979) (xy 40.021541 -334.714152) (xy 40.022018 -334.74152)
			(xy 40.021541 -334.768771) (xy 40.013782 -334.822719) (xy 39.998425 -334.875013) (xy 39.975782 -334.92459)
			(xy 39.946315 -334.97044) (xy 39.910622 -335.011629) (xy 39.869432 -335.047321) (xy 39.823581 -335.076787)
			(xy 39.774004 -335.099428) (xy 39.721709 -335.114784) (xy 39.667761 -335.122542) (xy 39.64051 -335.123028)
			(xy 39.613139 -335.122574) (xy 39.558959 -335.114756) (xy 39.506455 -335.099265) (xy 39.456708 -335.07642)
			(xy 39.410743 -335.046691) (xy 39.389812 -335.029048) (xy 39.389558 -335.028794) (xy 39.382459 -335.023225)
			(xy 39.365552 -335.016968) (xy 39.356538 -335.016602) (xy 39.289482 -335.016602) (xy 39.280464 -335.01695)
			(xy 39.263547 -335.023204) (xy 39.256462 -335.028794) (xy 39.256208 -335.029048) (xy 39.235275 -335.046689)
			(xy 39.189307 -335.076413) (xy 39.139561 -335.099259) (xy 39.087059 -335.114755) (xy 39.032881 -335.122584)
			(xy 38.978139 -335.122584) (xy 38.923961 -335.114755) (xy 38.871459 -335.099259) (xy 38.821713 -335.076413)
			(xy 38.775745 -335.046689) (xy 38.754812 -335.029048) (xy 38.754558 -335.028794) (xy 38.747459 -335.023225)
			(xy 38.730552 -335.016968) (xy 38.721538 -335.016602) (xy 38.654482 -335.016602) (xy 38.645464 -335.01695)
			(xy 38.628547 -335.023204) (xy 38.621462 -335.028794) (xy 38.621462 -335.029048) (xy 38.621208 -335.029048)
			(xy 38.600277 -335.046689) (xy 38.554305 -335.076402) (xy 38.504557 -335.099239) (xy 38.452056 -335.114729)
			(xy 38.397879 -335.122555) (xy 38.37051 -335.123028) (xy 38.34326 -335.122512) (xy 38.289314 -335.114758)
			(xy 38.237021 -335.099405) (xy 38.187446 -335.076767) (xy 38.141596 -335.047303) (xy 38.100406 -335.011615)
			(xy 38.064715 -334.970428) (xy 38.035248 -334.924581) (xy 38.012605 -334.875007) (xy 37.997249 -334.822715)
			(xy 37.98949 -334.76877) (xy 37.989002 -334.74152) (xy 36.008818 -334.74152) (xy 36.008341 -334.768771)
			(xy 36.000582 -334.822719) (xy 35.985225 -334.875013) (xy 35.962582 -334.92459) (xy 35.933115 -334.97044)
			(xy 35.897422 -335.011629) (xy 35.856232 -335.047321) (xy 35.810381 -335.076787) (xy 35.760804 -335.099428)
			(xy 35.708509 -335.114784) (xy 35.654561 -335.122542) (xy 35.62731 -335.123028) (xy 35.599939 -335.122574)
			(xy 35.545759 -335.114756) (xy 35.493255 -335.099265) (xy 35.443508 -335.07642) (xy 35.397543 -335.046691)
			(xy 35.376612 -335.029048) (xy 35.376358 -335.028794) (xy 35.369259 -335.023225) (xy 35.352352 -335.016968)
			(xy 35.343338 -335.016602) (xy 35.276282 -335.016602) (xy 35.267264 -335.01695) (xy 35.250347 -335.023204)
			(xy 35.243262 -335.028794) (xy 35.243262 -335.029048) (xy 35.243008 -335.029048) (xy 35.222077 -335.046689)
			(xy 35.176105 -335.076402) (xy 35.126357 -335.099239) (xy 35.073856 -335.114729) (xy 35.019679 -335.122555)
			(xy 34.99231 -335.123028) (xy 34.992056 -335.123028) (xy 34.962541 -335.12248) (xy 34.904218 -335.113375)
			(xy 34.848 -335.095376) (xy 34.821368 -335.082642) (xy 34.813488 -335.079041) (xy 34.79632 -335.076802)
			(xy 34.779392 -335.080431) (xy 34.771838 -335.084674) (xy 34.698178 -335.13014) (xy 34.690971 -335.134989)
			(xy 34.680082 -335.148507) (xy 34.674354 -335.164893) (xy 34.674048 -335.173574) (xy 34.674048 -348.276418)
			(xy 34.673546 -348.301367) (xy 34.665732 -348.350649) (xy 34.650316 -348.398106) (xy 34.627676 -348.442572)
			(xy 34.598368 -348.482955) (xy 34.581084 -348.500954) (xy 34.372538 -348.7095) (xy 37.198721 -348.7095)
			(xy 37.20289 -348.653877) (xy 37.215303 -348.599498) (xy 37.235682 -348.547575) (xy 37.263573 -348.49927)
			(xy 37.298352 -348.455662) (xy 37.339242 -348.417725) (xy 37.38533 -348.386307) (xy 37.435587 -348.362108)
			(xy 37.488888 -348.345671) (xy 37.544045 -348.337363) (xy 37.571934 -348.33687) (xy 37.598356 -348.337315)
			(xy 37.650672 -348.344769) (xy 37.70141 -348.359538) (xy 37.749554 -348.381324) (xy 37.794139 -348.409692)
			(xy 37.814504 -348.426532) (xy 37.821362 -348.432374) (xy 37.83838 -348.438724) (xy 37.922708 -348.438724)
			(xy 37.939726 -348.432374) (xy 37.946584 -348.426532) (xy 37.96695 -348.409693) (xy 38.011536 -348.381328)
			(xy 38.05968 -348.359541) (xy 38.110417 -348.34477) (xy 38.162732 -348.33731) (xy 38.215576 -348.33731)
			(xy 38.267891 -348.34477) (xy 38.318628 -348.359541) (xy 38.366772 -348.381328) (xy 38.411358 -348.409693)
			(xy 38.431724 -348.426532) (xy 38.438582 -348.432374) (xy 38.4556 -348.438724) (xy 38.539928 -348.438724)
			(xy 38.556946 -348.432374) (xy 38.563804 -348.426532) (xy 38.582653 -348.410899) (xy 38.623697 -348.384187)
			(xy 38.667889 -348.363089) (xy 38.691058 -348.355158) (xy 38.691312 -348.355158) (xy 38.702426 -348.350745)
			(xy 38.719249 -348.333795) (xy 38.72357 -348.322646) (xy 38.749224 -348.244414) (xy 38.752273 -348.232768)
			(xy 38.748427 -348.209037) (xy 38.741858 -348.198948) (xy 38.741858 -348.198694) (xy 38.724615 -348.1741)
			(xy 38.697284 -348.120617) (xy 38.678681 -348.063509) (xy 38.669266 -348.004189) (xy 38.668706 -347.974158)
			(xy 38.66921 -347.946585) (xy 38.677154 -347.892014) (xy 38.692871 -347.839154) (xy 38.716034 -347.789108)
			(xy 38.74616 -347.742918) (xy 38.782622 -347.701545) (xy 38.803326 -347.683328) (xy 38.811393 -347.675766)
			(xy 38.820751 -347.65576) (xy 38.82136 -347.64472) (xy 38.82136 -347.566996) (xy 38.820751 -347.555951)
			(xy 38.811416 -347.535929) (xy 38.803326 -347.528388) (xy 38.782611 -347.510181) (xy 38.74614 -347.468812)
			(xy 38.716008 -347.422621) (xy 38.692842 -347.372573) (xy 38.677127 -347.319709) (xy 38.66919 -347.265133)
			(xy 38.668706 -347.237558) (xy 38.669192 -347.210307) (xy 38.676948 -347.156359) (xy 38.692303 -347.104064)
			(xy 38.714945 -347.054487) (xy 38.744411 -347.008637) (xy 38.780102 -346.967446) (xy 38.821293 -346.931755)
			(xy 38.867143 -346.902289) (xy 38.91672 -346.879647) (xy 38.969015 -346.864292) (xy 39.022963 -346.856536)
			(xy 39.077465 -346.856536) (xy 39.131413 -346.864292) (xy 39.183708 -346.879647) (xy 39.233285 -346.902289)
			(xy 39.279135 -346.931755) (xy 39.320326 -346.967446) (xy 39.356017 -347.008637) (xy 39.385483 -347.054487)
			(xy 39.408125 -347.104064) (xy 39.42348 -347.156359) (xy 39.431236 -347.210307) (xy 39.431722 -347.237558)
			(xy 39.43122 -347.265131) (xy 39.423274 -347.319702) (xy 39.407555 -347.372561) (xy 39.384392 -347.422607)
			(xy 39.354266 -347.468797) (xy 39.317806 -347.510171) (xy 39.297102 -347.528388) (xy 39.289032 -347.535948)
			(xy 39.279675 -347.555956) (xy 39.279068 -347.566996) (xy 39.279068 -347.64472) (xy 39.279659 -347.655767)
			(xy 39.289006 -347.67579) (xy 39.297102 -347.683328) (xy 39.31783 -347.70152) (xy 39.354299 -347.742893)
			(xy 39.384429 -347.789087) (xy 39.407592 -347.839139) (xy 39.423305 -347.892005) (xy 39.431239 -347.946582)
			(xy 39.431722 -347.974158) (xy 39.431285 -348.001084) (xy 39.423713 -348.0544) (xy 39.408714 -348.10612)
			(xy 39.386586 -348.155215) (xy 39.357769 -348.200708) (xy 39.322837 -348.241693) (xy 39.282486 -348.277354)
			(xy 39.237518 -348.306983) (xy 39.188828 -348.329988) (xy 39.163244 -348.338394) (xy 39.16299 -348.338394)
			(xy 39.151826 -348.342701) (xy 39.134852 -348.359516) (xy 39.130478 -348.370652) (xy 39.12866 -348.375986)
			(xy 41.122346 -348.375986) (xy 41.122841 -348.348075) (xy 41.130977 -348.29285) (xy 41.147072 -348.2394)
			(xy 41.170784 -348.188865) (xy 41.201606 -348.142325) (xy 41.219882 -348.121224) (xy 41.225766 -348.114037)
			(xy 41.232425 -348.096719) (xy 41.232836 -348.087442) (xy 41.232836 -348.009718) (xy 41.226232 -347.992446)
			(xy 41.219882 -347.985334) (xy 41.201596 -347.964241) (xy 41.17077 -347.917701) (xy 41.147057 -347.867164)
			(xy 41.130962 -347.813712) (xy 41.12283 -347.758484) (xy 41.122346 -347.730572) (xy 41.122832 -347.703321)
			(xy 41.130588 -347.649373) (xy 41.145943 -347.597078) (xy 41.168585 -347.547501) (xy 41.198051 -347.501651)
			(xy 41.233742 -347.46046) (xy 41.274933 -347.424769) (xy 41.320783 -347.395303) (xy 41.37036 -347.372661)
			(xy 41.422655 -347.357306) (xy 41.476603 -347.34955) (xy 41.531105 -347.34955) (xy 41.585053 -347.357306)
			(xy 41.637348 -347.372661) (xy 41.686925 -347.395303) (xy 41.732775 -347.424769) (xy 41.773966 -347.46046)
			(xy 41.809657 -347.501651) (xy 41.839123 -347.547501) (xy 41.861765 -347.597078) (xy 41.87712 -347.649373)
			(xy 41.884876 -347.703321) (xy 41.885362 -347.730572) (xy 41.884899 -347.758484) (xy 41.876755 -347.81371)
			(xy 41.860652 -347.867161) (xy 41.836933 -347.917695) (xy 41.806105 -347.964234) (xy 41.787826 -347.985334)
			(xy 41.781918 -347.992504) (xy 41.775273 -348.009834) (xy 41.774872 -348.019116) (xy 41.774872 -348.09684)
			(xy 41.781476 -348.114112) (xy 41.787826 -348.121224) (xy 41.806094 -348.142332) (xy 41.836922 -348.188868)
			(xy 41.860639 -348.239401) (xy 41.876738 -348.29285) (xy 41.884875 -348.348075) (xy 41.885362 -348.375986)
			(xy 41.884346 -348.40291) (xy 41.883076 -348.418658) (xy 41.899332 -348.44609) (xy 42.000678 -348.492064)
			(xy 42.010238 -348.495903) (xy 42.030814 -348.496424) (xy 42.049939 -348.48882) (xy 42.057574 -348.481904)
			(xy 42.329354 -348.210378) (xy 42.33619 -348.202974) (xy 42.343913 -348.184378) (xy 42.34434 -348.17431)
			(xy 42.34434 -335.03362) (xy 42.344014 -335.024087) (xy 42.337074 -335.006331) (xy 42.330878 -334.999076)
			(xy 42.312178 -334.977845) (xy 42.280556 -334.930933) (xy 42.256212 -334.879865) (xy 42.239678 -334.82576)
			(xy 42.231318 -334.769807) (xy 42.230802 -334.74152) (xy 42.231279 -334.71415) (xy 42.239094 -334.659972)
			(xy 42.254581 -334.607469) (xy 42.27742 -334.557721) (xy 42.307142 -334.511754) (xy 42.324782 -334.490822)
			(xy 42.325036 -334.490568) (xy 42.330604 -334.483469) (xy 42.336861 -334.466562) (xy 42.337228 -334.457548)
			(xy 42.337228 -334.390492) (xy 42.336869 -334.381476) (xy 42.330622 -334.364559) (xy 42.325036 -334.357472)
			(xy 42.324782 -334.357472) (xy 42.324782 -334.357218) (xy 42.307163 -334.336269) (xy 42.277441 -334.290303)
			(xy 42.254597 -334.240559) (xy 42.239101 -334.18806) (xy 42.231271 -334.133884) (xy 42.231269 -334.079146)
			(xy 42.239094 -334.02497) (xy 42.254586 -333.972469) (xy 42.277426 -333.922724) (xy 42.307145 -333.876756)
			(xy 42.324782 -333.855822) (xy 42.325036 -333.855568) (xy 42.330604 -333.848469) (xy 42.336861 -333.831562)
			(xy 42.337228 -333.822548) (xy 42.337228 -333.755492) (xy 42.336869 -333.746476) (xy 42.330622 -333.729559)
			(xy 42.325036 -333.722472) (xy 42.324782 -333.722472) (xy 42.324782 -333.722218) (xy 42.307163 -333.701269)
			(xy 42.277441 -333.655303) (xy 42.254597 -333.605559) (xy 42.239101 -333.55306) (xy 42.231271 -333.498884)
			(xy 42.231269 -333.444146) (xy 42.239094 -333.38997) (xy 42.254586 -333.337469) (xy 42.277426 -333.287724)
			(xy 42.307145 -333.241756) (xy 42.324782 -333.220822) (xy 42.325036 -333.220568) (xy 42.330604 -333.213469)
			(xy 42.336861 -333.196562) (xy 42.337228 -333.187548) (xy 42.337228 -333.120492) (xy 42.336869 -333.111476)
			(xy 42.330622 -333.094559) (xy 42.325036 -333.087472) (xy 42.324782 -333.087472) (xy 42.324782 -333.087218)
			(xy 42.307163 -333.066269) (xy 42.277441 -333.020303) (xy 42.254597 -332.970559) (xy 42.239101 -332.91806)
			(xy 42.231271 -332.863884) (xy 42.231269 -332.809146) (xy 42.239094 -332.75497) (xy 42.254586 -332.702469)
			(xy 42.277426 -332.652724) (xy 42.307145 -332.606756) (xy 42.324782 -332.585822) (xy 42.325036 -332.585568)
			(xy 42.330604 -332.578469) (xy 42.336861 -332.561562) (xy 42.337228 -332.552548) (xy 42.337228 -332.485492)
			(xy 42.336869 -332.476476) (xy 42.330622 -332.459559) (xy 42.325036 -332.452472) (xy 42.324782 -332.452472)
			(xy 42.324782 -332.452218) (xy 42.307163 -332.431269) (xy 42.277441 -332.385303) (xy 42.254597 -332.335559)
			(xy 42.239101 -332.28306) (xy 42.231271 -332.228884) (xy 42.231269 -332.174146) (xy 42.239094 -332.11997)
			(xy 42.254586 -332.067469) (xy 42.277426 -332.017724) (xy 42.307145 -331.971756) (xy 42.324782 -331.950822)
			(xy 42.325036 -331.950568) (xy 42.330604 -331.943469) (xy 42.336861 -331.926562) (xy 42.337228 -331.917548)
			(xy 42.337228 -331.850492) (xy 42.336869 -331.841476) (xy 42.330622 -331.824559) (xy 42.325036 -331.817472)
			(xy 42.324782 -331.817472) (xy 42.324782 -331.817218) (xy 42.307163 -331.796269) (xy 42.277441 -331.750303)
			(xy 42.254597 -331.700559) (xy 42.239101 -331.64806) (xy 42.231271 -331.593884) (xy 42.231269 -331.539146)
			(xy 42.239094 -331.48497) (xy 42.254586 -331.432469) (xy 42.277426 -331.382724) (xy 42.307145 -331.336756)
			(xy 42.324782 -331.315822) (xy 42.325036 -331.315568) (xy 42.330604 -331.308469) (xy 42.336861 -331.291562)
			(xy 42.337228 -331.282548) (xy 42.337228 -331.215492) (xy 42.336869 -331.206476) (xy 42.330622 -331.189559)
			(xy 42.325036 -331.182472) (xy 42.324782 -331.182472) (xy 42.324782 -331.182218) (xy 42.307163 -331.161269)
			(xy 42.277441 -331.115303) (xy 42.254597 -331.065559) (xy 42.239101 -331.01306) (xy 42.231271 -330.958884)
			(xy 42.231269 -330.904146) (xy 42.239094 -330.84997) (xy 42.254586 -330.797469) (xy 42.277426 -330.747724)
			(xy 42.307145 -330.701756) (xy 42.324782 -330.680822) (xy 42.325036 -330.680568) (xy 42.330604 -330.673469)
			(xy 42.336861 -330.656562) (xy 42.337228 -330.647548) (xy 42.337228 -330.580492) (xy 42.336869 -330.571476)
			(xy 42.330622 -330.554559) (xy 42.325036 -330.547472) (xy 42.324782 -330.547472) (xy 42.324782 -330.547218)
			(xy 42.307135 -330.526292) (xy 42.277425 -330.480317) (xy 42.254591 -330.430568) (xy 42.239102 -330.378066)
			(xy 42.231275 -330.32389) (xy 42.230802 -330.29652) (xy 42.231274 -330.269267) (xy 42.239028 -330.215316)
			(xy 42.254382 -330.163018) (xy 42.277023 -330.113437) (xy 42.30649 -330.067583) (xy 42.342183 -330.02639)
			(xy 42.383375 -329.990696) (xy 42.429228 -329.961228) (xy 42.478808 -329.938586) (xy 42.531106 -329.923231)
			(xy 42.585057 -329.915475) (xy 42.61231 -329.915012) (xy 42.639681 -329.915469) (xy 42.69386 -329.923289)
			(xy 42.746363 -329.93878) (xy 42.79611 -329.961623) (xy 42.842077 -329.99135) (xy 42.863008 -330.008992)
			(xy 42.863262 -330.009246) (xy 42.870351 -330.014828) (xy 42.887266 -330.021076) (xy 42.896282 -330.021438)
			(xy 42.963338 -330.021438) (xy 42.972356 -330.021091) (xy 42.989272 -330.014836) (xy 42.996358 -330.009246)
			(xy 42.996358 -330.008992) (xy 42.996612 -330.008992) (xy 43.017545 -329.991351) (xy 43.063513 -329.961627)
			(xy 43.113259 -329.938781) (xy 43.165761 -329.923285) (xy 43.219939 -329.915456) (xy 43.274681 -329.915456)
			(xy 43.328859 -329.923285) (xy 43.381361 -329.938781) (xy 43.431107 -329.961627) (xy 43.477075 -329.991351)
			(xy 43.498008 -330.008992) (xy 43.498262 -330.009246) (xy 43.505351 -330.014828) (xy 43.522266 -330.021076)
			(xy 43.531282 -330.021438) (xy 43.598338 -330.021438) (xy 43.607356 -330.021091) (xy 43.624272 -330.014836)
			(xy 43.631358 -330.009246) (xy 43.631358 -330.008992) (xy 43.631612 -330.008992) (xy 43.652565 -329.991379)
			(xy 43.698532 -329.961664) (xy 43.748275 -329.938823) (xy 43.80077 -329.923326) (xy 43.854942 -329.91549)
			(xy 43.88231 -329.915012) (xy 43.909564 -329.915446) (xy 43.963517 -329.923204) (xy 44.015817 -329.938563)
			(xy 44.065398 -329.961208) (xy 44.111252 -329.990679) (xy 44.152446 -330.026376) (xy 44.188139 -330.067572)
			(xy 44.217606 -330.113428) (xy 44.240248 -330.163011) (xy 44.255602 -330.215312) (xy 44.263357 -330.269266)
			(xy 44.263818 -330.29652) (xy 44.263384 -330.323892) (xy 44.255561 -330.378073) (xy 44.240066 -330.430577)
			(xy 44.217217 -330.480324) (xy 44.187484 -330.526288) (xy 44.169838 -330.547218) (xy 44.169584 -330.547472)
			(xy 44.164001 -330.554561) (xy 44.157753 -330.571476) (xy 44.157392 -330.580492) (xy 44.157392 -330.647548)
			(xy 44.157776 -330.656562) (xy 44.164005 -330.673479) (xy 44.169584 -330.680568) (xy 44.169838 -330.680568)
			(xy 44.169838 -330.680822) (xy 44.1875 -330.701738) (xy 44.217226 -330.747708) (xy 44.240073 -330.797457)
			(xy 44.255569 -330.849962) (xy 44.263396 -330.904143) (xy 44.263394 -330.958887) (xy 44.255563 -331.013068)
			(xy 44.240062 -331.065571) (xy 44.217212 -331.115318) (xy 44.187482 -331.161286) (xy 44.169838 -331.182218)
			(xy 44.169584 -331.182472) (xy 44.164001 -331.189561) (xy 44.157753 -331.206476) (xy 44.157392 -331.215492)
			(xy 44.157392 -331.282548) (xy 44.157776 -331.291562) (xy 44.164005 -331.308479) (xy 44.169584 -331.315568)
			(xy 44.169838 -331.315568) (xy 44.169838 -331.315822) (xy 44.1875 -331.336738) (xy 44.217226 -331.382708)
			(xy 44.240073 -331.432457) (xy 44.255569 -331.484962) (xy 44.263396 -331.539143) (xy 44.263394 -331.593887)
			(xy 44.255563 -331.648068) (xy 44.240062 -331.700571) (xy 44.217212 -331.750318) (xy 44.187482 -331.796286)
			(xy 44.169838 -331.817218) (xy 44.169584 -331.817472) (xy 44.164001 -331.824561) (xy 44.157753 -331.841476)
			(xy 44.157392 -331.850492) (xy 44.157392 -331.917548) (xy 44.157776 -331.926562) (xy 44.164005 -331.943479)
			(xy 44.169584 -331.950568) (xy 44.169838 -331.950568) (xy 44.169838 -331.950822) (xy 44.1875 -331.971738)
			(xy 44.217226 -332.017708) (xy 44.240073 -332.067457) (xy 44.255569 -332.119962) (xy 44.263396 -332.174143)
			(xy 44.263394 -332.228887) (xy 44.255563 -332.283068) (xy 44.240062 -332.335571) (xy 44.217212 -332.385318)
			(xy 44.187482 -332.431286) (xy 44.169838 -332.452218) (xy 44.169584 -332.452472) (xy 44.164001 -332.459561)
			(xy 44.157753 -332.476476) (xy 44.157392 -332.485492) (xy 44.157392 -332.552548) (xy 44.157776 -332.561562)
			(xy 44.164005 -332.578479) (xy 44.169584 -332.585568) (xy 44.169838 -332.585568) (xy 44.169838 -332.585822)
			(xy 44.1875 -332.606738) (xy 44.217226 -332.652708) (xy 44.240073 -332.702457) (xy 44.255569 -332.754962)
			(xy 44.263396 -332.809143) (xy 44.263394 -332.863887) (xy 44.255563 -332.918068) (xy 44.240062 -332.970571)
			(xy 44.217212 -333.020318) (xy 44.187482 -333.066286) (xy 44.169838 -333.087218) (xy 44.169584 -333.087472)
			(xy 44.164001 -333.094561) (xy 44.157753 -333.111476) (xy 44.157392 -333.120492) (xy 44.157392 -333.187548)
			(xy 44.157776 -333.196562) (xy 44.164005 -333.213479) (xy 44.169584 -333.220568) (xy 44.169838 -333.220568)
			(xy 44.169838 -333.220822) (xy 44.1875 -333.241738) (xy 44.217226 -333.287708) (xy 44.240073 -333.337457)
			(xy 44.255569 -333.389962) (xy 44.263396 -333.444143) (xy 44.263394 -333.498887) (xy 44.255563 -333.553068)
			(xy 44.240062 -333.605571) (xy 44.217212 -333.655318) (xy 44.187482 -333.701286) (xy 44.169838 -333.722218)
			(xy 44.169584 -333.722472) (xy 44.164001 -333.729561) (xy 44.157753 -333.746476) (xy 44.157392 -333.755492)
			(xy 44.157392 -333.822548) (xy 44.157776 -333.831562) (xy 44.164005 -333.848479) (xy 44.169584 -333.855568)
			(xy 44.169838 -333.855568) (xy 44.169838 -333.855822) (xy 44.1875 -333.876738) (xy 44.217226 -333.922708)
			(xy 44.240073 -333.972457) (xy 44.255569 -334.024962) (xy 44.263396 -334.079143) (xy 44.263394 -334.133887)
			(xy 44.255563 -334.188068) (xy 44.240062 -334.240571) (xy 44.217212 -334.290318) (xy 44.187482 -334.336286)
			(xy 44.169838 -334.357218) (xy 44.169584 -334.357472) (xy 44.164001 -334.364561) (xy 44.157753 -334.381476)
			(xy 44.157392 -334.390492) (xy 44.157392 -334.457548) (xy 44.157776 -334.466562) (xy 44.164005 -334.483479)
			(xy 44.169584 -334.490568) (xy 44.169838 -334.490568) (xy 44.169838 -334.490822) (xy 44.18746 -334.511767)
			(xy 44.217173 -334.557737) (xy 44.240012 -334.607481) (xy 44.255507 -334.659979) (xy 44.263341 -334.714152)
			(xy 44.263818 -334.74152) (xy 46.244002 -334.74152) (xy 46.244479 -334.71415) (xy 46.252294 -334.659972)
			(xy 46.267781 -334.607469) (xy 46.29062 -334.557721) (xy 46.320342 -334.511754) (xy 46.337982 -334.490822)
			(xy 46.338236 -334.490568) (xy 46.343804 -334.483469) (xy 46.350061 -334.466562) (xy 46.350428 -334.457548)
			(xy 46.350428 -334.390492) (xy 46.350069 -334.381476) (xy 46.343822 -334.364559) (xy 46.338236 -334.357472)
			(xy 46.337982 -334.357472) (xy 46.337982 -334.357218) (xy 46.320363 -334.336269) (xy 46.290641 -334.290303)
			(xy 46.267797 -334.240559) (xy 46.252301 -334.18806) (xy 46.244471 -334.133884) (xy 46.244469 -334.079146)
			(xy 46.252294 -334.02497) (xy 46.267786 -333.972469) (xy 46.290626 -333.922724) (xy 46.320345 -333.876756)
			(xy 46.337982 -333.855822) (xy 46.338236 -333.855568) (xy 46.343804 -333.848469) (xy 46.350061 -333.831562)
			(xy 46.350428 -333.822548) (xy 46.350428 -333.755492) (xy 46.350069 -333.746476) (xy 46.343822 -333.729559)
			(xy 46.338236 -333.722472) (xy 46.337982 -333.722472) (xy 46.337982 -333.722218) (xy 46.320363 -333.701269)
			(xy 46.290641 -333.655303) (xy 46.267797 -333.605559) (xy 46.252301 -333.55306) (xy 46.244471 -333.498884)
			(xy 46.244469 -333.444146) (xy 46.252294 -333.38997) (xy 46.267786 -333.337469) (xy 46.290626 -333.287724)
			(xy 46.320345 -333.241756) (xy 46.337982 -333.220822) (xy 46.338236 -333.220568) (xy 46.343804 -333.213469)
			(xy 46.350061 -333.196562) (xy 46.350428 -333.187548) (xy 46.350428 -333.120492) (xy 46.350069 -333.111476)
			(xy 46.343822 -333.094559) (xy 46.338236 -333.087472) (xy 46.337982 -333.087472) (xy 46.337982 -333.087218)
			(xy 46.320363 -333.066269) (xy 46.290641 -333.020303) (xy 46.267797 -332.970559) (xy 46.252301 -332.91806)
			(xy 46.244471 -332.863884) (xy 46.244469 -332.809146) (xy 46.252294 -332.75497) (xy 46.267786 -332.702469)
			(xy 46.290626 -332.652724) (xy 46.320345 -332.606756) (xy 46.337982 -332.585822) (xy 46.338236 -332.585568)
			(xy 46.343804 -332.578469) (xy 46.350061 -332.561562) (xy 46.350428 -332.552548) (xy 46.350428 -332.485492)
			(xy 46.350069 -332.476476) (xy 46.343822 -332.459559) (xy 46.338236 -332.452472) (xy 46.337982 -332.452472)
			(xy 46.337982 -332.452218) (xy 46.320363 -332.431269) (xy 46.290641 -332.385303) (xy 46.267797 -332.335559)
			(xy 46.252301 -332.28306) (xy 46.244471 -332.228884) (xy 46.244469 -332.174146) (xy 46.252294 -332.11997)
			(xy 46.267786 -332.067469) (xy 46.290626 -332.017724) (xy 46.320345 -331.971756) (xy 46.337982 -331.950822)
			(xy 46.338236 -331.950568) (xy 46.343804 -331.943469) (xy 46.350061 -331.926562) (xy 46.350428 -331.917548)
			(xy 46.350428 -331.850492) (xy 46.350069 -331.841476) (xy 46.343822 -331.824559) (xy 46.338236 -331.817472)
			(xy 46.337982 -331.817472) (xy 46.337982 -331.817218) (xy 46.320363 -331.796269) (xy 46.290641 -331.750303)
			(xy 46.267797 -331.700559) (xy 46.252301 -331.64806) (xy 46.244471 -331.593884) (xy 46.244469 -331.539146)
			(xy 46.252294 -331.48497) (xy 46.267786 -331.432469) (xy 46.290626 -331.382724) (xy 46.320345 -331.336756)
			(xy 46.337982 -331.315822) (xy 46.338236 -331.315568) (xy 46.343804 -331.308469) (xy 46.350061 -331.291562)
			(xy 46.350428 -331.282548) (xy 46.350428 -331.215492) (xy 46.350069 -331.206476) (xy 46.343822 -331.189559)
			(xy 46.338236 -331.182472) (xy 46.337982 -331.182472) (xy 46.337982 -331.182218) (xy 46.320363 -331.161269)
			(xy 46.290641 -331.115303) (xy 46.267797 -331.065559) (xy 46.252301 -331.01306) (xy 46.244471 -330.958884)
			(xy 46.244469 -330.904146) (xy 46.252294 -330.84997) (xy 46.267786 -330.797469) (xy 46.290626 -330.747724)
			(xy 46.320345 -330.701756) (xy 46.337982 -330.680822) (xy 46.338236 -330.680568) (xy 46.343804 -330.673469)
			(xy 46.350061 -330.656562) (xy 46.350428 -330.647548) (xy 46.350428 -330.580492) (xy 46.350069 -330.571476)
			(xy 46.343822 -330.554559) (xy 46.338236 -330.547472) (xy 46.337982 -330.547472) (xy 46.337982 -330.547218)
			(xy 46.320335 -330.526292) (xy 46.290625 -330.480317) (xy 46.267791 -330.430568) (xy 46.252302 -330.378066)
			(xy 46.244475 -330.32389) (xy 46.244002 -330.29652) (xy 46.244474 -330.269267) (xy 46.252228 -330.215316)
			(xy 46.267582 -330.163018) (xy 46.290223 -330.113437) (xy 46.31969 -330.067583) (xy 46.355383 -330.02639)
			(xy 46.396575 -329.990696) (xy 46.442428 -329.961228) (xy 46.492008 -329.938586) (xy 46.544306 -329.923231)
			(xy 46.598257 -329.915475) (xy 46.62551 -329.915012) (xy 46.652881 -329.915469) (xy 46.70706 -329.923289)
			(xy 46.759563 -329.93878) (xy 46.80931 -329.961623) (xy 46.855277 -329.99135) (xy 46.876208 -330.008992)
			(xy 46.876462 -330.009246) (xy 46.883551 -330.014828) (xy 46.900466 -330.021076) (xy 46.909482 -330.021438)
			(xy 46.976538 -330.021438) (xy 46.985556 -330.021091) (xy 47.002472 -330.014836) (xy 47.009558 -330.009246)
			(xy 47.009558 -330.008992) (xy 47.009812 -330.008992) (xy 47.030745 -329.991351) (xy 47.076713 -329.961627)
			(xy 47.126459 -329.938781) (xy 47.178961 -329.923285) (xy 47.233139 -329.915456) (xy 47.287881 -329.915456)
			(xy 47.342059 -329.923285) (xy 47.394561 -329.938781) (xy 47.444307 -329.961627) (xy 47.490275 -329.991351)
			(xy 47.511208 -330.008992) (xy 47.511462 -330.009246) (xy 47.518551 -330.014828) (xy 47.535466 -330.021076)
			(xy 47.544482 -330.021438) (xy 47.611538 -330.021438) (xy 47.620556 -330.021091) (xy 47.637472 -330.014836)
			(xy 47.644558 -330.009246) (xy 47.644558 -330.008992) (xy 47.644812 -330.008992) (xy 47.665765 -329.991379)
			(xy 47.711732 -329.961664) (xy 47.761475 -329.938823) (xy 47.81397 -329.923326) (xy 47.868142 -329.91549)
			(xy 47.89551 -329.915012) (xy 47.922764 -329.915446) (xy 47.976717 -329.923204) (xy 48.029017 -329.938563)
			(xy 48.078598 -329.961208) (xy 48.124452 -329.990679) (xy 48.165646 -330.026376) (xy 48.201339 -330.067572)
			(xy 48.230806 -330.113428) (xy 48.253448 -330.163011) (xy 48.268802 -330.215312) (xy 48.276557 -330.269266)
			(xy 48.277018 -330.29652) (xy 48.276584 -330.323892) (xy 48.268761 -330.378073) (xy 48.253266 -330.430577)
			(xy 48.230417 -330.480324) (xy 48.200684 -330.526288) (xy 48.183038 -330.547218) (xy 48.182784 -330.547472)
			(xy 48.177201 -330.554561) (xy 48.170953 -330.571476) (xy 48.170592 -330.580492) (xy 48.170592 -330.647548)
			(xy 48.170976 -330.656562) (xy 48.177205 -330.673479) (xy 48.182784 -330.680568) (xy 48.183038 -330.680568)
			(xy 48.183038 -330.680822) (xy 48.2007 -330.701738) (xy 48.230426 -330.747708) (xy 48.253273 -330.797457)
			(xy 48.268769 -330.849962) (xy 48.276596 -330.904143) (xy 48.276594 -330.958887) (xy 48.268763 -331.013068)
			(xy 48.253262 -331.065571) (xy 48.230412 -331.115318) (xy 48.200682 -331.161286) (xy 48.183038 -331.182218)
			(xy 48.182784 -331.182472) (xy 48.177201 -331.189561) (xy 48.170953 -331.206476) (xy 48.170592 -331.215492)
			(xy 48.170592 -331.282548) (xy 48.170976 -331.291562) (xy 48.177205 -331.308479) (xy 48.182784 -331.315568)
			(xy 48.183038 -331.315568) (xy 48.183038 -331.315822) (xy 48.2007 -331.336738) (xy 48.230426 -331.382708)
			(xy 48.253273 -331.432457) (xy 48.268769 -331.484962) (xy 48.276596 -331.539143) (xy 48.276594 -331.593887)
			(xy 48.268763 -331.648068) (xy 48.253262 -331.700571) (xy 48.230412 -331.750318) (xy 48.200682 -331.796286)
			(xy 48.183038 -331.817218) (xy 48.182784 -331.817472) (xy 48.177201 -331.824561) (xy 48.170953 -331.841476)
			(xy 48.170592 -331.850492) (xy 48.170592 -331.917548) (xy 48.170976 -331.926562) (xy 48.177205 -331.943479)
			(xy 48.182784 -331.950568) (xy 48.183038 -331.950568) (xy 48.183038 -331.950822) (xy 48.2007 -331.971738)
			(xy 48.230426 -332.017708) (xy 48.253273 -332.067457) (xy 48.268769 -332.119962) (xy 48.276596 -332.174143)
			(xy 48.276594 -332.228887) (xy 48.268763 -332.283068) (xy 48.253262 -332.335571) (xy 48.230412 -332.385318)
			(xy 48.200682 -332.431286) (xy 48.183038 -332.452218) (xy 48.182784 -332.452472) (xy 48.177201 -332.459561)
			(xy 48.170953 -332.476476) (xy 48.170592 -332.485492) (xy 48.170592 -332.552548) (xy 48.170976 -332.561562)
			(xy 48.177205 -332.578479) (xy 48.182784 -332.585568) (xy 48.183038 -332.585568) (xy 48.183038 -332.585822)
			(xy 48.2007 -332.606738) (xy 48.230426 -332.652708) (xy 48.253273 -332.702457) (xy 48.268769 -332.754962)
			(xy 48.276596 -332.809143) (xy 48.276594 -332.863887) (xy 48.268763 -332.918068) (xy 48.253262 -332.970571)
			(xy 48.230412 -333.020318) (xy 48.200682 -333.066286) (xy 48.183038 -333.087218) (xy 48.182784 -333.087472)
			(xy 48.177201 -333.094561) (xy 48.170953 -333.111476) (xy 48.170592 -333.120492) (xy 48.170592 -333.187548)
			(xy 48.170976 -333.196562) (xy 48.177205 -333.213479) (xy 48.182784 -333.220568) (xy 48.183038 -333.220568)
			(xy 48.183038 -333.220822) (xy 48.2007 -333.241738) (xy 48.230426 -333.287708) (xy 48.253273 -333.337457)
			(xy 48.268769 -333.389962) (xy 48.276596 -333.444143) (xy 48.276594 -333.498887) (xy 48.268763 -333.553068)
			(xy 48.253262 -333.605571) (xy 48.230412 -333.655318) (xy 48.200682 -333.701286) (xy 48.183038 -333.722218)
			(xy 48.182784 -333.722472) (xy 48.177201 -333.729561) (xy 48.170953 -333.746476) (xy 48.170592 -333.755492)
			(xy 48.170592 -333.822548) (xy 48.170976 -333.831562) (xy 48.177205 -333.848479) (xy 48.182784 -333.855568)
			(xy 48.183038 -333.855568) (xy 48.183038 -333.855822) (xy 48.2007 -333.876738) (xy 48.230426 -333.922708)
			(xy 48.253273 -333.972457) (xy 48.268769 -334.024962) (xy 48.276596 -334.079143) (xy 48.276594 -334.133887)
			(xy 48.268763 -334.188068) (xy 48.253262 -334.240571) (xy 48.230412 -334.290318) (xy 48.200682 -334.336286)
			(xy 48.183038 -334.357218) (xy 48.182784 -334.357472) (xy 48.177201 -334.364561) (xy 48.170953 -334.381476)
			(xy 48.170592 -334.390492) (xy 48.170592 -334.457548) (xy 48.170976 -334.466562) (xy 48.177205 -334.483479)
			(xy 48.182784 -334.490568) (xy 48.183038 -334.490568) (xy 48.183038 -334.490822) (xy 48.20066 -334.511767)
			(xy 48.230373 -334.557737) (xy 48.253212 -334.607481) (xy 48.268707 -334.659979) (xy 48.276541 -334.714152)
			(xy 48.277018 -334.74152) (xy 48.276541 -334.768771) (xy 48.268782 -334.822719) (xy 48.253425 -334.875013)
			(xy 48.230782 -334.92459) (xy 48.201315 -334.97044) (xy 48.165622 -335.011629) (xy 48.124432 -335.047321)
			(xy 48.078581 -335.076787) (xy 48.029004 -335.099428) (xy 47.976709 -335.114784) (xy 47.922761 -335.122542)
			(xy 47.89551 -335.123028) (xy 47.868139 -335.122574) (xy 47.813959 -335.114756) (xy 47.761455 -335.099265)
			(xy 47.711708 -335.07642) (xy 47.665743 -335.046691) (xy 47.644812 -335.029048) (xy 47.644558 -335.028794)
			(xy 47.637459 -335.023225) (xy 47.620552 -335.016968) (xy 47.611538 -335.016602) (xy 47.544482 -335.016602)
			(xy 47.535464 -335.01695) (xy 47.518547 -335.023204) (xy 47.511462 -335.028794) (xy 47.511208 -335.029048)
			(xy 47.490275 -335.046689) (xy 47.444307 -335.076413) (xy 47.394561 -335.099259) (xy 47.342059 -335.114755)
			(xy 47.287881 -335.122584) (xy 47.233139 -335.122584) (xy 47.178961 -335.114755) (xy 47.126459 -335.099259)
			(xy 47.076713 -335.076413) (xy 47.030745 -335.046689) (xy 47.009812 -335.029048) (xy 47.009558 -335.028794)
			(xy 47.002459 -335.023225) (xy 46.985552 -335.016968) (xy 46.976538 -335.016602) (xy 46.909482 -335.016602)
			(xy 46.900464 -335.01695) (xy 46.883547 -335.023204) (xy 46.876462 -335.028794) (xy 46.876462 -335.029048)
			(xy 46.876208 -335.029048) (xy 46.855277 -335.046689) (xy 46.809305 -335.076402) (xy 46.759557 -335.099239)
			(xy 46.707056 -335.114729) (xy 46.652879 -335.122555) (xy 46.62551 -335.123028) (xy 46.59826 -335.122512)
			(xy 46.544314 -335.114758) (xy 46.492021 -335.099405) (xy 46.442446 -335.076767) (xy 46.396596 -335.047303)
			(xy 46.355406 -335.011615) (xy 46.319715 -334.970428) (xy 46.290248 -334.924581) (xy 46.267605 -334.875007)
			(xy 46.252249 -334.822715) (xy 46.24449 -334.76877) (xy 46.244002 -334.74152) (xy 44.263818 -334.74152)
			(xy 44.263341 -334.768771) (xy 44.255582 -334.822719) (xy 44.240225 -334.875013) (xy 44.217582 -334.92459)
			(xy 44.188115 -334.97044) (xy 44.152422 -335.011629) (xy 44.111232 -335.047321) (xy 44.065381 -335.076787)
			(xy 44.015804 -335.099428) (xy 43.963509 -335.114784) (xy 43.909561 -335.122542) (xy 43.88231 -335.123028)
			(xy 43.854939 -335.122574) (xy 43.800759 -335.114756) (xy 43.748255 -335.099265) (xy 43.698508 -335.07642)
			(xy 43.652543 -335.046691) (xy 43.631612 -335.029048) (xy 43.631358 -335.028794) (xy 43.624259 -335.023225)
			(xy 43.607352 -335.016968) (xy 43.598338 -335.016602) (xy 43.531282 -335.016602) (xy 43.522264 -335.01695)
			(xy 43.505347 -335.023204) (xy 43.498262 -335.028794) (xy 43.498262 -335.029048) (xy 43.498008 -335.029048)
			(xy 43.477077 -335.046689) (xy 43.431105 -335.076402) (xy 43.381357 -335.099239) (xy 43.328856 -335.114729)
			(xy 43.274679 -335.122555) (xy 43.24731 -335.123028) (xy 43.213907 -335.122329) (xy 43.148118 -335.110709)
			(xy 43.1165 -335.099914) (xy 43.104696 -335.096317) (xy 43.080264 -335.099524) (xy 43.069764 -335.10601)
			(xy 43.001692 -335.153508) (xy 42.991901 -335.161019) (xy 42.980443 -335.18284) (xy 42.979848 -335.195164)
			(xy 42.979848 -348.327218) (xy 42.979346 -348.352167) (xy 42.971532 -348.401449) (xy 42.956116 -348.448906)
			(xy 42.933476 -348.493372) (xy 42.904168 -348.533755) (xy 42.886884 -348.551754) (xy 42.729138 -348.7095)
			(xy 45.504521 -348.7095) (xy 45.50869 -348.653877) (xy 45.521103 -348.599498) (xy 45.541482 -348.547575)
			(xy 45.569373 -348.49927) (xy 45.604152 -348.455662) (xy 45.645042 -348.417725) (xy 45.69113 -348.386307)
			(xy 45.741387 -348.362108) (xy 45.794688 -348.345671) (xy 45.849845 -348.337363) (xy 45.877734 -348.33687)
			(xy 45.904156 -348.337315) (xy 45.956472 -348.344769) (xy 46.00721 -348.359538) (xy 46.055354 -348.381324)
			(xy 46.099939 -348.409692) (xy 46.120304 -348.426532) (xy 46.127162 -348.432374) (xy 46.14418 -348.438724)
			(xy 46.228508 -348.438724) (xy 46.245526 -348.432374) (xy 46.252384 -348.426532) (xy 46.27275 -348.409693)
			(xy 46.317336 -348.381328) (xy 46.36548 -348.359541) (xy 46.416217 -348.34477) (xy 46.468532 -348.33731)
			(xy 46.521376 -348.33731) (xy 46.573691 -348.34477) (xy 46.624428 -348.359541) (xy 46.672572 -348.381328)
			(xy 46.717158 -348.409693) (xy 46.737524 -348.426532) (xy 46.744382 -348.432374) (xy 46.7614 -348.438724)
			(xy 46.845728 -348.438724) (xy 46.862746 -348.432374) (xy 46.869604 -348.426532) (xy 46.895641 -348.405213)
			(xy 46.953781 -348.371343) (xy 46.985174 -348.359222) (xy 46.995597 -348.354864) (xy 47.011554 -348.338913)
			(xy 47.015908 -348.328488) (xy 47.04207 -348.254828) (xy 47.045301 -348.244099) (xy 47.043211 -348.221822)
			(xy 47.038006 -348.211902) (xy 47.02535 -348.189724) (xy 47.005398 -348.14272) (xy 46.991893 -348.093476)
			(xy 46.985077 -348.042869) (xy 46.984666 -348.017338) (xy 46.985135 -347.989763) (xy 46.993083 -347.93519)
			(xy 47.008806 -347.882329) (xy 47.031976 -347.832282) (xy 47.062109 -347.786093) (xy 47.098578 -347.744723)
			(xy 47.119286 -347.726508) (xy 47.127356 -347.718948) (xy 47.136714 -347.69894) (xy 47.13732 -347.6879)
			(xy 47.13732 -347.610176) (xy 47.136735 -347.599128) (xy 47.127384 -347.579105) (xy 47.119286 -347.571568)
			(xy 47.098553 -347.55338) (xy 47.062085 -347.512006) (xy 47.031956 -347.465811) (xy 47.008794 -347.415759)
			(xy 46.993082 -347.362892) (xy 46.985148 -347.308314) (xy 46.984666 -347.280738) (xy 46.985152 -347.253487)
			(xy 46.992908 -347.199539) (xy 47.008263 -347.147244) (xy 47.030905 -347.097667) (xy 47.060371 -347.051817)
			(xy 47.096062 -347.010626) (xy 47.137253 -346.974935) (xy 47.183103 -346.945469) (xy 47.23268 -346.922827)
			(xy 47.284975 -346.907472) (xy 47.338923 -346.899716) (xy 47.393425 -346.899716) (xy 47.447373 -346.907472)
			(xy 47.499668 -346.922827) (xy 47.549245 -346.945469) (xy 47.595095 -346.974935) (xy 47.636286 -347.010626)
			(xy 47.671977 -347.051817) (xy 47.701443 -347.097667) (xy 47.724085 -347.147244) (xy 47.73944 -347.199539)
			(xy 47.747196 -347.253487) (xy 47.747682 -347.280738) (xy 47.74718 -347.308311) (xy 47.739236 -347.362883)
			(xy 47.723518 -347.415742) (xy 47.700355 -347.465789) (xy 47.670229 -347.511979) (xy 47.633767 -347.553351)
			(xy 47.613062 -347.571568) (xy 47.604995 -347.57913) (xy 47.595638 -347.599136) (xy 47.595028 -347.610176)
			(xy 47.595028 -347.6879) (xy 47.595643 -347.698944) (xy 47.604974 -347.718966) (xy 47.613062 -347.726508)
			(xy 47.633773 -347.74472) (xy 47.670245 -347.786088) (xy 47.700378 -347.832277) (xy 47.723544 -347.882325)
			(xy 47.73926 -347.935188) (xy 47.747198 -347.989763) (xy 47.747682 -348.017338) (xy 47.747249 -348.043602)
			(xy 47.740051 -348.095633) (xy 47.725782 -348.146185) (xy 47.704713 -348.194302) (xy 47.677241 -348.239072)
			(xy 47.643886 -348.27965) (xy 47.60528 -348.315268) (xy 47.562152 -348.345253) (xy 47.515318 -348.369037)
			(xy 47.496219 -348.375986) (xy 49.478946 -348.375986) (xy 49.479441 -348.348075) (xy 49.487577 -348.29285)
			(xy 49.503672 -348.2394) (xy 49.527384 -348.188865) (xy 49.558206 -348.142325) (xy 49.576482 -348.121224)
			(xy 49.582366 -348.114037) (xy 49.589025 -348.096719) (xy 49.589436 -348.087442) (xy 49.589436 -348.009718)
			(xy 49.582832 -347.992446) (xy 49.576482 -347.985334) (xy 49.558196 -347.964241) (xy 49.52737 -347.917701)
			(xy 49.503657 -347.867164) (xy 49.487562 -347.813712) (xy 49.47943 -347.758484) (xy 49.478946 -347.730572)
			(xy 49.479432 -347.703321) (xy 49.487188 -347.649373) (xy 49.502543 -347.597078) (xy 49.525185 -347.547501)
			(xy 49.554651 -347.501651) (xy 49.590342 -347.46046) (xy 49.631533 -347.424769) (xy 49.677383 -347.395303)
			(xy 49.72696 -347.372661) (xy 49.779255 -347.357306) (xy 49.833203 -347.34955) (xy 49.887705 -347.34955)
			(xy 49.941653 -347.357306) (xy 49.993948 -347.372661) (xy 50.043525 -347.395303) (xy 50.089375 -347.424769)
			(xy 50.130566 -347.46046) (xy 50.166257 -347.501651) (xy 50.195723 -347.547501) (xy 50.218365 -347.597078)
			(xy 50.23372 -347.649373) (xy 50.241476 -347.703321) (xy 50.241962 -347.730572) (xy 50.241499 -347.758484)
			(xy 50.233355 -347.81371) (xy 50.217252 -347.867161) (xy 50.193533 -347.917695) (xy 50.162705 -347.964234)
			(xy 50.144426 -347.985334) (xy 50.138518 -347.992504) (xy 50.131873 -348.009834) (xy 50.131472 -348.019116)
			(xy 50.131472 -348.09684) (xy 50.138076 -348.114112) (xy 50.144426 -348.121224) (xy 50.162694 -348.142332)
			(xy 50.193522 -348.188868) (xy 50.217239 -348.239401) (xy 50.233338 -348.29285) (xy 50.241475 -348.348075)
			(xy 50.241962 -348.375986) (xy 50.241962 -348.381828) (xy 50.242219 -348.391947) (xy 50.249686 -348.410746)
			(xy 50.263814 -348.425221) (xy 50.27295 -348.42958) (xy 50.359564 -348.466156) (xy 50.368995 -348.469689)
			(xy 50.389116 -348.469867) (xy 50.407751 -348.462275) (xy 50.41519 -348.455488) (xy 50.685954 -348.184978)
			(xy 50.69279 -348.177574) (xy 50.700513 -348.158978) (xy 50.70094 -348.14891) (xy 50.70094 -335.529174)
			(xy 50.700544 -335.519101) (xy 50.692805 -335.500503) (xy 50.685954 -335.493106) (xy 50.66792 -335.475326)
			(xy 50.650641 -335.45732) (xy 50.621315 -335.416947) (xy 50.598665 -335.372484) (xy 50.583248 -335.325026)
			(xy 50.575444 -335.27574) (xy 50.574956 -335.25079) (xy 50.574956 -334.967326) (xy 50.574643 -334.96036)
			(xy 50.570789 -334.946967) (xy 50.567336 -334.94091) (xy 50.553996 -334.918317) (xy 50.53299 -334.870238)
			(xy 50.518775 -334.819732) (xy 50.51162 -334.767754) (xy 50.511202 -334.74152) (xy 50.511679 -334.71415)
			(xy 50.519494 -334.659972) (xy 50.534981 -334.607469) (xy 50.55782 -334.557721) (xy 50.587542 -334.511754)
			(xy 50.605182 -334.490822) (xy 50.605436 -334.490568) (xy 50.611004 -334.483469) (xy 50.617261 -334.466562)
			(xy 50.617628 -334.457548) (xy 50.617628 -334.390492) (xy 50.617269 -334.381476) (xy 50.611022 -334.364559)
			(xy 50.605436 -334.357472) (xy 50.605182 -334.357472) (xy 50.605182 -334.357218) (xy 50.587563 -334.336269)
			(xy 50.557841 -334.290303) (xy 50.534997 -334.240559) (xy 50.519501 -334.18806) (xy 50.511671 -334.133884)
			(xy 50.511669 -334.079146) (xy 50.519494 -334.02497) (xy 50.534986 -333.972469) (xy 50.557826 -333.922724)
			(xy 50.587545 -333.876756) (xy 50.605182 -333.855822) (xy 50.605436 -333.855568) (xy 50.611004 -333.848469)
			(xy 50.617261 -333.831562) (xy 50.617628 -333.822548) (xy 50.617628 -333.755492) (xy 50.617269 -333.746476)
			(xy 50.611022 -333.729559) (xy 50.605436 -333.722472) (xy 50.605182 -333.722472) (xy 50.605182 -333.722218)
			(xy 50.587563 -333.701269) (xy 50.557841 -333.655303) (xy 50.534997 -333.605559) (xy 50.519501 -333.55306)
			(xy 50.511671 -333.498884) (xy 50.511669 -333.444146) (xy 50.519494 -333.38997) (xy 50.534986 -333.337469)
			(xy 50.557826 -333.287724) (xy 50.587545 -333.241756) (xy 50.605182 -333.220822) (xy 50.605436 -333.220568)
			(xy 50.611004 -333.213469) (xy 50.617261 -333.196562) (xy 50.617628 -333.187548) (xy 50.617628 -333.120492)
			(xy 50.617269 -333.111476) (xy 50.611022 -333.094559) (xy 50.605436 -333.087472) (xy 50.605182 -333.087472)
			(xy 50.605182 -333.087218) (xy 50.587563 -333.066269) (xy 50.557841 -333.020303) (xy 50.534997 -332.970559)
			(xy 50.519501 -332.91806) (xy 50.511671 -332.863884) (xy 50.511669 -332.809146) (xy 50.519494 -332.75497)
			(xy 50.534986 -332.702469) (xy 50.557826 -332.652724) (xy 50.587545 -332.606756) (xy 50.605182 -332.585822)
			(xy 50.605436 -332.585568) (xy 50.611004 -332.578469) (xy 50.617261 -332.561562) (xy 50.617628 -332.552548)
			(xy 50.617628 -332.485492) (xy 50.617269 -332.476476) (xy 50.611022 -332.459559) (xy 50.605436 -332.452472)
			(xy 50.605182 -332.452472) (xy 50.605182 -332.452218) (xy 50.587563 -332.431269) (xy 50.557841 -332.385303)
			(xy 50.534997 -332.335559) (xy 50.519501 -332.28306) (xy 50.511671 -332.228884) (xy 50.511669 -332.174146)
			(xy 50.519494 -332.11997) (xy 50.534986 -332.067469) (xy 50.557826 -332.017724) (xy 50.587545 -331.971756)
			(xy 50.605182 -331.950822) (xy 50.605436 -331.950568) (xy 50.611004 -331.943469) (xy 50.617261 -331.926562)
			(xy 50.617628 -331.917548) (xy 50.617628 -331.850492) (xy 50.617269 -331.841476) (xy 50.611022 -331.824559)
			(xy 50.605436 -331.817472) (xy 50.605182 -331.817472) (xy 50.605182 -331.817218) (xy 50.587563 -331.796269)
			(xy 50.557841 -331.750303) (xy 50.534997 -331.700559) (xy 50.519501 -331.64806) (xy 50.511671 -331.593884)
			(xy 50.511669 -331.539146) (xy 50.519494 -331.48497) (xy 50.534986 -331.432469) (xy 50.557826 -331.382724)
			(xy 50.587545 -331.336756) (xy 50.605182 -331.315822) (xy 50.605436 -331.315568) (xy 50.611004 -331.308469)
			(xy 50.617261 -331.291562) (xy 50.617628 -331.282548) (xy 50.617628 -331.215492) (xy 50.617269 -331.206476)
			(xy 50.611022 -331.189559) (xy 50.605436 -331.182472) (xy 50.605182 -331.182472) (xy 50.605182 -331.182218)
			(xy 50.587563 -331.161269) (xy 50.557841 -331.115303) (xy 50.534997 -331.065559) (xy 50.519501 -331.01306)
			(xy 50.511671 -330.958884) (xy 50.511669 -330.904146) (xy 50.519494 -330.84997) (xy 50.534986 -330.797469)
			(xy 50.557826 -330.747724) (xy 50.587545 -330.701756) (xy 50.605182 -330.680822) (xy 50.605436 -330.680568)
			(xy 50.611004 -330.673469) (xy 50.617261 -330.656562) (xy 50.617628 -330.647548) (xy 50.617628 -330.580492)
			(xy 50.617269 -330.571476) (xy 50.611022 -330.554559) (xy 50.605436 -330.547472) (xy 50.605182 -330.547472)
			(xy 50.605182 -330.547218) (xy 50.587535 -330.526292) (xy 50.557825 -330.480317) (xy 50.534991 -330.430568)
			(xy 50.519502 -330.378066) (xy 50.511675 -330.32389) (xy 50.511202 -330.29652) (xy 50.511674 -330.269267)
			(xy 50.519428 -330.215316) (xy 50.534782 -330.163018) (xy 50.557423 -330.113437) (xy 50.58689 -330.067583)
			(xy 50.622583 -330.02639) (xy 50.663775 -329.990696) (xy 50.709628 -329.961228) (xy 50.759208 -329.938586)
			(xy 50.811506 -329.923231) (xy 50.865457 -329.915475) (xy 50.89271 -329.915012) (xy 50.920081 -329.915469)
			(xy 50.97426 -329.923289) (xy 51.026763 -329.93878) (xy 51.07651 -329.961623) (xy 51.122477 -329.99135)
			(xy 51.143408 -330.008992) (xy 51.143662 -330.009246) (xy 51.150751 -330.014828) (xy 51.167666 -330.021076)
			(xy 51.176682 -330.021438) (xy 51.243738 -330.021438) (xy 51.252756 -330.021091) (xy 51.269672 -330.014836)
			(xy 51.276758 -330.009246) (xy 51.276758 -330.008992) (xy 51.277012 -330.008992) (xy 51.297945 -329.991351)
			(xy 51.343913 -329.961627) (xy 51.393659 -329.938781) (xy 51.446161 -329.923285) (xy 51.500339 -329.915456)
			(xy 51.555081 -329.915456) (xy 51.609259 -329.923285) (xy 51.661761 -329.938781) (xy 51.711507 -329.961627)
			(xy 51.757475 -329.991351) (xy 51.778408 -330.008992) (xy 51.778662 -330.009246) (xy 51.785751 -330.014828)
			(xy 51.802666 -330.021076) (xy 51.811682 -330.021438) (xy 51.878738 -330.021438) (xy 51.887756 -330.021091)
			(xy 51.904672 -330.014836) (xy 51.911758 -330.009246) (xy 51.911758 -330.008992) (xy 51.912012 -330.008992)
			(xy 51.932965 -329.991379) (xy 51.978932 -329.961664) (xy 52.028675 -329.938823) (xy 52.08117 -329.923326)
			(xy 52.135342 -329.91549) (xy 52.16271 -329.915012) (xy 52.189964 -329.915446) (xy 52.243917 -329.923204)
			(xy 52.296217 -329.938563) (xy 52.345798 -329.961208) (xy 52.391652 -329.990679) (xy 52.432846 -330.026376)
			(xy 52.468539 -330.067572) (xy 52.498006 -330.113428) (xy 52.520648 -330.163011) (xy 52.536002 -330.215312)
			(xy 52.543757 -330.269266) (xy 52.544218 -330.29652) (xy 52.543784 -330.323892) (xy 52.535961 -330.378073)
			(xy 52.520466 -330.430577) (xy 52.497617 -330.480324) (xy 52.467884 -330.526288) (xy 52.450238 -330.547218)
			(xy 52.449984 -330.547472) (xy 52.444401 -330.554561) (xy 52.438153 -330.571476) (xy 52.437792 -330.580492)
			(xy 52.437792 -330.647548) (xy 52.438176 -330.656562) (xy 52.444405 -330.673479) (xy 52.449984 -330.680568)
			(xy 52.450238 -330.680568) (xy 52.450238 -330.680822) (xy 52.4679 -330.701738) (xy 52.497626 -330.747708)
			(xy 52.520473 -330.797457) (xy 52.535969 -330.849962) (xy 52.543796 -330.904143) (xy 52.543794 -330.958887)
			(xy 52.535963 -331.013068) (xy 52.520462 -331.065571) (xy 52.497612 -331.115318) (xy 52.467882 -331.161286)
			(xy 52.450238 -331.182218) (xy 52.449984 -331.182472) (xy 52.444401 -331.189561) (xy 52.438153 -331.206476)
			(xy 52.437792 -331.215492) (xy 52.437792 -331.282548) (xy 52.438176 -331.291562) (xy 52.444405 -331.308479)
			(xy 52.449984 -331.315568) (xy 52.450238 -331.315568) (xy 52.450238 -331.315822) (xy 52.4679 -331.336738)
			(xy 52.497626 -331.382708) (xy 52.520473 -331.432457) (xy 52.535969 -331.484962) (xy 52.543796 -331.539143)
			(xy 52.543794 -331.593887) (xy 52.535963 -331.648068) (xy 52.520462 -331.700571) (xy 52.497612 -331.750318)
			(xy 52.467882 -331.796286) (xy 52.450238 -331.817218) (xy 52.449984 -331.817472) (xy 52.444401 -331.824561)
			(xy 52.438153 -331.841476) (xy 52.437792 -331.850492) (xy 52.437792 -331.917548) (xy 52.438176 -331.926562)
			(xy 52.444405 -331.943479) (xy 52.449984 -331.950568) (xy 52.450238 -331.950568) (xy 52.450238 -331.950822)
			(xy 52.4679 -331.971738) (xy 52.497626 -332.017708) (xy 52.520473 -332.067457) (xy 52.535969 -332.119962)
			(xy 52.543796 -332.174143) (xy 52.543794 -332.228887) (xy 52.535963 -332.283068) (xy 52.520462 -332.335571)
			(xy 52.497612 -332.385318) (xy 52.467882 -332.431286) (xy 52.450238 -332.452218) (xy 52.449984 -332.452472)
			(xy 52.444401 -332.459561) (xy 52.438153 -332.476476) (xy 52.437792 -332.485492) (xy 52.437792 -332.552548)
			(xy 52.438176 -332.561562) (xy 52.444405 -332.578479) (xy 52.449984 -332.585568) (xy 52.450238 -332.585568)
			(xy 52.450238 -332.585822) (xy 52.4679 -332.606738) (xy 52.497626 -332.652708) (xy 52.520473 -332.702457)
			(xy 52.535969 -332.754962) (xy 52.543796 -332.809143) (xy 52.543794 -332.863887) (xy 52.535963 -332.918068)
			(xy 52.520462 -332.970571) (xy 52.497612 -333.020318) (xy 52.467882 -333.066286) (xy 52.450238 -333.087218)
			(xy 52.449984 -333.087472) (xy 52.444401 -333.094561) (xy 52.438153 -333.111476) (xy 52.437792 -333.120492)
			(xy 52.437792 -333.187548) (xy 52.438176 -333.196562) (xy 52.444405 -333.213479) (xy 52.449984 -333.220568)
			(xy 52.450238 -333.220568) (xy 52.450238 -333.220822) (xy 52.4679 -333.241738) (xy 52.497626 -333.287708)
			(xy 52.520473 -333.337457) (xy 52.535969 -333.389962) (xy 52.543796 -333.444143) (xy 52.543794 -333.498887)
			(xy 52.535963 -333.553068) (xy 52.520462 -333.605571) (xy 52.497612 -333.655318) (xy 52.467882 -333.701286)
			(xy 52.450238 -333.722218) (xy 52.449984 -333.722472) (xy 52.444401 -333.729561) (xy 52.438153 -333.746476)
			(xy 52.437792 -333.755492) (xy 52.437792 -333.822548) (xy 52.438176 -333.831562) (xy 52.444405 -333.848479)
			(xy 52.449984 -333.855568) (xy 52.450238 -333.855568) (xy 52.450238 -333.855822) (xy 52.4679 -333.876738)
			(xy 52.497626 -333.922708) (xy 52.520473 -333.972457) (xy 52.535969 -334.024962) (xy 52.543796 -334.079143)
			(xy 52.543794 -334.133887) (xy 52.535963 -334.188068) (xy 52.520462 -334.240571) (xy 52.497612 -334.290318)
			(xy 52.467882 -334.336286) (xy 52.450238 -334.357218) (xy 52.449984 -334.357472) (xy 52.444401 -334.364561)
			(xy 52.438153 -334.381476) (xy 52.437792 -334.390492) (xy 52.437792 -334.457548) (xy 52.438176 -334.466562)
			(xy 52.444405 -334.483479) (xy 52.449984 -334.490568) (xy 52.450238 -334.490568) (xy 52.450238 -334.490822)
			(xy 52.46786 -334.511767) (xy 52.497573 -334.557737) (xy 52.520412 -334.607481) (xy 52.535907 -334.659979)
			(xy 52.543741 -334.714152) (xy 52.544218 -334.74152) (xy 54.524402 -334.74152) (xy 54.524879 -334.71415)
			(xy 54.532694 -334.659972) (xy 54.548181 -334.607469) (xy 54.57102 -334.557721) (xy 54.600742 -334.511754)
			(xy 54.618382 -334.490822) (xy 54.618636 -334.490568) (xy 54.624204 -334.483469) (xy 54.630461 -334.466562)
			(xy 54.630828 -334.457548) (xy 54.630828 -334.390492) (xy 54.630469 -334.381476) (xy 54.624222 -334.364559)
			(xy 54.618636 -334.357472) (xy 54.618382 -334.357472) (xy 54.618382 -334.357218) (xy 54.600763 -334.336269)
			(xy 54.571041 -334.290303) (xy 54.548197 -334.240559) (xy 54.532701 -334.18806) (xy 54.524871 -334.133884)
			(xy 54.524869 -334.079146) (xy 54.532694 -334.02497) (xy 54.548186 -333.972469) (xy 54.571026 -333.922724)
			(xy 54.600745 -333.876756) (xy 54.618382 -333.855822) (xy 54.618636 -333.855568) (xy 54.624204 -333.848469)
			(xy 54.630461 -333.831562) (xy 54.630828 -333.822548) (xy 54.630828 -333.755492) (xy 54.630469 -333.746476)
			(xy 54.624222 -333.729559) (xy 54.618636 -333.722472) (xy 54.618382 -333.722472) (xy 54.618382 -333.722218)
			(xy 54.600763 -333.701269) (xy 54.571041 -333.655303) (xy 54.548197 -333.605559) (xy 54.532701 -333.55306)
			(xy 54.524871 -333.498884) (xy 54.524869 -333.444146) (xy 54.532694 -333.38997) (xy 54.548186 -333.337469)
			(xy 54.571026 -333.287724) (xy 54.600745 -333.241756) (xy 54.618382 -333.220822) (xy 54.618636 -333.220568)
			(xy 54.624204 -333.213469) (xy 54.630461 -333.196562) (xy 54.630828 -333.187548) (xy 54.630828 -333.120492)
			(xy 54.630469 -333.111476) (xy 54.624222 -333.094559) (xy 54.618636 -333.087472) (xy 54.618382 -333.087472)
			(xy 54.618382 -333.087218) (xy 54.600763 -333.066269) (xy 54.571041 -333.020303) (xy 54.548197 -332.970559)
			(xy 54.532701 -332.91806) (xy 54.524871 -332.863884) (xy 54.524869 -332.809146) (xy 54.532694 -332.75497)
			(xy 54.548186 -332.702469) (xy 54.571026 -332.652724) (xy 54.600745 -332.606756) (xy 54.618382 -332.585822)
			(xy 54.618636 -332.585568) (xy 54.624204 -332.578469) (xy 54.630461 -332.561562) (xy 54.630828 -332.552548)
			(xy 54.630828 -332.485492) (xy 54.630469 -332.476476) (xy 54.624222 -332.459559) (xy 54.618636 -332.452472)
			(xy 54.618382 -332.452472) (xy 54.618382 -332.452218) (xy 54.600763 -332.431269) (xy 54.571041 -332.385303)
			(xy 54.548197 -332.335559) (xy 54.532701 -332.28306) (xy 54.524871 -332.228884) (xy 54.524869 -332.174146)
			(xy 54.532694 -332.11997) (xy 54.548186 -332.067469) (xy 54.571026 -332.017724) (xy 54.600745 -331.971756)
			(xy 54.618382 -331.950822) (xy 54.618636 -331.950568) (xy 54.624204 -331.943469) (xy 54.630461 -331.926562)
			(xy 54.630828 -331.917548) (xy 54.630828 -331.850492) (xy 54.630469 -331.841476) (xy 54.624222 -331.824559)
			(xy 54.618636 -331.817472) (xy 54.618382 -331.817472) (xy 54.618382 -331.817218) (xy 54.600763 -331.796269)
			(xy 54.571041 -331.750303) (xy 54.548197 -331.700559) (xy 54.532701 -331.64806) (xy 54.524871 -331.593884)
			(xy 54.524869 -331.539146) (xy 54.532694 -331.48497) (xy 54.548186 -331.432469) (xy 54.571026 -331.382724)
			(xy 54.600745 -331.336756) (xy 54.618382 -331.315822) (xy 54.618636 -331.315568) (xy 54.624204 -331.308469)
			(xy 54.630461 -331.291562) (xy 54.630828 -331.282548) (xy 54.630828 -331.215492) (xy 54.630469 -331.206476)
			(xy 54.624222 -331.189559) (xy 54.618636 -331.182472) (xy 54.618382 -331.182472) (xy 54.618382 -331.182218)
			(xy 54.600763 -331.161269) (xy 54.571041 -331.115303) (xy 54.548197 -331.065559) (xy 54.532701 -331.01306)
			(xy 54.524871 -330.958884) (xy 54.524869 -330.904146) (xy 54.532694 -330.84997) (xy 54.548186 -330.797469)
			(xy 54.571026 -330.747724) (xy 54.600745 -330.701756) (xy 54.618382 -330.680822) (xy 54.618636 -330.680568)
			(xy 54.624204 -330.673469) (xy 54.630461 -330.656562) (xy 54.630828 -330.647548) (xy 54.630828 -330.580492)
			(xy 54.630469 -330.571476) (xy 54.624222 -330.554559) (xy 54.618636 -330.547472) (xy 54.618382 -330.547472)
			(xy 54.618382 -330.547218) (xy 54.600735 -330.526292) (xy 54.571025 -330.480317) (xy 54.548191 -330.430568)
			(xy 54.532702 -330.378066) (xy 54.524875 -330.32389) (xy 54.524402 -330.29652) (xy 54.524874 -330.269267)
			(xy 54.532628 -330.215316) (xy 54.547982 -330.163018) (xy 54.570623 -330.113437) (xy 54.60009 -330.067583)
			(xy 54.635783 -330.02639) (xy 54.676975 -329.990696) (xy 54.722828 -329.961228) (xy 54.772408 -329.938586)
			(xy 54.824706 -329.923231) (xy 54.878657 -329.915475) (xy 54.90591 -329.915012) (xy 54.933281 -329.915469)
			(xy 54.98746 -329.923289) (xy 55.039963 -329.93878) (xy 55.08971 -329.961623) (xy 55.135677 -329.99135)
			(xy 55.156608 -330.008992) (xy 55.156862 -330.009246) (xy 55.163951 -330.014828) (xy 55.180866 -330.021076)
			(xy 55.189882 -330.021438) (xy 55.256938 -330.021438) (xy 55.265956 -330.021091) (xy 55.282872 -330.014836)
			(xy 55.289958 -330.009246) (xy 55.289958 -330.008992) (xy 55.290212 -330.008992) (xy 55.311145 -329.991351)
			(xy 55.357113 -329.961627) (xy 55.406859 -329.938781) (xy 55.459361 -329.923285) (xy 55.513539 -329.915456)
			(xy 55.568281 -329.915456) (xy 55.622459 -329.923285) (xy 55.674961 -329.938781) (xy 55.724707 -329.961627)
			(xy 55.770675 -329.991351) (xy 55.791608 -330.008992) (xy 55.791862 -330.009246) (xy 55.798951 -330.014828)
			(xy 55.815866 -330.021076) (xy 55.824882 -330.021438) (xy 55.891938 -330.021438) (xy 55.900956 -330.021091)
			(xy 55.917872 -330.014836) (xy 55.924958 -330.009246) (xy 55.924958 -330.008992) (xy 55.925212 -330.008992)
			(xy 55.946165 -329.991379) (xy 55.992132 -329.961664) (xy 56.041875 -329.938823) (xy 56.09437 -329.923326)
			(xy 56.148542 -329.91549) (xy 56.17591 -329.915012) (xy 56.203164 -329.915446) (xy 56.257117 -329.923204)
			(xy 56.309417 -329.938563) (xy 56.358998 -329.961208) (xy 56.404852 -329.990679) (xy 56.446046 -330.026376)
			(xy 56.481739 -330.067572) (xy 56.511206 -330.113428) (xy 56.533848 -330.163011) (xy 56.549202 -330.215312)
			(xy 56.556957 -330.269266) (xy 56.557418 -330.29652) (xy 56.556984 -330.323892) (xy 56.549161 -330.378073)
			(xy 56.533666 -330.430577) (xy 56.510817 -330.480324) (xy 56.481084 -330.526288) (xy 56.463438 -330.547218)
			(xy 56.463184 -330.547472) (xy 56.457601 -330.554561) (xy 56.451353 -330.571476) (xy 56.450992 -330.580492)
			(xy 56.450992 -330.647548) (xy 56.451376 -330.656562) (xy 56.457605 -330.673479) (xy 56.463184 -330.680568)
			(xy 56.463438 -330.680568) (xy 56.463438 -330.680822) (xy 56.4811 -330.701738) (xy 56.510826 -330.747708)
			(xy 56.533673 -330.797457) (xy 56.549169 -330.849962) (xy 56.556996 -330.904143) (xy 56.556994 -330.958887)
			(xy 56.549163 -331.013068) (xy 56.533662 -331.065571) (xy 56.510812 -331.115318) (xy 56.481082 -331.161286)
			(xy 56.463438 -331.182218) (xy 56.463184 -331.182472) (xy 56.457601 -331.189561) (xy 56.451353 -331.206476)
			(xy 56.450992 -331.215492) (xy 56.450992 -331.282548) (xy 56.451376 -331.291562) (xy 56.457605 -331.308479)
			(xy 56.463184 -331.315568) (xy 56.463438 -331.315568) (xy 56.463438 -331.315822) (xy 56.4811 -331.336738)
			(xy 56.510826 -331.382708) (xy 56.533673 -331.432457) (xy 56.549169 -331.484962) (xy 56.556996 -331.539143)
			(xy 56.556994 -331.593887) (xy 56.549163 -331.648068) (xy 56.533662 -331.700571) (xy 56.510812 -331.750318)
			(xy 56.481082 -331.796286) (xy 56.463438 -331.817218) (xy 56.463184 -331.817472) (xy 56.457601 -331.824561)
			(xy 56.451353 -331.841476) (xy 56.450992 -331.850492) (xy 56.450992 -331.917548) (xy 56.451376 -331.926562)
			(xy 56.457605 -331.943479) (xy 56.463184 -331.950568) (xy 56.463438 -331.950568) (xy 56.463438 -331.950822)
			(xy 56.4811 -331.971738) (xy 56.510826 -332.017708) (xy 56.533673 -332.067457) (xy 56.549169 -332.119962)
			(xy 56.556996 -332.174143) (xy 56.556994 -332.228887) (xy 56.549163 -332.283068) (xy 56.533662 -332.335571)
			(xy 56.510812 -332.385318) (xy 56.481082 -332.431286) (xy 56.463438 -332.452218) (xy 56.463184 -332.452472)
			(xy 56.457601 -332.459561) (xy 56.451353 -332.476476) (xy 56.450992 -332.485492) (xy 56.450992 -332.552548)
			(xy 56.451376 -332.561562) (xy 56.457605 -332.578479) (xy 56.463184 -332.585568) (xy 56.463438 -332.585568)
			(xy 56.463438 -332.585822) (xy 56.4811 -332.606738) (xy 56.510826 -332.652708) (xy 56.533673 -332.702457)
			(xy 56.549169 -332.754962) (xy 56.556996 -332.809143) (xy 56.556994 -332.863887) (xy 56.549163 -332.918068)
			(xy 56.533662 -332.970571) (xy 56.510812 -333.020318) (xy 56.481082 -333.066286) (xy 56.463438 -333.087218)
			(xy 56.463184 -333.087472) (xy 56.457601 -333.094561) (xy 56.451353 -333.111476) (xy 56.450992 -333.120492)
			(xy 56.450992 -333.187548) (xy 56.451376 -333.196562) (xy 56.457605 -333.213479) (xy 56.463184 -333.220568)
			(xy 56.463438 -333.220568) (xy 56.463438 -333.220822) (xy 56.4811 -333.241738) (xy 56.510826 -333.287708)
			(xy 56.533673 -333.337457) (xy 56.549169 -333.389962) (xy 56.556996 -333.444143) (xy 56.556994 -333.498887)
			(xy 56.549163 -333.553068) (xy 56.533662 -333.605571) (xy 56.510812 -333.655318) (xy 56.481082 -333.701286)
			(xy 56.463438 -333.722218) (xy 56.463184 -333.722472) (xy 56.457601 -333.729561) (xy 56.451353 -333.746476)
			(xy 56.450992 -333.755492) (xy 56.450992 -333.822548) (xy 56.451376 -333.831562) (xy 56.457605 -333.848479)
			(xy 56.463184 -333.855568) (xy 56.463438 -333.855568) (xy 56.463438 -333.855822) (xy 56.4811 -333.876738)
			(xy 56.510826 -333.922708) (xy 56.533673 -333.972457) (xy 56.549169 -334.024962) (xy 56.556996 -334.079143)
			(xy 56.556994 -334.133887) (xy 56.549163 -334.188068) (xy 56.533662 -334.240571) (xy 56.510812 -334.290318)
			(xy 56.481082 -334.336286) (xy 56.463438 -334.357218) (xy 56.463184 -334.357472) (xy 56.457601 -334.364561)
			(xy 56.451353 -334.381476) (xy 56.450992 -334.390492) (xy 56.450992 -334.457548) (xy 56.451376 -334.466562)
			(xy 56.457605 -334.483479) (xy 56.463184 -334.490568) (xy 56.463438 -334.490568) (xy 56.463438 -334.490822)
			(xy 56.48106 -334.511767) (xy 56.510773 -334.557737) (xy 56.533612 -334.607481) (xy 56.549107 -334.659979)
			(xy 56.556941 -334.714152) (xy 56.557418 -334.74152) (xy 56.556941 -334.768771) (xy 56.549182 -334.822719)
			(xy 56.533825 -334.875013) (xy 56.511182 -334.92459) (xy 56.481715 -334.97044) (xy 56.446022 -335.011629)
			(xy 56.404832 -335.047321) (xy 56.358981 -335.076787) (xy 56.309404 -335.099428) (xy 56.257109 -335.114784)
			(xy 56.203161 -335.122542) (xy 56.17591 -335.123028) (xy 56.148539 -335.122574) (xy 56.094359 -335.114756)
			(xy 56.041855 -335.099265) (xy 55.992108 -335.07642) (xy 55.946143 -335.046691) (xy 55.925212 -335.029048)
			(xy 55.924958 -335.028794) (xy 55.917859 -335.023225) (xy 55.900952 -335.016968) (xy 55.891938 -335.016602)
			(xy 55.824882 -335.016602) (xy 55.815864 -335.01695) (xy 55.798947 -335.023204) (xy 55.791862 -335.028794)
			(xy 55.791608 -335.029048) (xy 55.770675 -335.046689) (xy 55.724707 -335.076413) (xy 55.674961 -335.099259)
			(xy 55.622459 -335.114755) (xy 55.568281 -335.122584) (xy 55.513539 -335.122584) (xy 55.459361 -335.114755)
			(xy 55.406859 -335.099259) (xy 55.357113 -335.076413) (xy 55.311145 -335.046689) (xy 55.290212 -335.029048)
			(xy 55.289958 -335.028794) (xy 55.282859 -335.023225) (xy 55.265952 -335.016968) (xy 55.256938 -335.016602)
			(xy 55.189882 -335.016602) (xy 55.180864 -335.01695) (xy 55.163947 -335.023204) (xy 55.156862 -335.028794)
			(xy 55.156862 -335.029048) (xy 55.156608 -335.029048) (xy 55.135677 -335.046689) (xy 55.089705 -335.076402)
			(xy 55.039957 -335.099239) (xy 54.987456 -335.114729) (xy 54.933279 -335.122555) (xy 54.90591 -335.123028)
			(xy 54.87866 -335.122512) (xy 54.824714 -335.114758) (xy 54.772421 -335.099405) (xy 54.722846 -335.076767)
			(xy 54.676996 -335.047303) (xy 54.635806 -335.011615) (xy 54.600115 -334.970428) (xy 54.570648 -334.924581)
			(xy 54.548005 -334.875007) (xy 54.532649 -334.822715) (xy 54.52489 -334.76877) (xy 54.524402 -334.74152)
			(xy 52.544218 -334.74152) (xy 52.543741 -334.768771) (xy 52.535982 -334.822719) (xy 52.520625 -334.875013)
			(xy 52.497982 -334.92459) (xy 52.468515 -334.97044) (xy 52.432822 -335.011629) (xy 52.391632 -335.047321)
			(xy 52.345781 -335.076787) (xy 52.296204 -335.099428) (xy 52.243909 -335.114784) (xy 52.189961 -335.122542)
			(xy 52.16271 -335.123028) (xy 52.135339 -335.122574) (xy 52.081159 -335.114756) (xy 52.028655 -335.099265)
			(xy 51.978908 -335.07642) (xy 51.932943 -335.046691) (xy 51.912012 -335.029048) (xy 51.911758 -335.028794)
			(xy 51.904659 -335.023225) (xy 51.887752 -335.016968) (xy 51.878738 -335.016602) (xy 51.811682 -335.016602)
			(xy 51.802664 -335.01695) (xy 51.785747 -335.023204) (xy 51.778662 -335.028794) (xy 51.778662 -335.029048)
			(xy 51.778408 -335.029048) (xy 51.757477 -335.046689) (xy 51.711505 -335.076402) (xy 51.661757 -335.099239)
			(xy 51.609256 -335.114729) (xy 51.555079 -335.122555) (xy 51.52771 -335.123028) (xy 51.502385 -335.122605)
			(xy 51.452183 -335.11589) (xy 51.403312 -335.10259) (xy 51.35663 -335.082938) (xy 51.31296 -335.057282)
			(xy 51.29276 -335.042002) (xy 51.292506 -335.041748) (xy 51.28567 -335.036954) (xy 51.269861 -335.03163)
			(xy 51.261518 -335.031334) (xy 51.261264 -335.031334) (xy 51.25125 -335.031759) (xy 51.232751 -335.039437)
			(xy 51.218598 -335.05361) (xy 51.210946 -335.072119) (xy 51.210464 -335.082134) (xy 51.210464 -335.097882)
			(xy 51.210882 -335.107952) (xy 51.218606 -335.126551) (xy 51.22545 -335.13395) (xy 51.243484 -335.15173)
			(xy 51.26079 -335.16971) (xy 51.290113 -335.21009) (xy 51.312758 -335.25456) (xy 51.328168 -335.302024)
			(xy 51.335964 -335.351314) (xy 51.336448 -335.376266) (xy 51.336448 -348.301818) (xy 51.335946 -348.326767)
			(xy 51.328132 -348.376049) (xy 51.312716 -348.423506) (xy 51.290076 -348.467972) (xy 51.260768 -348.508355)
			(xy 51.243484 -348.526354) (xy 51.060338 -348.7095) (xy 53.861121 -348.7095) (xy 53.86529 -348.653877)
			(xy 53.877703 -348.599498) (xy 53.898082 -348.547575) (xy 53.925973 -348.49927) (xy 53.960752 -348.455662)
			(xy 54.001642 -348.417725) (xy 54.04773 -348.386307) (xy 54.097987 -348.362108) (xy 54.151288 -348.345671)
			(xy 54.206445 -348.337363) (xy 54.234334 -348.33687) (xy 54.260756 -348.337315) (xy 54.313072 -348.344769)
			(xy 54.36381 -348.359538) (xy 54.411954 -348.381324) (xy 54.456539 -348.409692) (xy 54.476904 -348.426532)
			(xy 54.483762 -348.432374) (xy 54.50078 -348.438724) (xy 54.585108 -348.438724) (xy 54.602126 -348.432374)
			(xy 54.608984 -348.426532) (xy 54.62935 -348.409693) (xy 54.673936 -348.381328) (xy 54.72208 -348.359541)
			(xy 54.772817 -348.34477) (xy 54.825132 -348.33731) (xy 54.877976 -348.33731) (xy 54.930291 -348.34477)
			(xy 54.981028 -348.359541) (xy 55.029172 -348.381328) (xy 55.073758 -348.409693) (xy 55.094124 -348.426532)
			(xy 55.100982 -348.432374) (xy 55.118 -348.438724) (xy 55.202328 -348.438724) (xy 55.219346 -348.432374)
			(xy 55.226204 -348.426532) (xy 55.245009 -348.410904) (xy 55.285974 -348.384209) (xy 55.33008 -348.363102)
			(xy 55.353204 -348.355158) (xy 55.36438 -348.351602) (xy 55.381398 -348.335092) (xy 55.412386 -348.248224)
			(xy 55.415708 -348.236964) (xy 55.412936 -348.213678) (xy 55.407052 -348.20352) (xy 55.392675 -348.180322)
			(xy 55.369981 -348.130687) (xy 55.354589 -348.078326) (xy 55.346812 -348.024306) (xy 55.346346 -347.997018)
			(xy 55.346808 -347.969443) (xy 55.354759 -347.914869) (xy 55.370484 -347.862009) (xy 55.393654 -347.811962)
			(xy 55.423788 -347.765773) (xy 55.460258 -347.724403) (xy 55.480966 -347.706188) (xy 55.489058 -347.698648)
			(xy 55.4984 -347.678625) (xy 55.499 -347.66758) (xy 55.499 -347.589856) (xy 55.4984 -347.578811)
			(xy 55.489057 -347.558789) (xy 55.480966 -347.551248) (xy 55.460268 -347.533023) (xy 55.423798 -347.491656)
			(xy 55.393665 -347.445469) (xy 55.370498 -347.395424) (xy 55.354778 -347.342564) (xy 55.346834 -347.287992)
			(xy 55.346346 -347.260418) (xy 55.346832 -347.233167) (xy 55.354588 -347.179219) (xy 55.369943 -347.126924)
			(xy 55.392585 -347.077347) (xy 55.422051 -347.031497) (xy 55.457742 -346.990306) (xy 55.498933 -346.954615)
			(xy 55.544783 -346.925149) (xy 55.59436 -346.902507) (xy 55.646655 -346.887152) (xy 55.700603 -346.879396)
			(xy 55.755105 -346.879396) (xy 55.809053 -346.887152) (xy 55.861348 -346.902507) (xy 55.910925 -346.925149)
			(xy 55.956775 -346.954615) (xy 55.997966 -346.990306) (xy 56.033657 -347.031497) (xy 56.063123 -347.077347)
			(xy 56.085765 -347.126924) (xy 56.10112 -347.179219) (xy 56.108876 -347.233167) (xy 56.109362 -347.260418)
			(xy 56.108853 -347.287991) (xy 56.100911 -347.342563) (xy 56.085196 -347.395422) (xy 56.062034 -347.445469)
			(xy 56.031908 -347.491659) (xy 55.995447 -347.533032) (xy 55.974742 -347.551248) (xy 55.966636 -347.558775)
			(xy 55.957301 -347.578808) (xy 55.956708 -347.589856) (xy 55.956708 -347.66758) (xy 55.957285 -347.678628)
			(xy 55.966644 -347.698649) (xy 55.974742 -347.706188) (xy 55.995459 -347.724393) (xy 56.031927 -347.765764)
			(xy 56.062057 -347.811955) (xy 56.085222 -347.862005) (xy 56.100937 -347.914868) (xy 56.108877 -347.969443)
			(xy 56.109362 -347.997018) (xy 56.108932 -348.023945) (xy 56.101364 -348.077263) (xy 56.086367 -348.128986)
			(xy 56.06424 -348.178083) (xy 56.035422 -348.223577) (xy 56.000489 -348.264562) (xy 55.960135 -348.300223)
			(xy 55.915163 -348.329849) (xy 55.86647 -348.352851) (xy 55.840884 -348.361254) (xy 55.84063 -348.361254)
			(xy 55.829745 -348.365308) (xy 55.812942 -348.38131) (xy 55.808372 -348.391988) (xy 55.776114 -348.478856)
			(xy 55.7784 -348.50197) (xy 55.78475 -348.51213) (xy 55.798167 -348.534423) (xy 55.81936 -348.581941)
			(xy 55.833718 -348.63195) (xy 55.840962 -348.683473) (xy 55.841392 -348.709488) (xy 55.840955 -348.736107)
			(xy 55.833379 -348.788802) (xy 55.818381 -348.839884) (xy 55.796266 -348.88831) (xy 55.767483 -348.933096)
			(xy 55.73262 -348.97333) (xy 55.692385 -349.008192) (xy 55.647598 -349.036973) (xy 55.59917 -349.059086)
			(xy 55.548089 -349.074082) (xy 55.495393 -349.081656) (xy 55.468774 -349.082106) (xy 55.442352 -349.081662)
			(xy 55.390036 -349.074208) (xy 55.339297 -349.05944) (xy 55.291153 -349.037653) (xy 55.246569 -349.009285)
			(xy 55.226204 -348.992444) (xy 55.219346 -348.986602) (xy 55.202328 -348.980252) (xy 55.118 -348.980252)
			(xy 55.100982 -348.986602) (xy 55.094124 -348.992444) (xy 55.073758 -349.009283) (xy 55.029172 -349.037648)
			(xy 54.981028 -349.059435) (xy 54.930291 -349.074206) (xy 54.877976 -349.081666) (xy 54.825132 -349.081666)
			(xy 54.772817 -349.074206) (xy 54.72208 -349.059435) (xy 54.673936 -349.037648) (xy 54.62935 -349.009283)
			(xy 54.608984 -348.992444) (xy 54.602126 -348.986602) (xy 54.585108 -348.980252) (xy 54.50078 -348.980252)
			(xy 54.483762 -348.986602) (xy 54.476904 -348.992444) (xy 54.45653 -349.009272) (xy 54.411943 -349.03763)
			(xy 54.363801 -349.059412) (xy 54.313066 -349.074182) (xy 54.260754 -349.081644) (xy 54.234334 -349.082106)
			(xy 54.206445 -349.081637) (xy 54.151288 -349.073329) (xy 54.097987 -349.056892) (xy 54.04773 -349.032693)
			(xy 54.001642 -349.001275) (xy 53.960752 -348.963338) (xy 53.925973 -348.91973) (xy 53.898082 -348.871425)
			(xy 53.877703 -348.819502) (xy 53.86529 -348.765123) (xy 53.861121 -348.7095) (xy 51.060338 -348.7095)
			(xy 50.71618 -349.053658) (xy 50.70926 -349.06129) (xy 50.701591 -349.080391) (xy 50.701989 -349.100969)
			(xy 50.705766 -349.110554) (xy 50.751486 -349.211646) (xy 50.778664 -349.227902) (xy 50.794412 -349.226886)
			(xy 50.818796 -349.226124) (xy 50.846047 -349.226573) (xy 50.899995 -349.234329) (xy 50.952289 -349.249684)
			(xy 51.001867 -349.272324) (xy 51.047718 -349.301789) (xy 51.088908 -349.337479) (xy 51.124601 -349.378669)
			(xy 51.154068 -349.424518) (xy 51.17671 -349.474094) (xy 51.192067 -349.526388) (xy 51.199825 -349.580336)
			(xy 51.199827 -349.634838) (xy 51.192073 -349.688786) (xy 51.17672 -349.741081) (xy 51.154081 -349.790659)
			(xy 51.124617 -349.83651) (xy 51.088927 -349.877702) (xy 51.047739 -349.913395) (xy 51.00189 -349.942863)
			(xy 50.952314 -349.965507) (xy 50.900021 -349.980865) (xy 50.846074 -349.988625) (xy 50.791572 -349.988628)
			(xy 50.737624 -349.980875) (xy 50.685328 -349.965523) (xy 50.63575 -349.942885) (xy 50.589897 -349.913422)
			(xy 50.548705 -349.877734) (xy 50.513011 -349.836546) (xy 50.483541 -349.790698) (xy 50.460896 -349.741123)
			(xy 50.445537 -349.68883) (xy 50.437776 -349.634883) (xy 50.437288 -349.607632) (xy 50.437288 -349.607378)
			(xy 50.437879 -349.576288) (xy 50.447976 -349.514932) (xy 50.467913 -349.456035) (xy 50.481992 -349.428308)
			(xy 50.489866 -349.413322) (xy 50.48504 -349.380302) (xy 50.473102 -349.368364) (xy 50.46569 -349.36168)
			(xy 50.447257 -349.354083) (xy 50.427319 -349.354083) (xy 50.408886 -349.36168) (xy 50.401474 -349.368364)
			(xy 50.281078 -349.488506) (xy 50.27424 -349.495907) (xy 50.266519 -349.514506) (xy 50.266092 -349.524574)
			(xy 50.266092 -350.05899) (xy 50.266498 -350.069062) (xy 50.27423 -350.087661) (xy 50.281078 -350.095058)
			(xy 50.304954 -350.11868) (xy 50.309931 -350.123322) (xy 50.321779 -350.130013) (xy 50.328322 -350.131888)
			(xy 50.328576 -350.132142) (xy 50.329084 -350.132142) (xy 50.356477 -350.13924) (xy 50.408929 -350.160472)
			(xy 50.457669 -350.18922) (xy 50.501626 -350.224855) (xy 50.539835 -350.266593) (xy 50.571457 -350.313519)
			(xy 50.595799 -350.364602) (xy 50.612326 -350.418722) (xy 50.620675 -350.474689) (xy 50.621184 -350.502982)
			(xy 50.620728 -350.530235) (xy 50.612973 -350.584188) (xy 50.597618 -350.636487) (xy 50.574976 -350.686069)
			(xy 50.545507 -350.731923) (xy 50.509813 -350.773117) (xy 50.468619 -350.808811) (xy 50.422764 -350.838278)
			(xy 50.373182 -350.86092) (xy 50.320882 -350.876274) (xy 50.26693 -350.884028) (xy 50.239676 -350.88449)
			(xy 50.211367 -350.884034) (xy 50.155369 -350.875684) (xy 50.101222 -350.859143) (xy 50.050118 -350.834773)
			(xy 50.003182 -350.803112) (xy 49.961445 -350.764856) (xy 49.925827 -350.720846) (xy 49.897111 -350.672052)
			(xy 49.875929 -350.619546) (xy 49.868836 -350.592136) (xy 49.868836 -350.591628) (xy 49.866876 -350.585079)
			(xy 49.860062 -350.573235) (xy 49.855374 -350.56826) (xy 49.723548 -350.436434) (xy 49.706278 -350.41842)
			(xy 49.676949 -350.37805) (xy 49.654297 -350.333589) (xy 49.638878 -350.286132) (xy 49.631073 -350.236847)
			(xy 49.630584 -350.211898) (xy 49.630584 -349.371666) (xy 49.631067 -349.346716) (xy 49.638884 -349.297433)
			(xy 49.654304 -349.249975) (xy 49.676948 -349.20551) (xy 49.706262 -349.165128) (xy 49.723548 -349.14713)
			(xy 49.939956 -348.930722) (xy 49.946696 -348.923249) (xy 49.954274 -348.904627) (xy 49.954144 -348.884522)
			(xy 49.950624 -348.875096) (xy 49.914048 -348.788482) (xy 49.909765 -348.779298) (xy 49.895271 -348.76515)
			(xy 49.87643 -348.757717) (xy 49.866296 -348.757494) (xy 49.860454 -348.757494) (xy 49.833201 -348.757065)
			(xy 49.77925 -348.749302) (xy 49.726954 -348.73394) (xy 49.677376 -348.711293) (xy 49.631525 -348.68182)
			(xy 49.590335 -348.646123) (xy 49.554644 -348.604927) (xy 49.525179 -348.559072) (xy 49.502539 -348.50949)
			(xy 49.487185 -348.457191) (xy 49.479431 -348.403239) (xy 49.478946 -348.375986) (xy 47.496219 -348.375986)
			(xy 47.490634 -348.378018) (xy 47.479712 -348.381574) (xy 47.46371 -348.397322) (xy 47.432214 -348.48165)
			(xy 47.42878 -348.492215) (xy 47.430365 -348.51435) (xy 47.435262 -348.524322) (xy 47.435516 -348.524322)
			(xy 47.435516 -348.52483) (xy 47.44719 -348.545996) (xy 47.465591 -348.590694) (xy 47.478056 -348.637397)
			(xy 47.484374 -348.68532) (xy 47.484792 -348.709488) (xy 47.484355 -348.736107) (xy 47.476779 -348.788802)
			(xy 47.461781 -348.839884) (xy 47.439666 -348.88831) (xy 47.410883 -348.933096) (xy 47.37602 -348.97333)
			(xy 47.335785 -349.008192) (xy 47.290998 -349.036973) (xy 47.24257 -349.059086) (xy 47.191489 -349.074082)
			(xy 47.138793 -349.081656) (xy 47.112174 -349.082106) (xy 47.085752 -349.081662) (xy 47.033436 -349.074208)
			(xy 46.982697 -349.05944) (xy 46.934553 -349.037653) (xy 46.889969 -349.009285) (xy 46.869604 -348.992444)
			(xy 46.862746 -348.986602) (xy 46.845728 -348.980252) (xy 46.7614 -348.980252) (xy 46.744382 -348.986602)
			(xy 46.737524 -348.992444) (xy 46.717158 -349.009283) (xy 46.672572 -349.037648) (xy 46.624428 -349.059435)
			(xy 46.573691 -349.074206) (xy 46.521376 -349.081666) (xy 46.468532 -349.081666) (xy 46.416217 -349.074206)
			(xy 46.36548 -349.059435) (xy 46.317336 -349.037648) (xy 46.27275 -349.009283) (xy 46.252384 -348.992444)
			(xy 46.245526 -348.986602) (xy 46.228508 -348.980252) (xy 46.14418 -348.980252) (xy 46.127162 -348.986602)
			(xy 46.120304 -348.992444) (xy 46.09993 -349.009272) (xy 46.055343 -349.03763) (xy 46.007201 -349.059412)
			(xy 45.956466 -349.074182) (xy 45.904154 -349.081644) (xy 45.877734 -349.082106) (xy 45.849845 -349.081637)
			(xy 45.794688 -349.073329) (xy 45.741387 -349.056892) (xy 45.69113 -349.032693) (xy 45.645042 -349.001275)
			(xy 45.604152 -348.963338) (xy 45.569373 -348.91973) (xy 45.541482 -348.871425) (xy 45.521103 -348.819502)
			(xy 45.50869 -348.765123) (xy 45.504521 -348.7095) (xy 42.729138 -348.7095) (xy 42.385996 -349.052642)
			(xy 42.379147 -349.060048) (xy 42.371433 -349.078668) (xy 42.371532 -349.098823) (xy 42.375074 -349.108268)
			(xy 42.417492 -349.20936) (xy 42.443146 -349.226124) (xy 42.462196 -349.226124) (xy 42.489447 -349.226573)
			(xy 42.543395 -349.234329) (xy 42.595689 -349.249684) (xy 42.645267 -349.272324) (xy 42.691118 -349.301789)
			(xy 42.732308 -349.337479) (xy 42.768001 -349.378669) (xy 42.797468 -349.424518) (xy 42.82011 -349.474094)
			(xy 42.835467 -349.526388) (xy 42.843225 -349.580336) (xy 42.843227 -349.634838) (xy 42.835473 -349.688786)
			(xy 42.82012 -349.741081) (xy 42.797481 -349.790659) (xy 42.768017 -349.83651) (xy 42.732327 -349.877702)
			(xy 42.691139 -349.913395) (xy 42.64529 -349.942863) (xy 42.595714 -349.965507) (xy 42.543421 -349.980865)
			(xy 42.489474 -349.988625) (xy 42.434972 -349.988628) (xy 42.381024 -349.980875) (xy 42.328728 -349.965523)
			(xy 42.27915 -349.942885) (xy 42.233297 -349.913422) (xy 42.192105 -349.877734) (xy 42.156411 -349.836546)
			(xy 42.126941 -349.790698) (xy 42.104296 -349.741123) (xy 42.088937 -349.68883) (xy 42.081176 -349.634883)
			(xy 42.080688 -349.607632) (xy 42.081067 -349.584102) (xy 42.086885 -349.537401) (xy 42.098401 -349.49177)
			(xy 42.106596 -349.46971) (xy 42.109711 -349.460381) (xy 42.109422 -349.440733) (xy 42.101784 -349.422629)
			(xy 42.095166 -349.415354) (xy 42.094912 -349.415354) (xy 42.0875 -349.40867) (xy 42.069067 -349.401073)
			(xy 42.049129 -349.401073) (xy 42.030696 -349.40867) (xy 42.023284 -349.415354) (xy 41.924478 -349.513906)
			(xy 41.91764 -349.521307) (xy 41.909919 -349.539906) (xy 41.909492 -349.549974) (xy 41.909492 -350.05899)
			(xy 41.909898 -350.069062) (xy 41.91763 -350.087661) (xy 41.924478 -350.095058) (xy 41.948354 -350.11868)
			(xy 41.953331 -350.123322) (xy 41.965179 -350.130013) (xy 41.971722 -350.131888) (xy 41.971976 -350.132142)
			(xy 41.972484 -350.132142) (xy 41.999877 -350.13924) (xy 42.052329 -350.160472) (xy 42.101069 -350.18922)
			(xy 42.145026 -350.224855) (xy 42.183235 -350.266593) (xy 42.214857 -350.313519) (xy 42.239199 -350.364602)
			(xy 42.255726 -350.418722) (xy 42.264075 -350.474689) (xy 42.264584 -350.502982) (xy 42.264128 -350.530235)
			(xy 42.256373 -350.584188) (xy 42.241018 -350.636487) (xy 42.218376 -350.686069) (xy 42.188907 -350.731923)
			(xy 42.153213 -350.773117) (xy 42.112019 -350.808811) (xy 42.066164 -350.838278) (xy 42.016582 -350.86092)
			(xy 41.964282 -350.876274) (xy 41.91033 -350.884028) (xy 41.883076 -350.88449) (xy 41.854767 -350.884034)
			(xy 41.798769 -350.875684) (xy 41.744622 -350.859143) (xy 41.693518 -350.834773) (xy 41.646582 -350.803112)
			(xy 41.604845 -350.764856) (xy 41.569227 -350.720846) (xy 41.540511 -350.672052) (xy 41.519329 -350.619546)
			(xy 41.512236 -350.592136) (xy 41.512236 -350.591628) (xy 41.510276 -350.585079) (xy 41.503462 -350.573235)
			(xy 41.498774 -350.56826) (xy 41.366948 -350.436434) (xy 41.349678 -350.41842) (xy 41.320349 -350.37805)
			(xy 41.297697 -350.333589) (xy 41.282278 -350.286132) (xy 41.274473 -350.236847) (xy 41.273984 -350.211898)
			(xy 41.273984 -349.397066) (xy 41.274467 -349.372116) (xy 41.282284 -349.322833) (xy 41.297704 -349.275375)
			(xy 41.320348 -349.23091) (xy 41.349662 -349.190528) (xy 41.366948 -349.17253) (xy 41.609772 -348.929706)
			(xy 41.616683 -348.922069) (xy 41.624274 -348.902942) (xy 41.623767 -348.88237) (xy 41.619932 -348.87281)
			(xy 41.573958 -348.771464) (xy 41.546526 -348.755208) (xy 41.530778 -348.756478) (xy 41.503854 -348.757494)
			(xy 41.476601 -348.757065) (xy 41.42265 -348.749302) (xy 41.370354 -348.73394) (xy 41.320776 -348.711293)
			(xy 41.274925 -348.68182) (xy 41.233735 -348.646123) (xy 41.198044 -348.604927) (xy 41.168579 -348.559072)
			(xy 41.145939 -348.50949) (xy 41.130585 -348.457191) (xy 41.122831 -348.403239) (xy 41.122346 -348.375986)
			(xy 39.12866 -348.375986) (xy 39.103808 -348.448884) (xy 39.100616 -348.460369) (xy 39.103913 -348.483944)
			(xy 39.110158 -348.494096) (xy 39.110666 -348.494604) (xy 39.126771 -348.518304) (xy 39.152276 -348.569614)
			(xy 39.169637 -348.62422) (xy 39.178445 -348.680839) (xy 39.178992 -348.709488) (xy 39.178555 -348.736107)
			(xy 39.170979 -348.788802) (xy 39.155981 -348.839884) (xy 39.133866 -348.88831) (xy 39.105083 -348.933096)
			(xy 39.07022 -348.97333) (xy 39.029985 -349.008192) (xy 38.985198 -349.036973) (xy 38.93677 -349.059086)
			(xy 38.885689 -349.074082) (xy 38.832993 -349.081656) (xy 38.806374 -349.082106) (xy 38.779952 -349.081662)
			(xy 38.727636 -349.074208) (xy 38.676897 -349.05944) (xy 38.628753 -349.037653) (xy 38.584169 -349.009285)
			(xy 38.563804 -348.992444) (xy 38.556946 -348.986602) (xy 38.539928 -348.980252) (xy 38.4556 -348.980252)
			(xy 38.438582 -348.986602) (xy 38.431724 -348.992444) (xy 38.411358 -349.009283) (xy 38.366772 -349.037648)
			(xy 38.318628 -349.059435) (xy 38.267891 -349.074206) (xy 38.215576 -349.081666) (xy 38.162732 -349.081666)
			(xy 38.110417 -349.074206) (xy 38.05968 -349.059435) (xy 38.011536 -349.037648) (xy 37.96695 -349.009283)
			(xy 37.946584 -348.992444) (xy 37.939726 -348.986602) (xy 37.922708 -348.980252) (xy 37.83838 -348.980252)
			(xy 37.821362 -348.986602) (xy 37.814504 -348.992444) (xy 37.79413 -349.009272) (xy 37.749543 -349.03763)
			(xy 37.701401 -349.059412) (xy 37.650666 -349.074182) (xy 37.598354 -349.081644) (xy 37.571934 -349.082106)
			(xy 37.544045 -349.081637) (xy 37.488888 -349.073329) (xy 37.435587 -349.056892) (xy 37.38533 -349.032693)
			(xy 37.339242 -349.001275) (xy 37.298352 -348.963338) (xy 37.263573 -348.91973) (xy 37.235682 -348.871425)
			(xy 37.215303 -348.819502) (xy 37.20289 -348.765123) (xy 37.198721 -348.7095) (xy 34.372538 -348.7095)
			(xy 34.02584 -349.056198) (xy 34.018713 -349.063973) (xy 34.011015 -349.083591) (xy 34.011818 -349.10465)
			(xy 34.015934 -349.114364) (xy 34.064956 -349.215456) (xy 34.093658 -349.23095) (xy 34.109914 -349.228918)
			(xy 34.121299 -349.227615) (xy 34.144175 -349.226215) (xy 34.155634 -349.226124) (xy 34.156396 -349.226124)
			(xy 34.183647 -349.226573) (xy 34.237595 -349.234329) (xy 34.289889 -349.249684) (xy 34.339467 -349.272324)
			(xy 34.385318 -349.301789) (xy 34.426508 -349.337479) (xy 34.462201 -349.378669) (xy 34.491668 -349.424518)
			(xy 34.51431 -349.474094) (xy 34.529667 -349.526388) (xy 34.537425 -349.580336) (xy 34.537427 -349.634838)
			(xy 34.529673 -349.688786) (xy 34.51432 -349.741081) (xy 34.491681 -349.790659) (xy 34.462217 -349.83651)
			(xy 34.426527 -349.877702) (xy 34.385339 -349.913395) (xy 34.33949 -349.942863) (xy 34.289914 -349.965507)
			(xy 34.237621 -349.980865) (xy 34.183674 -349.988625) (xy 34.129172 -349.988628) (xy 34.075224 -349.980875)
			(xy 34.022928 -349.965523) (xy 33.97335 -349.942885) (xy 33.927497 -349.913422) (xy 33.886305 -349.877734)
			(xy 33.850611 -349.836546) (xy 33.821141 -349.790698) (xy 33.798496 -349.741123) (xy 33.783137 -349.68883)
			(xy 33.775376 -349.634883) (xy 33.774888 -349.607632) (xy 33.775437 -349.578581) (xy 33.784238 -349.521151)
			(xy 33.801657 -349.465722) (xy 33.82729 -349.413581) (xy 33.843468 -349.389446) (xy 33.848417 -349.381817)
			(xy 33.852986 -349.364226) (xy 33.851099 -349.34615) (xy 33.842997 -349.329881) (xy 33.83661 -349.323406)
			(xy 33.832038 -349.319342) (xy 33.824618 -349.312934) (xy 33.80634 -349.305878) (xy 33.786749 -349.306172)
			(xy 33.768691 -349.313771) (xy 33.761426 -349.320358) (xy 33.632902 -349.448882) (xy 33.626078 -349.456294)
			(xy 33.618349 -349.474884) (xy 33.617916 -349.48495) (xy 33.617916 -350.073214) (xy 33.61833 -350.083285)
			(xy 33.626058 -350.101882) (xy 33.632902 -350.109282) (xy 33.642554 -350.118934) (xy 33.647583 -350.123465)
			(xy 33.659413 -350.130031) (xy 33.665922 -350.131888) (xy 33.666176 -350.132142) (xy 33.666684 -350.132142)
			(xy 33.694077 -350.13924) (xy 33.746529 -350.160472) (xy 33.795269 -350.18922) (xy 33.839226 -350.224855)
			(xy 33.877435 -350.266593) (xy 33.909057 -350.313519) (xy 33.933399 -350.364602) (xy 33.949926 -350.418722)
			(xy 33.958275 -350.474689) (xy 33.958784 -350.502982) (xy 33.958328 -350.530235) (xy 33.950573 -350.584188)
			(xy 33.935218 -350.636487) (xy 33.912576 -350.686069) (xy 33.883107 -350.731923) (xy 33.847413 -350.773117)
			(xy 33.806219 -350.808811) (xy 33.760364 -350.838278) (xy 33.710782 -350.86092) (xy 33.658482 -350.876274)
			(xy 33.60453 -350.884028) (xy 33.577276 -350.88449) (xy 33.548967 -350.884034) (xy 33.492969 -350.875684)
			(xy 33.438822 -350.859143) (xy 33.387718 -350.834773) (xy 33.340782 -350.803112) (xy 33.299045 -350.764856)
			(xy 33.263427 -350.720846) (xy 33.234711 -350.672052) (xy 33.213529 -350.619546) (xy 33.206436 -350.592136)
			(xy 33.206436 -350.591628) (xy 33.204476 -350.585079) (xy 33.197662 -350.573235) (xy 33.192974 -350.56826)
			(xy 33.075372 -350.450658) (xy 33.05805 -350.43269) (xy 33.028723 -350.392309) (xy 33.006074 -350.347838)
			(xy 32.990662 -350.30037) (xy 32.982866 -350.251076) (xy 32.982408 -350.226122) (xy 32.982408 -349.332042)
			(xy 32.982869 -349.307091) (xy 32.99069 -349.257806) (xy 33.006115 -349.210349) (xy 33.028765 -349.165883)
			(xy 33.058083 -349.125503) (xy 33.075372 -349.107506) (xy 33.252156 -348.930722) (xy 33.258833 -348.923431)
			(xy 33.266506 -348.905228) (xy 33.266761 -348.885476) (xy 33.263586 -348.876112) (xy 33.22955 -348.789498)
			(xy 33.22555 -348.780458) (xy 33.211953 -348.766133) (xy 33.193938 -348.758037) (xy 33.184084 -348.75724)
			(xy 33.1575 -348.755856) (xy 33.10509 -348.746524) (xy 33.054486 -348.729998) (xy 33.006671 -348.706597)
			(xy 32.962573 -348.676776) (xy 32.923049 -348.641115) (xy 32.888865 -348.600306) (xy 32.860687 -348.555141)
			(xy 32.83906 -348.506498) (xy 32.824406 -348.455321) (xy 32.817007 -348.402603) (xy 32.816546 -348.375986)
			(xy 30.84993 -348.375986) (xy 30.81909 -348.458536) (xy 30.822646 -348.483428) (xy 30.830012 -348.493842)
			(xy 30.84618 -348.517552) (xy 30.871785 -348.568909) (xy 30.889211 -348.623585) (xy 30.898046 -348.680287)
			(xy 30.898592 -348.70898) (xy 30.898592 -348.709488) (xy 30.898155 -348.736107) (xy 30.890579 -348.788802)
			(xy 30.875581 -348.839884) (xy 30.853466 -348.88831) (xy 30.824683 -348.933096) (xy 30.78982 -348.97333)
			(xy 30.749585 -349.008192) (xy 30.704798 -349.036973) (xy 30.65637 -349.059086) (xy 30.605289 -349.074082)
			(xy 30.552593 -349.081656) (xy 30.525974 -349.082106) (xy 30.499552 -349.081662) (xy 30.447236 -349.074208)
			(xy 30.396497 -349.05944) (xy 30.348353 -349.037653) (xy 30.303769 -349.009285) (xy 30.283404 -348.992444)
			(xy 30.276546 -348.986602) (xy 30.259528 -348.980252) (xy 30.1752 -348.980252) (xy 30.158182 -348.986602)
			(xy 30.151324 -348.992444) (xy 30.130958 -349.009283) (xy 30.086372 -349.037648) (xy 30.038228 -349.059435)
			(xy 29.987491 -349.074206) (xy 29.935176 -349.081666) (xy 29.882332 -349.081666) (xy 29.830017 -349.074206)
			(xy 29.77928 -349.059435) (xy 29.731136 -349.037648) (xy 29.68655 -349.009283) (xy 29.666184 -348.992444)
			(xy 29.659326 -348.986602) (xy 29.642308 -348.980252) (xy 29.55798 -348.980252) (xy 29.540962 -348.986602)
			(xy 29.534104 -348.992444) (xy 29.51373 -349.009272) (xy 29.469143 -349.03763) (xy 29.421001 -349.059412)
			(xy 29.370266 -349.074182) (xy 29.317954 -349.081644) (xy 29.291534 -349.082106) (xy 29.263645 -349.081637)
			(xy 29.208488 -349.073329) (xy 29.155187 -349.056892) (xy 29.10493 -349.032693) (xy 29.058842 -349.001275)
			(xy 29.017952 -348.963338) (xy 28.983173 -348.91973) (xy 28.955282 -348.871425) (xy 28.934903 -348.819502)
			(xy 28.92249 -348.765123) (xy 28.918321 -348.7095) (xy 26.117538 -348.7095) (xy 25.77338 -349.053658)
			(xy 25.768197 -349.059296) (xy 25.761101 -349.072858) (xy 25.75941 -349.080328) (xy 25.758253 -349.087988)
			(xy 25.760075 -349.103365) (xy 25.762966 -349.110554) (xy 25.802082 -349.197168) (xy 25.807951 -349.208379)
			(xy 25.82807 -349.223678) (xy 25.840436 -349.226378) (xy 25.851612 -349.226886) (xy 25.851866 -349.226886)
			(xy 25.875996 -349.226124) (xy 25.901544 -349.226532) (xy 25.952183 -349.233347) (xy 26.001461 -349.246855)
			(xy 26.048496 -349.266815) (xy 26.092449 -349.292871) (xy 26.112724 -349.30842) (xy 26.134891 -349.326617)
			(xy 26.174032 -349.368534) (xy 26.206455 -349.415839) (xy 26.231429 -349.467466) (xy 26.248391 -349.52225)
			(xy 26.256959 -349.578957) (xy 26.257504 -349.607632) (xy 26.257016 -349.634882) (xy 26.249256 -349.688826)
			(xy 26.233898 -349.741116) (xy 26.211255 -349.790689) (xy 26.181788 -349.836535) (xy 26.146096 -349.877722)
			(xy 26.104907 -349.913409) (xy 26.059058 -349.942872) (xy 26.009483 -349.96551) (xy 25.95719 -349.980863)
			(xy 25.903246 -349.988619) (xy 25.875996 -349.98914) (xy 25.84732 -349.988624) (xy 25.790614 -349.980042)
			(xy 25.735831 -349.963071) (xy 25.684203 -349.938093) (xy 25.636895 -349.905672) (xy 25.59497 -349.866537)
			(xy 25.576784 -349.84436) (xy 25.561265 -349.824093) (xy 25.535208 -349.780198) (xy 25.51524 -349.733219)
			(xy 25.501718 -349.683996) (xy 25.494883 -349.633409) (xy 25.494488 -349.607886) (xy 25.494488 -349.607632)
			(xy 25.49525 -349.583502) (xy 25.49525 -349.576644) (xy 25.494233 -349.567794) (xy 25.486988 -349.551535)
			(xy 25.474638 -349.538715) (xy 25.466802 -349.53448) (xy 25.40254 -349.50527) (xy 25.378918 -349.494602)
			(xy 25.369331 -349.49081) (xy 25.348738 -349.490389) (xy 25.329618 -349.498049) (xy 25.322022 -349.505016)
			(xy 25.312878 -349.51416) (xy 25.30729 -349.520764) (xy 25.304101 -349.525483) (xy 25.299729 -349.535999)
			(xy 25.298654 -349.541592) (xy 25.297892 -349.550228) (xy 25.297892 -350.033336) (xy 25.298654 -350.041972)
			(xy 25.29978 -350.047551) (xy 25.304137 -350.058062) (xy 25.30729 -350.0628) (xy 25.312878 -350.069404)
			(xy 25.362154 -350.11868) (xy 25.364729 -350.121191) (xy 25.370462 -350.125531) (xy 25.373584 -350.127316)
			(xy 25.379172 -350.130364) (xy 25.38603 -350.132142) (xy 25.41344 -350.139235) (xy 25.465946 -350.160416)
			(xy 25.514741 -350.189132) (xy 25.55875 -350.22475) (xy 25.597007 -350.266487) (xy 25.628668 -350.313424)
			(xy 25.653037 -350.364528) (xy 25.669578 -350.418675) (xy 25.677927 -350.474673) (xy 25.678384 -350.502982)
			(xy 25.677922 -350.530235) (xy 25.670167 -350.584187) (xy 25.654812 -350.636485) (xy 25.63217 -350.686066)
			(xy 25.602702 -350.73192) (xy 25.567008 -350.773113) (xy 25.525815 -350.808806) (xy 25.479961 -350.838273)
			(xy 25.43038 -350.860914) (xy 25.378081 -350.876268) (xy 25.324129 -350.884022) (xy 25.296876 -350.88449)
			(xy 25.268576 -350.883966) (xy 25.212599 -350.875585) (xy 25.158475 -350.859025) (xy 25.107392 -350.83465)
			(xy 25.060471 -350.802995) (xy 25.018742 -350.764755) (xy 24.983121 -350.720768) (xy 24.95439 -350.672002)
			(xy 24.93318 -350.619525) (xy 24.926036 -350.592136) (xy 24.924258 -350.585278) (xy 24.92121 -350.57969)
			(xy 24.919415 -350.576574) (xy 24.915087 -350.570832) (xy 24.912574 -350.56826) (xy 24.755348 -350.411034)
			(xy 24.738064 -350.393036) (xy 24.708755 -350.352653) (xy 24.686115 -350.308187) (xy 24.670701 -350.260729)
			(xy 24.66289 -350.211447) (xy 24.662384 -350.186498) (xy 24.662384 -349.39732) (xy 24.662638 -349.383858)
			(xy 24.662892 -349.37319) (xy 24.659082 -349.363538) (xy 24.657052 -349.358668) (xy 24.651288 -349.349834)
			(xy 24.647652 -349.346012) (xy 24.640469 -349.339389) (xy 24.622534 -349.33168) (xy 24.603017 -349.331261)
			(xy 24.584768 -349.338194) (xy 24.577294 -349.344488) (xy 24.571198 -349.350584) (xy 24.568545 -349.353505)
			(xy 24.564084 -349.360014) (xy 24.562308 -349.363538) (xy 24.178768 -350.289368) (xy 24.176228 -350.302068)
			(xy 24.175974 -350.305878) (xy 24.175974 -351.178622) (xy 26.253694 -351.178622) (xy 26.254195 -351.151148)
			(xy 26.262083 -351.096769) (xy 26.2777 -351.044087) (xy 26.300722 -350.994194) (xy 26.33067 -350.948124)
			(xy 26.348436 -350.927162) (xy 26.34869 -350.926908) (xy 26.354278 -350.919823) (xy 26.360524 -350.902905)
			(xy 26.360882 -350.893888) (xy 26.360882 -350.826324) (xy 26.360517 -350.817308) (xy 26.354275 -350.800391)
			(xy 26.34869 -350.793304) (xy 26.348182 -350.792796) (xy 26.330448 -350.77185) (xy 26.300566 -350.725817)
			(xy 26.2776 -350.675972) (xy 26.262026 -350.623347) (xy 26.254165 -350.569031) (xy 26.253694 -350.54159)
			(xy 26.25418 -350.514339) (xy 26.261936 -350.460391) (xy 26.277291 -350.408096) (xy 26.299933 -350.358519)
			(xy 26.329399 -350.312669) (xy 26.36509 -350.271478) (xy 26.406281 -350.235787) (xy 26.452131 -350.206321)
			(xy 26.501708 -350.183679) (xy 26.554003 -350.168324) (xy 26.607951 -350.160568) (xy 26.662453 -350.160568)
			(xy 26.716401 -350.168324) (xy 26.768696 -350.183679) (xy 26.818273 -350.206321) (xy 26.864123 -350.235787)
			(xy 26.905314 -350.271478) (xy 26.941005 -350.312669) (xy 26.970471 -350.358519) (xy 26.993113 -350.408096)
			(xy 27.008468 -350.460391) (xy 27.016224 -350.514339) (xy 27.01671 -350.54159) (xy 27.016215 -350.569064)
			(xy 27.008325 -350.623443) (xy 26.992707 -350.676126) (xy 26.969684 -350.726018) (xy 26.939734 -350.772088)
			(xy 26.921968 -350.79305) (xy 26.921714 -350.793304) (xy 26.916121 -350.800386) (xy 26.909878 -350.817306)
			(xy 26.909522 -350.826324) (xy 26.909522 -350.893888) (xy 26.90988 -350.902905) (xy 26.916126 -350.919822)
			(xy 26.921714 -350.926908) (xy 26.922222 -350.927416) (xy 26.939962 -350.948356) (xy 26.969843 -350.994391)
			(xy 26.992808 -351.044238) (xy 27.008381 -351.096864) (xy 27.01624 -351.151181) (xy 27.01671 -351.178622)
			(xy 27.016224 -351.205873) (xy 27.008468 -351.259821) (xy 26.993113 -351.312116) (xy 26.970471 -351.361693)
			(xy 26.941005 -351.407543) (xy 26.905314 -351.448734) (xy 26.864123 -351.484425) (xy 26.818273 -351.513891)
			(xy 26.768696 -351.536533) (xy 26.716401 -351.551888) (xy 26.662453 -351.559644) (xy 26.607951 -351.559644)
			(xy 26.554003 -351.551888) (xy 26.501708 -351.536533) (xy 26.452131 -351.513891) (xy 26.406281 -351.484425)
			(xy 26.36509 -351.448734) (xy 26.329399 -351.407543) (xy 26.299933 -351.361693) (xy 26.277291 -351.312116)
			(xy 26.261936 -351.259821) (xy 26.25418 -351.205873) (xy 26.253694 -351.178622) (xy 24.175974 -351.178622)
			(xy 24.175974 -352.021648) (xy 24.394666 -352.021648) (xy 24.398737 -351.966026) (xy 24.410863 -351.911589)
			(xy 24.430786 -351.859498) (xy 24.458082 -351.810863) (xy 24.492168 -351.76672) (xy 24.532317 -351.728011)
			(xy 24.577675 -351.69556) (xy 24.627275 -351.670059) (xy 24.680059 -351.652052) (xy 24.734902 -351.641922)
			(xy 24.790636 -351.639885) (xy 24.846073 -351.645985) (xy 24.90003 -351.660091) (xy 24.951359 -351.681903)
			(xy 24.998965 -351.710957) (xy 25.041833 -351.746632) (xy 25.07905 -351.788169) (xy 25.109823 -351.834682)
			(xy 25.133495 -351.885179) (xy 25.149563 -351.938586) (xy 25.157683 -351.993762) (xy 25.158192 -352.021648)
			(xy 25.157683 -352.049534) (xy 25.149563 -352.10471) (xy 25.133495 -352.158117) (xy 25.109823 -352.208614)
			(xy 25.07905 -352.255127) (xy 25.041833 -352.296664) (xy 24.998965 -352.332339) (xy 24.951359 -352.361393)
			(xy 24.90003 -352.383205) (xy 24.846073 -352.397311) (xy 24.790636 -352.403411) (xy 24.734902 -352.401374)
			(xy 24.680059 -352.391244) (xy 24.627275 -352.373237) (xy 24.577675 -352.347736) (xy 24.532317 -352.315285)
			(xy 24.492168 -352.276576) (xy 24.458082 -352.232433) (xy 24.430786 -352.183798) (xy 24.410863 -352.131707)
			(xy 24.398737 -352.07727) (xy 24.394666 -352.021648) (xy 24.175974 -352.021648) (xy 24.175974 -354.02012)
			(xy 24.146256 -354.049838) (xy 24.137366 -354.049838) (xy 22.09292 -356.094284) (xy 22.086813 -356.100924)
			(xy 22.079294 -356.117309) (xy 22.077902 -356.135284) (xy 22.079966 -356.144068) (xy 22.10816 -356.242874)
			(xy 22.127718 -356.26167) (xy 22.141434 -356.264972) (xy 22.168966 -356.27199) (xy 22.221727 -356.293064)
			(xy 22.270781 -356.321729) (xy 22.315042 -356.357349) (xy 22.353532 -356.399139) (xy 22.385401 -356.446175)
			(xy 22.409943 -356.497415) (xy 22.426616 -356.551728) (xy 22.435052 -356.607913) (xy 22.435566 -356.63632)
			(xy 22.435101 -356.663571) (xy 22.427342 -356.717517) (xy 22.411984 -356.76981) (xy 22.389339 -356.819385)
			(xy 22.35987 -356.865233) (xy 22.324176 -356.90642) (xy 22.282983 -356.942107) (xy 22.237131 -356.971569)
			(xy 22.187552 -356.994205) (xy 22.135257 -357.009555) (xy 22.081309 -357.017306) (xy 22.054058 -357.017828)
			(xy 22.025649 -357.017309) (xy 21.969457 -357.008889) (xy 21.915137 -356.992227) (xy 21.863889 -356.967691)
			(xy 21.816848 -356.935824) (xy 21.775054 -356.897331) (xy 21.739433 -356.853065) (xy 21.710773 -356.804004)
			(xy 21.689708 -356.751235) (xy 21.68271 -356.723696) (xy 21.679408 -356.70998) (xy 21.660612 -356.690422)
			(xy 21.561806 -356.662228) (xy 21.553028 -356.660077) (xy 21.535018 -356.661439) (xy 21.518618 -356.669006)
			(xy 21.512022 -356.675182) (xy 20.83689 -357.350314) (xy 20.830036 -357.357709) (xy 20.822292 -357.376308)
			(xy 20.821904 -357.386382) (xy 20.821904 -357.632) (xy 23.239982 -357.632) (xy 23.244053 -357.576378)
			(xy 23.256179 -357.521941) (xy 23.276102 -357.46985) (xy 23.303398 -357.421215) (xy 23.337484 -357.377072)
			(xy 23.377633 -357.338363) (xy 23.422991 -357.305912) (xy 23.472591 -357.280411) (xy 23.525375 -357.262404)
			(xy 23.580218 -357.252274) (xy 23.635952 -357.250237) (xy 23.691389 -357.256337) (xy 23.745346 -357.270443)
			(xy 23.796675 -357.292255) (xy 23.844281 -357.321309) (xy 23.887149 -357.356984) (xy 23.924366 -357.398521)
			(xy 23.955139 -357.445034) (xy 23.978811 -357.495531) (xy 23.994879 -357.548938) (xy 24.002999 -357.604114)
			(xy 24.003508 -357.632) (xy 24.002999 -357.659886) (xy 23.994879 -357.715062) (xy 23.978811 -357.768469)
			(xy 23.955139 -357.818966) (xy 23.924366 -357.865479) (xy 23.887149 -357.907016) (xy 23.844281 -357.942691)
			(xy 23.796675 -357.971745) (xy 23.745346 -357.993557) (xy 23.691389 -358.007663) (xy 23.635952 -358.013763)
			(xy 23.580218 -358.011726) (xy 23.525375 -358.001596) (xy 23.472591 -357.983589) (xy 23.422991 -357.958088)
			(xy 23.377633 -357.925637) (xy 23.337484 -357.886928) (xy 23.303398 -357.842785) (xy 23.276102 -357.79415)
			(xy 23.256179 -357.742059) (xy 23.244053 -357.687622) (xy 23.239982 -357.632) (xy 20.821904 -357.632)
			(xy 20.821904 -358.775) (xy 23.257508 -358.775) (xy 23.261579 -358.719378) (xy 23.273705 -358.664941)
			(xy 23.293628 -358.61285) (xy 23.320924 -358.564215) (xy 23.35501 -358.520072) (xy 23.395159 -358.481363)
			(xy 23.440517 -358.448912) (xy 23.490117 -358.423411) (xy 23.542901 -358.405404) (xy 23.597744 -358.395274)
			(xy 23.653478 -358.393237) (xy 23.708915 -358.399337) (xy 23.762872 -358.413443) (xy 23.814201 -358.435255)
			(xy 23.861807 -358.464309) (xy 23.904675 -358.499984) (xy 23.941892 -358.541521) (xy 23.972665 -358.588034)
			(xy 23.996337 -358.638531) (xy 24.012405 -358.691938) (xy 24.017115 -358.723946) (xy 25.856692 -358.723946)
			(xy 25.856692 -353.811078) (xy 25.857295 -353.78608) (xy 25.867106 -353.737055) (xy 25.886289 -353.690884)
			(xy 25.914107 -353.64934) (xy 25.931368 -353.631246) (xy 27.370278 -352.192336) (xy 27.377092 -352.184915)
			(xy 27.384828 -352.166332) (xy 27.385264 -352.156268) (xy 27.385264 -350.96069) (xy 27.384853 -350.950619)
			(xy 27.377123 -350.932021) (xy 27.370278 -350.924622) (xy 27.349405 -350.903029) (xy 27.314014 -350.854511)
			(xy 27.286666 -350.801045) (xy 27.268038 -350.743953) (xy 27.25859 -350.684647) (xy 27.25801 -350.65462)
			(xy 27.258474 -350.627367) (xy 27.266229 -350.573415) (xy 27.281583 -350.521116) (xy 27.304225 -350.471535)
			(xy 27.333692 -350.425681) (xy 27.369386 -350.384487) (xy 27.410579 -350.348793) (xy 27.456433 -350.319326)
			(xy 27.506014 -350.296684) (xy 27.558313 -350.281329) (xy 27.612265 -350.273574) (xy 27.639518 -350.273112)
			(xy 27.639772 -350.273112) (xy 27.664975 -350.273528) (xy 27.714942 -350.280163) (xy 27.763597 -350.293335)
			(xy 27.810087 -350.312813) (xy 27.83205 -350.325182) (xy 27.841956 -350.331024) (xy 27.8638 -350.333056)
			(xy 27.958542 -350.299528) (xy 27.97429 -350.284034) (xy 27.978354 -350.27362) (xy 27.989083 -350.246857)
			(xy 28.017365 -350.196615) (xy 28.052889 -350.151205) (xy 28.094846 -350.111661) (xy 28.142279 -350.078885)
			(xy 28.194106 -350.053625) (xy 28.249145 -350.036457) (xy 28.306142 -350.027771) (xy 28.33497 -350.02724)
			(xy 28.362224 -350.027683) (xy 28.416178 -350.035437) (xy 28.46848 -350.050792) (xy 28.518063 -350.073435)
			(xy 28.563918 -350.102904) (xy 28.605113 -350.1386) (xy 28.640807 -350.179796) (xy 28.670274 -350.225653)
			(xy 28.692914 -350.275237) (xy 28.705636 -350.318578) (xy 30.846522 -350.318578) (xy 30.847034 -350.291005)
			(xy 30.854976 -350.236434) (xy 30.870691 -350.183575) (xy 30.893852 -350.133528) (xy 30.923977 -350.087337)
			(xy 30.960438 -350.045965) (xy 30.981142 -350.027748) (xy 30.989203 -350.02018) (xy 30.998563 -350.000178)
			(xy 30.999176 -349.98914) (xy 30.999176 -349.911416) (xy 30.998607 -349.900367) (xy 30.989243 -349.880345)
			(xy 30.981142 -349.872808) (xy 30.96044 -349.854587) (xy 30.923967 -349.813221) (xy 30.893833 -349.767034)
			(xy 30.870665 -349.716988) (xy 30.854947 -349.664126) (xy 30.847007 -349.609552) (xy 30.846522 -349.581978)
			(xy 30.846934 -349.554723) (xy 30.854695 -349.500769) (xy 30.870056 -349.448468) (xy 30.892703 -349.398886)
			(xy 30.922176 -349.353031) (xy 30.957875 -349.311838) (xy 30.999073 -349.276145) (xy 31.044932 -349.246678)
			(xy 31.094517 -349.224037) (xy 31.14682 -349.208684) (xy 31.200775 -349.200931) (xy 31.22803 -349.20047)
			(xy 31.228538 -349.20047) (xy 31.26232 -349.201994) (xy 31.27248 -349.20301) (xy 31.291784 -349.196914)
			(xy 31.354776 -349.144082) (xy 31.362049 -349.137342) (xy 31.371341 -349.11985) (xy 31.37281 -349.110046)
			(xy 31.37281 -349.109284) (xy 31.375762 -349.081135) (xy 31.388956 -349.026097) (xy 31.410141 -348.973613)
			(xy 31.438849 -348.924837) (xy 31.474452 -348.88084) (xy 31.516166 -348.842588) (xy 31.563076 -348.810921)
			(xy 31.614151 -348.786535) (xy 31.668269 -348.769966) (xy 31.724241 -348.761577) (xy 31.75254 -348.76105)
			(xy 31.752794 -348.76105) (xy 31.770813 -348.761277) (xy 31.806688 -348.764707) (xy 31.824422 -348.767908)
			(xy 31.834074 -348.769686) (xy 31.853124 -348.76613) (xy 31.928054 -348.718124) (xy 31.939484 -348.702376)
			(xy 31.94177 -348.692978) (xy 31.949225 -348.665951) (xy 31.970848 -348.614227) (xy 31.999805 -348.566223)
			(xy 32.035473 -348.522971) (xy 32.077085 -348.485403) (xy 32.123745 -348.454326) (xy 32.174449 -348.43041)
			(xy 32.228107 -348.414169) (xy 32.283563 -348.405952) (xy 32.311594 -348.40545) (xy 32.338843 -348.405983)
			(xy 32.392787 -348.413738) (xy 32.445078 -348.42909) (xy 32.494653 -348.451727) (xy 32.540501 -348.481189)
			(xy 32.58169 -348.516876) (xy 32.617382 -348.55806) (xy 32.64685 -348.603905) (xy 32.669493 -348.653477)
			(xy 32.684852 -348.705766) (xy 32.692613 -348.759709) (xy 32.693102 -348.786958) (xy 32.692607 -348.814531)
			(xy 32.68466 -348.869103) (xy 32.668941 -348.921962) (xy 32.645776 -348.972008) (xy 32.615649 -349.018199)
			(xy 32.579187 -349.059571) (xy 32.558482 -349.077788) (xy 32.550409 -349.085345) (xy 32.541054 -349.105355)
			(xy 32.540448 -349.116396) (xy 32.540448 -349.19412) (xy 32.541045 -349.205166) (xy 32.550388 -349.225188)
			(xy 32.558482 -349.232728) (xy 32.579206 -349.250925) (xy 32.615676 -349.292296) (xy 32.645807 -349.338489)
			(xy 32.668971 -349.38854) (xy 32.684684 -349.441405) (xy 32.692619 -349.495982) (xy 32.693102 -349.523558)
			(xy 32.692607 -349.551131) (xy 32.68466 -349.605703) (xy 32.668941 -349.658562) (xy 32.645776 -349.708608)
			(xy 32.615649 -349.754799) (xy 32.579187 -349.796171) (xy 32.558482 -349.814388) (xy 32.550409 -349.821945)
			(xy 32.541054 -349.841955) (xy 32.540448 -349.852996) (xy 32.540448 -349.93072) (xy 32.541045 -349.941766)
			(xy 32.550388 -349.961788) (xy 32.558482 -349.969328) (xy 32.579206 -349.987525) (xy 32.615676 -350.028896)
			(xy 32.645807 -350.075089) (xy 32.668971 -350.12514) (xy 32.684684 -350.178005) (xy 32.692619 -350.232582)
			(xy 32.693102 -350.260158) (xy 32.692606 -350.28741) (xy 32.684854 -350.34136) (xy 32.669503 -350.393658)
			(xy 32.646865 -350.443238) (xy 32.617401 -350.489092) (xy 32.581711 -350.530285) (xy 32.540521 -350.565979)
			(xy 32.49467 -350.595448) (xy 32.445092 -350.618091) (xy 32.392795 -350.633447) (xy 32.338846 -350.641203)
			(xy 32.311594 -350.641666) (xy 32.283737 -350.641174) (xy 32.228619 -350.633048) (xy 32.175267 -350.617)
			(xy 32.124813 -350.59337) (xy 32.078327 -350.56266) (xy 32.036798 -350.52552) (xy 32.001106 -350.482741)
			(xy 31.972009 -350.435229) (xy 31.950124 -350.383993) (xy 31.942532 -350.357186) (xy 31.940246 -350.348296)
			(xy 31.929578 -350.333056) (xy 31.857696 -350.285304) (xy 31.839662 -350.28124) (xy 31.830518 -350.28251)
			(xy 31.817501 -350.284175) (xy 31.791317 -350.285958) (xy 31.778194 -350.286066) (xy 31.764045 -350.285973)
			(xy 31.735822 -350.283938) (xy 31.721806 -350.282002) (xy 31.7119 -350.280478) (xy 31.692088 -350.285304)
			(xy 31.617666 -350.341184) (xy 31.607506 -350.35871) (xy 31.606236 -350.36887) (xy 31.60215 -350.396023)
			(xy 31.587174 -350.448852) (xy 31.564781 -350.498989) (xy 31.535432 -350.545399) (xy 31.499735 -350.587122)
			(xy 31.458425 -350.623298) (xy 31.412357 -350.653179) (xy 31.362481 -350.676149) (xy 31.309828 -350.691732)
			(xy 31.255485 -350.699607) (xy 31.22803 -350.700086) (xy 31.200777 -350.699617) (xy 31.146825 -350.691863)
			(xy 31.094526 -350.67651) (xy 31.044944 -350.653869) (xy 30.99909 -350.624402) (xy 30.957897 -350.588709)
			(xy 30.922202 -350.547516) (xy 30.892735 -350.501663) (xy 30.870093 -350.452082) (xy 30.854738 -350.399783)
			(xy 30.846984 -350.345831) (xy 30.846522 -350.318578) (xy 28.705636 -350.318578) (xy 28.708266 -350.327539)
			(xy 28.716018 -350.381494) (xy 28.716478 -350.408748) (xy 28.715825 -350.440311) (xy 28.705435 -350.502577)
			(xy 28.684947 -350.562286) (xy 28.670504 -350.590358) (xy 28.665678 -350.599248) (xy 28.663646 -350.618806)
			(xy 28.686506 -350.697292) (xy 28.689755 -350.706712) (xy 28.702165 -350.722273) (xy 28.710636 -350.727518)
			(xy 28.735715 -350.742104) (xy 28.7816 -350.777599) (xy 28.821578 -350.819635) (xy 28.854727 -350.867242)
			(xy 28.880282 -350.919322) (xy 28.897652 -350.974672) (xy 28.906437 -351.032014) (xy 28.906978 -351.06102)
			(xy 28.906492 -351.088271) (xy 28.898736 -351.142219) (xy 28.888047 -351.178622) (xy 34.534094 -351.178622)
			(xy 34.534595 -351.151148) (xy 34.542483 -351.096769) (xy 34.5581 -351.044087) (xy 34.581122 -350.994194)
			(xy 34.61107 -350.948124) (xy 34.628836 -350.927162) (xy 34.62909 -350.926908) (xy 34.634678 -350.919823)
			(xy 34.640924 -350.902905) (xy 34.641282 -350.893888) (xy 34.641282 -350.826324) (xy 34.640917 -350.817308)
			(xy 34.634675 -350.800391) (xy 34.62909 -350.793304) (xy 34.628582 -350.792796) (xy 34.610848 -350.77185)
			(xy 34.580966 -350.725817) (xy 34.558 -350.675972) (xy 34.542426 -350.623347) (xy 34.534565 -350.569031)
			(xy 34.534094 -350.54159) (xy 34.53458 -350.514339) (xy 34.542336 -350.460391) (xy 34.557691 -350.408096)
			(xy 34.580333 -350.358519) (xy 34.609799 -350.312669) (xy 34.64549 -350.271478) (xy 34.686681 -350.235787)
			(xy 34.732531 -350.206321) (xy 34.782108 -350.183679) (xy 34.834403 -350.168324) (xy 34.888351 -350.160568)
			(xy 34.942853 -350.160568) (xy 34.996801 -350.168324) (xy 35.049096 -350.183679) (xy 35.098673 -350.206321)
			(xy 35.144523 -350.235787) (xy 35.185714 -350.271478) (xy 35.221405 -350.312669) (xy 35.250871 -350.358519)
			(xy 35.273513 -350.408096) (xy 35.288868 -350.460391) (xy 35.296624 -350.514339) (xy 35.29711 -350.54159)
			(xy 35.296615 -350.569064) (xy 35.288725 -350.623443) (xy 35.273107 -350.676126) (xy 35.250084 -350.726018)
			(xy 35.220134 -350.772088) (xy 35.202368 -350.79305) (xy 35.202114 -350.793304) (xy 35.196521 -350.800386)
			(xy 35.190278 -350.817306) (xy 35.189922 -350.826324) (xy 35.189922 -350.893888) (xy 35.19028 -350.902905)
			(xy 35.196526 -350.919822) (xy 35.202114 -350.926908) (xy 35.202622 -350.927416) (xy 35.220362 -350.948356)
			(xy 35.250243 -350.994391) (xy 35.273208 -351.044238) (xy 35.288781 -351.096864) (xy 35.29664 -351.151181)
			(xy 35.29711 -351.178622) (xy 35.296624 -351.205873) (xy 35.288868 -351.259821) (xy 35.273513 -351.312116)
			(xy 35.250871 -351.361693) (xy 35.221405 -351.407543) (xy 35.185714 -351.448734) (xy 35.144523 -351.484425)
			(xy 35.098673 -351.513891) (xy 35.049096 -351.536533) (xy 34.996801 -351.551888) (xy 34.942853 -351.559644)
			(xy 34.888351 -351.559644) (xy 34.834403 -351.551888) (xy 34.782108 -351.536533) (xy 34.732531 -351.513891)
			(xy 34.686681 -351.484425) (xy 34.64549 -351.448734) (xy 34.609799 -351.407543) (xy 34.580333 -351.361693)
			(xy 34.557691 -351.312116) (xy 34.542336 -351.259821) (xy 34.53458 -351.205873) (xy 34.534094 -351.178622)
			(xy 28.888047 -351.178622) (xy 28.883381 -351.194514) (xy 28.860739 -351.244091) (xy 28.831273 -351.289941)
			(xy 28.795582 -351.331132) (xy 28.754391 -351.366823) (xy 28.708541 -351.396289) (xy 28.658964 -351.418931)
			(xy 28.606669 -351.434286) (xy 28.552721 -351.442042) (xy 28.498219 -351.442042) (xy 28.444271 -351.434286)
			(xy 28.391976 -351.418931) (xy 28.342399 -351.396289) (xy 28.296549 -351.366823) (xy 28.255358 -351.331132)
			(xy 28.219667 -351.289941) (xy 28.190201 -351.244091) (xy 28.167559 -351.194514) (xy 28.152204 -351.142219)
			(xy 28.144448 -351.088271) (xy 28.143962 -351.06102) (xy 28.14461 -351.029457) (xy 28.155003 -350.967191)
			(xy 28.175493 -350.907483) (xy 28.189936 -350.87941) (xy 28.194762 -350.87052) (xy 28.196794 -350.850962)
			(xy 28.173934 -350.772476) (xy 28.170719 -350.763041) (xy 28.158286 -350.747487) (xy 28.149804 -350.74225)
			(xy 28.142438 -350.738186) (xy 28.132532 -350.732344) (xy 28.110688 -350.730312) (xy 28.015946 -350.76384)
			(xy 28.000198 -350.779334) (xy 27.996134 -350.789748) (xy 27.986137 -350.814832) (xy 27.960057 -350.862115)
			(xy 27.927558 -350.905239) (xy 27.908758 -350.924622) (xy 27.90191 -350.932016) (xy 27.894196 -350.95062)
			(xy 27.893772 -350.96069) (xy 27.893772 -352.156268) (xy 27.894195 -352.166338) (xy 27.901915 -352.184937)
			(xy 27.908758 -352.192336) (xy 28.268422 -352.551746) (xy 28.275815 -352.558595) (xy 28.29442 -352.566308)
			(xy 28.30449 -352.566732) (xy 35.048698 -352.566732) (xy 35.058769 -352.566323) (xy 35.077368 -352.558593)
			(xy 35.084766 -352.551746) (xy 35.661854 -351.974912) (xy 35.668675 -351.967496) (xy 35.676407 -351.948909)
			(xy 35.67684 -351.938844) (xy 35.67684 -350.971612) (xy 35.676377 -350.961087) (xy 35.667964 -350.941794)
			(xy 35.660584 -350.934274) (xy 35.641645 -350.916198) (xy 35.608463 -350.875699) (xy 35.581138 -350.831039)
			(xy 35.560183 -350.78306) (xy 35.545994 -350.732663) (xy 35.538838 -350.680798) (xy 35.53841 -350.65462)
			(xy 35.538874 -350.627367) (xy 35.546629 -350.573415) (xy 35.561983 -350.521116) (xy 35.584625 -350.471535)
			(xy 35.614092 -350.425681) (xy 35.649786 -350.384487) (xy 35.690979 -350.348793) (xy 35.736833 -350.319326)
			(xy 35.786414 -350.296684) (xy 35.838713 -350.281329) (xy 35.892665 -350.273574) (xy 35.919918 -350.273112)
			(xy 35.920172 -350.273112) (xy 35.945375 -350.273528) (xy 35.995342 -350.280163) (xy 36.043997 -350.293335)
			(xy 36.090487 -350.312813) (xy 36.11245 -350.325182) (xy 36.122356 -350.331024) (xy 36.1442 -350.333056)
			(xy 36.238942 -350.299528) (xy 36.25469 -350.284034) (xy 36.258754 -350.27362) (xy 36.269483 -350.246857)
			(xy 36.297765 -350.196615) (xy 36.333289 -350.151205) (xy 36.375246 -350.111661) (xy 36.422679 -350.078885)
			(xy 36.474506 -350.053625) (xy 36.529545 -350.036457) (xy 36.586542 -350.027771) (xy 36.61537 -350.02724)
			(xy 36.642624 -350.027683) (xy 36.696578 -350.035437) (xy 36.74888 -350.050792) (xy 36.798463 -350.073435)
			(xy 36.844318 -350.102904) (xy 36.885513 -350.1386) (xy 36.921207 -350.179796) (xy 36.950674 -350.225653)
			(xy 36.973314 -350.275237) (xy 36.986036 -350.318578) (xy 39.126922 -350.318578) (xy 39.127434 -350.291005)
			(xy 39.135376 -350.236434) (xy 39.151091 -350.183575) (xy 39.174252 -350.133528) (xy 39.204377 -350.087337)
			(xy 39.240838 -350.045965) (xy 39.261542 -350.027748) (xy 39.269603 -350.02018) (xy 39.278963 -350.000178)
			(xy 39.279576 -349.98914) (xy 39.279576 -349.911416) (xy 39.279007 -349.900367) (xy 39.269643 -349.880345)
			(xy 39.261542 -349.872808) (xy 39.24084 -349.854587) (xy 39.204367 -349.813221) (xy 39.174233 -349.767034)
			(xy 39.151065 -349.716988) (xy 39.135347 -349.664126) (xy 39.127407 -349.609552) (xy 39.126922 -349.581978)
			(xy 39.127334 -349.554723) (xy 39.135095 -349.500769) (xy 39.150456 -349.448468) (xy 39.173103 -349.398886)
			(xy 39.202576 -349.353031) (xy 39.238275 -349.311838) (xy 39.279473 -349.276145) (xy 39.325332 -349.246678)
			(xy 39.374917 -349.224037) (xy 39.42722 -349.208684) (xy 39.481175 -349.200931) (xy 39.50843 -349.20047)
			(xy 39.508938 -349.20047) (xy 39.54272 -349.201994) (xy 39.55288 -349.20301) (xy 39.572184 -349.196914)
			(xy 39.635176 -349.144082) (xy 39.642449 -349.137342) (xy 39.651741 -349.11985) (xy 39.65321 -349.110046)
			(xy 39.65321 -349.109284) (xy 39.656162 -349.081135) (xy 39.669356 -349.026097) (xy 39.690541 -348.973613)
			(xy 39.719249 -348.924837) (xy 39.754852 -348.88084) (xy 39.796566 -348.842588) (xy 39.843476 -348.810921)
			(xy 39.894551 -348.786535) (xy 39.948669 -348.769966) (xy 40.004641 -348.761577) (xy 40.03294 -348.76105)
			(xy 40.033194 -348.76105) (xy 40.051213 -348.761277) (xy 40.087088 -348.764707) (xy 40.104822 -348.767908)
			(xy 40.114474 -348.769686) (xy 40.133524 -348.76613) (xy 40.208454 -348.718124) (xy 40.219884 -348.702376)
			(xy 40.22217 -348.692978) (xy 40.229625 -348.665951) (xy 40.251248 -348.614227) (xy 40.280205 -348.566223)
			(xy 40.315873 -348.522971) (xy 40.357485 -348.485403) (xy 40.404145 -348.454326) (xy 40.454849 -348.43041)
			(xy 40.508507 -348.414169) (xy 40.563963 -348.405952) (xy 40.591994 -348.40545) (xy 40.619243 -348.405983)
			(xy 40.673187 -348.413738) (xy 40.725478 -348.42909) (xy 40.775053 -348.451727) (xy 40.820901 -348.481189)
			(xy 40.86209 -348.516876) (xy 40.897782 -348.55806) (xy 40.92725 -348.603905) (xy 40.949893 -348.653477)
			(xy 40.965252 -348.705766) (xy 40.973013 -348.759709) (xy 40.973502 -348.786958) (xy 40.973007 -348.814531)
			(xy 40.96506 -348.869103) (xy 40.949341 -348.921962) (xy 40.926176 -348.972008) (xy 40.896049 -349.018199)
			(xy 40.859587 -349.059571) (xy 40.838882 -349.077788) (xy 40.830809 -349.085345) (xy 40.821454 -349.105355)
			(xy 40.820848 -349.116396) (xy 40.820848 -349.19412) (xy 40.821445 -349.205166) (xy 40.830788 -349.225188)
			(xy 40.838882 -349.232728) (xy 40.859606 -349.250925) (xy 40.896076 -349.292296) (xy 40.926207 -349.338489)
			(xy 40.949371 -349.38854) (xy 40.965084 -349.441405) (xy 40.973019 -349.495982) (xy 40.973502 -349.523558)
			(xy 40.973007 -349.551131) (xy 40.96506 -349.605703) (xy 40.949341 -349.658562) (xy 40.926176 -349.708608)
			(xy 40.896049 -349.754799) (xy 40.859587 -349.796171) (xy 40.838882 -349.814388) (xy 40.830809 -349.821945)
			(xy 40.821454 -349.841955) (xy 40.820848 -349.852996) (xy 40.820848 -349.93072) (xy 40.821445 -349.941766)
			(xy 40.830788 -349.961788) (xy 40.838882 -349.969328) (xy 40.859606 -349.987525) (xy 40.896076 -350.028896)
			(xy 40.926207 -350.075089) (xy 40.949371 -350.12514) (xy 40.965084 -350.178005) (xy 40.973019 -350.232582)
			(xy 40.973502 -350.260158) (xy 40.973006 -350.28741) (xy 40.965254 -350.34136) (xy 40.949903 -350.393658)
			(xy 40.927265 -350.443238) (xy 40.897801 -350.489092) (xy 40.862111 -350.530285) (xy 40.820921 -350.565979)
			(xy 40.77507 -350.595448) (xy 40.725492 -350.618091) (xy 40.673195 -350.633447) (xy 40.619246 -350.641203)
			(xy 40.591994 -350.641666) (xy 40.564137 -350.641174) (xy 40.509019 -350.633048) (xy 40.455667 -350.617)
			(xy 40.405213 -350.59337) (xy 40.358727 -350.56266) (xy 40.317198 -350.52552) (xy 40.281506 -350.482741)
			(xy 40.252409 -350.435229) (xy 40.230524 -350.383993) (xy 40.222932 -350.357186) (xy 40.220646 -350.348296)
			(xy 40.209978 -350.333056) (xy 40.138096 -350.285304) (xy 40.120062 -350.28124) (xy 40.110918 -350.28251)
			(xy 40.097901 -350.284175) (xy 40.071717 -350.285958) (xy 40.058594 -350.286066) (xy 40.044445 -350.285973)
			(xy 40.016222 -350.283938) (xy 40.002206 -350.282002) (xy 39.9923 -350.280478) (xy 39.972488 -350.285304)
			(xy 39.898066 -350.341184) (xy 39.887906 -350.35871) (xy 39.886636 -350.36887) (xy 39.88255 -350.396023)
			(xy 39.867574 -350.448852) (xy 39.845181 -350.498989) (xy 39.815832 -350.545399) (xy 39.780135 -350.587122)
			(xy 39.738825 -350.623298) (xy 39.692757 -350.653179) (xy 39.642881 -350.676149) (xy 39.590228 -350.691732)
			(xy 39.535885 -350.699607) (xy 39.50843 -350.700086) (xy 39.481177 -350.699617) (xy 39.427225 -350.691863)
			(xy 39.374926 -350.67651) (xy 39.325344 -350.653869) (xy 39.27949 -350.624402) (xy 39.238297 -350.588709)
			(xy 39.202602 -350.547516) (xy 39.173135 -350.501663) (xy 39.150493 -350.452082) (xy 39.135138 -350.399783)
			(xy 39.127384 -350.345831) (xy 39.126922 -350.318578) (xy 36.986036 -350.318578) (xy 36.988666 -350.327539)
			(xy 36.996418 -350.381494) (xy 36.996878 -350.408748) (xy 36.996225 -350.440311) (xy 36.985835 -350.502577)
			(xy 36.965347 -350.562286) (xy 36.950904 -350.590358) (xy 36.946078 -350.599248) (xy 36.944046 -350.618806)
			(xy 36.966906 -350.697292) (xy 36.970155 -350.706712) (xy 36.982565 -350.722273) (xy 36.991036 -350.727518)
			(xy 37.016115 -350.742104) (xy 37.062 -350.777599) (xy 37.101978 -350.819635) (xy 37.135127 -350.867242)
			(xy 37.160682 -350.919322) (xy 37.178052 -350.974672) (xy 37.186837 -351.032014) (xy 37.187378 -351.06102)
			(xy 37.186892 -351.088271) (xy 37.179136 -351.142219) (xy 37.168447 -351.178622) (xy 42.839894 -351.178622)
			(xy 42.840395 -351.151148) (xy 42.848283 -351.096769) (xy 42.8639 -351.044087) (xy 42.886922 -350.994194)
			(xy 42.91687 -350.948124) (xy 42.934636 -350.927162) (xy 42.93489 -350.926908) (xy 42.940478 -350.919823)
			(xy 42.946724 -350.902905) (xy 42.947082 -350.893888) (xy 42.947082 -350.826324) (xy 42.946717 -350.817308)
			(xy 42.940475 -350.800391) (xy 42.93489 -350.793304) (xy 42.934382 -350.792796) (xy 42.916648 -350.77185)
			(xy 42.886766 -350.725817) (xy 42.8638 -350.675972) (xy 42.848226 -350.623347) (xy 42.840365 -350.569031)
			(xy 42.839894 -350.54159) (xy 42.84038 -350.514339) (xy 42.848136 -350.460391) (xy 42.863491 -350.408096)
			(xy 42.886133 -350.358519) (xy 42.915599 -350.312669) (xy 42.95129 -350.271478) (xy 42.992481 -350.235787)
			(xy 43.038331 -350.206321) (xy 43.087908 -350.183679) (xy 43.140203 -350.168324) (xy 43.194151 -350.160568)
			(xy 43.248653 -350.160568) (xy 43.302601 -350.168324) (xy 43.354896 -350.183679) (xy 43.404473 -350.206321)
			(xy 43.450323 -350.235787) (xy 43.491514 -350.271478) (xy 43.527205 -350.312669) (xy 43.556671 -350.358519)
			(xy 43.579313 -350.408096) (xy 43.594668 -350.460391) (xy 43.602424 -350.514339) (xy 43.60291 -350.54159)
			(xy 43.602415 -350.569064) (xy 43.594525 -350.623443) (xy 43.578907 -350.676126) (xy 43.555884 -350.726018)
			(xy 43.525934 -350.772088) (xy 43.508168 -350.79305) (xy 43.507914 -350.793304) (xy 43.502321 -350.800386)
			(xy 43.496078 -350.817306) (xy 43.495722 -350.826324) (xy 43.495722 -350.893888) (xy 43.49608 -350.902905)
			(xy 43.502326 -350.919822) (xy 43.507914 -350.926908) (xy 43.508422 -350.927416) (xy 43.526162 -350.948356)
			(xy 43.556043 -350.994391) (xy 43.579008 -351.044238) (xy 43.594581 -351.096864) (xy 43.60244 -351.151181)
			(xy 43.60291 -351.178622) (xy 43.602424 -351.205873) (xy 43.594668 -351.259821) (xy 43.579313 -351.312116)
			(xy 43.556671 -351.361693) (xy 43.527205 -351.407543) (xy 43.491514 -351.448734) (xy 43.450323 -351.484425)
			(xy 43.404473 -351.513891) (xy 43.354896 -351.536533) (xy 43.302601 -351.551888) (xy 43.248653 -351.559644)
			(xy 43.194151 -351.559644) (xy 43.140203 -351.551888) (xy 43.087908 -351.536533) (xy 43.038331 -351.513891)
			(xy 42.992481 -351.484425) (xy 42.95129 -351.448734) (xy 42.915599 -351.407543) (xy 42.886133 -351.361693)
			(xy 42.863491 -351.312116) (xy 42.848136 -351.259821) (xy 42.84038 -351.205873) (xy 42.839894 -351.178622)
			(xy 37.168447 -351.178622) (xy 37.163781 -351.194514) (xy 37.141139 -351.244091) (xy 37.111673 -351.289941)
			(xy 37.075982 -351.331132) (xy 37.034791 -351.366823) (xy 36.988941 -351.396289) (xy 36.939364 -351.418931)
			(xy 36.887069 -351.434286) (xy 36.833121 -351.442042) (xy 36.778619 -351.442042) (xy 36.724671 -351.434286)
			(xy 36.672376 -351.418931) (xy 36.622799 -351.396289) (xy 36.576949 -351.366823) (xy 36.535758 -351.331132)
			(xy 36.500067 -351.289941) (xy 36.470601 -351.244091) (xy 36.447959 -351.194514) (xy 36.432604 -351.142219)
			(xy 36.424848 -351.088271) (xy 36.424362 -351.06102) (xy 36.42501 -351.029457) (xy 36.435403 -350.967191)
			(xy 36.455893 -350.907483) (xy 36.470336 -350.87941) (xy 36.475162 -350.87052) (xy 36.477194 -350.850962)
			(xy 36.454334 -350.772476) (xy 36.451119 -350.763041) (xy 36.438686 -350.747487) (xy 36.430204 -350.74225)
			(xy 36.422838 -350.738186) (xy 36.412932 -350.732344) (xy 36.391088 -350.730312) (xy 36.296346 -350.76384)
			(xy 36.280598 -350.779334) (xy 36.276534 -350.789748) (xy 36.267437 -350.812642) (xy 36.244202 -350.856083)
			(xy 36.215563 -350.896168) (xy 36.199064 -350.914462) (xy 36.1928 -350.921762) (xy 36.185757 -350.939649)
			(xy 36.185348 -350.94926) (xy 36.185348 -351.938844) (xy 36.185738 -351.948917) (xy 36.193482 -351.967516)
			(xy 36.200334 -351.974912) (xy 36.739322 -352.513646) (xy 36.746715 -352.520495) (xy 36.76532 -352.528208)
			(xy 36.77539 -352.528632) (xy 43.443398 -352.528632) (xy 43.453469 -352.528223) (xy 43.472068 -352.520493)
			(xy 43.479466 -352.513646) (xy 43.956478 -352.036888) (xy 43.963313 -352.029484) (xy 43.971036 -352.010888)
			(xy 43.971464 -352.00082) (xy 43.971464 -350.96069) (xy 43.971053 -350.950619) (xy 43.963323 -350.932021)
			(xy 43.956478 -350.924622) (xy 43.935605 -350.903029) (xy 43.900214 -350.854511) (xy 43.872866 -350.801045)
			(xy 43.854238 -350.743953) (xy 43.84479 -350.684647) (xy 43.84421 -350.65462) (xy 43.844674 -350.627367)
			(xy 43.852429 -350.573415) (xy 43.867783 -350.521116) (xy 43.890425 -350.471535) (xy 43.919892 -350.425681)
			(xy 43.955586 -350.384487) (xy 43.996779 -350.348793) (xy 44.042633 -350.319326) (xy 44.092214 -350.296684)
			(xy 44.144513 -350.281329) (xy 44.198465 -350.273574) (xy 44.225718 -350.273112) (xy 44.225972 -350.273112)
			(xy 44.251175 -350.273528) (xy 44.301142 -350.280163) (xy 44.349797 -350.293335) (xy 44.396287 -350.312813)
			(xy 44.41825 -350.325182) (xy 44.428156 -350.331024) (xy 44.45 -350.333056) (xy 44.544742 -350.299528)
			(xy 44.56049 -350.284034) (xy 44.564554 -350.27362) (xy 44.575283 -350.246857) (xy 44.603565 -350.196615)
			(xy 44.639089 -350.151205) (xy 44.681046 -350.111661) (xy 44.728479 -350.078885) (xy 44.780306 -350.053625)
			(xy 44.835345 -350.036457) (xy 44.892342 -350.027771) (xy 44.92117 -350.02724) (xy 44.948424 -350.027683)
			(xy 45.002378 -350.035437) (xy 45.05468 -350.050792) (xy 45.104263 -350.073435) (xy 45.150118 -350.102904)
			(xy 45.191313 -350.1386) (xy 45.227007 -350.179796) (xy 45.256474 -350.225653) (xy 45.279114 -350.275237)
			(xy 45.291836 -350.318578) (xy 47.432722 -350.318578) (xy 47.433234 -350.291005) (xy 47.441176 -350.236434)
			(xy 47.456891 -350.183575) (xy 47.480052 -350.133528) (xy 47.510177 -350.087337) (xy 47.546638 -350.045965)
			(xy 47.567342 -350.027748) (xy 47.575403 -350.02018) (xy 47.584763 -350.000178) (xy 47.585376 -349.98914)
			(xy 47.585376 -349.911416) (xy 47.584807 -349.900367) (xy 47.575443 -349.880345) (xy 47.567342 -349.872808)
			(xy 47.54664 -349.854587) (xy 47.510167 -349.813221) (xy 47.480033 -349.767034) (xy 47.456865 -349.716988)
			(xy 47.441147 -349.664126) (xy 47.433207 -349.609552) (xy 47.432722 -349.581978) (xy 47.433134 -349.554723)
			(xy 47.440895 -349.500769) (xy 47.456256 -349.448468) (xy 47.478903 -349.398886) (xy 47.508376 -349.353031)
			(xy 47.544075 -349.311838) (xy 47.585273 -349.276145) (xy 47.631132 -349.246678) (xy 47.680717 -349.224037)
			(xy 47.73302 -349.208684) (xy 47.786975 -349.200931) (xy 47.81423 -349.20047) (xy 47.814738 -349.20047)
			(xy 47.84852 -349.201994) (xy 47.85868 -349.20301) (xy 47.877984 -349.196914) (xy 47.940976 -349.144082)
			(xy 47.948249 -349.137342) (xy 47.957541 -349.11985) (xy 47.95901 -349.110046) (xy 47.95901 -349.109284)
			(xy 47.961962 -349.081135) (xy 47.975156 -349.026097) (xy 47.996341 -348.973613) (xy 48.025049 -348.924837)
			(xy 48.060652 -348.88084) (xy 48.102366 -348.842588) (xy 48.149276 -348.810921) (xy 48.200351 -348.786535)
			(xy 48.254469 -348.769966) (xy 48.310441 -348.761577) (xy 48.33874 -348.76105) (xy 48.338994 -348.76105)
			(xy 48.357013 -348.761277) (xy 48.392888 -348.764707) (xy 48.410622 -348.767908) (xy 48.420274 -348.769686)
			(xy 48.439324 -348.76613) (xy 48.514254 -348.718124) (xy 48.525684 -348.702376) (xy 48.52797 -348.692978)
			(xy 48.535425 -348.665951) (xy 48.557048 -348.614227) (xy 48.586005 -348.566223) (xy 48.621673 -348.522971)
			(xy 48.663285 -348.485403) (xy 48.709945 -348.454326) (xy 48.760649 -348.43041) (xy 48.814307 -348.414169)
			(xy 48.869763 -348.405952) (xy 48.897794 -348.40545) (xy 48.925043 -348.405983) (xy 48.978987 -348.413738)
			(xy 49.031278 -348.42909) (xy 49.080853 -348.451727) (xy 49.126701 -348.481189) (xy 49.16789 -348.516876)
			(xy 49.203582 -348.55806) (xy 49.23305 -348.603905) (xy 49.255693 -348.653477) (xy 49.271052 -348.705766)
			(xy 49.278813 -348.759709) (xy 49.279302 -348.786958) (xy 49.278807 -348.814531) (xy 49.27086 -348.869103)
			(xy 49.255141 -348.921962) (xy 49.231976 -348.972008) (xy 49.201849 -349.018199) (xy 49.165387 -349.059571)
			(xy 49.144682 -349.077788) (xy 49.136609 -349.085345) (xy 49.127254 -349.105355) (xy 49.126648 -349.116396)
			(xy 49.126648 -349.19412) (xy 49.127245 -349.205166) (xy 49.136588 -349.225188) (xy 49.144682 -349.232728)
			(xy 49.165406 -349.250925) (xy 49.201876 -349.292296) (xy 49.232007 -349.338489) (xy 49.255171 -349.38854)
			(xy 49.270884 -349.441405) (xy 49.278819 -349.495982) (xy 49.279302 -349.523558) (xy 49.278807 -349.551131)
			(xy 49.27086 -349.605703) (xy 49.255141 -349.658562) (xy 49.231976 -349.708608) (xy 49.201849 -349.754799)
			(xy 49.165387 -349.796171) (xy 49.144682 -349.814388) (xy 49.136609 -349.821945) (xy 49.127254 -349.841955)
			(xy 49.126648 -349.852996) (xy 49.126648 -349.93072) (xy 49.127245 -349.941766) (xy 49.136588 -349.961788)
			(xy 49.144682 -349.969328) (xy 49.165406 -349.987525) (xy 49.201876 -350.028896) (xy 49.232007 -350.075089)
			(xy 49.255171 -350.12514) (xy 49.270884 -350.178005) (xy 49.278819 -350.232582) (xy 49.279302 -350.260158)
			(xy 49.278806 -350.28741) (xy 49.271054 -350.34136) (xy 49.255703 -350.393658) (xy 49.233065 -350.443238)
			(xy 49.203601 -350.489092) (xy 49.167911 -350.530285) (xy 49.126721 -350.565979) (xy 49.08087 -350.595448)
			(xy 49.031292 -350.618091) (xy 48.978995 -350.633447) (xy 48.925046 -350.641203) (xy 48.897794 -350.641666)
			(xy 48.869937 -350.641174) (xy 48.814819 -350.633048) (xy 48.761467 -350.617) (xy 48.711013 -350.59337)
			(xy 48.664527 -350.56266) (xy 48.622998 -350.52552) (xy 48.587306 -350.482741) (xy 48.558209 -350.435229)
			(xy 48.536324 -350.383993) (xy 48.528732 -350.357186) (xy 48.526446 -350.348296) (xy 48.515778 -350.333056)
			(xy 48.443896 -350.285304) (xy 48.425862 -350.28124) (xy 48.416718 -350.28251) (xy 48.403701 -350.284175)
			(xy 48.377517 -350.285958) (xy 48.364394 -350.286066) (xy 48.350245 -350.285973) (xy 48.322022 -350.283938)
			(xy 48.308006 -350.282002) (xy 48.2981 -350.280478) (xy 48.278288 -350.285304) (xy 48.203866 -350.341184)
			(xy 48.193706 -350.35871) (xy 48.192436 -350.36887) (xy 48.18835 -350.396023) (xy 48.173374 -350.448852)
			(xy 48.150981 -350.498989) (xy 48.121632 -350.545399) (xy 48.085935 -350.587122) (xy 48.044625 -350.623298)
			(xy 47.998557 -350.653179) (xy 47.948681 -350.676149) (xy 47.896028 -350.691732) (xy 47.841685 -350.699607)
			(xy 47.81423 -350.700086) (xy 47.786977 -350.699617) (xy 47.733025 -350.691863) (xy 47.680726 -350.67651)
			(xy 47.631144 -350.653869) (xy 47.58529 -350.624402) (xy 47.544097 -350.588709) (xy 47.508402 -350.547516)
			(xy 47.478935 -350.501663) (xy 47.456293 -350.452082) (xy 47.440938 -350.399783) (xy 47.433184 -350.345831)
			(xy 47.432722 -350.318578) (xy 45.291836 -350.318578) (xy 45.294466 -350.327539) (xy 45.302218 -350.381494)
			(xy 45.302678 -350.408748) (xy 45.302025 -350.440311) (xy 45.291635 -350.502577) (xy 45.271147 -350.562286)
			(xy 45.256704 -350.590358) (xy 45.251878 -350.599248) (xy 45.249846 -350.618806) (xy 45.272706 -350.697292)
			(xy 45.275955 -350.706712) (xy 45.288365 -350.722273) (xy 45.296836 -350.727518) (xy 45.321915 -350.742104)
			(xy 45.3678 -350.777599) (xy 45.407778 -350.819635) (xy 45.440927 -350.867242) (xy 45.466482 -350.919322)
			(xy 45.483852 -350.974672) (xy 45.492637 -351.032014) (xy 45.493178 -351.06102) (xy 45.492692 -351.088271)
			(xy 45.484936 -351.142219) (xy 45.474247 -351.178622) (xy 51.196494 -351.178622) (xy 51.196995 -351.151148)
			(xy 51.204883 -351.096769) (xy 51.2205 -351.044087) (xy 51.243522 -350.994194) (xy 51.27347 -350.948124)
			(xy 51.291236 -350.927162) (xy 51.29149 -350.926908) (xy 51.297078 -350.919823) (xy 51.303324 -350.902905)
			(xy 51.303682 -350.893888) (xy 51.303682 -350.826324) (xy 51.303317 -350.817308) (xy 51.297075 -350.800391)
			(xy 51.29149 -350.793304) (xy 51.290982 -350.792796) (xy 51.273248 -350.77185) (xy 51.243366 -350.725817)
			(xy 51.2204 -350.675972) (xy 51.204826 -350.623347) (xy 51.196965 -350.569031) (xy 51.196494 -350.54159)
			(xy 51.19698 -350.514339) (xy 51.204736 -350.460391) (xy 51.220091 -350.408096) (xy 51.242733 -350.358519)
			(xy 51.272199 -350.312669) (xy 51.30789 -350.271478) (xy 51.349081 -350.235787) (xy 51.394931 -350.206321)
			(xy 51.444508 -350.183679) (xy 51.496803 -350.168324) (xy 51.550751 -350.160568) (xy 51.605253 -350.160568)
			(xy 51.659201 -350.168324) (xy 51.711496 -350.183679) (xy 51.761073 -350.206321) (xy 51.806923 -350.235787)
			(xy 51.848114 -350.271478) (xy 51.883805 -350.312669) (xy 51.913271 -350.358519) (xy 51.935913 -350.408096)
			(xy 51.951268 -350.460391) (xy 51.959024 -350.514339) (xy 51.95951 -350.54159) (xy 51.959015 -350.569064)
			(xy 51.951125 -350.623443) (xy 51.935507 -350.676126) (xy 51.912484 -350.726018) (xy 51.882534 -350.772088)
			(xy 51.864768 -350.79305) (xy 51.864514 -350.793304) (xy 51.858921 -350.800386) (xy 51.852678 -350.817306)
			(xy 51.852322 -350.826324) (xy 51.852322 -350.893888) (xy 51.85268 -350.902905) (xy 51.858926 -350.919822)
			(xy 51.864514 -350.926908) (xy 51.865022 -350.927416) (xy 51.882762 -350.948356) (xy 51.912643 -350.994391)
			(xy 51.935608 -351.044238) (xy 51.951181 -351.096864) (xy 51.95904 -351.151181) (xy 51.95951 -351.178622)
			(xy 51.959024 -351.205873) (xy 51.951268 -351.259821) (xy 51.935913 -351.312116) (xy 51.913271 -351.361693)
			(xy 51.883805 -351.407543) (xy 51.848114 -351.448734) (xy 51.806923 -351.484425) (xy 51.761073 -351.513891)
			(xy 51.711496 -351.536533) (xy 51.659201 -351.551888) (xy 51.605253 -351.559644) (xy 51.550751 -351.559644)
			(xy 51.496803 -351.551888) (xy 51.444508 -351.536533) (xy 51.394931 -351.513891) (xy 51.349081 -351.484425)
			(xy 51.30789 -351.448734) (xy 51.272199 -351.407543) (xy 51.242733 -351.361693) (xy 51.220091 -351.312116)
			(xy 51.204736 -351.259821) (xy 51.19698 -351.205873) (xy 51.196494 -351.178622) (xy 45.474247 -351.178622)
			(xy 45.469581 -351.194514) (xy 45.446939 -351.244091) (xy 45.417473 -351.289941) (xy 45.381782 -351.331132)
			(xy 45.340591 -351.366823) (xy 45.294741 -351.396289) (xy 45.245164 -351.418931) (xy 45.192869 -351.434286)
			(xy 45.138921 -351.442042) (xy 45.084419 -351.442042) (xy 45.030471 -351.434286) (xy 44.978176 -351.418931)
			(xy 44.928599 -351.396289) (xy 44.882749 -351.366823) (xy 44.841558 -351.331132) (xy 44.805867 -351.289941)
			(xy 44.776401 -351.244091) (xy 44.753759 -351.194514) (xy 44.738404 -351.142219) (xy 44.730648 -351.088271)
			(xy 44.730162 -351.06102) (xy 44.73081 -351.029457) (xy 44.741203 -350.967191) (xy 44.761693 -350.907483)
			(xy 44.776136 -350.87941) (xy 44.780962 -350.87052) (xy 44.782994 -350.850962) (xy 44.760134 -350.772476)
			(xy 44.756919 -350.763041) (xy 44.744486 -350.747487) (xy 44.736004 -350.74225) (xy 44.728638 -350.738186)
			(xy 44.718732 -350.732344) (xy 44.696888 -350.730312) (xy 44.602146 -350.76384) (xy 44.586398 -350.779334)
			(xy 44.582334 -350.789748) (xy 44.572337 -350.814832) (xy 44.546257 -350.862115) (xy 44.513758 -350.905239)
			(xy 44.494958 -350.924622) (xy 44.48811 -350.932016) (xy 44.480396 -350.95062) (xy 44.479972 -350.96069)
			(xy 44.479972 -352.00082) (xy 44.480368 -352.010893) (xy 44.488107 -352.029492) (xy 44.494958 -352.036888)
			(xy 44.93006 -352.47199) (xy 44.937481 -352.478804) (xy 44.956064 -352.486539) (xy 44.966128 -352.486976)
			(xy 51.700684 -352.486976) (xy 51.710753 -352.486549) (xy 51.729351 -352.47883) (xy 51.736752 -352.47199)
			(xy 52.313078 -351.895664) (xy 52.319923 -351.888268) (xy 52.327641 -351.869666) (xy 52.328064 -351.859596)
			(xy 52.328064 -350.96069) (xy 52.327653 -350.950619) (xy 52.319923 -350.932021) (xy 52.313078 -350.924622)
			(xy 52.292205 -350.903029) (xy 52.256814 -350.854511) (xy 52.229466 -350.801045) (xy 52.210838 -350.743953)
			(xy 52.20139 -350.684647) (xy 52.20081 -350.65462) (xy 52.201274 -350.627367) (xy 52.209029 -350.573415)
			(xy 52.224383 -350.521116) (xy 52.247025 -350.471535) (xy 52.276492 -350.425681) (xy 52.312186 -350.384487)
			(xy 52.353379 -350.348793) (xy 52.399233 -350.319326) (xy 52.448814 -350.296684) (xy 52.501113 -350.281329)
			(xy 52.555065 -350.273574) (xy 52.582318 -350.273112) (xy 52.582572 -350.273112) (xy 52.607775 -350.273528)
			(xy 52.657742 -350.280163) (xy 52.706397 -350.293335) (xy 52.752887 -350.312813) (xy 52.77485 -350.325182)
			(xy 52.784756 -350.331024) (xy 52.8066 -350.333056) (xy 52.901342 -350.299528) (xy 52.91709 -350.284034)
			(xy 52.921154 -350.27362) (xy 52.931883 -350.246857) (xy 52.960165 -350.196615) (xy 52.995689 -350.151205)
			(xy 53.037646 -350.111661) (xy 53.085079 -350.078885) (xy 53.136906 -350.053625) (xy 53.191945 -350.036457)
			(xy 53.248942 -350.027771) (xy 53.27777 -350.02724) (xy 53.305024 -350.027683) (xy 53.358978 -350.035437)
			(xy 53.41128 -350.050792) (xy 53.460863 -350.073435) (xy 53.506718 -350.102904) (xy 53.547913 -350.1386)
			(xy 53.583607 -350.179796) (xy 53.613074 -350.225653) (xy 53.635714 -350.275237) (xy 53.648436 -350.318578)
			(xy 55.789322 -350.318578) (xy 55.789834 -350.291005) (xy 55.797776 -350.236434) (xy 55.813491 -350.183575)
			(xy 55.836652 -350.133528) (xy 55.866777 -350.087337) (xy 55.903238 -350.045965) (xy 55.923942 -350.027748)
			(xy 55.932003 -350.02018) (xy 55.941363 -350.000178) (xy 55.941976 -349.98914) (xy 55.941976 -349.911416)
			(xy 55.941407 -349.900367) (xy 55.932043 -349.880345) (xy 55.923942 -349.872808) (xy 55.90324 -349.854587)
			(xy 55.866767 -349.813221) (xy 55.836633 -349.767034) (xy 55.813465 -349.716988) (xy 55.797747 -349.664126)
			(xy 55.789807 -349.609552) (xy 55.789322 -349.581978) (xy 55.789734 -349.554723) (xy 55.797495 -349.500769)
			(xy 55.812856 -349.448468) (xy 55.835503 -349.398886) (xy 55.864976 -349.353031) (xy 55.900675 -349.311838)
			(xy 55.941873 -349.276145) (xy 55.987732 -349.246678) (xy 56.037317 -349.224037) (xy 56.08962 -349.208684)
			(xy 56.143575 -349.200931) (xy 56.17083 -349.20047) (xy 56.171338 -349.20047) (xy 56.20512 -349.201994)
			(xy 56.21528 -349.20301) (xy 56.234584 -349.196914) (xy 56.297576 -349.144082) (xy 56.304849 -349.137342)
			(xy 56.314141 -349.11985) (xy 56.31561 -349.110046) (xy 56.31561 -349.109284) (xy 56.318562 -349.081135)
			(xy 56.331756 -349.026097) (xy 56.352941 -348.973613) (xy 56.381649 -348.924837) (xy 56.417252 -348.88084)
			(xy 56.458966 -348.842588) (xy 56.505876 -348.810921) (xy 56.556951 -348.786535) (xy 56.611069 -348.769966)
			(xy 56.667041 -348.761577) (xy 56.69534 -348.76105) (xy 56.695594 -348.76105) (xy 56.713613 -348.761277)
			(xy 56.749488 -348.764707) (xy 56.767222 -348.767908) (xy 56.776874 -348.769686) (xy 56.795924 -348.76613)
			(xy 56.870854 -348.718124) (xy 56.882284 -348.702376) (xy 56.88457 -348.692978) (xy 56.892025 -348.665951)
			(xy 56.913648 -348.614227) (xy 56.942605 -348.566223) (xy 56.978273 -348.522971) (xy 57.019885 -348.485403)
			(xy 57.066545 -348.454326) (xy 57.117249 -348.43041) (xy 57.170907 -348.414169) (xy 57.226363 -348.405952)
			(xy 57.254394 -348.40545) (xy 57.281643 -348.405983) (xy 57.335587 -348.413738) (xy 57.387878 -348.42909)
			(xy 57.437453 -348.451727) (xy 57.483301 -348.481189) (xy 57.52449 -348.516876) (xy 57.560182 -348.55806)
			(xy 57.58965 -348.603905) (xy 57.612293 -348.653477) (xy 57.627652 -348.705766) (xy 57.635413 -348.759709)
			(xy 57.635902 -348.786958) (xy 57.635407 -348.814531) (xy 57.62746 -348.869103) (xy 57.611741 -348.921962)
			(xy 57.588576 -348.972008) (xy 57.558449 -349.018199) (xy 57.521987 -349.059571) (xy 57.501282 -349.077788)
			(xy 57.493209 -349.085345) (xy 57.483854 -349.105355) (xy 57.483248 -349.116396) (xy 57.483248 -349.19412)
			(xy 57.483845 -349.205166) (xy 57.493188 -349.225188) (xy 57.501282 -349.232728) (xy 57.522006 -349.250925)
			(xy 57.558476 -349.292296) (xy 57.588607 -349.338489) (xy 57.611771 -349.38854) (xy 57.627484 -349.441405)
			(xy 57.635419 -349.495982) (xy 57.635902 -349.523558) (xy 57.635407 -349.551131) (xy 57.62746 -349.605703)
			(xy 57.611741 -349.658562) (xy 57.588576 -349.708608) (xy 57.558449 -349.754799) (xy 57.521987 -349.796171)
			(xy 57.501282 -349.814388) (xy 57.493209 -349.821945) (xy 57.483854 -349.841955) (xy 57.483248 -349.852996)
			(xy 57.483248 -349.93072) (xy 57.483845 -349.941766) (xy 57.493188 -349.961788) (xy 57.501282 -349.969328)
			(xy 57.522006 -349.987525) (xy 57.558476 -350.028896) (xy 57.588607 -350.075089) (xy 57.611771 -350.12514)
			(xy 57.627484 -350.178005) (xy 57.635419 -350.232582) (xy 57.635902 -350.260158) (xy 57.635406 -350.28741)
			(xy 57.627654 -350.34136) (xy 57.612303 -350.393658) (xy 57.589665 -350.443238) (xy 57.560201 -350.489092)
			(xy 57.524511 -350.530285) (xy 57.483321 -350.565979) (xy 57.43747 -350.595448) (xy 57.387892 -350.618091)
			(xy 57.335595 -350.633447) (xy 57.281646 -350.641203) (xy 57.254394 -350.641666) (xy 57.226537 -350.641174)
			(xy 57.171419 -350.633048) (xy 57.118067 -350.617) (xy 57.067613 -350.59337) (xy 57.021127 -350.56266)
			(xy 56.979598 -350.52552) (xy 56.943906 -350.482741) (xy 56.914809 -350.435229) (xy 56.892924 -350.383993)
			(xy 56.885332 -350.357186) (xy 56.883046 -350.348296) (xy 56.872378 -350.333056) (xy 56.800496 -350.285304)
			(xy 56.782462 -350.28124) (xy 56.773318 -350.28251) (xy 56.760301 -350.284175) (xy 56.734117 -350.285958)
			(xy 56.720994 -350.286066) (xy 56.706845 -350.285973) (xy 56.678622 -350.283938) (xy 56.664606 -350.282002)
			(xy 56.6547 -350.280478) (xy 56.634888 -350.285304) (xy 56.560466 -350.341184) (xy 56.550306 -350.35871)
			(xy 56.549036 -350.36887) (xy 56.54495 -350.396023) (xy 56.529974 -350.448852) (xy 56.507581 -350.498989)
			(xy 56.478232 -350.545399) (xy 56.442535 -350.587122) (xy 56.401225 -350.623298) (xy 56.355157 -350.653179)
			(xy 56.305281 -350.676149) (xy 56.252628 -350.691732) (xy 56.198285 -350.699607) (xy 56.17083 -350.700086)
			(xy 56.143577 -350.699617) (xy 56.089625 -350.691863) (xy 56.037326 -350.67651) (xy 55.987744 -350.653869)
			(xy 55.94189 -350.624402) (xy 55.900697 -350.588709) (xy 55.865002 -350.547516) (xy 55.835535 -350.501663)
			(xy 55.812893 -350.452082) (xy 55.797538 -350.399783) (xy 55.789784 -350.345831) (xy 55.789322 -350.318578)
			(xy 53.648436 -350.318578) (xy 53.651066 -350.327539) (xy 53.658818 -350.381494) (xy 53.659278 -350.408748)
			(xy 53.658625 -350.440311) (xy 53.648235 -350.502577) (xy 53.627747 -350.562286) (xy 53.613304 -350.590358)
			(xy 53.608478 -350.599248) (xy 53.606446 -350.618806) (xy 53.629306 -350.697292) (xy 53.632555 -350.706712)
			(xy 53.644965 -350.722273) (xy 53.653436 -350.727518) (xy 53.678515 -350.742104) (xy 53.7244 -350.777599)
			(xy 53.764378 -350.819635) (xy 53.797527 -350.867242) (xy 53.823082 -350.919322) (xy 53.840452 -350.974672)
			(xy 53.849237 -351.032014) (xy 53.849778 -351.06102) (xy 53.849292 -351.088271) (xy 53.841536 -351.142219)
			(xy 53.830847 -351.178622) (xy 59.527694 -351.178622) (xy 59.528195 -351.151148) (xy 59.536083 -351.096769)
			(xy 59.5517 -351.044087) (xy 59.574722 -350.994194) (xy 59.60467 -350.948124) (xy 59.622436 -350.927162)
			(xy 59.62269 -350.926908) (xy 59.628278 -350.919823) (xy 59.634524 -350.902905) (xy 59.634882 -350.893888)
			(xy 59.634882 -350.826324) (xy 59.634517 -350.817308) (xy 59.628275 -350.800391) (xy 59.62269 -350.793304)
			(xy 59.622182 -350.792796) (xy 59.604448 -350.77185) (xy 59.574566 -350.725817) (xy 59.5516 -350.675972)
			(xy 59.536026 -350.623347) (xy 59.528165 -350.569031) (xy 59.527694 -350.54159) (xy 59.52818 -350.514339)
			(xy 59.535936 -350.460391) (xy 59.551291 -350.408096) (xy 59.573933 -350.358519) (xy 59.603399 -350.312669)
			(xy 59.63909 -350.271478) (xy 59.680281 -350.235787) (xy 59.726131 -350.206321) (xy 59.775708 -350.183679)
			(xy 59.828003 -350.168324) (xy 59.881951 -350.160568) (xy 59.936453 -350.160568) (xy 59.990401 -350.168324)
			(xy 60.042696 -350.183679) (xy 60.092273 -350.206321) (xy 60.138123 -350.235787) (xy 60.179314 -350.271478)
			(xy 60.215005 -350.312669) (xy 60.244471 -350.358519) (xy 60.267113 -350.408096) (xy 60.282468 -350.460391)
			(xy 60.290224 -350.514339) (xy 60.29071 -350.54159) (xy 60.290215 -350.569064) (xy 60.282325 -350.623443)
			(xy 60.266707 -350.676126) (xy 60.243684 -350.726018) (xy 60.213734 -350.772088) (xy 60.195968 -350.79305)
			(xy 60.195714 -350.793304) (xy 60.190121 -350.800386) (xy 60.183878 -350.817306) (xy 60.183522 -350.826324)
			(xy 60.183522 -350.893888) (xy 60.18388 -350.902905) (xy 60.190126 -350.919822) (xy 60.195714 -350.926908)
			(xy 60.196222 -350.927416) (xy 60.213962 -350.948356) (xy 60.243843 -350.994391) (xy 60.266808 -351.044238)
			(xy 60.282381 -351.096864) (xy 60.29024 -351.151181) (xy 60.29071 -351.178622) (xy 60.290224 -351.205873)
			(xy 60.282468 -351.259821) (xy 60.267113 -351.312116) (xy 60.244471 -351.361693) (xy 60.215005 -351.407543)
			(xy 60.179314 -351.448734) (xy 60.138123 -351.484425) (xy 60.092273 -351.513891) (xy 60.042696 -351.536533)
			(xy 59.990401 -351.551888) (xy 59.936453 -351.559644) (xy 59.881951 -351.559644) (xy 59.828003 -351.551888)
			(xy 59.775708 -351.536533) (xy 59.726131 -351.513891) (xy 59.680281 -351.484425) (xy 59.63909 -351.448734)
			(xy 59.603399 -351.407543) (xy 59.573933 -351.361693) (xy 59.551291 -351.312116) (xy 59.535936 -351.259821)
			(xy 59.52818 -351.205873) (xy 59.527694 -351.178622) (xy 53.830847 -351.178622) (xy 53.826181 -351.194514)
			(xy 53.803539 -351.244091) (xy 53.774073 -351.289941) (xy 53.738382 -351.331132) (xy 53.697191 -351.366823)
			(xy 53.651341 -351.396289) (xy 53.601764 -351.418931) (xy 53.549469 -351.434286) (xy 53.495521 -351.442042)
			(xy 53.441019 -351.442042) (xy 53.387071 -351.434286) (xy 53.334776 -351.418931) (xy 53.285199 -351.396289)
			(xy 53.239349 -351.366823) (xy 53.198158 -351.331132) (xy 53.162467 -351.289941) (xy 53.133001 -351.244091)
			(xy 53.110359 -351.194514) (xy 53.095004 -351.142219) (xy 53.087248 -351.088271) (xy 53.086762 -351.06102)
			(xy 53.08741 -351.029457) (xy 53.097803 -350.967191) (xy 53.118293 -350.907483) (xy 53.132736 -350.87941)
			(xy 53.137562 -350.87052) (xy 53.139594 -350.850962) (xy 53.116734 -350.772476) (xy 53.113519 -350.763041)
			(xy 53.101086 -350.747487) (xy 53.092604 -350.74225) (xy 53.085238 -350.738186) (xy 53.075332 -350.732344)
			(xy 53.053488 -350.730312) (xy 52.958746 -350.76384) (xy 52.942998 -350.779334) (xy 52.938934 -350.789748)
			(xy 52.928937 -350.814832) (xy 52.902857 -350.862115) (xy 52.870358 -350.905239) (xy 52.851558 -350.924622)
			(xy 52.84471 -350.932016) (xy 52.836996 -350.95062) (xy 52.836572 -350.96069) (xy 52.836572 -351.986088)
			(xy 52.835929 -352.01107) (xy 52.826194 -352.060076) (xy 52.807096 -352.106246) (xy 52.779367 -352.147808)
			(xy 52.76215 -352.16592) (xy 52.007008 -352.921062) (xy 51.988909 -352.938296) (xy 51.947346 -352.966035)
			(xy 51.901172 -352.985139) (xy 51.852161 -352.994875) (xy 51.827176 -352.995484) (xy 44.839636 -352.995484)
			(xy 44.814652 -352.994883) (xy 44.765644 -352.985135) (xy 44.719475 -352.966024) (xy 44.677914 -352.938284)
			(xy 44.659804 -352.921062) (xy 44.261532 -352.52279) (xy 44.25412 -352.516106) (xy 44.235687 -352.508509)
			(xy 44.215749 -352.508509) (xy 44.197316 -352.516106) (xy 44.189904 -352.52279) (xy 43.749722 -352.962972)
			(xy 43.731606 -352.980206) (xy 43.690069 -353.008021) (xy 43.643904 -353.027201) (xy 43.594885 -353.037007)
			(xy 43.56989 -353.037648) (xy 36.648898 -353.037648) (xy 36.623901 -353.037022) (xy 36.574878 -353.027216)
			(xy 36.528707 -353.008039) (xy 36.487161 -352.980229) (xy 36.469066 -352.962972) (xy 35.966908 -352.460814)
			(xy 35.959496 -352.45413) (xy 35.941063 -352.446533) (xy 35.921125 -352.446533) (xy 35.902692 -352.45413)
			(xy 35.89528 -352.460814) (xy 35.355022 -353.001072) (xy 35.336906 -353.018306) (xy 35.295369 -353.046121)
			(xy 35.249204 -353.065301) (xy 35.200185 -353.075107) (xy 35.17519 -353.075748) (xy 28.177998 -353.075748)
			(xy 28.153001 -353.075122) (xy 28.103978 -353.065316) (xy 28.057807 -353.046139) (xy 28.016261 -353.018329)
			(xy 27.998166 -353.001072) (xy 27.675332 -352.678238) (xy 27.66792 -352.671554) (xy 27.649487 -352.663957)
			(xy 27.629549 -352.663957) (xy 27.611116 -352.671554) (xy 27.603704 -352.678238) (xy 26.380694 -353.901502)
			(xy 26.37386 -353.908907) (xy 26.366137 -353.927502) (xy 26.365708 -353.93757) (xy 26.365708 -358.597454)
			(xy 26.366155 -358.607521) (xy 26.37386 -358.626119) (xy 26.380694 -358.633522) (xy 29.072078 -361.324906)
			(xy 29.079491 -361.33173) (xy 29.09808 -361.339459) (xy 29.108146 -361.339892) (xy 34.4424 -361.339892)
			(xy 34.467397 -361.340508) (xy 34.516422 -361.350315) (xy 34.562593 -361.369495) (xy 34.604138 -361.397309)
			(xy 34.622232 -361.414568) (xy 35.90417 -362.696506) (xy 35.911586 -362.703326) (xy 35.930173 -362.711057)
			(xy 35.940238 -362.711492) (xy 35.940492 -362.711492) (xy 35.971897 -362.712095) (xy 36.033874 -362.72227)
			(xy 36.093352 -362.742448) (xy 36.12134 -362.756704) (xy 36.13277 -362.763054) (xy 36.159694 -362.762546)
			(xy 36.246054 -362.71073) (xy 36.253363 -362.705942) (xy 36.264463 -362.692466) (xy 36.270343 -362.676026)
			(xy 36.270692 -362.667296) (xy 36.270692 -362.660692) (xy 36.270273 -362.650622) (xy 36.262548 -362.632024)
			(xy 36.255706 -362.624624) (xy 34.656776 -361.025694) (xy 34.649379 -361.01885) (xy 34.630777 -361.011133)
			(xy 34.620708 -361.010708) (xy 29.21 -361.010708) (xy 29.185003 -361.010092) (xy 29.135978 -361.000285)
			(xy 29.089807 -360.981105) (xy 29.048262 -360.953291) (xy 29.030168 -360.936032) (xy 26.896568 -358.802432)
			(xy 26.879267 -358.784374) (xy 26.851452 -358.74282) (xy 26.832279 -358.696637) (xy 26.822484 -358.647602)
			(xy 26.821892 -358.6226) (xy 26.821892 -354.457) (xy 26.822508 -354.432003) (xy 26.832315 -354.382978)
			(xy 26.851495 -354.336807) (xy 26.879309 -354.295262) (xy 26.896568 -354.277168) (xy 27.891486 -353.28225)
			(xy 27.909589 -353.26502) (xy 27.951151 -353.23728) (xy 27.997323 -353.218175) (xy 28.046334 -353.208437)
			(xy 28.071318 -353.207828) (xy 52.868322 -353.207828) (xy 52.878395 -353.207433) (xy 52.896994 -353.199693)
			(xy 52.90439 -353.192842) (xy 53.308504 -352.788728) (xy 53.326609 -352.771482) (xy 53.36815 -352.743668)
			(xy 53.414318 -352.724492) (xy 53.46334 -352.71469) (xy 53.488336 -352.714052) (xy 60.347352 -352.714052)
			(xy 60.35742 -352.713614) (xy 60.376019 -352.705904) (xy 60.38342 -352.699066) (xy 60.644278 -352.438462)
			(xy 60.651124 -352.431067) (xy 60.658841 -352.412464) (xy 60.659264 -352.402394) (xy 60.659264 -350.96069)
			(xy 60.658853 -350.950619) (xy 60.651123 -350.932021) (xy 60.644278 -350.924622) (xy 60.623405 -350.903029)
			(xy 60.588014 -350.854511) (xy 60.560666 -350.801045) (xy 60.542038 -350.743953) (xy 60.53259 -350.684647)
			(xy 60.53201 -350.65462) (xy 60.532474 -350.627367) (xy 60.540229 -350.573415) (xy 60.555583 -350.521116)
			(xy 60.578225 -350.471535) (xy 60.607692 -350.425681) (xy 60.643386 -350.384487) (xy 60.684579 -350.348793)
			(xy 60.730433 -350.319326) (xy 60.780014 -350.296684) (xy 60.832313 -350.281329) (xy 60.886265 -350.273574)
			(xy 60.913518 -350.273112) (xy 60.913772 -350.273112) (xy 60.938975 -350.273528) (xy 60.988942 -350.280163)
			(xy 61.037597 -350.293335) (xy 61.084087 -350.312813) (xy 61.10605 -350.325182) (xy 61.115956 -350.331024)
			(xy 61.1378 -350.333056) (xy 61.232542 -350.299528) (xy 61.24829 -350.284034) (xy 61.252354 -350.27362)
			(xy 61.263083 -350.246857) (xy 61.291365 -350.196615) (xy 61.326889 -350.151205) (xy 61.368846 -350.111661)
			(xy 61.416279 -350.078885) (xy 61.468106 -350.053625) (xy 61.523145 -350.036457) (xy 61.580142 -350.027771)
			(xy 61.60897 -350.02724) (xy 61.636224 -350.027683) (xy 61.690178 -350.035437) (xy 61.74248 -350.050792)
			(xy 61.792063 -350.073435) (xy 61.837918 -350.102904) (xy 61.879113 -350.1386) (xy 61.914807 -350.179796)
			(xy 61.944274 -350.225653) (xy 61.966914 -350.275237) (xy 61.979636 -350.318578) (xy 64.120522 -350.318578)
			(xy 64.121034 -350.291005) (xy 64.128976 -350.236434) (xy 64.144691 -350.183575) (xy 64.167852 -350.133528)
			(xy 64.197977 -350.087337) (xy 64.234438 -350.045965) (xy 64.255142 -350.027748) (xy 64.263203 -350.02018)
			(xy 64.272563 -350.000178) (xy 64.273176 -349.98914) (xy 64.273176 -349.911416) (xy 64.272607 -349.900367)
			(xy 64.263243 -349.880345) (xy 64.255142 -349.872808) (xy 64.23444 -349.854587) (xy 64.197967 -349.813221)
			(xy 64.167833 -349.767034) (xy 64.144665 -349.716988) (xy 64.128947 -349.664126) (xy 64.121007 -349.609552)
			(xy 64.120522 -349.581978) (xy 64.120934 -349.554723) (xy 64.128695 -349.500769) (xy 64.144056 -349.448468)
			(xy 64.166703 -349.398886) (xy 64.196176 -349.353031) (xy 64.231875 -349.311838) (xy 64.273073 -349.276145)
			(xy 64.318932 -349.246678) (xy 64.368517 -349.224037) (xy 64.42082 -349.208684) (xy 64.474775 -349.200931)
			(xy 64.50203 -349.20047) (xy 64.502538 -349.20047) (xy 64.53632 -349.201994) (xy 64.54648 -349.20301)
			(xy 64.565784 -349.196914) (xy 64.628776 -349.144082) (xy 64.636049 -349.137342) (xy 64.645341 -349.11985)
			(xy 64.64681 -349.110046) (xy 64.64681 -349.109284) (xy 64.649762 -349.081135) (xy 64.662956 -349.026097)
			(xy 64.684141 -348.973613) (xy 64.712849 -348.924837) (xy 64.748452 -348.88084) (xy 64.790166 -348.842588)
			(xy 64.837076 -348.810921) (xy 64.888151 -348.786535) (xy 64.942269 -348.769966) (xy 64.998241 -348.761577)
			(xy 65.02654 -348.76105) (xy 65.026794 -348.76105) (xy 65.044813 -348.761277) (xy 65.080688 -348.764707)
			(xy 65.098422 -348.767908) (xy 65.108074 -348.769686) (xy 65.127124 -348.76613) (xy 65.202054 -348.718124)
			(xy 65.213484 -348.702376) (xy 65.21577 -348.692978) (xy 65.223225 -348.665951) (xy 65.244848 -348.614227)
			(xy 65.273805 -348.566223) (xy 65.309473 -348.522971) (xy 65.351085 -348.485403) (xy 65.397745 -348.454326)
			(xy 65.448449 -348.43041) (xy 65.502107 -348.414169) (xy 65.557563 -348.405952) (xy 65.585594 -348.40545)
			(xy 65.612843 -348.405983) (xy 65.666787 -348.413738) (xy 65.719078 -348.42909) (xy 65.768653 -348.451727)
			(xy 65.814501 -348.481189) (xy 65.85569 -348.516876) (xy 65.891382 -348.55806) (xy 65.92085 -348.603905)
			(xy 65.943493 -348.653477) (xy 65.958852 -348.705766) (xy 65.966613 -348.759709) (xy 65.967102 -348.786958)
			(xy 65.966607 -348.814531) (xy 65.95866 -348.869103) (xy 65.942941 -348.921962) (xy 65.919776 -348.972008)
			(xy 65.889649 -349.018199) (xy 65.853187 -349.059571) (xy 65.832482 -349.077788) (xy 65.824409 -349.085345)
			(xy 65.815054 -349.105355) (xy 65.814448 -349.116396) (xy 65.814448 -349.19412) (xy 65.815045 -349.205166)
			(xy 65.824388 -349.225188) (xy 65.832482 -349.232728) (xy 65.853206 -349.250925) (xy 65.889676 -349.292296)
			(xy 65.919807 -349.338489) (xy 65.942971 -349.38854) (xy 65.958684 -349.441405) (xy 65.966619 -349.495982)
			(xy 65.967102 -349.523558) (xy 65.966607 -349.551131) (xy 65.95866 -349.605703) (xy 65.942941 -349.658562)
			(xy 65.919776 -349.708608) (xy 65.889649 -349.754799) (xy 65.853187 -349.796171) (xy 65.832482 -349.814388)
			(xy 65.824409 -349.821945) (xy 65.815054 -349.841955) (xy 65.814448 -349.852996) (xy 65.814448 -349.93072)
			(xy 65.815045 -349.941766) (xy 65.824388 -349.961788) (xy 65.832482 -349.969328) (xy 65.853206 -349.987525)
			(xy 65.889676 -350.028896) (xy 65.919807 -350.075089) (xy 65.942971 -350.12514) (xy 65.958684 -350.178005)
			(xy 65.966619 -350.232582) (xy 65.967102 -350.260158) (xy 65.966606 -350.28741) (xy 65.958854 -350.34136)
			(xy 65.943503 -350.393658) (xy 65.920865 -350.443238) (xy 65.891401 -350.489092) (xy 65.855711 -350.530285)
			(xy 65.814521 -350.565979) (xy 65.76867 -350.595448) (xy 65.719092 -350.618091) (xy 65.666795 -350.633447)
			(xy 65.612846 -350.641203) (xy 65.585594 -350.641666) (xy 65.557737 -350.641174) (xy 65.502619 -350.633048)
			(xy 65.449267 -350.617) (xy 65.398813 -350.59337) (xy 65.352327 -350.56266) (xy 65.310798 -350.52552)
			(xy 65.275106 -350.482741) (xy 65.246009 -350.435229) (xy 65.224124 -350.383993) (xy 65.216532 -350.357186)
			(xy 65.214246 -350.348296) (xy 65.203578 -350.333056) (xy 65.131696 -350.285304) (xy 65.113662 -350.28124)
			(xy 65.104518 -350.28251) (xy 65.091501 -350.284175) (xy 65.065317 -350.285958) (xy 65.052194 -350.286066)
			(xy 65.038045 -350.285973) (xy 65.009822 -350.283938) (xy 64.995806 -350.282002) (xy 64.9859 -350.280478)
			(xy 64.966088 -350.285304) (xy 64.891666 -350.341184) (xy 64.881506 -350.35871) (xy 64.880236 -350.36887)
			(xy 64.87615 -350.396023) (xy 64.861174 -350.448852) (xy 64.838781 -350.498989) (xy 64.809432 -350.545399)
			(xy 64.773735 -350.587122) (xy 64.732425 -350.623298) (xy 64.686357 -350.653179) (xy 64.636481 -350.676149)
			(xy 64.583828 -350.691732) (xy 64.529485 -350.699607) (xy 64.50203 -350.700086) (xy 64.474777 -350.699617)
			(xy 64.420825 -350.691863) (xy 64.368526 -350.67651) (xy 64.318944 -350.653869) (xy 64.27309 -350.624402)
			(xy 64.231897 -350.588709) (xy 64.196202 -350.547516) (xy 64.166735 -350.501663) (xy 64.144093 -350.452082)
			(xy 64.128738 -350.399783) (xy 64.120984 -350.345831) (xy 64.120522 -350.318578) (xy 61.979636 -350.318578)
			(xy 61.982266 -350.327539) (xy 61.990018 -350.381494) (xy 61.990478 -350.408748) (xy 61.989825 -350.440311)
			(xy 61.979435 -350.502577) (xy 61.958947 -350.562286) (xy 61.944504 -350.590358) (xy 61.939678 -350.599248)
			(xy 61.937646 -350.618806) (xy 61.960506 -350.697292) (xy 61.963755 -350.706712) (xy 61.976165 -350.722273)
			(xy 61.984636 -350.727518) (xy 62.009715 -350.742104) (xy 62.0556 -350.777599) (xy 62.095578 -350.819635)
			(xy 62.128727 -350.867242) (xy 62.154282 -350.919322) (xy 62.171652 -350.974672) (xy 62.180437 -351.032014)
			(xy 62.180978 -351.06102) (xy 62.180492 -351.088271) (xy 62.172736 -351.142219) (xy 62.157381 -351.194514)
			(xy 62.134739 -351.244091) (xy 62.105273 -351.289941) (xy 62.069582 -351.331132) (xy 62.028391 -351.366823)
			(xy 61.982541 -351.396289) (xy 61.932964 -351.418931) (xy 61.880669 -351.434286) (xy 61.826721 -351.442042)
			(xy 61.772219 -351.442042) (xy 61.718271 -351.434286) (xy 61.665976 -351.418931) (xy 61.616399 -351.396289)
			(xy 61.570549 -351.366823) (xy 61.529358 -351.331132) (xy 61.493667 -351.289941) (xy 61.464201 -351.244091)
			(xy 61.441559 -351.194514) (xy 61.426204 -351.142219) (xy 61.418448 -351.088271) (xy 61.417962 -351.06102)
			(xy 61.41861 -351.029457) (xy 61.429003 -350.967191) (xy 61.449493 -350.907483) (xy 61.463936 -350.87941)
			(xy 61.468762 -350.87052) (xy 61.470794 -350.850962) (xy 61.447934 -350.772476) (xy 61.444719 -350.763041)
			(xy 61.432286 -350.747487) (xy 61.423804 -350.74225) (xy 61.416438 -350.738186) (xy 61.406532 -350.732344)
			(xy 61.384688 -350.730312) (xy 61.289946 -350.76384) (xy 61.274198 -350.779334) (xy 61.270134 -350.789748)
			(xy 61.260137 -350.814832) (xy 61.234057 -350.862115) (xy 61.201558 -350.905239) (xy 61.182758 -350.924622)
			(xy 61.17591 -350.932016) (xy 61.168196 -350.95062) (xy 61.167772 -350.96069) (xy 61.167772 -352.402394)
			(xy 61.168182 -352.412465) (xy 61.175911 -352.431064) (xy 61.182758 -352.438462) (xy 61.497718 -352.753422)
			(xy 61.505115 -352.760266) (xy 61.523717 -352.767983) (xy 61.533786 -352.768408) (xy 65.530476 -352.768408)
			(xy 65.540547 -352.767995) (xy 65.559146 -352.760268) (xy 65.566544 -352.753422) (xy 66.853054 -351.466912)
			(xy 66.859875 -351.459496) (xy 66.867607 -351.440909) (xy 66.86804 -351.430844) (xy 66.86804 -347.518228)
			(xy 66.867616 -347.508158) (xy 66.859896 -347.48956) (xy 66.853054 -347.48216) (xy 66.332862 -346.961968)
			(xy 66.31566 -346.94384) (xy 66.287914 -346.902287) (xy 66.268801 -346.856123) (xy 66.259054 -346.807118)
			(xy 66.25844 -346.782136) (xy 66.25844 -342.557862) (xy 66.25905 -342.532878) (xy 66.268794 -342.48387)
			(xy 66.287902 -342.437701) (xy 66.315641 -342.39614) (xy 66.332862 -342.37803) (xy 68.309998 -340.400894)
			(xy 68.328103 -340.383666) (xy 68.369663 -340.355924) (xy 68.415835 -340.336817) (xy 68.464846 -340.32708)
			(xy 68.48983 -340.326472) (xy 69.00926 -340.326472) (xy 69.019328 -340.326033) (xy 69.037926 -340.318322)
			(xy 69.045328 -340.311486) (xy 69.178678 -340.178136) (xy 69.185492 -340.170715) (xy 69.193228 -340.152132)
			(xy 69.193664 -340.142068) (xy 69.193664 -339.239606) (xy 69.193245 -339.229536) (xy 69.185521 -339.210937)
			(xy 69.178678 -339.203538) (xy 69.157813 -339.181938) (xy 69.122421 -339.133422) (xy 69.095071 -339.079958)
			(xy 69.076441 -339.022867) (xy 69.066991 -338.963562) (xy 69.06641 -338.933536) (xy 69.066889 -338.906283)
			(xy 69.074641 -338.852332) (xy 69.089994 -338.800033) (xy 69.112633 -338.750452) (xy 69.142099 -338.704598)
			(xy 69.177792 -338.663404) (xy 69.218983 -338.62771) (xy 69.264836 -338.598242) (xy 69.314416 -338.5756)
			(xy 69.366714 -338.560245) (xy 69.420665 -338.55249) (xy 69.447918 -338.552028) (xy 69.448172 -338.552028)
			(xy 69.473375 -338.552441) (xy 69.523343 -338.559077) (xy 69.571997 -338.57225) (xy 69.618487 -338.591728)
			(xy 69.64045 -338.604098) (xy 69.650356 -338.60994) (xy 69.6722 -338.611972) (xy 69.766942 -338.578444)
			(xy 69.78269 -338.56295) (xy 69.786754 -338.552536) (xy 69.797438 -338.525755) (xy 69.82573 -338.475516)
			(xy 69.861264 -338.430108) (xy 69.903228 -338.390568) (xy 69.950666 -338.357795) (xy 70.002498 -338.332538)
			(xy 70.057541 -338.315371) (xy 70.114541 -338.306687) (xy 70.14337 -338.306156) (xy 70.170619 -338.306706)
			(xy 70.224562 -338.314458) (xy 70.276854 -338.329807) (xy 70.326428 -338.352442) (xy 70.372277 -338.381902)
			(xy 70.413467 -338.417587) (xy 70.449159 -338.45877) (xy 70.478626 -338.504614) (xy 70.50127 -338.554184)
			(xy 70.513991 -338.597494) (xy 72.654922 -338.597494) (xy 72.655376 -338.569919) (xy 72.66333 -338.515345)
			(xy 72.679057 -338.462485) (xy 72.702229 -338.412439) (xy 72.732364 -338.366249) (xy 72.768834 -338.324879)
			(xy 72.789542 -338.306664) (xy 72.79764 -338.29913) (xy 72.80698 -338.279102) (xy 72.807576 -338.268056)
			(xy 72.807576 -338.190332) (xy 72.806997 -338.179284) (xy 72.79764 -338.159262) (xy 72.789542 -338.151724)
			(xy 72.768848 -338.133494) (xy 72.732374 -338.092131) (xy 72.702239 -338.045945) (xy 72.67907 -337.9959)
			(xy 72.66335 -337.943041) (xy 72.655408 -337.888468) (xy 72.654922 -337.860894) (xy 72.65535 -337.83364)
			(xy 72.663108 -337.779686) (xy 72.678467 -337.727386) (xy 72.701112 -337.677803) (xy 72.730584 -337.631949)
			(xy 72.766281 -337.590755) (xy 72.807478 -337.555062) (xy 72.853335 -337.525595) (xy 72.902919 -337.502954)
			(xy 72.955221 -337.487601) (xy 73.009176 -337.479847) (xy 73.03643 -337.479386) (xy 73.036938 -337.479386)
			(xy 73.07072 -337.48091) (xy 73.08088 -337.481926) (xy 73.100184 -337.47583) (xy 73.163176 -337.422998)
			(xy 73.170481 -337.416288) (xy 73.179755 -337.398774) (xy 73.18121 -337.388962) (xy 73.18121 -337.3882)
			(xy 73.184175 -337.360053) (xy 73.197368 -337.305015) (xy 73.21855 -337.252531) (xy 73.247257 -337.203755)
			(xy 73.282858 -337.159757) (xy 73.32457 -337.121505) (xy 73.371479 -337.089837) (xy 73.422553 -337.065451)
			(xy 73.47667 -337.048882) (xy 73.532642 -337.040493) (xy 73.56094 -337.039966) (xy 73.561194 -337.039966)
			(xy 73.579213 -337.040192) (xy 73.615088 -337.043623) (xy 73.632822 -337.046824) (xy 73.642474 -337.048602)
			(xy 73.661524 -337.045046) (xy 73.736454 -336.99704) (xy 73.747884 -336.981292) (xy 73.75017 -336.971894)
			(xy 73.757635 -336.94487) (xy 73.779256 -336.893146) (xy 73.808211 -336.845141) (xy 73.843878 -336.801889)
			(xy 73.885489 -336.76432) (xy 73.932148 -336.733243) (xy 73.982851 -336.709327) (xy 74.036508 -336.693085)
			(xy 74.091964 -336.684868) (xy 74.119994 -336.684366) (xy 74.147244 -336.684883) (xy 74.201189 -336.692638)
			(xy 74.253482 -336.707991) (xy 74.303057 -336.73063) (xy 74.348906 -336.760093) (xy 74.390096 -336.795781)
			(xy 74.425788 -336.836968) (xy 74.455255 -336.882815) (xy 74.477897 -336.932388) (xy 74.493255 -336.98468)
			(xy 74.501014 -337.038624) (xy 74.501502 -337.065874) (xy 74.501018 -337.093448) (xy 74.493069 -337.14802)
			(xy 74.477347 -337.200879) (xy 74.454181 -337.250925) (xy 74.424052 -337.297115) (xy 74.387588 -337.338488)
			(xy 74.366882 -337.356704) (xy 74.358802 -337.364255) (xy 74.349451 -337.38427) (xy 74.348848 -337.395312)
			(xy 74.348848 -337.473036) (xy 74.349437 -337.484083) (xy 74.358786 -337.504105) (xy 74.366882 -337.511644)
			(xy 74.387566 -337.529885) (xy 74.424039 -337.571247) (xy 74.454175 -337.617431) (xy 74.477346 -337.667473)
			(xy 74.493068 -337.72033) (xy 74.501013 -337.774901) (xy 74.501502 -337.802474) (xy 74.501018 -337.830048)
			(xy 74.493069 -337.88462) (xy 74.477347 -337.937479) (xy 74.454181 -337.987525) (xy 74.424052 -338.033715)
			(xy 74.387588 -338.075088) (xy 74.366882 -338.093304) (xy 74.358802 -338.100855) (xy 74.349451 -338.12087)
			(xy 74.348848 -338.131912) (xy 74.348848 -338.209636) (xy 74.349437 -338.220683) (xy 74.358786 -338.240705)
			(xy 74.366882 -338.248244) (xy 74.387566 -338.266485) (xy 74.424039 -338.307847) (xy 74.454175 -338.354031)
			(xy 74.477346 -338.404073) (xy 74.493068 -338.45693) (xy 74.501013 -338.511501) (xy 74.501502 -338.539074)
			(xy 74.50102 -338.566326) (xy 74.493267 -338.620277) (xy 74.477914 -338.672575) (xy 74.455274 -338.722155)
			(xy 74.425808 -338.768009) (xy 74.390116 -338.809202) (xy 74.348925 -338.844896) (xy 74.303073 -338.874364)
			(xy 74.253494 -338.897007) (xy 74.201197 -338.912363) (xy 74.147246 -338.920119) (xy 74.119994 -338.920582)
			(xy 74.092138 -338.920078) (xy 74.037021 -338.911953) (xy 73.983669 -338.895906) (xy 73.933216 -338.872277)
			(xy 73.886731 -338.841568) (xy 73.845201 -338.80443) (xy 73.809509 -338.761652) (xy 73.780411 -338.714142)
			(xy 73.758525 -338.662908) (xy 73.750932 -338.636102) (xy 73.748646 -338.627212) (xy 73.737978 -338.611972)
			(xy 73.666096 -338.56422) (xy 73.648062 -338.560156) (xy 73.638918 -338.561426) (xy 73.625901 -338.563091)
			(xy 73.599717 -338.564874) (xy 73.586594 -338.564982) (xy 73.572445 -338.564889) (xy 73.544222 -338.562854)
			(xy 73.530206 -338.560918) (xy 73.5203 -338.559394) (xy 73.500488 -338.56422) (xy 73.426066 -338.6201)
			(xy 73.415906 -338.637626) (xy 73.414636 -338.647786) (xy 73.410562 -338.674941) (xy 73.395584 -338.727771)
			(xy 73.373189 -338.777907) (xy 73.343839 -338.824317) (xy 73.30814 -338.86604) (xy 73.266829 -338.902215)
			(xy 73.22076 -338.932096) (xy 73.170883 -338.955065) (xy 73.118229 -338.970648) (xy 73.063886 -338.978523)
			(xy 73.03643 -338.979002) (xy 73.009178 -338.978517) (xy 72.955227 -338.970764) (xy 72.902929 -338.955411)
			(xy 72.853349 -338.932772) (xy 72.807495 -338.903306) (xy 72.766302 -338.867615) (xy 72.730608 -338.826424)
			(xy 72.70114 -338.780572) (xy 72.678497 -338.730993) (xy 72.663141 -338.678696) (xy 72.655385 -338.624746)
			(xy 72.654922 -338.597494) (xy 70.513991 -338.597494) (xy 70.516628 -338.606473) (xy 70.524389 -338.660415)
			(xy 70.524878 -338.687664) (xy 70.524231 -338.719227) (xy 70.513839 -338.781493) (xy 70.493348 -338.841202)
			(xy 70.478904 -338.869274) (xy 70.474078 -338.878164) (xy 70.472046 -338.897722) (xy 70.494906 -338.976208)
			(xy 70.498149 -338.98563) (xy 70.510563 -339.00119) (xy 70.519036 -339.006434) (xy 70.544122 -339.021008)
			(xy 70.590007 -339.056505) (xy 70.629985 -339.098543) (xy 70.663133 -339.146153) (xy 70.688687 -339.198234)
			(xy 70.706055 -339.253586) (xy 70.714838 -339.31093) (xy 70.715378 -339.339936) (xy 70.714892 -339.367187)
			(xy 70.707136 -339.421135) (xy 70.698535 -339.450426) (xy 76.417678 -339.450426) (xy 76.418185 -339.422952)
			(xy 76.426073 -339.368574) (xy 76.441688 -339.315892) (xy 76.464708 -339.265999) (xy 76.494655 -339.219929)
			(xy 76.51242 -339.198966) (xy 76.512674 -339.198712) (xy 76.51827 -339.191632) (xy 76.524509 -339.17471)
			(xy 76.524866 -339.165692) (xy 76.524866 -339.098128) (xy 76.524503 -339.089112) (xy 76.51826 -339.072194)
			(xy 76.512674 -339.065108) (xy 76.512166 -339.0646) (xy 76.494447 -339.043642) (xy 76.46456 -338.997613)
			(xy 76.44159 -338.947771) (xy 76.426012 -338.895148) (xy 76.418149 -338.840834) (xy 76.417678 -338.813394)
			(xy 76.418164 -338.786143) (xy 76.42592 -338.732195) (xy 76.441275 -338.6799) (xy 76.463917 -338.630323)
			(xy 76.493383 -338.584473) (xy 76.529074 -338.543282) (xy 76.570265 -338.507591) (xy 76.616115 -338.478125)
			(xy 76.665692 -338.455483) (xy 76.717987 -338.440128) (xy 76.771935 -338.432372) (xy 76.826437 -338.432372)
			(xy 76.880385 -338.440128) (xy 76.93268 -338.455483) (xy 76.982257 -338.478125) (xy 77.028107 -338.507591)
			(xy 77.069298 -338.543282) (xy 77.104989 -338.584473) (xy 77.134455 -338.630323) (xy 77.157097 -338.6799)
			(xy 77.172452 -338.732195) (xy 77.180208 -338.786143) (xy 77.180694 -338.813394) (xy 77.180206 -338.840869)
			(xy 77.172314 -338.895248) (xy 77.156695 -338.947931) (xy 77.133671 -338.997823) (xy 77.103719 -339.043892)
			(xy 77.085952 -339.064854) (xy 77.085698 -339.065108) (xy 77.080102 -339.072188) (xy 77.073861 -339.08911)
			(xy 77.073506 -339.098128) (xy 77.073506 -339.165692) (xy 77.073865 -339.174709) (xy 77.080111 -339.191626)
			(xy 77.085698 -339.198712) (xy 77.086206 -339.19922) (xy 77.103946 -339.220161) (xy 77.133827 -339.266195)
			(xy 77.156792 -339.316042) (xy 77.172365 -339.368668) (xy 77.180224 -339.422985) (xy 77.180694 -339.450426)
			(xy 77.180208 -339.477677) (xy 77.172452 -339.531625) (xy 77.157097 -339.58392) (xy 77.134455 -339.633497)
			(xy 77.104989 -339.679347) (xy 77.069298 -339.720538) (xy 77.028107 -339.756229) (xy 76.982257 -339.785695)
			(xy 76.93268 -339.808337) (xy 76.880385 -339.823692) (xy 76.826437 -339.831448) (xy 76.771935 -339.831448)
			(xy 76.717987 -339.823692) (xy 76.665692 -339.808337) (xy 76.616115 -339.785695) (xy 76.570265 -339.756229)
			(xy 76.529074 -339.720538) (xy 76.493383 -339.679347) (xy 76.463917 -339.633497) (xy 76.441275 -339.58392)
			(xy 76.42592 -339.531625) (xy 76.418164 -339.477677) (xy 76.417678 -339.450426) (xy 70.698535 -339.450426)
			(xy 70.691781 -339.47343) (xy 70.669139 -339.523007) (xy 70.639673 -339.568857) (xy 70.603982 -339.610048)
			(xy 70.562791 -339.645739) (xy 70.516941 -339.675205) (xy 70.467364 -339.697847) (xy 70.415069 -339.713202)
			(xy 70.361121 -339.720958) (xy 70.306619 -339.720958) (xy 70.252671 -339.713202) (xy 70.200376 -339.697847)
			(xy 70.150799 -339.675205) (xy 70.104949 -339.645739) (xy 70.063758 -339.610048) (xy 70.028067 -339.568857)
			(xy 69.998601 -339.523007) (xy 69.975959 -339.47343) (xy 69.960604 -339.421135) (xy 69.952848 -339.367187)
			(xy 69.952362 -339.339936) (xy 69.953016 -339.308373) (xy 69.963407 -339.246108) (xy 69.983894 -339.186399)
			(xy 69.998336 -339.158326) (xy 70.003162 -339.149436) (xy 70.005194 -339.129878) (xy 69.982334 -339.051392)
			(xy 69.979113 -339.04196) (xy 69.966684 -339.026404) (xy 69.958204 -339.021166) (xy 69.950838 -339.017102)
			(xy 69.940932 -339.01126) (xy 69.919088 -339.009228) (xy 69.824346 -339.042756) (xy 69.808598 -339.05825)
			(xy 69.804534 -339.068664) (xy 69.794514 -339.093739) (xy 69.768444 -339.141024) (xy 69.735954 -339.184152)
			(xy 69.717158 -339.203538) (xy 69.710303 -339.210926) (xy 69.702593 -339.229535) (xy 69.702172 -339.239606)
			(xy 69.702172 -340.142068) (xy 69.702595 -340.152138) (xy 69.710315 -340.170737) (xy 69.717158 -340.178136)
			(xy 70.209918 -340.670642) (xy 70.217313 -340.677488) (xy 70.235916 -340.685203) (xy 70.245986 -340.685628)
			(xy 70.49643 -340.685628) (xy 70.506504 -340.685237) (xy 70.525102 -340.677495) (xy 70.532498 -340.670642)
			(xy 70.952868 -340.250526) (xy 70.970975 -340.233301) (xy 71.012536 -340.205561) (xy 71.058707 -340.186455)
			(xy 71.107716 -340.176715) (xy 71.1327 -340.176104) (xy 72.319642 -340.176104) (xy 72.344625 -340.176721)
			(xy 72.393632 -340.186465) (xy 72.439801 -340.205571) (xy 72.481363 -340.233307) (xy 72.499474 -340.250526)
			(xy 73.149968 -340.900766) (xy 73.157389 -340.90758) (xy 73.175972 -340.915316) (xy 73.186036 -340.915752)
			(xy 77.001878 -340.915752) (xy 77.011948 -340.915328) (xy 77.030546 -340.907608) (xy 77.037946 -340.900766)
			(xy 77.534262 -340.404704) (xy 77.541087 -340.397292) (xy 77.548817 -340.378702) (xy 77.549248 -340.368636)
			(xy 77.549248 -339.232494) (xy 77.54884 -339.222423) (xy 77.541109 -339.203824) (xy 77.534262 -339.196426)
			(xy 77.513388 -339.174833) (xy 77.477998 -339.126315) (xy 77.450651 -339.072849) (xy 77.432022 -339.015757)
			(xy 77.422574 -338.956451) (xy 77.421994 -338.926424) (xy 77.422478 -338.899172) (xy 77.430231 -338.845221)
			(xy 77.445584 -338.792924) (xy 77.468224 -338.743344) (xy 77.49769 -338.69749) (xy 77.533382 -338.656297)
			(xy 77.574573 -338.620603) (xy 77.620424 -338.591135) (xy 77.670003 -338.568492) (xy 77.7223 -338.553136)
			(xy 77.77625 -338.545379) (xy 77.803502 -338.544916) (xy 77.803756 -338.544916) (xy 77.828959 -338.545338)
			(xy 77.878926 -338.551972) (xy 77.92758 -338.565142) (xy 77.974071 -338.584618) (xy 77.996034 -338.596986)
			(xy 78.00594 -338.602828) (xy 78.027784 -338.60486) (xy 78.122526 -338.571332) (xy 78.138274 -338.555838)
			(xy 78.142338 -338.545424) (xy 78.153082 -338.518668) (xy 78.181362 -338.468427) (xy 78.216884 -338.423016)
			(xy 78.258839 -338.383472) (xy 78.30627 -338.350695) (xy 78.358094 -338.325434) (xy 78.413132 -338.308264)
			(xy 78.470127 -338.299576) (xy 78.498954 -338.299044) (xy 78.526202 -338.299621) (xy 78.580144 -338.30737)
			(xy 78.632434 -338.322717) (xy 78.682008 -338.345349) (xy 78.727856 -338.374806) (xy 78.769045 -338.410488)
			(xy 78.804738 -338.451669) (xy 78.834206 -338.49751) (xy 78.85685 -338.547078) (xy 78.869571 -338.590382)
			(xy 81.010506 -338.590382) (xy 81.011026 -338.562809) (xy 81.018967 -338.508239) (xy 81.034681 -338.45538)
			(xy 81.057841 -338.405334) (xy 81.087964 -338.359143) (xy 81.124423 -338.317769) (xy 81.145126 -338.299552)
			(xy 81.153227 -338.292021) (xy 81.162566 -338.271991) (xy 81.16316 -338.260944) (xy 81.16316 -338.18322)
			(xy 81.162593 -338.17217) (xy 81.153228 -338.152149) (xy 81.145126 -338.144612) (xy 81.124423 -338.126392)
			(xy 81.087951 -338.085026) (xy 81.057817 -338.038838) (xy 81.03465 -337.988792) (xy 81.018932 -337.93593)
			(xy 81.010991 -337.881356) (xy 81.010506 -337.853782) (xy 81.010961 -337.82653) (xy 81.01872 -337.77258)
			(xy 81.034079 -337.720284) (xy 81.056723 -337.670706) (xy 81.086192 -337.624855) (xy 81.121887 -337.583664)
			(xy 81.16308 -337.547973) (xy 81.208934 -337.518507) (xy 81.258514 -337.495867) (xy 81.310811 -337.480514)
			(xy 81.364762 -337.472759) (xy 81.392014 -337.472274) (xy 81.392522 -337.472274) (xy 81.426304 -337.473798)
			(xy 81.436464 -337.474814) (xy 81.455768 -337.468718) (xy 81.51876 -337.415886) (xy 81.526045 -337.409158)
			(xy 81.535327 -337.391657) (xy 81.536794 -337.38185) (xy 81.536794 -337.381088) (xy 81.539765 -337.352942)
			(xy 81.552958 -337.297905) (xy 81.574141 -337.245422) (xy 81.602848 -337.196647) (xy 81.638448 -337.15265)
			(xy 81.68016 -337.114398) (xy 81.727067 -337.08273) (xy 81.77814 -337.058344) (xy 81.832256 -337.041773)
			(xy 81.888226 -337.033382) (xy 81.916524 -337.032854) (xy 81.916778 -337.032854) (xy 81.934798 -337.033069)
			(xy 81.970672 -337.036507) (xy 81.988406 -337.039712) (xy 81.998058 -337.04149) (xy 82.017108 -337.037934)
			(xy 82.092038 -336.989928) (xy 82.103468 -336.97418) (xy 82.105754 -336.964782) (xy 82.113135 -336.937733)
			(xy 82.134764 -336.886004) (xy 82.163729 -336.837996) (xy 82.199406 -336.794743) (xy 82.241027 -336.757175)
			(xy 82.287697 -336.726101) (xy 82.338412 -336.70219) (xy 82.392079 -336.685957) (xy 82.447544 -336.67775)
			(xy 82.475578 -336.677254) (xy 82.502827 -336.677799) (xy 82.556771 -336.685551) (xy 82.609062 -336.700902)
			(xy 82.658636 -336.723537) (xy 82.704485 -336.752998) (xy 82.745674 -336.788683) (xy 82.781366 -336.829867)
			(xy 82.810834 -336.875711) (xy 82.833477 -336.925282) (xy 82.848836 -336.977571) (xy 82.856597 -337.031513)
			(xy 82.857086 -337.058762) (xy 82.856599 -337.086336) (xy 82.848652 -337.140908) (xy 82.832931 -337.193768)
			(xy 82.809765 -337.243814) (xy 82.779636 -337.290004) (xy 82.743172 -337.331376) (xy 82.722466 -337.349592)
			(xy 82.714389 -337.357145) (xy 82.705037 -337.377158) (xy 82.704432 -337.3882) (xy 82.704432 -337.465924)
			(xy 82.705033 -337.47697) (xy 82.714374 -337.496991) (xy 82.722466 -337.504532) (xy 82.743189 -337.52273)
			(xy 82.77966 -337.564101) (xy 82.809791 -337.610293) (xy 82.832955 -337.660344) (xy 82.848669 -337.713209)
			(xy 82.856604 -337.767786) (xy 82.857086 -337.795362) (xy 82.856599 -337.822936) (xy 82.848652 -337.877508)
			(xy 82.832931 -337.930368) (xy 82.809765 -337.980414) (xy 82.779636 -338.026604) (xy 82.743172 -338.067976)
			(xy 82.722466 -338.086192) (xy 82.714389 -338.093745) (xy 82.705037 -338.113758) (xy 82.704432 -338.1248)
			(xy 82.704432 -338.202524) (xy 82.705033 -338.21357) (xy 82.714374 -338.233591) (xy 82.722466 -338.241132)
			(xy 82.743189 -338.25933) (xy 82.77966 -338.300701) (xy 82.809791 -338.346893) (xy 82.832955 -338.396944)
			(xy 82.848669 -338.449809) (xy 82.856604 -338.504386) (xy 82.857086 -338.531962) (xy 82.856609 -338.559215)
			(xy 82.848857 -338.613167) (xy 82.833505 -338.665465) (xy 82.810865 -338.715047) (xy 82.781399 -338.760901)
			(xy 82.745706 -338.802095) (xy 82.704514 -338.837789) (xy 82.658661 -338.867257) (xy 82.60908 -338.889899)
			(xy 82.556782 -338.905254) (xy 82.502831 -338.913008) (xy 82.475578 -338.91347) (xy 82.447721 -338.912989)
			(xy 82.392603 -338.904862) (xy 82.33925 -338.888812) (xy 82.288796 -338.86518) (xy 82.242311 -338.834468)
			(xy 82.200782 -338.797327) (xy 82.16509 -338.754547) (xy 82.135993 -338.707034) (xy 82.114108 -338.655797)
			(xy 82.106516 -338.62899) (xy 82.10423 -338.6201) (xy 82.093562 -338.60486) (xy 82.02168 -338.557108)
			(xy 82.003646 -338.553044) (xy 81.994502 -338.554314) (xy 81.981485 -338.555981) (xy 81.955301 -338.557762)
			(xy 81.942178 -338.55787) (xy 81.928029 -338.557779) (xy 81.899806 -338.555743) (xy 81.88579 -338.553806)
			(xy 81.875884 -338.552282) (xy 81.856072 -338.557108) (xy 81.78165 -338.612988) (xy 81.77149 -338.630514)
			(xy 81.77022 -338.640674) (xy 81.766152 -338.667831) (xy 81.751175 -338.720661) (xy 81.72878 -338.770799)
			(xy 81.69943 -338.817209) (xy 81.66373 -338.858933) (xy 81.622418 -338.895108) (xy 81.576348 -338.924989)
			(xy 81.52647 -338.947957) (xy 81.473815 -338.963539) (xy 81.41947 -338.971412) (xy 81.392014 -338.97189)
			(xy 81.364761 -338.971432) (xy 81.310809 -338.963676) (xy 81.25851 -338.948321) (xy 81.208928 -338.925679)
			(xy 81.163074 -338.896211) (xy 81.121881 -338.860516) (xy 81.086187 -338.819323) (xy 81.056719 -338.773468)
			(xy 81.034078 -338.723887) (xy 81.018723 -338.671587) (xy 81.010968 -338.617635) (xy 81.010506 -338.590382)
			(xy 78.869571 -338.590382) (xy 78.87221 -338.599364) (xy 78.879972 -338.653304) (xy 78.880462 -338.680552)
			(xy 78.879812 -338.712115) (xy 78.869421 -338.774381) (xy 78.848932 -338.83409) (xy 78.834488 -338.862162)
			(xy 78.829662 -338.871052) (xy 78.82763 -338.89061) (xy 78.85049 -338.969096) (xy 78.853744 -338.978514)
			(xy 78.86615 -338.994076) (xy 78.87462 -338.999322) (xy 78.89972 -339.013872) (xy 78.945601 -339.049377)
			(xy 78.985575 -339.091421) (xy 79.01872 -339.139034) (xy 79.044271 -339.191118) (xy 79.061638 -339.246472)
			(xy 79.070422 -339.303817) (xy 79.070962 -339.332824) (xy 79.070476 -339.360075) (xy 79.06272 -339.414023)
			(xy 79.056282 -339.435948) (xy 84.775294 -339.435948) (xy 84.775751 -339.408472) (xy 84.78365 -339.354092)
			(xy 84.799277 -339.301409) (xy 84.822308 -339.251517) (xy 84.852266 -339.205449) (xy 84.870036 -339.184488)
			(xy 84.87029 -339.184234) (xy 84.875867 -339.177141) (xy 84.88212 -339.160229) (xy 84.882482 -339.151214)
			(xy 84.882482 -339.08365) (xy 84.882105 -339.074635) (xy 84.875872 -339.057718) (xy 84.87029 -339.05063)
			(xy 84.869782 -339.050122) (xy 84.85206 -339.029167) (xy 84.822176 -338.983136) (xy 84.799208 -338.933293)
			(xy 84.783631 -338.88067) (xy 84.775767 -338.826356) (xy 84.775294 -338.798916) (xy 84.77578 -338.771665)
			(xy 84.783536 -338.717717) (xy 84.798891 -338.665422) (xy 84.821533 -338.615845) (xy 84.850999 -338.569995)
			(xy 84.88669 -338.528804) (xy 84.927881 -338.493113) (xy 84.973731 -338.463647) (xy 85.023308 -338.441005)
			(xy 85.075603 -338.42565) (xy 85.129551 -338.417894) (xy 85.184053 -338.417894) (xy 85.238001 -338.42565)
			(xy 85.290296 -338.441005) (xy 85.339873 -338.463647) (xy 85.385723 -338.493113) (xy 85.426914 -338.528804)
			(xy 85.462605 -338.569995) (xy 85.492071 -338.615845) (xy 85.514713 -338.665422) (xy 85.530068 -338.717717)
			(xy 85.537824 -338.771665) (xy 85.53831 -338.798916) (xy 85.537831 -338.826391) (xy 85.529937 -338.880771)
			(xy 85.514315 -338.933453) (xy 85.491289 -338.983346) (xy 85.461336 -339.029414) (xy 85.443568 -339.050376)
			(xy 85.443314 -339.05063) (xy 85.437752 -339.057734) (xy 85.43149 -339.074637) (xy 85.431122 -339.08365)
			(xy 85.431122 -339.151214) (xy 85.431467 -339.160232) (xy 85.437722 -339.177149) (xy 85.443314 -339.184234)
			(xy 85.443822 -339.184742) (xy 85.461575 -339.205673) (xy 85.491454 -339.25171) (xy 85.514416 -339.301559)
			(xy 85.529986 -339.354188) (xy 85.537842 -339.408506) (xy 85.53831 -339.435948) (xy 85.537824 -339.463199)
			(xy 85.530068 -339.517147) (xy 85.514713 -339.569442) (xy 85.492071 -339.619019) (xy 85.462605 -339.664869)
			(xy 85.426914 -339.70606) (xy 85.385723 -339.741751) (xy 85.339873 -339.771217) (xy 85.290296 -339.793859)
			(xy 85.238001 -339.809214) (xy 85.184053 -339.81697) (xy 85.129551 -339.81697) (xy 85.075603 -339.809214)
			(xy 85.023308 -339.793859) (xy 84.973731 -339.771217) (xy 84.927881 -339.741751) (xy 84.88669 -339.70606)
			(xy 84.850999 -339.664869) (xy 84.821533 -339.619019) (xy 84.798891 -339.569442) (xy 84.783536 -339.517147)
			(xy 84.77578 -339.463199) (xy 84.775294 -339.435948) (xy 79.056282 -339.435948) (xy 79.047365 -339.466318)
			(xy 79.024723 -339.515895) (xy 78.995257 -339.561745) (xy 78.959566 -339.602936) (xy 78.918375 -339.638627)
			(xy 78.872525 -339.668093) (xy 78.822948 -339.690735) (xy 78.770653 -339.70609) (xy 78.716705 -339.713846)
			(xy 78.662203 -339.713846) (xy 78.608255 -339.70609) (xy 78.55596 -339.690735) (xy 78.506383 -339.668093)
			(xy 78.460533 -339.638627) (xy 78.419342 -339.602936) (xy 78.383651 -339.561745) (xy 78.354185 -339.515895)
			(xy 78.331543 -339.466318) (xy 78.316188 -339.414023) (xy 78.308432 -339.360075) (xy 78.307946 -339.332824)
			(xy 78.308586 -339.30126) (xy 78.31898 -339.238994) (xy 78.339474 -339.179286) (xy 78.35392 -339.151214)
			(xy 78.358746 -339.142324) (xy 78.360778 -339.122766) (xy 78.337918 -339.04428) (xy 78.334671 -339.03486)
			(xy 78.322259 -339.0193) (xy 78.313788 -339.014054) (xy 78.306422 -339.00999) (xy 78.296516 -339.004148)
			(xy 78.274672 -339.002116) (xy 78.17993 -339.035644) (xy 78.164182 -339.051138) (xy 78.160118 -339.061552)
			(xy 78.150125 -339.086638) (xy 78.124043 -339.13392) (xy 78.091543 -339.177043) (xy 78.072742 -339.196426)
			(xy 78.065904 -339.203828) (xy 78.058182 -339.222426) (xy 78.057756 -339.232494) (xy 78.057756 -340.369652)
			(xy 78.058192 -340.37972) (xy 78.065903 -340.398319) (xy 78.072742 -340.40572) (xy 78.464918 -340.797642)
			(xy 78.472313 -340.804488) (xy 78.490916 -340.812203) (xy 78.500986 -340.812628) (xy 85.360002 -340.812628)
			(xy 85.370074 -340.812223) (xy 85.388673 -340.80449) (xy 85.39607 -340.797642) (xy 85.891878 -340.302088)
			(xy 85.898713 -340.294684) (xy 85.906436 -340.276088) (xy 85.906864 -340.26602) (xy 85.906864 -339.218016)
			(xy 85.90644 -339.207946) (xy 85.898719 -339.189348) (xy 85.891878 -339.181948) (xy 85.871017 -339.160343)
			(xy 85.835625 -339.111828) (xy 85.808275 -339.058365) (xy 85.789643 -339.001276) (xy 85.780192 -338.941972)
			(xy 85.77961 -338.911946) (xy 85.780098 -338.884693) (xy 85.787849 -338.830742) (xy 85.8032 -338.778444)
			(xy 85.825839 -338.728863) (xy 85.855304 -338.683009) (xy 85.890995 -338.641815) (xy 85.932186 -338.606121)
			(xy 85.978038 -338.576652) (xy 86.027618 -338.55401) (xy 86.079915 -338.538655) (xy 86.133866 -338.5309)
			(xy 86.161118 -338.530438) (xy 86.161372 -338.530438) (xy 86.186575 -338.53085) (xy 86.236543 -338.537486)
			(xy 86.285197 -338.550659) (xy 86.331688 -338.570138) (xy 86.35365 -338.582508) (xy 86.363556 -338.58835)
			(xy 86.3854 -338.590382) (xy 86.480142 -338.556854) (xy 86.49589 -338.54136) (xy 86.499954 -338.530946)
			(xy 86.510643 -338.504167) (xy 86.538934 -338.453928) (xy 86.574467 -338.40852) (xy 86.61643 -338.368979)
			(xy 86.663868 -338.336206) (xy 86.715699 -338.310948) (xy 86.770741 -338.293782) (xy 86.827741 -338.285097)
			(xy 86.85657 -338.284566) (xy 86.883821 -338.285083) (xy 86.937769 -338.292835) (xy 86.990064 -338.308186)
			(xy 87.039642 -338.330823) (xy 87.085494 -338.360286) (xy 87.126686 -338.395974) (xy 87.162381 -338.437161)
			(xy 87.19185 -338.483009) (xy 87.214494 -338.532584) (xy 87.227218 -338.575904) (xy 89.368122 -338.575904)
			(xy 89.368583 -338.548329) (xy 89.376535 -338.493756) (xy 89.392261 -338.440895) (xy 89.415432 -338.390849)
			(xy 89.445565 -338.34466) (xy 89.482034 -338.303289) (xy 89.502742 -338.285074) (xy 89.510836 -338.277536)
			(xy 89.520178 -338.257511) (xy 89.520776 -338.246466) (xy 89.520776 -338.168742) (xy 89.520192 -338.157694)
			(xy 89.510839 -338.137673) (xy 89.502742 -338.130134) (xy 89.482052 -338.111899) (xy 89.445579 -338.070536)
			(xy 89.415443 -338.024352) (xy 89.392273 -337.974308) (xy 89.376552 -337.921449) (xy 89.368609 -337.866878)
			(xy 89.368122 -337.839304) (xy 89.368559 -337.81205) (xy 89.376316 -337.758096) (xy 89.391673 -337.705796)
			(xy 89.414318 -337.656214) (xy 89.443788 -337.61036) (xy 89.479485 -337.569166) (xy 89.52068 -337.533472)
			(xy 89.566537 -337.504005) (xy 89.616121 -337.481364) (xy 89.668422 -337.466011) (xy 89.722376 -337.458257)
			(xy 89.74963 -337.457796) (xy 89.750138 -337.457796) (xy 89.78392 -337.45932) (xy 89.79408 -337.460336)
			(xy 89.813384 -337.45424) (xy 89.876376 -337.401408) (xy 89.883678 -337.394695) (xy 89.892954 -337.377183)
			(xy 89.89441 -337.367372) (xy 89.89441 -337.36661) (xy 89.8973 -337.338454) (xy 89.910505 -337.283414)
			(xy 89.931698 -337.230931) (xy 89.960416 -337.182155) (xy 89.996025 -337.138159) (xy 90.037746 -337.099908)
			(xy 90.084661 -337.068243) (xy 90.135741 -337.043859) (xy 90.189863 -337.027291) (xy 90.24584 -337.018903)
			(xy 90.27414 -337.018376) (xy 90.274394 -337.018376) (xy 90.292413 -337.018602) (xy 90.328288 -337.022033)
			(xy 90.346022 -337.025234) (xy 90.355674 -337.027012) (xy 90.374724 -337.023456) (xy 90.449654 -336.97545)
			(xy 90.461084 -336.959702) (xy 90.46337 -336.950304) (xy 90.470776 -336.923263) (xy 90.492409 -336.87154)
			(xy 90.521374 -336.823538) (xy 90.55705 -336.780288) (xy 90.598668 -336.742722) (xy 90.645333 -336.711648)
			(xy 90.696041 -336.687734) (xy 90.749702 -336.671494) (xy 90.805162 -336.663278) (xy 90.833194 -336.662776)
			(xy 90.860444 -336.663283) (xy 90.914391 -336.671039) (xy 90.966684 -336.686392) (xy 91.01626 -336.709031)
			(xy 91.06211 -336.738496) (xy 91.1033 -336.774185) (xy 91.138991 -336.815373) (xy 91.168458 -336.861221)
			(xy 91.1911 -336.910795) (xy 91.206457 -336.963088) (xy 91.214215 -337.017034) (xy 91.214702 -337.044284)
			(xy 91.214225 -337.071858) (xy 91.206274 -337.12643) (xy 91.190552 -337.17929) (xy 91.167384 -337.229336)
			(xy 91.137253 -337.275526) (xy 91.100788 -337.316898) (xy 91.080082 -337.335114) (xy 91.071997 -337.342661)
			(xy 91.062649 -337.362679) (xy 91.062048 -337.373722) (xy 91.062048 -337.451446) (xy 91.062631 -337.462494)
			(xy 91.071984 -337.482516) (xy 91.080082 -337.490054) (xy 91.100771 -337.50829) (xy 91.137243 -337.549653)
			(xy 91.167379 -337.595837) (xy 91.190549 -337.645881) (xy 91.20627 -337.698739) (xy 91.214214 -337.753311)
			(xy 91.214702 -337.780884) (xy 91.214225 -337.808458) (xy 91.206274 -337.86303) (xy 91.190552 -337.91589)
			(xy 91.167384 -337.965936) (xy 91.137253 -338.012126) (xy 91.100788 -338.053498) (xy 91.080082 -338.071714)
			(xy 91.071997 -338.079261) (xy 91.062649 -338.099279) (xy 91.062048 -338.110322) (xy 91.062048 -338.188046)
			(xy 91.062631 -338.199094) (xy 91.071984 -338.219116) (xy 91.080082 -338.226654) (xy 91.100771 -338.24489)
			(xy 91.137243 -338.286253) (xy 91.167379 -338.332437) (xy 91.190549 -338.382481) (xy 91.20627 -338.435339)
			(xy 91.214214 -338.489911) (xy 91.214702 -338.517484) (xy 91.21423 -338.544737) (xy 91.206475 -338.598688)
			(xy 91.191121 -338.650986) (xy 91.168479 -338.700566) (xy 91.139013 -338.74642) (xy 91.10332 -338.787613)
			(xy 91.062128 -338.823307) (xy 91.016275 -338.852775) (xy 90.966695 -338.875417) (xy 90.914397 -338.890773)
			(xy 90.860447 -338.898529) (xy 90.833194 -338.898992) (xy 90.805338 -338.89848) (xy 90.750222 -338.890356)
			(xy 90.696871 -338.874309) (xy 90.646418 -338.850681) (xy 90.599933 -338.819973) (xy 90.558404 -338.782836)
			(xy 90.522711 -338.740059) (xy 90.493612 -338.69255) (xy 90.471725 -338.641318) (xy 90.464132 -338.614512)
			(xy 90.461846 -338.605622) (xy 90.451178 -338.590382) (xy 90.379296 -338.54263) (xy 90.361262 -338.538566)
			(xy 90.352118 -338.539836) (xy 90.339101 -338.541502) (xy 90.312917 -338.543284) (xy 90.299794 -338.543392)
			(xy 90.285645 -338.543299) (xy 90.257422 -338.541264) (xy 90.243406 -338.539328) (xy 90.2335 -338.537804)
			(xy 90.213688 -338.54263) (xy 90.139266 -338.59851) (xy 90.129106 -338.616036) (xy 90.127836 -338.626196)
			(xy 90.12377 -338.653353) (xy 90.108791 -338.706182) (xy 90.086395 -338.756319) (xy 90.057043 -338.802728)
			(xy 90.021343 -338.844451) (xy 89.980032 -338.880626) (xy 89.933961 -338.910507) (xy 89.884084 -338.933475)
			(xy 89.83143 -338.949058) (xy 89.777086 -338.956933) (xy 89.74963 -338.957412) (xy 89.722378 -338.956917)
			(xy 89.668428 -338.949164) (xy 89.616131 -338.933812) (xy 89.566552 -338.911173) (xy 89.520699 -338.881709)
			(xy 89.479506 -338.846018) (xy 89.443812 -338.804829) (xy 89.414343 -338.758978) (xy 89.3917 -338.7094)
			(xy 89.376343 -338.657105) (xy 89.368586 -338.603156) (xy 89.368122 -338.575904) (xy 87.227218 -338.575904)
			(xy 87.229853 -338.584877) (xy 87.237613 -338.638823) (xy 87.238078 -338.666074) (xy 87.237435 -338.697638)
			(xy 87.227041 -338.759903) (xy 87.206549 -338.819612) (xy 87.192104 -338.847684) (xy 87.187278 -338.856574)
			(xy 87.185246 -338.876132) (xy 87.208106 -338.954618) (xy 87.211345 -338.964042) (xy 87.223762 -338.979601)
			(xy 87.232236 -338.984844) (xy 87.257326 -338.999411) (xy 87.303211 -339.034909) (xy 87.343189 -339.076948)
			(xy 87.376337 -339.124559) (xy 87.40189 -339.176642) (xy 87.419257 -339.231994) (xy 87.428039 -339.289339)
			(xy 87.428578 -339.318346) (xy 87.428092 -339.345597) (xy 87.420336 -339.399545) (xy 87.404981 -339.45184)
			(xy 87.389038 -339.486748) (xy 93.106494 -339.486748) (xy 93.106951 -339.459272) (xy 93.11485 -339.404892)
			(xy 93.130477 -339.352209) (xy 93.153508 -339.302317) (xy 93.183466 -339.256249) (xy 93.201236 -339.235288)
			(xy 93.20149 -339.235034) (xy 93.207067 -339.227941) (xy 93.21332 -339.211029) (xy 93.213682 -339.202014)
			(xy 93.213682 -339.13445) (xy 93.213305 -339.125435) (xy 93.207072 -339.108518) (xy 93.20149 -339.10143)
			(xy 93.200982 -339.100922) (xy 93.18326 -339.079967) (xy 93.153376 -339.033936) (xy 93.130408 -338.984093)
			(xy 93.114831 -338.93147) (xy 93.106967 -338.877156) (xy 93.106494 -338.849716) (xy 93.10698 -338.822465)
			(xy 93.114736 -338.768517) (xy 93.130091 -338.716222) (xy 93.152733 -338.666645) (xy 93.182199 -338.620795)
			(xy 93.21789 -338.579604) (xy 93.259081 -338.543913) (xy 93.304931 -338.514447) (xy 93.354508 -338.491805)
			(xy 93.406803 -338.47645) (xy 93.460751 -338.468694) (xy 93.515253 -338.468694) (xy 93.569201 -338.47645)
			(xy 93.621496 -338.491805) (xy 93.671073 -338.514447) (xy 93.716923 -338.543913) (xy 93.758114 -338.579604)
			(xy 93.793805 -338.620795) (xy 93.823271 -338.666645) (xy 93.845913 -338.716222) (xy 93.861268 -338.768517)
			(xy 93.869024 -338.822465) (xy 93.86951 -338.849716) (xy 93.869031 -338.877191) (xy 93.861137 -338.931571)
			(xy 93.845515 -338.984253) (xy 93.822489 -339.034146) (xy 93.792536 -339.080214) (xy 93.774768 -339.101176)
			(xy 93.774514 -339.10143) (xy 93.768952 -339.108534) (xy 93.76269 -339.125437) (xy 93.762322 -339.13445)
			(xy 93.762322 -339.202014) (xy 93.762667 -339.211032) (xy 93.768922 -339.227949) (xy 93.774514 -339.235034)
			(xy 93.775022 -339.235542) (xy 93.792775 -339.256473) (xy 93.822654 -339.30251) (xy 93.845616 -339.352359)
			(xy 93.861186 -339.404988) (xy 93.869042 -339.459306) (xy 93.86951 -339.486748) (xy 93.869024 -339.513999)
			(xy 93.861268 -339.567947) (xy 93.845913 -339.620242) (xy 93.823271 -339.669819) (xy 93.793805 -339.715669)
			(xy 93.758114 -339.75686) (xy 93.716923 -339.792551) (xy 93.671073 -339.822017) (xy 93.621496 -339.844659)
			(xy 93.569201 -339.860014) (xy 93.515253 -339.86777) (xy 93.460751 -339.86777) (xy 93.406803 -339.860014)
			(xy 93.354508 -339.844659) (xy 93.304931 -339.822017) (xy 93.259081 -339.792551) (xy 93.21789 -339.75686)
			(xy 93.182199 -339.715669) (xy 93.152733 -339.669819) (xy 93.130091 -339.620242) (xy 93.114736 -339.567947)
			(xy 93.10698 -339.513999) (xy 93.106494 -339.486748) (xy 87.389038 -339.486748) (xy 87.382339 -339.501417)
			(xy 87.352873 -339.547267) (xy 87.317182 -339.588458) (xy 87.275991 -339.624149) (xy 87.230141 -339.653615)
			(xy 87.180564 -339.676257) (xy 87.128269 -339.691612) (xy 87.074321 -339.699368) (xy 87.019819 -339.699368)
			(xy 86.965871 -339.691612) (xy 86.913576 -339.676257) (xy 86.863999 -339.653615) (xy 86.818149 -339.624149)
			(xy 86.776958 -339.588458) (xy 86.741267 -339.547267) (xy 86.711801 -339.501417) (xy 86.689159 -339.45184)
			(xy 86.673804 -339.399545) (xy 86.666048 -339.345597) (xy 86.665562 -339.318346) (xy 86.66622 -339.286783)
			(xy 86.676609 -339.224518) (xy 86.697095 -339.164809) (xy 86.711536 -339.136736) (xy 86.716362 -339.127846)
			(xy 86.718394 -339.108288) (xy 86.695534 -339.029802) (xy 86.692309 -339.020372) (xy 86.679883 -339.004815)
			(xy 86.671404 -338.999576) (xy 86.664038 -338.995512) (xy 86.654132 -338.98967) (xy 86.632288 -338.987638)
			(xy 86.537546 -339.021166) (xy 86.521798 -339.03666) (xy 86.517734 -339.047074) (xy 86.507717 -339.07215)
			(xy 86.481645 -339.119435) (xy 86.449155 -339.162562) (xy 86.430358 -339.181948) (xy 86.423601 -339.189406)
			(xy 86.415878 -339.207966) (xy 86.415372 -339.218016) (xy 86.415372 -340.26602) (xy 86.415768 -340.276093)
			(xy 86.423507 -340.294692) (xy 86.430358 -340.302088) (xy 86.926166 -340.797642) (xy 86.933618 -340.804407)
			(xy 86.952182 -340.812125) (xy 86.962234 -340.812628) (xy 93.869002 -340.812628) (xy 93.879074 -340.812223)
			(xy 93.897673 -340.80449) (xy 93.90507 -340.797642) (xy 94.223078 -340.479888) (xy 94.229913 -340.472484)
			(xy 94.237636 -340.453888) (xy 94.238064 -340.44382) (xy 94.238064 -339.268816) (xy 94.23764 -339.258746)
			(xy 94.229919 -339.240148) (xy 94.223078 -339.232748) (xy 94.202217 -339.211143) (xy 94.166825 -339.162628)
			(xy 94.139475 -339.109165) (xy 94.120843 -339.052076) (xy 94.111392 -338.992772) (xy 94.11081 -338.962746)
			(xy 94.111298 -338.935493) (xy 94.119049 -338.881542) (xy 94.1344 -338.829244) (xy 94.157039 -338.779663)
			(xy 94.186504 -338.733809) (xy 94.222195 -338.692615) (xy 94.263386 -338.656921) (xy 94.309238 -338.627452)
			(xy 94.358818 -338.60481) (xy 94.411115 -338.589455) (xy 94.465066 -338.5817) (xy 94.492318 -338.581238)
			(xy 94.492572 -338.581238) (xy 94.517775 -338.58165) (xy 94.567743 -338.588286) (xy 94.616397 -338.601459)
			(xy 94.662888 -338.620938) (xy 94.68485 -338.633308) (xy 94.694756 -338.63915) (xy 94.7166 -338.641182)
			(xy 94.811342 -338.607654) (xy 94.82709 -338.59216) (xy 94.831154 -338.581746) (xy 94.841843 -338.554967)
			(xy 94.870134 -338.504728) (xy 94.905667 -338.45932) (xy 94.94763 -338.419779) (xy 94.995068 -338.387006)
			(xy 95.046899 -338.361748) (xy 95.101941 -338.344582) (xy 95.158941 -338.335897) (xy 95.18777 -338.335366)
			(xy 95.215021 -338.335883) (xy 95.268969 -338.343635) (xy 95.321264 -338.358986) (xy 95.370842 -338.381623)
			(xy 95.416694 -338.411086) (xy 95.457886 -338.446774) (xy 95.493581 -338.487961) (xy 95.52305 -338.533809)
			(xy 95.545694 -338.583384) (xy 95.558418 -338.626704) (xy 97.699322 -338.626704) (xy 97.699783 -338.599129)
			(xy 97.707735 -338.544556) (xy 97.723461 -338.491695) (xy 97.746632 -338.441649) (xy 97.776765 -338.39546)
			(xy 97.813234 -338.354089) (xy 97.833942 -338.335874) (xy 97.842036 -338.328336) (xy 97.851378 -338.308311)
			(xy 97.851976 -338.297266) (xy 97.851976 -338.219542) (xy 97.851392 -338.208494) (xy 97.842039 -338.188473)
			(xy 97.833942 -338.180934) (xy 97.813252 -338.162699) (xy 97.776779 -338.121336) (xy 97.746643 -338.075152)
			(xy 97.723473 -338.025108) (xy 97.707752 -337.972249) (xy 97.699809 -337.917678) (xy 97.699322 -337.890104)
			(xy 97.699759 -337.86285) (xy 97.707516 -337.808896) (xy 97.722873 -337.756596) (xy 97.745518 -337.707014)
			(xy 97.774988 -337.66116) (xy 97.810685 -337.619966) (xy 97.85188 -337.584272) (xy 97.897737 -337.554805)
			(xy 97.947321 -337.532164) (xy 97.999622 -337.516811) (xy 98.053576 -337.509057) (xy 98.08083 -337.508596)
			(xy 98.081338 -337.508596) (xy 98.11512 -337.51012) (xy 98.12528 -337.511136) (xy 98.144584 -337.50504)
			(xy 98.207576 -337.452208) (xy 98.214878 -337.445495) (xy 98.224154 -337.427983) (xy 98.22561 -337.418172)
			(xy 98.22561 -337.41741) (xy 98.228502 -337.389241) (xy 98.241716 -337.334178) (xy 98.262927 -337.281674)
			(xy 98.291666 -337.232882) (xy 98.327304 -337.188876) (xy 98.369056 -337.150622) (xy 98.416005 -337.118961)
			(xy 98.467119 -337.09459) (xy 98.521274 -337.078043) (xy 98.57728 -337.069685) (xy 98.605594 -337.069176)
			(xy 98.632844 -337.069683) (xy 98.686791 -337.077439) (xy 98.739084 -337.092792) (xy 98.78866 -337.115431)
			(xy 98.83451 -337.144896) (xy 98.8757 -337.180585) (xy 98.911391 -337.221773) (xy 98.940858 -337.267621)
			(xy 98.9635 -337.317195) (xy 98.978857 -337.369488) (xy 98.986615 -337.423434) (xy 98.987102 -337.450684)
			(xy 98.986613 -337.478546) (xy 98.978512 -337.533679) (xy 98.962482 -337.587049) (xy 98.938862 -337.63752)
			(xy 98.908154 -337.68402) (xy 98.871012 -337.725562) (xy 98.849942 -337.7438) (xy 98.840798 -337.75142)
			(xy 98.8314 -337.772502) (xy 98.834448 -337.864704) (xy 98.835391 -337.876182) (xy 98.846094 -337.896547)
			(xy 98.855022 -337.90382) (xy 98.855276 -337.904074) (xy 98.875807 -337.919521) (xy 98.91294 -337.95503)
			(xy 98.944972 -337.995202) (xy 98.971323 -338.039309) (xy 98.991515 -338.086554) (xy 99.005184 -338.136081)
			(xy 99.012082 -338.186995) (xy 99.012502 -338.212684) (xy 99.011987 -338.242127) (xy 99.002939 -338.300314)
			(xy 98.985057 -338.356419) (xy 98.958764 -338.409109) (xy 98.924687 -338.457133) (xy 98.904552 -338.478622)
			(xy 98.904298 -338.478876) (xy 98.896575 -338.487741) (xy 98.889414 -338.510104) (xy 98.890582 -338.521802)
			(xy 98.904806 -338.614004) (xy 98.918522 -338.633308) (xy 98.928936 -338.638896) (xy 98.954506 -338.6533)
			(xy 99.001281 -338.688741) (xy 99.042078 -338.730927) (xy 99.075934 -338.778862) (xy 99.102052 -338.831415)
			(xy 99.119814 -338.887348) (xy 99.128803 -338.945341) (xy 99.129342 -338.974684) (xy 99.128834 -339.003602)
			(xy 99.120106 -339.060774) (xy 99.102848 -339.115974) (xy 99.077454 -339.167936) (xy 99.044508 -339.21547)
			(xy 99.004763 -339.257485) (xy 98.982276 -339.275674) (xy 98.973486 -339.283298) (xy 98.963294 -339.304186)
			(xy 98.962718 -339.315806) (xy 98.962718 -339.395562) (xy 98.963229 -339.407198) (xy 98.973437 -339.428107)
			(xy 98.982276 -339.435694) (xy 99.004752 -339.453894) (xy 99.044488 -339.495912) (xy 99.077429 -339.543444)
			(xy 99.102819 -339.595404) (xy 99.120077 -339.6506) (xy 99.128807 -339.707768) (xy 99.129342 -339.736684)
			(xy 99.128807 -339.763933) (xy 99.121054 -339.817877) (xy 99.105702 -339.870169) (xy 99.083065 -339.919744)
			(xy 99.053604 -339.965593) (xy 99.017918 -340.006782) (xy 98.976733 -340.042474) (xy 98.930888 -340.071941)
			(xy 98.881316 -340.094585) (xy 98.829026 -340.109943) (xy 98.775083 -340.117703) (xy 98.747834 -340.118192)
			(xy 98.718894 -340.117667) (xy 98.661681 -340.108901) (xy 98.606448 -340.091596) (xy 98.554462 -340.066148)
			(xy 98.506915 -340.033142) (xy 98.464898 -339.993334) (xy 98.429374 -339.947637) (xy 98.401158 -339.897099)
			(xy 98.380898 -339.842881) (xy 98.374454 -339.814662) (xy 98.374454 -339.814408) (xy 98.37202 -339.80506)
			(xy 98.361327 -339.788995) (xy 98.353626 -339.783166) (xy 98.287332 -339.7377) (xy 98.26879 -339.733382)
			(xy 98.259138 -339.734906) (xy 98.25863 -339.734906) (xy 98.243871 -339.737128) (xy 98.214119 -339.739547)
			(xy 98.199194 -339.739732) (xy 98.171944 -339.739228) (xy 98.117998 -339.731471) (xy 98.065705 -339.716116)
			(xy 98.016129 -339.693476) (xy 97.97028 -339.664012) (xy 97.929091 -339.628322) (xy 97.893399 -339.587134)
			(xy 97.863932 -339.541287) (xy 97.84129 -339.491712) (xy 97.825933 -339.43942) (xy 97.818173 -339.385474)
			(xy 97.817686 -339.358224) (xy 97.818159 -339.330984) (xy 97.825925 -339.277061) (xy 97.841289 -339.224793)
			(xy 97.863937 -339.175245) (xy 97.893407 -339.129424) (xy 97.910904 -339.108542) (xy 97.917723 -339.099699)
			(xy 97.923796 -339.07824) (xy 97.922588 -339.06714) (xy 97.908364 -338.978748) (xy 97.895918 -338.96046)
			(xy 97.886012 -338.954618) (xy 97.862006 -338.939797) (xy 97.818266 -338.904163) (xy 97.780254 -338.862474)
			(xy 97.748798 -338.81564) (xy 97.724585 -338.764683) (xy 97.708143 -338.710714) (xy 97.699831 -338.654913)
			(xy 97.699322 -338.626704) (xy 95.558418 -338.626704) (xy 95.561053 -338.635677) (xy 95.568813 -338.689623)
			(xy 95.569278 -338.716874) (xy 95.568635 -338.748438) (xy 95.558241 -338.810703) (xy 95.537749 -338.870412)
			(xy 95.523304 -338.898484) (xy 95.518478 -338.907374) (xy 95.516446 -338.926932) (xy 95.539306 -339.005418)
			(xy 95.542545 -339.014842) (xy 95.554962 -339.030401) (xy 95.563436 -339.035644) (xy 95.588526 -339.050211)
			(xy 95.634411 -339.085709) (xy 95.674389 -339.127748) (xy 95.707537 -339.175359) (xy 95.73309 -339.227442)
			(xy 95.750457 -339.282794) (xy 95.759239 -339.340139) (xy 95.759778 -339.369146) (xy 95.759292 -339.396397)
			(xy 95.751536 -339.450345) (xy 95.736181 -339.50264) (xy 95.713539 -339.552217) (xy 95.684073 -339.598067)
			(xy 95.648382 -339.639258) (xy 95.607191 -339.674949) (xy 95.561341 -339.704415) (xy 95.511764 -339.727057)
			(xy 95.459469 -339.742412) (xy 95.405521 -339.750168) (xy 95.351019 -339.750168) (xy 95.297071 -339.742412)
			(xy 95.244776 -339.727057) (xy 95.195199 -339.704415) (xy 95.149349 -339.674949) (xy 95.108158 -339.639258)
			(xy 95.072467 -339.598067) (xy 95.043001 -339.552217) (xy 95.020359 -339.50264) (xy 95.005004 -339.450345)
			(xy 94.997248 -339.396397) (xy 94.996762 -339.369146) (xy 94.99742 -339.337583) (xy 95.007809 -339.275318)
			(xy 95.028295 -339.215609) (xy 95.042736 -339.187536) (xy 95.047562 -339.178646) (xy 95.049594 -339.159088)
			(xy 95.026734 -339.080602) (xy 95.023509 -339.071172) (xy 95.011083 -339.055615) (xy 95.002604 -339.050376)
			(xy 94.995238 -339.046312) (xy 94.985332 -339.04047) (xy 94.963488 -339.038438) (xy 94.868746 -339.071966)
			(xy 94.852998 -339.08746) (xy 94.848934 -339.097874) (xy 94.838917 -339.12295) (xy 94.812845 -339.170235)
			(xy 94.780355 -339.213362) (xy 94.761558 -339.232748) (xy 94.754801 -339.240206) (xy 94.747078 -339.258766)
			(xy 94.746572 -339.268816) (xy 94.746572 -340.421468) (xy 94.746995 -340.431538) (xy 94.754715 -340.450137)
			(xy 94.761558 -340.457536) (xy 97.604326 -343.300304) (xy 97.62156 -343.318403) (xy 97.6493 -343.359966)
			(xy 97.668405 -343.406139) (xy 97.67814 -343.455151) (xy 97.678748 -343.480136) (xy 97.678748 -344.396822)
			(xy 101.382322 -344.396822) (xy 101.382816 -344.369348) (xy 101.390705 -344.314968) (xy 101.406323 -344.262286)
			(xy 101.429346 -344.212393) (xy 101.459297 -344.166324) (xy 101.477064 -344.145362) (xy 101.477318 -344.145108)
			(xy 101.482909 -344.138025) (xy 101.489153 -344.121105) (xy 101.48951 -344.112088) (xy 101.48951 -344.044524)
			(xy 101.489139 -344.035509) (xy 101.482901 -344.018592) (xy 101.477318 -344.011504) (xy 101.47681 -344.010996)
			(xy 101.45908 -343.990047) (xy 101.429197 -343.944015) (xy 101.40623 -343.894171) (xy 101.390654 -343.841546)
			(xy 101.382793 -343.787231) (xy 101.382322 -343.75979) (xy 101.382808 -343.732539) (xy 101.390564 -343.678591)
			(xy 101.405919 -343.626296) (xy 101.428561 -343.576719) (xy 101.458027 -343.530869) (xy 101.493718 -343.489678)
			(xy 101.534909 -343.453987) (xy 101.580759 -343.424521) (xy 101.630336 -343.401879) (xy 101.682631 -343.386524)
			(xy 101.736579 -343.378768) (xy 101.791081 -343.378768) (xy 101.845029 -343.386524) (xy 101.897324 -343.401879)
			(xy 101.946901 -343.424521) (xy 101.992751 -343.453987) (xy 102.033942 -343.489678) (xy 102.069633 -343.530869)
			(xy 102.099099 -343.576719) (xy 102.121741 -343.626296) (xy 102.137096 -343.678591) (xy 102.144852 -343.732539)
			(xy 102.145338 -343.75979) (xy 102.144836 -343.787264) (xy 102.136947 -343.841643) (xy 102.12133 -343.894324)
			(xy 102.098309 -343.944217) (xy 102.068361 -343.990287) (xy 102.050596 -344.01125) (xy 102.050342 -344.011504)
			(xy 102.044741 -344.01858) (xy 102.038504 -344.035505) (xy 102.03815 -344.044524) (xy 102.03815 -344.112088)
			(xy 102.038502 -344.121106) (xy 102.044752 -344.138023) (xy 102.050342 -344.145108) (xy 102.05085 -344.145616)
			(xy 102.068579 -344.166566) (xy 102.098464 -344.212597) (xy 102.121432 -344.262441) (xy 102.137007 -344.315066)
			(xy 102.144868 -344.369381) (xy 102.145338 -344.396822) (xy 102.144852 -344.424073) (xy 102.137096 -344.478021)
			(xy 102.121741 -344.530316) (xy 102.099099 -344.579893) (xy 102.069633 -344.625743) (xy 102.033942 -344.666934)
			(xy 101.992751 -344.702625) (xy 101.946901 -344.732091) (xy 101.897324 -344.754733) (xy 101.845029 -344.770088)
			(xy 101.791081 -344.777844) (xy 101.736579 -344.777844) (xy 101.682631 -344.770088) (xy 101.630336 -344.754733)
			(xy 101.580759 -344.732091) (xy 101.534909 -344.702625) (xy 101.493718 -344.666934) (xy 101.458027 -344.625743)
			(xy 101.428561 -344.579893) (xy 101.405919 -344.530316) (xy 101.390564 -344.478021) (xy 101.382808 -344.424073)
			(xy 101.382322 -344.396822) (xy 97.678748 -344.396822) (xy 97.678748 -344.750644) (xy 97.679138 -344.760717)
			(xy 97.686882 -344.779316) (xy 97.693734 -344.786712) (xy 98.784918 -345.877642) (xy 98.792313 -345.884488)
			(xy 98.810916 -345.892203) (xy 98.820986 -345.892628) (xy 101.743002 -345.892628) (xy 101.753074 -345.892223)
			(xy 101.771673 -345.88449) (xy 101.77907 -345.877642) (xy 102.362254 -345.294712) (xy 102.369075 -345.287296)
			(xy 102.376807 -345.268709) (xy 102.37724 -345.258644) (xy 102.37724 -344.009218) (xy 102.377563 -343.991052)
			(xy 102.382793 -343.955097) (xy 102.387654 -343.93759) (xy 102.38891 -343.932612) (xy 102.389686 -343.922378)
			(xy 102.389178 -343.91727) (xy 102.38797 -343.906198) (xy 102.386702 -343.883958) (xy 102.386638 -343.87282)
			(xy 102.387074 -343.845566) (xy 102.39483 -343.791611) (xy 102.410185 -343.73931) (xy 102.432829 -343.689727)
			(xy 102.462299 -343.643872) (xy 102.497996 -343.602677) (xy 102.539192 -343.566983) (xy 102.58505 -343.537516)
			(xy 102.634634 -343.514876) (xy 102.686937 -343.499524) (xy 102.740892 -343.491772) (xy 102.768146 -343.491312)
			(xy 102.7684 -343.491312) (xy 102.793604 -343.491715) (xy 102.843571 -343.498354) (xy 102.892226 -343.51153)
			(xy 102.938716 -343.531011) (xy 102.960678 -343.543382) (xy 102.970584 -343.549224) (xy 102.992428 -343.551256)
			(xy 103.08717 -343.517728) (xy 103.102918 -343.502234) (xy 103.106982 -343.49182) (xy 103.117687 -343.465047)
			(xy 103.145972 -343.414804) (xy 103.1815 -343.369393) (xy 103.22346 -343.32985) (xy 103.270896 -343.297075)
			(xy 103.322727 -343.271817) (xy 103.377769 -343.254651) (xy 103.434769 -343.245969) (xy 103.463598 -343.24544)
			(xy 103.490853 -343.245857) (xy 103.544808 -343.253615) (xy 103.59711 -343.268973) (xy 103.646693 -343.291619)
			(xy 103.692548 -343.321092) (xy 103.733742 -343.35679) (xy 103.769436 -343.397988) (xy 103.798903 -343.443847)
			(xy 103.801787 -343.450164) (xy 105.961942 -343.450164) (xy 105.962437 -343.42259) (xy 105.970382 -343.368018)
			(xy 105.9861 -343.315158) (xy 106.009264 -343.265112) (xy 106.039392 -343.218922) (xy 106.075856 -343.17755)
			(xy 106.096562 -343.159334) (xy 106.104632 -343.151775) (xy 106.113987 -343.131766) (xy 106.114596 -343.120726)
			(xy 106.114596 -343.043002) (xy 106.114028 -343.031953) (xy 106.104663 -343.011932) (xy 106.096562 -343.004394)
			(xy 106.075837 -342.986198) (xy 106.03937 -342.944825) (xy 106.00924 -342.898632) (xy 105.986077 -342.848581)
			(xy 105.970363 -342.795716) (xy 105.962426 -342.741139) (xy 105.961942 -342.713564) (xy 105.962322 -342.686308)
			(xy 105.970085 -342.632351) (xy 105.985448 -342.580049) (xy 106.008098 -342.530465) (xy 106.037575 -342.48461)
			(xy 106.073277 -342.443416) (xy 106.114479 -342.407723) (xy 106.160341 -342.378257) (xy 106.20993 -342.355618)
			(xy 106.262236 -342.340266) (xy 106.316194 -342.332515) (xy 106.34345 -342.332056) (xy 106.375072 -342.33266)
			(xy 106.437445 -342.343115) (xy 106.497234 -342.363729) (xy 106.525314 -342.378284) (xy 106.53395 -342.382856)
			(xy 106.553254 -342.385142) (xy 106.639868 -342.362028) (xy 106.655362 -342.350344) (xy 106.660442 -342.341962)
			(xy 106.676797 -342.316317) (xy 106.716359 -342.270121) (xy 106.739182 -342.250014) (xy 106.747248 -342.24245)
			(xy 106.756608 -342.222446) (xy 106.757216 -342.211406) (xy 106.757216 -342.133682) (xy 106.756629 -342.122634)
			(xy 106.74728 -342.102611) (xy 106.739182 -342.095074) (xy 106.718451 -342.076884) (xy 106.681983 -342.03551)
			(xy 106.651854 -341.989316) (xy 106.628692 -341.939264) (xy 106.61298 -341.886398) (xy 106.605045 -341.83182)
			(xy 106.604562 -341.804244) (xy 106.605048 -341.776993) (xy 106.612804 -341.723045) (xy 106.628159 -341.67075)
			(xy 106.650801 -341.621173) (xy 106.680267 -341.575323) (xy 106.715958 -341.534132) (xy 106.757149 -341.498441)
			(xy 106.802999 -341.468975) (xy 106.852576 -341.446333) (xy 106.904871 -341.430978) (xy 106.958819 -341.423222)
			(xy 107.013321 -341.423222) (xy 107.067269 -341.430978) (xy 107.119564 -341.446333) (xy 107.169141 -341.468975)
			(xy 107.214991 -341.498441) (xy 107.256182 -341.534132) (xy 107.291873 -341.575323) (xy 107.321339 -341.621173)
			(xy 107.343981 -341.67075) (xy 107.359336 -341.723045) (xy 107.367092 -341.776993) (xy 107.367578 -341.804244)
			(xy 107.367081 -341.831818) (xy 107.359136 -341.886389) (xy 107.343418 -341.939249) (xy 107.320254 -341.989295)
			(xy 107.290126 -342.035486) (xy 107.253663 -342.076858) (xy 107.232958 -342.095074) (xy 107.224887 -342.102633)
			(xy 107.215532 -342.122642) (xy 107.214924 -342.133682) (xy 107.214924 -342.211406) (xy 107.215537 -342.22245)
			(xy 107.22487 -342.242472) (xy 107.232958 -342.250014) (xy 107.253671 -342.268224) (xy 107.290143 -342.309592)
			(xy 107.320276 -342.355781) (xy 107.343442 -342.40583) (xy 107.359157 -342.458693) (xy 107.367094 -342.513269)
			(xy 107.367578 -342.540844) (xy 107.367008 -342.570786) (xy 107.357634 -342.629932) (xy 107.339138 -342.686889)
			(xy 107.311974 -342.740259) (xy 107.27681 -342.788732) (xy 107.256072 -342.810338) (xy 107.248971 -342.818108)
			(xy 107.241235 -342.837659) (xy 107.241086 -342.848184) (xy 107.244134 -342.922606) (xy 107.245046 -342.933142)
			(xy 107.254233 -342.952166) (xy 107.261914 -342.959436) (xy 107.282469 -342.977667) (xy 107.318675 -343.018991)
			(xy 107.34858 -343.065079) (xy 107.371568 -343.114979) (xy 107.387162 -343.167661) (xy 107.39504 -343.222034)
			(xy 107.395518 -343.249504) (xy 107.395049 -343.277078) (xy 107.387096 -343.331651) (xy 107.371371 -343.38451)
			(xy 107.348202 -343.434556) (xy 107.31807 -343.480746) (xy 107.281604 -343.522118) (xy 107.260898 -343.540334)
			(xy 107.252807 -343.547875) (xy 107.243462 -343.567897) (xy 107.242864 -343.578942) (xy 107.242864 -343.656666)
			(xy 107.243431 -343.667716) (xy 107.252795 -343.687738) (xy 107.260898 -343.695274) (xy 107.281599 -343.713496)
			(xy 107.318071 -343.754862) (xy 107.348204 -343.80105) (xy 107.371371 -343.851096) (xy 107.38709 -343.903957)
			(xy 107.395032 -343.95853) (xy 107.395518 -343.986104) (xy 107.395032 -344.013355) (xy 107.387276 -344.067303)
			(xy 107.371921 -344.119598) (xy 107.349279 -344.169175) (xy 107.319813 -344.215025) (xy 107.284122 -344.256216)
			(xy 107.242931 -344.291907) (xy 107.197081 -344.321373) (xy 107.147504 -344.344015) (xy 107.095209 -344.35937)
			(xy 107.041261 -344.367126) (xy 106.986759 -344.367126) (xy 106.932811 -344.35937) (xy 106.880516 -344.344015)
			(xy 106.830939 -344.321373) (xy 106.785089 -344.291907) (xy 106.743898 -344.256216) (xy 106.708207 -344.215025)
			(xy 106.678741 -344.169175) (xy 106.656099 -344.119598) (xy 106.640744 -344.067303) (xy 106.632988 -344.013355)
			(xy 106.632502 -343.986104) (xy 106.632502 -343.985342) (xy 106.632746 -343.966675) (xy 106.636431 -343.929523)
			(xy 106.639868 -343.911174) (xy 106.642662 -343.897204) (xy 106.63301 -343.870534) (xy 106.540046 -343.796366)
			(xy 106.512106 -343.79281) (xy 106.498898 -343.798652) (xy 106.474378 -343.809107) (xy 106.423142 -343.823814)
			(xy 106.370356 -343.831233) (xy 106.343704 -343.831672) (xy 106.34345 -343.831672) (xy 106.316197 -343.831198)
			(xy 106.262244 -343.823447) (xy 106.209944 -343.808095) (xy 106.160362 -343.785456) (xy 106.114507 -343.75599)
			(xy 106.073313 -343.720297) (xy 106.037618 -343.679104) (xy 106.008151 -343.63325) (xy 105.985509 -343.583669)
			(xy 105.970156 -343.531369) (xy 105.962403 -343.477417) (xy 105.961942 -343.450164) (xy 103.801787 -343.450164)
			(xy 103.821543 -343.493433) (xy 103.836895 -343.545737) (xy 103.844646 -343.599693) (xy 103.845106 -343.626948)
			(xy 103.844449 -343.658511) (xy 103.834061 -343.720776) (xy 103.813574 -343.780485) (xy 103.799132 -343.808558)
			(xy 103.794306 -343.817448) (xy 103.792274 -343.837006) (xy 103.815134 -343.915492) (xy 103.818373 -343.924916)
			(xy 103.83079 -343.940476) (xy 103.839264 -343.945718) (xy 103.864349 -343.960293) (xy 103.910233 -343.995791)
			(xy 103.95021 -344.037829) (xy 103.983358 -344.085439) (xy 104.008911 -344.13752) (xy 104.026281 -344.192871)
			(xy 104.035065 -344.250214) (xy 104.035606 -344.27922) (xy 104.03512 -344.306471) (xy 104.027364 -344.360419)
			(xy 104.012009 -344.412714) (xy 103.989367 -344.462291) (xy 103.959901 -344.508141) (xy 103.92421 -344.549332)
			(xy 103.883019 -344.585023) (xy 103.837169 -344.614489) (xy 103.787592 -344.637131) (xy 103.735297 -344.652486)
			(xy 103.681349 -344.660242) (xy 103.626847 -344.660242) (xy 103.572899 -344.652486) (xy 103.520604 -344.637131)
			(xy 103.471027 -344.614489) (xy 103.425177 -344.585023) (xy 103.383986 -344.549332) (xy 103.348295 -344.508141)
			(xy 103.318829 -344.462291) (xy 103.296187 -344.412714) (xy 103.280832 -344.360419) (xy 103.273076 -344.306471)
			(xy 103.27259 -344.27922) (xy 103.273235 -344.247657) (xy 103.283628 -344.185391) (xy 103.30412 -344.125682)
			(xy 103.318564 -344.09761) (xy 103.32339 -344.08872) (xy 103.325422 -344.069162) (xy 103.302562 -343.990676)
			(xy 103.299337 -343.981246) (xy 103.28691 -343.96569) (xy 103.278432 -343.96045) (xy 103.271066 -343.956386)
			(xy 103.26116 -343.950544) (xy 103.239316 -343.948512) (xy 103.144574 -343.98204) (xy 103.128826 -343.997534)
			(xy 103.124762 -344.007948) (xy 103.115304 -344.031836) (xy 103.090831 -344.07701) (xy 103.060516 -344.118491)
			(xy 103.024908 -344.155529) (xy 102.984652 -344.187452) (xy 102.940475 -344.213683) (xy 102.91699 -344.224102)
			(xy 102.916736 -344.224102) (xy 102.907735 -344.228438) (xy 102.893707 -344.242631) (xy 102.886177 -344.261111)
			(xy 102.885748 -344.271092) (xy 102.885748 -345.385136) (xy 102.885141 -345.41012) (xy 102.875396 -345.459128)
			(xy 102.856288 -345.505298) (xy 102.828548 -345.546858) (xy 102.811326 -345.564968) (xy 102.049326 -346.326968)
			(xy 102.031251 -346.344247) (xy 101.989699 -346.372054) (xy 101.943522 -346.391222) (xy 101.894492 -346.401012)
			(xy 101.869494 -346.401644) (xy 98.694494 -346.401644) (xy 98.669497 -346.401021) (xy 98.620473 -346.391214)
			(xy 98.574303 -346.372037) (xy 98.532757 -346.344225) (xy 98.514662 -346.326968) (xy 97.244662 -345.056968)
			(xy 97.22746 -345.03884) (xy 97.199714 -344.997287) (xy 97.180601 -344.951123) (xy 97.170854 -344.902118)
			(xy 97.17024 -344.877136) (xy 97.17024 -343.606628) (xy 97.169816 -343.596558) (xy 97.162096 -343.57796)
			(xy 97.155254 -343.57056) (xy 94.539308 -340.954614) (xy 94.531896 -340.94793) (xy 94.513463 -340.940333)
			(xy 94.493525 -340.940333) (xy 94.475092 -340.94793) (xy 94.46768 -340.954614) (xy 94.175326 -341.246968)
			(xy 94.157251 -341.264247) (xy 94.115699 -341.292054) (xy 94.069522 -341.311222) (xy 94.020492 -341.321012)
			(xy 93.995494 -341.321644) (xy 86.835742 -341.321644) (xy 86.810747 -341.320992) (xy 86.761724 -341.311194)
			(xy 86.715553 -341.292025) (xy 86.674006 -341.264222) (xy 86.65591 -341.246968) (xy 86.196932 -340.78799)
			(xy 86.18952 -340.781306) (xy 86.171087 -340.773709) (xy 86.151149 -340.773709) (xy 86.132716 -340.781306)
			(xy 86.125304 -340.78799) (xy 85.666326 -341.246968) (xy 85.648251 -341.264247) (xy 85.606699 -341.292054)
			(xy 85.560522 -341.311222) (xy 85.511492 -341.321012) (xy 85.486494 -341.321644) (xy 78.374494 -341.321644)
			(xy 78.349497 -341.321021) (xy 78.300473 -341.311214) (xy 78.254303 -341.292037) (xy 78.212757 -341.264225)
			(xy 78.194662 -341.246968) (xy 77.838808 -340.891114) (xy 77.831396 -340.88443) (xy 77.812963 -340.876833)
			(xy 77.793025 -340.876833) (xy 77.774592 -340.88443) (xy 77.76718 -340.891114) (xy 77.308202 -341.350092)
			(xy 77.290098 -341.367339) (xy 77.248556 -341.395151) (xy 77.202388 -341.414327) (xy 77.153366 -341.424129)
			(xy 77.12837 -341.424768) (xy 73.059544 -341.424768) (xy 73.034549 -341.424108) (xy 72.985528 -341.414311)
			(xy 72.939357 -341.395145) (xy 72.897809 -341.367344) (xy 72.879712 -341.350092) (xy 72.229218 -340.699598)
			(xy 72.221806 -340.692773) (xy 72.203216 -340.685045) (xy 72.19315 -340.684612) (xy 71.259192 -340.684612)
			(xy 71.249122 -340.68503) (xy 71.230524 -340.692756) (xy 71.223124 -340.699598) (xy 70.802754 -341.119968)
			(xy 70.784667 -341.137233) (xy 70.74312 -341.165043) (xy 70.696946 -341.184214) (xy 70.647919 -341.19401)
			(xy 70.622922 -341.194644) (xy 70.119494 -341.194644) (xy 70.094497 -341.194021) (xy 70.045473 -341.184214)
			(xy 69.999303 -341.165037) (xy 69.957757 -341.137225) (xy 69.939662 -341.119968) (xy 69.483732 -340.664038)
			(xy 69.47632 -340.657354) (xy 69.457887 -340.649757) (xy 69.437949 -340.649757) (xy 69.419516 -340.657354)
			(xy 69.412104 -340.664038) (xy 69.315584 -340.760558) (xy 69.297495 -340.777803) (xy 69.255928 -340.80554)
			(xy 69.209752 -340.824641) (xy 69.160738 -340.834374) (xy 69.135752 -340.83498) (xy 68.616322 -340.83498)
			(xy 68.606251 -340.835396) (xy 68.587652 -340.843121) (xy 68.580254 -340.849966) (xy 66.781934 -342.648286)
			(xy 66.775112 -342.655701) (xy 66.767381 -342.674289) (xy 66.766948 -342.684354) (xy 66.766948 -346.655644)
			(xy 66.767338 -346.665717) (xy 66.775082 -346.684316) (xy 66.781934 -346.691712) (xy 67.302126 -347.211904)
			(xy 67.31936 -347.230003) (xy 67.3471 -347.271566) (xy 67.366205 -347.317739) (xy 67.37594 -347.366751)
			(xy 67.376548 -347.391736) (xy 67.376548 -351.557336) (xy 67.375941 -351.58232) (xy 67.366196 -351.631328)
			(xy 67.347088 -351.677498) (xy 67.319348 -351.719058) (xy 67.302126 -351.737168) (xy 65.8368 -353.202494)
			(xy 65.818694 -353.219721) (xy 65.777135 -353.247464) (xy 65.730963 -353.266571) (xy 65.681952 -353.276308)
			(xy 65.656968 -353.276916) (xy 61.407294 -353.276916) (xy 61.382311 -353.276299) (xy 61.333302 -353.266559)
			(xy 61.287133 -353.247453) (xy 61.245572 -353.219715) (xy 61.227462 -353.202494) (xy 60.949332 -352.924364)
			(xy 60.94192 -352.91768) (xy 60.923487 -352.910083) (xy 60.903549 -352.910083) (xy 60.885116 -352.91768)
			(xy 60.877704 -352.924364) (xy 60.653676 -353.148392) (xy 60.635583 -353.165651) (xy 60.594037 -353.193461)
			(xy 60.547865 -353.212633) (xy 60.498841 -353.222432) (xy 60.473844 -353.223068) (xy 53.614828 -353.223068)
			(xy 53.604758 -353.22349) (xy 53.586159 -353.231211) (xy 53.57876 -353.238054) (xy 53.174646 -353.641914)
			(xy 53.156524 -353.659122) (xy 53.114969 -353.686868) (xy 53.068803 -353.705979) (xy 53.019797 -353.715724)
			(xy 52.994814 -353.716336) (xy 28.19781 -353.716336) (xy 28.18774 -353.716757) (xy 28.169142 -353.72448)
			(xy 28.161742 -353.731322) (xy 27.345894 -354.547424) (xy 27.33905 -354.554821) (xy 27.331333 -354.573423)
			(xy 27.330908 -354.583492) (xy 27.330908 -355.2444) (xy 28.446982 -355.2444) (xy 28.451053 -355.188778)
			(xy 28.463179 -355.134341) (xy 28.483102 -355.08225) (xy 28.510398 -355.033615) (xy 28.544484 -354.989472)
			(xy 28.584633 -354.950763) (xy 28.629991 -354.918312) (xy 28.679591 -354.892811) (xy 28.732375 -354.874804)
			(xy 28.787218 -354.864674) (xy 28.842952 -354.862637) (xy 28.898389 -354.868737) (xy 28.952346 -354.882843)
			(xy 29.003675 -354.904655) (xy 29.051281 -354.933709) (xy 29.094149 -354.969384) (xy 29.131366 -355.010921)
			(xy 29.162139 -355.057434) (xy 29.185811 -355.107931) (xy 29.201879 -355.161338) (xy 29.209999 -355.216514)
			(xy 29.210508 -355.2444) (xy 29.209999 -355.272286) (xy 29.201879 -355.327462) (xy 29.185811 -355.380869)
			(xy 29.162139 -355.431366) (xy 29.131366 -355.477879) (xy 29.094149 -355.519416) (xy 29.051281 -355.555091)
			(xy 29.003675 -355.584145) (xy 28.952346 -355.605957) (xy 28.898389 -355.620063) (xy 28.842952 -355.626163)
			(xy 28.787218 -355.624126) (xy 28.732375 -355.613996) (xy 28.679591 -355.595989) (xy 28.629991 -355.570488)
			(xy 28.584633 -355.538037) (xy 28.544484 -355.499328) (xy 28.510398 -355.455185) (xy 28.483102 -355.40655)
			(xy 28.463179 -355.354459) (xy 28.451053 -355.300022) (xy 28.446982 -355.2444) (xy 27.330908 -355.2444)
			(xy 27.330908 -356.3874) (xy 27.964382 -356.3874) (xy 27.968453 -356.331778) (xy 27.980579 -356.277341)
			(xy 28.000502 -356.22525) (xy 28.027798 -356.176615) (xy 28.061884 -356.132472) (xy 28.102033 -356.093763)
			(xy 28.147391 -356.061312) (xy 28.196991 -356.035811) (xy 28.249775 -356.017804) (xy 28.304618 -356.007674)
			(xy 28.360352 -356.005637) (xy 28.415789 -356.011737) (xy 28.469746 -356.025843) (xy 28.521075 -356.047655)
			(xy 28.568681 -356.076709) (xy 28.611549 -356.112384) (xy 28.648766 -356.153921) (xy 28.679539 -356.200434)
			(xy 28.703211 -356.250931) (xy 28.719279 -356.304338) (xy 28.727399 -356.359514) (xy 28.727908 -356.3874)
			(xy 28.727399 -356.415286) (xy 28.719279 -356.470462) (xy 28.703211 -356.523869) (xy 28.679539 -356.574366)
			(xy 28.648766 -356.620879) (xy 28.611549 -356.662416) (xy 28.568681 -356.698091) (xy 28.521075 -356.727145)
			(xy 28.469746 -356.748957) (xy 28.415789 -356.763063) (xy 28.360352 -356.769163) (xy 28.304618 -356.767126)
			(xy 28.249775 -356.756996) (xy 28.196991 -356.738989) (xy 28.147391 -356.713488) (xy 28.102033 -356.681037)
			(xy 28.061884 -356.642328) (xy 28.027798 -356.598185) (xy 28.000502 -356.54955) (xy 27.980579 -356.497459)
			(xy 27.968453 -356.443022) (xy 27.964382 -356.3874) (xy 27.330908 -356.3874) (xy 27.330908 -357.48595)
			(xy 27.558492 -357.48595) (xy 27.559002 -357.458698) (xy 27.566752 -357.404749) (xy 27.582102 -357.352452)
			(xy 27.604738 -357.302872) (xy 27.634201 -357.257019) (xy 27.66989 -357.215826) (xy 27.711079 -357.180131)
			(xy 27.756928 -357.150662) (xy 27.806505 -357.128019) (xy 27.8588 -357.112663) (xy 27.912748 -357.104905)
			(xy 27.94 -357.104442) (xy 27.970027 -357.105) (xy 28.029331 -357.114467) (xy 28.086421 -357.133104)
			(xy 28.139888 -357.160451) (xy 28.188413 -357.195833) (xy 28.210002 -357.21671) (xy 28.217406 -357.223545)
			(xy 28.236002 -357.231267) (xy 28.24607 -357.231696) (xy 28.55722 -357.231696) (xy 28.567294 -357.231309)
			(xy 28.585893 -357.223564) (xy 28.593288 -357.21671) (xy 31.312866 -354.497132) (xy 31.330945 -354.479857)
			(xy 31.372495 -354.452049) (xy 31.418671 -354.432881) (xy 31.4677 -354.423088) (xy 31.492698 -354.422456)
			(xy 66.716656 -354.422456) (xy 66.726724 -354.422019) (xy 66.745323 -354.414308) (xy 66.752724 -354.40747)
			(xy 78.748382 -342.412066) (xy 78.766489 -342.394841) (xy 78.808049 -342.367099) (xy 78.85422 -342.347993)
			(xy 78.90323 -342.338254) (xy 78.928214 -342.337644) (xy 93.26753 -342.337644) (xy 93.292513 -342.338257)
			(xy 93.341521 -342.348) (xy 93.387691 -342.367107) (xy 93.429252 -342.394845) (xy 93.447362 -342.412066)
			(xy 98.097594 -347.062298) (xy 98.105002 -347.069128) (xy 98.123595 -347.076854) (xy 98.133662 -347.077284)
			(xy 105.652062 -347.077284) (xy 105.66213 -347.076843) (xy 105.680728 -347.069134) (xy 105.68813 -347.062298)
			(xy 108.288582 -344.461846) (xy 108.295392 -344.454422) (xy 108.30313 -344.435841) (xy 108.303568 -344.425778)
			(xy 108.303568 -328.981816) (xy 108.304203 -328.956834) (xy 108.313938 -328.907826) (xy 108.333039 -328.861657)
			(xy 108.360771 -328.820095) (xy 108.37799 -328.801984) (xy 110.576868 -326.603106) (xy 110.583693 -326.595694)
			(xy 110.591423 -326.577104) (xy 110.591854 -326.567038) (xy 110.591854 -326.566784) (xy 110.592298 -326.539509)
			(xy 110.599999 -326.485505) (xy 110.615312 -326.433149) (xy 110.637925 -326.383507) (xy 110.667378 -326.337592)
			(xy 110.70307 -326.29634) (xy 110.744274 -326.260592) (xy 110.790148 -326.231076) (xy 110.839759 -326.208394)
			(xy 110.892094 -326.193009) (xy 110.946087 -326.185235) (xy 110.973362 -326.184768) (xy 111.000626 -326.185277)
			(xy 111.054601 -326.193036) (xy 111.10692 -326.2084) (xy 111.156519 -326.231058) (xy 111.202386 -326.260547)
			(xy 111.243587 -326.296266) (xy 111.279283 -326.337487) (xy 111.308746 -326.383371) (xy 111.331375 -326.432983)
			(xy 111.34671 -326.485311) (xy 111.354438 -326.539289) (xy 111.354402 -326.593818) (xy 111.346602 -326.647786)
			(xy 111.331197 -326.700094) (xy 111.308502 -326.749675) (xy 111.278978 -326.79552) (xy 111.243227 -326.836694)
			(xy 111.201979 -326.872358) (xy 111.156072 -326.901786) (xy 111.106443 -326.924377) (xy 111.054103 -326.939672)
			(xy 111.000119 -326.947359) (xy 110.972854 -326.947784) (xy 110.9726 -326.947784) (xy 110.962528 -326.948187)
			(xy 110.943929 -326.955921) (xy 110.936532 -326.96277) (xy 110.871 -327.028302) (xy 110.864087 -327.035939)
			(xy 110.856488 -327.055065) (xy 110.857 -327.075639) (xy 110.86084 -327.085198) (xy 110.906306 -327.18629)
			(xy 110.933484 -327.202546) (xy 110.949232 -327.20153) (xy 110.973362 -327.200768) (xy 111.000615 -327.201277)
			(xy 111.054567 -327.209029) (xy 111.106866 -327.224381) (xy 111.156447 -327.247019) (xy 111.202302 -327.276485)
			(xy 111.243497 -327.312176) (xy 111.279193 -327.353367) (xy 111.308662 -327.399219) (xy 111.331306 -327.448799)
			(xy 111.346663 -327.501096) (xy 111.354421 -327.555047) (xy 111.354421 -327.609553) (xy 111.346663 -327.663504)
			(xy 111.331306 -327.715801) (xy 111.308662 -327.765381) (xy 111.279193 -327.811233) (xy 111.243497 -327.852424)
			(xy 111.202302 -327.888115) (xy 111.156447 -327.917581) (xy 111.106866 -327.940219) (xy 111.054567 -327.955571)
			(xy 111.000615 -327.963323) (xy 110.973362 -327.963784) (xy 110.94331 -327.963231) (xy 110.883952 -327.95379)
			(xy 110.826807 -327.935163) (xy 110.773287 -327.90781) (xy 110.724716 -327.872408) (xy 110.703106 -327.851516)
			(xy 110.695994 -327.844404) (xy 110.677452 -327.836784) (xy 110.622842 -327.836784) (xy 110.612772 -327.837209)
			(xy 110.594173 -327.844928) (xy 110.586774 -327.85177) (xy 109.208062 -329.230228) (xy 109.201212 -329.23762)
			(xy 109.193499 -329.256226) (xy 109.193076 -329.266296) (xy 109.193076 -344.710258) (xy 109.192474 -344.735242)
			(xy 109.182726 -344.78425) (xy 109.163616 -344.830419) (xy 109.135876 -344.87198) (xy 109.118654 -344.89009)
			(xy 106.116374 -347.89237) (xy 106.098291 -347.909622) (xy 106.056722 -347.937357) (xy 106.010544 -347.956456)
			(xy 105.961528 -347.966187) (xy 105.936542 -347.966792) (xy 97.849182 -347.966792) (xy 97.8242 -347.966161)
			(xy 97.775193 -347.956422) (xy 97.729024 -347.93732) (xy 97.687462 -347.909588) (xy 97.66935 -347.89237)
			(xy 93.019118 -343.242138) (xy 93.011701 -343.235319) (xy 92.993115 -343.227586) (xy 92.98305 -343.227152)
			(xy 79.212694 -343.227152) (xy 79.202623 -343.22756) (xy 79.184024 -343.235291) (xy 79.176626 -343.242138)
			(xy 77.181202 -345.237562) (xy 88.93302 -345.237562) (xy 88.933443 -345.210309) (xy 88.941205 -345.156357)
			(xy 88.956566 -345.104059) (xy 88.979214 -345.05448) (xy 89.008687 -345.008629) (xy 89.044385 -344.967438)
			(xy 89.085582 -344.931747) (xy 89.131438 -344.902282) (xy 89.181021 -344.879643) (xy 89.233322 -344.864291)
			(xy 89.287274 -344.856538) (xy 89.314528 -344.856054) (xy 89.339987 -344.856488) (xy 89.390452 -344.863253)
			(xy 89.439569 -344.876671) (xy 89.486464 -344.896505) (xy 89.530304 -344.922402) (xy 89.570308 -344.953902)
			(xy 89.58834 -344.971878) (xy 89.595447 -344.978501) (xy 89.613201 -344.986344) (xy 89.622884 -344.987118)
			(xy 89.702894 -344.989912) (xy 89.721436 -344.983308) (xy 89.728802 -344.976704) (xy 89.749893 -344.958526)
			(xy 89.796364 -344.927857) (xy 89.8468 -344.904269) (xy 89.900128 -344.888262) (xy 89.955217 -344.880177)
			(xy 89.983056 -344.879676) (xy 90.010426 -344.880149) (xy 90.064606 -344.887963) (xy 90.117109 -344.903449)
			(xy 90.166857 -344.92629) (xy 90.212823 -344.956014) (xy 90.233754 -344.973656) (xy 90.234008 -344.97391)
			(xy 90.241087 -344.979507) (xy 90.25801 -344.985747) (xy 90.267028 -344.986102) (xy 90.334084 -344.986102)
			(xy 90.3431 -344.985737) (xy 90.360017 -344.979495) (xy 90.367104 -344.97391) (xy 90.367104 -344.973656)
			(xy 90.367358 -344.973656) (xy 90.388289 -344.956016) (xy 90.434263 -344.926306) (xy 90.484011 -344.90347)
			(xy 90.536511 -344.887979) (xy 90.590687 -344.88015) (xy 90.618056 -344.879676) (xy 90.646973 -344.880197)
			(xy 90.704145 -344.888922) (xy 90.759345 -344.906177) (xy 90.811308 -344.931568) (xy 90.858841 -344.964513)
			(xy 90.900857 -345.004256) (xy 90.919046 -345.026742) (xy 90.926636 -345.035567) (xy 90.94755 -345.045739)
			(xy 90.959178 -345.0463) (xy 91.038934 -345.0463) (xy 91.050566 -345.045766) (xy 91.071476 -345.035573)
			(xy 91.079066 -345.026742) (xy 91.097287 -345.004284) (xy 91.139299 -344.964545) (xy 91.186827 -344.931602)
			(xy 91.238783 -344.906209) (xy 91.293976 -344.888947) (xy 91.351142 -344.880213) (xy 91.380056 -344.879676)
			(xy 91.407426 -344.880149) (xy 91.461606 -344.887963) (xy 91.514109 -344.903449) (xy 91.563857 -344.92629)
			(xy 91.609823 -344.956014) (xy 91.630754 -344.973656) (xy 91.631008 -344.97391) (xy 91.638087 -344.979507)
			(xy 91.65501 -344.985747) (xy 91.664028 -344.986102) (xy 91.731084 -344.986102) (xy 91.7401 -344.985737)
			(xy 91.757017 -344.979495) (xy 91.764104 -344.97391) (xy 91.764104 -344.973656) (xy 91.764358 -344.973656)
			(xy 91.785291 -344.956015) (xy 91.831259 -344.926291) (xy 91.881005 -344.903445) (xy 91.933507 -344.887949)
			(xy 91.987685 -344.88012) (xy 92.042427 -344.88012) (xy 92.096605 -344.887949) (xy 92.149107 -344.903445)
			(xy 92.198853 -344.926291) (xy 92.244821 -344.956015) (xy 92.265754 -344.973656) (xy 92.266008 -344.97391)
			(xy 92.273087 -344.979507) (xy 92.29001 -344.985747) (xy 92.299028 -344.986102) (xy 92.366084 -344.986102)
			(xy 92.3751 -344.985737) (xy 92.392017 -344.979495) (xy 92.399104 -344.97391) (xy 92.399104 -344.973656)
			(xy 92.399358 -344.973656) (xy 92.420289 -344.956016) (xy 92.466263 -344.926306) (xy 92.516011 -344.90347)
			(xy 92.568511 -344.887979) (xy 92.622687 -344.88015) (xy 92.650056 -344.879676) (xy 92.677307 -344.880196)
			(xy 92.731255 -344.887947) (xy 92.783551 -344.903296) (xy 92.83313 -344.925933) (xy 92.878982 -344.955395)
			(xy 92.920175 -344.991082) (xy 92.955869 -345.03227) (xy 92.985339 -345.078117) (xy 93.007983 -345.127693)
			(xy 93.02334 -345.179986) (xy 93.0311 -345.233933) (xy 93.031564 -345.261184) (xy 93.031019 -345.289629)
			(xy 93.022568 -345.345888) (xy 93.00585 -345.400266) (xy 92.981238 -345.451556) (xy 92.949277 -345.49862)
			(xy 92.910677 -345.540411) (xy 92.888816 -345.558618) (xy 92.880986 -345.565633) (xy 92.871273 -345.584249)
			(xy 92.87002 -345.594686) (xy 92.86494 -345.669362) (xy 92.864763 -345.679888) (xy 92.871843 -345.699691)
			(xy 92.878656 -345.707716) (xy 92.898109 -345.72907) (xy 92.930987 -345.776563) (xy 92.956328 -345.828471)
			(xy 92.973551 -345.883606) (xy 92.982263 -345.940709) (xy 92.982796 -345.96959) (xy 92.98234 -345.996725)
			(xy 92.974645 -346.050445) (xy 92.959409 -346.102532) (xy 92.936941 -346.151931) (xy 92.907694 -346.197645)
			(xy 92.89034 -346.21851) (xy 92.890086 -346.218764) (xy 92.884144 -346.226452) (xy 92.877994 -346.244864)
			(xy 92.878148 -346.254578) (xy 92.881958 -346.324936) (xy 92.882979 -346.334743) (xy 92.891491 -346.352511)
			(xy 92.898468 -346.35948) (xy 92.917459 -346.377615) (xy 92.950775 -346.418205) (xy 92.978215 -346.462976)
			(xy 92.999261 -346.511085) (xy 93.013517 -346.561624) (xy 93.020713 -346.61364) (xy 93.02115 -346.639896)
			(xy 93.020619 -346.667145) (xy 93.012864 -346.721089) (xy 92.997511 -346.77338) (xy 92.974874 -346.822955)
			(xy 92.945412 -346.868803) (xy 92.909725 -346.909992) (xy 92.86854 -346.945684) (xy 92.822695 -346.975152)
			(xy 92.773124 -346.997795) (xy 92.720834 -347.013154) (xy 92.666891 -347.020915) (xy 92.639642 -347.021404)
			(xy 92.612273 -347.020912) (xy 92.558095 -347.013101) (xy 92.505592 -346.997617) (xy 92.455845 -346.974781)
			(xy 92.409877 -346.945063) (xy 92.388944 -346.927424) (xy 92.38869 -346.92717) (xy 92.381613 -346.92157)
			(xy 92.364689 -346.915332) (xy 92.35567 -346.914978) (xy 92.288614 -346.914978) (xy 92.279598 -346.915347)
			(xy 92.262682 -346.921587) (xy 92.255594 -346.92717) (xy 92.255594 -346.927424) (xy 92.25534 -346.927424)
			(xy 92.234407 -346.945062) (xy 92.188434 -346.974773) (xy 92.138687 -346.997609) (xy 92.086186 -347.0131)
			(xy 92.032011 -347.020929) (xy 92.004642 -347.021404) (xy 91.978327 -347.020974) (xy 91.926197 -347.013731)
			(xy 91.875553 -346.999405) (xy 91.827355 -346.978265) (xy 91.782512 -346.950713) (xy 91.741874 -346.917268)
			(xy 91.723718 -346.898214) (xy 91.71619 -346.89082) (xy 91.696915 -346.882291) (xy 91.68638 -346.881704)
			(xy 91.611704 -346.881704) (xy 91.601153 -346.882221) (xy 91.581858 -346.890765) (xy 91.574366 -346.898214)
			(xy 91.556223 -346.917282) (xy 91.51559 -346.950737) (xy 91.470747 -346.978294) (xy 91.422544 -346.999431)
			(xy 91.371894 -347.013745) (xy 91.319759 -347.020967) (xy 91.293442 -347.021404) (xy 91.266073 -347.020912)
			(xy 91.211895 -347.013101) (xy 91.159392 -346.997617) (xy 91.109645 -346.974781) (xy 91.063677 -346.945063)
			(xy 91.042744 -346.927424) (xy 91.04249 -346.92717) (xy 91.035413 -346.92157) (xy 91.018489 -346.915332)
			(xy 91.00947 -346.914978) (xy 90.942414 -346.914978) (xy 90.933398 -346.915347) (xy 90.916482 -346.921587)
			(xy 90.909394 -346.92717) (xy 90.909394 -346.927424) (xy 90.90914 -346.927424) (xy 90.888207 -346.945065)
			(xy 90.842239 -346.974789) (xy 90.792493 -346.997635) (xy 90.739991 -347.013131) (xy 90.685813 -347.02096)
			(xy 90.631071 -347.02096) (xy 90.576893 -347.013131) (xy 90.524391 -346.997635) (xy 90.474645 -346.974789)
			(xy 90.428677 -346.945065) (xy 90.407744 -346.927424) (xy 90.40749 -346.92717) (xy 90.400413 -346.92157)
			(xy 90.383489 -346.915332) (xy 90.37447 -346.914978) (xy 90.307414 -346.914978) (xy 90.298398 -346.915347)
			(xy 90.281482 -346.921587) (xy 90.274394 -346.92717) (xy 90.274394 -346.927424) (xy 90.27414 -346.927424)
			(xy 90.253207 -346.945065) (xy 90.207239 -346.974789) (xy 90.157493 -346.997635) (xy 90.104991 -347.013131)
			(xy 90.050813 -347.02096) (xy 89.996071 -347.02096) (xy 89.941893 -347.013131) (xy 89.889391 -346.997635)
			(xy 89.839645 -346.974789) (xy 89.793677 -346.945065) (xy 89.772744 -346.927424) (xy 89.77249 -346.92717)
			(xy 89.765413 -346.92157) (xy 89.748489 -346.915332) (xy 89.73947 -346.914978) (xy 89.672414 -346.914978)
			(xy 89.663398 -346.915347) (xy 89.646482 -346.921587) (xy 89.639394 -346.92717) (xy 89.639394 -346.927424)
			(xy 89.63914 -346.927424) (xy 89.618207 -346.945062) (xy 89.572234 -346.974773) (xy 89.522487 -346.997609)
			(xy 89.469986 -347.0131) (xy 89.415811 -347.020929) (xy 89.388442 -347.021404) (xy 89.36119 -347.020906)
			(xy 89.30724 -347.013154) (xy 89.254943 -346.997803) (xy 89.205362 -346.975165) (xy 89.159509 -346.945701)
			(xy 89.118316 -346.910011) (xy 89.082621 -346.868822) (xy 89.053153 -346.822971) (xy 89.03051 -346.773393)
			(xy 89.015154 -346.721097) (xy 89.007397 -346.667148) (xy 89.006934 -346.639896) (xy 89.007433 -346.612763)
			(xy 89.015116 -346.559044) (xy 89.030342 -346.506957) (xy 89.0528 -346.457557) (xy 89.082039 -346.411842)
			(xy 89.09939 -346.390976) (xy 89.099644 -346.390722) (xy 89.105596 -346.383041) (xy 89.111739 -346.364624)
			(xy 89.111582 -346.354908) (xy 89.107772 -346.28455) (xy 89.1067 -346.274752) (xy 89.098224 -346.256981)
			(xy 89.091262 -346.250006) (xy 89.07227 -346.231872) (xy 89.038953 -346.191283) (xy 89.011512 -346.146511)
			(xy 88.990466 -346.098402) (xy 88.976211 -346.047862) (xy 88.969016 -345.995846) (xy 88.96858 -345.96959)
			(xy 88.968982 -345.943757) (xy 88.975961 -345.892564) (xy 88.989789 -345.842783) (xy 89.010214 -345.795326)
			(xy 89.036861 -345.751062) (xy 89.069241 -345.710801) (xy 89.087706 -345.69273) (xy 89.08796 -345.692476)
			(xy 89.095447 -345.684537) (xy 89.103483 -345.664272) (xy 89.103454 -345.65336) (xy 89.099644 -345.576144)
			(xy 89.098606 -345.565329) (xy 89.088744 -345.545991) (xy 89.080594 -345.538806) (xy 89.080086 -345.538552)
			(xy 89.057625 -345.520335) (xy 89.017889 -345.47832) (xy 88.984947 -345.430791) (xy 88.959555 -345.378835)
			(xy 88.942294 -345.323642) (xy 88.933559 -345.266476) (xy 88.93302 -345.237562) (xy 77.181202 -345.237562)
			(xy 73.519284 -348.89948) (xy 81.802478 -348.89948) (xy 81.802982 -348.871033) (xy 81.81144 -348.814772)
			(xy 81.828164 -348.760392) (xy 81.852784 -348.709102) (xy 81.884753 -348.66204) (xy 81.923361 -348.620251)
			(xy 81.945226 -348.602046) (xy 81.953061 -348.595036) (xy 81.962773 -348.576416) (xy 81.964022 -348.565978)
			(xy 81.969102 -348.491302) (xy 81.969289 -348.480776) (xy 81.962201 -348.460973) (xy 81.955386 -348.452948)
			(xy 81.93597 -348.431562) (xy 81.903085 -348.384078) (xy 81.877737 -348.332179) (xy 81.860505 -348.27705)
			(xy 81.851784 -348.219953) (xy 81.851246 -348.191074) (xy 81.851732 -348.163823) (xy 81.859488 -348.109875)
			(xy 81.874843 -348.05758) (xy 81.897485 -348.008003) (xy 81.926951 -347.962153) (xy 81.962642 -347.920962)
			(xy 82.003833 -347.885271) (xy 82.049683 -347.855805) (xy 82.09926 -347.833163) (xy 82.151555 -347.817808)
			(xy 82.205503 -347.810052) (xy 82.260005 -347.810052) (xy 82.313953 -347.817808) (xy 82.366248 -347.833163)
			(xy 82.415825 -347.855805) (xy 82.461675 -347.885271) (xy 82.502866 -347.920962) (xy 82.538557 -347.962153)
			(xy 82.568023 -348.008003) (xy 82.590665 -348.05758) (xy 82.60602 -348.109875) (xy 82.613776 -348.163823)
			(xy 82.614262 -348.191074) (xy 82.613711 -348.219519) (xy 82.605261 -348.275777) (xy 82.588544 -348.330155)
			(xy 82.563933 -348.381446) (xy 82.531973 -348.428509) (xy 82.493375 -348.470301) (xy 82.471514 -348.488508)
			(xy 82.463647 -348.495487) (xy 82.453955 -348.51413) (xy 82.452718 -348.524576) (xy 82.447638 -348.599252)
			(xy 82.447467 -348.609778) (xy 82.454543 -348.62958) (xy 82.461354 -348.637606) (xy 82.480802 -348.658964)
			(xy 82.513681 -348.706456) (xy 82.539022 -348.758363) (xy 82.556247 -348.813497) (xy 82.563515 -348.861126)
			(xy 84.464144 -348.861126) (xy 84.464693 -348.832681) (xy 84.473143 -348.776422) (xy 84.48986 -348.722044)
			(xy 84.514471 -348.670754) (xy 84.546432 -348.62369) (xy 84.585031 -348.581899) (xy 84.606892 -348.563692)
			(xy 84.61476 -348.556714) (xy 84.624452 -348.53807) (xy 84.625688 -348.527624) (xy 84.630768 -348.452948)
			(xy 84.630938 -348.442422) (xy 84.623863 -348.42262) (xy 84.617052 -348.414594) (xy 84.597605 -348.393235)
			(xy 84.564726 -348.345743) (xy 84.539384 -348.293837) (xy 84.522159 -348.238702) (xy 84.513446 -348.181601)
			(xy 84.512912 -348.15272) (xy 84.513398 -348.125469) (xy 84.521154 -348.071521) (xy 84.536509 -348.019226)
			(xy 84.559151 -347.969649) (xy 84.588617 -347.923799) (xy 84.624308 -347.882608) (xy 84.665499 -347.846917)
			(xy 84.711349 -347.817451) (xy 84.760926 -347.794809) (xy 84.813221 -347.779454) (xy 84.867169 -347.771698)
			(xy 84.921671 -347.771698) (xy 84.975619 -347.779454) (xy 85.027914 -347.794809) (xy 85.077491 -347.817451)
			(xy 85.123341 -347.846917) (xy 85.164532 -347.882608) (xy 85.200223 -347.923799) (xy 85.229689 -347.969649)
			(xy 85.252331 -348.019226) (xy 85.267686 -348.071521) (xy 85.275442 -348.125469) (xy 85.275928 -348.15272)
			(xy 85.275422 -348.181167) (xy 85.266964 -348.237428) (xy 85.25024 -348.291807) (xy 85.22562 -348.343098)
			(xy 85.193652 -348.39016) (xy 85.155045 -348.431949) (xy 85.13318 -348.450154) (xy 85.125346 -348.457165)
			(xy 85.115633 -348.475784) (xy 85.114384 -348.486222) (xy 85.109304 -348.560898) (xy 85.109116 -348.571424)
			(xy 85.116205 -348.591227) (xy 85.12302 -348.599252) (xy 85.142437 -348.620638) (xy 85.175321 -348.668121)
			(xy 85.200669 -348.720021) (xy 85.217901 -348.77515) (xy 85.226622 -348.832247) (xy 85.22716 -348.861126)
			(xy 85.226675 -348.88826) (xy 85.218989 -348.94198) (xy 85.20376 -348.994066) (xy 85.181298 -349.043466)
			(xy 85.152056 -349.089181) (xy 85.134704 -349.110046) (xy 85.13445 -349.1103) (xy 85.128487 -349.117974)
			(xy 85.122351 -349.136397) (xy 85.122512 -349.146114) (xy 85.126322 -349.216472) (xy 85.127385 -349.226271)
			(xy 85.135868 -349.244041) (xy 85.142832 -349.251016) (xy 85.161804 -349.26917) (xy 85.19512 -349.309756)
			(xy 85.222561 -349.354524) (xy 85.24361 -349.40263) (xy 85.257871 -349.453165) (xy 85.265073 -349.505178)
			(xy 85.265514 -349.531432) (xy 85.265084 -349.557607) (xy 85.257906 -349.609464) (xy 85.243704 -349.659852)
			(xy 85.222744 -349.707825) (xy 85.195421 -349.75248) (xy 85.162246 -349.792978) (xy 85.14334 -349.811086)
			(xy 85.135996 -349.818627) (xy 85.127606 -349.83791) (xy 85.127084 -349.848424) (xy 85.127084 -349.922846)
			(xy 85.127591 -349.933366) (xy 85.135975 -349.952657) (xy 85.14334 -349.960184) (xy 85.162244 -349.978296)
			(xy 85.195432 -350.018785) (xy 85.222764 -350.063437) (xy 85.243724 -350.11141) (xy 85.25792 -350.161801)
			(xy 85.265082 -350.213662) (xy 85.265514 -350.239838) (xy 85.265028 -350.267089) (xy 85.257272 -350.321037)
			(xy 85.241917 -350.373332) (xy 85.219275 -350.422909) (xy 85.189809 -350.468759) (xy 85.154118 -350.50995)
			(xy 85.112927 -350.545641) (xy 85.067077 -350.575107) (xy 85.0175 -350.597749) (xy 84.965205 -350.613104)
			(xy 84.911257 -350.62086) (xy 84.856755 -350.62086) (xy 84.802807 -350.613104) (xy 84.750512 -350.597749)
			(xy 84.700935 -350.575107) (xy 84.655085 -350.545641) (xy 84.613894 -350.50995) (xy 84.578203 -350.468759)
			(xy 84.548737 -350.422909) (xy 84.526095 -350.373332) (xy 84.51074 -350.321037) (xy 84.502984 -350.267089)
			(xy 84.502498 -350.239838) (xy 84.502904 -350.213662) (xy 84.510086 -350.161804) (xy 84.524293 -350.111415)
			(xy 84.545257 -350.063443) (xy 84.572585 -350.018788) (xy 84.605763 -349.978291) (xy 84.624672 -349.960184)
			(xy 84.632031 -349.952655) (xy 84.640412 -349.933363) (xy 84.640928 -349.922846) (xy 84.640928 -349.848424)
			(xy 84.640462 -349.837899) (xy 84.632052 -349.818606) (xy 84.624672 -349.811086) (xy 84.605736 -349.793006)
			(xy 84.572555 -349.752508) (xy 84.545229 -349.707849) (xy 84.524274 -349.65987) (xy 84.510085 -349.609474)
			(xy 84.502927 -349.55761) (xy 84.502498 -349.531432) (xy 84.502968 -349.504298) (xy 84.51066 -349.450578)
			(xy 84.525892 -349.398491) (xy 84.548357 -349.349092) (xy 84.577601 -349.303377) (xy 84.594954 -349.282512)
			(xy 84.595208 -349.282258) (xy 84.60114 -349.274563) (xy 84.607296 -349.256157) (xy 84.607146 -349.246444)
			(xy 84.603336 -349.176086) (xy 84.602306 -349.166281) (xy 84.593801 -349.148512) (xy 84.586826 -349.141542)
			(xy 84.567845 -349.123397) (xy 84.534528 -349.08281) (xy 84.507087 -349.03804) (xy 84.486039 -348.989933)
			(xy 84.471781 -348.939396) (xy 84.464582 -348.887381) (xy 84.464144 -348.861126) (xy 82.563515 -348.861126)
			(xy 82.56496 -348.870599) (xy 82.565494 -348.89948) (xy 82.565032 -348.926614) (xy 82.557339 -348.980335)
			(xy 82.542105 -349.032421) (xy 82.519638 -349.081821) (xy 82.490392 -349.127535) (xy 82.473038 -349.1484)
			(xy 82.472784 -349.148654) (xy 82.466846 -349.156345) (xy 82.460694 -349.174754) (xy 82.460846 -349.184468)
			(xy 82.464656 -349.254826) (xy 82.465682 -349.264632) (xy 82.47419 -349.282401) (xy 82.481166 -349.28937)
			(xy 82.500152 -349.307511) (xy 82.533468 -349.348099) (xy 82.560909 -349.392869) (xy 82.581956 -349.440977)
			(xy 82.596213 -349.491515) (xy 82.60341 -349.543531) (xy 82.603848 -349.569786) (xy 82.603378 -349.597599)
			(xy 82.595301 -349.652636) (xy 82.579317 -349.705916) (xy 82.555764 -349.756309) (xy 82.525142 -349.802748)
			(xy 82.4881 -349.844246) (xy 82.445423 -349.879925) (xy 82.421984 -349.894906) (xy 82.410554 -349.901764)
			(xy 82.397854 -349.924624) (xy 82.3976 -350.0247) (xy 82.397893 -350.033379) (xy 82.403646 -350.049756)
			(xy 82.414528 -350.063278) (xy 82.42173 -350.068134) (xy 82.421984 -350.068134) (xy 82.445372 -350.083138)
			(xy 82.487977 -350.118807) (xy 82.524956 -350.16028) (xy 82.555528 -350.206678) (xy 82.579045 -350.257021)
			(xy 82.59501 -350.310243) (xy 82.603085 -350.365218) (xy 82.603594 -350.393) (xy 82.603108 -350.420251)
			(xy 82.595352 -350.474199) (xy 82.579997 -350.526494) (xy 82.557355 -350.576071) (xy 82.527889 -350.621921)
			(xy 82.492198 -350.663112) (xy 82.451007 -350.698803) (xy 82.405157 -350.728269) (xy 82.35558 -350.750911)
			(xy 82.303285 -350.766266) (xy 82.249337 -350.774022) (xy 82.194835 -350.774022) (xy 82.140887 -350.766266)
			(xy 82.088592 -350.750911) (xy 82.039015 -350.728269) (xy 81.993165 -350.698803) (xy 81.951974 -350.663112)
			(xy 81.916283 -350.621921) (xy 81.886817 -350.576071) (xy 81.864175 -350.526494) (xy 81.84882 -350.474199)
			(xy 81.841064 -350.420251) (xy 81.840578 -350.393) (xy 81.841025 -350.365186) (xy 81.849104 -350.310148)
			(xy 81.865092 -350.256867) (xy 81.888648 -350.206473) (xy 81.919274 -350.160034) (xy 81.95632 -350.118537)
			(xy 81.999001 -350.082859) (xy 82.022442 -350.06788) (xy 82.033872 -350.061022) (xy 82.046572 -350.038162)
			(xy 82.046826 -349.938086) (xy 82.046531 -349.929407) (xy 82.040776 -349.913032) (xy 82.029896 -349.899509)
			(xy 82.022696 -349.894652) (xy 82.022442 -349.894652) (xy 81.999053 -349.879648) (xy 81.956447 -349.84398)
			(xy 81.919467 -349.802508) (xy 81.888895 -349.756109) (xy 81.865378 -349.705766) (xy 81.849414 -349.652544)
			(xy 81.84134 -349.597568) (xy 81.840832 -349.569786) (xy 81.841326 -349.542653) (xy 81.84901 -349.488933)
			(xy 81.864237 -349.436847) (xy 81.886697 -349.387447) (xy 81.915937 -349.341731) (xy 81.933288 -349.320866)
			(xy 81.933542 -349.320612) (xy 81.939499 -349.312934) (xy 81.945639 -349.294515) (xy 81.94548 -349.284798)
			(xy 81.94167 -349.21444) (xy 81.940604 -349.204641) (xy 81.932123 -349.186871) (xy 81.92516 -349.179896)
			(xy 81.906163 -349.161767) (xy 81.872846 -349.121177) (xy 81.845406 -349.076404) (xy 81.824361 -349.028294)
			(xy 81.810107 -348.977753) (xy 81.802913 -348.925736) (xy 81.802478 -348.89948) (xy 73.519284 -348.89948)
			(xy 70.78091 -351.637854) (xy 74.429874 -351.637854) (xy 74.430361 -351.609407) (xy 74.438823 -351.553145)
			(xy 74.455551 -351.498765) (xy 74.480174 -351.447474) (xy 74.512146 -351.400413) (xy 74.550756 -351.358624)
			(xy 74.572622 -351.34042) (xy 74.580467 -351.333419) (xy 74.590174 -351.314793) (xy 74.591418 -351.304352)
			(xy 74.596498 -351.229676) (xy 74.596645 -351.219152) (xy 74.589585 -351.199351) (xy 74.582782 -351.191322)
			(xy 74.563353 -351.169947) (xy 74.53047 -351.12246) (xy 74.505125 -351.070558) (xy 74.487896 -351.015427)
			(xy 74.479178 -350.958328) (xy 74.478642 -350.929448) (xy 74.479128 -350.902197) (xy 74.486884 -350.848249)
			(xy 74.502239 -350.795954) (xy 74.524881 -350.746377) (xy 74.554347 -350.700527) (xy 74.590038 -350.659336)
			(xy 74.631229 -350.623645) (xy 74.677079 -350.594179) (xy 74.726656 -350.571537) (xy 74.778951 -350.556182)
			(xy 74.832899 -350.548426) (xy 74.887401 -350.548426) (xy 74.941349 -350.556182) (xy 74.993644 -350.571537)
			(xy 75.043221 -350.594179) (xy 75.089071 -350.623645) (xy 75.130262 -350.659336) (xy 75.165953 -350.700527)
			(xy 75.195419 -350.746377) (xy 75.218061 -350.795954) (xy 75.233416 -350.848249) (xy 75.241172 -350.902197)
			(xy 75.241658 -350.929448) (xy 75.24116 -350.957895) (xy 75.232699 -351.014156) (xy 75.215973 -351.068535)
			(xy 75.191351 -351.119825) (xy 75.159382 -351.166887) (xy 75.120775 -351.208677) (xy 75.09891 -351.226882)
			(xy 75.091053 -351.233871) (xy 75.081355 -351.252507) (xy 75.080114 -351.26295) (xy 75.075034 -351.337626)
			(xy 75.074878 -351.348151) (xy 75.081943 -351.367953) (xy 75.08875 -351.37598) (xy 75.108185 -351.39735)
			(xy 75.141066 -351.444838) (xy 75.16641 -351.496742) (xy 75.183637 -351.551874) (xy 75.190908 -351.5995)
			(xy 77.09154 -351.5995) (xy 77.092072 -351.571055) (xy 77.100526 -351.514795) (xy 77.117246 -351.460417)
			(xy 77.141861 -351.409126) (xy 77.173824 -351.362063) (xy 77.212426 -351.320272) (xy 77.234288 -351.302066)
			(xy 77.242125 -351.295058) (xy 77.251835 -351.276436) (xy 77.253084 -351.265998) (xy 77.258164 -351.191322)
			(xy 77.25835 -351.180796) (xy 77.251264 -351.160992) (xy 77.244448 -351.152968) (xy 77.224988 -351.13162)
			(xy 77.192111 -351.084126) (xy 77.166771 -351.032216) (xy 77.14955 -350.977079) (xy 77.14084 -350.919976)
			(xy 77.140308 -350.891094) (xy 77.140794 -350.863843) (xy 77.14855 -350.809895) (xy 77.163905 -350.7576)
			(xy 77.186547 -350.708023) (xy 77.216013 -350.662173) (xy 77.251704 -350.620982) (xy 77.292895 -350.585291)
			(xy 77.338745 -350.555825) (xy 77.388322 -350.533183) (xy 77.440617 -350.517828) (xy 77.494565 -350.510072)
			(xy 77.549067 -350.510072) (xy 77.603015 -350.517828) (xy 77.65531 -350.533183) (xy 77.704887 -350.555825)
			(xy 77.750737 -350.585291) (xy 77.791928 -350.620982) (xy 77.827619 -350.662173) (xy 77.857085 -350.708023)
			(xy 77.879727 -350.7576) (xy 77.895082 -350.809895) (xy 77.902838 -350.863843) (xy 77.903324 -350.891094)
			(xy 77.902801 -350.91954) (xy 77.894347 -350.9758) (xy 77.877626 -351.03018) (xy 77.85301 -351.08147)
			(xy 77.821044 -351.128533) (xy 77.78244 -351.170323) (xy 77.760576 -351.188528) (xy 77.752752 -351.195549)
			(xy 77.743033 -351.21416) (xy 77.74178 -351.224596) (xy 77.7367 -351.299272) (xy 77.736527 -351.309797)
			(xy 77.743605 -351.3296) (xy 77.750416 -351.337626) (xy 77.769867 -351.358982) (xy 77.802747 -351.406473)
			(xy 77.828089 -351.458381) (xy 77.845312 -351.513516) (xy 77.854023 -351.570619) (xy 77.854556 -351.5995)
			(xy 77.854057 -351.626633) (xy 77.846374 -351.680352) (xy 77.831149 -351.732439) (xy 77.80869 -351.781839)
			(xy 77.779451 -351.827555) (xy 77.7621 -351.84842) (xy 77.761846 -351.848674) (xy 77.755895 -351.856356)
			(xy 77.749752 -351.874772) (xy 77.749908 -351.884488) (xy 77.753718 -351.954846) (xy 77.754795 -351.964643)
			(xy 77.763268 -351.982414) (xy 77.770228 -351.98939) (xy 77.789235 -352.007508) (xy 77.822548 -352.048103)
			(xy 77.849984 -352.092878) (xy 77.871028 -352.14099) (xy 77.88528 -352.191532) (xy 77.892474 -352.24355)
			(xy 77.89291 -352.269806) (xy 77.892464 -352.295981) (xy 77.88529 -352.347837) (xy 77.871091 -352.398225)
			(xy 77.850134 -352.446197) (xy 77.822813 -352.490853) (xy 77.789641 -352.531352) (xy 77.770736 -352.54946)
			(xy 77.763403 -352.55701) (xy 77.755007 -352.576286) (xy 77.75448 -352.586798) (xy 77.75448 -352.66122)
			(xy 77.754974 -352.671742) (xy 77.763364 -352.691035) (xy 77.770736 -352.698558) (xy 77.789627 -352.716683)
			(xy 77.822816 -352.757169) (xy 77.850149 -352.801818) (xy 77.871113 -352.849789) (xy 77.885311 -352.900178)
			(xy 77.892477 -352.952036) (xy 77.89291 -352.978212) (xy 77.892424 -353.005463) (xy 77.884668 -353.059411)
			(xy 77.869313 -353.111706) (xy 77.846671 -353.161283) (xy 77.817205 -353.207133) (xy 77.781514 -353.248324)
			(xy 77.740323 -353.284015) (xy 77.694473 -353.313481) (xy 77.644896 -353.336123) (xy 77.592601 -353.351478)
			(xy 77.538653 -353.359234) (xy 77.484151 -353.359234) (xy 77.430203 -353.351478) (xy 77.377908 -353.336123)
			(xy 77.328331 -353.313481) (xy 77.282481 -353.284015) (xy 77.24129 -353.248324) (xy 77.205599 -353.207133)
			(xy 77.176133 -353.161283) (xy 77.153491 -353.111706) (xy 77.138136 -353.059411) (xy 77.13038 -353.005463)
			(xy 77.129894 -352.978212) (xy 77.130351 -352.952037) (xy 77.137522 -352.900182) (xy 77.151719 -352.849794)
			(xy 77.172674 -352.801822) (xy 77.199993 -352.757166) (xy 77.233163 -352.716666) (xy 77.252068 -352.698558)
			(xy 77.259393 -352.691002) (xy 77.267794 -352.67173) (xy 77.268324 -352.66122) (xy 77.268324 -352.586798)
			(xy 77.267873 -352.576271) (xy 77.259452 -352.556979) (xy 77.252068 -352.54946) (xy 77.233187 -352.531325)
			(xy 77.199997 -352.490841) (xy 77.172662 -352.446194) (xy 77.151697 -352.398226) (xy 77.137497 -352.347838)
			(xy 77.130328 -352.295981) (xy 77.129894 -352.269806) (xy 77.130385 -352.242672) (xy 77.138068 -352.188952)
			(xy 77.153294 -352.136865) (xy 77.175756 -352.087465) (xy 77.204998 -352.041751) (xy 77.22235 -352.020886)
			(xy 77.222604 -352.020632) (xy 77.228547 -352.012944) (xy 77.234697 -351.994533) (xy 77.234542 -351.984818)
			(xy 77.230732 -351.91446) (xy 77.229667 -351.904661) (xy 77.221186 -351.88689) (xy 77.214222 -351.879916)
			(xy 77.195227 -351.861784) (xy 77.161912 -351.821194) (xy 77.134473 -351.776422) (xy 77.113427 -351.728312)
			(xy 77.099172 -351.677772) (xy 77.091977 -351.625756) (xy 77.09154 -351.5995) (xy 75.190908 -351.5995)
			(xy 75.192354 -351.608974) (xy 75.19289 -351.637854) (xy 75.192414 -351.664988) (xy 75.184724 -351.718708)
			(xy 75.169494 -351.770794) (xy 75.14703 -351.820194) (xy 75.117787 -351.865909) (xy 75.100434 -351.886774)
			(xy 75.10018 -351.887028) (xy 75.094208 -351.894696) (xy 75.088076 -351.913123) (xy 75.088242 -351.922842)
			(xy 75.092052 -351.9932) (xy 75.093093 -352.003003) (xy 75.101591 -352.020773) (xy 75.108562 -352.027744)
			(xy 75.127534 -352.045898) (xy 75.160852 -352.086483) (xy 75.188295 -352.131251) (xy 75.209345 -352.179356)
			(xy 75.223604 -352.229892) (xy 75.230805 -352.281905) (xy 75.231244 -352.30816) (xy 75.230756 -352.335972)
			(xy 75.222682 -352.391008) (xy 75.206701 -352.444288) (xy 75.183151 -352.494681) (xy 75.152532 -352.54112)
			(xy 75.115492 -352.582619) (xy 75.072818 -352.618299) (xy 75.04938 -352.63328) (xy 75.03795 -352.640138)
			(xy 75.02525 -352.662998) (xy 75.024996 -352.763074) (xy 75.025309 -352.771752) (xy 75.031054 -352.788127)
			(xy 75.041928 -352.801651) (xy 75.049126 -352.806508) (xy 75.04938 -352.806508) (xy 75.072801 -352.821464)
			(xy 75.115406 -352.857141) (xy 75.152383 -352.898621) (xy 75.182951 -352.945028) (xy 75.206463 -352.995379)
			(xy 75.22242 -353.048608) (xy 75.230486 -353.103589) (xy 75.23099 -353.131374) (xy 75.230504 -353.158625)
			(xy 75.222748 -353.212573) (xy 75.207393 -353.264868) (xy 75.184751 -353.314445) (xy 75.155285 -353.360295)
			(xy 75.119594 -353.401486) (xy 75.078403 -353.437177) (xy 75.032553 -353.466643) (xy 74.982976 -353.489285)
			(xy 74.930681 -353.50464) (xy 74.876733 -353.512396) (xy 74.822231 -353.512396) (xy 74.768283 -353.50464)
			(xy 74.715988 -353.489285) (xy 74.666411 -353.466643) (xy 74.620561 -353.437177) (xy 74.57937 -353.401486)
			(xy 74.543679 -353.360295) (xy 74.514213 -353.314445) (xy 74.491571 -353.264868) (xy 74.476216 -353.212573)
			(xy 74.46846 -353.158625) (xy 74.467974 -353.131374) (xy 74.46848 -353.103562) (xy 74.476549 -353.048527)
			(xy 74.492526 -352.995247) (xy 74.516073 -352.944853) (xy 74.54669 -352.898414) (xy 74.583728 -352.856915)
			(xy 74.6264 -352.821235) (xy 74.649838 -352.806254) (xy 74.661268 -352.799396) (xy 74.673968 -352.776536)
			(xy 74.674222 -352.67646) (xy 74.673877 -352.667785) (xy 74.668146 -352.651412) (xy 74.657284 -352.637886)
			(xy 74.650092 -352.633026) (xy 74.649838 -352.633026) (xy 74.626436 -352.618041) (xy 74.583831 -352.58237)
			(xy 74.546852 -352.540894) (xy 74.516281 -352.494492) (xy 74.492766 -352.444146) (xy 74.476805 -352.390921)
			(xy 74.468734 -352.335943) (xy 74.468228 -352.30816) (xy 74.468708 -352.281026) (xy 74.476396 -352.227306)
			(xy 74.491626 -352.17522) (xy 74.514089 -352.12582) (xy 74.543331 -352.080105) (xy 74.560684 -352.05924)
			(xy 74.560938 -352.058986) (xy 74.566906 -352.051316) (xy 74.57304 -352.03289) (xy 74.572876 -352.023172)
			(xy 74.569066 -351.952814) (xy 74.568013 -351.943013) (xy 74.559523 -351.925243) (xy 74.552556 -351.91827)
			(xy 74.533594 -351.900106) (xy 74.500274 -351.859523) (xy 74.47283 -351.814758) (xy 74.451778 -351.766655)
			(xy 74.437517 -351.71612) (xy 74.430314 -351.664108) (xy 74.429874 -351.637854) (xy 70.78091 -351.637854)
			(xy 68.0466 -354.372164) (xy 86.93785 -354.372164) (xy 86.938309 -354.346244) (xy 86.945343 -354.294883)
			(xy 86.959263 -354.244946) (xy 86.979813 -354.197352) (xy 87.006615 -354.152978) (xy 87.039176 -354.112639)
			(xy 87.057738 -354.094542) (xy 87.064596 -354.087938) (xy 87.072724 -354.07092) (xy 87.079074 -353.98329)
			(xy 87.073486 -353.965256) (xy 87.067644 -353.957636) (xy 87.052104 -353.937355) (xy 87.026046 -353.893404)
			(xy 87.006084 -353.84637) (xy 86.992574 -353.797094) (xy 86.985757 -353.746455) (xy 86.985348 -353.720908)
			(xy 86.985807 -353.693537) (xy 86.993625 -353.639358) (xy 87.009115 -353.586854) (xy 87.031958 -353.537107)
			(xy 87.061685 -353.491141) (xy 87.079328 -353.47021) (xy 87.079582 -353.469956) (xy 87.085149 -353.462856)
			(xy 87.091408 -353.44595) (xy 87.091774 -353.436936) (xy 87.091774 -353.36988) (xy 87.091432 -353.360861)
			(xy 87.085175 -353.343944) (xy 87.079582 -353.33686) (xy 87.079328 -353.33686) (xy 87.079328 -353.336606)
			(xy 87.061695 -353.315667) (xy 87.03197 -353.2697) (xy 87.009124 -353.219955) (xy 86.993627 -353.167454)
			(xy 86.985798 -353.113276) (xy 86.985797 -353.058536) (xy 86.993625 -353.004358) (xy 87.00912 -352.951856)
			(xy 87.031964 -352.90211) (xy 87.061688 -352.856143) (xy 87.079328 -352.83521) (xy 87.079582 -352.834956)
			(xy 87.085149 -352.827856) (xy 87.091408 -352.81095) (xy 87.091774 -352.801936) (xy 87.091774 -352.73488)
			(xy 87.091432 -352.725861) (xy 87.085175 -352.708944) (xy 87.079582 -352.70186) (xy 87.079328 -352.70186)
			(xy 87.079328 -352.701606) (xy 87.061695 -352.680667) (xy 87.03197 -352.6347) (xy 87.009124 -352.584955)
			(xy 86.993627 -352.532454) (xy 86.985798 -352.478276) (xy 86.985797 -352.423536) (xy 86.993625 -352.369358)
			(xy 87.00912 -352.316856) (xy 87.031964 -352.26711) (xy 87.061688 -352.221143) (xy 87.079328 -352.20021)
			(xy 87.079582 -352.199956) (xy 87.085149 -352.192856) (xy 87.091408 -352.17595) (xy 87.091774 -352.166936)
			(xy 87.091774 -352.09988) (xy 87.091432 -352.090861) (xy 87.085175 -352.073944) (xy 87.079582 -352.06686)
			(xy 87.079328 -352.06686) (xy 87.079328 -352.066606) (xy 87.061695 -352.045667) (xy 87.03197 -351.9997)
			(xy 87.009124 -351.949955) (xy 86.993627 -351.897454) (xy 86.985798 -351.843276) (xy 86.985797 -351.788536)
			(xy 86.993625 -351.734358) (xy 87.00912 -351.681856) (xy 87.031964 -351.63211) (xy 87.061688 -351.586143)
			(xy 87.079328 -351.56521) (xy 87.079582 -351.564956) (xy 87.085149 -351.557856) (xy 87.091408 -351.54095)
			(xy 87.091774 -351.531936) (xy 87.091774 -351.46488) (xy 87.091432 -351.455861) (xy 87.085175 -351.438944)
			(xy 87.079582 -351.43186) (xy 87.079328 -351.43186) (xy 87.079328 -351.431606) (xy 87.061695 -351.410667)
			(xy 87.03197 -351.3647) (xy 87.009124 -351.314955) (xy 86.993627 -351.262454) (xy 86.985798 -351.208276)
			(xy 86.985797 -351.153536) (xy 86.993625 -351.099358) (xy 87.00912 -351.046856) (xy 87.031964 -350.99711)
			(xy 87.061688 -350.951143) (xy 87.079328 -350.93021) (xy 87.079582 -350.929956) (xy 87.085149 -350.922856)
			(xy 87.091408 -350.90595) (xy 87.091774 -350.896936) (xy 87.091774 -350.82988) (xy 87.091432 -350.820861)
			(xy 87.085175 -350.803944) (xy 87.079582 -350.79686) (xy 87.079328 -350.79686) (xy 87.079328 -350.796606)
			(xy 87.061683 -350.775679) (xy 87.031971 -350.729705) (xy 87.009136 -350.679956) (xy 86.993646 -350.627455)
			(xy 86.98582 -350.573278) (xy 86.985348 -350.545908) (xy 86.985885 -350.518659) (xy 86.993639 -350.464715)
			(xy 87.008991 -350.412424) (xy 87.031628 -350.36285) (xy 87.06109 -350.317002) (xy 87.096776 -350.275812)
			(xy 87.13796 -350.240121) (xy 87.183804 -350.210653) (xy 87.233375 -350.188009) (xy 87.285664 -350.17265)
			(xy 87.339607 -350.164889) (xy 87.366856 -350.1644) (xy 87.394225 -350.164892) (xy 87.448403 -350.172703)
			(xy 87.500906 -350.188187) (xy 87.550653 -350.211022) (xy 87.596621 -350.240741) (xy 87.617554 -350.25838)
			(xy 87.617808 -350.258634) (xy 87.624885 -350.264234) (xy 87.641809 -350.270471) (xy 87.650828 -350.270826)
			(xy 87.717884 -350.270826) (xy 87.726899 -350.270456) (xy 87.743816 -350.264217) (xy 87.750904 -350.258634)
			(xy 87.750904 -350.25838) (xy 87.751158 -350.25838) (xy 87.772091 -350.240739) (xy 87.818059 -350.211015)
			(xy 87.867805 -350.188169) (xy 87.920307 -350.172673) (xy 87.974485 -350.164844) (xy 88.029227 -350.164844)
			(xy 88.083405 -350.172673) (xy 88.135907 -350.188169) (xy 88.185653 -350.211015) (xy 88.231621 -350.240739)
			(xy 88.252554 -350.25838) (xy 88.252808 -350.258634) (xy 88.259885 -350.264234) (xy 88.276809 -350.270471)
			(xy 88.285828 -350.270826) (xy 88.352884 -350.270826) (xy 88.361899 -350.270456) (xy 88.378816 -350.264217)
			(xy 88.385904 -350.258634) (xy 88.385904 -350.25838) (xy 88.386158 -350.25838) (xy 88.407091 -350.240739)
			(xy 88.453059 -350.211015) (xy 88.502805 -350.188169) (xy 88.555307 -350.172673) (xy 88.609485 -350.164844)
			(xy 88.664227 -350.164844) (xy 88.718405 -350.172673) (xy 88.770907 -350.188169) (xy 88.820653 -350.211015)
			(xy 88.866621 -350.240739) (xy 88.887554 -350.25838) (xy 88.887808 -350.258634) (xy 88.894885 -350.264234)
			(xy 88.911809 -350.270471) (xy 88.920828 -350.270826) (xy 88.987884 -350.270826) (xy 88.996899 -350.270456)
			(xy 89.013816 -350.264217) (xy 89.020904 -350.258634) (xy 89.020904 -350.25838) (xy 89.021158 -350.25838)
			(xy 89.042091 -350.240739) (xy 89.088059 -350.211015) (xy 89.137805 -350.188169) (xy 89.190307 -350.172673)
			(xy 89.244485 -350.164844) (xy 89.299227 -350.164844) (xy 89.353405 -350.172673) (xy 89.405907 -350.188169)
			(xy 89.455653 -350.211015) (xy 89.501621 -350.240739) (xy 89.522554 -350.25838) (xy 89.522808 -350.258634)
			(xy 89.529885 -350.264234) (xy 89.546809 -350.270471) (xy 89.555828 -350.270826) (xy 89.622884 -350.270826)
			(xy 89.631899 -350.270456) (xy 89.648816 -350.264217) (xy 89.655904 -350.258634) (xy 89.655904 -350.25838)
			(xy 89.656158 -350.25838) (xy 89.677091 -350.240739) (xy 89.723059 -350.211015) (xy 89.772805 -350.188169)
			(xy 89.825307 -350.172673) (xy 89.879485 -350.164844) (xy 89.934227 -350.164844) (xy 89.988405 -350.172673)
			(xy 90.040907 -350.188169) (xy 90.090653 -350.211015) (xy 90.136621 -350.240739) (xy 90.157554 -350.25838)
			(xy 90.157808 -350.258634) (xy 90.164885 -350.264234) (xy 90.181809 -350.270471) (xy 90.190828 -350.270826)
			(xy 90.257884 -350.270826) (xy 90.266899 -350.270456) (xy 90.283816 -350.264217) (xy 90.290904 -350.258634)
			(xy 90.290904 -350.25838) (xy 90.291158 -350.25838) (xy 90.312091 -350.240739) (xy 90.358059 -350.211015)
			(xy 90.407805 -350.188169) (xy 90.460307 -350.172673) (xy 90.514485 -350.164844) (xy 90.569227 -350.164844)
			(xy 90.623405 -350.172673) (xy 90.675907 -350.188169) (xy 90.725653 -350.211015) (xy 90.771621 -350.240739)
			(xy 90.792554 -350.25838) (xy 90.792808 -350.258634) (xy 90.799885 -350.264234) (xy 90.816809 -350.270471)
			(xy 90.825828 -350.270826) (xy 90.892884 -350.270826) (xy 90.901899 -350.270456) (xy 90.918816 -350.264217)
			(xy 90.925904 -350.258634) (xy 90.925904 -350.25838) (xy 90.926158 -350.25838) (xy 90.947091 -350.240739)
			(xy 90.993059 -350.211015) (xy 91.042805 -350.188169) (xy 91.095307 -350.172673) (xy 91.149485 -350.164844)
			(xy 91.204227 -350.164844) (xy 91.258405 -350.172673) (xy 91.310907 -350.188169) (xy 91.360653 -350.211015)
			(xy 91.406621 -350.240739) (xy 91.427554 -350.25838) (xy 91.427808 -350.258634) (xy 91.434885 -350.264234)
			(xy 91.451809 -350.270471) (xy 91.460828 -350.270826) (xy 91.527884 -350.270826) (xy 91.536899 -350.270456)
			(xy 91.553816 -350.264217) (xy 91.560904 -350.258634) (xy 91.560904 -350.25838) (xy 91.561158 -350.25838)
			(xy 91.582091 -350.240739) (xy 91.628059 -350.211015) (xy 91.677805 -350.188169) (xy 91.730307 -350.172673)
			(xy 91.784485 -350.164844) (xy 91.839227 -350.164844) (xy 91.893405 -350.172673) (xy 91.945907 -350.188169)
			(xy 91.995653 -350.211015) (xy 92.041621 -350.240739) (xy 92.062554 -350.25838) (xy 92.062808 -350.258634)
			(xy 92.069885 -350.264234) (xy 92.086809 -350.270471) (xy 92.095828 -350.270826) (xy 92.162884 -350.270826)
			(xy 92.171899 -350.270456) (xy 92.188816 -350.264217) (xy 92.195904 -350.258634) (xy 92.195904 -350.25838)
			(xy 92.196158 -350.25838) (xy 92.217091 -350.240739) (xy 92.263059 -350.211015) (xy 92.312805 -350.188169)
			(xy 92.365307 -350.172673) (xy 92.419485 -350.164844) (xy 92.474227 -350.164844) (xy 92.528405 -350.172673)
			(xy 92.580907 -350.188169) (xy 92.630653 -350.211015) (xy 92.676621 -350.240739) (xy 92.697554 -350.25838)
			(xy 92.697808 -350.258634) (xy 92.704885 -350.264234) (xy 92.721809 -350.270471) (xy 92.730828 -350.270826)
			(xy 92.797884 -350.270826) (xy 92.806899 -350.270456) (xy 92.823816 -350.264217) (xy 92.830904 -350.258634)
			(xy 92.830904 -350.25838) (xy 92.831158 -350.25838) (xy 92.852091 -350.240739) (xy 92.898059 -350.211015)
			(xy 92.947805 -350.188169) (xy 93.000307 -350.172673) (xy 93.054485 -350.164844) (xy 93.109227 -350.164844)
			(xy 93.163405 -350.172673) (xy 93.215907 -350.188169) (xy 93.265653 -350.211015) (xy 93.311621 -350.240739)
			(xy 93.332554 -350.25838) (xy 93.332808 -350.258634) (xy 93.339885 -350.264234) (xy 93.356809 -350.270471)
			(xy 93.365828 -350.270826) (xy 93.432884 -350.270826) (xy 93.441899 -350.270456) (xy 93.458816 -350.264217)
			(xy 93.465904 -350.258634) (xy 93.465904 -350.25838) (xy 93.466158 -350.25838) (xy 93.487093 -350.240744)
			(xy 93.533065 -350.211032) (xy 93.582812 -350.188196) (xy 93.635312 -350.172704) (xy 93.689487 -350.164875)
			(xy 93.716856 -350.1644) (xy 93.744108 -350.164896) (xy 93.798058 -350.172647) (xy 93.850356 -350.187998)
			(xy 93.899937 -350.210636) (xy 93.94579 -350.2401) (xy 93.986984 -350.275791) (xy 94.022678 -350.316981)
			(xy 94.052146 -350.362832) (xy 94.074789 -350.41241) (xy 94.090145 -350.464706) (xy 94.097901 -350.518656)
			(xy 94.098364 -350.545908) (xy 94.097911 -350.573279) (xy 94.090092 -350.627459) (xy 94.0746 -350.679962)
			(xy 94.051755 -350.729709) (xy 94.022027 -350.775675) (xy 94.004384 -350.796606) (xy 94.00413 -350.79686)
			(xy 93.998546 -350.803948) (xy 93.9923 -350.820864) (xy 93.991938 -350.82988) (xy 93.991938 -350.896936)
			(xy 93.99227 -350.905956) (xy 93.998534 -350.922873) (xy 94.00413 -350.929956) (xy 94.004384 -350.929956)
			(xy 94.004384 -350.93021) (xy 94.022032 -350.951137) (xy 94.051756 -350.997106) (xy 94.0746 -351.046853)
			(xy 94.090095 -351.099356) (xy 94.097923 -351.153535) (xy 94.097922 -351.208277) (xy 94.090093 -351.262456)
			(xy 94.074596 -351.314958) (xy 94.05175 -351.364705) (xy 94.022025 -351.410673) (xy 94.004384 -351.431606)
			(xy 94.00413 -351.43186) (xy 93.998546 -351.438948) (xy 93.9923 -351.455864) (xy 93.991938 -351.46488)
			(xy 93.991938 -351.531936) (xy 93.99227 -351.540956) (xy 93.998534 -351.557873) (xy 94.00413 -351.564956)
			(xy 94.004384 -351.564956) (xy 94.004384 -351.56521) (xy 94.022039 -351.58613) (xy 94.051749 -351.632106)
			(xy 94.074582 -351.681856) (xy 94.090069 -351.73436) (xy 94.097893 -351.788538) (xy 94.098364 -351.815908)
			(xy 94.097824 -351.844763) (xy 94.089138 -351.901815) (xy 94.07195 -351.956905) (xy 94.046654 -352.008775)
			(xy 94.013827 -352.056238) (xy 93.97422 -352.098211) (xy 93.951806 -352.11639) (xy 93.94467 -352.122532)
			(xy 93.935035 -352.138691) (xy 93.93301 -352.147886) (xy 93.92031 -352.22561) (xy 93.92412 -352.244152)
			(xy 93.9292 -352.252026) (xy 93.943856 -352.275367) (xy 93.966997 -352.325387) (xy 93.982711 -352.378213)
			(xy 93.990672 -352.432749) (xy 93.991176 -352.460306) (xy 93.990727 -352.486168) (xy 93.983745 -352.537418)
			(xy 93.969896 -352.587253) (xy 93.949435 -352.634758) (xy 93.922738 -352.679059) (xy 93.890296 -352.719343)
			(xy 93.871796 -352.73742) (xy 93.871542 -352.737674) (xy 93.864419 -352.745175) (xy 93.856286 -352.764172)
			(xy 93.855794 -352.774504) (xy 93.855794 -352.858832) (xy 93.864176 -352.878136) (xy 93.871796 -352.885248)
			(xy 93.890305 -352.903358) (xy 93.922813 -352.943663) (xy 93.949569 -352.987995) (xy 93.970082 -353.03554)
			(xy 93.983975 -353.085422) (xy 93.990991 -353.136726) (xy 93.99143 -353.162616) (xy 93.99099 -353.189987)
			(xy 93.983169 -353.244168) (xy 93.967674 -353.296672) (xy 93.944826 -353.346419) (xy 93.915095 -353.392384)
			(xy 93.89745 -353.413314) (xy 93.897196 -353.413568) (xy 93.891616 -353.420659) (xy 93.885366 -353.437572)
			(xy 93.885004 -353.446588) (xy 93.885004 -353.513644) (xy 93.885387 -353.522658) (xy 93.891617 -353.539575)
			(xy 93.897196 -353.546664) (xy 93.89745 -353.546664) (xy 93.89745 -353.546918) (xy 93.915056 -353.567877)
			(xy 93.944775 -353.613841) (xy 93.967618 -353.663582) (xy 93.983116 -353.716077) (xy 93.990952 -353.770249)
			(xy 93.99143 -353.797616) (xy 93.990974 -353.823944) (xy 93.983748 -353.876102) (xy 93.969409 -353.926768)
			(xy 93.948229 -353.974977) (xy 93.920612 -354.01981) (xy 93.887085 -354.060413) (xy 93.867986 -354.07854)
			(xy 93.861184 -354.085297) (xy 93.852836 -354.102543) (xy 93.85173 -354.112068) (xy 93.846904 -354.181664)
			(xy 93.846559 -354.191229) (xy 93.852162 -354.209511) (xy 93.857826 -354.217224) (xy 93.85808 -354.217478)
			(xy 93.874192 -354.237978) (xy 93.901292 -354.282522) (xy 93.922072 -354.330342) (xy 93.936146 -354.380546)
			(xy 93.943251 -354.4322) (xy 93.943678 -354.45827) (xy 93.943217 -354.485523) (xy 93.935463 -354.539476)
			(xy 93.920109 -354.591776) (xy 93.897468 -354.641358) (xy 93.868 -354.687213) (xy 93.832306 -354.728406)
			(xy 93.791113 -354.7641) (xy 93.745258 -354.793568) (xy 93.695676 -354.816209) (xy 93.643376 -354.831563)
			(xy 93.589423 -354.839317) (xy 93.56217 -354.839778) (xy 93.533989 -354.839267) (xy 93.478242 -354.830966)
			(xy 93.42432 -354.814563) (xy 93.373394 -354.790415) (xy 93.326569 -354.759046) (xy 93.305376 -354.740464)
			(xy 93.298518 -354.734114) (xy 93.280738 -354.727256) (xy 93.193108 -354.727256) (xy 93.175328 -354.734114)
			(xy 93.16847 -354.740464) (xy 93.147286 -354.759166) (xy 93.100394 -354.790697) (xy 93.049364 -354.814968)
			(xy 92.995313 -354.831449) (xy 92.939422 -354.839777) (xy 92.911168 -354.840286) (xy 92.883666 -354.839821)
			(xy 92.829232 -354.831924) (xy 92.776495 -354.816297) (xy 92.726546 -354.793264) (xy 92.68042 -354.763302)
			(xy 92.63907 -354.727031) (xy 92.620846 -354.706428) (xy 92.613662 -354.698707) (xy 92.594769 -354.68939)
			(xy 92.58427 -354.688394) (xy 92.510102 -354.6856) (xy 92.499539 -354.685655) (xy 92.479859 -354.69327)
			(xy 92.472002 -354.700332) (xy 92.450393 -354.720963) (xy 92.401994 -354.755981) (xy 92.348726 -354.783024)
			(xy 92.291893 -354.80143) (xy 92.232886 -354.810748) (xy 92.203016 -354.81133) (xy 92.202762 -354.81133)
			(xy 92.1747 -354.810835) (xy 92.119184 -354.802595) (xy 92.065474 -354.786314) (xy 92.014727 -354.762341)
			(xy 91.968039 -354.731195) (xy 91.926415 -354.693547) (xy 91.890754 -354.650209) (xy 91.875864 -354.626418)
			(xy 91.868918 -354.616097) (xy 91.847599 -354.603323) (xy 91.835224 -354.602034) (xy 91.73845 -354.5967)
			(xy 91.71559 -354.607368) (xy 91.70797 -354.617528) (xy 91.689791 -354.640507) (xy 91.647619 -354.681181)
			(xy 91.599726 -354.71493) (xy 91.547235 -354.740961) (xy 91.491383 -354.758662) (xy 91.433481 -354.767617)
			(xy 91.404186 -354.76815) (xy 91.374745 -354.767578) (xy 91.316562 -354.758542) (xy 91.260458 -354.740672)
			(xy 91.207767 -354.714393) (xy 91.15974 -354.680328) (xy 91.138248 -354.6602) (xy 91.130882 -354.653088)
			(xy 91.113102 -354.645976) (xy 91.021916 -354.645976) (xy 91.004136 -354.653088) (xy 90.99677 -354.6602)
			(xy 90.975265 -354.680314) (xy 90.927241 -354.714383) (xy 90.874554 -354.74067) (xy 90.818454 -354.758551)
			(xy 90.760272 -354.767602) (xy 90.730832 -354.76815) (xy 90.702652 -354.767668) (xy 90.64691 -354.759354)
			(xy 90.592996 -354.742931) (xy 90.542085 -354.718756) (xy 90.495283 -354.687356) (xy 90.453608 -354.649413)
			(xy 90.417969 -354.605753) (xy 90.389138 -354.557326) (xy 90.367745 -354.505184) (xy 90.354253 -354.450464)
			(xy 90.351102 -354.422456) (xy 90.351102 -354.422202) (xy 90.349826 -354.41288) (xy 90.341413 -354.396066)
			(xy 90.327498 -354.383421) (xy 90.309957 -354.376651) (xy 90.300556 -354.376228) (xy 89.917778 -354.376228)
			(xy 89.908391 -354.376727) (xy 89.890879 -354.383496) (xy 89.876981 -354.396119) (xy 89.868562 -354.4129)
			(xy 89.867232 -354.422202) (xy 89.867232 -354.422456) (xy 89.864083 -354.450461) (xy 89.850594 -354.505176)
			(xy 89.829201 -354.557311) (xy 89.800369 -354.605731) (xy 89.764727 -354.649382) (xy 89.72305 -354.687313)
			(xy 89.676246 -354.718699) (xy 89.625333 -354.742856) (xy 89.571419 -354.75926) (xy 89.515679 -354.767551)
			(xy 89.459325 -354.767551) (xy 89.403585 -354.75926) (xy 89.349671 -354.742856) (xy 89.298758 -354.718699)
			(xy 89.251954 -354.687313) (xy 89.210277 -354.649382) (xy 89.174635 -354.605731) (xy 89.145803 -354.557311)
			(xy 89.12441 -354.505176) (xy 89.110921 -354.450461) (xy 89.107772 -354.422456) (xy 89.107772 -354.422202)
			(xy 89.10643 -354.412894) (xy 89.098031 -354.39609) (xy 89.084138 -354.383446) (xy 89.066619 -354.376662)
			(xy 89.057226 -354.376228) (xy 89.03462 -354.376228) (xy 89.024597 -354.376637) (xy 89.006075 -354.384305)
			(xy 88.991901 -354.398482) (xy 88.984235 -354.417005) (xy 88.98382 -354.427028) (xy 88.98382 -354.429568)
			(xy 88.983315 -354.45682) (xy 88.975563 -354.510768) (xy 88.960211 -354.563065) (xy 88.937573 -354.612644)
			(xy 88.90811 -354.658497) (xy 88.87242 -354.699689) (xy 88.831232 -354.735383) (xy 88.785383 -354.764852)
			(xy 88.735806 -354.787496) (xy 88.683511 -354.802853) (xy 88.629563 -354.810612) (xy 88.602312 -354.811076)
			(xy 88.572261 -354.810494) (xy 88.512904 -354.80106) (xy 88.455759 -354.78244) (xy 88.402239 -354.755094)
			(xy 88.353666 -354.719697) (xy 88.332056 -354.698808) (xy 88.325198 -354.692555) (xy 88.30827 -354.684991)
			(xy 88.299036 -354.684076) (xy 88.231472 -354.680012) (xy 88.222307 -354.67998) (xy 88.204866 -354.685568)
			(xy 88.197436 -354.690934) (xy 88.197182 -354.690934) (xy 88.176892 -354.706404) (xy 88.13298 -354.732385)
			(xy 88.086 -354.752287) (xy 88.036787 -354.765755) (xy 87.986219 -354.772551) (xy 87.960708 -354.772976)
			(xy 87.931827 -354.772419) (xy 87.874725 -354.763719) (xy 87.819589 -354.746503) (xy 87.767682 -354.721164)
			(xy 87.720192 -354.688283) (xy 87.698834 -354.668836) (xy 87.691976 -354.662486) (xy 87.674958 -354.655374)
			(xy 87.597742 -354.653088) (xy 87.588657 -354.653208) (xy 87.57147 -354.659051) (xy 87.564214 -354.664518)
			(xy 87.563706 -354.665026) (xy 87.543037 -354.68167) (xy 87.497971 -354.709691) (xy 87.449461 -354.731205)
			(xy 87.39844 -354.745799) (xy 87.345891 -354.753192) (xy 87.319358 -354.753672) (xy 87.292104 -354.753261)
			(xy 87.238152 -354.745498) (xy 87.185853 -354.730136) (xy 87.136274 -354.707487) (xy 87.090422 -354.678013)
			(xy 87.049231 -354.642314) (xy 87.01354 -354.601116) (xy 86.984076 -354.555258) (xy 86.961437 -354.505673)
			(xy 86.946085 -354.453372) (xy 86.938333 -354.399418) (xy 86.93785 -354.372164) (xy 68.0466 -354.372164)
			(xy 67.180968 -355.237796) (xy 67.162879 -355.25506) (xy 67.121332 -355.282868) (xy 67.075159 -355.30204)
			(xy 67.026133 -355.311837) (xy 67.001136 -355.312472) (xy 35.396678 -355.312472) (xy 35.386722 -355.312987)
			(xy 35.36834 -355.320653) (xy 35.354236 -355.334716) (xy 35.349942 -355.343714) (xy 35.31362 -355.430074)
			(xy 35.310233 -355.439435) (xy 35.310186 -355.459325) (xy 35.317671 -355.477753) (xy 35.324288 -355.485192)
			(xy 35.344625 -355.506735) (xy 35.379089 -355.554916) (xy 35.405691 -355.607847) (xy 35.423788 -355.664254)
			(xy 35.432947 -355.72278) (xy 35.433508 -355.7524) (xy 35.433022 -355.779651) (xy 35.425266 -355.833599)
			(xy 35.409911 -355.885894) (xy 35.387269 -355.935471) (xy 35.357803 -355.981321) (xy 35.322112 -356.022512)
			(xy 35.280921 -356.058203) (xy 35.235071 -356.087669) (xy 35.185494 -356.110311) (xy 35.133199 -356.125666)
			(xy 35.079251 -356.133422) (xy 35.024749 -356.133422) (xy 34.970801 -356.125666) (xy 34.918506 -356.110311)
			(xy 34.868929 -356.087669) (xy 34.823079 -356.058203) (xy 34.781888 -356.022512) (xy 34.746197 -355.981321)
			(xy 34.716731 -355.935471) (xy 34.694089 -355.885894) (xy 34.678734 -355.833599) (xy 34.670978 -355.779651)
			(xy 34.670492 -355.7524) (xy 34.67109 -355.722782) (xy 34.680244 -355.664257) (xy 34.698333 -355.60785)
			(xy 34.724921 -355.554916) (xy 34.75937 -355.506727) (xy 34.779712 -355.485192) (xy 34.786345 -355.477761)
			(xy 34.793854 -355.459336) (xy 34.793769 -355.439439) (xy 34.79038 -355.430074) (xy 34.754058 -355.343714)
			(xy 34.749851 -355.334651) (xy 34.735751 -355.320517) (xy 34.717305 -355.31288) (xy 34.707322 -355.312472)
			(xy 31.777178 -355.312472) (xy 31.767132 -355.312837) (xy 31.748535 -355.320427) (xy 31.74111 -355.327204)
			(xy 31.680658 -355.38791) (xy 31.673993 -355.395385) (xy 31.666353 -355.413866) (xy 31.666339 -355.433865)
			(xy 31.673954 -355.452357) (xy 31.680658 -355.459792) (xy 31.687008 -355.466142) (xy 31.702502 -355.473508)
			(xy 31.711392 -355.47427) (xy 31.7393 -355.477546) (xy 31.793796 -355.491246) (xy 31.845693 -355.512788)
			(xy 31.893872 -355.541706) (xy 31.937291 -355.577375) (xy 31.975011 -355.619024) (xy 32.006218 -355.665752)
			(xy 32.030237 -355.716551) (xy 32.046549 -355.770323) (xy 32.054802 -355.825905) (xy 32.055308 -355.854)
			(xy 32.434782 -355.854) (xy 32.438853 -355.798378) (xy 32.450979 -355.743941) (xy 32.470902 -355.69185)
			(xy 32.498198 -355.643215) (xy 32.532284 -355.599072) (xy 32.572433 -355.560363) (xy 32.617791 -355.527912)
			(xy 32.667391 -355.502411) (xy 32.720175 -355.484404) (xy 32.775018 -355.474274) (xy 32.830752 -355.472237)
			(xy 32.886189 -355.478337) (xy 32.940146 -355.492443) (xy 32.991475 -355.514255) (xy 33.039081 -355.543309)
			(xy 33.081949 -355.578984) (xy 33.119166 -355.620521) (xy 33.149939 -355.667034) (xy 33.173611 -355.717531)
			(xy 33.189679 -355.770938) (xy 33.197799 -355.826114) (xy 33.198308 -355.854) (xy 33.197799 -355.881886)
			(xy 33.189679 -355.937062) (xy 33.173611 -355.990469) (xy 33.149939 -356.040966) (xy 33.119166 -356.087479)
			(xy 33.081949 -356.129016) (xy 33.039081 -356.164691) (xy 32.991475 -356.193745) (xy 32.940146 -356.215557)
			(xy 32.886189 -356.229663) (xy 32.830752 -356.235763) (xy 32.775018 -356.233726) (xy 32.720175 -356.223596)
			(xy 32.667391 -356.205589) (xy 32.617791 -356.180088) (xy 32.572433 -356.147637) (xy 32.532284 -356.108928)
			(xy 32.498198 -356.064785) (xy 32.470902 -356.01615) (xy 32.450979 -355.964059) (xy 32.438853 -355.909622)
			(xy 32.434782 -355.854) (xy 32.055308 -355.854) (xy 32.054822 -355.881251) (xy 32.047066 -355.935199)
			(xy 32.031711 -355.987494) (xy 32.009069 -356.037071) (xy 31.979603 -356.082921) (xy 31.943912 -356.124112)
			(xy 31.902721 -356.159803) (xy 31.856871 -356.189269) (xy 31.807294 -356.211911) (xy 31.754999 -356.227266)
			(xy 31.701051 -356.235022) (xy 31.6738 -356.235508) (xy 31.646955 -356.235018) (xy 31.593791 -356.227516)
			(xy 31.542205 -356.21263) (xy 31.493217 -356.190657) (xy 31.447795 -356.16203) (xy 31.406837 -356.127315)
			(xy 31.371153 -356.087198) (xy 31.341449 -356.042473) (xy 31.318311 -355.994024) (xy 31.309818 -355.968554)
			(xy 31.306008 -355.955854) (xy 31.286704 -355.93782) (xy 31.189168 -355.913944) (xy 31.180637 -355.912206)
			(xy 31.163324 -355.913876) (xy 31.147582 -355.921274) (xy 31.141162 -355.927152) (xy 31.054294 -356.01402)
			(xy 31.048225 -356.020587) (xy 31.040663 -356.036777) (xy 31.039102 -356.054578) (xy 31.041086 -356.063296)
			(xy 31.067248 -356.16134) (xy 31.086552 -356.180644) (xy 31.09976 -356.183946) (xy 31.126435 -356.191595)
			(xy 31.177367 -356.213626) (xy 31.224571 -356.242801) (xy 31.267052 -356.278506) (xy 31.303913 -356.319987)
			(xy 31.334377 -356.36637) (xy 31.357802 -356.416676) (xy 31.373694 -356.469844) (xy 31.381717 -356.524754)
			(xy 31.382208 -356.5525) (xy 31.381722 -356.579751) (xy 31.373966 -356.633699) (xy 31.358611 -356.685994)
			(xy 31.335969 -356.735571) (xy 31.306503 -356.781421) (xy 31.270812 -356.822612) (xy 31.229621 -356.858303)
			(xy 31.183771 -356.887769) (xy 31.134194 -356.910411) (xy 31.081899 -356.925766) (xy 31.027951 -356.933522)
			(xy 31.0007 -356.934008) (xy 30.972958 -356.933504) (xy 30.918061 -356.925459) (xy 30.864906 -356.909553)
			(xy 30.814613 -356.88612) (xy 30.768241 -356.855655) (xy 30.726768 -356.818798) (xy 30.691065 -356.776327)
			(xy 30.661887 -356.729135) (xy 30.639846 -356.678217) (xy 30.632146 -356.65156) (xy 30.628844 -356.638352)
			(xy 30.60954 -356.619048) (xy 30.511242 -356.592886) (xy 30.502555 -356.590932) (xy 30.484832 -356.592465)
			(xy 30.468725 -356.600017) (xy 30.46222 -356.606094) (xy 29.410914 -357.6574) (xy 30.275782 -357.6574)
			(xy 30.279853 -357.601778) (xy 30.291979 -357.547341) (xy 30.311902 -357.49525) (xy 30.339198 -357.446615)
			(xy 30.373284 -357.402472) (xy 30.413433 -357.363763) (xy 30.458791 -357.331312) (xy 30.508391 -357.305811)
			(xy 30.561175 -357.287804) (xy 30.616018 -357.277674) (xy 30.671752 -357.275637) (xy 30.727189 -357.281737)
			(xy 30.781146 -357.295843) (xy 30.832475 -357.317655) (xy 30.880081 -357.346709) (xy 30.922949 -357.382384)
			(xy 30.960166 -357.423921) (xy 30.990939 -357.470434) (xy 31.014611 -357.520931) (xy 31.030679 -357.574338)
			(xy 31.038799 -357.629514) (xy 31.039308 -357.6574) (xy 33.857182 -357.6574) (xy 33.861253 -357.601778)
			(xy 33.873379 -357.547341) (xy 33.893302 -357.49525) (xy 33.920598 -357.446615) (xy 33.954684 -357.402472)
			(xy 33.994833 -357.363763) (xy 34.040191 -357.331312) (xy 34.089791 -357.305811) (xy 34.142575 -357.287804)
			(xy 34.197418 -357.277674) (xy 34.253152 -357.275637) (xy 34.308589 -357.281737) (xy 34.362546 -357.295843)
			(xy 34.413875 -357.317655) (xy 34.461481 -357.346709) (xy 34.504349 -357.382384) (xy 34.541566 -357.423921)
			(xy 34.572339 -357.470434) (xy 34.596011 -357.520931) (xy 34.612079 -357.574338) (xy 34.620199 -357.629514)
			(xy 34.620708 -357.6574) (xy 34.620199 -357.685286) (xy 34.612079 -357.740462) (xy 34.596011 -357.793869)
			(xy 34.572339 -357.844366) (xy 34.541566 -357.890879) (xy 34.504349 -357.932416) (xy 34.461481 -357.968091)
			(xy 34.413875 -357.997145) (xy 34.362546 -358.018957) (xy 34.308589 -358.033063) (xy 34.253152 -358.039163)
			(xy 34.197418 -358.037126) (xy 34.142575 -358.026996) (xy 34.089791 -358.008989) (xy 34.040191 -357.983488)
			(xy 33.994833 -357.951037) (xy 33.954684 -357.912328) (xy 33.920598 -357.868185) (xy 33.893302 -357.81955)
			(xy 33.873379 -357.767459) (xy 33.861253 -357.713022) (xy 33.857182 -357.6574) (xy 31.039308 -357.6574)
			(xy 31.038799 -357.685286) (xy 31.030679 -357.740462) (xy 31.014611 -357.793869) (xy 30.990939 -357.844366)
			(xy 30.960166 -357.890879) (xy 30.922949 -357.932416) (xy 30.880081 -357.968091) (xy 30.832475 -357.997145)
			(xy 30.781146 -358.018957) (xy 30.727189 -358.033063) (xy 30.671752 -358.039163) (xy 30.616018 -358.037126)
			(xy 30.561175 -358.026996) (xy 30.508391 -358.008989) (xy 30.458791 -357.983488) (xy 30.413433 -357.951037)
			(xy 30.373284 -357.912328) (xy 30.339198 -357.868185) (xy 30.311902 -357.81955) (xy 30.291979 -357.767459)
			(xy 30.279853 -357.713022) (xy 30.275782 -357.6574) (xy 29.410914 -357.6574) (xy 28.801314 -358.267)
			(xy 29.259782 -358.267) (xy 29.263853 -358.211378) (xy 29.275979 -358.156941) (xy 29.295902 -358.10485)
			(xy 29.323198 -358.056215) (xy 29.357284 -358.012072) (xy 29.397433 -357.973363) (xy 29.442791 -357.940912)
			(xy 29.492391 -357.915411) (xy 29.545175 -357.897404) (xy 29.600018 -357.887274) (xy 29.655752 -357.885237)
			(xy 29.711189 -357.891337) (xy 29.765146 -357.905443) (xy 29.816475 -357.927255) (xy 29.864081 -357.956309)
			(xy 29.906949 -357.991984) (xy 29.944166 -358.033521) (xy 29.974939 -358.080034) (xy 29.998611 -358.130531)
			(xy 30.014679 -358.183938) (xy 30.022799 -358.239114) (xy 30.023308 -358.267) (xy 30.022799 -358.294886)
			(xy 30.014679 -358.350062) (xy 29.998611 -358.403469) (xy 29.974939 -358.453966) (xy 29.944166 -358.500479)
			(xy 29.906949 -358.542016) (xy 29.898324 -358.549194) (xy 40.988234 -358.549194) (xy 40.988686 -358.523273)
			(xy 40.995718 -358.471911) (xy 41.009638 -358.421973) (xy 41.030189 -358.374379) (xy 41.056993 -358.330005)
			(xy 41.089557 -358.289667) (xy 41.108122 -358.271572) (xy 41.11498 -358.264968) (xy 41.123108 -358.24795)
			(xy 41.129712 -358.16032) (xy 41.124124 -358.142286) (xy 41.118028 -358.134666) (xy 41.102545 -358.114386)
			(xy 41.076567 -358.070471) (xy 41.056669 -358.023487) (xy 41.043203 -357.974273) (xy 41.03641 -357.923704)
			(xy 41.035986 -357.898192) (xy 41.036451 -357.870822) (xy 41.044269 -357.816643) (xy 41.059759 -357.76414)
			(xy 41.082601 -357.714393) (xy 41.112325 -357.668426) (xy 41.129966 -357.647494) (xy 41.13022 -357.64724)
			(xy 41.135798 -357.640148) (xy 41.142049 -357.623235) (xy 41.142412 -357.61422) (xy 41.142412 -357.547164)
			(xy 41.14207 -357.538146) (xy 41.135812 -357.521229) (xy 41.13022 -357.514144) (xy 41.129966 -357.514144)
			(xy 41.129966 -357.51389) (xy 41.112303 -357.492977) (xy 41.082596 -357.446998) (xy 41.059765 -357.397246)
			(xy 41.04428 -357.344741) (xy 41.036457 -357.290562) (xy 41.035986 -357.263192) (xy 41.036472 -357.235941)
			(xy 41.044228 -357.181993) (xy 41.059583 -357.129698) (xy 41.082225 -357.080121) (xy 41.111691 -357.034271)
			(xy 41.147382 -356.99308) (xy 41.188573 -356.957389) (xy 41.234423 -356.927923) (xy 41.284 -356.905281)
			(xy 41.336295 -356.889926) (xy 41.390243 -356.88217) (xy 41.444745 -356.88217) (xy 41.498693 -356.889926)
			(xy 41.550988 -356.905281) (xy 41.600565 -356.927923) (xy 41.646415 -356.957389) (xy 41.687606 -356.99308)
			(xy 41.723297 -357.034271) (xy 41.752763 -357.080121) (xy 41.775405 -357.129698) (xy 41.79076 -357.181993)
			(xy 41.798516 -357.235941) (xy 41.799002 -357.263192) (xy 41.798531 -357.290562) (xy 41.790714 -357.344741)
			(xy 41.775226 -357.397244) (xy 41.752386 -357.446991) (xy 41.722663 -357.492958) (xy 41.705022 -357.51389)
			(xy 41.704768 -357.514144) (xy 41.699195 -357.52124) (xy 41.692941 -357.53815) (xy 41.692576 -357.547164)
			(xy 41.692576 -357.61422) (xy 41.692928 -357.623237) (xy 41.69918 -357.640154) (xy 41.704768 -357.64724)
			(xy 41.705022 -357.64724) (xy 41.705022 -357.647494) (xy 41.722675 -357.668415) (xy 41.752384 -357.714391)
			(xy 41.775217 -357.764141) (xy 41.790705 -357.816644) (xy 41.79853 -357.870822) (xy 41.799002 -357.898192)
			(xy 41.798529 -357.924112) (xy 41.7915 -357.975473) (xy 41.777584 -358.02541) (xy 41.757036 -358.073004)
			(xy 41.730236 -358.117379) (xy 41.697676 -358.157718) (xy 41.679114 -358.175814) (xy 41.672256 -358.182418)
			(xy 41.664128 -358.199436) (xy 41.657524 -358.287066) (xy 41.663112 -358.3051) (xy 41.669208 -358.31272)
			(xy 41.684676 -358.333012) (xy 41.710657 -358.376923) (xy 41.73056 -358.423903) (xy 41.744029 -358.473115)
			(xy 41.749099 -358.51084) (xy 43.554396 -358.51084) (xy 43.554825 -358.484919) (xy 43.561863 -358.433556)
			(xy 43.575788 -358.383618) (xy 43.596343 -358.336024) (xy 43.623151 -358.29165) (xy 43.655718 -358.251313)
			(xy 43.674284 -358.233218) (xy 43.681142 -358.226614) (xy 43.68927 -358.209596) (xy 43.695874 -358.121966)
			(xy 43.690286 -358.103932) (xy 43.68419 -358.096312) (xy 43.668737 -358.07601) (xy 43.642753 -358.032102)
			(xy 43.622847 -357.985124) (xy 43.609375 -357.935914) (xy 43.602575 -357.885348) (xy 43.602148 -357.859838)
			(xy 43.602625 -357.832468) (xy 43.610438 -357.778289) (xy 43.625924 -357.725785) (xy 43.648764 -357.676038)
			(xy 43.678487 -357.630072) (xy 43.696128 -357.60914) (xy 43.696382 -357.608886) (xy 43.701978 -357.601806)
			(xy 43.708219 -357.584884) (xy 43.708574 -357.575866) (xy 43.708574 -357.50881) (xy 43.708218 -357.499793)
			(xy 43.70197 -357.482876) (xy 43.696382 -357.47579) (xy 43.696128 -357.47579) (xy 43.696128 -357.475536)
			(xy 43.678497 -357.454598) (xy 43.648783 -357.408627) (xy 43.625945 -357.358881) (xy 43.610452 -357.306382)
			(xy 43.602623 -357.252207) (xy 43.602148 -357.224838) (xy 43.602634 -357.197587) (xy 43.61039 -357.143639)
			(xy 43.625745 -357.091344) (xy 43.648387 -357.041767) (xy 43.677853 -356.995917) (xy 43.713544 -356.954726)
			(xy 43.754735 -356.919035) (xy 43.800585 -356.889569) (xy 43.850162 -356.866927) (xy 43.902457 -356.851572)
			(xy 43.956405 -356.843816) (xy 44.010907 -356.843816) (xy 44.064855 -356.851572) (xy 44.11715 -356.866927)
			(xy 44.166727 -356.889569) (xy 44.212577 -356.919035) (xy 44.253768 -356.954726) (xy 44.289459 -356.995917)
			(xy 44.318925 -357.041767) (xy 44.341567 -357.091344) (xy 44.356922 -357.143639) (xy 44.364678 -357.197587)
			(xy 44.365164 -357.224838) (xy 44.36467 -357.252207) (xy 44.356861 -357.306386) (xy 44.341378 -357.358889)
			(xy 44.318543 -357.408636) (xy 44.288823 -357.454604) (xy 44.271184 -357.475536) (xy 44.27093 -357.47579)
			(xy 44.265333 -357.482869) (xy 44.259095 -357.499792) (xy 44.258738 -357.50881) (xy 44.258738 -357.575866)
			(xy 44.259103 -357.584882) (xy 44.265344 -357.6018) (xy 44.27093 -357.608886) (xy 44.271184 -357.608886)
			(xy 44.271184 -357.60914) (xy 44.288806 -357.630086) (xy 44.318521 -357.676055) (xy 44.34136 -357.725799)
			(xy 44.356855 -357.778296) (xy 44.364688 -357.83247) (xy 44.365164 -357.859838) (xy 44.364733 -357.885759)
			(xy 44.357697 -357.937123) (xy 44.343774 -357.987061) (xy 44.323218 -358.034655) (xy 44.29641 -358.079029)
			(xy 44.272612 -358.108504) (xy 47.49927 -358.108504) (xy 47.499749 -358.082584) (xy 47.506778 -358.031224)
			(xy 47.520694 -357.981287) (xy 47.54124 -357.933694) (xy 47.568039 -357.889318) (xy 47.600597 -357.848979)
			(xy 47.619158 -357.830882) (xy 47.626016 -357.824278) (xy 47.634144 -357.80726) (xy 47.640748 -357.71963)
			(xy 47.63516 -357.701596) (xy 47.629064 -357.693976) (xy 47.613591 -357.673689) (xy 47.587611 -357.629776)
			(xy 47.567709 -357.582795) (xy 47.554241 -357.533581) (xy 47.547447 -357.483013) (xy 47.547022 -357.457502)
			(xy 47.547484 -357.430132) (xy 47.555302 -357.375952) (xy 47.570792 -357.323449) (xy 47.593634 -357.273702)
			(xy 47.62336 -357.227735) (xy 47.641002 -357.206804) (xy 47.641256 -357.20655) (xy 47.646834 -357.199458)
			(xy 47.653085 -357.182545) (xy 47.653448 -357.17353) (xy 47.653448 -357.106474) (xy 47.653115 -357.097454)
			(xy 47.646852 -357.080537) (xy 47.641256 -357.073454) (xy 47.641002 -357.073454) (xy 47.641002 -357.0732)
			(xy 47.62335 -357.052279) (xy 47.59364 -357.006303) (xy 47.570806 -356.956553) (xy 47.555318 -356.90405)
			(xy 47.547494 -356.849872) (xy 47.547022 -356.822502) (xy 47.547457 -356.795248) (xy 47.555215 -356.741294)
			(xy 47.570572 -356.688994) (xy 47.593217 -356.639412) (xy 47.622687 -356.593557) (xy 47.658384 -356.552364)
			(xy 47.69958 -356.51667) (xy 47.745437 -356.487203) (xy 47.79502 -356.464562) (xy 47.847322 -356.449209)
			(xy 47.901276 -356.441455) (xy 47.92853 -356.440994) (xy 47.957165 -356.441498) (xy 48.01379 -356.450062)
			(xy 48.0685 -356.466994) (xy 48.120064 -356.491913) (xy 48.167324 -356.52426) (xy 48.209219 -356.563306)
			(xy 48.244806 -356.608177) (xy 48.259492 -356.632764) (xy 48.264243 -356.640338) (xy 48.277941 -356.651811)
			(xy 48.294752 -356.657867) (xy 48.303688 -356.658164) (xy 48.391572 -356.658164) (xy 48.4005 -356.657828)
			(xy 48.417292 -356.651761) (xy 48.430994 -356.640315) (xy 48.435768 -356.632764) (xy 48.450459 -356.608179)
			(xy 48.486042 -356.563306) (xy 48.527934 -356.524256) (xy 48.575194 -356.491909) (xy 48.626758 -356.466992)
			(xy 48.681469 -356.450064) (xy 48.738095 -356.441506) (xy 48.76673 -356.440994) (xy 48.794101 -356.441444)
			(xy 48.848281 -356.449266) (xy 48.900784 -356.464759) (xy 48.95053 -356.487604) (xy 48.996497 -356.517332)
			(xy 49.017428 -356.534974) (xy 49.017682 -356.535228) (xy 49.024767 -356.540816) (xy 49.041685 -356.547061)
			(xy 49.050702 -356.54742) (xy 49.117758 -356.54742) (xy 49.126772 -356.547039) (xy 49.143689 -356.540808)
			(xy 49.150778 -356.535228) (xy 49.150778 -356.534974) (xy 49.151032 -356.534974) (xy 49.171965 -356.517333)
			(xy 49.217933 -356.487609) (xy 49.267679 -356.464763) (xy 49.320181 -356.449267) (xy 49.374359 -356.441438)
			(xy 49.429101 -356.441438) (xy 49.483279 -356.449267) (xy 49.535781 -356.464763) (xy 49.585527 -356.487609)
			(xy 49.631495 -356.517333) (xy 49.652428 -356.534974) (xy 49.652682 -356.535228) (xy 49.659767 -356.540816)
			(xy 49.676685 -356.547061) (xy 49.685702 -356.54742) (xy 49.752758 -356.54742) (xy 49.761772 -356.547039)
			(xy 49.778689 -356.540808) (xy 49.785778 -356.535228) (xy 49.785778 -356.534974) (xy 49.786032 -356.534974)
			(xy 49.806965 -356.517333) (xy 49.852933 -356.487609) (xy 49.902679 -356.464763) (xy 49.955181 -356.449267)
			(xy 50.009359 -356.441438) (xy 50.064101 -356.441438) (xy 50.118279 -356.449267) (xy 50.170781 -356.464763)
			(xy 50.220527 -356.487609) (xy 50.266495 -356.517333) (xy 50.287428 -356.534974) (xy 50.287682 -356.535228)
			(xy 50.294767 -356.540816) (xy 50.311685 -356.547061) (xy 50.320702 -356.54742) (xy 50.387758 -356.54742)
			(xy 50.396772 -356.547039) (xy 50.413689 -356.540808) (xy 50.420778 -356.535228) (xy 50.420778 -356.534974)
			(xy 50.421032 -356.534974) (xy 50.441976 -356.517349) (xy 50.487946 -356.487636) (xy 50.53769 -356.464798)
			(xy 50.590188 -356.449303) (xy 50.644362 -356.441471) (xy 50.67173 -356.440994) (xy 50.698982 -356.44145)
			(xy 50.752931 -356.449211) (xy 50.805226 -356.46457) (xy 50.854804 -356.487214) (xy 50.900654 -356.516684)
			(xy 50.941844 -356.552379) (xy 50.977535 -356.593571) (xy 51.007001 -356.639424) (xy 51.029642 -356.689004)
			(xy 51.044996 -356.7413) (xy 51.052752 -356.79525) (xy 51.053238 -356.822502) (xy 51.052788 -356.849873)
			(xy 51.044969 -356.904053) (xy 51.029477 -356.956557) (xy 51.006631 -357.006304) (xy 50.976902 -357.052269)
			(xy 50.959258 -357.0732) (xy 50.959004 -357.073454) (xy 50.953431 -357.08055) (xy 50.947176 -357.097459)
			(xy 50.946812 -357.106474) (xy 50.946812 -357.17353) (xy 50.947152 -357.182549) (xy 50.953411 -357.199466)
			(xy 50.959004 -357.20655) (xy 50.959258 -357.20655) (xy 50.959258 -357.206804) (xy 50.976906 -357.227729)
			(xy 51.006618 -357.273703) (xy 51.029453 -357.323452) (xy 51.044942 -357.375955) (xy 51.052766 -357.430132)
			(xy 51.053238 -357.457502) (xy 51.052761 -357.483422) (xy 51.045731 -357.534782) (xy 51.031815 -357.584719)
			(xy 51.011268 -357.632312) (xy 50.984469 -357.676687) (xy 50.951911 -357.717027) (xy 50.93335 -357.735124)
			(xy 50.926492 -357.741728) (xy 50.918364 -357.758746) (xy 50.91176 -357.846376) (xy 50.917348 -357.86441)
			(xy 50.923444 -357.87203) (xy 50.938921 -357.892314) (xy 50.964901 -357.936228) (xy 50.984801 -357.98321)
			(xy 50.998268 -358.032424) (xy 51.005062 -358.082993) (xy 51.005486 -358.108504) (xy 51.005048 -358.135758)
			(xy 50.99729 -358.189711) (xy 50.981933 -358.242011) (xy 50.959288 -358.291592) (xy 50.929818 -358.337446)
			(xy 50.894121 -358.37864) (xy 50.852926 -358.414333) (xy 50.807069 -358.4438) (xy 50.757486 -358.466442)
			(xy 50.705185 -358.481796) (xy 50.651232 -358.48955) (xy 50.623978 -358.490012) (xy 50.596607 -358.489556)
			(xy 50.542428 -358.481735) (xy 50.489925 -358.466244) (xy 50.440178 -358.4434) (xy 50.394212 -358.413674)
			(xy 50.37328 -358.396032) (xy 50.373026 -358.395778) (xy 50.365938 -358.390194) (xy 50.349022 -358.383946)
			(xy 50.340006 -358.383586) (xy 50.27295 -358.383586) (xy 50.263936 -358.38397) (xy 50.247019 -358.390199)
			(xy 50.23993 -358.395778) (xy 50.23993 -358.396032) (xy 50.239676 -358.396032) (xy 50.218743 -358.413673)
			(xy 50.172775 -358.443397) (xy 50.123029 -358.466243) (xy 50.070527 -358.481739) (xy 50.016349 -358.489568)
			(xy 49.961607 -358.489568) (xy 49.907429 -358.481739) (xy 49.854927 -358.466243) (xy 49.805181 -358.443397)
			(xy 49.759213 -358.413673) (xy 49.73828 -358.396032) (xy 49.738026 -358.395778) (xy 49.730938 -358.390194)
			(xy 49.714022 -358.383946) (xy 49.705006 -358.383586) (xy 49.63795 -358.383586) (xy 49.628936 -358.38397)
			(xy 49.612019 -358.390199) (xy 49.60493 -358.395778) (xy 49.60493 -358.396032) (xy 49.604676 -358.396032)
			(xy 49.583743 -358.413673) (xy 49.537775 -358.443397) (xy 49.488029 -358.466243) (xy 49.435527 -358.481739)
			(xy 49.381349 -358.489568) (xy 49.326607 -358.489568) (xy 49.272429 -358.481739) (xy 49.219927 -358.466243)
			(xy 49.170181 -358.443397) (xy 49.124213 -358.413673) (xy 49.10328 -358.396032) (xy 49.103026 -358.395778)
			(xy 49.095938 -358.390194) (xy 49.079022 -358.383946) (xy 49.070006 -358.383586) (xy 49.00295 -358.383586)
			(xy 48.993936 -358.38397) (xy 48.977019 -358.390199) (xy 48.96993 -358.395778) (xy 48.96993 -358.396032)
			(xy 48.969676 -358.396032) (xy 48.94873 -358.413654) (xy 48.902761 -358.443367) (xy 48.853017 -358.466206)
			(xy 48.800519 -358.481701) (xy 48.746346 -358.489535) (xy 48.718978 -358.490012) (xy 48.690344 -358.489499)
			(xy 48.633719 -358.480936) (xy 48.57901 -358.464005) (xy 48.527446 -358.439088) (xy 48.480185 -358.406743)
			(xy 48.43829 -358.367697) (xy 48.402702 -358.322829) (xy 48.388016 -358.298242) (xy 48.383258 -358.290673)
			(xy 48.369563 -358.279199) (xy 48.352755 -358.273141) (xy 48.34382 -358.272842) (xy 48.255936 -358.272842)
			(xy 48.247008 -358.273181) (xy 48.230216 -358.279246) (xy 48.216514 -358.290691) (xy 48.21174 -358.298242)
			(xy 48.197046 -358.322824) (xy 48.161463 -358.367698) (xy 48.119571 -358.406747) (xy 48.072312 -358.439094)
			(xy 48.020748 -358.464012) (xy 47.966039 -358.480941) (xy 47.909413 -358.4895) (xy 47.880778 -358.490012)
			(xy 47.853526 -358.489543) (xy 47.799578 -358.481783) (xy 47.747283 -358.466426) (xy 47.697706 -358.443782)
			(xy 47.651856 -358.414314) (xy 47.610666 -358.378621) (xy 47.574975 -358.337429) (xy 47.545509 -358.291578)
			(xy 47.522868 -358.242) (xy 47.507513 -358.189704) (xy 47.499756 -358.135756) (xy 47.49927 -358.108504)
			(xy 44.272612 -358.108504) (xy 44.263842 -358.119366) (xy 44.245276 -358.13746) (xy 44.238418 -358.144064)
			(xy 44.23029 -358.161082) (xy 44.223686 -358.248712) (xy 44.229274 -358.266746) (xy 44.23537 -358.274366)
			(xy 44.250822 -358.294669) (xy 44.276804 -358.338578) (xy 44.296709 -358.385555) (xy 44.310182 -358.434765)
			(xy 44.316984 -358.48533) (xy 44.317412 -358.51084) (xy 44.316847 -358.539303) (xy 44.308379 -358.595597)
			(xy 44.291638 -358.650006) (xy 44.266995 -358.701322) (xy 44.234998 -358.748406) (xy 44.216066 -358.769666)
			(xy 44.208954 -358.77754) (xy 44.202096 -358.797352) (xy 44.209716 -358.893618) (xy 44.219622 -358.91216)
			(xy 44.228258 -358.918764) (xy 44.250665 -358.936951) (xy 44.290263 -358.978928) (xy 44.323086 -359.026392)
			(xy 44.348384 -359.078259) (xy 44.36558 -359.133345) (xy 44.374282 -359.190392) (xy 44.374816 -359.219246)
			(xy 44.37433 -359.246497) (xy 44.366574 -359.300445) (xy 44.351219 -359.35274) (xy 44.328577 -359.402317)
			(xy 44.299111 -359.448167) (xy 44.26342 -359.489358) (xy 44.222229 -359.525049) (xy 44.176379 -359.554515)
			(xy 44.126802 -359.577157) (xy 44.074507 -359.592512) (xy 44.020559 -359.600268) (xy 43.966057 -359.600268)
			(xy 43.912109 -359.592512) (xy 43.859814 -359.577157) (xy 43.810237 -359.554515) (xy 43.764387 -359.525049)
			(xy 43.723196 -359.489358) (xy 43.687505 -359.448167) (xy 43.658039 -359.402317) (xy 43.635397 -359.35274)
			(xy 43.620042 -359.300445) (xy 43.612286 -359.246497) (xy 43.6118 -359.219246) (xy 43.612354 -359.190782)
			(xy 43.620824 -359.134488) (xy 43.637567 -359.080079) (xy 43.662213 -359.028763) (xy 43.694212 -358.98168)
			(xy 43.713146 -358.96042) (xy 43.720258 -358.952546) (xy 43.727116 -358.932734) (xy 43.719496 -358.836468)
			(xy 43.70959 -358.817926) (xy 43.700954 -358.811322) (xy 43.678543 -358.79314) (xy 43.638944 -358.751162)
			(xy 43.606122 -358.703697) (xy 43.580824 -358.65183) (xy 43.563629 -358.596743) (xy 43.554929 -358.539694)
			(xy 43.554396 -358.51084) (xy 41.749099 -358.51084) (xy 41.750825 -358.523683) (xy 41.75125 -358.549194)
			(xy 41.750733 -358.577659) (xy 41.742256 -358.633955) (xy 41.725505 -358.688366) (xy 41.700851 -358.739682)
			(xy 41.668842 -358.786762) (xy 41.649904 -358.80802) (xy 41.642792 -358.815894) (xy 41.635934 -358.835706)
			(xy 41.643554 -358.931972) (xy 41.65346 -358.950514) (xy 41.662096 -358.957118) (xy 41.684516 -358.97529)
			(xy 41.724116 -359.017269) (xy 41.756939 -359.064735) (xy 41.782236 -359.116605) (xy 41.799428 -359.171694)
			(xy 41.808123 -359.228745) (xy 41.808654 -359.2576) (xy 41.808168 -359.284851) (xy 41.800412 -359.338799)
			(xy 41.785057 -359.391094) (xy 41.762415 -359.440671) (xy 41.732949 -359.486521) (xy 41.697258 -359.527712)
			(xy 41.656067 -359.563403) (xy 41.610217 -359.592869) (xy 41.56064 -359.615511) (xy 41.508345 -359.630866)
			(xy 41.454397 -359.638622) (xy 41.399895 -359.638622) (xy 41.345947 -359.630866) (xy 41.293652 -359.615511)
			(xy 41.244075 -359.592869) (xy 41.198225 -359.563403) (xy 41.157034 -359.527712) (xy 41.121343 -359.486521)
			(xy 41.091877 -359.440671) (xy 41.069235 -359.391094) (xy 41.05388 -359.338799) (xy 41.046124 -359.284851)
			(xy 41.045638 -359.2576) (xy 41.046154 -359.229135) (xy 41.054632 -359.172839) (xy 41.071384 -359.118428)
			(xy 41.096038 -359.067113) (xy 41.128046 -359.020032) (xy 41.146984 -358.998774) (xy 41.154096 -358.9909)
			(xy 41.160954 -358.971088) (xy 41.153334 -358.874822) (xy 41.143428 -358.85628) (xy 41.134792 -358.849676)
			(xy 41.112367 -358.831511) (xy 41.072767 -358.78953) (xy 41.039945 -358.742062) (xy 41.01465 -358.690191)
			(xy 40.997459 -358.635101) (xy 40.988764 -358.578049) (xy 40.988234 -358.549194) (xy 29.898324 -358.549194)
			(xy 29.864081 -358.577691) (xy 29.816475 -358.606745) (xy 29.765146 -358.628557) (xy 29.711189 -358.642663)
			(xy 29.655752 -358.648763) (xy 29.600018 -358.646726) (xy 29.545175 -358.636596) (xy 29.492391 -358.618589)
			(xy 29.442791 -358.593088) (xy 29.397433 -358.560637) (xy 29.357284 -358.521928) (xy 29.323198 -358.477785)
			(xy 29.295902 -358.42915) (xy 29.275979 -358.377059) (xy 29.263853 -358.322622) (xy 29.259782 -358.267)
			(xy 28.801314 -358.267) (xy 28.621482 -358.446832) (xy 28.603377 -358.464078) (xy 28.561837 -358.491893)
			(xy 28.515668 -358.51107) (xy 28.466646 -358.520871) (xy 28.44165 -358.521508) (xy 28.26512 -358.521508)
			(xy 28.255052 -358.521942) (xy 28.236454 -358.529656) (xy 28.229052 -358.536494) (xy 28.207457 -358.557351)
			(xy 28.158922 -358.592684) (xy 28.10545 -358.619976) (xy 28.048361 -358.638551) (xy 27.989067 -358.647951)
			(xy 27.95905 -358.648508) (xy 27.931798 -358.647998) (xy 27.877849 -358.640248) (xy 27.825552 -358.624898)
			(xy 27.775972 -358.602262) (xy 27.730119 -358.572799) (xy 27.688926 -358.53711) (xy 27.653231 -358.495921)
			(xy 27.623762 -358.450072) (xy 27.601119 -358.400495) (xy 27.585763 -358.3482) (xy 27.578005 -358.294252)
			(xy 27.577542 -358.267) (xy 27.578092 -358.237813) (xy 27.586992 -358.18012) (xy 27.604568 -358.124454)
			(xy 27.630413 -358.072111) (xy 27.663922 -358.024312) (xy 27.704316 -357.982169) (xy 27.727148 -357.963978)
			(xy 27.736337 -357.956157) (xy 27.746672 -357.934387) (xy 27.74696 -357.922322) (xy 27.745182 -357.840534)
			(xy 27.744211 -357.828481) (xy 27.732667 -357.80727) (xy 27.723084 -357.799894) (xy 27.701646 -357.784578)
			(xy 27.662848 -357.748932) (xy 27.629322 -357.708287) (xy 27.601704 -357.663419) (xy 27.580519 -357.615178)
			(xy 27.566171 -357.564481) (xy 27.558932 -357.512294) (xy 27.558492 -357.48595) (xy 27.330908 -357.48595)
			(xy 27.330908 -358.496108) (xy 27.331327 -358.506178) (xy 27.339052 -358.524776) (xy 27.345894 -358.532176)
			(xy 27.969718 -359.156) (xy 31.621982 -359.156) (xy 31.626053 -359.100378) (xy 31.638179 -359.045941)
			(xy 31.658102 -358.99385) (xy 31.685398 -358.945215) (xy 31.719484 -358.901072) (xy 31.759633 -358.862363)
			(xy 31.804991 -358.829912) (xy 31.854591 -358.804411) (xy 31.907375 -358.786404) (xy 31.962218 -358.776274)
			(xy 32.017952 -358.774237) (xy 32.073389 -358.780337) (xy 32.127346 -358.794443) (xy 32.178675 -358.816255)
			(xy 32.226281 -358.845309) (xy 32.269149 -358.880984) (xy 32.306366 -358.922521) (xy 32.337139 -358.969034)
			(xy 32.360811 -359.019531) (xy 32.376879 -359.072938) (xy 32.384999 -359.128114) (xy 32.385508 -359.156)
			(xy 32.384999 -359.183886) (xy 32.376879 -359.239062) (xy 32.360811 -359.292469) (xy 32.352475 -359.310251)
			(xy 35.686978 -359.310251) (xy 35.686978 -359.255749) (xy 35.694734 -359.201801) (xy 35.710089 -359.149506)
			(xy 35.732731 -359.099929) (xy 35.762197 -359.054079) (xy 35.797888 -359.012888) (xy 35.839079 -358.977197)
			(xy 35.884929 -358.947731) (xy 35.934506 -358.925089) (xy 35.986801 -358.909734) (xy 36.040749 -358.901978)
			(xy 36.068 -358.901492) (xy 36.096113 -358.902001) (xy 36.151727 -358.910272) (xy 36.205524 -358.926621)
			(xy 36.256337 -358.950693) (xy 36.303064 -358.981965) (xy 36.344692 -359.019761) (xy 36.362894 -359.041192)
			(xy 36.370771 -359.049649) (xy 36.391733 -359.059293) (xy 36.40328 -359.059734) (xy 36.495482 -359.057194)
			(xy 36.516056 -359.046526) (xy 36.523168 -359.037128) (xy 36.541324 -359.013594) (xy 36.583643 -358.971861)
			(xy 36.631921 -358.937195) (xy 36.68499 -358.910434) (xy 36.741567 -358.892225) (xy 36.800283 -358.883009)
			(xy 36.83 -358.882442) (xy 36.857255 -358.882828) (xy 36.91121 -358.890585) (xy 36.963511 -358.905943)
			(xy 37.013095 -358.928587) (xy 37.058951 -358.958057) (xy 37.100147 -358.993753) (xy 37.135843 -359.034949)
			(xy 37.165313 -359.080805) (xy 37.187957 -359.130389) (xy 37.203315 -359.18269) (xy 37.211072 -359.236645)
			(xy 37.211072 -359.291155) (xy 37.203315 -359.34511) (xy 37.187957 -359.397411) (xy 37.165313 -359.446995)
			(xy 37.135843 -359.492851) (xy 37.100147 -359.534047) (xy 37.058951 -359.569743) (xy 37.013095 -359.599213)
			(xy 36.963511 -359.621857) (xy 36.91121 -359.637215) (xy 36.857255 -359.644972) (xy 36.83 -359.645458)
			(xy 36.801888 -359.644931) (xy 36.746275 -359.636661) (xy 36.692479 -359.620314) (xy 36.641667 -359.596246)
			(xy 36.594939 -359.564978) (xy 36.553309 -359.527187) (xy 36.535106 -359.505758) (xy 36.527237 -359.497293)
			(xy 36.506268 -359.487656) (xy 36.49472 -359.487216) (xy 36.402518 -359.489756) (xy 36.381944 -359.500424)
			(xy 36.374832 -359.509822) (xy 36.35669 -359.533367) (xy 36.314367 -359.575097) (xy 36.266085 -359.60976)
			(xy 36.213014 -359.636519) (xy 36.156435 -359.654726) (xy 36.097718 -359.663941) (xy 36.068 -359.664508)
			(xy 36.040749 -359.664022) (xy 35.986801 -359.656266) (xy 35.934506 -359.640911) (xy 35.884929 -359.618269)
			(xy 35.839079 -359.588803) (xy 35.797888 -359.553112) (xy 35.762197 -359.511921) (xy 35.732731 -359.466071)
			(xy 35.710089 -359.416494) (xy 35.694734 -359.364199) (xy 35.686978 -359.310251) (xy 32.352475 -359.310251)
			(xy 32.337139 -359.342966) (xy 32.306366 -359.389479) (xy 32.269149 -359.431016) (xy 32.226281 -359.466691)
			(xy 32.178675 -359.495745) (xy 32.127346 -359.517557) (xy 32.073389 -359.531663) (xy 32.017952 -359.537763)
			(xy 31.962218 -359.535726) (xy 31.907375 -359.525596) (xy 31.854591 -359.507589) (xy 31.804991 -359.482088)
			(xy 31.759633 -359.449637) (xy 31.719484 -359.410928) (xy 31.685398 -359.366785) (xy 31.658102 -359.31815)
			(xy 31.638179 -359.266059) (xy 31.626053 -359.211622) (xy 31.621982 -359.156) (xy 27.969718 -359.156)
			(xy 28.401518 -359.5878) (xy 29.259782 -359.5878) (xy 29.263853 -359.532178) (xy 29.275979 -359.477741)
			(xy 29.295902 -359.42565) (xy 29.323198 -359.377015) (xy 29.357284 -359.332872) (xy 29.397433 -359.294163)
			(xy 29.442791 -359.261712) (xy 29.492391 -359.236211) (xy 29.545175 -359.218204) (xy 29.600018 -359.208074)
			(xy 29.655752 -359.206037) (xy 29.711189 -359.212137) (xy 29.765146 -359.226243) (xy 29.816475 -359.248055)
			(xy 29.864081 -359.277109) (xy 29.906949 -359.312784) (xy 29.944166 -359.354321) (xy 29.974939 -359.400834)
			(xy 29.998611 -359.451331) (xy 30.014679 -359.504738) (xy 30.022799 -359.559914) (xy 30.023308 -359.5878)
			(xy 30.022799 -359.615686) (xy 30.014679 -359.670862) (xy 29.998611 -359.724269) (xy 29.974939 -359.774766)
			(xy 29.944166 -359.821279) (xy 29.906949 -359.862816) (xy 29.864081 -359.898491) (xy 29.816475 -359.927545)
			(xy 29.765146 -359.949357) (xy 29.711189 -359.963463) (xy 29.655752 -359.969563) (xy 29.600018 -359.967526)
			(xy 29.545175 -359.957396) (xy 29.492391 -359.939389) (xy 29.442791 -359.913888) (xy 29.397433 -359.881437)
			(xy 29.357284 -359.842728) (xy 29.323198 -359.798585) (xy 29.295902 -359.74995) (xy 29.275979 -359.697859)
			(xy 29.263853 -359.643422) (xy 29.259782 -359.5878) (xy 28.401518 -359.5878) (xy 29.300424 -360.486706)
			(xy 29.307821 -360.49355) (xy 29.326423 -360.501267) (xy 29.336492 -360.501692) (xy 31.578296 -360.501692)
			(xy 31.587015 -360.501308) (xy 31.603424 -360.49539) (xy 31.616916 -360.484335) (xy 31.62173 -360.477054)
			(xy 31.673546 -360.390694) (xy 31.674054 -360.36377) (xy 31.667704 -360.35234) (xy 31.653487 -360.324472)
			(xy 31.633331 -360.265251) (xy 31.623119 -360.203533) (xy 31.622492 -360.172254) (xy 31.622492 -360.172)
			(xy 31.622978 -360.144749) (xy 31.630734 -360.090801) (xy 31.646089 -360.038506) (xy 31.668731 -359.988929)
			(xy 31.698197 -359.943079) (xy 31.733888 -359.901888) (xy 31.775079 -359.866197) (xy 31.820929 -359.836731)
			(xy 31.870506 -359.814089) (xy 31.922801 -359.798734) (xy 31.976749 -359.790978) (xy 32.031251 -359.790978)
			(xy 32.085199 -359.798734) (xy 32.137494 -359.814089) (xy 32.187071 -359.836731) (xy 32.232921 -359.866197)
			(xy 32.274112 -359.901888) (xy 32.309803 -359.943079) (xy 32.339269 -359.988929) (xy 32.361911 -360.038506)
			(xy 32.377266 -360.090801) (xy 32.385022 -360.144749) (xy 32.385508 -360.172) (xy 32.385508 -360.172254)
			(xy 32.384865 -360.203531) (xy 32.374646 -360.265246) (xy 32.354505 -360.32447) (xy 32.340296 -360.35234)
			(xy 32.333946 -360.36377) (xy 32.334454 -360.390694) (xy 32.38627 -360.477054) (xy 32.391058 -360.484363)
			(xy 32.404534 -360.495463) (xy 32.420974 -360.501343) (xy 32.429704 -360.501692) (xy 34.7472 -360.501692)
			(xy 34.772197 -360.502308) (xy 34.821222 -360.512115) (xy 34.867393 -360.531295) (xy 34.908938 -360.559109)
			(xy 34.927032 -360.576368) (xy 36.427664 -362.077) (xy 37.946582 -362.077) (xy 37.950653 -362.021378)
			(xy 37.962779 -361.966941) (xy 37.982702 -361.91485) (xy 38.009998 -361.866215) (xy 38.044084 -361.822072)
			(xy 38.084233 -361.783363) (xy 38.129591 -361.750912) (xy 38.179191 -361.725411) (xy 38.231975 -361.707404)
			(xy 38.286818 -361.697274) (xy 38.342552 -361.695237) (xy 38.397989 -361.701337) (xy 38.451946 -361.715443)
			(xy 38.503275 -361.737255) (xy 38.550881 -361.766309) (xy 38.593749 -361.801984) (xy 38.630966 -361.843521)
			(xy 38.661739 -361.890034) (xy 38.685411 -361.940531) (xy 38.701479 -361.993938) (xy 38.709599 -362.049114)
			(xy 38.710108 -362.077) (xy 38.709599 -362.104886) (xy 38.701479 -362.160062) (xy 38.685411 -362.213469)
			(xy 38.661739 -362.263966) (xy 38.630966 -362.310479) (xy 38.593749 -362.352016) (xy 38.550881 -362.387691)
			(xy 38.503275 -362.416745) (xy 38.451946 -362.438557) (xy 38.397989 -362.452663) (xy 38.342552 -362.458763)
			(xy 38.286818 -362.456726) (xy 38.231975 -362.446596) (xy 38.179191 -362.428589) (xy 38.129591 -362.403088)
			(xy 38.084233 -362.370637) (xy 38.044084 -362.331928) (xy 38.009998 -362.287785) (xy 37.982702 -362.23915)
			(xy 37.962779 -362.187059) (xy 37.950653 -362.132622) (xy 37.946582 -362.077) (xy 36.427664 -362.077)
			(xy 36.705032 -362.354368) (xy 36.722333 -362.372426) (xy 36.750148 -362.41398) (xy 36.769321 -362.460163)
			(xy 36.779116 -362.509198) (xy 36.779708 -362.5342) (xy 36.779708 -363.5248) (xy 36.779092 -363.549797)
			(xy 36.769285 -363.598822) (xy 36.750105 -363.644993) (xy 36.722291 -363.686538) (xy 36.705032 -363.704632)
			(xy 36.337494 -364.07217) (xy 36.330674 -364.079586) (xy 36.322943 -364.098173) (xy 36.322508 -364.108238)
			(xy 36.322508 -364.108492) (xy 36.32204 -364.137284) (xy 36.313438 -364.19422) (xy 36.296382 -364.249218)
			(xy 36.271259 -364.301031) (xy 36.238639 -364.348482) (xy 36.199262 -364.390496) (xy 36.176966 -364.40872)
			(xy 36.176712 -364.40872) (xy 36.168019 -364.416374) (xy 36.158097 -364.437277) (xy 36.157662 -364.448852)
			(xy 36.157916 -364.529116) (xy 36.158472 -364.540686) (xy 36.168676 -364.561457) (xy 36.177474 -364.568994)
			(xy 36.177728 -364.568994) (xy 36.2004 -364.587168) (xy 36.240465 -364.629252) (xy 36.273688 -364.676923)
			(xy 36.299301 -364.729078) (xy 36.316712 -364.784513) (xy 36.32552 -364.841947) (xy 36.326064 -364.871)
			(xy 36.325578 -364.898251) (xy 36.317822 -364.952199) (xy 36.302467 -365.004494) (xy 36.279825 -365.054071)
			(xy 36.250359 -365.099921) (xy 36.214668 -365.141112) (xy 36.173477 -365.176803) (xy 36.127627 -365.206269)
			(xy 36.07805 -365.228911) (xy 36.025755 -365.244266) (xy 35.971807 -365.252022) (xy 35.917305 -365.252022)
			(xy 35.863357 -365.244266) (xy 35.811062 -365.228911) (xy 35.761485 -365.206269) (xy 35.715635 -365.176803)
			(xy 35.674444 -365.141112) (xy 35.638753 -365.099921) (xy 35.609287 -365.054071) (xy 35.586645 -365.004494)
			(xy 35.57129 -364.952199) (xy 35.563534 -364.898251) (xy 35.563048 -364.871) (xy 35.56353 -364.84225)
			(xy 35.572184 -364.785405) (xy 35.589267 -364.730502) (xy 35.614391 -364.678781) (xy 35.646989 -364.631415)
			(xy 35.686323 -364.589473) (xy 35.70859 -364.57128) (xy 35.708844 -364.57128) (xy 35.717546 -364.563635)
			(xy 35.727461 -364.542724) (xy 35.727894 -364.531148) (xy 35.72764 -364.450884) (xy 35.7271 -364.439312)
			(xy 35.716886 -364.41854) (xy 35.708082 -364.411006) (xy 35.707828 -364.411006) (xy 35.685147 -364.392843)
			(xy 35.645085 -364.350755) (xy 35.611864 -364.303082) (xy 35.586253 -364.250925) (xy 35.568843 -364.195488)
			(xy 35.560036 -364.138053) (xy 35.559492 -364.109) (xy 35.559957 -364.081724) (xy 35.567727 -364.027728)
			(xy 35.583108 -363.97539) (xy 35.605788 -363.925776) (xy 35.635303 -363.879898) (xy 35.671052 -363.838692)
			(xy 35.712306 -363.802999) (xy 35.758223 -363.773544) (xy 35.807867 -363.750931) (xy 35.860225 -363.735619)
			(xy 35.914231 -363.727921) (xy 35.941508 -363.727492) (xy 35.941762 -363.727492) (xy 35.951829 -363.727049)
			(xy 35.970427 -363.719341) (xy 35.97783 -363.712506) (xy 36.043362 -363.646974) (xy 36.050297 -363.639356)
			(xy 36.057883 -363.620218) (xy 36.057364 -363.599639) (xy 36.053522 -363.590078) (xy 36.008056 -363.488986)
			(xy 35.980878 -363.47273) (xy 35.96513 -363.473746) (xy 35.941 -363.474508) (xy 35.913724 -363.474043)
			(xy 35.859728 -363.466273) (xy 35.80739 -363.450892) (xy 35.757776 -363.428212) (xy 35.711898 -363.398697)
			(xy 35.670692 -363.362948) (xy 35.634999 -363.321694) (xy 35.605544 -363.275777) (xy 35.582931 -363.226133)
			(xy 35.567619 -363.173775) (xy 35.559921 -363.119769) (xy 35.559492 -363.092492) (xy 35.559492 -363.092238)
			(xy 35.559049 -363.082171) (xy 35.551341 -363.063573) (xy 35.544506 -363.05617) (xy 34.351976 -361.863894)
			(xy 34.344579 -361.85705) (xy 34.325977 -361.849333) (xy 34.315908 -361.848908) (xy 28.981654 -361.848908)
			(xy 28.956658 -361.848259) (xy 28.907635 -361.838462) (xy 28.861464 -361.819292) (xy 28.819918 -361.791487)
			(xy 28.801822 -361.774232) (xy 25.931368 -358.903778) (xy 25.91412 -358.885675) (xy 25.886305 -358.844134)
			(xy 25.867129 -358.797965) (xy 25.857329 -358.748942) (xy 25.856692 -358.723946) (xy 24.017115 -358.723946)
			(xy 24.020525 -358.747114) (xy 24.021034 -358.775) (xy 24.020525 -358.802886) (xy 24.012405 -358.858062)
			(xy 23.996337 -358.911469) (xy 23.972665 -358.961966) (xy 23.941892 -359.008479) (xy 23.904675 -359.050016)
			(xy 23.861807 -359.085691) (xy 23.814201 -359.114745) (xy 23.762872 -359.136557) (xy 23.708915 -359.150663)
			(xy 23.653478 -359.156763) (xy 23.597744 -359.154726) (xy 23.542901 -359.144596) (xy 23.490117 -359.126589)
			(xy 23.440517 -359.101088) (xy 23.395159 -359.068637) (xy 23.35501 -359.029928) (xy 23.320924 -358.985785)
			(xy 23.293628 -358.93715) (xy 23.273705 -358.885059) (xy 23.261579 -358.830622) (xy 23.257508 -358.775)
			(xy 20.821904 -358.775) (xy 20.821904 -359.918) (xy 23.239982 -359.918) (xy 23.244053 -359.862378)
			(xy 23.256179 -359.807941) (xy 23.276102 -359.75585) (xy 23.303398 -359.707215) (xy 23.337484 -359.663072)
			(xy 23.377633 -359.624363) (xy 23.422991 -359.591912) (xy 23.472591 -359.566411) (xy 23.525375 -359.548404)
			(xy 23.580218 -359.538274) (xy 23.635952 -359.536237) (xy 23.691389 -359.542337) (xy 23.745346 -359.556443)
			(xy 23.796675 -359.578255) (xy 23.844281 -359.607309) (xy 23.887149 -359.642984) (xy 23.924366 -359.684521)
			(xy 23.955139 -359.731034) (xy 23.978811 -359.781531) (xy 23.994879 -359.834938) (xy 24.002999 -359.890114)
			(xy 24.003508 -359.918) (xy 24.002999 -359.945886) (xy 23.994879 -360.001062) (xy 23.978811 -360.054469)
			(xy 23.955139 -360.104966) (xy 23.924366 -360.151479) (xy 23.887149 -360.193016) (xy 23.844281 -360.228691)
			(xy 23.796675 -360.257745) (xy 23.745346 -360.279557) (xy 23.691389 -360.293663) (xy 23.635952 -360.299763)
			(xy 23.580218 -360.297726) (xy 23.525375 -360.287596) (xy 23.472591 -360.269589) (xy 23.422991 -360.244088)
			(xy 23.377633 -360.211637) (xy 23.337484 -360.172928) (xy 23.303398 -360.128785) (xy 23.276102 -360.08015)
			(xy 23.256179 -360.028059) (xy 23.244053 -359.973622) (xy 23.239982 -359.918) (xy 20.821904 -359.918)
			(xy 20.821904 -361.061) (xy 23.239982 -361.061) (xy 23.244053 -361.005378) (xy 23.256179 -360.950941)
			(xy 23.276102 -360.89885) (xy 23.303398 -360.850215) (xy 23.337484 -360.806072) (xy 23.377633 -360.767363)
			(xy 23.422991 -360.734912) (xy 23.472591 -360.709411) (xy 23.525375 -360.691404) (xy 23.580218 -360.681274)
			(xy 23.635952 -360.679237) (xy 23.691389 -360.685337) (xy 23.745346 -360.699443) (xy 23.796675 -360.721255)
			(xy 23.844281 -360.750309) (xy 23.887149 -360.785984) (xy 23.924366 -360.827521) (xy 23.955139 -360.874034)
			(xy 23.978811 -360.924531) (xy 23.994879 -360.977938) (xy 24.002999 -361.033114) (xy 24.003508 -361.061)
			(xy 24.002999 -361.088886) (xy 23.994879 -361.144062) (xy 23.978811 -361.197469) (xy 23.955139 -361.247966)
			(xy 23.924366 -361.294479) (xy 23.887149 -361.336016) (xy 23.844281 -361.371691) (xy 23.796675 -361.400745)
			(xy 23.745346 -361.422557) (xy 23.691389 -361.436663) (xy 23.635952 -361.442763) (xy 23.580218 -361.440726)
			(xy 23.525375 -361.430596) (xy 23.472591 -361.412589) (xy 23.422991 -361.387088) (xy 23.377633 -361.354637)
			(xy 23.337484 -361.315928) (xy 23.303398 -361.271785) (xy 23.276102 -361.22315) (xy 23.256179 -361.171059)
			(xy 23.244053 -361.116622) (xy 23.239982 -361.061) (xy 20.821904 -361.061) (xy 20.821904 -361.404154)
			(xy 20.822472 -361.415779) (xy 20.832652 -361.436682) (xy 20.841462 -361.444286) (xy 20.862306 -361.461025)
			(xy 20.899553 -361.499371) (xy 20.931078 -361.542545) (xy 20.956262 -361.589699) (xy 20.974611 -361.63991)
			(xy 20.985765 -361.692191) (xy 20.989506 -361.745518) (xy 20.98576 -361.798845) (xy 20.9746 -361.851126)
			(xy 20.956247 -361.901334) (xy 20.931058 -361.948487) (xy 20.899529 -361.991657) (xy 20.862278 -362.03)
			(xy 20.841462 -362.046774) (xy 20.832637 -362.054367) (xy 20.82246 -362.075276) (xy 20.821904 -362.086906)
			(xy 20.821904 -362.204) (xy 23.239982 -362.204) (xy 23.244053 -362.148378) (xy 23.256179 -362.093941)
			(xy 23.276102 -362.04185) (xy 23.303398 -361.993215) (xy 23.337484 -361.949072) (xy 23.377633 -361.910363)
			(xy 23.422991 -361.877912) (xy 23.472591 -361.852411) (xy 23.525375 -361.834404) (xy 23.580218 -361.824274)
			(xy 23.635952 -361.822237) (xy 23.691389 -361.828337) (xy 23.745346 -361.842443) (xy 23.796675 -361.864255)
			(xy 23.844281 -361.893309) (xy 23.887149 -361.928984) (xy 23.924366 -361.970521) (xy 23.955139 -362.017034)
			(xy 23.978811 -362.067531) (xy 23.994879 -362.120938) (xy 24.002999 -362.176114) (xy 24.003508 -362.204)
			(xy 24.002999 -362.231886) (xy 23.994879 -362.287062) (xy 23.978811 -362.340469) (xy 23.955139 -362.390966)
			(xy 23.924366 -362.437479) (xy 23.887149 -362.479016) (xy 23.844281 -362.514691) (xy 23.796675 -362.543745)
			(xy 23.745346 -362.565557) (xy 23.691389 -362.579663) (xy 23.635952 -362.585763) (xy 23.580218 -362.583726)
			(xy 23.525375 -362.573596) (xy 23.472591 -362.555589) (xy 23.422991 -362.530088) (xy 23.377633 -362.497637)
			(xy 23.337484 -362.458928) (xy 23.303398 -362.414785) (xy 23.276102 -362.36615) (xy 23.256179 -362.314059)
			(xy 23.244053 -362.259622) (xy 23.239982 -362.204) (xy 20.821904 -362.204) (xy 20.821904 -362.237528)
			(xy 20.822401 -362.248367) (xy 20.831351 -362.26811) (xy 20.839176 -362.275628) (xy 20.859157 -362.293825)
			(xy 20.894297 -362.334882) (xy 20.923291 -362.380488) (xy 20.945561 -362.429728) (xy 20.960659 -362.481618)
			(xy 20.968285 -362.535119) (xy 20.968285 -362.589161) (xy 20.960659 -362.642662) (xy 20.952826 -362.669582)
			(xy 25.545286 -362.669582) (xy 25.549357 -362.61396) (xy 25.561483 -362.559523) (xy 25.581406 -362.507432)
			(xy 25.608702 -362.458797) (xy 25.642788 -362.414654) (xy 25.682937 -362.375945) (xy 25.728295 -362.343494)
			(xy 25.777895 -362.317993) (xy 25.830679 -362.299986) (xy 25.885522 -362.289856) (xy 25.941256 -362.287819)
			(xy 25.996693 -362.293919) (xy 26.05065 -362.308025) (xy 26.101979 -362.329837) (xy 26.149585 -362.358891)
			(xy 26.192453 -362.394566) (xy 26.22967 -362.436103) (xy 26.260443 -362.482616) (xy 26.284115 -362.533113)
			(xy 26.300183 -362.58652) (xy 26.308303 -362.641696) (xy 26.308812 -362.669582) (xy 26.308303 -362.697468)
			(xy 26.300183 -362.752644) (xy 26.284115 -362.806051) (xy 26.260443 -362.856548) (xy 26.22967 -362.903061)
			(xy 26.192453 -362.944598) (xy 26.149585 -362.980273) (xy 26.101979 -363.009327) (xy 26.05065 -363.031139)
			(xy 25.996693 -363.045245) (xy 25.941256 -363.051345) (xy 25.885522 -363.049308) (xy 25.830679 -363.039178)
			(xy 25.777895 -363.021171) (xy 25.728295 -362.99567) (xy 25.682937 -362.963219) (xy 25.642788 -362.92451)
			(xy 25.608702 -362.880367) (xy 25.581406 -362.831732) (xy 25.561483 -362.779641) (xy 25.549357 -362.725204)
			(xy 25.545286 -362.669582) (xy 20.952826 -362.669582) (xy 20.945561 -362.694552) (xy 20.923291 -362.743792)
			(xy 20.894297 -362.789398) (xy 20.859157 -362.830455) (xy 20.839176 -362.848652) (xy 20.831377 -362.856187)
			(xy 20.822433 -362.87592) (xy 20.821904 -362.886752) (xy 20.821904 -362.946696) (xy 20.822283 -362.955867)
			(xy 20.828757 -362.973028) (xy 20.840899 -362.986774) (xy 20.848828 -362.9914) (xy 20.928076 -363.033818)
			(xy 20.936388 -363.03779) (xy 20.954647 -363.040122) (xy 20.97255 -363.035847) (xy 20.9804 -363.031024)
			(xy 21.004175 -363.015553) (xy 21.055335 -362.991061) (xy 21.109561 -362.974422) (xy 21.165654 -362.966003)
			(xy 21.194014 -362.965492) (xy 21.221265 -362.965979) (xy 21.275211 -362.973737) (xy 21.327504 -362.989093)
			(xy 21.377079 -363.011735) (xy 21.422928 -363.041202) (xy 21.464117 -363.076893) (xy 21.499807 -363.118083)
			(xy 21.529272 -363.163933) (xy 21.551912 -363.213509) (xy 21.567266 -363.265803) (xy 21.575022 -363.319749)
			(xy 21.575522 -363.347) (xy 21.575522 -363.347508) (xy 21.57477 -363.380844) (xy 21.563144 -363.446495)
			(xy 21.552408 -363.478064) (xy 21.54809 -363.48924) (xy 21.550884 -363.513116) (xy 21.608288 -363.601508)
			(xy 21.629116 -363.613446) (xy 21.641054 -363.614208) (xy 21.669696 -363.6166) (xy 21.725838 -363.628905)
			(xy 21.779499 -363.649493) (xy 21.829465 -363.677897) (xy 21.874604 -363.713475) (xy 21.913896 -363.755421)
			(xy 21.946451 -363.802787) (xy 21.971532 -363.8545) (xy 21.988572 -363.909391) (xy 21.997186 -363.966217)
			(xy 21.997452 -363.982) (xy 24.459182 -363.982) (xy 24.463253 -363.926378) (xy 24.475379 -363.871941)
			(xy 24.495302 -363.81985) (xy 24.522598 -363.771215) (xy 24.556684 -363.727072) (xy 24.596833 -363.688363)
			(xy 24.642191 -363.655912) (xy 24.691791 -363.630411) (xy 24.744575 -363.612404) (xy 24.799418 -363.602274)
			(xy 24.855152 -363.600237) (xy 24.910589 -363.606337) (xy 24.964546 -363.620443) (xy 25.015875 -363.642255)
			(xy 25.063481 -363.671309) (xy 25.106349 -363.706984) (xy 25.143566 -363.748521) (xy 25.174339 -363.795034)
			(xy 25.198011 -363.845531) (xy 25.214079 -363.898938) (xy 25.222199 -363.954114) (xy 25.222708 -363.982)
			(xy 25.222199 -364.009886) (xy 25.214079 -364.065062) (xy 25.198011 -364.118469) (xy 25.174339 -364.168966)
			(xy 25.143566 -364.215479) (xy 25.106349 -364.257016) (xy 25.063481 -364.292691) (xy 25.015875 -364.321745)
			(xy 24.964546 -364.343557) (xy 24.910589 -364.357663) (xy 24.855152 -364.363763) (xy 24.799418 -364.361726)
			(xy 24.744575 -364.351596) (xy 24.691791 -364.333589) (xy 24.642191 -364.308088) (xy 24.596833 -364.275637)
			(xy 24.556684 -364.236928) (xy 24.522598 -364.192785) (xy 24.495302 -364.14415) (xy 24.475379 -364.092059)
			(xy 24.463253 -364.037622) (xy 24.459182 -363.982) (xy 21.997452 -363.982) (xy 21.99767 -363.994954)
			(xy 21.997226 -364.021343) (xy 21.989957 -364.073619) (xy 21.97555 -364.124393) (xy 21.954282 -364.172696)
			(xy 21.926557 -364.217606) (xy 21.892907 -364.258265) (xy 21.873718 -364.276386) (xy 21.866098 -364.283244)
			(xy 21.857462 -364.30204) (xy 21.855684 -364.386114) (xy 21.855943 -364.396352) (xy 21.863546 -364.415349)
			(xy 21.870416 -364.422944) (xy 22.191472 -364.744) (xy 25.399492 -364.744) (xy 25.399972 -364.71724)
			(xy 25.407447 -364.664245) (xy 25.42225 -364.612813) (xy 25.444091 -364.563953) (xy 25.472542 -364.518622)
			(xy 25.507045 -364.477709) (xy 25.546924 -364.442015) (xy 25.56891 -364.426754) (xy 25.580028 -364.418875)
			(xy 25.597849 -364.398266) (xy 25.609593 -364.373682) (xy 25.614427 -364.34687) (xy 25.612007 -364.319732)
			(xy 25.602505 -364.294198) (xy 25.586597 -364.27208) (xy 25.576276 -364.263178) (xy 25.554506 -364.244975)
			(xy 25.516101 -364.2032) (xy 25.484308 -364.156197) (xy 25.45983 -364.105002) (xy 25.443208 -364.050746)
			(xy 25.434807 -363.994625) (xy 25.43429 -363.966252) (xy 25.434776 -363.939001) (xy 25.442532 -363.885053)
			(xy 25.457887 -363.832758) (xy 25.480529 -363.783181) (xy 25.509995 -363.737331) (xy 25.545686 -363.69614)
			(xy 25.586877 -363.660449) (xy 25.632727 -363.630983) (xy 25.682304 -363.608341) (xy 25.734599 -363.592986)
			(xy 25.788547 -363.58523) (xy 25.843049 -363.58523) (xy 25.896997 -363.592986) (xy 25.949292 -363.608341)
			(xy 25.998869 -363.630983) (xy 26.044719 -363.660449) (xy 26.08591 -363.69614) (xy 26.121601 -363.737331)
			(xy 26.151067 -363.783181) (xy 26.173709 -363.832758) (xy 26.189064 -363.885053) (xy 26.19682 -363.939001)
			(xy 26.197306 -363.966252) (xy 26.196866 -363.993013) (xy 26.189384 -364.04601) (xy 26.174574 -364.097443)
			(xy 26.152727 -364.146303) (xy 26.12427 -364.191634) (xy 26.089761 -364.232546) (xy 26.049877 -364.268238)
			(xy 26.027888 -364.283498) (xy 26.016815 -364.291436) (xy 25.998996 -364.312032) (xy 25.98725 -364.336603)
			(xy 25.982411 -364.363403) (xy 25.984822 -364.390531) (xy 25.994313 -364.416058) (xy 26.010208 -364.438172)
			(xy 26.020522 -364.447074) (xy 26.042268 -364.465304) (xy 26.080676 -364.507073) (xy 26.112471 -364.55407)
			(xy 26.136953 -364.60526) (xy 26.153581 -364.659512) (xy 26.161987 -364.715629) (xy 26.162508 -364.744)
			(xy 26.162022 -364.771251) (xy 26.154266 -364.825199) (xy 26.138911 -364.877494) (xy 26.116269 -364.927071)
			(xy 26.086803 -364.972921) (xy 26.051112 -365.014112) (xy 26.009921 -365.049803) (xy 25.964071 -365.079269)
			(xy 25.914494 -365.101911) (xy 25.862199 -365.117266) (xy 25.808251 -365.125022) (xy 25.753749 -365.125022)
			(xy 25.699801 -365.117266) (xy 25.647506 -365.101911) (xy 25.597929 -365.079269) (xy 25.552079 -365.049803)
			(xy 25.510888 -365.014112) (xy 25.475197 -364.972921) (xy 25.445731 -364.927071) (xy 25.423089 -364.877494)
			(xy 25.407734 -364.825199) (xy 25.399978 -364.771251) (xy 25.399492 -364.744) (xy 22.191472 -364.744)
			(xy 22.905212 -365.45774) (xy 22.912062 -365.465136) (xy 22.919796 -365.483736) (xy 22.920198 -365.493808)
			(xy 22.920198 -365.76) (xy 25.627074 -365.76) (xy 25.631145 -365.704378) (xy 25.643271 -365.649941)
			(xy 25.663194 -365.59785) (xy 25.69049 -365.549215) (xy 25.724576 -365.505072) (xy 25.764725 -365.466363)
			(xy 25.810083 -365.433912) (xy 25.859683 -365.408411) (xy 25.912467 -365.390404) (xy 25.96731 -365.380274)
			(xy 26.023044 -365.378237) (xy 26.078481 -365.384337) (xy 26.132438 -365.398443) (xy 26.183767 -365.420255)
			(xy 26.231373 -365.449309) (xy 26.274241 -365.484984) (xy 26.311458 -365.526521) (xy 26.342231 -365.573034)
			(xy 26.365903 -365.623531) (xy 26.381971 -365.676938) (xy 26.390091 -365.732114) (xy 26.3906 -365.76)
			(xy 26.390091 -365.787886) (xy 26.381971 -365.843062) (xy 26.365903 -365.896469) (xy 26.342231 -365.946966)
			(xy 26.311458 -365.993479) (xy 26.274241 -366.035016) (xy 26.231373 -366.070691) (xy 26.183767 -366.099745)
			(xy 26.132438 -366.121557) (xy 26.078481 -366.135663) (xy 26.023044 -366.141763) (xy 25.96731 -366.139726)
			(xy 25.912467 -366.129596) (xy 25.859683 -366.111589) (xy 25.810083 -366.086088) (xy 25.764725 -366.053637)
			(xy 25.724576 -366.014928) (xy 25.69049 -365.970785) (xy 25.663194 -365.92215) (xy 25.643271 -365.870059)
			(xy 25.631145 -365.815622) (xy 25.627074 -365.76) (xy 22.920198 -365.76) (xy 22.920198 -366.021874)
			(xy 22.920635 -366.031938) (xy 22.928368 -366.050523) (xy 22.935184 -366.057942) (xy 23.42896 -366.551718)
			(xy 23.459186 -366.55756) (xy 23.473664 -366.551464) (xy 23.497188 -366.541982) (xy 23.546117 -366.528629)
			(xy 23.596387 -366.521896) (xy 23.621746 -366.521492) (xy 23.622 -366.521492) (xy 23.653521 -366.522163)
			(xy 23.715698 -366.532565) (xy 23.775324 -366.553037) (xy 23.803356 -366.567466) (xy 23.808984 -366.570294)
			(xy 23.82119 -366.573384) (xy 23.827486 -366.573562)
		)
		(stroke
			(width 0)
			(type solid)
		)
		(fill yes)
		(layer "In2.Cu")
		(net "GND")
	)
	(gr_poly
		(pts
			(xy 100.456492 -202.079352) (xy 100.466562 -202.078929) (xy 100.485164 -202.071211) (xy 100.49256 -202.064366)
			(xy 101.062028 -201.494898) (xy 101.069902 -201.484738) (xy 101.670104 -200.468738) (xy 101.672842 -200.464412)
			(xy 101.679754 -200.456863) (xy 101.68382 -200.453752) (xy 139.589764 -172.384974) (xy 139.595606 -172.380148)
			(xy 142.766288 -169.209212) (xy 142.773102 -169.201868) (xy 142.78084 -169.183406) (xy 142.781274 -169.173398)
			(xy 142.781274 -146.797014) (xy 142.780835 -146.786951) (xy 142.773095 -146.768372) (xy 142.766288 -146.760946)
			(xy 132.505196 -136.499854) (xy 132.498084 -136.492488) (xy 131.656074 -135.650478) (xy 131.65582 -135.650478)
			(xy 130.61696 -134.611618) (xy 130.60956 -134.604776) (xy 130.590962 -134.597053) (xy 130.580892 -134.596632)
			(xy 119.984012 -134.596632) (xy 119.974024 -134.597168) (xy 119.955592 -134.604882) (xy 119.948198 -134.611618)
			(xy 110.910161 -143.649446) (xy 112.505996 -143.649446) (xy 112.510067 -143.593824) (xy 112.522193 -143.539387)
			(xy 112.542116 -143.487296) (xy 112.569412 -143.438661) (xy 112.603498 -143.394518) (xy 112.643647 -143.355809)
			(xy 112.689005 -143.323358) (xy 112.738605 -143.297857) (xy 112.791389 -143.27985) (xy 112.846232 -143.26972)
			(xy 112.901966 -143.267683) (xy 112.957403 -143.273783) (xy 113.01136 -143.287889) (xy 113.062689 -143.309701)
			(xy 113.110295 -143.338755) (xy 113.153163 -143.37443) (xy 113.19038 -143.415967) (xy 113.221153 -143.46248)
			(xy 113.244825 -143.512977) (xy 113.260893 -143.566384) (xy 113.269013 -143.62156) (xy 113.269522 -143.649446)
			(xy 113.269013 -143.677332) (xy 113.260893 -143.732508) (xy 113.244825 -143.785915) (xy 113.221153 -143.836412)
			(xy 113.19038 -143.882925) (xy 113.153163 -143.924462) (xy 113.110295 -143.960137) (xy 113.062689 -143.989191)
			(xy 113.01136 -144.011003) (xy 112.957403 -144.025109) (xy 112.901966 -144.031209) (xy 112.846232 -144.029172)
			(xy 112.791389 -144.019042) (xy 112.738605 -144.001035) (xy 112.689005 -143.975534) (xy 112.643647 -143.943083)
			(xy 112.603498 -143.904374) (xy 112.569412 -143.860231) (xy 112.542116 -143.811596) (xy 112.522193 -143.759505)
			(xy 112.510067 -143.705068) (xy 112.505996 -143.649446) (xy 110.910161 -143.649446) (xy 108.985812 -145.57375)
			(xy 108.972597 -145.586352) (xy 108.942259 -145.606667) (xy 108.908546 -145.620685) (xy 108.872749 -145.627871)
			(xy 108.854494 -145.62836) (xy 104.52989 -145.62836) (xy 104.51725 -145.629039) (xy 104.495002 -145.641043)
			(xy 104.487472 -145.65122) (xy 104.472283 -145.67359) (xy 104.436601 -145.714216) (xy 104.395541 -145.749397)
			(xy 104.349926 -145.77843) (xy 104.300669 -145.800732) (xy 104.248757 -145.815858) (xy 104.195229 -145.823504)
			(xy 104.168194 -145.82394) (xy 104.140941 -145.823454) (xy 104.086989 -145.815696) (xy 104.034691 -145.800339)
			(xy 103.98511 -145.777696) (xy 103.939257 -145.748227) (xy 103.898064 -145.712532) (xy 103.86237 -145.671339)
			(xy 103.832902 -145.625485) (xy 103.810259 -145.575904) (xy 103.794903 -145.523605) (xy 103.787146 -145.469653)
			(xy 103.787146 -145.415147) (xy 103.794903 -145.361195) (xy 103.810259 -145.308896) (xy 103.832902 -145.259315)
			(xy 103.86237 -145.213461) (xy 103.898064 -145.172268) (xy 103.939257 -145.136573) (xy 103.98511 -145.107104)
			(xy 104.034691 -145.084461) (xy 104.086989 -145.069104) (xy 104.140941 -145.061346) (xy 104.168194 -145.060924)
			(xy 104.195228 -145.061395) (xy 104.248754 -145.06903) (xy 104.300665 -145.084149) (xy 104.34992 -145.106447)
			(xy 104.395532 -145.135479) (xy 104.436587 -145.170661) (xy 104.472262 -145.211289) (xy 104.487472 -145.233644)
			(xy 104.494989 -145.243832) (xy 104.517247 -145.255827) (xy 104.52989 -145.256504) (xy 108.75645 -145.256504)
			(xy 108.766483 -145.256067) (xy 108.785059 -145.248494) (xy 108.792518 -145.241772) (xy 119.35079 -134.683246)
			(xy 119.357622 -134.675884) (xy 119.365374 -134.657371) (xy 119.365428 -134.637301) (xy 119.361966 -134.627874)
			(xy 119.35587 -134.61365) (xy 119.330724 -134.596632) (xy 99.833176 -134.596632) (xy 99.81438 -134.604252)
			(xy 99.807268 -134.611618) (xy 96.4946 -137.924286) (xy 96.486472 -137.932414) (xy 96.478852 -137.95375)
			(xy 96.487234 -138.041634) (xy 96.487996 -138.049762) (xy 96.491298 -138.057382) (xy 96.495108 -138.066272)
			(xy 96.508824 -138.079988) (xy 96.512634 -138.082528) (xy 96.53396 -138.097888) (xy 96.572589 -138.133524)
			(xy 96.605965 -138.174121) (xy 96.633456 -138.218912) (xy 96.654545 -138.267051) (xy 96.668831 -138.317628)
			(xy 96.673491 -138.35126) (xy 104.87609 -138.35126) (xy 104.880161 -138.295638) (xy 104.892287 -138.241201)
			(xy 104.91221 -138.18911) (xy 104.939506 -138.140475) (xy 104.973592 -138.096332) (xy 105.013741 -138.057623)
			(xy 105.059099 -138.025172) (xy 105.108699 -137.999671) (xy 105.161483 -137.981664) (xy 105.216326 -137.971534)
			(xy 105.27206 -137.969497) (xy 105.327497 -137.975597) (xy 105.381454 -137.989703) (xy 105.432783 -138.011515)
			(xy 105.480389 -138.040569) (xy 105.523257 -138.076244) (xy 105.560474 -138.117781) (xy 105.591247 -138.164294)
			(xy 105.614919 -138.214791) (xy 105.630987 -138.268198) (xy 105.639107 -138.323374) (xy 105.639616 -138.35126)
			(xy 105.639107 -138.379146) (xy 105.630987 -138.434322) (xy 105.614919 -138.487729) (xy 105.591247 -138.538226)
			(xy 105.560474 -138.584739) (xy 105.523257 -138.626276) (xy 105.480389 -138.661951) (xy 105.432783 -138.691005)
			(xy 105.381454 -138.712817) (xy 105.327497 -138.726923) (xy 105.27206 -138.733023) (xy 105.216326 -138.730986)
			(xy 105.161483 -138.720856) (xy 105.108699 -138.702849) (xy 105.059099 -138.677348) (xy 105.013741 -138.644897)
			(xy 104.973592 -138.606188) (xy 104.939506 -138.562045) (xy 104.91221 -138.51341) (xy 104.892287 -138.461319)
			(xy 104.880161 -138.406882) (xy 104.87609 -138.35126) (xy 96.673491 -138.35126) (xy 96.676044 -138.369686)
			(xy 96.676464 -138.395964) (xy 96.675978 -138.423215) (xy 96.668222 -138.477163) (xy 96.652867 -138.529458)
			(xy 96.630225 -138.579035) (xy 96.600759 -138.624885) (xy 96.565068 -138.666076) (xy 96.523877 -138.701767)
			(xy 96.478027 -138.731233) (xy 96.42845 -138.753875) (xy 96.376155 -138.76923) (xy 96.322207 -138.776986)
			(xy 96.267705 -138.776986) (xy 96.213757 -138.76923) (xy 96.161462 -138.753875) (xy 96.111885 -138.731233)
			(xy 96.066035 -138.701767) (xy 96.024844 -138.666076) (xy 95.989153 -138.624885) (xy 95.959687 -138.579035)
			(xy 95.937045 -138.529458) (xy 95.92169 -138.477163) (xy 95.913934 -138.423215) (xy 95.913448 -138.395964)
			(xy 95.913961 -138.367301) (xy 95.922538 -138.310621) (xy 95.939509 -138.255865) (xy 95.951548 -138.229848)
			(xy 95.957136 -138.21791) (xy 95.955866 -138.191748) (xy 95.903034 -138.107928) (xy 95.898196 -138.100791)
			(xy 95.884743 -138.090024) (xy 95.868471 -138.084358) (xy 95.859854 -138.084052) (xy 95.433134 -138.084052)
			(xy 95.426784 -138.084306) (xy 95.415354 -138.08583) (xy 95.412052 -138.086592) (xy 95.411798 -138.086592)
			(xy 95.405956 -138.087862) (xy 95.38589 -138.09218) (xy 95.369333 -138.095) (xy 95.335882 -138.09805)
			(xy 95.319088 -138.098276) (xy 95.31858 -138.098276) (xy 95.294113 -138.097882) (xy 95.245578 -138.091636)
			(xy 95.221806 -138.08583) (xy 95.215456 -138.084052) (xy 90.67038 -138.084052) (xy 90.655715 -138.08454)
			(xy 90.627596 -138.092882) (xy 90.603008 -138.108872) (xy 90.583979 -138.131192) (xy 90.572079 -138.158)
			(xy 90.568289 -138.187084) (xy 90.57005 -138.201654) (xy 90.57005 -138.202162) (xy 90.570304 -138.203432)
			(xy 90.573507 -138.221166) (xy 90.576944 -138.257041) (xy 90.577162 -138.27506) (xy 90.576676 -138.302329)
			(xy 90.568914 -138.356313) (xy 90.553549 -138.408643) (xy 90.530892 -138.458253) (xy 90.501406 -138.504134)
			(xy 90.465691 -138.545351) (xy 90.424474 -138.581066) (xy 90.378593 -138.610552) (xy 90.328983 -138.633209)
			(xy 90.276653 -138.648574) (xy 90.222669 -138.656336) (xy 90.168131 -138.656336) (xy 90.114147 -138.648574)
			(xy 90.061817 -138.633209) (xy 90.012207 -138.610552) (xy 89.966326 -138.581066) (xy 89.925109 -138.545351)
			(xy 89.889394 -138.504134) (xy 89.859908 -138.458253) (xy 89.837251 -138.408643) (xy 89.821886 -138.356313)
			(xy 89.814124 -138.302329) (xy 89.813638 -138.27506) (xy 89.813873 -138.257042) (xy 89.817311 -138.221168)
			(xy 89.820496 -138.203432) (xy 89.82075 -138.202162) (xy 89.82075 -138.201654) (xy 89.822575 -138.187094)
			(xy 89.818761 -138.158011) (xy 89.806843 -138.13121) (xy 89.787802 -138.108898) (xy 89.763208 -138.092915)
			(xy 89.735086 -138.084577) (xy 89.72042 -138.084052) (xy 89.550748 -138.084052) (xy 89.542874 -138.08456)
			(xy 89.532206 -138.086338) (xy 89.528396 -138.087608) (xy 89.499706 -138.096275) (xy 89.440505 -138.105587)
			(xy 89.41054 -138.10615) (xy 89.40673 -138.10615) (xy 89.37609 -138.105515) (xy 89.315602 -138.095681)
			(xy 89.286334 -138.086592) (xy 89.27846 -138.084052) (xy 89.127838 -138.084052) (xy 89.119964 -138.086592)
			(xy 89.091266 -138.095631) (xy 89.031931 -138.105589) (xy 89.001854 -138.106404) (xy 89.001346 -138.106404)
			(xy 88.971271 -138.105576) (xy 88.911937 -138.095619) (xy 88.883236 -138.086592) (xy 88.875362 -138.084052)
			(xy 88.655652 -138.084052) (xy 88.645647 -138.084548) (xy 88.627164 -138.092214) (xy 88.613014 -138.106364)
			(xy 88.605348 -138.124847) (xy 88.604852 -138.134852) (xy 88.604852 -138.793982) (xy 96.825052 -138.793982)
			(xy 96.829123 -138.73836) (xy 96.841249 -138.683923) (xy 96.861172 -138.631832) (xy 96.888468 -138.583197)
			(xy 96.922554 -138.539054) (xy 96.962703 -138.500345) (xy 97.008061 -138.467894) (xy 97.057661 -138.442393)
			(xy 97.110445 -138.424386) (xy 97.165288 -138.414256) (xy 97.221022 -138.412219) (xy 97.276459 -138.418319)
			(xy 97.330416 -138.432425) (xy 97.381745 -138.454237) (xy 97.429351 -138.483291) (xy 97.472219 -138.518966)
			(xy 97.509436 -138.560503) (xy 97.540209 -138.607016) (xy 97.563881 -138.657513) (xy 97.579949 -138.71092)
			(xy 97.588069 -138.766096) (xy 97.588578 -138.793982) (xy 97.588069 -138.821868) (xy 97.579949 -138.877044)
			(xy 97.568105 -138.91641) (xy 102.14686 -138.91641) (xy 102.150931 -138.860788) (xy 102.163057 -138.806351)
			(xy 102.18298 -138.75426) (xy 102.210276 -138.705625) (xy 102.244362 -138.661482) (xy 102.284511 -138.622773)
			(xy 102.329869 -138.590322) (xy 102.379469 -138.564821) (xy 102.432253 -138.546814) (xy 102.487096 -138.536684)
			(xy 102.54283 -138.534647) (xy 102.598267 -138.540747) (xy 102.652224 -138.554853) (xy 102.703553 -138.576665)
			(xy 102.751159 -138.605719) (xy 102.794027 -138.641394) (xy 102.831244 -138.682931) (xy 102.862017 -138.729444)
			(xy 102.885689 -138.779941) (xy 102.901757 -138.833348) (xy 102.909877 -138.888524) (xy 102.910386 -138.91641)
			(xy 102.909877 -138.944296) (xy 102.901757 -138.999472) (xy 102.885689 -139.052879) (xy 102.862017 -139.103376)
			(xy 102.831244 -139.149889) (xy 102.794027 -139.191426) (xy 102.751159 -139.227101) (xy 102.703553 -139.256155)
			(xy 102.652224 -139.277967) (xy 102.598267 -139.292073) (xy 102.54283 -139.298173) (xy 102.487096 -139.296136)
			(xy 102.432253 -139.286006) (xy 102.379469 -139.267999) (xy 102.329869 -139.242498) (xy 102.284511 -139.210047)
			(xy 102.244362 -139.171338) (xy 102.210276 -139.127195) (xy 102.18298 -139.07856) (xy 102.163057 -139.026469)
			(xy 102.150931 -138.972032) (xy 102.14686 -138.91641) (xy 97.568105 -138.91641) (xy 97.563881 -138.930451)
			(xy 97.540209 -138.980948) (xy 97.509436 -139.027461) (xy 97.472219 -139.068998) (xy 97.429351 -139.104673)
			(xy 97.381745 -139.133727) (xy 97.330416 -139.155539) (xy 97.276459 -139.169645) (xy 97.221022 -139.175745)
			(xy 97.165288 -139.173708) (xy 97.110445 -139.163578) (xy 97.057661 -139.145571) (xy 97.008061 -139.12007)
			(xy 96.962703 -139.087619) (xy 96.922554 -139.04891) (xy 96.888468 -139.004767) (xy 96.861172 -138.956132)
			(xy 96.841249 -138.904041) (xy 96.829123 -138.849604) (xy 96.825052 -138.793982) (xy 88.604852 -138.793982)
			(xy 88.604852 -138.930126) (xy 88.605106 -138.93165) (xy 88.60536 -138.943842) (xy 88.61298 -138.961622)
			(xy 88.619838 -138.96848) (xy 88.626696 -138.975338) (xy 89.068402 -139.417044) (xy 89.075745 -139.42386)
			(xy 89.094208 -139.431601) (xy 89.104216 -139.43203) (xy 89.114122 -139.43203) (xy 89.119202 -139.431014)
			(xy 89.137927 -139.427512) (xy 89.175845 -139.423819) (xy 89.194894 -139.423648) (xy 89.222117 -139.424202)
			(xy 89.275992 -139.432079) (xy 89.328202 -139.44753) (xy 89.377687 -139.470243) (xy 89.423442 -139.499756)
			(xy 89.46454 -139.535471) (xy 89.500147 -139.576662) (xy 89.52954 -139.622495) (xy 89.552122 -139.67204)
			(xy 89.567436 -139.72429) (xy 89.575171 -139.778186) (xy 89.57564 -139.80541) (xy 89.575176 -139.83268)
			(xy 89.567412 -139.886665) (xy 89.552045 -139.938995) (xy 89.540784 -139.963652) (xy 92.346016 -139.963652)
			(xy 92.350087 -139.90803) (xy 92.362213 -139.853593) (xy 92.382136 -139.801502) (xy 92.409432 -139.752867)
			(xy 92.443518 -139.708724) (xy 92.483667 -139.670015) (xy 92.529025 -139.637564) (xy 92.578625 -139.612063)
			(xy 92.631409 -139.594056) (xy 92.686252 -139.583926) (xy 92.741986 -139.581889) (xy 92.797423 -139.587989)
			(xy 92.85138 -139.602095) (xy 92.902709 -139.623907) (xy 92.950315 -139.652961) (xy 92.993183 -139.688636)
			(xy 93.0304 -139.730173) (xy 93.061173 -139.776686) (xy 93.084845 -139.827183) (xy 93.100913 -139.88059)
			(xy 93.109033 -139.935766) (xy 93.109542 -139.963652) (xy 93.109033 -139.991538) (xy 93.100913 -140.046714)
			(xy 93.084845 -140.100121) (xy 93.061173 -140.150618) (xy 93.0304 -140.197131) (xy 92.993183 -140.238668)
			(xy 92.950315 -140.274343) (xy 92.902709 -140.303397) (xy 92.85138 -140.325209) (xy 92.797423 -140.339315)
			(xy 92.741986 -140.345415) (xy 92.686252 -140.343378) (xy 92.631409 -140.333248) (xy 92.578625 -140.315241)
			(xy 92.529025 -140.28974) (xy 92.483667 -140.257289) (xy 92.443518 -140.21858) (xy 92.409432 -140.174437)
			(xy 92.382136 -140.125802) (xy 92.362213 -140.073711) (xy 92.350087 -140.019274) (xy 92.346016 -139.963652)
			(xy 89.540784 -139.963652) (xy 89.529387 -139.988605) (xy 89.499898 -140.034486) (xy 89.464181 -140.075703)
			(xy 89.42296 -140.111418) (xy 89.377077 -140.140902) (xy 89.327465 -140.163556) (xy 89.275133 -140.178919)
			(xy 89.221148 -140.186678) (xy 89.193878 -140.187172) (xy 89.166725 -140.186692) (xy 89.112967 -140.178993)
			(xy 89.060842 -140.163754) (xy 89.011403 -140.141283) (xy 88.965647 -140.112032) (xy 88.924498 -140.076592)
			(xy 88.888787 -140.035678) (xy 88.859233 -139.990117) (xy 88.836435 -139.940828) (xy 88.820851 -139.888805)
			(xy 88.812796 -139.835099) (xy 88.812116 -139.80795) (xy 88.812116 -139.80541) (xy 88.812361 -139.785707)
			(xy 88.816435 -139.746511) (xy 88.820244 -139.727178) (xy 88.823038 -139.714478) (xy 88.815672 -139.68984)
			(xy 88.28786 -139.162028) (xy 88.28405 -139.158218) (xy 88.283542 -139.15771) (xy 88.24849 -139.122404)
			(xy 88.24168 -139.115058) (xy 88.233948 -139.096596) (xy 88.233504 -139.08659) (xy 88.233504 -139.036806)
			(xy 88.233504 -138.535156) (xy 88.23325 -138.5316) (xy 88.231678 -138.517151) (xy 88.221491 -138.489945)
			(xy 88.204058 -138.466707) (xy 88.180787 -138.449317) (xy 88.153562 -138.439181) (xy 88.124584 -138.43712)
			(xy 88.096199 -138.4433) (xy 88.070701 -138.457221) (xy 88.060022 -138.467084) (xy 86.055454 -140.471652)
			(xy 93.184726 -140.471652) (xy 93.185197 -140.444014) (xy 93.193157 -140.389315) (xy 93.208932 -140.336339)
			(xy 93.232191 -140.286196) (xy 93.262446 -140.239937) (xy 93.299065 -140.198531) (xy 93.319854 -140.180314)
			(xy 93.327474 -140.173964) (xy 93.336618 -140.156946) (xy 93.346016 -140.06703) (xy 93.340682 -140.048488)
			(xy 93.334586 -140.040614) (xy 93.31952 -140.020498) (xy 93.294254 -139.977053) (xy 93.274912 -139.930666)
			(xy 93.261828 -139.88214) (xy 93.25523 -139.832317) (xy 93.25483 -139.807188) (xy 93.255316 -139.779937)
			(xy 93.263072 -139.725989) (xy 93.278427 -139.673694) (xy 93.301069 -139.624117) (xy 93.330535 -139.578267)
			(xy 93.366226 -139.537076) (xy 93.407417 -139.501385) (xy 93.453267 -139.471919) (xy 93.502844 -139.449277)
			(xy 93.555139 -139.433922) (xy 93.609087 -139.426166) (xy 93.663589 -139.426166) (xy 93.717537 -139.433922)
			(xy 93.769832 -139.449277) (xy 93.819409 -139.471919) (xy 93.865259 -139.501385) (xy 93.90645 -139.537076)
			(xy 93.942141 -139.578267) (xy 93.971607 -139.624117) (xy 93.994249 -139.673694) (xy 94.009604 -139.725989)
			(xy 94.01736 -139.779937) (xy 94.017846 -139.807188) (xy 94.017377 -139.834825) (xy 94.009413 -139.889523)
			(xy 93.993637 -139.942498) (xy 93.970377 -139.992641) (xy 93.940122 -140.0389) (xy 93.903506 -140.080307)
			(xy 93.882718 -140.098526) (xy 93.875098 -140.104876) (xy 93.865954 -140.121894) (xy 93.856556 -140.21181)
			(xy 93.86189 -140.230352) (xy 93.867986 -140.238226) (xy 93.883066 -140.258332) (xy 93.908331 -140.30178)
			(xy 93.927671 -140.348169) (xy 93.940751 -140.396697) (xy 93.947345 -140.446522) (xy 93.947742 -140.471652)
			(xy 93.947234 -140.49121) (xy 93.946726 -140.501878) (xy 93.953838 -140.521182) (xy 94.019116 -140.590016)
			(xy 94.038166 -140.598144) (xy 94.048834 -140.598144) (xy 94.050866 -140.598144) (xy 94.086934 -140.557758)
			(xy 94.093281 -140.549951) (xy 94.099945 -140.530989) (xy 94.099888 -140.520928) (xy 94.099126 -140.497052)
			(xy 94.099612 -140.469801) (xy 94.107368 -140.415853) (xy 94.122723 -140.363558) (xy 94.145365 -140.313981)
			(xy 94.174831 -140.268131) (xy 94.210522 -140.22694) (xy 94.251713 -140.191249) (xy 94.297563 -140.161783)
			(xy 94.34714 -140.139141) (xy 94.399435 -140.123786) (xy 94.453383 -140.11603) (xy 94.507885 -140.11603)
			(xy 94.561833 -140.123786) (xy 94.614128 -140.139141) (xy 94.663705 -140.161783) (xy 94.709555 -140.191249)
			(xy 94.750746 -140.22694) (xy 94.766624 -140.245265) (xy 94.973013 -140.245265) (xy 94.980769 -140.191306)
			(xy 94.996124 -140.139) (xy 95.018768 -140.089412) (xy 95.048238 -140.043552) (xy 95.083935 -140.002352)
			(xy 95.125133 -139.966653) (xy 95.170991 -139.937179) (xy 95.220578 -139.914533) (xy 95.272883 -139.899174)
			(xy 95.326841 -139.891415) (xy 95.381354 -139.891415) (xy 95.435312 -139.899173) (xy 95.487617 -139.914531)
			(xy 95.537204 -139.937177) (xy 95.583063 -139.966649) (xy 95.624261 -140.002349) (xy 95.659959 -140.043548)
			(xy 95.68943 -140.089408) (xy 95.712074 -140.138995) (xy 95.72743 -140.191301) (xy 95.735186 -140.245259)
			(xy 95.735648 -140.272516) (xy 95.735648 -140.281914) (xy 95.73514 -140.292836) (xy 95.743776 -140.312902)
			(xy 95.815658 -140.379704) (xy 95.836232 -140.386562) (xy 95.847154 -140.385546) (xy 95.885508 -140.383514)
			(xy 95.914971 -140.384028) (xy 95.9732 -140.393065) (xy 96.02934 -140.410969) (xy 96.055942 -140.423646)
			(xy 96.066102 -140.428726) (xy 96.087692 -140.429488) (xy 96.179386 -140.391388) (xy 96.194118 -140.375386)
			(xy 96.197674 -140.364718) (xy 96.20646 -140.339692) (xy 96.229977 -140.292153) (xy 96.259852 -140.248328)
			(xy 96.29551 -140.209064) (xy 96.336261 -140.175118) (xy 96.381322 -140.147142) (xy 96.429823 -140.125678)
			(xy 96.48083 -140.111138) (xy 96.533359 -140.103802) (xy 96.559878 -140.103352) (xy 96.586625 -140.103759)
			(xy 96.639593 -140.111249) (xy 96.690996 -140.126058) (xy 96.739831 -140.147895) (xy 96.78514 -140.176333)
			(xy 96.826037 -140.210816) (xy 96.861722 -140.250669) (xy 96.891496 -140.295112) (xy 96.90354 -140.318998)
			(xy 96.90862 -140.329666) (xy 96.926654 -140.34389) (xy 97.027746 -140.366496) (xy 97.049844 -140.361162)
			(xy 97.058988 -140.353542) (xy 97.079508 -140.337414) (xy 97.124099 -140.310294) (xy 97.171971 -140.289506)
			(xy 97.22223 -140.275439) (xy 97.273938 -140.268355) (xy 97.300034 -140.267944) (xy 97.326337 -140.268382)
			(xy 97.378441 -140.275627) (xy 97.429057 -140.289961) (xy 97.477223 -140.311112) (xy 97.522027 -140.33868)
			(xy 97.56262 -140.372141) (xy 97.598231 -140.410861) (xy 97.628185 -140.454106) (xy 97.651914 -140.501056)
			(xy 97.668969 -140.55082) (xy 97.67443 -140.576554) (xy 97.676462 -140.58646) (xy 97.687638 -140.603478)
			(xy 97.7646 -140.654786) (xy 97.784412 -140.658596) (xy 97.794572 -140.656564) (xy 97.813418 -140.652987)
			(xy 97.851591 -140.64917) (xy 97.870772 -140.648944) (xy 97.898023 -140.649501) (xy 97.95197 -140.657254)
			(xy 98.004265 -140.672606) (xy 98.053842 -140.695244) (xy 98.099693 -140.724707) (xy 98.140884 -140.760397)
			(xy 98.176576 -140.801585) (xy 98.206043 -140.847433) (xy 98.228684 -140.897009) (xy 98.240421 -140.93698)
			(xy 98.420172 -140.93698) (xy 98.424243 -140.881358) (xy 98.436369 -140.826921) (xy 98.456292 -140.77483)
			(xy 98.483588 -140.726195) (xy 98.517674 -140.682052) (xy 98.557823 -140.643343) (xy 98.603181 -140.610892)
			(xy 98.652781 -140.585391) (xy 98.705565 -140.567384) (xy 98.760408 -140.557254) (xy 98.816142 -140.555217)
			(xy 98.871579 -140.561317) (xy 98.925536 -140.575423) (xy 98.976865 -140.597235) (xy 99.024471 -140.626289)
			(xy 99.067339 -140.661964) (xy 99.104556 -140.703501) (xy 99.135329 -140.750014) (xy 99.159001 -140.800511)
			(xy 99.175069 -140.853918) (xy 99.183189 -140.909094) (xy 99.183698 -140.93698) (xy 99.183189 -140.964866)
			(xy 99.175069 -141.020042) (xy 99.159001 -141.073449) (xy 99.135329 -141.123946) (xy 99.104556 -141.170459)
			(xy 99.067339 -141.211996) (xy 99.024471 -141.247671) (xy 98.976865 -141.276725) (xy 98.925536 -141.298537)
			(xy 98.871579 -141.312643) (xy 98.816142 -141.318743) (xy 98.760408 -141.316706) (xy 98.705565 -141.306576)
			(xy 98.652781 -141.288569) (xy 98.603181 -141.263068) (xy 98.557823 -141.230617) (xy 98.517674 -141.191908)
			(xy 98.483588 -141.147765) (xy 98.456292 -141.09913) (xy 98.436369 -141.047039) (xy 98.424243 -140.992602)
			(xy 98.420172 -140.93698) (xy 98.240421 -140.93698) (xy 98.24404 -140.949303) (xy 98.251797 -141.003249)
			(xy 98.251797 -141.057751) (xy 98.24404 -141.111697) (xy 98.228684 -141.163991) (xy 98.206043 -141.213567)
			(xy 98.176576 -141.259415) (xy 98.140884 -141.300603) (xy 98.099693 -141.336293) (xy 98.053842 -141.365756)
			(xy 98.004265 -141.388394) (xy 97.95197 -141.403746) (xy 97.898023 -141.411499) (xy 97.870772 -141.41196)
			(xy 97.84447 -141.411513) (xy 97.792365 -141.404269) (xy 97.74175 -141.389936) (xy 97.693584 -141.368786)
			(xy 97.64878 -141.341219) (xy 97.608188 -141.307759) (xy 97.572577 -141.26904) (xy 97.542622 -141.225796)
			(xy 97.518893 -141.178847) (xy 97.501837 -141.129083) (xy 97.496376 -141.10335) (xy 97.494344 -141.093444)
			(xy 97.483168 -141.076426) (xy 97.406206 -141.025118) (xy 97.386394 -141.021308) (xy 97.376234 -141.02334)
			(xy 97.357388 -141.026916) (xy 97.319215 -141.030734) (xy 97.300034 -141.03096) (xy 97.273288 -141.030536)
			(xy 97.220321 -141.023048) (xy 97.168918 -141.008242) (xy 97.120084 -140.986407) (xy 97.074775 -140.957971)
			(xy 97.033877 -140.92349) (xy 96.998192 -140.88364) (xy 96.968417 -140.839199) (xy 96.956372 -140.815314)
			(xy 96.951292 -140.804646) (xy 96.933258 -140.790422) (xy 96.832166 -140.767816) (xy 96.810068 -140.77315)
			(xy 96.800924 -140.78077) (xy 96.780402 -140.796895) (xy 96.735811 -140.824015) (xy 96.68794 -140.844804)
			(xy 96.637681 -140.858872) (xy 96.585974 -140.865957) (xy 96.559878 -140.866368) (xy 96.530415 -140.865851)
			(xy 96.472187 -140.856813) (xy 96.416046 -140.838912) (xy 96.389444 -140.826236) (xy 96.379284 -140.821156)
			(xy 96.357694 -140.820394) (xy 96.266 -140.858494) (xy 96.251268 -140.874496) (xy 96.247712 -140.885164)
			(xy 96.238928 -140.910191) (xy 96.215411 -140.957731) (xy 96.185537 -141.001556) (xy 96.14988 -141.040821)
			(xy 96.109128 -141.074768) (xy 96.064066 -141.102744) (xy 96.015565 -141.124208) (xy 95.964557 -141.138747)
			(xy 95.912028 -141.146081) (xy 95.885508 -141.14653) (xy 95.858258 -141.146015) (xy 95.804312 -141.13826)
			(xy 95.75202 -141.122907) (xy 95.702444 -141.100268) (xy 95.656594 -141.070805) (xy 95.615405 -141.035117)
			(xy 95.579713 -140.99393) (xy 95.550246 -140.948083) (xy 95.527604 -140.898509) (xy 95.512246 -140.846217)
			(xy 95.504487 -140.792272) (xy 95.504 -140.765022) (xy 95.504 -140.755624) (xy 95.504508 -140.744702)
			(xy 95.495872 -140.724636) (xy 95.42399 -140.657834) (xy 95.403416 -140.650976) (xy 95.392494 -140.651992)
			(xy 95.35414 -140.654024) (xy 95.326883 -140.653588) (xy 95.272924 -140.645835) (xy 95.220618 -140.630482)
			(xy 95.171029 -140.607841) (xy 95.125167 -140.578373) (xy 95.083966 -140.542678) (xy 95.048264 -140.501482)
			(xy 95.018788 -140.455625) (xy 94.996139 -140.40604) (xy 94.980778 -140.353736) (xy 94.973017 -140.299778)
			(xy 94.973013 -140.245265) (xy 94.766624 -140.245265) (xy 94.786437 -140.268131) (xy 94.815903 -140.313981)
			(xy 94.838545 -140.363558) (xy 94.8539 -140.415853) (xy 94.861656 -140.469801) (xy 94.862142 -140.497052)
			(xy 94.861593 -140.525011) (xy 94.853464 -140.580336) (xy 94.837342 -140.63388) (xy 94.813575 -140.684495)
			(xy 94.78267 -140.731098) (xy 94.745292 -140.772688) (xy 94.702242 -140.808374) (xy 94.654441 -140.83739)
			(xy 94.602916 -140.859116) (xy 94.548771 -140.873084) (xy 94.52102 -140.876528) (xy 94.511622 -140.877544)
			(xy 94.495112 -140.885926) (xy 94.436946 -140.95095) (xy 94.430342 -140.968222) (xy 94.430342 -140.979652)
			(xy 94.429856 -141.006903) (xy 94.4221 -141.060851) (xy 94.406745 -141.113146) (xy 94.384103 -141.162723)
			(xy 94.354637 -141.208573) (xy 94.318946 -141.249764) (xy 94.277755 -141.285455) (xy 94.231905 -141.314921)
			(xy 94.182328 -141.337563) (xy 94.130033 -141.352918) (xy 94.076085 -141.360674) (xy 94.021583 -141.360674)
			(xy 93.967635 -141.352918) (xy 93.91534 -141.337563) (xy 93.865763 -141.314921) (xy 93.819913 -141.285455)
			(xy 93.778722 -141.249764) (xy 93.743031 -141.208573) (xy 93.713565 -141.162723) (xy 93.690923 -141.113146)
			(xy 93.675568 -141.060851) (xy 93.667812 -141.006903) (xy 93.667326 -140.979652) (xy 93.667834 -140.960094)
			(xy 93.668342 -140.949426) (xy 93.66123 -140.930122) (xy 93.595952 -140.861288) (xy 93.576902 -140.85316)
			(xy 93.566234 -140.85316) (xy 93.53898 -140.852713) (xy 93.485026 -140.844959) (xy 93.432725 -140.829605)
			(xy 93.383142 -140.806963) (xy 93.337286 -140.777494) (xy 93.296092 -140.741799) (xy 93.260397 -140.700603)
			(xy 93.23093 -140.654746) (xy 93.20829 -140.605162) (xy 93.192938 -140.552861) (xy 93.185186 -140.498906)
			(xy 93.184726 -140.471652) (xy 86.055454 -140.471652) (xy 85.751924 -140.775182) (xy 85.741697 -140.786154)
			(xy 85.727549 -140.812586) (xy 85.721676 -140.841984) (xy 85.724582 -140.871823) (xy 85.736017 -140.899536)
			(xy 85.754998 -140.922742) (xy 85.779893 -140.939445) (xy 85.793432 -140.943584) (xy 88.776554 -140.943584)
			(xy 88.780625 -140.887962) (xy 88.792751 -140.833525) (xy 88.812674 -140.781434) (xy 88.83997 -140.732799)
			(xy 88.874056 -140.688656) (xy 88.914205 -140.649947) (xy 88.959563 -140.617496) (xy 89.009163 -140.591995)
			(xy 89.061947 -140.573988) (xy 89.11679 -140.563858) (xy 89.172524 -140.561821) (xy 89.227961 -140.567921)
			(xy 89.281918 -140.582027) (xy 89.333247 -140.603839) (xy 89.380853 -140.632893) (xy 89.423721 -140.668568)
			(xy 89.460938 -140.710105) (xy 89.491711 -140.756618) (xy 89.515383 -140.807115) (xy 89.531451 -140.860522)
			(xy 89.539571 -140.915698) (xy 89.54008 -140.943584) (xy 89.539571 -140.97147) (xy 89.531451 -141.026646)
			(xy 89.515383 -141.080053) (xy 89.491711 -141.13055) (xy 89.460938 -141.177063) (xy 89.423721 -141.2186)
			(xy 89.380853 -141.254275) (xy 89.333247 -141.283329) (xy 89.281918 -141.305141) (xy 89.227961 -141.319247)
			(xy 89.172524 -141.325347) (xy 89.11679 -141.32331) (xy 89.061947 -141.31318) (xy 89.009163 -141.295173)
			(xy 88.959563 -141.269672) (xy 88.914205 -141.237221) (xy 88.874056 -141.198512) (xy 88.83997 -141.154369)
			(xy 88.812674 -141.105734) (xy 88.792751 -141.053643) (xy 88.780625 -140.999206) (xy 88.776554 -140.943584)
			(xy 85.793432 -140.943584) (xy 85.808563 -140.94821) (xy 85.823552 -140.948664) (xy 86.364572 -140.948664)
			(xy 86.635844 -140.948664) (xy 86.660434 -140.949125) (xy 86.709007 -140.956827) (xy 86.755777 -140.972034)
			(xy 86.799591 -140.994372) (xy 86.839371 -141.02329) (xy 86.857078 -141.040358) (xy 87.237062 -141.420342)
			(xy 92.08592 -141.420342) (xy 92.089991 -141.36472) (xy 92.102117 -141.310283) (xy 92.12204 -141.258192)
			(xy 92.149336 -141.209557) (xy 92.183422 -141.165414) (xy 92.223571 -141.126705) (xy 92.268929 -141.094254)
			(xy 92.318529 -141.068753) (xy 92.371313 -141.050746) (xy 92.426156 -141.040616) (xy 92.48189 -141.038579)
			(xy 92.537327 -141.044679) (xy 92.591284 -141.058785) (xy 92.642613 -141.080597) (xy 92.690219 -141.109651)
			(xy 92.733087 -141.145326) (xy 92.770304 -141.186863) (xy 92.801077 -141.233376) (xy 92.824749 -141.283873)
			(xy 92.840817 -141.33728) (xy 92.848937 -141.392456) (xy 92.849446 -141.420342) (xy 92.848937 -141.448228)
			(xy 92.840817 -141.503404) (xy 92.824749 -141.556811) (xy 92.801077 -141.607308) (xy 92.770304 -141.653821)
			(xy 92.734393 -141.6939) (xy 103.389682 -141.6939) (xy 103.393753 -141.638278) (xy 103.405879 -141.583841)
			(xy 103.425802 -141.53175) (xy 103.453098 -141.483115) (xy 103.487184 -141.438972) (xy 103.527333 -141.400263)
			(xy 103.572691 -141.367812) (xy 103.622291 -141.342311) (xy 103.675075 -141.324304) (xy 103.729918 -141.314174)
			(xy 103.785652 -141.312137) (xy 103.841089 -141.318237) (xy 103.895046 -141.332343) (xy 103.946375 -141.354155)
			(xy 103.993981 -141.383209) (xy 104.036849 -141.418884) (xy 104.074066 -141.460421) (xy 104.104839 -141.506934)
			(xy 104.128511 -141.557431) (xy 104.144579 -141.610838) (xy 104.152699 -141.666014) (xy 104.153208 -141.6939)
			(xy 104.152699 -141.721786) (xy 104.144579 -141.776962) (xy 104.128511 -141.830369) (xy 104.104839 -141.880866)
			(xy 104.074066 -141.927379) (xy 104.036849 -141.968916) (xy 103.993981 -142.004591) (xy 103.946375 -142.033645)
			(xy 103.895046 -142.055457) (xy 103.841089 -142.069563) (xy 103.785652 -142.075663) (xy 103.729918 -142.073626)
			(xy 103.675075 -142.063496) (xy 103.622291 -142.045489) (xy 103.572691 -142.019988) (xy 103.527333 -141.987537)
			(xy 103.487184 -141.948828) (xy 103.453098 -141.904685) (xy 103.425802 -141.85605) (xy 103.405879 -141.803959)
			(xy 103.393753 -141.749522) (xy 103.389682 -141.6939) (xy 92.734393 -141.6939) (xy 92.733087 -141.695358)
			(xy 92.690219 -141.731033) (xy 92.642613 -141.760087) (xy 92.591284 -141.781899) (xy 92.537327 -141.796005)
			(xy 92.48189 -141.802105) (xy 92.426156 -141.800068) (xy 92.371313 -141.789938) (xy 92.318529 -141.771931)
			(xy 92.268929 -141.74643) (xy 92.223571 -141.713979) (xy 92.183422 -141.67527) (xy 92.149336 -141.631127)
			(xy 92.12204 -141.582492) (xy 92.102117 -141.530401) (xy 92.089991 -141.475964) (xy 92.08592 -141.420342)
			(xy 87.237062 -141.420342) (xy 87.920322 -142.103602) (xy 99.991416 -142.103602) (xy 99.995487 -142.04798)
			(xy 100.007613 -141.993543) (xy 100.027536 -141.941452) (xy 100.054832 -141.892817) (xy 100.088918 -141.848674)
			(xy 100.129067 -141.809965) (xy 100.174425 -141.777514) (xy 100.224025 -141.752013) (xy 100.276809 -141.734006)
			(xy 100.331652 -141.723876) (xy 100.387386 -141.721839) (xy 100.442823 -141.727939) (xy 100.49678 -141.742045)
			(xy 100.548109 -141.763857) (xy 100.595715 -141.792911) (xy 100.638583 -141.828586) (xy 100.6758 -141.870123)
			(xy 100.706573 -141.916636) (xy 100.730245 -141.967133) (xy 100.746313 -142.02054) (xy 100.754433 -142.075716)
			(xy 100.754942 -142.103602) (xy 100.754433 -142.131488) (xy 100.746313 -142.186664) (xy 100.730245 -142.240071)
			(xy 100.706573 -142.290568) (xy 100.6758 -142.337081) (xy 100.638583 -142.378618) (xy 100.595715 -142.414293)
			(xy 100.548109 -142.443347) (xy 100.49678 -142.465159) (xy 100.442823 -142.479265) (xy 100.387386 -142.485365)
			(xy 100.331652 -142.483328) (xy 100.276809 -142.473198) (xy 100.224025 -142.455191) (xy 100.174425 -142.42969)
			(xy 100.129067 -142.397239) (xy 100.088918 -142.35853) (xy 100.054832 -142.314387) (xy 100.027536 -142.265752)
			(xy 100.007613 -142.213661) (xy 99.995487 -142.159224) (xy 99.991416 -142.103602) (xy 87.920322 -142.103602)
			(xy 88.321896 -142.505176) (xy 91.124276 -142.505176) (xy 91.128347 -142.449554) (xy 91.140473 -142.395117)
			(xy 91.160396 -142.343026) (xy 91.187692 -142.294391) (xy 91.221778 -142.250248) (xy 91.261927 -142.211539)
			(xy 91.307285 -142.179088) (xy 91.356885 -142.153587) (xy 91.409669 -142.13558) (xy 91.464512 -142.12545)
			(xy 91.520246 -142.123413) (xy 91.575683 -142.129513) (xy 91.62964 -142.143619) (xy 91.680969 -142.165431)
			(xy 91.728575 -142.194485) (xy 91.771443 -142.23016) (xy 91.80866 -142.271697) (xy 91.839433 -142.31821)
			(xy 91.863105 -142.368707) (xy 91.879173 -142.422114) (xy 91.887293 -142.47729) (xy 91.887802 -142.505176)
			(xy 91.887293 -142.533062) (xy 91.879173 -142.588238) (xy 91.863105 -142.641645) (xy 91.839433 -142.692142)
			(xy 91.80866 -142.738655) (xy 91.771443 -142.780192) (xy 91.728575 -142.815867) (xy 91.680969 -142.844921)
			(xy 91.62964 -142.866733) (xy 91.575683 -142.880839) (xy 91.520246 -142.886939) (xy 91.464512 -142.884902)
			(xy 91.409669 -142.874772) (xy 91.356885 -142.856765) (xy 91.307285 -142.831264) (xy 91.261927 -142.798813)
			(xy 91.221778 -142.760104) (xy 91.187692 -142.715961) (xy 91.160396 -142.667326) (xy 91.140473 -142.615235)
			(xy 91.128347 -142.560798) (xy 91.124276 -142.505176) (xy 88.321896 -142.505176) (xy 88.802464 -142.985744)
			(xy 88.805041 -142.988252) (xy 88.810778 -142.992587) (xy 88.813894 -142.99438) (xy 88.820752 -142.997936)
			(xy 88.849288 -143.004152) (xy 88.904181 -143.024083) (xy 88.955402 -143.052134) (xy 89.00176 -143.087652)
			(xy 89.042173 -143.12981) (xy 89.075701 -143.177626) (xy 89.101564 -143.229986) (xy 89.11916 -143.285672)
			(xy 89.128078 -143.343387) (xy 89.1286 -143.372586) (xy 89.128028 -143.401897) (xy 89.118968 -143.459815)
			(xy 89.110566 -143.487902) (xy 89.110566 -143.488156) (xy 89.110312 -143.488664) (xy 89.10748 -143.50007)
			(xy 89.111324 -143.523227) (xy 89.117678 -143.533114) (xy 89.164668 -143.5989) (xy 89.16817 -143.603548)
			(xy 89.176891 -143.611247) (xy 89.18194 -143.61414) (xy 89.182194 -143.61414) (xy 89.187478 -143.616801)
			(xy 89.198895 -143.619888) (xy 89.2048 -143.620236) (xy 89.231543 -143.621458) (xy 89.284315 -143.63046)
			(xy 89.335312 -143.646745) (xy 89.383535 -143.669994) (xy 89.428037 -143.699751) (xy 89.467946 -143.735433)
			(xy 89.50248 -143.776339) (xy 89.530961 -143.821668) (xy 89.552831 -143.870532) (xy 89.567661 -143.921971)
			(xy 89.575161 -143.974977) (xy 89.57564 -144.001744) (xy 89.575154 -144.029013) (xy 89.573178 -144.042754)
			(xy 90.855738 -144.042754) (xy 90.855738 -143.988246) (xy 90.863495 -143.934293) (xy 90.878852 -143.881992)
			(xy 90.901495 -143.83241) (xy 90.930965 -143.786555) (xy 90.96666 -143.74536) (xy 91.007855 -143.709665)
			(xy 91.05371 -143.680195) (xy 91.103292 -143.657552) (xy 91.155593 -143.642195) (xy 91.209546 -143.634438)
			(xy 91.2368 -143.633952) (xy 91.26329 -143.634388) (xy 91.315759 -143.641738) (xy 91.366705 -143.65628)
			(xy 91.415147 -143.677737) (xy 91.460151 -143.705694) (xy 91.500851 -143.739612) (xy 91.518994 -143.75892)
			(xy 91.52822 -143.768469) (xy 91.550551 -143.782819) (xy 91.575827 -143.790926) (xy 91.602338 -143.792242)
			(xy 91.628293 -143.786678) (xy 91.651935 -143.77461) (xy 91.671666 -143.756854) (xy 91.679268 -143.745966)
			(xy 91.694495 -143.723592) (xy 91.730189 -143.682913) (xy 91.771271 -143.647684) (xy 91.816917 -143.618611)
			(xy 91.866212 -143.596277) (xy 91.918167 -143.581129) (xy 91.971741 -143.573471) (xy 91.9988 -143.572992)
			(xy 92.026051 -143.573478) (xy 92.079999 -143.581234) (xy 92.132294 -143.596589) (xy 92.181871 -143.619231)
			(xy 92.227721 -143.648697) (xy 92.268912 -143.684388) (xy 92.304603 -143.725579) (xy 92.334069 -143.771429)
			(xy 92.356711 -143.821006) (xy 92.372066 -143.873301) (xy 92.379822 -143.927249) (xy 92.379822 -143.981751)
			(xy 92.372066 -144.035699) (xy 92.356711 -144.087994) (xy 92.334069 -144.137571) (xy 92.304603 -144.183421)
			(xy 92.268912 -144.224612) (xy 92.227721 -144.260303) (xy 92.181871 -144.289769) (xy 92.132294 -144.312411)
			(xy 92.079999 -144.327766) (xy 92.026051 -144.335522) (xy 91.9988 -144.336008) (xy 91.972309 -144.335585)
			(xy 91.919839 -144.328235) (xy 91.868893 -144.31369) (xy 91.820451 -144.292231) (xy 91.775447 -144.264272)
			(xy 91.734748 -144.23035) (xy 91.716606 -144.21104) (xy 91.705788 -144.199934) (xy 91.679009 -144.184333)
			(xy 91.648787 -144.177468) (xy 91.617896 -144.179968) (xy 91.589172 -144.191605) (xy 91.565251 -144.21131)
			(xy 91.556332 -144.223994) (xy 91.541125 -144.246382) (xy 91.505425 -144.287057) (xy 91.464339 -144.322283)
			(xy 91.418689 -144.351353) (xy 91.369392 -144.373686) (xy 91.317435 -144.388832) (xy 91.26386 -144.396489)
			(xy 91.2368 -144.396968) (xy 91.209546 -144.396562) (xy 91.155593 -144.388805) (xy 91.103292 -144.373448)
			(xy 91.05371 -144.350805) (xy 91.007855 -144.321335) (xy 90.96666 -144.28564) (xy 90.930965 -144.244445)
			(xy 90.901495 -144.19859) (xy 90.878852 -144.149008) (xy 90.863495 -144.096707) (xy 90.855738 -144.042754)
			(xy 89.573178 -144.042754) (xy 89.567392 -144.082997) (xy 89.552027 -144.135327) (xy 89.52937 -144.184937)
			(xy 89.499884 -144.230818) (xy 89.464169 -144.272035) (xy 89.422952 -144.30775) (xy 89.377071 -144.337236)
			(xy 89.327461 -144.359893) (xy 89.275131 -144.375258) (xy 89.221147 -144.38302) (xy 89.166609 -144.38302)
			(xy 89.112625 -144.375258) (xy 89.060295 -144.359893) (xy 89.010685 -144.337236) (xy 88.964804 -144.30775)
			(xy 88.923587 -144.272035) (xy 88.887872 -144.230818) (xy 88.858386 -144.184937) (xy 88.835729 -144.135327)
			(xy 88.820364 -144.082997) (xy 88.812602 -144.029013) (xy 88.812116 -144.001744) (xy 88.812686 -143.972433)
			(xy 88.821742 -143.914513) (xy 88.83015 -143.886428) (xy 88.83015 -143.886174) (xy 88.830404 -143.885666)
			(xy 88.833243 -143.874259) (xy 88.829411 -143.851093) (xy 88.823038 -143.841216) (xy 88.776048 -143.77543)
			(xy 88.772544 -143.770785) (xy 88.763818 -143.763094) (xy 88.758776 -143.76019) (xy 88.758522 -143.76019)
			(xy 88.753238 -143.75753) (xy 88.741821 -143.754444) (xy 88.735916 -143.754094) (xy 88.707745 -143.752778)
			(xy 88.652227 -143.742885) (xy 88.598766 -143.724937) (xy 88.548525 -143.699323) (xy 88.502596 -143.6666)
			(xy 88.461979 -143.627479) (xy 88.427554 -143.582812) (xy 88.400072 -143.533568) (xy 88.38013 -143.480818)
			(xy 88.373712 -143.453358) (xy 88.372188 -143.445992) (xy 88.36533 -143.433546) (xy 88.34374 -143.411702)
			(xy 88.343486 -143.411702) (xy 88.310212 -143.378428) (xy 88.302869 -143.371613) (xy 88.284406 -143.363872)
			(xy 88.274398 -143.363442) (xy 88.26119 -143.363442) (xy 88.20912 -143.37919) (xy 88.206326 -143.379952)
			(xy 88.1888 -143.384016) (xy 88.181577 -143.38604) (xy 88.168665 -143.393659) (xy 88.1634 -143.399002)
			(xy 88.144858 -143.419068) (xy 88.141556 -143.425926) (xy 88.134444 -143.44015) (xy 88.13292 -143.445738)
			(xy 88.132666 -143.446246) (xy 88.125418 -143.473474) (xy 88.104005 -143.525591) (xy 88.075161 -143.573993)
			(xy 88.039514 -143.617628) (xy 87.997839 -143.655547) (xy 87.951041 -143.686925) (xy 87.900137 -143.711081)
			(xy 87.846235 -143.72749) (xy 87.790506 -143.735795) (xy 87.762334 -143.736314) (xy 87.735063 -143.735853)
			(xy 87.681075 -143.728094) (xy 87.628741 -143.712731) (xy 87.579126 -143.690074) (xy 87.533242 -143.660587)
			(xy 87.492022 -143.624869) (xy 87.456305 -143.583647) (xy 87.426819 -143.537761) (xy 87.404165 -143.488146)
			(xy 87.388803 -143.435812) (xy 87.381046 -143.381823) (xy 87.380572 -143.354552) (xy 87.381127 -143.325399)
			(xy 87.389999 -143.267771) (xy 87.407529 -143.212162) (xy 87.43331 -143.159864) (xy 87.466743 -143.112095)
			(xy 87.507049 -143.069963) (xy 87.553293 -143.03445) (xy 87.604398 -143.00638) (xy 87.659177 -142.986406)
			(xy 87.687658 -142.980156) (xy 87.688166 -142.980156) (xy 87.69985 -142.977616) (xy 87.71382 -142.966948)
			(xy 87.72144 -142.957804) (xy 87.723726 -142.952978) (xy 87.726774 -142.947136) (xy 87.752174 -142.86357)
			(xy 87.752682 -142.86103) (xy 87.753952 -142.855696) (xy 87.755613 -142.845881) (xy 87.752205 -142.826287)
			(xy 87.747348 -142.817596) (xy 87.743538 -142.811754) (xy 87.00516 -142.073376) (xy 86.52129 -141.589506)
			(xy 86.513891 -141.582661) (xy 86.495293 -141.574929) (xy 86.485222 -141.57452) (xy 85.278976 -141.57452)
			(xy 85.274223 -141.574621) (xy 85.26489 -141.57642) (xy 85.260434 -141.578076) (xy 85.23605 -141.587474)
			(xy 85.229192 -141.593062) (xy 85.228684 -141.593316) (xy 85.207894 -141.610458) (xy 85.162402 -141.639337)
			(xy 85.113302 -141.661532) (xy 85.061568 -141.676602) (xy 85.008229 -141.684248) (xy 84.981288 -141.684756)
			(xy 84.981034 -141.684756) (xy 84.957742 -141.684379) (xy 84.91151 -141.678653) (xy 84.888832 -141.673326)
			(xy 84.888578 -141.673326) (xy 84.880053 -141.671589) (xy 84.862752 -141.673302) (xy 84.847009 -141.680681)
			(xy 84.840572 -141.686534) (xy 84.239608 -142.287498) (xy 84.23221 -142.294346) (xy 84.213612 -142.302084)
			(xy 84.20354 -142.302484) (xy 56.326024 -142.302484) (xy 56.31596 -142.30292) (xy 56.297374 -142.310652)
			(xy 56.289956 -142.31747) (xy 54.821582 -143.785844) (xy 82.07832 -143.785844) (xy 82.082391 -143.730222)
			(xy 82.094517 -143.675785) (xy 82.11444 -143.623694) (xy 82.141736 -143.575059) (xy 82.175822 -143.530916)
			(xy 82.215971 -143.492207) (xy 82.261329 -143.459756) (xy 82.310929 -143.434255) (xy 82.363713 -143.416248)
			(xy 82.418556 -143.406118) (xy 82.47429 -143.404081) (xy 82.529727 -143.410181) (xy 82.583684 -143.424287)
			(xy 82.635013 -143.446099) (xy 82.682619 -143.475153) (xy 82.725487 -143.510828) (xy 82.762704 -143.552365)
			(xy 82.793477 -143.598878) (xy 82.817149 -143.649375) (xy 82.833217 -143.702782) (xy 82.841337 -143.757958)
			(xy 82.841846 -143.785844) (xy 82.841337 -143.81373) (xy 82.833217 -143.868906) (xy 82.817149 -143.922313)
			(xy 82.793477 -143.97281) (xy 82.762704 -144.019323) (xy 82.725487 -144.06086) (xy 82.682619 -144.096535)
			(xy 82.635013 -144.125589) (xy 82.583684 -144.147401) (xy 82.529727 -144.161507) (xy 82.47429 -144.167607)
			(xy 82.418556 -144.16557) (xy 82.363713 -144.15544) (xy 82.310929 -144.137433) (xy 82.261329 -144.111932)
			(xy 82.215971 -144.079481) (xy 82.175822 -144.040772) (xy 82.141736 -143.996629) (xy 82.11444 -143.947994)
			(xy 82.094517 -143.895903) (xy 82.082391 -143.841466) (xy 82.07832 -143.785844) (xy 54.821582 -143.785844)
			(xy 53.581046 -145.02638) (xy 57.174128 -145.02638) (xy 57.178199 -144.970758) (xy 57.190325 -144.916321)
			(xy 57.210248 -144.86423) (xy 57.237544 -144.815595) (xy 57.27163 -144.771452) (xy 57.311779 -144.732743)
			(xy 57.357137 -144.700292) (xy 57.406737 -144.674791) (xy 57.459521 -144.656784) (xy 57.514364 -144.646654)
			(xy 57.570098 -144.644617) (xy 57.625535 -144.650717) (xy 57.679492 -144.664823) (xy 57.730821 -144.686635)
			(xy 57.778427 -144.715689) (xy 57.821295 -144.751364) (xy 57.858512 -144.792901) (xy 57.889285 -144.839414)
			(xy 57.910847 -144.88541) (xy 88.81186 -144.88541) (xy 88.815931 -144.829788) (xy 88.828057 -144.775351)
			(xy 88.84798 -144.72326) (xy 88.875276 -144.674625) (xy 88.909362 -144.630482) (xy 88.949511 -144.591773)
			(xy 88.994869 -144.559322) (xy 89.044469 -144.533821) (xy 89.097253 -144.515814) (xy 89.152096 -144.505684)
			(xy 89.20783 -144.503647) (xy 89.263267 -144.509747) (xy 89.317224 -144.523853) (xy 89.368553 -144.545665)
			(xy 89.416159 -144.574719) (xy 89.459027 -144.610394) (xy 89.496244 -144.651931) (xy 89.527017 -144.698444)
			(xy 89.550689 -144.748941) (xy 89.566757 -144.802348) (xy 89.574877 -144.857524) (xy 89.575386 -144.88541)
			(xy 89.574877 -144.913296) (xy 89.568253 -144.958308) (xy 90.97086 -144.958308) (xy 90.974931 -144.902686)
			(xy 90.987057 -144.848249) (xy 91.00698 -144.796158) (xy 91.034276 -144.747523) (xy 91.068362 -144.70338)
			(xy 91.108511 -144.664671) (xy 91.153869 -144.63222) (xy 91.203469 -144.606719) (xy 91.256253 -144.588712)
			(xy 91.311096 -144.578582) (xy 91.36683 -144.576545) (xy 91.422267 -144.582645) (xy 91.476224 -144.596751)
			(xy 91.527553 -144.618563) (xy 91.575159 -144.647617) (xy 91.618027 -144.683292) (xy 91.655244 -144.724829)
			(xy 91.686017 -144.771342) (xy 91.709689 -144.821839) (xy 91.725757 -144.875246) (xy 91.733877 -144.930422)
			(xy 91.734386 -144.958308) (xy 91.733877 -144.986194) (xy 91.725757 -145.04137) (xy 91.709689 -145.094777)
			(xy 91.686017 -145.145274) (xy 91.655244 -145.191787) (xy 91.618027 -145.233324) (xy 91.575159 -145.268999)
			(xy 91.527553 -145.298053) (xy 91.476224 -145.319865) (xy 91.422267 -145.333971) (xy 91.36683 -145.340071)
			(xy 91.311096 -145.338034) (xy 91.256253 -145.327904) (xy 91.203469 -145.309897) (xy 91.153869 -145.284396)
			(xy 91.108511 -145.251945) (xy 91.068362 -145.213236) (xy 91.034276 -145.169093) (xy 91.00698 -145.120458)
			(xy 90.987057 -145.068367) (xy 90.974931 -145.01393) (xy 90.97086 -144.958308) (xy 89.568253 -144.958308)
			(xy 89.566757 -144.968472) (xy 89.550689 -145.021879) (xy 89.527017 -145.072376) (xy 89.496244 -145.118889)
			(xy 89.459027 -145.160426) (xy 89.416159 -145.196101) (xy 89.368553 -145.225155) (xy 89.317224 -145.246967)
			(xy 89.263267 -145.261073) (xy 89.20783 -145.267173) (xy 89.152096 -145.265136) (xy 89.097253 -145.255006)
			(xy 89.044469 -145.236999) (xy 88.994869 -145.211498) (xy 88.949511 -145.179047) (xy 88.909362 -145.140338)
			(xy 88.875276 -145.096195) (xy 88.84798 -145.04756) (xy 88.828057 -144.995469) (xy 88.815931 -144.941032)
			(xy 88.81186 -144.88541) (xy 57.910847 -144.88541) (xy 57.912957 -144.889911) (xy 57.929025 -144.943318)
			(xy 57.937145 -144.998494) (xy 57.937654 -145.02638) (xy 57.937145 -145.054266) (xy 57.929025 -145.109442)
			(xy 57.912957 -145.162849) (xy 57.889285 -145.213346) (xy 57.858512 -145.259859) (xy 57.821295 -145.301396)
			(xy 57.778427 -145.337071) (xy 57.730821 -145.366125) (xy 57.679492 -145.387937) (xy 57.625535 -145.402043)
			(xy 57.570098 -145.408143) (xy 57.514364 -145.406106) (xy 57.459521 -145.395976) (xy 57.406737 -145.377969)
			(xy 57.357137 -145.352468) (xy 57.311779 -145.320017) (xy 57.27163 -145.281308) (xy 57.237544 -145.237165)
			(xy 57.210248 -145.18853) (xy 57.190325 -145.136439) (xy 57.178199 -145.082002) (xy 57.174128 -145.02638)
			(xy 53.581046 -145.02638) (xy 52.634134 -145.973292) (xy 69.238366 -145.973292) (xy 69.242437 -145.91767)
			(xy 69.254563 -145.863233) (xy 69.274486 -145.811142) (xy 69.301782 -145.762507) (xy 69.335868 -145.718364)
			(xy 69.376017 -145.679655) (xy 69.421375 -145.647204) (xy 69.470975 -145.621703) (xy 69.523759 -145.603696)
			(xy 69.578602 -145.593566) (xy 69.634336 -145.591529) (xy 69.689773 -145.597629) (xy 69.74373 -145.611735)
			(xy 69.795059 -145.633547) (xy 69.842665 -145.662601) (xy 69.885533 -145.698276) (xy 69.92275 -145.739813)
			(xy 69.953523 -145.786326) (xy 69.977195 -145.836823) (xy 69.993263 -145.89023) (xy 70.001383 -145.945406)
			(xy 70.001892 -145.973292) (xy 70.001383 -146.001178) (xy 69.993263 -146.056354) (xy 69.987686 -146.074892)
			(xy 73.130916 -146.074892) (xy 73.134987 -146.01927) (xy 73.147113 -145.964833) (xy 73.167036 -145.912742)
			(xy 73.194332 -145.864107) (xy 73.228418 -145.819964) (xy 73.268567 -145.781255) (xy 73.313925 -145.748804)
			(xy 73.363525 -145.723303) (xy 73.416309 -145.705296) (xy 73.471152 -145.695166) (xy 73.526886 -145.693129)
			(xy 73.582323 -145.699229) (xy 73.63628 -145.713335) (xy 73.687609 -145.735147) (xy 73.735215 -145.764201)
			(xy 73.778083 -145.799876) (xy 73.8153 -145.841413) (xy 73.846073 -145.887926) (xy 73.869745 -145.938423)
			(xy 73.873303 -145.95025) (xy 85.577678 -145.95025) (xy 85.577678 -145.89575) (xy 85.585434 -145.841804)
			(xy 85.600788 -145.789511) (xy 85.623428 -145.739935) (xy 85.652892 -145.694085) (xy 85.688581 -145.652895)
			(xy 85.729769 -145.617204) (xy 85.775617 -145.587737) (xy 85.825192 -145.565095) (xy 85.877484 -145.549738)
			(xy 85.93143 -145.541979) (xy 85.95868 -145.541492) (xy 85.984408 -145.541906) (xy 86.035397 -145.548825)
			(xy 86.084992 -145.56254) (xy 86.132291 -145.582801) (xy 86.176435 -145.609241) (xy 86.216621 -145.641379)
			(xy 86.252119 -145.67863) (xy 86.267544 -145.699226) (xy 86.275964 -145.710071) (xy 86.297411 -145.727195)
			(xy 86.322644 -145.737991) (xy 86.34984 -145.741678) (xy 86.377036 -145.737991) (xy 86.402269 -145.727195)
			(xy 86.423716 -145.710071) (xy 86.432136 -145.699226) (xy 86.44755 -145.678622) (xy 86.483053 -145.641377)
			(xy 86.523243 -145.609244) (xy 86.567389 -145.582808) (xy 86.614689 -145.562548) (xy 86.664283 -145.548834)
			(xy 86.715272 -145.541914) (xy 86.741 -145.541492) (xy 86.768251 -145.541978) (xy 86.822199 -145.549734)
			(xy 86.874494 -145.565089) (xy 86.924071 -145.587731) (xy 86.969921 -145.617197) (xy 87.011112 -145.652888)
			(xy 87.046803 -145.694079) (xy 87.076269 -145.739929) (xy 87.098911 -145.789506) (xy 87.114266 -145.841801)
			(xy 87.122022 -145.895749) (xy 87.122022 -145.90141) (xy 90.84386 -145.90141) (xy 90.847931 -145.845788)
			(xy 90.860057 -145.791351) (xy 90.87998 -145.73926) (xy 90.907276 -145.690625) (xy 90.941362 -145.646482)
			(xy 90.981511 -145.607773) (xy 91.026869 -145.575322) (xy 91.076469 -145.549821) (xy 91.129253 -145.531814)
			(xy 91.184096 -145.521684) (xy 91.23983 -145.519647) (xy 91.295267 -145.525747) (xy 91.349224 -145.539853)
			(xy 91.400553 -145.561665) (xy 91.448159 -145.590719) (xy 91.491027 -145.626394) (xy 91.528244 -145.667931)
			(xy 91.559017 -145.714444) (xy 91.582689 -145.764941) (xy 91.598757 -145.818348) (xy 91.606877 -145.873524)
			(xy 91.607386 -145.90141) (xy 91.606877 -145.929296) (xy 91.598757 -145.984472) (xy 91.582689 -146.037879)
			(xy 91.559017 -146.088376) (xy 91.528244 -146.134889) (xy 91.491027 -146.176426) (xy 91.448159 -146.212101)
			(xy 91.400553 -146.241155) (xy 91.349224 -146.262967) (xy 91.295267 -146.277073) (xy 91.23983 -146.283173)
			(xy 91.184096 -146.281136) (xy 91.129253 -146.271006) (xy 91.076469 -146.252999) (xy 91.026869 -146.227498)
			(xy 90.981511 -146.195047) (xy 90.941362 -146.156338) (xy 90.907276 -146.112195) (xy 90.87998 -146.06356)
			(xy 90.860057 -146.011469) (xy 90.847931 -145.957032) (xy 90.84386 -145.90141) (xy 87.122022 -145.90141)
			(xy 87.122022 -145.950251) (xy 87.114266 -146.004199) (xy 87.098911 -146.056494) (xy 87.076269 -146.106071)
			(xy 87.046803 -146.151921) (xy 87.011112 -146.193112) (xy 86.969921 -146.228803) (xy 86.924071 -146.258269)
			(xy 86.874494 -146.280911) (xy 86.822199 -146.296266) (xy 86.768251 -146.304022) (xy 86.741 -146.304508)
			(xy 86.715271 -146.304109) (xy 86.664282 -146.297187) (xy 86.614686 -146.28347) (xy 86.567387 -146.263206)
			(xy 86.523243 -146.236764) (xy 86.483058 -146.204624) (xy 86.44756 -146.167371) (xy 86.432136 -146.146774)
			(xy 86.423716 -146.135929) (xy 86.402269 -146.118805) (xy 86.377036 -146.108009) (xy 86.34984 -146.104322)
			(xy 86.322644 -146.108009) (xy 86.297411 -146.118805) (xy 86.275964 -146.135929) (xy 86.267544 -146.146774)
			(xy 86.252142 -146.167387) (xy 86.216637 -146.204632) (xy 86.176445 -146.236765) (xy 86.132297 -146.2632)
			(xy 86.084995 -146.283457) (xy 86.035399 -146.297169) (xy 85.984409 -146.304087) (xy 85.95868 -146.304508)
			(xy 85.93143 -146.304021) (xy 85.877484 -146.296262) (xy 85.825192 -146.280905) (xy 85.775617 -146.258263)
			(xy 85.729769 -146.228796) (xy 85.688581 -146.193105) (xy 85.652892 -146.151915) (xy 85.623428 -146.106065)
			(xy 85.600788 -146.056489) (xy 85.585434 -146.004196) (xy 85.577678 -145.95025) (xy 73.873303 -145.95025)
			(xy 73.885813 -145.99183) (xy 73.893933 -146.047006) (xy 73.894442 -146.074892) (xy 73.893933 -146.102778)
			(xy 73.885813 -146.157954) (xy 73.869745 -146.211361) (xy 73.846073 -146.261858) (xy 73.8153 -146.308371)
			(xy 73.778083 -146.349908) (xy 73.735215 -146.385583) (xy 73.687609 -146.414637) (xy 73.63628 -146.436449)
			(xy 73.582323 -146.450555) (xy 73.526886 -146.456655) (xy 73.471152 -146.454618) (xy 73.416309 -146.444488)
			(xy 73.363525 -146.426481) (xy 73.313925 -146.40098) (xy 73.268567 -146.368529) (xy 73.228418 -146.32982)
			(xy 73.194332 -146.285677) (xy 73.167036 -146.237042) (xy 73.147113 -146.184951) (xy 73.134987 -146.130514)
			(xy 73.130916 -146.074892) (xy 69.987686 -146.074892) (xy 69.977195 -146.109761) (xy 69.953523 -146.160258)
			(xy 69.92275 -146.206771) (xy 69.885533 -146.248308) (xy 69.842665 -146.283983) (xy 69.795059 -146.313037)
			(xy 69.74373 -146.334849) (xy 69.689773 -146.348955) (xy 69.634336 -146.355055) (xy 69.578602 -146.353018)
			(xy 69.523759 -146.342888) (xy 69.470975 -146.324881) (xy 69.421375 -146.29938) (xy 69.376017 -146.266929)
			(xy 69.335868 -146.22822) (xy 69.301782 -146.184077) (xy 69.274486 -146.135442) (xy 69.254563 -146.083351)
			(xy 69.242437 -146.028914) (xy 69.238366 -145.973292) (xy 52.634134 -145.973292) (xy 52.001674 -146.605752)
			(xy 74.369928 -146.605752) (xy 74.373999 -146.55013) (xy 74.386125 -146.495693) (xy 74.406048 -146.443602)
			(xy 74.433344 -146.394967) (xy 74.46743 -146.350824) (xy 74.507579 -146.312115) (xy 74.552937 -146.279664)
			(xy 74.602537 -146.254163) (xy 74.655321 -146.236156) (xy 74.710164 -146.226026) (xy 74.765898 -146.223989)
			(xy 74.821335 -146.230089) (xy 74.875292 -146.244195) (xy 74.926621 -146.266007) (xy 74.974227 -146.295061)
			(xy 75.017095 -146.330736) (xy 75.054312 -146.372273) (xy 75.085085 -146.418786) (xy 75.108757 -146.469283)
			(xy 75.124825 -146.52269) (xy 75.132945 -146.577866) (xy 75.133454 -146.605752) (xy 75.132945 -146.633638)
			(xy 75.124825 -146.688814) (xy 75.108757 -146.742221) (xy 75.085085 -146.792718) (xy 75.054312 -146.839231)
			(xy 75.017095 -146.880768) (xy 74.974227 -146.916443) (xy 74.937267 -146.939) (xy 86.612982 -146.939)
			(xy 86.617053 -146.883378) (xy 86.629179 -146.828941) (xy 86.649102 -146.77685) (xy 86.676398 -146.728215)
			(xy 86.710484 -146.684072) (xy 86.750633 -146.645363) (xy 86.795991 -146.612912) (xy 86.845591 -146.587411)
			(xy 86.898375 -146.569404) (xy 86.953218 -146.559274) (xy 87.008952 -146.557237) (xy 87.064389 -146.563337)
			(xy 87.118346 -146.577443) (xy 87.169675 -146.599255) (xy 87.217281 -146.628309) (xy 87.260149 -146.663984)
			(xy 87.297366 -146.705521) (xy 87.328139 -146.752034) (xy 87.351811 -146.802531) (xy 87.367879 -146.855938)
			(xy 87.375999 -146.911114) (xy 87.376508 -146.939) (xy 87.375999 -146.966886) (xy 87.367879 -147.022062)
			(xy 87.351811 -147.075469) (xy 87.328139 -147.125966) (xy 87.297366 -147.172479) (xy 87.260149 -147.214016)
			(xy 87.217281 -147.249691) (xy 87.169675 -147.278745) (xy 87.118346 -147.300557) (xy 87.064389 -147.314663)
			(xy 87.008952 -147.320763) (xy 86.953218 -147.318726) (xy 86.898375 -147.308596) (xy 86.845591 -147.290589)
			(xy 86.795991 -147.265088) (xy 86.750633 -147.232637) (xy 86.710484 -147.193928) (xy 86.676398 -147.149785)
			(xy 86.649102 -147.10115) (xy 86.629179 -147.049059) (xy 86.617053 -146.994622) (xy 86.612982 -146.939)
			(xy 74.937267 -146.939) (xy 74.926621 -146.945497) (xy 74.875292 -146.967309) (xy 74.821335 -146.981415)
			(xy 74.765898 -146.987515) (xy 74.710164 -146.985478) (xy 74.655321 -146.975348) (xy 74.602537 -146.957341)
			(xy 74.552937 -146.93184) (xy 74.507579 -146.899389) (xy 74.46743 -146.86068) (xy 74.433344 -146.816537)
			(xy 74.406048 -146.767902) (xy 74.386125 -146.715811) (xy 74.373999 -146.661374) (xy 74.369928 -146.605752)
			(xy 52.001674 -146.605752) (xy 51.18989 -147.417536) (xy 75.262992 -147.417536) (xy 75.267063 -147.361914)
			(xy 75.279189 -147.307477) (xy 75.299112 -147.255386) (xy 75.326408 -147.206751) (xy 75.360494 -147.162608)
			(xy 75.400643 -147.123899) (xy 75.446001 -147.091448) (xy 75.495601 -147.065947) (xy 75.548385 -147.04794)
			(xy 75.603228 -147.03781) (xy 75.658962 -147.035773) (xy 75.714399 -147.041873) (xy 75.768356 -147.055979)
			(xy 75.819685 -147.077791) (xy 75.867291 -147.106845) (xy 75.910159 -147.14252) (xy 75.947376 -147.184057)
			(xy 75.978149 -147.23057) (xy 76.001821 -147.281067) (xy 76.017889 -147.334474) (xy 76.026009 -147.38965)
			(xy 76.026518 -147.417536) (xy 76.026009 -147.445422) (xy 76.017889 -147.500598) (xy 76.001821 -147.554005)
			(xy 75.978149 -147.604502) (xy 75.947376 -147.651015) (xy 75.910159 -147.692552) (xy 75.867291 -147.728227)
			(xy 75.819685 -147.757281) (xy 75.768356 -147.779093) (xy 75.714399 -147.793199) (xy 75.658962 -147.799299)
			(xy 75.603228 -147.797262) (xy 75.548385 -147.787132) (xy 75.495601 -147.769125) (xy 75.446001 -147.743624)
			(xy 75.400643 -147.711173) (xy 75.360494 -147.672464) (xy 75.326408 -147.628321) (xy 75.299112 -147.579686)
			(xy 75.279189 -147.527595) (xy 75.267063 -147.473158) (xy 75.262992 -147.417536) (xy 51.18989 -147.417536)
			(xy 50.652426 -147.955) (xy 86.612982 -147.955) (xy 86.617053 -147.899378) (xy 86.629179 -147.844941)
			(xy 86.649102 -147.79285) (xy 86.676398 -147.744215) (xy 86.710484 -147.700072) (xy 86.750633 -147.661363)
			(xy 86.795991 -147.628912) (xy 86.845591 -147.603411) (xy 86.898375 -147.585404) (xy 86.953218 -147.575274)
			(xy 87.008952 -147.573237) (xy 87.064389 -147.579337) (xy 87.118346 -147.593443) (xy 87.169675 -147.615255)
			(xy 87.217281 -147.644309) (xy 87.260149 -147.679984) (xy 87.297366 -147.721521) (xy 87.328139 -147.768034)
			(xy 87.351811 -147.818531) (xy 87.367879 -147.871938) (xy 87.375999 -147.927114) (xy 87.376508 -147.955)
			(xy 87.375999 -147.982886) (xy 87.367879 -148.038062) (xy 87.351811 -148.091469) (xy 87.328139 -148.141966)
			(xy 87.297366 -148.188479) (xy 87.260149 -148.230016) (xy 87.217281 -148.265691) (xy 87.169675 -148.294745)
			(xy 87.118346 -148.316557) (xy 87.064389 -148.330663) (xy 87.008952 -148.336763) (xy 86.953218 -148.334726)
			(xy 86.898375 -148.324596) (xy 86.845591 -148.306589) (xy 86.795991 -148.281088) (xy 86.750633 -148.248637)
			(xy 86.710484 -148.209928) (xy 86.676398 -148.165785) (xy 86.649102 -148.11715) (xy 86.629179 -148.065059)
			(xy 86.617053 -148.010622) (xy 86.612982 -147.955) (xy 50.652426 -147.955) (xy 50.230786 -148.37664)
			(xy 76.359002 -148.37664) (xy 76.363073 -148.321018) (xy 76.375199 -148.266581) (xy 76.395122 -148.21449)
			(xy 76.422418 -148.165855) (xy 76.456504 -148.121712) (xy 76.496653 -148.083003) (xy 76.542011 -148.050552)
			(xy 76.591611 -148.025051) (xy 76.644395 -148.007044) (xy 76.699238 -147.996914) (xy 76.754972 -147.994877)
			(xy 76.810409 -148.000977) (xy 76.864366 -148.015083) (xy 76.915695 -148.036895) (xy 76.963301 -148.065949)
			(xy 77.006169 -148.101624) (xy 77.043386 -148.143161) (xy 77.074159 -148.189674) (xy 77.097831 -148.240171)
			(xy 77.113899 -148.293578) (xy 77.122019 -148.348754) (xy 77.122528 -148.37664) (xy 77.122019 -148.404526)
			(xy 77.113899 -148.459702) (xy 77.112448 -148.464524) (xy 97.942144 -148.464524) (xy 97.946215 -148.408902)
			(xy 97.958341 -148.354465) (xy 97.978264 -148.302374) (xy 98.00556 -148.253739) (xy 98.039646 -148.209596)
			(xy 98.079795 -148.170887) (xy 98.125153 -148.138436) (xy 98.174753 -148.112935) (xy 98.227537 -148.094928)
			(xy 98.28238 -148.084798) (xy 98.338114 -148.082761) (xy 98.393551 -148.088861) (xy 98.447508 -148.102967)
			(xy 98.498837 -148.124779) (xy 98.546443 -148.153833) (xy 98.589311 -148.189508) (xy 98.626528 -148.231045)
			(xy 98.657301 -148.277558) (xy 98.680973 -148.328055) (xy 98.697041 -148.381462) (xy 98.705161 -148.436638)
			(xy 98.70567 -148.464524) (xy 98.705161 -148.49241) (xy 98.697041 -148.547586) (xy 98.680973 -148.600993)
			(xy 98.657301 -148.65149) (xy 98.626528 -148.698003) (xy 98.589311 -148.73954) (xy 98.546443 -148.775215)
			(xy 98.498837 -148.804269) (xy 98.447508 -148.826081) (xy 98.393551 -148.840187) (xy 98.338114 -148.846287)
			(xy 98.28238 -148.84425) (xy 98.227537 -148.83412) (xy 98.174753 -148.816113) (xy 98.125153 -148.790612)
			(xy 98.079795 -148.758161) (xy 98.039646 -148.719452) (xy 98.00556 -148.675309) (xy 97.978264 -148.626674)
			(xy 97.958341 -148.574583) (xy 97.946215 -148.520146) (xy 97.942144 -148.464524) (xy 77.112448 -148.464524)
			(xy 77.097831 -148.513109) (xy 77.074159 -148.563606) (xy 77.043386 -148.610119) (xy 77.006169 -148.651656)
			(xy 76.963301 -148.687331) (xy 76.915695 -148.716385) (xy 76.864366 -148.738197) (xy 76.810409 -148.752303)
			(xy 76.754972 -148.758403) (xy 76.699238 -148.756366) (xy 76.644395 -148.746236) (xy 76.591611 -148.728229)
			(xy 76.542011 -148.702728) (xy 76.496653 -148.670277) (xy 76.456504 -148.631568) (xy 76.422418 -148.587425)
			(xy 76.395122 -148.53879) (xy 76.375199 -148.486699) (xy 76.363073 -148.432262) (xy 76.359002 -148.37664)
			(xy 50.230786 -148.37664) (xy 49.820469 -148.786957) (xy 54.228627 -148.786957) (xy 54.228627 -148.732443)
			(xy 54.236386 -148.678484) (xy 54.251745 -148.626179) (xy 54.274393 -148.576592) (xy 54.303867 -148.530733)
			(xy 54.339569 -148.489536) (xy 54.38077 -148.45384) (xy 54.426632 -148.424371) (xy 54.476222 -148.401729)
			(xy 54.528529 -148.386376) (xy 54.582489 -148.378624) (xy 54.609746 -148.378164) (xy 54.638663 -148.378697)
			(xy 54.695834 -148.38742) (xy 54.751034 -148.404673) (xy 54.802996 -148.430062) (xy 54.85053 -148.463004)
			(xy 54.892546 -148.502745) (xy 54.910736 -148.52523) (xy 54.918281 -148.534009) (xy 54.939053 -148.544182)
			(xy 54.950614 -148.544788) (xy 55.030878 -148.544788) (xy 55.042445 -148.544209) (xy 55.063216 -148.534021)
			(xy 55.070756 -148.52523) (xy 55.087509 -148.504447) (xy 55.125863 -148.467317) (xy 55.169017 -148.435895)
			(xy 55.216131 -148.410796) (xy 55.266283 -148.39251) (xy 55.318494 -148.381393) (xy 55.371746 -148.377663)
			(xy 55.424998 -148.381393) (xy 55.477209 -148.39251) (xy 55.527361 -148.410796) (xy 55.574475 -148.435895)
			(xy 55.617629 -148.467317) (xy 55.655983 -148.504447) (xy 55.672736 -148.52523) (xy 55.680281 -148.534009)
			(xy 55.701053 -148.544182) (xy 55.712614 -148.544788) (xy 55.792878 -148.544788) (xy 55.804445 -148.544209)
			(xy 55.825216 -148.534021) (xy 55.832756 -148.52523) (xy 55.849509 -148.504447) (xy 55.887863 -148.467317)
			(xy 55.931017 -148.435895) (xy 55.978131 -148.410796) (xy 56.028283 -148.39251) (xy 56.080494 -148.381393)
			(xy 56.133746 -148.377663) (xy 56.186998 -148.381393) (xy 56.239209 -148.39251) (xy 56.289361 -148.410796)
			(xy 56.336475 -148.435895) (xy 56.379629 -148.467317) (xy 56.417983 -148.504447) (xy 56.434736 -148.52523)
			(xy 56.442281 -148.534009) (xy 56.463053 -148.544182) (xy 56.474614 -148.544788) (xy 56.554878 -148.544788)
			(xy 56.566445 -148.544209) (xy 56.587216 -148.534021) (xy 56.594756 -148.52523) (xy 56.612979 -148.502774)
			(xy 56.654992 -148.463036) (xy 56.702519 -148.430092) (xy 56.754475 -148.404699) (xy 56.809667 -148.387437)
			(xy 56.866832 -148.378702) (xy 56.895746 -148.378164) (xy 56.922993 -148.378709) (xy 56.976932 -148.386471)
			(xy 57.029217 -148.401829) (xy 57.078785 -148.424471) (xy 57.124626 -148.453936) (xy 57.165808 -148.489625)
			(xy 57.201492 -148.530811) (xy 57.230951 -148.576656) (xy 57.253588 -148.626226) (xy 57.268939 -148.678513)
			(xy 57.276694 -148.732453) (xy 57.276694 -148.786947) (xy 57.268939 -148.840887) (xy 57.253588 -148.893174)
			(xy 57.230951 -148.942744) (xy 57.226668 -148.94941) (xy 88.81186 -148.94941) (xy 88.815931 -148.893788)
			(xy 88.828057 -148.839351) (xy 88.84798 -148.78726) (xy 88.875276 -148.738625) (xy 88.909362 -148.694482)
			(xy 88.949511 -148.655773) (xy 88.994869 -148.623322) (xy 89.044469 -148.597821) (xy 89.097253 -148.579814)
			(xy 89.152096 -148.569684) (xy 89.20783 -148.567647) (xy 89.263267 -148.573747) (xy 89.317224 -148.587853)
			(xy 89.368553 -148.609665) (xy 89.416159 -148.638719) (xy 89.459027 -148.674394) (xy 89.496244 -148.715931)
			(xy 89.527017 -148.762444) (xy 89.550689 -148.812941) (xy 89.56309 -148.85416) (xy 96.058988 -148.85416)
			(xy 96.063059 -148.798538) (xy 96.075185 -148.744101) (xy 96.095108 -148.69201) (xy 96.122404 -148.643375)
			(xy 96.15649 -148.599232) (xy 96.196639 -148.560523) (xy 96.241997 -148.528072) (xy 96.291597 -148.502571)
			(xy 96.344381 -148.484564) (xy 96.399224 -148.474434) (xy 96.454958 -148.472397) (xy 96.510395 -148.478497)
			(xy 96.564352 -148.492603) (xy 96.615681 -148.514415) (xy 96.663287 -148.543469) (xy 96.706155 -148.579144)
			(xy 96.743372 -148.620681) (xy 96.774145 -148.667194) (xy 96.797817 -148.717691) (xy 96.813885 -148.771098)
			(xy 96.822005 -148.826274) (xy 96.822514 -148.85416) (xy 96.822005 -148.882046) (xy 96.813885 -148.937222)
			(xy 96.797817 -148.990629) (xy 96.774145 -149.041126) (xy 96.743372 -149.087639) (xy 96.706155 -149.129176)
			(xy 96.663287 -149.164851) (xy 96.615681 -149.193905) (xy 96.564352 -149.215717) (xy 96.510395 -149.229823)
			(xy 96.454958 -149.235923) (xy 96.399224 -149.233886) (xy 96.344381 -149.223756) (xy 96.291597 -149.205749)
			(xy 96.241997 -149.180248) (xy 96.196639 -149.147797) (xy 96.15649 -149.109088) (xy 96.122404 -149.064945)
			(xy 96.095108 -149.01631) (xy 96.075185 -148.964219) (xy 96.063059 -148.909782) (xy 96.058988 -148.85416)
			(xy 89.56309 -148.85416) (xy 89.566757 -148.866348) (xy 89.574877 -148.921524) (xy 89.575386 -148.94941)
			(xy 89.574877 -148.977296) (xy 89.566757 -149.032472) (xy 89.550689 -149.085879) (xy 89.527017 -149.136376)
			(xy 89.496244 -149.182889) (xy 89.459027 -149.224426) (xy 89.416159 -149.260101) (xy 89.368553 -149.289155)
			(xy 89.317224 -149.310967) (xy 89.263267 -149.325073) (xy 89.20783 -149.331173) (xy 89.152096 -149.329136)
			(xy 89.097253 -149.319006) (xy 89.044469 -149.300999) (xy 88.994869 -149.275498) (xy 88.949511 -149.243047)
			(xy 88.909362 -149.204338) (xy 88.875276 -149.160195) (xy 88.84798 -149.11156) (xy 88.828057 -149.059469)
			(xy 88.815931 -149.005032) (xy 88.81186 -148.94941) (xy 57.226668 -148.94941) (xy 57.201492 -148.988589)
			(xy 57.165808 -149.029775) (xy 57.124626 -149.065464) (xy 57.078785 -149.094929) (xy 57.029217 -149.117571)
			(xy 56.976932 -149.132929) (xy 56.922993 -149.140691) (xy 56.895746 -149.14118) (xy 56.86683 -149.140636)
			(xy 56.80966 -149.131914) (xy 56.754461 -149.114661) (xy 56.702499 -149.089274) (xy 56.654964 -149.056335)
			(xy 56.612947 -149.016598) (xy 56.594756 -148.994114) (xy 56.587207 -148.985339) (xy 56.566439 -148.975162)
			(xy 56.554878 -148.974556) (xy 56.474614 -148.974556) (xy 56.463044 -148.975115) (xy 56.442272 -148.985316)
			(xy 56.434736 -148.994114) (xy 56.417983 -149.014897) (xy 56.379629 -149.052027) (xy 56.336475 -149.083449)
			(xy 56.289361 -149.108548) (xy 56.239209 -149.126834) (xy 56.186998 -149.137951) (xy 56.133746 -149.141681)
			(xy 56.080494 -149.137951) (xy 56.028283 -149.126834) (xy 55.978131 -149.108548) (xy 55.931017 -149.083449)
			(xy 55.887863 -149.052027) (xy 55.849509 -149.014897) (xy 55.832756 -148.994114) (xy 55.825207 -148.985339)
			(xy 55.804439 -148.975162) (xy 55.792878 -148.974556) (xy 55.712614 -148.974556) (xy 55.701044 -148.975115)
			(xy 55.680272 -148.985316) (xy 55.672736 -148.994114) (xy 55.655983 -149.014897) (xy 55.617629 -149.052027)
			(xy 55.574475 -149.083449) (xy 55.527361 -149.108548) (xy 55.477209 -149.126834) (xy 55.424998 -149.137951)
			(xy 55.371746 -149.141681) (xy 55.318494 -149.137951) (xy 55.266283 -149.126834) (xy 55.216131 -149.108548)
			(xy 55.169017 -149.083449) (xy 55.125863 -149.052027) (xy 55.087509 -149.014897) (xy 55.070756 -148.994114)
			(xy 55.063207 -148.985339) (xy 55.042439 -148.975162) (xy 55.030878 -148.974556) (xy 54.950614 -148.974556)
			(xy 54.939044 -148.975115) (xy 54.918272 -148.985316) (xy 54.910736 -148.994114) (xy 54.892528 -149.016583)
			(xy 54.850512 -149.056319) (xy 54.80298 -149.089259) (xy 54.751022 -149.11465) (xy 54.695828 -149.131909)
			(xy 54.638661 -149.140643) (xy 54.609746 -149.14118) (xy 54.582489 -149.140776) (xy 54.528529 -149.133024)
			(xy 54.476222 -149.117671) (xy 54.426632 -149.095029) (xy 54.38077 -149.06556) (xy 54.339569 -149.029864)
			(xy 54.303867 -148.988667) (xy 54.274393 -148.942808) (xy 54.251745 -148.893221) (xy 54.236386 -148.840916)
			(xy 54.228627 -148.786957) (xy 49.820469 -148.786957) (xy 49.195228 -149.412198) (xy 69.012814 -149.412198)
			(xy 69.016885 -149.356576) (xy 69.029011 -149.302139) (xy 69.048934 -149.250048) (xy 69.07623 -149.201413)
			(xy 69.110316 -149.15727) (xy 69.150465 -149.118561) (xy 69.195823 -149.08611) (xy 69.245423 -149.060609)
			(xy 69.298207 -149.042602) (xy 69.35305 -149.032472) (xy 69.408784 -149.030435) (xy 69.464221 -149.036535)
			(xy 69.518178 -149.050641) (xy 69.569507 -149.072453) (xy 69.617113 -149.101507) (xy 69.659981 -149.137182)
			(xy 69.697198 -149.178719) (xy 69.727971 -149.225232) (xy 69.751643 -149.275729) (xy 69.767711 -149.329136)
			(xy 69.768758 -149.336252) (xy 93.292674 -149.336252) (xy 93.296745 -149.28063) (xy 93.308871 -149.226193)
			(xy 93.328794 -149.174102) (xy 93.35609 -149.125467) (xy 93.390176 -149.081324) (xy 93.430325 -149.042615)
			(xy 93.475683 -149.010164) (xy 93.525283 -148.984663) (xy 93.578067 -148.966656) (xy 93.63291 -148.956526)
			(xy 93.688644 -148.954489) (xy 93.744081 -148.960589) (xy 93.798038 -148.974695) (xy 93.849367 -148.996507)
			(xy 93.896973 -149.025561) (xy 93.939841 -149.061236) (xy 93.977058 -149.102773) (xy 94.007831 -149.149286)
			(xy 94.031503 -149.199783) (xy 94.047571 -149.25319) (xy 94.055691 -149.308366) (xy 94.0562 -149.336252)
			(xy 94.055691 -149.364138) (xy 94.047571 -149.419314) (xy 94.031503 -149.472721) (xy 94.007831 -149.523218)
			(xy 93.977058 -149.569731) (xy 93.939841 -149.611268) (xy 93.896973 -149.646943) (xy 93.849367 -149.675997)
			(xy 93.798038 -149.697809) (xy 93.744081 -149.711915) (xy 93.688644 -149.718015) (xy 93.63291 -149.715978)
			(xy 93.578067 -149.705848) (xy 93.525283 -149.687841) (xy 93.475683 -149.66234) (xy 93.430325 -149.629889)
			(xy 93.390176 -149.59118) (xy 93.35609 -149.547037) (xy 93.328794 -149.498402) (xy 93.308871 -149.446311)
			(xy 93.296745 -149.391874) (xy 93.292674 -149.336252) (xy 69.768758 -149.336252) (xy 69.775831 -149.384312)
			(xy 69.77634 -149.412198) (xy 69.775831 -149.440084) (xy 69.767711 -149.49526) (xy 69.751643 -149.548667)
			(xy 69.727971 -149.599164) (xy 69.697198 -149.645677) (xy 69.659981 -149.687214) (xy 69.617113 -149.722889)
			(xy 69.569507 -149.751943) (xy 69.518178 -149.773755) (xy 69.464221 -149.787861) (xy 69.408784 -149.793961)
			(xy 69.35305 -149.791924) (xy 69.298207 -149.781794) (xy 69.245423 -149.763787) (xy 69.195823 -149.738286)
			(xy 69.150465 -149.705835) (xy 69.110316 -149.667126) (xy 69.07623 -149.622983) (xy 69.048934 -149.574348)
			(xy 69.029011 -149.522257) (xy 69.016885 -149.46782) (xy 69.012814 -149.412198) (xy 49.195228 -149.412198)
			(xy 48.642016 -149.96541) (xy 88.81186 -149.96541) (xy 88.815931 -149.909788) (xy 88.828057 -149.855351)
			(xy 88.84798 -149.80326) (xy 88.875276 -149.754625) (xy 88.909362 -149.710482) (xy 88.949511 -149.671773)
			(xy 88.994869 -149.639322) (xy 89.044469 -149.613821) (xy 89.097253 -149.595814) (xy 89.152096 -149.585684)
			(xy 89.20783 -149.583647) (xy 89.263267 -149.589747) (xy 89.317224 -149.603853) (xy 89.368553 -149.625665)
			(xy 89.416159 -149.654719) (xy 89.459027 -149.690394) (xy 89.496244 -149.731931) (xy 89.527017 -149.778444)
			(xy 89.550689 -149.828941) (xy 89.566757 -149.882348) (xy 89.568178 -149.892004) (xy 95.52305 -149.892004)
			(xy 95.523536 -149.864753) (xy 95.531292 -149.810805) (xy 95.546647 -149.75851) (xy 95.569289 -149.708933)
			(xy 95.598755 -149.663083) (xy 95.634446 -149.621892) (xy 95.675637 -149.586201) (xy 95.721487 -149.556735)
			(xy 95.771064 -149.534093) (xy 95.823359 -149.518738) (xy 95.877307 -149.510982) (xy 95.931809 -149.510982)
			(xy 95.985757 -149.518738) (xy 96.038052 -149.534093) (xy 96.077594 -149.552152) (xy 98.937316 -149.552152)
			(xy 98.941387 -149.49653) (xy 98.953513 -149.442093) (xy 98.973436 -149.390002) (xy 99.000732 -149.341367)
			(xy 99.034818 -149.297224) (xy 99.074967 -149.258515) (xy 99.120325 -149.226064) (xy 99.169925 -149.200563)
			(xy 99.222709 -149.182556) (xy 99.277552 -149.172426) (xy 99.333286 -149.170389) (xy 99.388723 -149.176489)
			(xy 99.44268 -149.190595) (xy 99.494009 -149.212407) (xy 99.541615 -149.241461) (xy 99.584483 -149.277136)
			(xy 99.6217 -149.318673) (xy 99.652473 -149.365186) (xy 99.676145 -149.415683) (xy 99.692213 -149.46909)
			(xy 99.700333 -149.524266) (xy 99.700842 -149.552152) (xy 99.700333 -149.580038) (xy 99.692213 -149.635214)
			(xy 99.676145 -149.688621) (xy 99.652473 -149.739118) (xy 99.6217 -149.785631) (xy 99.584483 -149.827168)
			(xy 99.541615 -149.862843) (xy 99.494009 -149.891897) (xy 99.44268 -149.913709) (xy 99.388723 -149.927815)
			(xy 99.333286 -149.933915) (xy 99.277552 -149.931878) (xy 99.222709 -149.921748) (xy 99.169925 -149.903741)
			(xy 99.120325 -149.87824) (xy 99.074967 -149.845789) (xy 99.034818 -149.80708) (xy 99.000732 -149.762937)
			(xy 98.973436 -149.714302) (xy 98.953513 -149.662211) (xy 98.941387 -149.607774) (xy 98.937316 -149.552152)
			(xy 96.077594 -149.552152) (xy 96.087629 -149.556735) (xy 96.133479 -149.586201) (xy 96.17467 -149.621892)
			(xy 96.210361 -149.663083) (xy 96.239827 -149.708933) (xy 96.262469 -149.75851) (xy 96.277824 -149.810805)
			(xy 96.28558 -149.864753) (xy 96.286066 -149.892004) (xy 96.285543 -149.920929) (xy 96.276862 -149.978124)
			(xy 96.25964 -150.033351) (xy 96.234273 -150.085342) (xy 96.218248 -150.109428) (xy 96.210868 -150.120879)
			(xy 96.201847 -150.146571) (xy 96.199948 -150.173736) (xy 96.205307 -150.200434) (xy 96.217541 -150.224761)
			(xy 96.235777 -150.244983) (xy 96.258715 -150.259658) (xy 96.271588 -150.264114) (xy 96.297187 -150.272507)
			(xy 96.345882 -150.295554) (xy 96.390851 -150.325221) (xy 96.4312 -150.360919) (xy 96.466126 -150.401936)
			(xy 96.494936 -150.447459) (xy 96.517056 -150.496582) (xy 96.532047 -150.548327) (xy 96.53961 -150.601667)
			(xy 96.540066 -150.628604) (xy 96.53958 -150.655855) (xy 96.531824 -150.709803) (xy 96.516469 -150.762098)
			(xy 96.493827 -150.811675) (xy 96.464361 -150.857525) (xy 96.42867 -150.898716) (xy 96.387479 -150.934407)
			(xy 96.341629 -150.963873) (xy 96.292052 -150.986515) (xy 96.239757 -151.00187) (xy 96.185809 -151.009626)
			(xy 96.131307 -151.009626) (xy 96.077359 -151.00187) (xy 96.025064 -150.986515) (xy 95.975487 -150.963873)
			(xy 95.929637 -150.934407) (xy 95.888446 -150.898716) (xy 95.852755 -150.857525) (xy 95.823289 -150.811675)
			(xy 95.800647 -150.762098) (xy 95.785292 -150.709803) (xy 95.777536 -150.655855) (xy 95.77705 -150.628604)
			(xy 95.777543 -150.599678) (xy 95.786235 -150.542482) (xy 95.803466 -150.487256) (xy 95.828841 -150.435266)
			(xy 95.844868 -150.41118) (xy 95.85223 -150.399719) (xy 95.861249 -150.37403) (xy 95.863149 -150.346869)
			(xy 95.857793 -150.320174) (xy 95.845563 -150.295849) (xy 95.827331 -150.275627) (xy 95.804398 -150.260952)
			(xy 95.791528 -150.256494) (xy 95.765935 -150.248084) (xy 95.71724 -150.22504) (xy 95.672271 -150.195375)
			(xy 95.631922 -150.15968) (xy 95.596994 -150.118664) (xy 95.568184 -150.073144) (xy 95.546063 -150.024023)
			(xy 95.531071 -149.972279) (xy 95.523506 -149.91894) (xy 95.52305 -149.892004) (xy 89.568178 -149.892004)
			(xy 89.574877 -149.937524) (xy 89.575386 -149.96541) (xy 89.574877 -149.993296) (xy 89.566757 -150.048472)
			(xy 89.550689 -150.101879) (xy 89.527017 -150.152376) (xy 89.496244 -150.198889) (xy 89.459027 -150.240426)
			(xy 89.416159 -150.276101) (xy 89.368553 -150.305155) (xy 89.317224 -150.326967) (xy 89.263267 -150.341073)
			(xy 89.20783 -150.347173) (xy 89.152096 -150.345136) (xy 89.097253 -150.335006) (xy 89.044469 -150.316999)
			(xy 88.994869 -150.291498) (xy 88.949511 -150.259047) (xy 88.909362 -150.220338) (xy 88.875276 -150.176195)
			(xy 88.84798 -150.12756) (xy 88.828057 -150.075469) (xy 88.815931 -150.021032) (xy 88.81186 -149.96541)
			(xy 48.642016 -149.96541) (xy 47.810166 -150.79726) (xy 47.8028 -150.804372) (xy 47.79518 -150.823168)
			(xy 47.79518 -151.194051) (xy 52.515485 -151.194051) (xy 52.515485 -151.139549) (xy 52.523242 -151.0856)
			(xy 52.538598 -151.033305) (xy 52.56124 -150.983728) (xy 52.590707 -150.937878) (xy 52.626399 -150.896688)
			(xy 52.667591 -150.860997) (xy 52.713442 -150.831532) (xy 52.76302 -150.808892) (xy 52.815316 -150.793539)
			(xy 52.869265 -150.785784) (xy 52.896516 -150.785322) (xy 52.925431 -150.785893) (xy 52.9826 -150.79461)
			(xy 53.037798 -150.811857) (xy 53.08976 -150.837239) (xy 53.137296 -150.870173) (xy 53.179314 -150.909906)
			(xy 53.197506 -150.932388) (xy 53.205072 -150.941146) (xy 53.225827 -150.951332) (xy 53.237384 -150.951946)
			(xy 53.317648 -150.951946) (xy 53.329215 -150.951365) (xy 53.349987 -150.94118) (xy 53.357526 -150.932388)
			(xy 53.375699 -150.90989) (xy 53.417723 -150.870156) (xy 53.465262 -150.837219) (xy 53.517226 -150.811833)
			(xy 53.572427 -150.79458) (xy 53.629599 -150.785855) (xy 53.658516 -150.785322) (xy 53.685769 -150.785749)
			(xy 53.739719 -150.793508) (xy 53.792016 -150.808866) (xy 53.841595 -150.831509) (xy 53.887447 -150.860979)
			(xy 53.928638 -150.896673) (xy 53.964331 -150.937866) (xy 53.993798 -150.983719) (xy 54.01644 -151.033299)
			(xy 54.031795 -151.085597) (xy 54.039552 -151.139547) (xy 54.039552 -151.194053) (xy 54.031795 -151.248003)
			(xy 54.01644 -151.300301) (xy 53.993798 -151.349881) (xy 53.964331 -151.395734) (xy 53.928638 -151.436927)
			(xy 53.887447 -151.472621) (xy 53.841595 -151.502091) (xy 53.792016 -151.524734) (xy 53.739719 -151.540092)
			(xy 53.685769 -151.547851) (xy 53.658516 -151.548338) (xy 53.629598 -151.547832) (xy 53.572426 -151.539104)
			(xy 53.517225 -151.521845) (xy 53.465263 -151.496451) (xy 53.41773 -151.463504) (xy 53.375715 -151.423759)
			(xy 53.357526 -151.401272) (xy 53.349953 -151.392522) (xy 53.329203 -151.382333) (xy 53.317648 -151.381714)
			(xy 53.237384 -151.381714) (xy 53.225814 -151.38227) (xy 53.205043 -151.392474) (xy 53.197506 -151.401272)
			(xy 53.179305 -151.423747) (xy 53.137288 -151.463484) (xy 53.089755 -151.496425) (xy 53.037796 -151.521815)
			(xy 52.9826 -151.539073) (xy 52.925432 -151.547803) (xy 52.896516 -151.548338) (xy 52.869265 -151.547816)
			(xy 52.815316 -151.540061) (xy 52.76302 -151.524708) (xy 52.713442 -151.502068) (xy 52.667591 -151.472603)
			(xy 52.626399 -151.436912) (xy 52.590707 -151.395722) (xy 52.56124 -151.349872) (xy 52.538598 -151.300295)
			(xy 52.523242 -151.248) (xy 52.515485 -151.194051) (xy 47.79518 -151.194051) (xy 47.79518 -153.251451)
			(xy 52.515485 -153.251451) (xy 52.515485 -153.196949) (xy 52.523242 -153.143) (xy 52.538598 -153.090705)
			(xy 52.56124 -153.041128) (xy 52.590707 -152.995278) (xy 52.626399 -152.954088) (xy 52.667591 -152.918397)
			(xy 52.713442 -152.888932) (xy 52.76302 -152.866292) (xy 52.815316 -152.850939) (xy 52.869265 -152.843184)
			(xy 52.896516 -152.842722) (xy 52.925431 -152.843293) (xy 52.9826 -152.85201) (xy 53.037798 -152.869257)
			(xy 53.08976 -152.894639) (xy 53.137296 -152.927573) (xy 53.179314 -152.967306) (xy 53.197506 -152.989788)
			(xy 53.205072 -152.998546) (xy 53.225827 -153.008732) (xy 53.237384 -153.009346) (xy 53.317648 -153.009346)
			(xy 53.329215 -153.008765) (xy 53.349987 -152.99858) (xy 53.357526 -152.989788) (xy 53.375699 -152.96729)
			(xy 53.417723 -152.927556) (xy 53.465262 -152.894619) (xy 53.517226 -152.869233) (xy 53.572427 -152.85198)
			(xy 53.629599 -152.843255) (xy 53.658516 -152.842722) (xy 53.685769 -152.843149) (xy 53.739719 -152.850908)
			(xy 53.792016 -152.866266) (xy 53.841595 -152.888909) (xy 53.887447 -152.918379) (xy 53.928638 -152.954073)
			(xy 53.964331 -152.995266) (xy 53.993798 -153.041119) (xy 54.01644 -153.090699) (xy 54.031795 -153.142997)
			(xy 54.039552 -153.196947) (xy 54.039552 -153.251453) (xy 54.031795 -153.305403) (xy 54.01644 -153.357701)
			(xy 53.993798 -153.407281) (xy 53.964331 -153.453134) (xy 53.928638 -153.494327) (xy 53.887447 -153.530021)
			(xy 53.841595 -153.559491) (xy 53.792016 -153.582134) (xy 53.739719 -153.597492) (xy 53.685769 -153.605251)
			(xy 53.658516 -153.605738) (xy 53.629598 -153.605232) (xy 53.572426 -153.596504) (xy 53.517225 -153.579245)
			(xy 53.465263 -153.553851) (xy 53.41773 -153.520904) (xy 53.375715 -153.481159) (xy 53.357526 -153.458672)
			(xy 53.349953 -153.449922) (xy 53.329203 -153.439733) (xy 53.317648 -153.439114) (xy 53.237384 -153.439114)
			(xy 53.225814 -153.43967) (xy 53.205043 -153.449874) (xy 53.197506 -153.458672) (xy 53.179305 -153.481147)
			(xy 53.137288 -153.520884) (xy 53.089755 -153.553825) (xy 53.037796 -153.579215) (xy 52.9826 -153.596473)
			(xy 52.925432 -153.605203) (xy 52.896516 -153.605738) (xy 52.869265 -153.605216) (xy 52.815316 -153.597461)
			(xy 52.76302 -153.582108) (xy 52.713442 -153.559468) (xy 52.667591 -153.530003) (xy 52.626399 -153.494312)
			(xy 52.590707 -153.453122) (xy 52.56124 -153.407272) (xy 52.538598 -153.357695) (xy 52.523242 -153.3054)
			(xy 52.515485 -153.251451) (xy 47.79518 -153.251451) (xy 47.79518 -154.562302) (xy 47.795018 -154.567128)
			(xy 47.793102 -154.576591) (xy 47.79137 -154.581098) (xy 47.79137 -154.581352) (xy 47.78756 -154.591004)
			(xy 47.78756 -154.940254) (xy 52.452778 -154.940254) (xy 52.453308 -154.9115) (xy 52.461938 -154.854644)
			(xy 52.47901 -154.799729) (xy 52.504137 -154.748001) (xy 52.536749 -154.700635) (xy 52.576105 -154.658704)
			(xy 52.621313 -154.62316) (xy 52.646072 -154.60853) (xy 52.656994 -154.60218) (xy 52.670202 -154.58186)
			(xy 52.681124 -154.474672) (xy 52.672234 -154.452066) (xy 52.66309 -154.443684) (xy 52.643127 -154.425459)
			(xy 52.607955 -154.384415) (xy 52.578923 -154.338822) (xy 52.556612 -154.289589) (xy 52.541467 -154.237702)
			(xy 52.533791 -154.184198) (xy 52.533296 -154.157172) (xy 52.533752 -154.12992) (xy 52.541512 -154.075971)
			(xy 52.556871 -154.023675) (xy 52.579516 -153.974098) (xy 52.608985 -153.928247) (xy 52.64468 -153.887057)
			(xy 52.685873 -153.851366) (xy 52.731726 -153.8219) (xy 52.781305 -153.79926) (xy 52.833602 -153.783905)
			(xy 52.887552 -153.776149) (xy 52.914804 -153.775664) (xy 52.943722 -153.776155) (xy 53.000896 -153.784886)
			(xy 53.056096 -153.802148) (xy 53.108058 -153.827545) (xy 53.155591 -153.860494) (xy 53.197606 -153.900241)
			(xy 53.215794 -153.92273) (xy 53.223358 -153.93149) (xy 53.244115 -153.941673) (xy 53.255672 -153.942288)
			(xy 53.335936 -153.942288) (xy 53.3475 -153.941685) (xy 53.368271 -153.931514) (xy 53.375814 -153.92273)
			(xy 53.394005 -153.900246) (xy 53.436024 -153.86051) (xy 53.483558 -153.82757) (xy 53.53552 -153.802181)
			(xy 53.590718 -153.784925) (xy 53.647888 -153.776198) (xy 53.676804 -153.775664) (xy 53.704349 -153.776165)
			(xy 53.758868 -153.78407) (xy 53.811679 -153.799745) (xy 53.861683 -153.822863) (xy 53.907836 -153.852941)
			(xy 53.949177 -153.889352) (xy 53.96738 -153.91003) (xy 53.974746 -153.918666) (xy 53.994304 -153.92781)
			(xy 54.093872 -153.928572) (xy 54.113684 -153.919682) (xy 54.12105 -153.9113) (xy 54.139233 -153.89135)
			(xy 54.180275 -153.856289) (xy 54.225848 -153.827363) (xy 54.275044 -153.805147) (xy 54.326879 -153.790086)
			(xy 54.380319 -153.78248) (xy 54.407308 -153.782014) (xy 54.436223 -153.782593) (xy 54.493391 -153.791309)
			(xy 54.548589 -153.808555) (xy 54.600551 -153.833935) (xy 54.648087 -153.866868) (xy 54.690106 -153.906599)
			(xy 54.708298 -153.92908) (xy 54.715851 -153.93785) (xy 54.736617 -153.948026) (xy 54.748176 -153.948638)
			(xy 54.82844 -153.948638) (xy 54.840007 -153.948055) (xy 54.860779 -153.937871) (xy 54.868318 -153.92908)
			(xy 54.885071 -153.908297) (xy 54.923425 -153.871167) (xy 54.966579 -153.839745) (xy 55.013693 -153.814646)
			(xy 55.063845 -153.79636) (xy 55.116056 -153.785243) (xy 55.169308 -153.781513) (xy 55.22256 -153.785243)
			(xy 55.274771 -153.79636) (xy 55.324923 -153.814646) (xy 55.372037 -153.839745) (xy 55.415191 -153.871167)
			(xy 55.453545 -153.908297) (xy 55.470298 -153.92908) (xy 55.477851 -153.93785) (xy 55.498617 -153.948026)
			(xy 55.510176 -153.948638) (xy 55.59044 -153.948638) (xy 55.602007 -153.948055) (xy 55.622779 -153.937871)
			(xy 55.630318 -153.92908) (xy 55.647801 -153.90749) (xy 55.687963 -153.869107) (xy 55.710328 -153.852626)
			(xy 55.720742 -153.845006) (xy 55.731918 -153.822654) (xy 55.72887 -153.712418) (xy 55.716424 -153.690574)
			(xy 55.705248 -153.683716) (xy 55.682195 -153.668651) (xy 55.640264 -153.632952) (xy 55.6039 -153.591597)
			(xy 55.573857 -153.545444) (xy 55.550761 -153.495452) (xy 55.53509 -153.442659) (xy 55.527171 -153.388163)
			(xy 55.526686 -153.360628) (xy 55.527181 -153.333376) (xy 55.534934 -153.279427) (xy 55.550287 -153.22713)
			(xy 55.572925 -153.17755) (xy 55.60239 -153.131697) (xy 55.63808 -153.090504) (xy 55.67927 -153.05481)
			(xy 55.72512 -153.025342) (xy 55.774698 -153.002698) (xy 55.826993 -152.987342) (xy 55.880942 -152.979584)
			(xy 55.908194 -152.97912) (xy 55.937111 -152.979635) (xy 55.994283 -152.988364) (xy 56.049482 -153.005622)
			(xy 56.101444 -153.031014) (xy 56.148978 -153.063958) (xy 56.190994 -153.1037) (xy 56.209184 -153.126186)
			(xy 56.216759 -153.134934) (xy 56.237508 -153.145126) (xy 56.249062 -153.145744) (xy 56.329326 -153.145744)
			(xy 56.340891 -153.145151) (xy 56.361664 -153.134974) (xy 56.369204 -153.126186) (xy 56.387389 -153.103698)
			(xy 56.429411 -153.063963) (xy 56.476947 -153.031025) (xy 56.528909 -153.005638) (xy 56.584108 -152.988383)
			(xy 56.641278 -152.979655) (xy 56.670194 -152.97912) (xy 56.697448 -152.979561) (xy 56.751401 -152.987318)
			(xy 56.803701 -153.002675) (xy 56.853283 -153.025318) (xy 56.899138 -153.054788) (xy 56.940331 -153.090485)
			(xy 56.976025 -153.13168) (xy 57.005492 -153.177536) (xy 57.028133 -153.22712) (xy 57.043487 -153.27942)
			(xy 57.051241 -153.333374) (xy 57.051702 -153.360628) (xy 57.051259 -153.386603) (xy 57.044214 -153.438073)
			(xy 57.030243 -153.48811) (xy 57.009607 -153.535785) (xy 56.982687 -153.580217) (xy 56.949983 -153.62058)
			(xy 56.9121 -153.656129) (xy 56.891174 -153.671524) (xy 56.88076 -153.679144) (xy 56.869584 -153.701496)
			(xy 56.872632 -153.811732) (xy 56.885078 -153.833576) (xy 56.896254 -153.840434) (xy 56.919285 -153.855531)
			(xy 56.961216 -153.891225) (xy 56.997581 -153.932575) (xy 57.027626 -153.978722) (xy 57.050726 -154.028709)
			(xy 57.066402 -154.081496) (xy 57.074328 -154.135989) (xy 57.074816 -154.163522) (xy 57.074448 -154.189074)
			(xy 57.067633 -154.239722) (xy 57.054115 -154.289006) (xy 57.034136 -154.336044) (xy 57.008055 -154.379992)
			(xy 56.976337 -154.420063) (xy 56.95823 -154.438096) (xy 56.951182 -154.445548) (xy 56.943198 -154.464424)
			(xy 56.942736 -154.474672) (xy 56.942736 -154.547824) (xy 56.943192 -154.558073) (xy 56.951179 -154.576949)
			(xy 56.95823 -154.5844) (xy 56.964326 -154.590496) (xy 56.971438 -154.597862) (xy 56.990234 -154.605482)
			(xy 57.082436 -154.60599) (xy 57.100978 -154.598116) (xy 57.108344 -154.591004) (xy 57.129939 -154.570358)
			(xy 57.178341 -154.53534) (xy 57.231612 -154.508299) (xy 57.288448 -154.489897) (xy 57.347459 -154.480584)
			(xy 57.37733 -154.480006) (xy 57.406245 -154.480572) (xy 57.463414 -154.489291) (xy 57.518612 -154.506539)
			(xy 57.570574 -154.531922) (xy 57.618109 -154.564857) (xy 57.660128 -154.60459) (xy 57.67832 -154.627072)
			(xy 57.685865 -154.63585) (xy 57.706637 -154.646022) (xy 57.718198 -154.64663) (xy 57.798462 -154.64663)
			(xy 57.810031 -154.646062) (xy 57.830804 -154.635868) (xy 57.83834 -154.627072) (xy 57.856501 -154.604564)
			(xy 57.898528 -154.564831) (xy 57.946069 -154.531896) (xy 57.998036 -154.506512) (xy 58.053239 -154.489261)
			(xy 58.110412 -154.480538) (xy 58.13933 -154.480006) (xy 58.166581 -154.480466) (xy 58.220527 -154.488226)
			(xy 58.27282 -154.503584) (xy 58.322396 -154.526228) (xy 58.325172 -154.528012) (xy 67.588636 -154.528012)
			(xy 67.592707 -154.47239) (xy 67.604833 -154.417953) (xy 67.624756 -154.365862) (xy 67.652052 -154.317227)
			(xy 67.686138 -154.273084) (xy 67.726287 -154.234375) (xy 67.771645 -154.201924) (xy 67.821245 -154.176423)
			(xy 67.874029 -154.158416) (xy 67.928872 -154.148286) (xy 67.984606 -154.146249) (xy 68.040043 -154.152349)
			(xy 68.094 -154.166455) (xy 68.145329 -154.188267) (xy 68.192935 -154.217321) (xy 68.235803 -154.252996)
			(xy 68.27302 -154.294533) (xy 68.303793 -154.341046) (xy 68.327465 -154.391543) (xy 68.343533 -154.44495)
			(xy 68.351653 -154.500126) (xy 68.352162 -154.528012) (xy 68.351653 -154.555898) (xy 68.343533 -154.611074)
			(xy 68.327465 -154.664481) (xy 68.303793 -154.714978) (xy 68.27302 -154.761491) (xy 68.235803 -154.803028)
			(xy 68.192935 -154.838703) (xy 68.145329 -154.867757) (xy 68.094 -154.889569) (xy 68.040043 -154.903675)
			(xy 67.984606 -154.909775) (xy 67.928872 -154.907738) (xy 67.874029 -154.897608) (xy 67.821245 -154.879601)
			(xy 67.771645 -154.8541) (xy 67.726287 -154.821649) (xy 67.686138 -154.78294) (xy 67.652052 -154.738797)
			(xy 67.624756 -154.690162) (xy 67.604833 -154.638071) (xy 67.592707 -154.583634) (xy 67.588636 -154.528012)
			(xy 58.325172 -154.528012) (xy 58.368244 -154.555696) (xy 58.409432 -154.591389) (xy 58.445122 -154.63258)
			(xy 58.474586 -154.678431) (xy 58.497226 -154.728008) (xy 58.51258 -154.780302) (xy 58.520336 -154.834249)
			(xy 58.520336 -154.888751) (xy 58.51258 -154.942698) (xy 58.497226 -154.994992) (xy 58.474586 -155.044569)
			(xy 58.445122 -155.09042) (xy 58.409432 -155.131611) (xy 58.368244 -155.167304) (xy 58.322396 -155.196772)
			(xy 58.27282 -155.219416) (xy 58.220527 -155.234774) (xy 58.166581 -155.242534) (xy 58.13933 -155.243022)
			(xy 58.110412 -155.242512) (xy 58.053239 -155.233785) (xy 57.998039 -155.216528) (xy 57.946077 -155.191135)
			(xy 57.898543 -155.158188) (xy 57.856528 -155.118444) (xy 57.83834 -155.095956) (xy 57.830764 -155.087209)
			(xy 57.810016 -155.077019) (xy 57.798462 -155.076398) (xy 57.718198 -155.076398) (xy 57.70663 -155.076968)
			(xy 57.685859 -155.087163) (xy 57.67832 -155.095956) (xy 57.660107 -155.118421) (xy 57.618093 -155.158159)
			(xy 57.570563 -155.191102) (xy 57.518606 -155.216494) (xy 57.463412 -155.233753) (xy 57.406245 -155.242486)
			(xy 57.37733 -155.243022) (xy 57.347171 -155.242439) (xy 57.287605 -155.232939) (xy 57.230276 -155.214187)
			(xy 57.17661 -155.18665) (xy 57.127945 -155.151014) (xy 57.106312 -155.129992) (xy 57.0992 -155.122626)
			(xy 57.080404 -155.115006) (xy 56.988202 -155.114498) (xy 56.96966 -155.122372) (xy 56.962294 -155.129484)
			(xy 56.940697 -155.150127) (xy 56.892294 -155.185142) (xy 56.839023 -155.212182) (xy 56.782188 -155.230585)
			(xy 56.723178 -155.239901) (xy 56.693308 -155.240482) (xy 56.664391 -155.239965) (xy 56.607219 -155.231236)
			(xy 56.55202 -155.213979) (xy 56.500059 -155.188587) (xy 56.452525 -155.155643) (xy 56.410508 -155.115902)
			(xy 56.392318 -155.093416) (xy 56.384759 -155.084652) (xy 56.363997 -155.074473) (xy 56.35244 -155.073858)
			(xy 56.272176 -155.073858) (xy 56.260611 -155.074452) (xy 56.239838 -155.084628) (xy 56.232298 -155.093416)
			(xy 56.215545 -155.114199) (xy 56.177191 -155.151329) (xy 56.134037 -155.182751) (xy 56.086923 -155.20785)
			(xy 56.036771 -155.226136) (xy 55.98456 -155.237253) (xy 55.931308 -155.240983) (xy 55.878056 -155.237253)
			(xy 55.825845 -155.226136) (xy 55.775693 -155.20785) (xy 55.728579 -155.182751) (xy 55.685425 -155.151329)
			(xy 55.647071 -155.114199) (xy 55.630318 -155.093416) (xy 55.622759 -155.084652) (xy 55.601997 -155.074473)
			(xy 55.59044 -155.073858) (xy 55.510176 -155.073858) (xy 55.498611 -155.074452) (xy 55.477838 -155.084628)
			(xy 55.470298 -155.093416) (xy 55.453545 -155.114199) (xy 55.415191 -155.151329) (xy 55.372037 -155.182751)
			(xy 55.324923 -155.20785) (xy 55.274771 -155.226136) (xy 55.22256 -155.237253) (xy 55.169308 -155.240983)
			(xy 55.116056 -155.237253) (xy 55.063845 -155.226136) (xy 55.013693 -155.20785) (xy 54.966579 -155.182751)
			(xy 54.923425 -155.151329) (xy 54.885071 -155.114199) (xy 54.868318 -155.093416) (xy 54.860759 -155.084652)
			(xy 54.839997 -155.074473) (xy 54.82844 -155.073858) (xy 54.748176 -155.073858) (xy 54.736611 -155.074452)
			(xy 54.715838 -155.084628) (xy 54.708298 -155.093416) (xy 54.690112 -155.115904) (xy 54.648091 -155.155638)
			(xy 54.600555 -155.188576) (xy 54.548593 -155.213963) (xy 54.493394 -155.231219) (xy 54.436224 -155.239947)
			(xy 54.407308 -155.240482) (xy 54.378559 -155.239983) (xy 54.321716 -155.231331) (xy 54.266813 -155.214251)
			(xy 54.215093 -155.18913) (xy 54.167725 -155.156535) (xy 54.125782 -155.117206) (xy 54.107588 -155.09494)
			(xy 54.09946 -155.084526) (xy 54.075584 -155.074366) (xy 53.964078 -155.085542) (xy 53.942742 -155.100274)
			(xy 53.9369 -155.111958) (xy 53.924612 -155.135249) (xy 53.894686 -155.178579) (xy 53.859083 -155.217378)
			(xy 53.818478 -155.250907) (xy 53.773646 -155.27853) (xy 53.725438 -155.29972) (xy 53.674774 -155.314074)
			(xy 53.622615 -155.321319) (xy 53.596286 -155.321762) (xy 53.567371 -155.321196) (xy 53.510201 -155.312479)
			(xy 53.455003 -155.295231) (xy 53.40304 -155.269849) (xy 53.355505 -155.236913) (xy 53.313487 -155.197178)
			(xy 53.295296 -155.174696) (xy 53.287732 -155.165936) (xy 53.266975 -155.155752) (xy 53.255418 -155.155138)
			(xy 53.175154 -155.155138) (xy 53.163588 -155.155726) (xy 53.142816 -155.165907) (xy 53.135276 -155.174696)
			(xy 53.117098 -155.19719) (xy 53.075075 -155.236925) (xy 53.027538 -155.269863) (xy 52.975574 -155.295249)
			(xy 52.920374 -155.312503) (xy 52.863203 -155.321229) (xy 52.834286 -155.321762) (xy 52.807031 -155.321358)
			(xy 52.753075 -155.313598) (xy 52.700773 -155.298238) (xy 52.65119 -155.27559) (xy 52.605335 -155.246117)
			(xy 52.564141 -155.210417) (xy 52.528447 -155.169217) (xy 52.498981 -155.123357) (xy 52.476341 -155.07377)
			(xy 52.460989 -155.021466) (xy 52.453238 -154.967509) (xy 52.452778 -154.940254) (xy 47.78756 -154.940254)
			(xy 47.78756 -158.113052) (xy 54.997068 -158.113052) (xy 54.997068 -158.058548) (xy 55.004824 -158.004599)
			(xy 55.02018 -157.952304) (xy 55.042821 -157.902725) (xy 55.072288 -157.856874) (xy 55.10798 -157.815683)
			(xy 55.149171 -157.77999) (xy 55.195022 -157.750523) (xy 55.2446 -157.727881) (xy 55.296896 -157.712525)
			(xy 55.350844 -157.704768) (xy 55.378096 -157.704282) (xy 55.407014 -157.704772) (xy 55.464188 -157.713503)
			(xy 55.519389 -157.730764) (xy 55.571351 -157.756161) (xy 55.618884 -157.789111) (xy 55.660898 -157.828859)
			(xy 55.679086 -157.851348) (xy 55.68665 -157.860107) (xy 55.707407 -157.87029) (xy 55.718964 -157.870906)
			(xy 55.799228 -157.870906) (xy 55.81079 -157.870292) (xy 55.831562 -157.860128) (xy 55.839106 -157.851348)
			(xy 55.855859 -157.830565) (xy 55.894213 -157.793435) (xy 55.937367 -157.762013) (xy 55.984481 -157.736914)
			(xy 56.034633 -157.718628) (xy 56.086844 -157.707511) (xy 56.140096 -157.703781) (xy 56.193348 -157.707511)
			(xy 56.245559 -157.718628) (xy 56.295711 -157.736914) (xy 56.342825 -157.762013) (xy 56.385979 -157.793435)
			(xy 56.424333 -157.830565) (xy 56.441086 -157.851348) (xy 56.44865 -157.860107) (xy 56.469407 -157.87029)
			(xy 56.480964 -157.870906) (xy 56.561228 -157.870906) (xy 56.57279 -157.870292) (xy 56.593562 -157.860128)
			(xy 56.601106 -157.851348) (xy 56.617859 -157.830565) (xy 56.656213 -157.793435) (xy 56.699367 -157.762013)
			(xy 56.746481 -157.736914) (xy 56.796633 -157.718628) (xy 56.848844 -157.707511) (xy 56.902096 -157.703781)
			(xy 56.955348 -157.707511) (xy 57.007559 -157.718628) (xy 57.057711 -157.736914) (xy 57.104825 -157.762013)
			(xy 57.147979 -157.793435) (xy 57.186333 -157.830565) (xy 57.203086 -157.851348) (xy 57.21065 -157.860107)
			(xy 57.231407 -157.87029) (xy 57.242964 -157.870906) (xy 57.323228 -157.870906) (xy 57.33479 -157.870292)
			(xy 57.355562 -157.860128) (xy 57.363106 -157.851348) (xy 57.38128 -157.828851) (xy 57.423305 -157.789119)
			(xy 57.470844 -157.756183) (xy 57.522808 -157.730797) (xy 57.578008 -157.713544) (xy 57.635179 -157.704816)
			(xy 57.664096 -157.704282) (xy 57.691348 -157.704765) (xy 57.745298 -157.712521) (xy 57.797595 -157.727877)
			(xy 57.847175 -157.750518) (xy 57.893027 -157.779985) (xy 57.934219 -157.815678) (xy 57.969912 -157.85687)
			(xy 57.99938 -157.902722) (xy 58.022022 -157.952301) (xy 58.037378 -158.004598) (xy 58.045135 -158.058548)
			(xy 58.045135 -158.113052) (xy 58.037378 -158.167002) (xy 58.022022 -158.219299) (xy 57.99938 -158.268878)
			(xy 57.969912 -158.31473) (xy 57.934219 -158.355922) (xy 57.893027 -158.391615) (xy 57.847175 -158.421082)
			(xy 57.797595 -158.443723) (xy 57.745298 -158.459079) (xy 57.691348 -158.466835) (xy 57.664096 -158.467298)
			(xy 57.635179 -158.466783) (xy 57.578008 -158.458053) (xy 57.522809 -158.440795) (xy 57.470847 -158.415403)
			(xy 57.423313 -158.382458) (xy 57.381296 -158.342717) (xy 57.363106 -158.320232) (xy 57.355549 -158.311466)
			(xy 57.334786 -158.301288) (xy 57.323228 -158.300674) (xy 57.242964 -158.300674) (xy 57.231397 -158.301255)
			(xy 57.210624 -158.31144) (xy 57.203086 -158.320232) (xy 57.186333 -158.341015) (xy 57.147979 -158.378145)
			(xy 57.104825 -158.409567) (xy 57.057711 -158.434666) (xy 57.007559 -158.452952) (xy 56.955348 -158.464069)
			(xy 56.902096 -158.467799) (xy 56.848844 -158.464069) (xy 56.796633 -158.452952) (xy 56.746481 -158.434666)
			(xy 56.699367 -158.409567) (xy 56.656213 -158.378145) (xy 56.617859 -158.341015) (xy 56.601106 -158.320232)
			(xy 56.593549 -158.311466) (xy 56.572786 -158.301288) (xy 56.561228 -158.300674) (xy 56.480964 -158.300674)
			(xy 56.469397 -158.301255) (xy 56.448624 -158.31144) (xy 56.441086 -158.320232) (xy 56.424333 -158.341015)
			(xy 56.385979 -158.378145) (xy 56.342825 -158.409567) (xy 56.295711 -158.434666) (xy 56.245559 -158.452952)
			(xy 56.193348 -158.464069) (xy 56.140096 -158.467799) (xy 56.086844 -158.464069) (xy 56.034633 -158.452952)
			(xy 55.984481 -158.434666) (xy 55.937367 -158.409567) (xy 55.894213 -158.378145) (xy 55.855859 -158.341015)
			(xy 55.839106 -158.320232) (xy 55.831549 -158.311466) (xy 55.810786 -158.301288) (xy 55.799228 -158.300674)
			(xy 55.718964 -158.300674) (xy 55.707397 -158.301255) (xy 55.686624 -158.31144) (xy 55.679086 -158.320232)
			(xy 55.660911 -158.342729) (xy 55.618887 -158.382462) (xy 55.571348 -158.415398) (xy 55.519384 -158.440784)
			(xy 55.464184 -158.458038) (xy 55.407013 -158.466764) (xy 55.378096 -158.467298) (xy 55.350844 -158.466832)
			(xy 55.296896 -158.459075) (xy 55.2446 -158.443719) (xy 55.195022 -158.421077) (xy 55.149171 -158.39161)
			(xy 55.10798 -158.355917) (xy 55.072288 -158.314726) (xy 55.042821 -158.268875) (xy 55.02018 -158.219296)
			(xy 55.004824 -158.167001) (xy 54.997068 -158.113052) (xy 47.78756 -158.113052) (xy 47.78756 -160.653052)
			(xy 54.997068 -160.653052) (xy 54.997068 -160.598548) (xy 55.004824 -160.544599) (xy 55.02018 -160.492304)
			(xy 55.042821 -160.442725) (xy 55.072288 -160.396874) (xy 55.10798 -160.355683) (xy 55.149171 -160.31999)
			(xy 55.195022 -160.290523) (xy 55.2446 -160.267881) (xy 55.296896 -160.252525) (xy 55.350844 -160.244768)
			(xy 55.378096 -160.244282) (xy 55.407014 -160.244772) (xy 55.464188 -160.253503) (xy 55.519389 -160.270764)
			(xy 55.571351 -160.296161) (xy 55.618884 -160.329111) (xy 55.660898 -160.368859) (xy 55.679086 -160.391348)
			(xy 55.68665 -160.400107) (xy 55.707407 -160.41029) (xy 55.718964 -160.410906) (xy 55.799228 -160.410906)
			(xy 55.81079 -160.410292) (xy 55.831562 -160.400128) (xy 55.839106 -160.391348) (xy 55.855859 -160.370565)
			(xy 55.894213 -160.333435) (xy 55.937367 -160.302013) (xy 55.984481 -160.276914) (xy 56.034633 -160.258628)
			(xy 56.086844 -160.247511) (xy 56.140096 -160.243781) (xy 56.193348 -160.247511) (xy 56.245559 -160.258628)
			(xy 56.295711 -160.276914) (xy 56.342825 -160.302013) (xy 56.385979 -160.333435) (xy 56.424333 -160.370565)
			(xy 56.441086 -160.391348) (xy 56.44865 -160.400107) (xy 56.469407 -160.41029) (xy 56.480964 -160.410906)
			(xy 56.561228 -160.410906) (xy 56.57279 -160.410292) (xy 56.593562 -160.400128) (xy 56.601106 -160.391348)
			(xy 56.617859 -160.370565) (xy 56.656213 -160.333435) (xy 56.699367 -160.302013) (xy 56.746481 -160.276914)
			(xy 56.796633 -160.258628) (xy 56.848844 -160.247511) (xy 56.902096 -160.243781) (xy 56.955348 -160.247511)
			(xy 57.007559 -160.258628) (xy 57.057711 -160.276914) (xy 57.104825 -160.302013) (xy 57.147979 -160.333435)
			(xy 57.186333 -160.370565) (xy 57.203086 -160.391348) (xy 57.21065 -160.400107) (xy 57.231407 -160.41029)
			(xy 57.242964 -160.410906) (xy 57.323228 -160.410906) (xy 57.33479 -160.410292) (xy 57.355562 -160.400128)
			(xy 57.363106 -160.391348) (xy 57.38128 -160.368851) (xy 57.423305 -160.329119) (xy 57.470844 -160.296183)
			(xy 57.522808 -160.270797) (xy 57.578008 -160.253544) (xy 57.635179 -160.244816) (xy 57.664096 -160.244282)
			(xy 57.691348 -160.244765) (xy 57.745298 -160.252521) (xy 57.797595 -160.267877) (xy 57.847175 -160.290518)
			(xy 57.893027 -160.319985) (xy 57.934219 -160.355678) (xy 57.969912 -160.39687) (xy 57.99938 -160.442722)
			(xy 58.022022 -160.492301) (xy 58.037378 -160.544598) (xy 58.045135 -160.598548) (xy 58.045135 -160.653052)
			(xy 58.037378 -160.707002) (xy 58.022022 -160.759299) (xy 57.99938 -160.808878) (xy 57.969912 -160.85473)
			(xy 57.934219 -160.895922) (xy 57.893027 -160.931615) (xy 57.847175 -160.961082) (xy 57.797595 -160.983723)
			(xy 57.745298 -160.999079) (xy 57.691348 -161.006835) (xy 57.664096 -161.007298) (xy 57.635179 -161.006783)
			(xy 57.578008 -160.998053) (xy 57.522809 -160.980795) (xy 57.470847 -160.955403) (xy 57.423313 -160.922458)
			(xy 57.381296 -160.882717) (xy 57.363106 -160.860232) (xy 57.355549 -160.851466) (xy 57.334786 -160.841288)
			(xy 57.323228 -160.840674) (xy 57.242964 -160.840674) (xy 57.231397 -160.841255) (xy 57.210624 -160.85144)
			(xy 57.203086 -160.860232) (xy 57.186333 -160.881015) (xy 57.147979 -160.918145) (xy 57.104825 -160.949567)
			(xy 57.057711 -160.974666) (xy 57.007559 -160.992952) (xy 56.955348 -161.004069) (xy 56.902096 -161.007799)
			(xy 56.848844 -161.004069) (xy 56.796633 -160.992952) (xy 56.746481 -160.974666) (xy 56.699367 -160.949567)
			(xy 56.656213 -160.918145) (xy 56.617859 -160.881015) (xy 56.601106 -160.860232) (xy 56.593549 -160.851466)
			(xy 56.572786 -160.841288) (xy 56.561228 -160.840674) (xy 56.480964 -160.840674) (xy 56.469397 -160.841255)
			(xy 56.448624 -160.85144) (xy 56.441086 -160.860232) (xy 56.424333 -160.881015) (xy 56.385979 -160.918145)
			(xy 56.342825 -160.949567) (xy 56.295711 -160.974666) (xy 56.245559 -160.992952) (xy 56.193348 -161.004069)
			(xy 56.140096 -161.007799) (xy 56.086844 -161.004069) (xy 56.034633 -160.992952) (xy 55.984481 -160.974666)
			(xy 55.937367 -160.949567) (xy 55.894213 -160.918145) (xy 55.855859 -160.881015) (xy 55.839106 -160.860232)
			(xy 55.831549 -160.851466) (xy 55.810786 -160.841288) (xy 55.799228 -160.840674) (xy 55.718964 -160.840674)
			(xy 55.707397 -160.841255) (xy 55.686624 -160.85144) (xy 55.679086 -160.860232) (xy 55.660911 -160.882729)
			(xy 55.618887 -160.922462) (xy 55.571348 -160.955398) (xy 55.519384 -160.980784) (xy 55.464184 -160.998038)
			(xy 55.407013 -161.006764) (xy 55.378096 -161.007298) (xy 55.350844 -161.006832) (xy 55.296896 -160.999075)
			(xy 55.2446 -160.983719) (xy 55.195022 -160.961077) (xy 55.149171 -160.93161) (xy 55.10798 -160.895917)
			(xy 55.072288 -160.854726) (xy 55.042821 -160.808875) (xy 55.02018 -160.759296) (xy 55.004824 -160.707001)
			(xy 54.997068 -160.653052) (xy 47.78756 -160.653052) (xy 47.78756 -181.374796) (xy 51.992528 -181.374796)
			(xy 51.996599 -181.319174) (xy 52.008725 -181.264737) (xy 52.028648 -181.212646) (xy 52.055944 -181.164011)
			(xy 52.09003 -181.119868) (xy 52.130179 -181.081159) (xy 52.175537 -181.048708) (xy 52.225137 -181.023207)
			(xy 52.277921 -181.0052) (xy 52.332764 -180.99507) (xy 52.388498 -180.993033) (xy 52.443935 -180.999133)
			(xy 52.497892 -181.013239) (xy 52.549221 -181.035051) (xy 52.596827 -181.064105) (xy 52.639695 -181.09978)
			(xy 52.676912 -181.141317) (xy 52.707685 -181.18783) (xy 52.731357 -181.238327) (xy 52.747425 -181.291734)
			(xy 52.755545 -181.34691) (xy 52.756054 -181.374796) (xy 53.008528 -181.374796) (xy 53.012599 -181.319174)
			(xy 53.024725 -181.264737) (xy 53.044648 -181.212646) (xy 53.071944 -181.164011) (xy 53.10603 -181.119868)
			(xy 53.146179 -181.081159) (xy 53.191537 -181.048708) (xy 53.241137 -181.023207) (xy 53.293921 -181.0052)
			(xy 53.348764 -180.99507) (xy 53.404498 -180.993033) (xy 53.459935 -180.999133) (xy 53.513892 -181.013239)
			(xy 53.565221 -181.035051) (xy 53.612827 -181.064105) (xy 53.655695 -181.09978) (xy 53.692912 -181.141317)
			(xy 53.723685 -181.18783) (xy 53.747357 -181.238327) (xy 53.763425 -181.291734) (xy 53.771545 -181.34691)
			(xy 53.772054 -181.374796) (xy 53.771545 -181.402682) (xy 53.763425 -181.457858) (xy 53.747357 -181.511265)
			(xy 53.723685 -181.561762) (xy 53.692912 -181.608275) (xy 53.655695 -181.649812) (xy 53.612827 -181.685487)
			(xy 53.565221 -181.714541) (xy 53.513892 -181.736353) (xy 53.459935 -181.750459) (xy 53.404498 -181.756559)
			(xy 53.348764 -181.754522) (xy 53.293921 -181.744392) (xy 53.241137 -181.726385) (xy 53.191537 -181.700884)
			(xy 53.146179 -181.668433) (xy 53.10603 -181.629724) (xy 53.071944 -181.585581) (xy 53.044648 -181.536946)
			(xy 53.024725 -181.484855) (xy 53.012599 -181.430418) (xy 53.008528 -181.374796) (xy 52.756054 -181.374796)
			(xy 52.755545 -181.402682) (xy 52.747425 -181.457858) (xy 52.731357 -181.511265) (xy 52.707685 -181.561762)
			(xy 52.676912 -181.608275) (xy 52.639695 -181.649812) (xy 52.596827 -181.685487) (xy 52.549221 -181.714541)
			(xy 52.497892 -181.736353) (xy 52.443935 -181.750459) (xy 52.388498 -181.756559) (xy 52.332764 -181.754522)
			(xy 52.277921 -181.744392) (xy 52.225137 -181.726385) (xy 52.175537 -181.700884) (xy 52.130179 -181.668433)
			(xy 52.09003 -181.629724) (xy 52.055944 -181.585581) (xy 52.028648 -181.536946) (xy 52.008725 -181.484855)
			(xy 51.996599 -181.430418) (xy 51.992528 -181.374796) (xy 47.78756 -181.374796) (xy 47.78756 -181.84241)
			(xy 56.55437 -181.84241) (xy 56.554869 -181.813492) (xy 56.563598 -181.756319) (xy 56.580858 -181.701118)
			(xy 56.606253 -181.649156) (xy 56.639202 -181.601623) (xy 56.678948 -181.559608) (xy 56.701436 -181.54142)
			(xy 56.71019 -181.533851) (xy 56.720376 -181.513097) (xy 56.720994 -181.501542) (xy 56.720994 -181.421278)
			(xy 56.720381 -181.409716) (xy 56.710217 -181.388944) (xy 56.701436 -181.3814) (xy 56.67896 -181.3632)
			(xy 56.639223 -181.321183) (xy 56.606282 -181.27365) (xy 56.580892 -181.221691) (xy 56.563634 -181.166494)
			(xy 56.554905 -181.109326) (xy 56.55437 -181.08041) (xy 56.554888 -181.05316) (xy 56.562642 -180.999215)
			(xy 56.577995 -180.946922) (xy 56.600633 -180.897346) (xy 56.630096 -180.851497) (xy 56.665784 -180.810307)
			(xy 56.706971 -180.774616) (xy 56.752818 -180.745149) (xy 56.802392 -180.722506) (xy 56.854683 -180.707149)
			(xy 56.908628 -180.69939) (xy 56.935878 -180.698902) (xy 56.963495 -180.699374) (xy 57.018148 -180.707362)
			(xy 57.071079 -180.723146) (xy 57.121181 -180.746395) (xy 57.167409 -180.776624) (xy 57.208796 -180.813202)
			(xy 57.244477 -180.855364) (xy 57.273708 -180.902229) (xy 57.295877 -180.952819) (xy 57.30367 -180.979318)
			(xy 57.308242 -180.996082) (xy 57.33542 -181.016656) (xy 58.222896 -181.016656) (xy 58.232967 -181.01624)
			(xy 58.251565 -181.008514) (xy 58.258964 -181.00167) (xy 59.591194 -179.66944) (xy 59.598008 -179.66202)
			(xy 59.605743 -179.643436) (xy 59.60618 -179.633372) (xy 59.60618 -171.317666) (xy 59.605778 -171.307594)
			(xy 59.598042 -171.288996) (xy 59.591194 -171.281598) (xy 58.410602 -170.101006) (xy 58.393377 -170.082898)
			(xy 58.365634 -170.041339) (xy 58.346527 -169.995168) (xy 58.336789 -169.946158) (xy 58.33618 -169.921174)
			(xy 58.33618 -163.961064) (xy 58.336779 -163.93608) (xy 58.346525 -163.887071) (xy 58.365636 -163.840901)
			(xy 58.393378 -163.799341) (xy 58.410602 -163.781232) (xy 64.272414 -157.91942) (xy 64.290513 -157.902168)
			(xy 64.332056 -157.874356) (xy 64.378227 -157.855182) (xy 64.42725 -157.845381) (xy 64.452246 -157.844744)
			(xy 77.157834 -157.844744) (xy 77.16788 -157.844381) (xy 77.186477 -157.836789) (xy 77.193902 -157.830012)
			(xy 84.121244 -150.90267) (xy 84.139368 -150.885464) (xy 84.180922 -150.857718) (xy 84.227088 -150.838607)
			(xy 84.276093 -150.828861) (xy 84.301076 -150.828248) (xy 92.310458 -150.828248) (xy 92.320527 -150.827814)
			(xy 92.339125 -150.820101) (xy 92.346526 -150.813262) (xy 92.361004 -150.798784) (xy 92.368624 -150.780242)
			(xy 92.368624 -150.769828) (xy 92.36904 -150.742551) (xy 92.376736 -150.688542) (xy 92.392047 -150.636181)
			(xy 92.414661 -150.586535) (xy 92.444116 -150.540617) (xy 92.479811 -150.499362) (xy 92.521019 -150.463613)
			(xy 92.566899 -150.434099) (xy 92.616516 -150.41142) (xy 92.668857 -150.396041) (xy 92.722855 -150.388275)
			(xy 92.750132 -150.387812) (xy 92.777396 -150.388238) (xy 92.831369 -150.396005) (xy 92.883686 -150.411378)
			(xy 92.933282 -150.434042) (xy 92.979146 -150.463536) (xy 93.020343 -150.499259) (xy 93.056036 -150.540484)
			(xy 93.085495 -150.586369) (xy 93.108122 -150.635982) (xy 93.123456 -150.688311) (xy 93.126253 -150.707852)
			(xy 94.48114 -150.707852) (xy 94.485211 -150.65223) (xy 94.497337 -150.597793) (xy 94.51726 -150.545702)
			(xy 94.544556 -150.497067) (xy 94.578642 -150.452924) (xy 94.618791 -150.414215) (xy 94.664149 -150.381764)
			(xy 94.713749 -150.356263) (xy 94.766533 -150.338256) (xy 94.821376 -150.328126) (xy 94.87711 -150.326089)
			(xy 94.932547 -150.332189) (xy 94.986504 -150.346295) (xy 95.037833 -150.368107) (xy 95.085439 -150.397161)
			(xy 95.128307 -150.432836) (xy 95.165524 -150.474373) (xy 95.196297 -150.520886) (xy 95.219969 -150.571383)
			(xy 95.236037 -150.62479) (xy 95.244157 -150.679966) (xy 95.244666 -150.707852) (xy 95.244157 -150.735738)
			(xy 95.236037 -150.790914) (xy 95.219969 -150.844321) (xy 95.196297 -150.894818) (xy 95.165524 -150.941331)
			(xy 95.128307 -150.982868) (xy 95.085439 -151.018543) (xy 95.037833 -151.047597) (xy 94.986504 -151.069409)
			(xy 94.932547 -151.083515) (xy 94.87711 -151.089615) (xy 94.821376 -151.087578) (xy 94.766533 -151.077448)
			(xy 94.713749 -151.059441) (xy 94.664149 -151.03394) (xy 94.618791 -151.001489) (xy 94.578642 -150.96278)
			(xy 94.544556 -150.918637) (xy 94.51726 -150.870002) (xy 94.497337 -150.817911) (xy 94.485211 -150.763474)
			(xy 94.48114 -150.707852) (xy 93.126253 -150.707852) (xy 93.131183 -150.742289) (xy 93.131146 -150.796818)
			(xy 93.123347 -150.850786) (xy 93.107944 -150.903094) (xy 93.085252 -150.952677) (xy 93.055731 -150.998524)
			(xy 93.019984 -151.039701) (xy 92.978738 -151.075369) (xy 92.932835 -151.104802) (xy 92.88321 -151.1274)
			(xy 92.830872 -151.142703) (xy 92.776889 -151.150398) (xy 92.749624 -151.150828) (xy 92.73921 -151.150828)
			(xy 92.720668 -151.158448) (xy 92.642182 -151.237188) (xy 92.635469 -151.244586) (xy 92.627834 -151.263023)
			(xy 92.627834 -151.282979) (xy 92.635471 -151.301416) (xy 92.642182 -151.308816) (xy 92.720668 -151.387556)
			(xy 92.73921 -151.395176) (xy 92.749624 -151.395176) (xy 92.776901 -151.395591) (xy 92.830906 -151.403293)
			(xy 92.883264 -151.418608) (xy 92.932908 -151.441224) (xy 92.978824 -151.47068) (xy 93.020076 -151.506375)
			(xy 93.055825 -151.547582) (xy 93.08534 -151.59346) (xy 93.104307 -151.634952) (xy 99.305616 -151.634952)
			(xy 99.309687 -151.57933) (xy 99.321813 -151.524893) (xy 99.341736 -151.472802) (xy 99.369032 -151.424167)
			(xy 99.403118 -151.380024) (xy 99.443267 -151.341315) (xy 99.488625 -151.308864) (xy 99.538225 -151.283363)
			(xy 99.591009 -151.265356) (xy 99.645852 -151.255226) (xy 99.701586 -151.253189) (xy 99.757023 -151.259289)
			(xy 99.81098 -151.273395) (xy 99.862309 -151.295207) (xy 99.909915 -151.324261) (xy 99.952783 -151.359936)
			(xy 99.99 -151.401473) (xy 100.020773 -151.447986) (xy 100.044445 -151.498483) (xy 100.060513 -151.55189)
			(xy 100.068633 -151.607066) (xy 100.069142 -151.634952) (xy 100.068633 -151.662838) (xy 100.060513 -151.718014)
			(xy 100.044445 -151.771421) (xy 100.020773 -151.821918) (xy 99.99 -151.868431) (xy 99.952783 -151.909968)
			(xy 99.909915 -151.945643) (xy 99.862309 -151.974697) (xy 99.81098 -151.996509) (xy 99.757023 -152.010615)
			(xy 99.701586 -152.016715) (xy 99.645852 -152.014678) (xy 99.591009 -152.004548) (xy 99.538225 -151.986541)
			(xy 99.488625 -151.96104) (xy 99.443267 -151.928589) (xy 99.403118 -151.88988) (xy 99.369032 -151.845737)
			(xy 99.341736 -151.797102) (xy 99.321813 -151.745011) (xy 99.309687 -151.690574) (xy 99.305616 -151.634952)
			(xy 93.104307 -151.634952) (xy 93.10802 -151.643074) (xy 93.123403 -151.695412) (xy 93.131174 -151.749408)
			(xy 93.13164 -151.776684) (xy 93.131113 -151.803947) (xy 93.123352 -151.857917) (xy 93.107986 -151.910233)
			(xy 93.085328 -151.959828) (xy 93.055839 -152.005692) (xy 93.020121 -152.046889) (xy 92.978901 -152.082582)
			(xy 92.933019 -152.112042) (xy 92.88341 -152.134669) (xy 92.831085 -152.150003) (xy 92.777109 -152.15773)
			(xy 92.722583 -152.157694) (xy 92.668618 -152.149895) (xy 92.616314 -152.134492) (xy 92.566735 -152.111798)
			(xy 92.520892 -152.082277) (xy 92.47972 -152.04653) (xy 92.444056 -152.005284) (xy 92.414629 -151.959381)
			(xy 92.392036 -151.909756) (xy 92.37674 -151.85742) (xy 92.369051 -151.803439) (xy 92.368624 -151.776176)
			(xy 92.368624 -151.765762) (xy 92.361004 -151.74722) (xy 92.346526 -151.732742) (xy 92.339106 -151.725927)
			(xy 92.320522 -151.718191) (xy 92.310458 -151.717756) (xy 84.585556 -151.717756) (xy 84.575482 -151.718144)
			(xy 84.556884 -151.725889) (xy 84.549488 -151.732742) (xy 82.387948 -153.894282) (xy 83.466178 -153.894282)
			(xy 83.466726 -153.865366) (xy 83.475445 -153.808195) (xy 83.492695 -153.752995) (xy 83.518081 -153.701033)
			(xy 83.551021 -153.653498) (xy 83.590759 -153.611482) (xy 83.613244 -153.593292) (xy 83.622012 -153.585737)
			(xy 83.63219 -153.564973) (xy 83.632802 -153.553414) (xy 83.632802 -153.47315) (xy 83.632202 -153.461586)
			(xy 83.622028 -153.440815) (xy 83.613244 -153.433272) (xy 83.590756 -153.415086) (xy 83.551019 -153.373066)
			(xy 83.51808 -153.325531) (xy 83.492691 -153.273568) (xy 83.475437 -153.218369) (xy 83.466711 -153.161199)
			(xy 83.466178 -153.132282) (xy 83.466661 -153.105031) (xy 83.47442 -153.051084) (xy 83.489776 -152.99879)
			(xy 83.512419 -152.949214) (xy 83.541885 -152.903364) (xy 83.577577 -152.862174) (xy 83.618767 -152.826483)
			(xy 83.664617 -152.797017) (xy 83.714194 -152.774375) (xy 83.766488 -152.759019) (xy 83.820435 -152.751261)
			(xy 83.847686 -152.750774) (xy 83.874961 -152.751244) (xy 83.928959 -152.758987) (xy 83.981303 -152.774346)
			(xy 84.030923 -152.797008) (xy 84.076808 -152.82651) (xy 84.11802 -152.86225) (xy 84.153718 -152.903497)
			(xy 84.183174 -152.949411) (xy 84.194904 -152.97404) (xy 84.201 -152.987248) (xy 84.224622 -153.00325)
			(xy 84.344256 -153.008076) (xy 84.369148 -152.994106) (xy 84.376006 -152.981406) (xy 84.388811 -152.959294)
			(xy 84.419408 -152.918369) (xy 84.455175 -152.881876) (xy 84.475066 -152.865836) (xy 84.483818 -152.858266)
			(xy 84.494004 -152.837513) (xy 84.494624 -152.825958) (xy 84.494624 -152.745694) (xy 84.494084 -152.734121)
			(xy 84.483871 -152.713349) (xy 84.475066 -152.705816) (xy 84.452583 -152.687625) (xy 84.412849 -152.645604)
			(xy 84.379911 -152.598069) (xy 84.354523 -152.546108) (xy 84.337266 -152.490911) (xy 84.328536 -152.433742)
			(xy 84.328 -152.404826) (xy 84.328486 -152.377575) (xy 84.336242 -152.323627) (xy 84.351597 -152.271332)
			(xy 84.374239 -152.221755) (xy 84.403705 -152.175905) (xy 84.439396 -152.134714) (xy 84.480587 -152.099023)
			(xy 84.526437 -152.069557) (xy 84.576014 -152.046915) (xy 84.628309 -152.03156) (xy 84.682257 -152.023804)
			(xy 84.736759 -152.023804) (xy 84.790707 -152.03156) (xy 84.843002 -152.046915) (xy 84.892579 -152.069557)
			(xy 84.938429 -152.099023) (xy 84.97962 -152.134714) (xy 85.015311 -152.175905) (xy 85.044777 -152.221755)
			(xy 85.067419 -152.271332) (xy 85.082774 -152.323627) (xy 85.09053 -152.377575) (xy 85.091016 -152.404826)
			(xy 85.090476 -152.433743) (xy 85.090276 -152.435052) (xy 93.412816 -152.435052) (xy 93.416887 -152.37943)
			(xy 93.429013 -152.324993) (xy 93.448936 -152.272902) (xy 93.476232 -152.224267) (xy 93.510318 -152.180124)
			(xy 93.550467 -152.141415) (xy 93.595825 -152.108964) (xy 93.645425 -152.083463) (xy 93.698209 -152.065456)
			(xy 93.753052 -152.055326) (xy 93.808786 -152.053289) (xy 93.864223 -152.059389) (xy 93.91818 -152.073495)
			(xy 93.969509 -152.095307) (xy 94.017115 -152.124361) (xy 94.059983 -152.160036) (xy 94.0972 -152.201573)
			(xy 94.127973 -152.248086) (xy 94.151645 -152.298583) (xy 94.167713 -152.35199) (xy 94.175833 -152.407166)
			(xy 94.176342 -152.435052) (xy 94.175833 -152.462938) (xy 94.167713 -152.518114) (xy 94.151645 -152.571521)
			(xy 94.127973 -152.622018) (xy 94.0972 -152.668531) (xy 94.059983 -152.710068) (xy 94.017115 -152.745743)
			(xy 93.969509 -152.774797) (xy 93.91818 -152.796609) (xy 93.864223 -152.810715) (xy 93.808786 -152.816815)
			(xy 93.753052 -152.814778) (xy 93.698209 -152.804648) (xy 93.645425 -152.786641) (xy 93.595825 -152.76114)
			(xy 93.550467 -152.728689) (xy 93.510318 -152.68998) (xy 93.476232 -152.645837) (xy 93.448936 -152.597202)
			(xy 93.429013 -152.545111) (xy 93.416887 -152.490674) (xy 93.412816 -152.435052) (xy 85.090276 -152.435052)
			(xy 85.081756 -152.490914) (xy 85.064505 -152.546114) (xy 85.039117 -152.598076) (xy 85.006176 -152.645611)
			(xy 84.966435 -152.687626) (xy 84.94395 -152.705816) (xy 84.935177 -152.713367) (xy 84.925001 -152.734134)
			(xy 84.924392 -152.745694) (xy 84.924392 -152.825958) (xy 84.924989 -152.837522) (xy 84.935165 -152.858293)
			(xy 84.94395 -152.865836) (xy 84.966461 -152.883994) (xy 85.006192 -152.926022) (xy 85.039127 -152.973564)
			(xy 85.06451 -153.025532) (xy 85.081761 -153.080735) (xy 85.090484 -153.137908) (xy 85.091016 -153.166826)
			(xy 85.090546 -153.194078) (xy 85.082787 -153.248025) (xy 85.067429 -153.30032) (xy 85.044785 -153.349897)
			(xy 85.015317 -153.395747) (xy 84.979624 -153.436936) (xy 84.938432 -153.472628) (xy 84.892581 -153.502094)
			(xy 84.843003 -153.524735) (xy 84.790708 -153.54009) (xy 84.73676 -153.547848) (xy 84.709508 -153.548334)
			(xy 84.682233 -153.547865) (xy 84.628235 -153.540121) (xy 84.575892 -153.524761) (xy 84.526271 -153.502099)
			(xy 84.480387 -153.472597) (xy 84.439175 -153.436857) (xy 84.403476 -153.39561) (xy 84.37402 -153.349696)
			(xy 84.36229 -153.325068) (xy 84.356194 -153.31186) (xy 84.332572 -153.295858) (xy 84.212938 -153.291032)
			(xy 84.188046 -153.305002) (xy 84.181188 -153.317702) (xy 84.168386 -153.339816) (xy 84.137788 -153.38074)
			(xy 84.102019 -153.417232) (xy 84.082128 -153.433272) (xy 84.073371 -153.440838) (xy 84.063188 -153.461594)
			(xy 84.06257 -153.47315) (xy 84.06257 -153.553414) (xy 84.063108 -153.564987) (xy 84.073323 -153.585759)
			(xy 84.082128 -153.593292) (xy 84.104613 -153.61148) (xy 84.144347 -153.653502) (xy 84.177285 -153.701037)
			(xy 84.202673 -153.752999) (xy 84.219929 -153.808197) (xy 84.228659 -153.865366) (xy 84.229194 -153.894282)
			(xy 84.228708 -153.921533) (xy 84.220952 -153.975481) (xy 84.205597 -154.027776) (xy 84.182955 -154.077353)
			(xy 84.153489 -154.123203) (xy 84.117798 -154.164394) (xy 84.076607 -154.200085) (xy 84.030757 -154.229551)
			(xy 83.98118 -154.252193) (xy 83.928885 -154.267548) (xy 83.874937 -154.275304) (xy 83.820435 -154.275304)
			(xy 83.766487 -154.267548) (xy 83.714192 -154.252193) (xy 83.664615 -154.229551) (xy 83.618765 -154.200085)
			(xy 83.577574 -154.164394) (xy 83.541883 -154.123203) (xy 83.512417 -154.077353) (xy 83.489775 -154.027776)
			(xy 83.47442 -153.975481) (xy 83.466664 -153.921533) (xy 83.466178 -153.894282) (xy 82.387948 -153.894282)
			(xy 80.453735 -155.828495) (xy 83.791294 -155.828495) (xy 83.795025 -155.775242) (xy 83.806143 -155.72303)
			(xy 83.824431 -155.672877) (xy 83.849532 -155.625763) (xy 83.880955 -155.582608) (xy 83.918088 -155.544255)
			(xy 83.938872 -155.527502) (xy 83.947641 -155.519947) (xy 83.957817 -155.499183) (xy 83.95843 -155.487624)
			(xy 83.95843 -155.40736) (xy 83.957849 -155.395793) (xy 83.947664 -155.37502) (xy 83.938872 -155.367482)
			(xy 83.916374 -155.349308) (xy 83.876641 -155.307284) (xy 83.843705 -155.259745) (xy 83.818319 -155.207781)
			(xy 83.801066 -155.152581) (xy 83.79234 -155.095409) (xy 83.791806 -155.066492) (xy 83.792248 -155.039238)
			(xy 83.800006 -154.985286) (xy 83.815364 -154.932987) (xy 83.838009 -154.883406) (xy 83.867479 -154.837552)
			(xy 83.903175 -154.796359) (xy 83.94437 -154.760666) (xy 83.990225 -154.731198) (xy 84.039807 -154.708556)
			(xy 84.092107 -154.693202) (xy 84.14606 -154.685446) (xy 84.173314 -154.684984) (xy 84.202588 -154.685536)
			(xy 84.260445 -154.694503) (xy 84.316252 -154.712208) (xy 84.368696 -154.738236) (xy 84.416546 -154.771974)
			(xy 84.437982 -154.791918) (xy 84.445348 -154.798776) (xy 84.463382 -154.806142) (xy 84.553806 -154.806142)
			(xy 84.57184 -154.798776) (xy 84.579206 -154.791918) (xy 84.600664 -154.772) (xy 84.648515 -154.738272)
			(xy 84.700954 -154.712245) (xy 84.756753 -154.694529) (xy 84.814603 -154.685541) (xy 84.843874 -154.684984)
			(xy 84.872792 -154.685489) (xy 84.929965 -154.694216) (xy 84.985166 -154.711475) (xy 85.037128 -154.736869)
			(xy 85.084661 -154.769816) (xy 85.126676 -154.809562) (xy 85.144864 -154.83205) (xy 85.152437 -154.8408)
			(xy 85.173188 -154.850988) (xy 85.184742 -154.851608) (xy 85.265006 -154.851608) (xy 85.276574 -154.851038)
			(xy 85.297344 -154.840843) (xy 85.304884 -154.83205) (xy 85.319664 -154.813652) (xy 85.353034 -154.780281)
			(xy 85.371432 -154.765502) (xy 85.380194 -154.75794) (xy 85.390376 -154.737181) (xy 85.39099 -154.725624)
			(xy 85.39099 -154.64536) (xy 85.390389 -154.633796) (xy 85.380216 -154.613025) (xy 85.371432 -154.605482)
			(xy 85.348947 -154.587293) (xy 85.30921 -154.545274) (xy 85.27627 -154.497739) (xy 85.250882 -154.445777)
			(xy 85.233627 -154.390579) (xy 85.2249 -154.333408) (xy 85.224366 -154.304492) (xy 85.22487 -154.277242)
			(xy 85.232627 -154.223296) (xy 85.247982 -154.171003) (xy 85.270622 -154.121428) (xy 85.300087 -154.075579)
			(xy 85.335776 -154.034389) (xy 85.376964 -153.998698) (xy 85.422812 -153.969231) (xy 85.472386 -153.946588)
			(xy 85.524678 -153.931231) (xy 85.578624 -153.923472) (xy 85.605874 -153.922984) (xy 85.634792 -153.923489)
			(xy 85.691965 -153.932216) (xy 85.747166 -153.949475) (xy 85.799128 -153.974869) (xy 85.846661 -154.007816)
			(xy 85.888676 -154.047562) (xy 85.906864 -154.07005) (xy 85.914437 -154.0788) (xy 85.935188 -154.088988)
			(xy 85.946742 -154.089608) (xy 86.027006 -154.089608) (xy 86.038574 -154.089038) (xy 86.059344 -154.078843)
			(xy 86.066884 -154.07005) (xy 86.081664 -154.051652) (xy 86.115034 -154.018281) (xy 86.133432 -154.003502)
			(xy 86.142194 -153.99594) (xy 86.152376 -153.975181) (xy 86.15299 -153.963624) (xy 86.15299 -153.88336)
			(xy 86.152389 -153.871796) (xy 86.142216 -153.851025) (xy 86.133432 -153.843482) (xy 86.110947 -153.825293)
			(xy 86.07121 -153.783274) (xy 86.03827 -153.735739) (xy 86.012882 -153.683777) (xy 85.995627 -153.628579)
			(xy 85.9869 -153.571408) (xy 85.986366 -153.542492) (xy 85.98687 -153.515242) (xy 85.994627 -153.461296)
			(xy 86.009982 -153.409003) (xy 86.032622 -153.359428) (xy 86.062087 -153.313579) (xy 86.097776 -153.272389)
			(xy 86.138964 -153.236698) (xy 86.184812 -153.207231) (xy 86.234386 -153.184588) (xy 86.286678 -153.169231)
			(xy 86.340624 -153.161472) (xy 86.367874 -153.160984) (xy 86.396792 -153.161489) (xy 86.453965 -153.170216)
			(xy 86.509166 -153.187475) (xy 86.561128 -153.212869) (xy 86.608661 -153.245816) (xy 86.650676 -153.285562)
			(xy 86.668864 -153.30805) (xy 86.676437 -153.3168) (xy 86.697188 -153.326988) (xy 86.708742 -153.327608)
			(xy 86.789006 -153.327608) (xy 86.800574 -153.327038) (xy 86.821344 -153.316843) (xy 86.828884 -153.30805)
			(xy 86.845637 -153.287267) (xy 86.883991 -153.250137) (xy 86.927145 -153.218715) (xy 86.974259 -153.193616)
			(xy 87.024411 -153.17533) (xy 87.076622 -153.164213) (xy 87.129874 -153.160483) (xy 87.183126 -153.164213)
			(xy 87.235337 -153.17533) (xy 87.285489 -153.193616) (xy 87.332603 -153.218715) (xy 87.375757 -153.250137)
			(xy 87.414111 -153.287267) (xy 87.430864 -153.30805) (xy 87.438437 -153.3168) (xy 87.459188 -153.326988)
			(xy 87.470742 -153.327608) (xy 87.551006 -153.327608) (xy 87.562574 -153.327038) (xy 87.583344 -153.316843)
			(xy 87.590884 -153.30805) (xy 87.607637 -153.287267) (xy 87.645991 -153.250137) (xy 87.689145 -153.218715)
			(xy 87.736259 -153.193616) (xy 87.786411 -153.17533) (xy 87.838622 -153.164213) (xy 87.891874 -153.160483)
			(xy 87.945126 -153.164213) (xy 87.997337 -153.17533) (xy 88.047489 -153.193616) (xy 88.094603 -153.218715)
			(xy 88.137757 -153.250137) (xy 88.176111 -153.287267) (xy 88.192864 -153.30805) (xy 88.200437 -153.3168)
			(xy 88.221188 -153.326988) (xy 88.232742 -153.327608) (xy 88.313006 -153.327608) (xy 88.324574 -153.327038)
			(xy 88.345344 -153.316843) (xy 88.352884 -153.30805) (xy 88.369637 -153.287267) (xy 88.407991 -153.250137)
			(xy 88.451145 -153.218715) (xy 88.498259 -153.193616) (xy 88.548411 -153.17533) (xy 88.600622 -153.164213)
			(xy 88.653874 -153.160483) (xy 88.707126 -153.164213) (xy 88.759337 -153.17533) (xy 88.809489 -153.193616)
			(xy 88.856603 -153.218715) (xy 88.899757 -153.250137) (xy 88.938111 -153.287267) (xy 88.954864 -153.30805)
			(xy 88.962437 -153.3168) (xy 88.983188 -153.326988) (xy 88.994742 -153.327608) (xy 89.075006 -153.327608)
			(xy 89.086574 -153.327038) (xy 89.107344 -153.316843) (xy 89.114884 -153.30805) (xy 89.131637 -153.287267)
			(xy 89.169991 -153.250137) (xy 89.213145 -153.218715) (xy 89.260259 -153.193616) (xy 89.310411 -153.17533)
			(xy 89.362622 -153.164213) (xy 89.415874 -153.160483) (xy 89.469126 -153.164213) (xy 89.521337 -153.17533)
			(xy 89.571489 -153.193616) (xy 89.618603 -153.218715) (xy 89.661757 -153.250137) (xy 89.700111 -153.287267)
			(xy 89.716864 -153.30805) (xy 89.724437 -153.3168) (xy 89.745188 -153.326988) (xy 89.756742 -153.327608)
			(xy 89.837006 -153.327608) (xy 89.848574 -153.327038) (xy 89.869344 -153.316843) (xy 89.876884 -153.30805)
			(xy 89.893637 -153.287267) (xy 89.931991 -153.250137) (xy 89.975145 -153.218715) (xy 90.022259 -153.193616)
			(xy 90.072411 -153.17533) (xy 90.124622 -153.164213) (xy 90.177874 -153.160483) (xy 90.231126 -153.164213)
			(xy 90.283337 -153.17533) (xy 90.333489 -153.193616) (xy 90.380603 -153.218715) (xy 90.423757 -153.250137)
			(xy 90.462111 -153.287267) (xy 90.478864 -153.30805) (xy 90.486437 -153.3168) (xy 90.507188 -153.326988)
			(xy 90.518742 -153.327608) (xy 90.599006 -153.327608) (xy 90.610574 -153.327038) (xy 90.631344 -153.316843)
			(xy 90.638884 -153.30805) (xy 90.657071 -153.285564) (xy 90.699093 -153.245831) (xy 90.74663 -153.212894)
			(xy 90.798591 -153.187506) (xy 90.853789 -153.17025) (xy 90.910958 -153.16152) (xy 90.939874 -153.160984)
			(xy 90.967126 -153.161479) (xy 91.021075 -153.169233) (xy 91.073372 -153.184585) (xy 91.122951 -153.207224)
			(xy 91.168804 -153.236688) (xy 91.209997 -153.272379) (xy 91.245691 -153.313568) (xy 91.27516 -153.359419)
			(xy 91.297803 -153.408996) (xy 91.31316 -153.461292) (xy 91.320918 -153.51524) (xy 91.321382 -153.542492)
			(xy 91.320865 -153.571409) (xy 91.312136 -153.628581) (xy 91.294879 -153.68378) (xy 91.269487 -153.735741)
			(xy 91.236543 -153.783275) (xy 91.196802 -153.825292) (xy 91.174316 -153.843482) (xy 91.165552 -153.851041)
			(xy 91.155373 -153.871803) (xy 91.154758 -153.88336) (xy 91.154758 -153.963624) (xy 91.155352 -153.975189)
			(xy 91.165528 -153.995962) (xy 91.174316 -154.003502) (xy 91.192712 -154.018284) (xy 91.226085 -154.051652)
			(xy 91.240864 -154.07005) (xy 91.248437 -154.0788) (xy 91.269188 -154.088988) (xy 91.280742 -154.089608)
			(xy 91.361006 -154.089608) (xy 91.372574 -154.089038) (xy 91.393344 -154.078843) (xy 91.400884 -154.07005)
			(xy 91.419071 -154.047564) (xy 91.461093 -154.007831) (xy 91.50863 -153.974894) (xy 91.560591 -153.949506)
			(xy 91.615789 -153.93225) (xy 91.672958 -153.92352) (xy 91.701874 -153.922984) (xy 91.729126 -153.923479)
			(xy 91.783075 -153.931233) (xy 91.835372 -153.946585) (xy 91.884951 -153.969224) (xy 91.930804 -153.998688)
			(xy 91.971997 -154.034379) (xy 92.007691 -154.075568) (xy 92.03716 -154.121419) (xy 92.059803 -154.170996)
			(xy 92.07516 -154.223292) (xy 92.082918 -154.27724) (xy 92.083382 -154.304492) (xy 92.082865 -154.333409)
			(xy 92.074136 -154.390581) (xy 92.056879 -154.44578) (xy 92.031487 -154.497741) (xy 91.998543 -154.545275)
			(xy 91.958802 -154.587292) (xy 91.936316 -154.605482) (xy 91.927552 -154.613041) (xy 91.917373 -154.633803)
			(xy 91.916758 -154.64536) (xy 91.916758 -154.725624) (xy 91.917352 -154.737189) (xy 91.927528 -154.757962)
			(xy 91.936316 -154.765502) (xy 91.957092 -154.782264) (xy 91.994224 -154.820615) (xy 92.025648 -154.863768)
			(xy 92.050749 -154.910881) (xy 92.069037 -154.961032) (xy 92.080155 -155.013244) (xy 92.083885 -155.066495)
			(xy 92.080156 -155.119747) (xy 92.06904 -155.171958) (xy 92.050753 -155.22211) (xy 92.025653 -155.269223)
			(xy 91.994231 -155.312377) (xy 91.957099 -155.350729) (xy 91.936316 -155.367482) (xy 91.927552 -155.375041)
			(xy 91.917373 -155.395803) (xy 91.916758 -155.40736) (xy 91.916758 -155.487624) (xy 91.917352 -155.499189)
			(xy 91.927528 -155.519962) (xy 91.936316 -155.527502) (xy 91.957092 -155.544264) (xy 91.994224 -155.582615)
			(xy 92.025648 -155.625768) (xy 92.050749 -155.672881) (xy 92.069037 -155.723032) (xy 92.080155 -155.775244)
			(xy 92.083885 -155.828495) (xy 92.080156 -155.881747) (xy 92.06904 -155.933958) (xy 92.050753 -155.98411)
			(xy 92.025653 -156.031223) (xy 91.994231 -156.074377) (xy 91.957099 -156.112729) (xy 91.936316 -156.129482)
			(xy 91.927552 -156.137041) (xy 91.917373 -156.157803) (xy 91.916758 -156.16936) (xy 91.916758 -156.249624)
			(xy 91.917352 -156.261189) (xy 91.927528 -156.281962) (xy 91.936316 -156.289502) (xy 91.958804 -156.307688)
			(xy 91.998538 -156.349709) (xy 92.031476 -156.397245) (xy 92.056863 -156.449207) (xy 92.074119 -156.504406)
			(xy 92.082847 -156.561576) (xy 92.083382 -156.590492) (xy 92.082917 -156.618067) (xy 92.074965 -156.67264)
			(xy 92.059241 -156.7255) (xy 92.03607 -156.775546) (xy 92.005937 -156.821736) (xy 91.969469 -156.863106)
			(xy 91.948762 -156.881322) (xy 91.940632 -156.888914) (xy 91.931286 -156.909074) (xy 91.930728 -156.920184)
			(xy 91.930728 -156.9974) (xy 91.931271 -157.008513) (xy 91.940626 -157.028672) (xy 91.948762 -157.036262)
			(xy 91.96945 -157.054498) (xy 92.005924 -157.095861) (xy 92.03606 -157.142045) (xy 92.05923 -157.192088)
			(xy 92.074951 -157.244947) (xy 92.082895 -157.299519) (xy 92.083382 -157.327092) (xy 92.082937 -157.354346)
			(xy 92.075181 -157.408299) (xy 92.059824 -157.460599) (xy 92.037181 -157.51018) (xy 92.007711 -157.556035)
			(xy 91.972015 -157.597228) (xy 91.93082 -157.632922) (xy 91.884965 -157.662389) (xy 91.835382 -157.685031)
			(xy 91.783081 -157.700384) (xy 91.729128 -157.708138) (xy 91.701874 -157.7086) (xy 91.672959 -157.708029)
			(xy 91.61579 -157.699311) (xy 91.560593 -157.682063) (xy 91.508631 -157.656682) (xy 91.461095 -157.623747)
			(xy 91.419076 -157.584015) (xy 91.400884 -157.561534) (xy 91.393336 -157.552758) (xy 91.372566 -157.542585)
			(xy 91.361006 -157.541976) (xy 91.280742 -157.541976) (xy 91.269173 -157.542544) (xy 91.248401 -157.552738)
			(xy 91.240864 -157.561534) (xy 91.224111 -157.582317) (xy 91.185757 -157.619447) (xy 91.142603 -157.650869)
			(xy 91.095489 -157.675968) (xy 91.045337 -157.694254) (xy 90.993126 -157.705371) (xy 90.939874 -157.709101)
			(xy 90.886622 -157.705371) (xy 90.834411 -157.694254) (xy 90.784259 -157.675968) (xy 90.737145 -157.650869)
			(xy 90.693991 -157.619447) (xy 90.655637 -157.582317) (xy 90.638884 -157.561534) (xy 90.631336 -157.552758)
			(xy 90.610566 -157.542585) (xy 90.599006 -157.541976) (xy 90.518742 -157.541976) (xy 90.507173 -157.542544)
			(xy 90.486401 -157.552738) (xy 90.478864 -157.561534) (xy 90.460702 -157.584042) (xy 90.418675 -157.623774)
			(xy 90.371134 -157.656709) (xy 90.319167 -157.682093) (xy 90.263965 -157.699344) (xy 90.206792 -157.708068)
			(xy 90.177874 -157.7086) (xy 90.15153 -157.708154) (xy 90.099341 -157.700917) (xy 90.048644 -157.686571)
			(xy 90.000402 -157.665389) (xy 89.955532 -157.637772) (xy 89.914886 -157.604247) (xy 89.879239 -157.565449)
			(xy 89.849266 -157.522118) (xy 89.837006 -157.498796) (xy 89.830656 -157.485588) (xy 89.806272 -157.470856)
			(xy 86.739476 -157.470856) (xy 86.715092 -157.485588) (xy 86.708742 -157.498796) (xy 86.696496 -157.522125)
			(xy 86.666517 -157.565453) (xy 86.630865 -157.604247) (xy 86.590217 -157.63777) (xy 86.545346 -157.665386)
			(xy 86.497103 -157.686569) (xy 86.446407 -157.700918) (xy 86.394218 -157.708159) (xy 86.367874 -157.7086)
			(xy 86.338959 -157.708029) (xy 86.28179 -157.699311) (xy 86.226593 -157.682063) (xy 86.174631 -157.656682)
			(xy 86.127095 -157.623747) (xy 86.085076 -157.584015) (xy 86.066884 -157.561534) (xy 86.059336 -157.552758)
			(xy 86.038566 -157.542585) (xy 86.027006 -157.541976) (xy 85.946742 -157.541976) (xy 85.935173 -157.542544)
			(xy 85.914401 -157.552738) (xy 85.906864 -157.561534) (xy 85.890111 -157.582317) (xy 85.851757 -157.619447)
			(xy 85.808603 -157.650869) (xy 85.761489 -157.675968) (xy 85.711337 -157.694254) (xy 85.659126 -157.705371)
			(xy 85.605874 -157.709101) (xy 85.552622 -157.705371) (xy 85.500411 -157.694254) (xy 85.450259 -157.675968)
			(xy 85.403145 -157.650869) (xy 85.359991 -157.619447) (xy 85.321637 -157.582317) (xy 85.304884 -157.561534)
			(xy 85.297336 -157.552758) (xy 85.276566 -157.542585) (xy 85.265006 -157.541976) (xy 85.184742 -157.541976)
			(xy 85.173173 -157.542544) (xy 85.152401 -157.552738) (xy 85.144864 -157.561534) (xy 85.126702 -157.584042)
			(xy 85.084675 -157.623774) (xy 85.037134 -157.656709) (xy 84.985167 -157.682093) (xy 84.929965 -157.699344)
			(xy 84.872792 -157.708068) (xy 84.843874 -157.7086) (xy 84.8146 -157.70806) (xy 84.756742 -157.699091)
			(xy 84.700935 -157.681383) (xy 84.64849 -157.655352) (xy 84.600641 -157.621611) (xy 84.579206 -157.601666)
			(xy 84.57184 -157.594808) (xy 84.553806 -157.587442) (xy 84.463382 -157.587442) (xy 84.445348 -157.594808)
			(xy 84.437982 -157.601666) (xy 84.416527 -157.621587) (xy 84.368676 -157.655316) (xy 84.316235 -157.681342)
			(xy 84.260436 -157.699057) (xy 84.202586 -157.708044) (xy 84.173314 -157.7086) (xy 84.146061 -157.708132)
			(xy 84.09211 -157.700376) (xy 84.039812 -157.685022) (xy 83.990231 -157.66238) (xy 83.944378 -157.632913)
			(xy 83.903185 -157.59722) (xy 83.867491 -157.556027) (xy 83.838023 -157.510174) (xy 83.81538 -157.460594)
			(xy 83.800025 -157.408296) (xy 83.792269 -157.354345) (xy 83.791806 -157.327092) (xy 83.792333 -157.29952)
			(xy 83.800273 -157.244949) (xy 83.815985 -157.192091) (xy 83.839144 -157.142044) (xy 83.869266 -157.095853)
			(xy 83.905723 -157.054479) (xy 83.926426 -157.036262) (xy 83.934561 -157.028675) (xy 83.943905 -157.008512)
			(xy 83.94446 -156.9974) (xy 83.94446 -156.920184) (xy 83.94393 -156.909069) (xy 83.934566 -156.88891)
			(xy 83.926426 -156.881322) (xy 83.905727 -156.863097) (xy 83.869255 -156.821732) (xy 83.839121 -156.775545)
			(xy 83.815953 -156.7255) (xy 83.800234 -156.672639) (xy 83.792292 -156.618066) (xy 83.791806 -156.590492)
			(xy 83.792388 -156.561577) (xy 83.801103 -156.504409) (xy 83.818349 -156.449211) (xy 83.843728 -156.397249)
			(xy 83.876661 -156.349714) (xy 83.916391 -156.307694) (xy 83.938872 -156.289502) (xy 83.947641 -156.281947)
			(xy 83.957817 -156.261183) (xy 83.95843 -156.249624) (xy 83.95843 -156.16936) (xy 83.957849 -156.157793)
			(xy 83.947664 -156.13702) (xy 83.938872 -156.129482) (xy 83.91808 -156.112738) (xy 83.880949 -156.074385)
			(xy 83.849526 -156.031229) (xy 83.824427 -155.984115) (xy 83.80614 -155.933961) (xy 83.795023 -155.881748)
			(xy 83.791294 -155.828495) (xy 80.453735 -155.828495) (xy 77.622146 -158.660084) (xy 77.604065 -158.677356)
			(xy 77.562515 -158.705164) (xy 77.516339 -158.724333) (xy 77.467312 -158.734127) (xy 77.442314 -158.73476)
			(xy 64.736726 -158.73476) (xy 64.726677 -158.735101) (xy 64.708081 -158.742709) (xy 64.700658 -158.749492)
			(xy 59.240674 -164.209476) (xy 59.233848 -164.216887) (xy 59.226121 -164.235478) (xy 59.225688 -164.245544)
			(xy 59.225688 -164.588698) (xy 65.341246 -164.588698) (xy 65.341732 -164.561447) (xy 65.349488 -164.507499)
			(xy 65.364843 -164.455204) (xy 65.387485 -164.405627) (xy 65.416951 -164.359777) (xy 65.452642 -164.318586)
			(xy 65.493833 -164.282895) (xy 65.539683 -164.253429) (xy 65.58926 -164.230787) (xy 65.641555 -164.215432)
			(xy 65.695503 -164.207676) (xy 65.750005 -164.207676) (xy 65.803953 -164.215432) (xy 65.856248 -164.230787)
			(xy 65.905825 -164.253429) (xy 65.951675 -164.282895) (xy 65.992866 -164.318586) (xy 66.028557 -164.359777)
			(xy 66.058023 -164.405627) (xy 66.080665 -164.455204) (xy 66.09602 -164.507499) (xy 66.103776 -164.561447)
			(xy 66.104262 -164.588698) (xy 66.10363 -164.620262) (xy 66.093232 -164.682528) (xy 66.072735 -164.742237)
			(xy 66.058288 -164.770308) (xy 66.053462 -164.779198) (xy 66.05143 -164.798756) (xy 66.077084 -164.886894)
			(xy 66.08953 -164.902388) (xy 66.09842 -164.907468) (xy 66.105786 -164.911532) (xy 66.115438 -164.917374)
			(xy 66.137536 -164.919406) (xy 66.232024 -164.885878) (xy 66.248026 -164.870384) (xy 66.25209 -164.85997)
			(xy 66.262097 -164.834852) (xy 66.288173 -164.787488) (xy 66.320666 -164.744274) (xy 66.339466 -164.724842)
			(xy 66.346182 -164.717432) (xy 66.353908 -164.699012) (xy 66.354452 -164.689028) (xy 66.354452 -164.092382)
			(xy 66.35507 -164.067399) (xy 66.364811 -164.018391) (xy 66.383917 -163.972221) (xy 66.411653 -163.93066)
			(xy 66.428874 -163.91255) (xy 67.297046 -163.044378) (xy 67.31517 -163.027172) (xy 67.356724 -162.999426)
			(xy 67.40289 -162.980314) (xy 67.451895 -162.970569) (xy 67.476878 -162.969956) (xy 70.042278 -162.969956)
			(xy 70.067263 -162.970537) (xy 70.116273 -162.980289) (xy 70.162442 -162.999406) (xy 70.204001 -163.027153)
			(xy 70.22211 -163.044378) (xy 71.275448 -164.097716) (xy 86.637622 -164.097716) (xy 86.638123 -164.068308)
			(xy 86.647149 -164.010189) (xy 86.66499 -163.954145) (xy 86.691223 -163.901503) (xy 86.725225 -163.853512)
			(xy 86.745318 -163.832032) (xy 86.751922 -163.825428) (xy 86.759288 -163.807902) (xy 86.762082 -163.720526)
			(xy 86.755732 -163.702746) (xy 86.749382 -163.69538) (xy 86.732199 -163.674557) (xy 86.703277 -163.62897)
			(xy 86.681067 -163.579764) (xy 86.66601 -163.527919) (xy 86.658407 -163.47447) (xy 86.657942 -163.447476)
			(xy 86.658384 -163.420105) (xy 86.666206 -163.365924) (xy 86.6817 -163.31342) (xy 86.704547 -163.263674)
			(xy 86.734278 -163.217709) (xy 86.751922 -163.196778) (xy 86.758018 -163.189666) (xy 86.764368 -163.172648)
			(xy 86.764368 -163.087304) (xy 86.758018 -163.070286) (xy 86.751922 -163.063174) (xy 86.734308 -163.042222)
			(xy 86.704591 -162.996255) (xy 86.68175 -162.946513) (xy 86.666253 -162.894016) (xy 86.658419 -162.839844)
			(xy 86.657942 -162.812476) (xy 86.658333 -162.78522) (xy 86.666094 -162.731264) (xy 86.681456 -162.678962)
			(xy 86.704105 -162.629378) (xy 86.73358 -162.583523) (xy 86.769281 -162.542329) (xy 86.810482 -162.506636)
			(xy 86.856343 -162.477169) (xy 86.905931 -162.45453) (xy 86.958236 -162.439178) (xy 87.012194 -162.431427)
			(xy 87.03945 -162.430968) (xy 87.06682 -162.431447) (xy 87.120999 -162.439259) (xy 87.173503 -162.454744)
			(xy 87.22325 -162.477584) (xy 87.269217 -162.507307) (xy 87.290148 -162.524948) (xy 87.29726 -162.531044)
			(xy 87.314278 -162.537394) (xy 87.399622 -162.537394) (xy 87.41664 -162.531044) (xy 87.423752 -162.524948)
			(xy 87.444685 -162.507307) (xy 87.490653 -162.477583) (xy 87.540399 -162.454737) (xy 87.592901 -162.439241)
			(xy 87.647079 -162.431412) (xy 87.701821 -162.431412) (xy 87.755999 -162.439241) (xy 87.808501 -162.454737)
			(xy 87.858247 -162.477583) (xy 87.904215 -162.507307) (xy 87.925148 -162.524948) (xy 87.93226 -162.531044)
			(xy 87.949278 -162.537394) (xy 88.034622 -162.537394) (xy 88.05164 -162.531044) (xy 88.058752 -162.524948)
			(xy 88.079685 -162.507307) (xy 88.125653 -162.477583) (xy 88.175399 -162.454737) (xy 88.227901 -162.439241)
			(xy 88.282079 -162.431412) (xy 88.336821 -162.431412) (xy 88.390999 -162.439241) (xy 88.443501 -162.454737)
			(xy 88.493247 -162.477583) (xy 88.539215 -162.507307) (xy 88.560148 -162.524948) (xy 88.56726 -162.531044)
			(xy 88.584278 -162.537394) (xy 88.669622 -162.537394) (xy 88.68664 -162.531044) (xy 88.693752 -162.524948)
			(xy 88.714685 -162.507307) (xy 88.760653 -162.477583) (xy 88.810399 -162.454737) (xy 88.862901 -162.439241)
			(xy 88.917079 -162.431412) (xy 88.971821 -162.431412) (xy 89.025999 -162.439241) (xy 89.078501 -162.454737)
			(xy 89.128247 -162.477583) (xy 89.174215 -162.507307) (xy 89.195148 -162.524948) (xy 89.20226 -162.531044)
			(xy 89.219278 -162.537394) (xy 89.304622 -162.537394) (xy 89.32164 -162.531044) (xy 89.328752 -162.524948)
			(xy 89.349698 -162.507325) (xy 89.395666 -162.477609) (xy 89.44541 -162.45477) (xy 89.497908 -162.439275)
			(xy 89.552082 -162.431443) (xy 89.57945 -162.430968) (xy 89.60876 -162.431511) (xy 89.666686 -162.440505)
			(xy 89.722554 -162.458257) (xy 89.775046 -162.48435) (xy 89.822928 -162.518168) (xy 89.844372 -162.538156)
			(xy 89.851738 -162.545014) (xy 89.86901 -162.552126) (xy 89.958418 -162.55365) (xy 89.975944 -162.546792)
			(xy 89.98331 -162.540188) (xy 90.004476 -162.521627) (xy 90.051268 -162.490328) (xy 90.102149 -162.466241)
			(xy 90.156017 -162.449889) (xy 90.211702 -162.441627) (xy 90.23985 -162.441128) (xy 90.267103 -162.441602)
			(xy 90.321056 -162.449353) (xy 90.373356 -162.464705) (xy 90.422938 -162.487344) (xy 90.468793 -162.51681)
			(xy 90.509987 -162.552503) (xy 90.545682 -162.593696) (xy 90.575149 -162.63955) (xy 90.597791 -162.689131)
			(xy 90.613144 -162.741431) (xy 90.620897 -162.795383) (xy 90.621358 -162.822636) (xy 90.620923 -162.850007)
			(xy 90.613099 -162.904188) (xy 90.597604 -162.956692) (xy 90.574755 -163.006439) (xy 90.545023 -163.052404)
			(xy 90.527378 -163.073334) (xy 90.521282 -163.080446) (xy 90.514932 -163.097464) (xy 90.514932 -163.182808)
			(xy 90.521282 -163.199826) (xy 90.527378 -163.206938) (xy 90.544998 -163.227885) (xy 90.574714 -163.273854)
			(xy 90.597553 -163.323597) (xy 90.613049 -163.376095) (xy 90.620882 -163.430268) (xy 90.621358 -163.457636)
			(xy 90.620806 -163.487042) (xy 90.611789 -163.545157) (xy 90.593959 -163.601201) (xy 90.567738 -163.653843)
			(xy 90.533749 -163.701837) (xy 90.513662 -163.72332) (xy 90.507058 -163.729924) (xy 90.499692 -163.74745)
			(xy 90.496898 -163.834826) (xy 90.503248 -163.852606) (xy 90.509598 -163.859972) (xy 90.526755 -163.880815)
			(xy 90.555682 -163.926396) (xy 90.577898 -163.975598) (xy 90.592961 -164.027438) (xy 90.60057 -164.080884)
			(xy 90.601038 -164.107876) (xy 90.6005 -164.135125) (xy 90.592747 -164.189069) (xy 90.577396 -164.241361)
			(xy 90.55476 -164.290936) (xy 90.525299 -164.336785) (xy 90.489613 -164.377975) (xy 90.448429 -164.413667)
			(xy 90.402584 -164.443134) (xy 90.353012 -164.465778) (xy 90.300722 -164.481136) (xy 90.246779 -164.488896)
			(xy 90.21953 -164.489384) (xy 90.19022 -164.488839) (xy 90.132295 -164.479843) (xy 90.076428 -164.462091)
			(xy 90.023935 -164.435999) (xy 89.976053 -164.402183) (xy 89.954608 -164.382196) (xy 89.947242 -164.375338)
			(xy 89.92997 -164.368226) (xy 89.840562 -164.366702) (xy 89.823036 -164.37356) (xy 89.81567 -164.380164)
			(xy 89.794479 -164.398695) (xy 89.747694 -164.429997) (xy 89.696818 -164.454089) (xy 89.642956 -164.470448)
			(xy 89.587276 -164.478719) (xy 89.55913 -164.479224) (xy 89.53176 -164.478759) (xy 89.47758 -164.470944)
			(xy 89.425076 -164.455455) (xy 89.375329 -164.432613) (xy 89.329363 -164.402887) (xy 89.308432 -164.385244)
			(xy 89.30132 -164.379148) (xy 89.284302 -164.372798) (xy 89.198958 -164.372798) (xy 89.18194 -164.379148)
			(xy 89.174828 -164.385244) (xy 89.153895 -164.402885) (xy 89.107927 -164.432609) (xy 89.058181 -164.455455)
			(xy 89.005679 -164.470951) (xy 88.951501 -164.47878) (xy 88.896759 -164.47878) (xy 88.842581 -164.470951)
			(xy 88.790079 -164.455455) (xy 88.740333 -164.432609) (xy 88.694365 -164.402885) (xy 88.673432 -164.385244)
			(xy 88.66632 -164.379148) (xy 88.649302 -164.372798) (xy 88.563958 -164.372798) (xy 88.54694 -164.379148)
			(xy 88.539828 -164.385244) (xy 88.518895 -164.402885) (xy 88.472927 -164.432609) (xy 88.423181 -164.455455)
			(xy 88.370679 -164.470951) (xy 88.316501 -164.47878) (xy 88.261759 -164.47878) (xy 88.207581 -164.470951)
			(xy 88.155079 -164.455455) (xy 88.105333 -164.432609) (xy 88.059365 -164.402885) (xy 88.038432 -164.385244)
			(xy 88.03132 -164.379148) (xy 88.014302 -164.372798) (xy 87.928958 -164.372798) (xy 87.91194 -164.379148)
			(xy 87.904828 -164.385244) (xy 87.883895 -164.402885) (xy 87.837927 -164.432609) (xy 87.788181 -164.455455)
			(xy 87.735679 -164.470951) (xy 87.681501 -164.47878) (xy 87.626759 -164.47878) (xy 87.572581 -164.470951)
			(xy 87.520079 -164.455455) (xy 87.470333 -164.432609) (xy 87.424365 -164.402885) (xy 87.403432 -164.385244)
			(xy 87.39632 -164.379148) (xy 87.379302 -164.372798) (xy 87.293958 -164.372798) (xy 87.27694 -164.379148)
			(xy 87.269828 -164.385244) (xy 87.248902 -164.402891) (xy 87.202927 -164.4326) (xy 87.153178 -164.455434)
			(xy 87.100676 -164.470923) (xy 87.046499 -164.478751) (xy 87.01913 -164.479224) (xy 86.991879 -164.478717)
			(xy 86.93793 -164.470964) (xy 86.885634 -164.455613) (xy 86.836055 -164.432975) (xy 86.790203 -164.403512)
			(xy 86.74901 -164.367823) (xy 86.713316 -164.326634) (xy 86.683847 -164.280785) (xy 86.661203 -164.231209)
			(xy 86.645845 -164.178915) (xy 86.638086 -164.124967) (xy 86.637622 -164.097716) (xy 71.275448 -164.097716)
			(xy 71.28891 -164.111178) (xy 71.306129 -164.129291) (xy 71.333873 -164.170848) (xy 71.352982 -164.217017)
			(xy 71.362722 -164.266026) (xy 71.363332 -164.29101) (xy 71.363332 -166.004424) (xy 82.10067 -166.004424)
			(xy 82.10067 -165.919728) (xy 82.108721 -165.835414) (xy 82.12475 -165.752248) (xy 82.148611 -165.670981)
			(xy 82.18009 -165.592351) (xy 82.218901 -165.51707) (xy 82.264691 -165.445818) (xy 82.317047 -165.379242)
			(xy 82.375495 -165.317944) (xy 82.439505 -165.262479) (xy 82.508497 -165.21335) (xy 82.581847 -165.171001)
			(xy 82.65889 -165.135817) (xy 82.738929 -165.108115) (xy 82.821238 -165.088147) (xy 82.905073 -165.076094)
			(xy 82.989674 -165.072064) (xy 83.074275 -165.076094) (xy 83.15811 -165.088147) (xy 83.240419 -165.108115)
			(xy 83.320458 -165.135817) (xy 83.397501 -165.171001) (xy 83.470851 -165.21335) (xy 83.539843 -165.262479)
			(xy 83.603853 -165.317944) (xy 83.662301 -165.379242) (xy 83.714657 -165.445818) (xy 83.760447 -165.51707)
			(xy 83.799258 -165.592351) (xy 83.830737 -165.670981) (xy 83.854598 -165.752248) (xy 83.870627 -165.835414)
			(xy 83.878678 -165.919728) (xy 83.879182 -165.962076) (xy 83.878678 -166.004424) (xy 91.49867 -166.004424)
			(xy 91.49867 -165.919728) (xy 91.506721 -165.835414) (xy 91.52275 -165.752248) (xy 91.546611 -165.670981)
			(xy 91.57809 -165.592351) (xy 91.616901 -165.51707) (xy 91.662691 -165.445818) (xy 91.715047 -165.379242)
			(xy 91.773495 -165.317944) (xy 91.837505 -165.262479) (xy 91.906497 -165.21335) (xy 91.979847 -165.171001)
			(xy 92.05689 -165.135817) (xy 92.136929 -165.108115) (xy 92.219238 -165.088147) (xy 92.303073 -165.076094)
			(xy 92.387674 -165.072064) (xy 92.472275 -165.076094) (xy 92.55611 -165.088147) (xy 92.638419 -165.108115)
			(xy 92.718458 -165.135817) (xy 92.795501 -165.171001) (xy 92.868851 -165.21335) (xy 92.937843 -165.262479)
			(xy 93.001853 -165.317944) (xy 93.060301 -165.379242) (xy 93.112657 -165.445818) (xy 93.158447 -165.51707)
			(xy 93.197258 -165.592351) (xy 93.228737 -165.670981) (xy 93.252598 -165.752248) (xy 93.268627 -165.835414)
			(xy 93.276678 -165.919728) (xy 93.277182 -165.962076) (xy 93.276678 -166.004424) (xy 93.268627 -166.088738)
			(xy 93.252598 -166.171904) (xy 93.228737 -166.253171) (xy 93.197258 -166.331801) (xy 93.158447 -166.407082)
			(xy 93.112657 -166.478334) (xy 93.060301 -166.54491) (xy 93.001853 -166.606208) (xy 92.937843 -166.661673)
			(xy 92.868851 -166.710802) (xy 92.795501 -166.753151) (xy 92.718458 -166.788335) (xy 92.638419 -166.816037)
			(xy 92.55611 -166.836005) (xy 92.472275 -166.848058) (xy 92.387674 -166.852089) (xy 92.303073 -166.848058)
			(xy 92.219238 -166.836005) (xy 92.136929 -166.816037) (xy 92.05689 -166.788335) (xy 91.979847 -166.753151)
			(xy 91.906497 -166.710802) (xy 91.837505 -166.661673) (xy 91.773495 -166.606208) (xy 91.715047 -166.54491)
			(xy 91.662691 -166.478334) (xy 91.616901 -166.407082) (xy 91.57809 -166.331801) (xy 91.546611 -166.253171)
			(xy 91.52275 -166.171904) (xy 91.506721 -166.088738) (xy 91.49867 -166.004424) (xy 83.878678 -166.004424)
			(xy 83.870627 -166.088738) (xy 83.854598 -166.171904) (xy 83.830737 -166.253171) (xy 83.799258 -166.331801)
			(xy 83.760447 -166.407082) (xy 83.714657 -166.478334) (xy 83.662301 -166.54491) (xy 83.603853 -166.606208)
			(xy 83.539843 -166.661673) (xy 83.470851 -166.710802) (xy 83.397501 -166.753151) (xy 83.320458 -166.788335)
			(xy 83.240419 -166.816037) (xy 83.15811 -166.836005) (xy 83.074275 -166.848058) (xy 82.989674 -166.852089)
			(xy 82.905073 -166.848058) (xy 82.821238 -166.836005) (xy 82.738929 -166.816037) (xy 82.65889 -166.788335)
			(xy 82.581847 -166.753151) (xy 82.508497 -166.710802) (xy 82.439505 -166.661673) (xy 82.375495 -166.606208)
			(xy 82.317047 -166.54491) (xy 82.264691 -166.478334) (xy 82.218901 -166.407082) (xy 82.18009 -166.331801)
			(xy 82.148611 -166.253171) (xy 82.12475 -166.171904) (xy 82.108721 -166.088738) (xy 82.10067 -166.004424)
			(xy 71.363332 -166.004424) (xy 71.363332 -168.044622) (xy 71.363738 -168.054694) (xy 71.371471 -168.073292)
			(xy 71.378318 -168.08069) (xy 71.802205 -168.504546) (xy 82.10067 -168.504546) (xy 82.10067 -168.41985)
			(xy 82.108721 -168.335536) (xy 82.12475 -168.25237) (xy 82.148611 -168.171103) (xy 82.18009 -168.092473)
			(xy 82.218901 -168.017192) (xy 82.264691 -167.94594) (xy 82.317047 -167.879364) (xy 82.375495 -167.818066)
			(xy 82.439505 -167.762601) (xy 82.508497 -167.713472) (xy 82.581847 -167.671123) (xy 82.65889 -167.635939)
			(xy 82.738929 -167.608237) (xy 82.821238 -167.588269) (xy 82.905073 -167.576216) (xy 82.989674 -167.572186)
			(xy 83.074275 -167.576216) (xy 83.15811 -167.588269) (xy 83.240419 -167.608237) (xy 83.320458 -167.635939)
			(xy 83.397501 -167.671123) (xy 83.470851 -167.713472) (xy 83.539843 -167.762601) (xy 83.603853 -167.818066)
			(xy 83.662301 -167.879364) (xy 83.714657 -167.94594) (xy 83.760447 -168.017192) (xy 83.799258 -168.092473)
			(xy 83.830737 -168.171103) (xy 83.854598 -168.25237) (xy 83.870627 -168.335536) (xy 83.878678 -168.41985)
			(xy 83.879182 -168.462198) (xy 83.878678 -168.504546) (xy 91.49867 -168.504546) (xy 91.49867 -168.41985)
			(xy 91.506721 -168.335536) (xy 91.52275 -168.25237) (xy 91.546611 -168.171103) (xy 91.57809 -168.092473)
			(xy 91.616901 -168.017192) (xy 91.662691 -167.94594) (xy 91.715047 -167.879364) (xy 91.773495 -167.818066)
			(xy 91.837505 -167.762601) (xy 91.906497 -167.713472) (xy 91.979847 -167.671123) (xy 92.05689 -167.635939)
			(xy 92.136929 -167.608237) (xy 92.219238 -167.588269) (xy 92.303073 -167.576216) (xy 92.387674 -167.572186)
			(xy 92.472275 -167.576216) (xy 92.55611 -167.588269) (xy 92.638419 -167.608237) (xy 92.718458 -167.635939)
			(xy 92.795501 -167.671123) (xy 92.868851 -167.713472) (xy 92.937843 -167.762601) (xy 93.001853 -167.818066)
			(xy 93.060301 -167.879364) (xy 93.112657 -167.94594) (xy 93.158447 -168.017192) (xy 93.197258 -168.092473)
			(xy 93.228737 -168.171103) (xy 93.252598 -168.25237) (xy 93.268627 -168.335536) (xy 93.276678 -168.41985)
			(xy 93.277182 -168.462198) (xy 93.276678 -168.504546) (xy 93.268627 -168.58886) (xy 93.252598 -168.672026)
			(xy 93.228737 -168.753293) (xy 93.197258 -168.831923) (xy 93.158447 -168.907204) (xy 93.112657 -168.978456)
			(xy 93.060301 -169.045032) (xy 93.001853 -169.10633) (xy 92.937843 -169.161795) (xy 92.868851 -169.210924)
			(xy 92.795501 -169.253273) (xy 92.718458 -169.288457) (xy 92.638419 -169.316159) (xy 92.55611 -169.336127)
			(xy 92.472275 -169.34818) (xy 92.387674 -169.352211) (xy 92.303073 -169.34818) (xy 92.219238 -169.336127)
			(xy 92.136929 -169.316159) (xy 92.05689 -169.288457) (xy 91.979847 -169.253273) (xy 91.906497 -169.210924)
			(xy 91.837505 -169.161795) (xy 91.773495 -169.10633) (xy 91.715047 -169.045032) (xy 91.662691 -168.978456)
			(xy 91.616901 -168.907204) (xy 91.57809 -168.831923) (xy 91.546611 -168.753293) (xy 91.52275 -168.672026)
			(xy 91.506721 -168.58886) (xy 91.49867 -168.504546) (xy 83.878678 -168.504546) (xy 83.870627 -168.58886)
			(xy 83.854598 -168.672026) (xy 83.830737 -168.753293) (xy 83.799258 -168.831923) (xy 83.760447 -168.907204)
			(xy 83.714657 -168.978456) (xy 83.662301 -169.045032) (xy 83.603853 -169.10633) (xy 83.539843 -169.161795)
			(xy 83.470851 -169.210924) (xy 83.397501 -169.253273) (xy 83.320458 -169.288457) (xy 83.240419 -169.316159)
			(xy 83.15811 -169.336127) (xy 83.074275 -169.34818) (xy 82.989674 -169.352211) (xy 82.905073 -169.34818)
			(xy 82.821238 -169.336127) (xy 82.738929 -169.316159) (xy 82.65889 -169.288457) (xy 82.581847 -169.253273)
			(xy 82.508497 -169.210924) (xy 82.439505 -169.161795) (xy 82.375495 -169.10633) (xy 82.317047 -169.045032)
			(xy 82.264691 -168.978456) (xy 82.218901 -168.907204) (xy 82.18009 -168.831923) (xy 82.148611 -168.753293)
			(xy 82.12475 -168.672026) (xy 82.108721 -168.58886) (xy 82.10067 -168.504546) (xy 71.802205 -168.504546)
			(xy 74.886312 -171.58843) (xy 74.893673 -171.595199) (xy 74.912135 -171.602846) (xy 74.932117 -171.602846)
			(xy 74.950579 -171.595199) (xy 74.95794 -171.58843) (xy 75.120246 -171.426378) (xy 75.13837 -171.409172)
			(xy 75.179924 -171.381426) (xy 75.22609 -171.362314) (xy 75.275095 -171.352569) (xy 75.300078 -171.351956)
			(xy 77.856334 -171.351956) (xy 77.881318 -171.352563) (xy 77.930326 -171.362308) (xy 77.976496 -171.381416)
			(xy 78.018056 -171.409156) (xy 78.036166 -171.426378) (xy 83.209892 -176.59985) (xy 83.217253 -176.606619)
			(xy 83.235715 -176.614266) (xy 83.255697 -176.614266) (xy 83.274159 -176.606619) (xy 83.28152 -176.59985)
			(xy 83.680046 -176.201578) (xy 83.69817 -176.184372) (xy 83.739724 -176.156626) (xy 83.78589 -176.137514)
			(xy 83.834895 -176.127769) (xy 83.859878 -176.127156) (xy 91.018614 -176.127156) (xy 91.043597 -176.127776)
			(xy 91.092605 -176.137516) (xy 91.138775 -176.156621) (xy 91.180336 -176.184357) (xy 91.198446 -176.201578)
			(xy 91.607132 -176.61001) (xy 91.614493 -176.616779) (xy 91.632955 -176.624426) (xy 91.652937 -176.624426)
			(xy 91.671399 -176.616779) (xy 91.67876 -176.61001) (xy 91.985846 -176.303178) (xy 92.00397 -176.285972)
			(xy 92.045524 -176.258226) (xy 92.09169 -176.239114) (xy 92.140695 -176.229369) (xy 92.165678 -176.228756)
			(xy 99.573334 -176.228756) (xy 99.598318 -176.229363) (xy 99.647326 -176.239108) (xy 99.693496 -176.258216)
			(xy 99.735056 -176.285956) (xy 99.753166 -176.303178) (xy 99.999292 -176.54905) (xy 100.006653 -176.555819)
			(xy 100.025115 -176.563466) (xy 100.045097 -176.563466) (xy 100.063559 -176.555819) (xy 100.07092 -176.54905)
			(xy 100.786438 -175.833786) (xy 100.793282 -175.826389) (xy 100.800998 -175.807787) (xy 100.801424 -175.797718)
			(xy 100.801424 -174.24781) (xy 100.802067 -174.222828) (xy 100.811802 -174.173822) (xy 100.8309 -174.127653)
			(xy 100.858629 -174.08609) (xy 100.875846 -174.067978) (xy 102.894638 -172.049186) (xy 102.901482 -172.041789)
			(xy 102.909198 -172.023187) (xy 102.909624 -172.013118) (xy 102.909624 -150.0632) (xy 102.909219 -150.053128)
			(xy 102.901486 -150.034529) (xy 102.894638 -150.027132) (xy 100.465128 -147.597622) (xy 100.45771 -147.590805)
			(xy 100.439125 -147.583071) (xy 100.42906 -147.582636) (xy 99.746816 -147.582636) (xy 99.721834 -147.582)
			(xy 99.672827 -147.572265) (xy 99.626657 -147.553165) (xy 99.585095 -147.525432) (xy 99.566984 -147.508214)
			(xy 98.344228 -146.285458) (xy 98.326964 -146.26737) (xy 98.299154 -146.225823) (xy 98.279983 -146.179649)
			(xy 98.270187 -146.130623) (xy 98.269552 -146.105626) (xy 98.269552 -144.480026) (xy 98.270195 -144.45503)
			(xy 98.279996 -144.406008) (xy 98.299167 -144.359837) (xy 98.326973 -144.31829) (xy 98.344228 -144.300194)
			(xy 99.050602 -143.59382) (xy 99.068706 -143.576573) (xy 99.110248 -143.548761) (xy 99.156416 -143.529585)
			(xy 99.205438 -143.519782) (xy 99.230434 -143.519144) (xy 100.149406 -143.519144) (xy 100.159258 -143.518609)
			(xy 100.177476 -143.511078) (xy 100.191543 -143.497268) (xy 100.195888 -143.48841) (xy 100.239068 -143.388588)
			(xy 100.233734 -143.35887) (xy 100.223066 -143.347694) (xy 100.203533 -143.326317) (xy 100.170494 -143.278762)
			(xy 100.145026 -143.226759) (xy 100.127715 -143.171503) (xy 100.118957 -143.114264) (xy 100.118418 -143.085312)
			(xy 100.118904 -143.058061) (xy 100.12666 -143.004113) (xy 100.142015 -142.951818) (xy 100.164657 -142.902241)
			(xy 100.194123 -142.856391) (xy 100.229814 -142.8152) (xy 100.271005 -142.779509) (xy 100.316855 -142.750043)
			(xy 100.366432 -142.727401) (xy 100.418727 -142.712046) (xy 100.472675 -142.70429) (xy 100.527177 -142.70429)
			(xy 100.581125 -142.712046) (xy 100.63342 -142.727401) (xy 100.682997 -142.750043) (xy 100.728847 -142.779509)
			(xy 100.770038 -142.8152) (xy 100.805729 -142.856391) (xy 100.835195 -142.902241) (xy 100.857837 -142.951818)
			(xy 100.873192 -143.004113) (xy 100.880948 -143.058061) (xy 100.881434 -143.085312) (xy 100.880989 -143.111288)
			(xy 100.873938 -143.162759) (xy 100.859968 -143.212797) (xy 100.839337 -143.260477) (xy 100.812427 -143.304916)
			(xy 100.779736 -143.345293) (xy 100.741869 -143.38086) (xy 100.699525 -143.41096) (xy 100.67671 -143.423386)
			(xy 100.66401 -143.42999) (xy 100.649278 -143.45412) (xy 100.649278 -143.468344) (xy 100.649752 -143.478352)
			(xy 100.657421 -143.49684) (xy 100.671578 -143.510991) (xy 100.69007 -143.518653) (xy 100.700078 -143.519144)
			(xy 100.762562 -143.519144) (xy 100.77261 -143.518796) (xy 100.791207 -143.511193) (xy 100.79863 -143.504412)
			(xy 101.471222 -142.83182) (xy 101.489318 -142.814564) (xy 101.530862 -142.786753) (xy 101.577033 -142.76758)
			(xy 101.626058 -142.75778) (xy 101.651054 -142.757144) (xy 102.903274 -142.757144) (xy 102.92827 -142.75779)
			(xy 102.977292 -142.76759) (xy 103.023463 -142.786761) (xy 103.06501 -142.814566) (xy 103.083106 -142.83182)
			(xy 103.306626 -143.05534) (xy 103.32383 -143.073466) (xy 103.351576 -143.115019) (xy 103.370688 -143.161184)
			(xy 103.380434 -143.21019) (xy 103.381048 -143.235172) (xy 103.381048 -143.814292) (xy 103.380414 -143.839274)
			(xy 103.370678 -143.888281) (xy 103.351577 -143.934451) (xy 103.323845 -143.976013) (xy 103.306626 -143.994124)
			(xy 103.226362 -144.074388) (xy 103.218742 -144.09293) (xy 103.218742 -144.103344) (xy 103.218234 -144.130618)
			(xy 103.210544 -144.184619) (xy 103.195239 -144.236974) (xy 103.172634 -144.286616) (xy 103.143188 -144.332532)
			(xy 103.107502 -144.373785) (xy 103.066304 -144.409534) (xy 103.020435 -144.439051) (xy 102.970828 -144.461733)
			(xy 102.918496 -144.477118) (xy 102.864507 -144.484893) (xy 102.837234 -144.48536) (xy 102.80998 -144.484913)
			(xy 102.756026 -144.477159) (xy 102.703725 -144.461805) (xy 102.654142 -144.439163) (xy 102.608286 -144.409694)
			(xy 102.567092 -144.373999) (xy 102.531397 -144.332803) (xy 102.50193 -144.286946) (xy 102.47929 -144.237362)
			(xy 102.463938 -144.185061) (xy 102.456186 -144.131106) (xy 102.455726 -144.103852) (xy 102.456168 -144.07548)
			(xy 102.464551 -144.01936) (xy 102.481156 -143.965101) (xy 102.505615 -143.913901) (xy 102.53739 -143.866889)
			(xy 102.575778 -143.825102) (xy 102.619933 -143.789464) (xy 102.66888 -143.76076) (xy 102.72154 -143.739624)
			(xy 102.776749 -143.726522) (xy 102.804976 -143.723614) (xy 102.814049 -143.722445) (xy 102.830581 -143.71465)
			(xy 102.837234 -143.708374) (xy 102.858062 -143.68653) (xy 102.864585 -143.679187) (xy 102.872035 -143.661033)
			(xy 102.87254 -143.651224) (xy 102.87254 -143.361664) (xy 102.872149 -143.351591) (xy 102.864406 -143.332992)
			(xy 102.857554 -143.325596) (xy 102.81285 -143.280892) (xy 102.805373 -143.274193) (xy 102.786811 -143.266605)
			(xy 102.776782 -143.26616) (xy 101.777546 -143.26616) (xy 101.767498 -143.266511) (xy 101.748902 -143.274112)
			(xy 101.741478 -143.280892) (xy 101.068886 -143.953484) (xy 101.050788 -143.970737) (xy 101.009244 -143.998548)
			(xy 100.963074 -144.017723) (xy 100.91405 -144.027523) (xy 100.889054 -144.02816) (xy 100.522786 -144.02816)
			(xy 100.513676 -144.028523) (xy 100.496598 -144.034874) (xy 100.482801 -144.046774) (xy 100.478082 -144.054576)
			(xy 100.428806 -144.145762) (xy 100.430076 -144.173448) (xy 100.437696 -144.185386) (xy 100.444552 -144.196001)
			(xy 100.457009 -144.21799) (xy 100.462588 -144.229328) (xy 100.466621 -144.236966) (xy 100.478825 -144.249173)
			(xy 100.486464 -144.253204) (xy 100.505517 -144.262912) (xy 100.540375 -144.287676) (xy 100.555806 -144.30248)
			(xy 101.620066 -145.36674) (xy 101.637276 -145.38486) (xy 101.665019 -145.426416) (xy 101.68413 -145.472583)
			(xy 101.693874 -145.521589) (xy 101.694488 -145.546572) (xy 101.694488 -145.673064) (xy 102.076756 -145.673064)
			(xy 102.080827 -145.617442) (xy 102.092953 -145.563005) (xy 102.112876 -145.510914) (xy 102.140172 -145.462279)
			(xy 102.174258 -145.418136) (xy 102.214407 -145.379427) (xy 102.259765 -145.346976) (xy 102.309365 -145.321475)
			(xy 102.362149 -145.303468) (xy 102.416992 -145.293338) (xy 102.472726 -145.291301) (xy 102.528163 -145.297401)
			(xy 102.58212 -145.311507) (xy 102.633449 -145.333319) (xy 102.681055 -145.362373) (xy 102.723923 -145.398048)
			(xy 102.76114 -145.439585) (xy 102.791913 -145.486098) (xy 102.815585 -145.536595) (xy 102.831653 -145.590002)
			(xy 102.839773 -145.645178) (xy 102.840282 -145.673064) (xy 102.839773 -145.70095) (xy 102.831653 -145.756126)
			(xy 102.815585 -145.809533) (xy 102.791913 -145.86003) (xy 102.76114 -145.906543) (xy 102.723923 -145.94808)
			(xy 102.681055 -145.983755) (xy 102.633449 -146.012809) (xy 102.58212 -146.034621) (xy 102.528163 -146.048727)
			(xy 102.472726 -146.054827) (xy 102.416992 -146.05279) (xy 102.362149 -146.04266) (xy 102.309365 -146.024653)
			(xy 102.259765 -145.999152) (xy 102.214407 -145.966701) (xy 102.174258 -145.927992) (xy 102.140172 -145.883849)
			(xy 102.112876 -145.835214) (xy 102.092953 -145.783123) (xy 102.080827 -145.728686) (xy 102.076756 -145.673064)
			(xy 101.694488 -145.673064) (xy 101.694488 -146.33956) (xy 101.694911 -146.34963) (xy 101.702631 -146.368229)
			(xy 101.709474 -146.375628) (xy 102.778306 -147.44446) (xy 103.134414 -147.44446) (xy 103.134842 -147.418796)
			(xy 103.14171 -147.367929) (xy 103.155345 -147.318446) (xy 103.175498 -147.27124) (xy 103.201806 -147.227166)
			(xy 103.233791 -147.187023) (xy 103.270876 -147.151537) (xy 103.291386 -147.136104) (xy 103.302172 -147.127651)
			(xy 103.319255 -147.106243) (xy 103.330025 -147.081061) (xy 103.333708 -147.053921) (xy 103.330036 -147.026779)
			(xy 103.319276 -147.001593) (xy 103.302202 -146.980177) (xy 103.291386 -146.971766) (xy 103.267495 -146.953705)
			(xy 103.225182 -146.911322) (xy 103.190012 -146.862847) (xy 103.162849 -146.809472) (xy 103.14436 -146.752508)
			(xy 103.135 -146.693355) (xy 103.134414 -146.66341) (xy 103.1349 -146.636159) (xy 103.142656 -146.582211)
			(xy 103.158011 -146.529916) (xy 103.180653 -146.480339) (xy 103.210119 -146.434489) (xy 103.24581 -146.393298)
			(xy 103.287001 -146.357607) (xy 103.332851 -146.328141) (xy 103.382428 -146.305499) (xy 103.434723 -146.290144)
			(xy 103.488671 -146.282388) (xy 103.543173 -146.282388) (xy 103.597121 -146.290144) (xy 103.649416 -146.305499)
			(xy 103.698993 -146.328141) (xy 103.744843 -146.357607) (xy 103.786034 -146.393298) (xy 103.821725 -146.434489)
			(xy 103.84103 -146.464528) (xy 115.805966 -146.464528) (xy 115.806432 -146.437158) (xy 115.814248 -146.382978)
			(xy 115.829736 -146.330474) (xy 115.852578 -146.280727) (xy 115.882304 -146.234761) (xy 115.899946 -146.21383)
			(xy 115.906042 -146.206718) (xy 115.912392 -146.1897) (xy 115.912392 -146.104356) (xy 115.906042 -146.087338)
			(xy 115.899946 -146.080226) (xy 115.882332 -146.059271) (xy 115.852605 -146.013308) (xy 115.829756 -145.963565)
			(xy 115.814257 -145.911066) (xy 115.806426 -145.856891) (xy 115.806422 -145.802152) (xy 115.814248 -145.747975)
			(xy 115.829742 -145.695474) (xy 115.852584 -145.645729) (xy 115.882307 -145.599762) (xy 115.899946 -145.57883)
			(xy 115.906042 -145.571718) (xy 115.912392 -145.5547) (xy 115.912392 -145.469356) (xy 115.906042 -145.452338)
			(xy 115.899946 -145.445226) (xy 115.882332 -145.424271) (xy 115.852605 -145.378308) (xy 115.829756 -145.328565)
			(xy 115.814257 -145.276066) (xy 115.806426 -145.221891) (xy 115.806422 -145.167152) (xy 115.814248 -145.112975)
			(xy 115.829742 -145.060474) (xy 115.852584 -145.010729) (xy 115.882307 -144.964762) (xy 115.899946 -144.94383)
			(xy 115.906042 -144.936718) (xy 115.912392 -144.9197) (xy 115.912392 -144.834356) (xy 115.906042 -144.817338)
			(xy 115.899946 -144.810226) (xy 115.882332 -144.789271) (xy 115.852605 -144.743308) (xy 115.829756 -144.693565)
			(xy 115.814257 -144.641066) (xy 115.806426 -144.586891) (xy 115.806422 -144.532152) (xy 115.814248 -144.477975)
			(xy 115.829742 -144.425474) (xy 115.852584 -144.375729) (xy 115.882307 -144.329762) (xy 115.899946 -144.30883)
			(xy 115.906042 -144.301718) (xy 115.912392 -144.2847) (xy 115.912392 -144.199356) (xy 115.906042 -144.182338)
			(xy 115.899946 -144.175226) (xy 115.882313 -144.154289) (xy 115.852598 -144.108318) (xy 115.829761 -144.058572)
			(xy 115.814268 -144.006072) (xy 115.80644 -143.951897) (xy 115.805966 -143.924528) (xy 115.806481 -143.897277)
			(xy 115.814234 -143.843329) (xy 115.829585 -143.791034) (xy 115.852222 -143.741456) (xy 115.881685 -143.695604)
			(xy 115.917373 -143.654411) (xy 115.95856 -143.618717) (xy 116.004408 -143.589248) (xy 116.053983 -143.566604)
			(xy 116.106276 -143.551245) (xy 116.160223 -143.543485) (xy 116.187474 -143.54302) (xy 116.214844 -143.543496)
			(xy 116.269023 -143.551311) (xy 116.321526 -143.566797) (xy 116.371273 -143.589637) (xy 116.41724 -143.61936)
			(xy 116.438172 -143.637) (xy 116.445284 -143.643096) (xy 116.462302 -143.649446) (xy 116.547646 -143.649446)
			(xy 116.564664 -143.643096) (xy 116.571776 -143.637) (xy 116.592706 -143.619359) (xy 116.63868 -143.589647)
			(xy 116.688428 -143.566812) (xy 116.740929 -143.551321) (xy 116.795105 -143.543494) (xy 116.822474 -143.54302)
			(xy 116.850048 -143.543497) (xy 116.904621 -143.551446) (xy 116.957481 -143.567168) (xy 117.007527 -143.590336)
			(xy 117.053717 -143.620467) (xy 117.095088 -143.656933) (xy 117.113304 -143.67764) (xy 117.120903 -143.685762)
			(xy 117.141057 -143.695113) (xy 117.152166 -143.695674) (xy 117.229382 -143.695674) (xy 117.240494 -143.69512)
			(xy 117.260653 -143.685773) (xy 117.268244 -143.67764) (xy 117.28649 -143.656961) (xy 117.32785 -143.620486)
			(xy 117.374033 -143.590349) (xy 117.424074 -143.567177) (xy 117.476931 -143.551455) (xy 117.531501 -143.543509)
			(xy 117.559074 -143.54302) (xy 117.586444 -143.543496) (xy 117.640623 -143.551311) (xy 117.693126 -143.566797)
			(xy 117.742873 -143.589637) (xy 117.78884 -143.61936) (xy 117.809772 -143.637) (xy 117.816884 -143.643096)
			(xy 117.833902 -143.649446) (xy 117.919246 -143.649446) (xy 117.936264 -143.643096) (xy 117.943376 -143.637)
			(xy 117.964309 -143.619359) (xy 118.010277 -143.589635) (xy 118.060023 -143.566789) (xy 118.112525 -143.551293)
			(xy 118.166703 -143.543464) (xy 118.221445 -143.543464) (xy 118.275623 -143.551293) (xy 118.328125 -143.566789)
			(xy 118.377871 -143.589635) (xy 118.423839 -143.619359) (xy 118.444772 -143.637) (xy 118.451884 -143.643096)
			(xy 118.468902 -143.649446) (xy 118.554246 -143.649446) (xy 118.571264 -143.643096) (xy 118.578376 -143.637)
			(xy 118.599309 -143.619359) (xy 118.645277 -143.589635) (xy 118.695023 -143.566789) (xy 118.747525 -143.551293)
			(xy 118.801703 -143.543464) (xy 118.856445 -143.543464) (xy 118.910623 -143.551293) (xy 118.963125 -143.566789)
			(xy 119.012871 -143.589635) (xy 119.058839 -143.619359) (xy 119.079772 -143.637) (xy 119.086884 -143.643096)
			(xy 119.103902 -143.649446) (xy 119.189246 -143.649446) (xy 119.206264 -143.643096) (xy 119.213376 -143.637)
			(xy 119.234306 -143.619359) (xy 119.28028 -143.589647) (xy 119.330028 -143.566812) (xy 119.382529 -143.551321)
			(xy 119.436705 -143.543494) (xy 119.464074 -143.54302) (xy 119.491648 -143.543497) (xy 119.546221 -143.551446)
			(xy 119.599081 -143.567168) (xy 119.649127 -143.590336) (xy 119.695317 -143.620467) (xy 119.736688 -143.656933)
			(xy 119.754904 -143.67764) (xy 119.762503 -143.685762) (xy 119.782657 -143.695113) (xy 119.793766 -143.695674)
			(xy 119.870982 -143.695674) (xy 119.882094 -143.69512) (xy 119.902253 -143.685773) (xy 119.909844 -143.67764)
			(xy 119.92809 -143.656961) (xy 119.96945 -143.620486) (xy 120.015633 -143.590349) (xy 120.065674 -143.567177)
			(xy 120.118531 -143.551455) (xy 120.173101 -143.543509) (xy 120.200674 -143.54302) (xy 120.228044 -143.543496)
			(xy 120.282223 -143.551311) (xy 120.334726 -143.566797) (xy 120.384473 -143.589637) (xy 120.43044 -143.61936)
			(xy 120.451372 -143.637) (xy 120.458484 -143.643096) (xy 120.475502 -143.649446) (xy 120.560846 -143.649446)
			(xy 120.577864 -143.643096) (xy 120.584976 -143.637) (xy 120.605906 -143.619359) (xy 120.65188 -143.589647)
			(xy 120.701628 -143.566812) (xy 120.754129 -143.551321) (xy 120.808305 -143.543494) (xy 120.835674 -143.54302)
			(xy 120.862927 -143.54348) (xy 120.91688 -143.551234) (xy 120.96918 -143.566588) (xy 121.018762 -143.589229)
			(xy 121.064616 -143.618697) (xy 121.10581 -143.654392) (xy 121.141504 -143.695585) (xy 121.170972 -143.74144)
			(xy 121.193613 -143.791022) (xy 121.208967 -143.843322) (xy 121.216721 -143.897275) (xy 121.217182 -143.924528)
			(xy 121.216737 -143.951899) (xy 121.208915 -144.006079) (xy 121.193421 -144.058583) (xy 121.170574 -144.108329)
			(xy 121.140845 -144.154295) (xy 121.123202 -144.175226) (xy 121.117106 -144.182338) (xy 121.110756 -144.199356)
			(xy 121.110756 -144.2847) (xy 121.117106 -144.301718) (xy 121.123202 -144.30883) (xy 121.140869 -144.329741)
			(xy 121.17059 -144.375713) (xy 121.193432 -144.425463) (xy 121.208925 -144.477968) (xy 121.216751 -144.532149)
			(xy 121.216747 -144.586893) (xy 121.208916 -144.641073) (xy 121.193417 -144.693576) (xy 121.17057 -144.743324)
			(xy 121.140843 -144.789293) (xy 121.123202 -144.810226) (xy 121.117106 -144.817338) (xy 121.110756 -144.834356)
			(xy 121.110756 -144.9197) (xy 121.117106 -144.936718) (xy 121.123202 -144.94383) (xy 121.140869 -144.964741)
			(xy 121.17059 -145.010713) (xy 121.193432 -145.060463) (xy 121.208925 -145.112968) (xy 121.216751 -145.167149)
			(xy 121.216747 -145.221893) (xy 121.208916 -145.276073) (xy 121.193417 -145.328576) (xy 121.17057 -145.378324)
			(xy 121.140843 -145.424293) (xy 121.123202 -145.445226) (xy 121.117106 -145.452338) (xy 121.110756 -145.469356)
			(xy 121.110756 -145.5547) (xy 121.117106 -145.571718) (xy 121.123202 -145.57883) (xy 121.140869 -145.599741)
			(xy 121.17059 -145.645713) (xy 121.193432 -145.695463) (xy 121.208925 -145.747968) (xy 121.216751 -145.802149)
			(xy 121.216747 -145.856893) (xy 121.208916 -145.911073) (xy 121.193417 -145.963576) (xy 121.17057 -146.013324)
			(xy 121.140843 -146.059293) (xy 121.123202 -146.080226) (xy 121.117106 -146.087338) (xy 121.110756 -146.104356)
			(xy 121.110756 -146.1897) (xy 121.117106 -146.206718) (xy 121.123202 -146.21383) (xy 121.140822 -146.234777)
			(xy 121.170537 -146.280746) (xy 121.193376 -146.33049) (xy 121.208872 -146.382987) (xy 121.216705 -146.43716)
			(xy 121.217182 -146.464528) (xy 121.216748 -146.491781) (xy 121.208987 -146.545732) (xy 121.193627 -146.598029)
			(xy 121.170981 -146.647608) (xy 121.141509 -146.69346) (xy 121.105812 -146.734651) (xy 121.064617 -146.770342)
			(xy 121.018761 -146.799807) (xy 120.969179 -146.822446) (xy 120.916879 -146.837799) (xy 120.862927 -146.845552)
			(xy 120.835674 -146.846036) (xy 120.808302 -146.845601) (xy 120.754121 -146.837778) (xy 120.701617 -146.822282)
			(xy 120.651871 -146.799433) (xy 120.605906 -146.769701) (xy 120.584976 -146.752056) (xy 120.577864 -146.74596)
			(xy 120.560846 -146.73961) (xy 120.475502 -146.73961) (xy 120.458484 -146.74596) (xy 120.451372 -146.752056)
			(xy 120.430418 -146.769668) (xy 120.384452 -146.799385) (xy 120.33471 -146.822227) (xy 120.282214 -146.837725)
			(xy 120.228042 -146.845559) (xy 120.200674 -146.846036) (xy 120.173354 -146.845559) (xy 120.119273 -146.83776)
			(xy 120.066857 -146.822326) (xy 120.01718 -146.799573) (xy 119.971256 -146.769965) (xy 119.930026 -146.734109)
			(xy 119.894333 -146.692738) (xy 119.864907 -146.646698) (xy 119.853202 -146.622008) (xy 119.847106 -146.608292)
			(xy 119.82196 -146.592036) (xy 119.759984 -146.592036) (xy 119.741188 -146.59991) (xy 119.734076 -146.607022)
			(xy 119.714472 -146.626004) (xy 119.670814 -146.658738) (xy 119.622937 -146.684918) (xy 119.571819 -146.704009)
			(xy 119.518502 -146.715621) (xy 119.464074 -146.719519) (xy 119.409646 -146.715621) (xy 119.356329 -146.704009)
			(xy 119.305211 -146.684918) (xy 119.257334 -146.658738) (xy 119.213676 -146.626004) (xy 119.194072 -146.607022)
			(xy 119.18696 -146.59991) (xy 119.168164 -146.592036) (xy 119.124984 -146.592036) (xy 119.106188 -146.59991)
			(xy 119.099076 -146.607022) (xy 119.079472 -146.626004) (xy 119.035814 -146.658738) (xy 118.987937 -146.684918)
			(xy 118.936819 -146.704009) (xy 118.883502 -146.715621) (xy 118.829074 -146.719519) (xy 118.774646 -146.715621)
			(xy 118.721329 -146.704009) (xy 118.670211 -146.684918) (xy 118.622334 -146.658738) (xy 118.578676 -146.626004)
			(xy 118.559072 -146.607022) (xy 118.55196 -146.59991) (xy 118.533164 -146.592036) (xy 118.489984 -146.592036)
			(xy 118.471188 -146.59991) (xy 118.464076 -146.607022) (xy 118.444472 -146.626004) (xy 118.400814 -146.658738)
			(xy 118.352937 -146.684918) (xy 118.301819 -146.704009) (xy 118.248502 -146.715621) (xy 118.194074 -146.719519)
			(xy 118.139646 -146.715621) (xy 118.086329 -146.704009) (xy 118.035211 -146.684918) (xy 117.987334 -146.658738)
			(xy 117.943676 -146.626004) (xy 117.924072 -146.607022) (xy 117.91696 -146.59991) (xy 117.898164 -146.592036)
			(xy 117.854984 -146.592036) (xy 117.836188 -146.59991) (xy 117.829076 -146.607022) (xy 117.809472 -146.626004)
			(xy 117.765814 -146.658738) (xy 117.717937 -146.684918) (xy 117.666819 -146.704009) (xy 117.613502 -146.715621)
			(xy 117.559074 -146.719519) (xy 117.504646 -146.715621) (xy 117.451329 -146.704009) (xy 117.400211 -146.684918)
			(xy 117.352334 -146.658738) (xy 117.308676 -146.626004) (xy 117.289072 -146.607022) (xy 117.28196 -146.59991)
			(xy 117.263164 -146.592036) (xy 117.201188 -146.592036) (xy 117.176042 -146.608292) (xy 117.169946 -146.622008)
			(xy 117.158242 -146.6467) (xy 117.128821 -146.692745) (xy 117.093131 -146.734122) (xy 117.051901 -146.769981)
			(xy 117.005977 -146.799591) (xy 116.956297 -146.822344) (xy 116.903879 -146.837776) (xy 116.849795 -146.845569)
			(xy 116.822474 -146.846036) (xy 116.795102 -146.845601) (xy 116.740921 -146.837778) (xy 116.688417 -146.822282)
			(xy 116.638671 -146.799433) (xy 116.592706 -146.769701) (xy 116.571776 -146.752056) (xy 116.564664 -146.74596)
			(xy 116.547646 -146.73961) (xy 116.462302 -146.73961) (xy 116.445284 -146.74596) (xy 116.438172 -146.752056)
			(xy 116.417218 -146.769668) (xy 116.371252 -146.799385) (xy 116.32151 -146.822227) (xy 116.269014 -146.837725)
			(xy 116.214842 -146.845559) (xy 116.187474 -146.846036) (xy 116.160223 -146.845546) (xy 116.106277 -146.837787)
			(xy 116.053984 -146.82243) (xy 116.004409 -146.799788) (xy 115.95856 -146.770322) (xy 115.917371 -146.734631)
			(xy 115.88168 -146.693442) (xy 115.852213 -146.647593) (xy 115.829571 -146.598018) (xy 115.814213 -146.545725)
			(xy 115.806454 -146.491779) (xy 115.805966 -146.464528) (xy 103.84103 -146.464528) (xy 103.851191 -146.480339)
			(xy 103.873833 -146.529916) (xy 103.889188 -146.582211) (xy 103.896944 -146.636159) (xy 103.89743 -146.66341)
			(xy 103.897037 -146.689075) (xy 103.89016 -146.739942) (xy 103.876518 -146.789426) (xy 103.856359 -146.836632)
			(xy 103.830046 -146.880705) (xy 103.798057 -146.920847) (xy 103.760969 -146.956334) (xy 103.740458 -146.971766)
			(xy 103.729652 -146.980167) (xy 103.712661 -147.001617) (xy 103.701957 -147.026801) (xy 103.698306 -147.053921)
			(xy 103.701968 -147.081039) (xy 103.712682 -147.106219) (xy 103.729682 -147.127662) (xy 103.740458 -147.136104)
			(xy 103.764322 -147.154199) (xy 103.806639 -147.196573) (xy 103.841814 -147.24504) (xy 103.868982 -147.298409)
			(xy 103.887476 -147.355368) (xy 103.896841 -147.414517) (xy 103.89743 -147.44446) (xy 103.896944 -147.471711)
			(xy 103.889188 -147.525659) (xy 103.873833 -147.577954) (xy 103.851191 -147.627531) (xy 103.821725 -147.673381)
			(xy 103.786034 -147.714572) (xy 103.744843 -147.750263) (xy 103.698993 -147.779729) (xy 103.649416 -147.802371)
			(xy 103.597121 -147.817726) (xy 103.543173 -147.825482) (xy 103.488671 -147.825482) (xy 103.434723 -147.817726)
			(xy 103.382428 -147.802371) (xy 103.332851 -147.779729) (xy 103.287001 -147.750263) (xy 103.24581 -147.714572)
			(xy 103.210119 -147.673381) (xy 103.180653 -147.627531) (xy 103.158011 -147.577954) (xy 103.142656 -147.525659)
			(xy 103.1349 -147.471711) (xy 103.134414 -147.44446) (xy 102.778306 -147.44446) (xy 106.31798 -150.984134)
			(xy 109.251492 -150.984134) (xy 109.251492 -150.899438) (xy 109.259543 -150.815124) (xy 109.275572 -150.731958)
			(xy 109.299433 -150.650691) (xy 109.330912 -150.572061) (xy 109.369723 -150.49678) (xy 109.415513 -150.425528)
			(xy 109.467869 -150.358952) (xy 109.526317 -150.297654) (xy 109.590327 -150.242189) (xy 109.659319 -150.19306)
			(xy 109.732669 -150.150711) (xy 109.809712 -150.115527) (xy 109.889751 -150.087825) (xy 109.97206 -150.067857)
			(xy 110.055895 -150.055804) (xy 110.140496 -150.051774) (xy 110.225097 -150.055804) (xy 110.308932 -150.067857)
			(xy 110.391241 -150.087825) (xy 110.47128 -150.115527) (xy 110.548323 -150.150711) (xy 110.621673 -150.19306)
			(xy 110.690665 -150.242189) (xy 110.754675 -150.297654) (xy 110.813123 -150.358952) (xy 110.865479 -150.425528)
			(xy 110.911269 -150.49678) (xy 110.95008 -150.572061) (xy 110.981559 -150.650691) (xy 111.00542 -150.731958)
			(xy 111.021449 -150.815124) (xy 111.0295 -150.899438) (xy 111.030004 -150.941786) (xy 111.0295 -150.984134)
			(xy 111.751614 -150.984134) (xy 111.751614 -150.899438) (xy 111.759665 -150.815124) (xy 111.775694 -150.731958)
			(xy 111.799555 -150.650691) (xy 111.831034 -150.572061) (xy 111.869845 -150.49678) (xy 111.915635 -150.425528)
			(xy 111.967991 -150.358952) (xy 112.026439 -150.297654) (xy 112.090449 -150.242189) (xy 112.159441 -150.19306)
			(xy 112.232791 -150.150711) (xy 112.309834 -150.115527) (xy 112.389873 -150.087825) (xy 112.472182 -150.067857)
			(xy 112.556017 -150.055804) (xy 112.640618 -150.051774) (xy 112.725219 -150.055804) (xy 112.809054 -150.067857)
			(xy 112.891363 -150.087825) (xy 112.971402 -150.115527) (xy 113.048445 -150.150711) (xy 113.121795 -150.19306)
			(xy 113.190787 -150.242189) (xy 113.254797 -150.297654) (xy 113.313245 -150.358952) (xy 113.365601 -150.425528)
			(xy 113.411391 -150.49678) (xy 113.450202 -150.572061) (xy 113.481681 -150.650691) (xy 113.505542 -150.731958)
			(xy 113.521571 -150.815124) (xy 113.529622 -150.899438) (xy 113.530126 -150.941786) (xy 113.529622 -150.984134)
			(xy 113.521571 -151.068448) (xy 113.505542 -151.151614) (xy 113.481681 -151.232881) (xy 113.450202 -151.311511)
			(xy 113.411391 -151.386792) (xy 113.365601 -151.458044) (xy 113.313245 -151.52462) (xy 113.254797 -151.585918)
			(xy 113.190787 -151.641383) (xy 113.121795 -151.690512) (xy 113.048445 -151.732861) (xy 112.971402 -151.768045)
			(xy 112.891363 -151.795747) (xy 112.809054 -151.815715) (xy 112.725219 -151.827768) (xy 112.640618 -151.831799)
			(xy 112.556017 -151.827768) (xy 112.472182 -151.815715) (xy 112.389873 -151.795747) (xy 112.309834 -151.768045)
			(xy 112.232791 -151.732861) (xy 112.159441 -151.690512) (xy 112.090449 -151.641383) (xy 112.026439 -151.585918)
			(xy 111.967991 -151.52462) (xy 111.915635 -151.458044) (xy 111.869845 -151.386792) (xy 111.831034 -151.311511)
			(xy 111.799555 -151.232881) (xy 111.775694 -151.151614) (xy 111.759665 -151.068448) (xy 111.751614 -150.984134)
			(xy 111.0295 -150.984134) (xy 111.021449 -151.068448) (xy 111.00542 -151.151614) (xy 110.981559 -151.232881)
			(xy 110.95008 -151.311511) (xy 110.911269 -151.386792) (xy 110.865479 -151.458044) (xy 110.813123 -151.52462)
			(xy 110.754675 -151.585918) (xy 110.690665 -151.641383) (xy 110.621673 -151.690512) (xy 110.548323 -151.732861)
			(xy 110.47128 -151.768045) (xy 110.391241 -151.795747) (xy 110.308932 -151.815715) (xy 110.225097 -151.827768)
			(xy 110.140496 -151.831799) (xy 110.055895 -151.827768) (xy 109.97206 -151.815715) (xy 109.889751 -151.795747)
			(xy 109.809712 -151.768045) (xy 109.732669 -151.732861) (xy 109.659319 -151.690512) (xy 109.590327 -151.641383)
			(xy 109.526317 -151.585918) (xy 109.467869 -151.52462) (xy 109.415513 -151.458044) (xy 109.369723 -151.386792)
			(xy 109.330912 -151.311511) (xy 109.299433 -151.232881) (xy 109.275572 -151.151614) (xy 109.259543 -151.068448)
			(xy 109.251492 -150.984134) (xy 106.31798 -150.984134) (xy 107.991402 -152.657556) (xy 115.877086 -152.657556)
			(xy 115.877588 -152.630187) (xy 115.885398 -152.57601) (xy 115.900879 -152.523507) (xy 115.923712 -152.47376)
			(xy 115.953429 -152.427791) (xy 115.971066 -152.406858) (xy 115.977162 -152.399746) (xy 115.983512 -152.382728)
			(xy 115.983512 -152.297384) (xy 115.977162 -152.280366) (xy 115.971066 -152.273254) (xy 115.953433 -152.252317)
			(xy 115.923722 -152.206345) (xy 115.900885 -152.156599) (xy 115.885392 -152.104099) (xy 115.877562 -152.049925)
			(xy 115.877086 -152.022556) (xy 115.877537 -151.995304) (xy 115.885299 -151.941355) (xy 115.90066 -151.88906)
			(xy 115.923305 -151.839483) (xy 115.952776 -151.793633) (xy 115.988471 -151.752444) (xy 116.029664 -151.716753)
			(xy 116.075517 -151.687287) (xy 116.125096 -151.664646) (xy 116.177392 -151.649291) (xy 116.231342 -151.641534)
			(xy 116.258594 -151.641048) (xy 116.285965 -151.641506) (xy 116.340145 -151.649324) (xy 116.392648 -151.664814)
			(xy 116.442395 -151.687658) (xy 116.488361 -151.717385) (xy 116.509292 -151.735028) (xy 116.516404 -151.741124)
			(xy 116.533422 -151.747474) (xy 116.618766 -151.747474) (xy 116.635784 -151.741124) (xy 116.642896 -151.735028)
			(xy 116.663822 -151.717382) (xy 116.709796 -151.68767) (xy 116.759545 -151.664835) (xy 116.812047 -151.649346)
			(xy 116.866224 -151.64152) (xy 116.893594 -151.641048) (xy 116.922607 -151.64157) (xy 116.979966 -151.65034)
			(xy 117.035335 -151.667693) (xy 117.087439 -151.69323) (xy 117.135076 -151.726361) (xy 117.156484 -151.74595)
			(xy 117.163596 -151.752808) (xy 117.181376 -151.75992) (xy 117.271292 -151.75992) (xy 117.289072 -151.752808)
			(xy 117.296184 -151.74595) (xy 117.317594 -151.726366) (xy 117.365238 -151.693251) (xy 117.417343 -151.667723)
			(xy 117.472709 -151.650369) (xy 117.530063 -151.64159) (xy 117.559074 -151.641048) (xy 117.586444 -151.641518)
			(xy 117.640624 -151.649333) (xy 117.693127 -151.66482) (xy 117.742874 -151.687662) (xy 117.788841 -151.717386)
			(xy 117.809772 -151.735028) (xy 117.816884 -151.741124) (xy 117.833902 -151.747474) (xy 117.919246 -151.747474)
			(xy 117.936264 -151.741124) (xy 117.943376 -151.735028) (xy 117.964309 -151.717387) (xy 118.010277 -151.687663)
			(xy 118.060023 -151.664817) (xy 118.112525 -151.649321) (xy 118.166703 -151.641492) (xy 118.221445 -151.641492)
			(xy 118.275623 -151.649321) (xy 118.328125 -151.664817) (xy 118.377871 -151.687663) (xy 118.423839 -151.717387)
			(xy 118.444772 -151.735028) (xy 118.451884 -151.741124) (xy 118.468902 -151.747474) (xy 118.554246 -151.747474)
			(xy 118.571264 -151.741124) (xy 118.578376 -151.735028) (xy 118.599309 -151.717387) (xy 118.645277 -151.687663)
			(xy 118.695023 -151.664817) (xy 118.747525 -151.649321) (xy 118.801703 -151.641492) (xy 118.856445 -151.641492)
			(xy 118.910623 -151.649321) (xy 118.963125 -151.664817) (xy 119.012871 -151.687663) (xy 119.058839 -151.717387)
			(xy 119.079772 -151.735028) (xy 119.086884 -151.741124) (xy 119.103902 -151.747474) (xy 119.189246 -151.747474)
			(xy 119.206264 -151.741124) (xy 119.213376 -151.735028) (xy 119.23431 -151.717391) (xy 119.280282 -151.687678)
			(xy 119.330029 -151.664841) (xy 119.382529 -151.64935) (xy 119.436705 -151.641522) (xy 119.464074 -151.641048)
			(xy 119.491323 -151.641602) (xy 119.545266 -151.649354) (xy 119.597556 -151.664704) (xy 119.64713 -151.687339)
			(xy 119.692979 -151.716798) (xy 119.734168 -151.752482) (xy 119.76986 -151.793665) (xy 119.799328 -151.839508)
			(xy 119.821972 -151.889078) (xy 119.837331 -151.941366) (xy 119.845093 -151.995308) (xy 119.845582 -152.022556)
			(xy 119.845095 -152.049926) (xy 119.837283 -152.104104) (xy 119.821799 -152.156607) (xy 119.798962 -152.206354)
			(xy 119.769241 -152.252322) (xy 119.751602 -152.273254) (xy 119.745506 -152.280366) (xy 119.739156 -152.297384)
			(xy 119.739156 -152.382728) (xy 119.745506 -152.399746) (xy 119.751602 -152.406858) (xy 119.769235 -152.427795)
			(xy 119.798948 -152.473766) (xy 119.821785 -152.523513) (xy 119.837277 -152.576012) (xy 119.845107 -152.630187)
			(xy 119.845582 -152.657556) (xy 119.845104 -152.684809) (xy 119.837352 -152.738761) (xy 119.822 -152.79106)
			(xy 119.799361 -152.840642) (xy 119.769895 -152.886496) (xy 119.734203 -152.92769) (xy 119.693011 -152.963384)
			(xy 119.647157 -152.992852) (xy 119.597577 -153.015494) (xy 119.545278 -153.030848) (xy 119.491327 -153.038602)
			(xy 119.464074 -153.039064) (xy 119.436703 -153.038622) (xy 119.382522 -153.0308) (xy 119.330019 -153.015305)
			(xy 119.280272 -152.992458) (xy 119.234307 -152.962728) (xy 119.213376 -152.945084) (xy 119.206264 -152.938988)
			(xy 119.189246 -152.932638) (xy 119.103902 -152.932638) (xy 119.086884 -152.938988) (xy 119.079772 -152.945084)
			(xy 119.058839 -152.962725) (xy 119.012871 -152.992449) (xy 118.963125 -153.015295) (xy 118.910623 -153.030791)
			(xy 118.856445 -153.03862) (xy 118.801703 -153.03862) (xy 118.747525 -153.030791) (xy 118.695023 -153.015295)
			(xy 118.645277 -152.992449) (xy 118.599309 -152.962725) (xy 118.578376 -152.945084) (xy 118.571264 -152.938988)
			(xy 118.554246 -152.932638) (xy 118.468902 -152.932638) (xy 118.451884 -152.938988) (xy 118.444772 -152.945084)
			(xy 118.423839 -152.962725) (xy 118.377871 -152.992449) (xy 118.328125 -153.015295) (xy 118.275623 -153.030791)
			(xy 118.221445 -153.03862) (xy 118.166703 -153.03862) (xy 118.112525 -153.030791) (xy 118.060023 -153.015295)
			(xy 118.010277 -152.992449) (xy 117.964309 -152.962725) (xy 117.943376 -152.945084) (xy 117.936264 -152.938988)
			(xy 117.919246 -152.932638) (xy 117.833902 -152.932638) (xy 117.816884 -152.938988) (xy 117.809772 -152.945084)
			(xy 117.788822 -152.9627) (xy 117.742854 -152.992416) (xy 117.693111 -153.015257) (xy 117.640615 -153.030753)
			(xy 117.586442 -153.038587) (xy 117.559074 -153.039064) (xy 117.530061 -153.038558) (xy 117.472701 -153.029784)
			(xy 117.417332 -153.012427) (xy 117.365228 -152.986886) (xy 117.317592 -152.953752) (xy 117.296184 -152.934162)
			(xy 117.289072 -152.927304) (xy 117.271292 -152.920192) (xy 117.181376 -152.920192) (xy 117.163596 -152.927304)
			(xy 117.156484 -152.934162) (xy 117.135089 -152.953763) (xy 117.087441 -152.986876) (xy 117.035332 -153.0124)
			(xy 116.979963 -153.029749) (xy 116.922606 -153.038525) (xy 116.893594 -153.039064) (xy 116.866223 -153.03861)
			(xy 116.812043 -153.030791) (xy 116.75954 -153.015299) (xy 116.709793 -152.992455) (xy 116.663827 -152.962727)
			(xy 116.642896 -152.945084) (xy 116.635784 -152.938988) (xy 116.618766 -152.932638) (xy 116.533422 -152.932638)
			(xy 116.516404 -152.938988) (xy 116.509292 -152.945084) (xy 116.488372 -152.962738) (xy 116.442396 -152.992448)
			(xy 116.392645 -153.015281) (xy 116.340142 -153.030769) (xy 116.285964 -153.038593) (xy 116.258594 -153.039064)
			(xy 116.231339 -153.03865) (xy 116.177384 -153.030891) (xy 116.125083 -153.015532) (xy 116.075499 -152.992886)
			(xy 116.029644 -152.963413) (xy 115.988451 -152.927714) (xy 115.952757 -152.886516) (xy 115.92329 -152.840657)
			(xy 115.90065 -152.791071) (xy 115.885298 -152.738767) (xy 115.877546 -152.684811) (xy 115.877086 -152.657556)
			(xy 107.991402 -152.657556) (xy 116.206016 -160.87217) (xy 116.21342 -160.879005) (xy 116.232016 -160.886729)
			(xy 116.242084 -160.887156) (xy 117.515386 -160.887156) (xy 117.525456 -160.886735) (xy 117.544054 -160.879012)
			(xy 117.551454 -160.87217) (xy 119.240046 -159.183578) (xy 119.25817 -159.166372) (xy 119.299724 -159.138626)
			(xy 119.34589 -159.119514) (xy 119.394895 -159.109769) (xy 119.419878 -159.109156) (xy 124.465334 -159.109156)
			(xy 124.490318 -159.109763) (xy 124.539326 -159.119508) (xy 124.585496 -159.138616) (xy 124.627056 -159.166356)
			(xy 124.645166 -159.183578) (xy 124.891292 -159.42945) (xy 124.898653 -159.436219) (xy 124.917115 -159.443866)
			(xy 124.937097 -159.443866) (xy 124.955559 -159.436219) (xy 124.96292 -159.42945) (xy 126.135638 -158.256986)
			(xy 126.142482 -158.249589) (xy 126.150198 -158.230987) (xy 126.150624 -158.220918) (xy 126.150624 -153.26741)
			(xy 126.151267 -153.242428) (xy 126.161002 -153.193422) (xy 126.1801 -153.147253) (xy 126.207829 -153.10569)
			(xy 126.225046 -153.087578) (xy 128.892046 -150.420578) (xy 128.91017 -150.403372) (xy 128.951724 -150.375626)
			(xy 128.99789 -150.356514) (xy 129.046895 -150.346769) (xy 129.071878 -150.346156) (xy 133.008878 -150.346156)
			(xy 133.033863 -150.346737) (xy 133.082873 -150.356489) (xy 133.129042 -150.375606) (xy 133.170601 -150.403353)
			(xy 133.18871 -150.420578) (xy 133.30174 -150.533608) (xy 136.287 -150.533608) (xy 136.291071 -150.477986)
			(xy 136.303197 -150.423549) (xy 136.32312 -150.371458) (xy 136.350416 -150.322823) (xy 136.384502 -150.27868)
			(xy 136.424651 -150.239971) (xy 136.470009 -150.20752) (xy 136.519609 -150.182019) (xy 136.572393 -150.164012)
			(xy 136.627236 -150.153882) (xy 136.68297 -150.151845) (xy 136.738407 -150.157945) (xy 136.792364 -150.172051)
			(xy 136.843693 -150.193863) (xy 136.891299 -150.222917) (xy 136.934167 -150.258592) (xy 136.971384 -150.300129)
			(xy 137.002157 -150.346642) (xy 137.025829 -150.397139) (xy 137.041897 -150.450546) (xy 137.050017 -150.505722)
			(xy 137.050526 -150.533608) (xy 137.050017 -150.561494) (xy 137.041897 -150.61667) (xy 137.033492 -150.644606)
			(xy 137.304016 -150.644606) (xy 137.308087 -150.588984) (xy 137.320213 -150.534547) (xy 137.340136 -150.482456)
			(xy 137.367432 -150.433821) (xy 137.401518 -150.389678) (xy 137.441667 -150.350969) (xy 137.487025 -150.318518)
			(xy 137.536625 -150.293017) (xy 137.589409 -150.27501) (xy 137.644252 -150.26488) (xy 137.699986 -150.262843)
			(xy 137.755423 -150.268943) (xy 137.80938 -150.283049) (xy 137.860709 -150.304861) (xy 137.908315 -150.333915)
			(xy 137.951183 -150.36959) (xy 137.9884 -150.411127) (xy 138.019173 -150.45764) (xy 138.042845 -150.508137)
			(xy 138.058913 -150.561544) (xy 138.067033 -150.61672) (xy 138.067542 -150.644606) (xy 138.067033 -150.672492)
			(xy 138.058913 -150.727668) (xy 138.042845 -150.781075) (xy 138.019173 -150.831572) (xy 137.9884 -150.878085)
			(xy 137.951183 -150.919622) (xy 137.908315 -150.955297) (xy 137.860709 -150.984351) (xy 137.80938 -151.006163)
			(xy 137.755423 -151.020269) (xy 137.699986 -151.026369) (xy 137.644252 -151.024332) (xy 137.589409 -151.014202)
			(xy 137.536625 -150.996195) (xy 137.487025 -150.970694) (xy 137.441667 -150.938243) (xy 137.401518 -150.899534)
			(xy 137.367432 -150.855391) (xy 137.340136 -150.806756) (xy 137.320213 -150.754665) (xy 137.308087 -150.700228)
			(xy 137.304016 -150.644606) (xy 137.033492 -150.644606) (xy 137.025829 -150.670077) (xy 137.002157 -150.720574)
			(xy 136.971384 -150.767087) (xy 136.934167 -150.808624) (xy 136.891299 -150.844299) (xy 136.843693 -150.873353)
			(xy 136.792364 -150.895165) (xy 136.738407 -150.909271) (xy 136.68297 -150.915371) (xy 136.627236 -150.913334)
			(xy 136.572393 -150.903204) (xy 136.519609 -150.885197) (xy 136.470009 -150.859696) (xy 136.424651 -150.827245)
			(xy 136.384502 -150.788536) (xy 136.350416 -150.744393) (xy 136.32312 -150.695758) (xy 136.303197 -150.643667)
			(xy 136.291071 -150.58923) (xy 136.287 -150.533608) (xy 133.30174 -150.533608) (xy 133.565138 -150.797006)
			(xy 133.582375 -150.815103) (xy 133.610114 -150.856666) (xy 133.629218 -150.90284) (xy 133.638953 -150.951853)
			(xy 133.63956 -150.976838) (xy 133.63956 -152.07869) (xy 134.023354 -152.07869) (xy 134.02384 -152.051439)
			(xy 134.031596 -151.997491) (xy 134.046951 -151.945196) (xy 134.069593 -151.895619) (xy 134.099059 -151.849769)
			(xy 134.13475 -151.808578) (xy 134.175941 -151.772887) (xy 134.221791 -151.743421) (xy 134.271368 -151.720779)
			(xy 134.323663 -151.705424) (xy 134.377611 -151.697668) (xy 134.432113 -151.697668) (xy 134.486061 -151.705424)
			(xy 134.538356 -151.720779) (xy 134.587933 -151.743421) (xy 134.633783 -151.772887) (xy 134.674974 -151.808578)
			(xy 134.710665 -151.849769) (xy 134.740131 -151.895619) (xy 134.762773 -151.945196) (xy 134.778128 -151.997491)
			(xy 134.785884 -152.051439) (xy 134.78637 -152.07869) (xy 134.785938 -152.104179) (xy 134.779161 -152.154704)
			(xy 134.765712 -152.203876) (xy 134.745833 -152.250818) (xy 134.719877 -152.294693) (xy 134.688307 -152.334719)
			(xy 134.670292 -152.352756) (xy 134.662418 -152.360376) (xy 134.654544 -152.380188) (xy 134.657338 -152.476454)
			(xy 134.666482 -152.495758) (xy 134.67461 -152.50287) (xy 134.695019 -152.52108) (xy 134.730949 -152.562319)
			(xy 134.760621 -152.608266) (xy 134.783427 -152.65798) (xy 134.7989 -152.710441) (xy 134.806722 -152.764574)
			(xy 134.807198 -152.791922) (xy 134.806712 -152.819173) (xy 134.798956 -152.873121) (xy 134.783601 -152.925416)
			(xy 134.760959 -152.974993) (xy 134.731493 -153.020843) (xy 134.695802 -153.062034) (xy 134.654611 -153.097725)
			(xy 134.608761 -153.127191) (xy 134.559184 -153.149833) (xy 134.506889 -153.165188) (xy 134.452941 -153.172944)
			(xy 134.398439 -153.172944) (xy 134.344491 -153.165188) (xy 134.292196 -153.149833) (xy 134.242619 -153.127191)
			(xy 134.196769 -153.097725) (xy 134.155578 -153.062034) (xy 134.119887 -153.020843) (xy 134.090421 -152.974993)
			(xy 134.067779 -152.925416) (xy 134.052424 -152.873121) (xy 134.044668 -152.819173) (xy 134.044182 -152.791922)
			(xy 134.044637 -152.766434) (xy 134.051411 -152.71591) (xy 134.064856 -152.666739) (xy 134.084731 -152.619797)
			(xy 134.110683 -152.575922) (xy 134.142248 -152.535894) (xy 134.16026 -152.517856) (xy 134.168134 -152.510236)
			(xy 134.176008 -152.490424) (xy 134.173214 -152.394158) (xy 134.16407 -152.374854) (xy 134.155942 -152.367742)
			(xy 134.135549 -152.349514) (xy 134.099616 -152.30828) (xy 134.06994 -152.262337) (xy 134.047131 -152.212627)
			(xy 134.031655 -152.160168) (xy 134.023831 -152.106037) (xy 134.023354 -152.07869) (xy 133.63956 -152.07869)
			(xy 133.63956 -152.291542) (xy 133.640014 -152.301547) (xy 133.647737 -152.320011) (xy 133.654546 -152.327356)
			(xy 133.67543 -152.348974) (xy 133.710844 -152.397537) (xy 133.738201 -152.451054) (xy 133.756824 -152.5082)
			(xy 133.766251 -152.56756) (xy 133.766814 -152.597612) (xy 133.766333 -152.624863) (xy 133.758575 -152.678811)
			(xy 133.743219 -152.731105) (xy 133.720577 -152.780682) (xy 133.69111 -152.826532) (xy 133.655418 -152.867722)
			(xy 133.614227 -152.903414) (xy 133.568377 -152.93288) (xy 133.5188 -152.955521) (xy 133.466505 -152.970877)
			(xy 133.412557 -152.978634) (xy 133.385306 -152.97912) (xy 133.360071 -152.978718) (xy 133.310037 -152.972101)
			(xy 133.261317 -152.958929) (xy 133.214765 -152.939434) (xy 133.192774 -152.92705) (xy 133.183122 -152.921208)
			(xy 133.161024 -152.919176) (xy 133.066536 -152.952704) (xy 133.050534 -152.968198) (xy 133.04647 -152.978612)
			(xy 133.035739 -153.005373) (xy 133.007455 -153.055613) (xy 132.97193 -153.101022) (xy 132.929973 -153.140565)
			(xy 132.882541 -153.17334) (xy 132.830715 -153.198601) (xy 132.775677 -153.215771) (xy 132.718681 -153.224459)
			(xy 132.689854 -153.224992) (xy 132.662601 -153.224565) (xy 132.60865 -153.216802) (xy 132.556353 -153.20144)
			(xy 132.506775 -153.178792) (xy 132.460924 -153.14932) (xy 132.419734 -153.113622) (xy 132.384043 -153.072426)
			(xy 132.354578 -153.026571) (xy 132.331938 -152.976988) (xy 132.316585 -152.924689) (xy 132.308831 -152.870737)
			(xy 132.308346 -152.843484) (xy 132.309009 -152.811921) (xy 132.319394 -152.749656) (xy 132.339879 -152.689947)
			(xy 132.35432 -152.661874) (xy 132.359146 -152.652984) (xy 132.361178 -152.633426) (xy 132.335524 -152.545288)
			(xy 132.323078 -152.529794) (xy 132.314188 -152.524714) (xy 132.289062 -152.510206) (xy 132.24318 -152.474696)
			(xy 132.203207 -152.432645) (xy 132.170065 -152.385024) (xy 132.144518 -152.332933) (xy 132.127157 -152.277572)
			(xy 132.118382 -152.220221) (xy 132.117846 -152.191212) (xy 132.118332 -152.163961) (xy 132.126088 -152.110013)
			(xy 132.141443 -152.057718) (xy 132.164085 -152.008141) (xy 132.193551 -151.962291) (xy 132.229242 -151.9211)
			(xy 132.270433 -151.885409) (xy 132.316283 -151.855943) (xy 132.36586 -151.833301) (xy 132.418155 -151.817946)
			(xy 132.472103 -151.81019) (xy 132.526605 -151.81019) (xy 132.580553 -151.817946) (xy 132.632848 -151.833301)
			(xy 132.682425 -151.855943) (xy 132.728275 -151.885409) (xy 132.769466 -151.9211) (xy 132.805157 -151.962291)
			(xy 132.834623 -152.008141) (xy 132.857265 -152.057718) (xy 132.87262 -152.110013) (xy 132.880376 -152.163961)
			(xy 132.880862 -152.191212) (xy 132.880196 -152.222775) (xy 132.869812 -152.28504) (xy 132.849329 -152.344749)
			(xy 132.834888 -152.372822) (xy 132.830062 -152.381712) (xy 132.82803 -152.40127) (xy 132.853684 -152.489408)
			(xy 132.86613 -152.504902) (xy 132.87502 -152.509982) (xy 132.882386 -152.514046) (xy 132.892038 -152.519888)
			(xy 132.914136 -152.52192) (xy 133.008624 -152.488392) (xy 133.024626 -152.472898) (xy 133.02869 -152.462484)
			(xy 133.038701 -152.437368) (xy 133.064775 -152.390003) (xy 133.097267 -152.346789) (xy 133.116066 -152.327356)
			(xy 133.122776 -152.319941) (xy 133.130506 -152.301525) (xy 133.131052 -152.291542) (xy 133.131052 -151.10333)
			(xy 133.130624 -151.093261) (xy 133.122906 -151.074662) (xy 133.116066 -151.067262) (xy 132.918454 -150.86965)
			(xy 132.911024 -150.862848) (xy 132.892448 -150.855105) (xy 132.882386 -150.854664) (xy 129.19837 -150.854664)
			(xy 129.188297 -150.855057) (xy 129.169698 -150.862798) (xy 129.162302 -150.86965) (xy 126.674118 -153.357834)
			(xy 126.667273 -153.36523) (xy 126.659555 -153.383832) (xy 126.659132 -153.393902) (xy 126.659132 -154.465274)
			(xy 128.331722 -154.465274) (xy 128.332231 -154.437701) (xy 128.340174 -154.38313) (xy 128.35589 -154.33027)
			(xy 128.379051 -154.280224) (xy 128.409177 -154.234033) (xy 128.445638 -154.192661) (xy 128.466342 -154.174444)
			(xy 128.474443 -154.166826) (xy 128.483805 -154.146686) (xy 128.484376 -154.135582) (xy 128.484376 -154.058366)
			(xy 128.483851 -154.047251) (xy 128.474483 -154.027092) (xy 128.466342 -154.019504) (xy 128.445609 -154.001318)
			(xy 128.409141 -153.959944) (xy 128.379012 -153.913751) (xy 128.355848 -153.8637) (xy 128.340133 -153.810835)
			(xy 128.332193 -153.756259) (xy 128.332196 -153.701108) (xy 128.34014 -153.646532) (xy 128.35586 -153.593669)
			(xy 128.379028 -153.54362) (xy 128.409162 -153.497429) (xy 128.445633 -153.456059) (xy 128.466342 -153.437844)
			(xy 128.474443 -153.430226) (xy 128.483805 -153.410086) (xy 128.484376 -153.398982) (xy 128.484376 -153.321766)
			(xy 128.483851 -153.310651) (xy 128.474483 -153.290492) (xy 128.466342 -153.282904) (xy 128.445638 -153.264685)
			(xy 128.409165 -153.223319) (xy 128.379031 -153.177131) (xy 128.355864 -153.127084) (xy 128.340147 -153.074223)
			(xy 128.332207 -153.019648) (xy 128.331722 -152.992074) (xy 128.332131 -152.964819) (xy 128.339892 -152.910865)
			(xy 128.355253 -152.858564) (xy 128.377901 -152.808982) (xy 128.407374 -152.763127) (xy 128.443074 -152.721934)
			(xy 128.484272 -152.686241) (xy 128.530131 -152.656774) (xy 128.579716 -152.634133) (xy 128.632019 -152.61878)
			(xy 128.685975 -152.611027) (xy 128.71323 -152.610566) (xy 128.741085 -152.611087) (xy 128.796199 -152.619214)
			(xy 128.849548 -152.635262) (xy 128.9 -152.65889) (xy 128.946483 -152.689597) (xy 128.988012 -152.726732)
			(xy 129.023706 -152.769506) (xy 129.052806 -152.817012) (xy 129.074696 -152.868242) (xy 129.082292 -152.895046)
			(xy 129.084578 -152.903936) (xy 129.095246 -152.919176) (xy 129.167128 -152.966928) (xy 129.185162 -152.970992)
			(xy 129.194306 -152.969722) (xy 129.207323 -152.968054) (xy 129.233507 -152.966273) (xy 129.24663 -152.966166)
			(xy 129.260779 -152.966257) (xy 129.289002 -152.968293) (xy 129.303018 -152.97023) (xy 129.313178 -152.971754)
			(xy 129.332736 -152.966928) (xy 129.407158 -152.911048) (xy 129.417318 -152.893522) (xy 129.418588 -152.883362)
			(xy 129.422677 -152.856208) (xy 129.437649 -152.803378) (xy 129.46004 -152.753239) (xy 129.489387 -152.706828)
			(xy 129.525085 -152.665104) (xy 129.566394 -152.628927) (xy 129.612463 -152.599046) (xy 129.66234 -152.576077)
			(xy 129.714994 -152.560496) (xy 129.769338 -152.552624) (xy 129.796794 -152.552146) (xy 129.824043 -152.552683)
			(xy 129.877987 -152.560438) (xy 129.930277 -152.57579) (xy 129.979852 -152.598427) (xy 130.0257 -152.627888)
			(xy 130.066889 -152.663574) (xy 130.102581 -152.704758) (xy 130.132048 -152.750603) (xy 130.154692 -152.800174)
			(xy 130.170051 -152.852463) (xy 130.177813 -152.906405) (xy 130.178302 -152.933654) (xy 130.177804 -152.961227)
			(xy 130.169858 -153.015799) (xy 130.154139 -153.068658) (xy 130.130975 -153.118704) (xy 130.100849 -153.164894)
			(xy 130.064387 -153.206267) (xy 130.043682 -153.224484) (xy 130.035573 -153.232095) (xy 130.026214 -153.25224)
			(xy 130.025648 -153.263346) (xy 130.025648 -153.340562) (xy 130.026206 -153.351673) (xy 130.03555 -153.371833)
			(xy 130.043682 -153.379424) (xy 130.064404 -153.397623) (xy 130.100875 -153.438994) (xy 130.131006 -153.485186)
			(xy 130.15417 -153.535237) (xy 130.169883 -153.588102) (xy 130.177819 -153.642678) (xy 130.178302 -153.670254)
			(xy 130.177802 -153.697506) (xy 130.170051 -153.751456) (xy 130.154701 -153.803753) (xy 130.132063 -153.853334)
			(xy 130.102599 -153.899187) (xy 130.066909 -153.940381) (xy 130.02572 -153.976075) (xy 129.979869 -154.005544)
			(xy 129.930291 -154.028187) (xy 129.877995 -154.043543) (xy 129.824046 -154.051299) (xy 129.796794 -154.051762)
			(xy 129.762504 -154.050238) (xy 129.752344 -154.049222) (xy 129.73304 -154.055318) (xy 129.662428 -154.1145)
			(xy 129.65303 -154.132534) (xy 129.652014 -154.142694) (xy 129.649102 -154.170872) (xy 129.635921 -154.225965)
			(xy 129.614737 -154.278502) (xy 129.586014 -154.327328) (xy 129.550385 -154.371368) (xy 129.508633 -154.409654)
			(xy 129.461678 -154.441342) (xy 129.410552 -154.465737) (xy 129.35638 -154.482301) (xy 129.300354 -154.49067)
			(xy 129.27203 -154.491182) (xy 129.254011 -154.490966) (xy 129.218136 -154.487528) (xy 129.200402 -154.484324)
			(xy 129.191004 -154.482546) (xy 129.171954 -154.486356) (xy 129.09677 -154.534108) (xy 129.08534 -154.549856)
			(xy 129.083054 -154.559254) (xy 129.075689 -154.586308) (xy 129.054056 -154.638036) (xy 129.025088 -154.686042)
			(xy 128.989409 -154.729294) (xy 128.947785 -154.766861) (xy 128.901113 -154.797934) (xy 128.850398 -154.821844)
			(xy 128.79673 -154.838078) (xy 128.741265 -154.846285) (xy 128.71323 -154.846782) (xy 128.685977 -154.846317)
			(xy 128.632024 -154.838563) (xy 128.579725 -154.82321) (xy 128.530143 -154.800569) (xy 128.484289 -154.771101)
			(xy 128.443095 -154.735408) (xy 128.407401 -154.694214) (xy 128.377933 -154.64836) (xy 128.355292 -154.598779)
			(xy 128.339938 -154.546479) (xy 128.332184 -154.492527) (xy 128.331722 -154.465274) (xy 126.659132 -154.465274)
			(xy 126.659132 -155.94076) (xy 129.92354 -155.94076) (xy 129.924033 -155.913186) (xy 129.931978 -155.858614)
			(xy 129.947697 -155.805754) (xy 129.970862 -155.755708) (xy 130.00099 -155.709517) (xy 130.037454 -155.668146)
			(xy 130.05816 -155.64993) (xy 130.06627 -155.64232) (xy 130.075626 -155.622174) (xy 130.076194 -155.611068)
			(xy 130.076194 -155.533852) (xy 130.075614 -155.522744) (xy 130.066284 -155.502585) (xy 130.05816 -155.49499)
			(xy 130.037433 -155.476797) (xy 130.000965 -155.435423) (xy 129.970836 -155.389229) (xy 129.947674 -155.339178)
			(xy 129.93196 -155.286313) (xy 129.924024 -155.231736) (xy 129.92354 -155.20416) (xy 129.923989 -155.177973)
			(xy 129.93117 -155.126093) (xy 129.945377 -155.075683) (xy 129.966344 -155.027688) (xy 129.993677 -154.983012)
			(xy 130.026862 -154.942493) (xy 130.065276 -154.906892) (xy 130.108198 -154.876878) (xy 130.131312 -154.864562)
			(xy 130.140456 -154.859736) (xy 130.153664 -154.843988) (xy 130.180842 -154.754072) (xy 130.178556 -154.733752)
			(xy 130.173476 -154.724608) (xy 130.158585 -154.696638) (xy 130.137512 -154.636883) (xy 130.126844 -154.574425)
			(xy 130.126232 -154.542744) (xy 130.126675 -154.516125) (xy 130.134247 -154.463428) (xy 130.149242 -154.412346)
			(xy 130.171355 -154.363918) (xy 130.200137 -154.31913) (xy 130.235 -154.278896) (xy 130.275235 -154.244033)
			(xy 130.320023 -154.215252) (xy 130.368451 -154.19314) (xy 130.419534 -154.178145) (xy 130.472231 -154.170575)
			(xy 130.49885 -154.170126) (xy 130.525272 -154.170572) (xy 130.577587 -154.178028) (xy 130.628325 -154.192796)
			(xy 130.676469 -154.214582) (xy 130.721054 -154.242948) (xy 130.74142 -154.259788) (xy 130.748278 -154.265884)
			(xy 130.765296 -154.27198) (xy 130.849624 -154.27198) (xy 130.866642 -154.265884) (xy 130.8735 -154.259788)
			(xy 130.893866 -154.242949) (xy 130.938452 -154.214584) (xy 130.986596 -154.192797) (xy 131.037333 -154.178026)
			(xy 131.089648 -154.170566) (xy 131.142492 -154.170566) (xy 131.194807 -154.178026) (xy 131.245544 -154.192797)
			(xy 131.293688 -154.214584) (xy 131.338274 -154.242949) (xy 131.35864 -154.259788) (xy 131.365498 -154.265884)
			(xy 131.382516 -154.27198) (xy 131.466844 -154.27198) (xy 131.483862 -154.265884) (xy 131.49072 -154.259788)
			(xy 131.511077 -154.242939) (xy 131.555669 -154.214586) (xy 131.603816 -154.192809) (xy 131.654554 -154.178044)
			(xy 131.706869 -154.170586) (xy 131.73329 -154.170126) (xy 131.761181 -154.170532) (xy 131.816339 -154.178845)
			(xy 131.869642 -154.195285) (xy 131.919899 -154.219487) (xy 131.965988 -154.250909) (xy 132.006879 -154.288849)
			(xy 132.041659 -154.33246) (xy 132.06955 -154.380767) (xy 132.089929 -154.432692) (xy 132.102342 -154.487075)
			(xy 132.106511 -154.5427) (xy 132.102342 -154.598325) (xy 132.089929 -154.652708) (xy 132.06955 -154.704633)
			(xy 132.041659 -154.75294) (xy 132.006879 -154.796551) (xy 131.965988 -154.834491) (xy 131.919899 -154.865913)
			(xy 131.869642 -154.890115) (xy 131.816339 -154.906555) (xy 131.761181 -154.914868) (xy 131.73329 -154.915362)
			(xy 131.706869 -154.914895) (xy 131.654554 -154.907445) (xy 131.603816 -154.892682) (xy 131.555672 -154.8709)
			(xy 131.511086 -154.842538) (xy 131.49072 -154.8257) (xy 131.483862 -154.819604) (xy 131.466844 -154.813508)
			(xy 131.382516 -154.813508) (xy 131.365498 -154.819604) (xy 131.35864 -154.8257) (xy 131.338274 -154.842539)
			(xy 131.293688 -154.870904) (xy 131.245544 -154.892691) (xy 131.194807 -154.907462) (xy 131.142492 -154.914922)
			(xy 131.089648 -154.914922) (xy 131.037333 -154.907462) (xy 130.986596 -154.892691) (xy 130.938452 -154.870904)
			(xy 130.893866 -154.842539) (xy 130.8735 -154.8257) (xy 130.866642 -154.819604) (xy 130.849624 -154.813508)
			(xy 130.765296 -154.813508) (xy 130.748278 -154.819604) (xy 130.74142 -154.8257) (xy 130.725853 -154.838706)
			(xy 130.692378 -154.861619) (xy 130.674618 -154.87142) (xy 130.665474 -154.876246) (xy 130.65252 -154.892248)
			(xy 130.626866 -154.982672) (xy 130.629406 -155.002992) (xy 130.63474 -155.012136) (xy 130.647068 -155.034075)
			(xy 130.666446 -155.08052) (xy 130.679551 -155.129108) (xy 130.686158 -155.178997) (xy 130.686556 -155.20416)
			(xy 130.686078 -155.231734) (xy 130.67813 -155.286307) (xy 130.662409 -155.339168) (xy 130.639241 -155.389214)
			(xy 130.60911 -155.435404) (xy 130.572643 -155.476775) (xy 130.551936 -155.49499) (xy 130.543816 -155.502591)
			(xy 130.534465 -155.522744) (xy 130.533902 -155.533852) (xy 130.533902 -155.611068) (xy 130.534471 -155.622178)
			(xy 130.543809 -155.642336) (xy 130.551936 -155.64993) (xy 130.572672 -155.668114) (xy 130.609139 -155.709489)
			(xy 130.639267 -155.755685) (xy 130.662428 -155.805738) (xy 130.67814 -155.858605) (xy 130.686074 -155.913184)
			(xy 130.686556 -155.94076) (xy 130.68607 -155.968011) (xy 130.678314 -156.021959) (xy 130.662959 -156.074254)
			(xy 130.640317 -156.123831) (xy 130.610851 -156.169681) (xy 130.57516 -156.210872) (xy 130.533969 -156.246563)
			(xy 130.488119 -156.276029) (xy 130.438542 -156.298671) (xy 130.386247 -156.314026) (xy 130.332299 -156.321782)
			(xy 130.277797 -156.321782) (xy 130.223849 -156.314026) (xy 130.171554 -156.298671) (xy 130.121977 -156.276029)
			(xy 130.076127 -156.246563) (xy 130.034936 -156.210872) (xy 129.999245 -156.169681) (xy 129.969779 -156.123831)
			(xy 129.947137 -156.074254) (xy 129.931782 -156.021959) (xy 129.924026 -155.968011) (xy 129.92354 -155.94076)
			(xy 126.659132 -155.94076) (xy 126.659132 -158.34741) (xy 126.658513 -158.372393) (xy 126.648773 -158.421401)
			(xy 126.629668 -158.467571) (xy 126.601931 -158.509132) (xy 126.58471 -158.527242) (xy 125.196346 -159.915606)
			(xy 125.189517 -159.923015) (xy 125.181789 -159.941607) (xy 125.18136 -159.951674) (xy 125.18136 -160.73501)
			(xy 125.549914 -160.73501) (xy 125.5504 -160.707759) (xy 125.558156 -160.653811) (xy 125.573511 -160.601516)
			(xy 125.596153 -160.551939) (xy 125.625619 -160.506089) (xy 125.66131 -160.464898) (xy 125.702501 -160.429207)
			(xy 125.748351 -160.399741) (xy 125.797928 -160.377099) (xy 125.850223 -160.361744) (xy 125.904171 -160.353988)
			(xy 125.958673 -160.353988) (xy 126.012621 -160.361744) (xy 126.064916 -160.377099) (xy 126.114493 -160.399741)
			(xy 126.160343 -160.429207) (xy 126.201534 -160.464898) (xy 126.237225 -160.506089) (xy 126.266691 -160.551939)
			(xy 126.289333 -160.601516) (xy 126.304688 -160.653811) (xy 126.312444 -160.707759) (xy 126.31293 -160.73501)
			(xy 126.312484 -160.761804) (xy 126.304979 -160.814864) (xy 126.290129 -160.866354) (xy 126.268229 -160.915263)
			(xy 126.239707 -160.960631) (xy 126.22276 -160.98139) (xy 126.216664 -160.988502) (xy 126.210568 -161.00552)
			(xy 126.212092 -161.091372) (xy 126.21895 -161.108136) (xy 126.2253 -161.115248) (xy 126.243886 -161.136439)
			(xy 126.275271 -161.183257) (xy 126.299425 -161.234183) (xy 126.315825 -161.288108) (xy 126.324111 -161.34386)
			(xy 126.324614 -161.372042) (xy 126.324128 -161.399293) (xy 126.316372 -161.453241) (xy 126.301017 -161.505536)
			(xy 126.278375 -161.555113) (xy 126.248909 -161.600963) (xy 126.213218 -161.642154) (xy 126.172027 -161.677845)
			(xy 126.126177 -161.707311) (xy 126.0766 -161.729953) (xy 126.024305 -161.745308) (xy 125.970357 -161.753064)
			(xy 125.915855 -161.753064) (xy 125.861907 -161.745308) (xy 125.809612 -161.729953) (xy 125.760035 -161.707311)
			(xy 125.714185 -161.677845) (xy 125.672994 -161.642154) (xy 125.637303 -161.600963) (xy 125.607837 -161.555113)
			(xy 125.585195 -161.505536) (xy 125.56984 -161.453241) (xy 125.562084 -161.399293) (xy 125.561598 -161.372042)
			(xy 125.562067 -161.345249) (xy 125.569567 -161.292189) (xy 125.58441 -161.240699) (xy 125.606306 -161.19179)
			(xy 125.634823 -161.146422) (xy 125.651768 -161.125662) (xy 125.657864 -161.11855) (xy 125.66396 -161.101532)
			(xy 125.662436 -161.01568) (xy 125.655578 -160.998916) (xy 125.649228 -160.991804) (xy 125.630608 -160.970642)
			(xy 125.59923 -160.923815) (xy 125.575084 -160.872882) (xy 125.558692 -160.81895) (xy 125.550413 -160.763194)
			(xy 125.549914 -160.73501) (xy 125.18136 -160.73501) (xy 125.18136 -160.952942) (xy 125.181814 -160.962947)
			(xy 125.189537 -160.981411) (xy 125.196346 -160.988756) (xy 125.21723 -161.010374) (xy 125.252644 -161.058937)
			(xy 125.280001 -161.112454) (xy 125.298624 -161.1696) (xy 125.308051 -161.22896) (xy 125.308614 -161.259012)
			(xy 125.308133 -161.286263) (xy 125.300375 -161.340211) (xy 125.285019 -161.392505) (xy 125.262377 -161.442082)
			(xy 125.23291 -161.487932) (xy 125.197218 -161.529122) (xy 125.156027 -161.564814) (xy 125.110177 -161.59428)
			(xy 125.0606 -161.616921) (xy 125.008305 -161.632277) (xy 124.954357 -161.640034) (xy 124.927106 -161.64052)
			(xy 124.901871 -161.640118) (xy 124.851837 -161.633501) (xy 124.803117 -161.620329) (xy 124.756565 -161.600834)
			(xy 124.734574 -161.58845) (xy 124.724922 -161.582608) (xy 124.702824 -161.580576) (xy 124.608336 -161.614104)
			(xy 124.592334 -161.629598) (xy 124.58827 -161.640012) (xy 124.577539 -161.666773) (xy 124.549255 -161.717013)
			(xy 124.51373 -161.762422) (xy 124.471773 -161.801965) (xy 124.424341 -161.83474) (xy 124.372515 -161.860001)
			(xy 124.317477 -161.877171) (xy 124.260481 -161.885859) (xy 124.231654 -161.886392) (xy 124.204401 -161.885965)
			(xy 124.15045 -161.878202) (xy 124.098153 -161.86284) (xy 124.048575 -161.840192) (xy 124.002724 -161.81072)
			(xy 123.961534 -161.775022) (xy 123.925843 -161.733826) (xy 123.896378 -161.687971) (xy 123.873738 -161.638388)
			(xy 123.858385 -161.586089) (xy 123.850631 -161.532137) (xy 123.850146 -161.504884) (xy 123.850809 -161.473321)
			(xy 123.861194 -161.411056) (xy 123.881679 -161.351347) (xy 123.89612 -161.323274) (xy 123.900946 -161.314384)
			(xy 123.902978 -161.294826) (xy 123.877324 -161.206688) (xy 123.864878 -161.191194) (xy 123.855988 -161.186114)
			(xy 123.830862 -161.171606) (xy 123.78498 -161.136096) (xy 123.745007 -161.094045) (xy 123.711865 -161.046424)
			(xy 123.686318 -160.994333) (xy 123.668957 -160.938972) (xy 123.660182 -160.881621) (xy 123.659646 -160.852612)
			(xy 123.660132 -160.825361) (xy 123.667888 -160.771413) (xy 123.683243 -160.719118) (xy 123.705885 -160.669541)
			(xy 123.735351 -160.623691) (xy 123.771042 -160.5825) (xy 123.812233 -160.546809) (xy 123.858083 -160.517343)
			(xy 123.90766 -160.494701) (xy 123.959955 -160.479346) (xy 124.013903 -160.47159) (xy 124.068405 -160.47159)
			(xy 124.122353 -160.479346) (xy 124.174648 -160.494701) (xy 124.224225 -160.517343) (xy 124.270075 -160.546809)
			(xy 124.311266 -160.5825) (xy 124.346957 -160.623691) (xy 124.376423 -160.669541) (xy 124.399065 -160.719118)
			(xy 124.41442 -160.771413) (xy 124.422176 -160.825361) (xy 124.422662 -160.852612) (xy 124.421996 -160.884175)
			(xy 124.411612 -160.94644) (xy 124.391129 -161.006149) (xy 124.376688 -161.034222) (xy 124.371862 -161.043112)
			(xy 124.36983 -161.06267) (xy 124.395484 -161.150808) (xy 124.40793 -161.166302) (xy 124.41682 -161.171382)
			(xy 124.424186 -161.175446) (xy 124.433838 -161.181288) (xy 124.455936 -161.18332) (xy 124.550424 -161.149792)
			(xy 124.566426 -161.134298) (xy 124.57049 -161.123884) (xy 124.580501 -161.098768) (xy 124.606575 -161.051403)
			(xy 124.639067 -161.008189) (xy 124.657866 -160.988756) (xy 124.664576 -160.981341) (xy 124.672306 -160.962925)
			(xy 124.672852 -160.952942) (xy 124.672852 -159.951674) (xy 124.672453 -159.941602) (xy 124.664715 -159.923003)
			(xy 124.657866 -159.915606) (xy 124.37491 -159.63265) (xy 124.367495 -159.625829) (xy 124.348907 -159.618096)
			(xy 124.338842 -159.617664) (xy 119.54637 -159.617664) (xy 119.536297 -159.618057) (xy 119.517698 -159.625798)
			(xy 119.510302 -159.63265) (xy 117.911118 -161.231834) (xy 117.904273 -161.23923) (xy 117.896555 -161.257832)
			(xy 117.896132 -161.267902) (xy 117.896132 -163.126674) (xy 119.873522 -163.126674) (xy 119.874031 -163.099101)
			(xy 119.881974 -163.04453) (xy 119.89769 -162.99167) (xy 119.920851 -162.941624) (xy 119.950977 -162.895433)
			(xy 119.987438 -162.854061) (xy 120.008142 -162.835844) (xy 120.016243 -162.828226) (xy 120.025605 -162.808086)
			(xy 120.026176 -162.796982) (xy 120.026176 -162.719766) (xy 120.025651 -162.708651) (xy 120.016283 -162.688492)
			(xy 120.008142 -162.680904) (xy 119.987409 -162.662718) (xy 119.950941 -162.621344) (xy 119.920812 -162.575151)
			(xy 119.897648 -162.5251) (xy 119.881933 -162.472235) (xy 119.873993 -162.417659) (xy 119.873996 -162.362508)
			(xy 119.88194 -162.307932) (xy 119.89766 -162.255069) (xy 119.920828 -162.20502) (xy 119.950962 -162.158829)
			(xy 119.987433 -162.117459) (xy 120.008142 -162.099244) (xy 120.016243 -162.091626) (xy 120.025605 -162.071486)
			(xy 120.026176 -162.060382) (xy 120.026176 -161.983166) (xy 120.025651 -161.972051) (xy 120.016283 -161.951892)
			(xy 120.008142 -161.944304) (xy 119.987438 -161.926085) (xy 119.950965 -161.884719) (xy 119.920831 -161.838531)
			(xy 119.897664 -161.788484) (xy 119.881947 -161.735623) (xy 119.874007 -161.681048) (xy 119.873522 -161.653474)
			(xy 119.873931 -161.626219) (xy 119.881692 -161.572265) (xy 119.897053 -161.519964) (xy 119.919701 -161.470382)
			(xy 119.949174 -161.424527) (xy 119.984874 -161.383334) (xy 120.026072 -161.347641) (xy 120.071931 -161.318174)
			(xy 120.121516 -161.295533) (xy 120.173819 -161.28018) (xy 120.227775 -161.272427) (xy 120.25503 -161.271966)
			(xy 120.282885 -161.272487) (xy 120.337999 -161.280614) (xy 120.391348 -161.296662) (xy 120.4418 -161.32029)
			(xy 120.488283 -161.350997) (xy 120.529812 -161.388132) (xy 120.565506 -161.430906) (xy 120.594606 -161.478412)
			(xy 120.616496 -161.529642) (xy 120.624092 -161.556446) (xy 120.626378 -161.565336) (xy 120.637046 -161.580576)
			(xy 120.708928 -161.628328) (xy 120.726962 -161.632392) (xy 120.736106 -161.631122) (xy 120.749123 -161.629454)
			(xy 120.775307 -161.627673) (xy 120.78843 -161.627566) (xy 120.802579 -161.627657) (xy 120.830802 -161.629693)
			(xy 120.844818 -161.63163) (xy 120.854978 -161.633154) (xy 120.874536 -161.628328) (xy 120.948958 -161.572448)
			(xy 120.959118 -161.554922) (xy 120.960388 -161.544762) (xy 120.964477 -161.517608) (xy 120.979449 -161.464778)
			(xy 121.00184 -161.414639) (xy 121.031187 -161.368228) (xy 121.066885 -161.326504) (xy 121.108194 -161.290327)
			(xy 121.154263 -161.260446) (xy 121.20414 -161.237477) (xy 121.256794 -161.221896) (xy 121.311138 -161.214024)
			(xy 121.338594 -161.213546) (xy 121.365843 -161.214083) (xy 121.419787 -161.221838) (xy 121.472077 -161.23719)
			(xy 121.521652 -161.259827) (xy 121.5675 -161.289288) (xy 121.608689 -161.324974) (xy 121.644381 -161.366158)
			(xy 121.673848 -161.412003) (xy 121.696492 -161.461574) (xy 121.711851 -161.513863) (xy 121.719613 -161.567805)
			(xy 121.720102 -161.595054) (xy 121.719604 -161.622627) (xy 121.711658 -161.677199) (xy 121.695939 -161.730058)
			(xy 121.672775 -161.780104) (xy 121.642649 -161.826294) (xy 121.606187 -161.867667) (xy 121.585482 -161.885884)
			(xy 121.577373 -161.893495) (xy 121.568014 -161.91364) (xy 121.567448 -161.924746) (xy 121.567448 -162.001962)
			(xy 121.568006 -162.013073) (xy 121.57735 -162.033233) (xy 121.585482 -162.040824) (xy 121.606204 -162.059023)
			(xy 121.642675 -162.100394) (xy 121.672806 -162.146586) (xy 121.69597 -162.196637) (xy 121.711683 -162.249502)
			(xy 121.719619 -162.304078) (xy 121.719653 -162.306) (xy 126.30861 -162.306) (xy 126.312681 -162.250378)
			(xy 126.324807 -162.195941) (xy 126.34473 -162.14385) (xy 126.372026 -162.095215) (xy 126.406112 -162.051072)
			(xy 126.446261 -162.012363) (xy 126.491619 -161.979912) (xy 126.541219 -161.954411) (xy 126.594003 -161.936404)
			(xy 126.648846 -161.926274) (xy 126.70458 -161.924237) (xy 126.760017 -161.930337) (xy 126.813974 -161.944443)
			(xy 126.865303 -161.966255) (xy 126.912909 -161.995309) (xy 126.955777 -162.030984) (xy 126.992994 -162.072521)
			(xy 127.023767 -162.119034) (xy 127.047439 -162.169531) (xy 127.063507 -162.222938) (xy 127.071627 -162.278114)
			(xy 127.072136 -162.306) (xy 127.071627 -162.333886) (xy 127.063507 -162.389062) (xy 127.047439 -162.442469)
			(xy 127.023767 -162.492966) (xy 126.992994 -162.539479) (xy 126.955777 -162.581016) (xy 126.912909 -162.616691)
			(xy 126.865303 -162.645745) (xy 126.813974 -162.667557) (xy 126.760017 -162.681663) (xy 126.70458 -162.687763)
			(xy 126.648846 -162.685726) (xy 126.594003 -162.675596) (xy 126.541219 -162.657589) (xy 126.491619 -162.632088)
			(xy 126.446261 -162.599637) (xy 126.406112 -162.560928) (xy 126.372026 -162.516785) (xy 126.34473 -162.46815)
			(xy 126.324807 -162.416059) (xy 126.312681 -162.361622) (xy 126.30861 -162.306) (xy 121.719653 -162.306)
			(xy 121.720102 -162.331654) (xy 121.719602 -162.358906) (xy 121.711851 -162.412856) (xy 121.696501 -162.465153)
			(xy 121.673863 -162.514734) (xy 121.644399 -162.560587) (xy 121.608709 -162.601781) (xy 121.56752 -162.637475)
			(xy 121.521669 -162.666944) (xy 121.472091 -162.689587) (xy 121.419795 -162.704943) (xy 121.365846 -162.712699)
			(xy 121.338594 -162.713162) (xy 121.304304 -162.711638) (xy 121.294144 -162.710622) (xy 121.27484 -162.716718)
			(xy 121.204228 -162.7759) (xy 121.19483 -162.793934) (xy 121.193814 -162.804094) (xy 121.190902 -162.832272)
			(xy 121.177721 -162.887365) (xy 121.156537 -162.939902) (xy 121.127814 -162.988728) (xy 121.092185 -163.032768)
			(xy 121.050433 -163.071054) (xy 121.003478 -163.102742) (xy 120.952352 -163.127137) (xy 120.89818 -163.143701)
			(xy 120.842154 -163.15207) (xy 120.81383 -163.152582) (xy 120.795811 -163.152366) (xy 120.759936 -163.148928)
			(xy 120.742202 -163.145724) (xy 120.732804 -163.143946) (xy 120.713754 -163.147756) (xy 120.63857 -163.195508)
			(xy 120.62714 -163.211256) (xy 120.624854 -163.220654) (xy 120.617489 -163.247708) (xy 120.595856 -163.299436)
			(xy 120.566888 -163.347442) (xy 120.531209 -163.390694) (xy 120.489585 -163.428261) (xy 120.442913 -163.459334)
			(xy 120.392198 -163.483244) (xy 120.33853 -163.499478) (xy 120.283065 -163.507685) (xy 120.25503 -163.508182)
			(xy 120.227777 -163.507717) (xy 120.173824 -163.499963) (xy 120.121525 -163.48461) (xy 120.071943 -163.461969)
			(xy 120.026089 -163.432501) (xy 119.984895 -163.396808) (xy 119.949201 -163.355614) (xy 119.919733 -163.30976)
			(xy 119.897092 -163.260179) (xy 119.881738 -163.207879) (xy 119.873984 -163.153927) (xy 119.873522 -163.126674)
			(xy 117.896132 -163.126674) (xy 117.896132 -164.62756) (xy 121.49074 -164.62756) (xy 121.491233 -164.599986)
			(xy 121.499178 -164.545414) (xy 121.514897 -164.492554) (xy 121.538062 -164.442508) (xy 121.56819 -164.396317)
			(xy 121.604654 -164.354946) (xy 121.62536 -164.33673) (xy 121.63347 -164.32912) (xy 121.642826 -164.308974)
			(xy 121.643394 -164.297868) (xy 121.643394 -164.220652) (xy 121.642814 -164.209544) (xy 121.633484 -164.189385)
			(xy 121.62536 -164.18179) (xy 121.604633 -164.163597) (xy 121.568165 -164.122223) (xy 121.538036 -164.076029)
			(xy 121.514874 -164.025978) (xy 121.49916 -163.973113) (xy 121.491224 -163.918536) (xy 121.49074 -163.89096)
			(xy 121.491336 -163.861514) (xy 121.500398 -163.803322) (xy 121.518285 -163.747211) (xy 121.544574 -163.694511)
			(xy 121.578641 -163.646472) (xy 121.619678 -163.604231) (xy 121.666714 -163.56879) (xy 121.692416 -163.55441)
			(xy 121.701814 -163.54933) (xy 121.715022 -163.532566) (xy 121.738898 -163.439094) (xy 121.735342 -163.418012)
			(xy 121.7295 -163.409122) (xy 121.714965 -163.386192) (xy 121.691987 -163.337005) (xy 121.676395 -163.285003)
			(xy 121.668519 -163.231289) (xy 121.668032 -163.204144) (xy 121.668475 -163.177525) (xy 121.676047 -163.124828)
			(xy 121.691042 -163.073746) (xy 121.713155 -163.025318) (xy 121.741937 -162.98053) (xy 121.7768 -162.940296)
			(xy 121.817035 -162.905433) (xy 121.861823 -162.876652) (xy 121.910251 -162.85454) (xy 121.961334 -162.839545)
			(xy 122.014031 -162.831975) (xy 122.04065 -162.831526) (xy 122.067072 -162.831972) (xy 122.119387 -162.839428)
			(xy 122.170125 -162.854196) (xy 122.218269 -162.875982) (xy 122.262854 -162.904348) (xy 122.28322 -162.921188)
			(xy 122.290078 -162.927284) (xy 122.307096 -162.93338) (xy 122.391424 -162.93338) (xy 122.408442 -162.927284)
			(xy 122.4153 -162.921188) (xy 122.435666 -162.904349) (xy 122.480252 -162.875984) (xy 122.528396 -162.854197)
			(xy 122.579133 -162.839426) (xy 122.631448 -162.831966) (xy 122.684292 -162.831966) (xy 122.736607 -162.839426)
			(xy 122.787344 -162.854197) (xy 122.835488 -162.875984) (xy 122.880074 -162.904349) (xy 122.90044 -162.921188)
			(xy 122.907298 -162.927284) (xy 122.924316 -162.93338) (xy 123.008644 -162.93338) (xy 123.025662 -162.927284)
			(xy 123.03252 -162.921188) (xy 123.052877 -162.904339) (xy 123.097469 -162.875986) (xy 123.145616 -162.854209)
			(xy 123.196354 -162.839444) (xy 123.248669 -162.831986) (xy 123.27509 -162.831526) (xy 123.302981 -162.831932)
			(xy 123.358139 -162.840245) (xy 123.411442 -162.856685) (xy 123.461699 -162.880887) (xy 123.507788 -162.912309)
			(xy 123.548679 -162.950249) (xy 123.583459 -162.99386) (xy 123.61135 -163.042167) (xy 123.631729 -163.094092)
			(xy 123.644142 -163.148475) (xy 123.648311 -163.2041) (xy 123.644142 -163.259725) (xy 123.631729 -163.314108)
			(xy 123.61135 -163.366033) (xy 123.583459 -163.41434) (xy 123.548679 -163.457951) (xy 123.507788 -163.495891)
			(xy 123.461699 -163.527313) (xy 123.411442 -163.551515) (xy 123.358139 -163.567955) (xy 123.302981 -163.576268)
			(xy 123.27509 -163.576762) (xy 123.248669 -163.576295) (xy 123.196354 -163.568845) (xy 123.145616 -163.554082)
			(xy 123.097472 -163.5323) (xy 123.052886 -163.503938) (xy 123.03252 -163.4871) (xy 123.025662 -163.481004)
			(xy 123.008644 -163.474908) (xy 122.924316 -163.474908) (xy 122.907298 -163.481004) (xy 122.90044 -163.4871)
			(xy 122.880074 -163.503939) (xy 122.835488 -163.532304) (xy 122.787344 -163.554091) (xy 122.736607 -163.568862)
			(xy 122.684292 -163.576322) (xy 122.631448 -163.576322) (xy 122.579133 -163.568862) (xy 122.528396 -163.554091)
			(xy 122.480252 -163.532304) (xy 122.435666 -163.503939) (xy 122.4153 -163.4871) (xy 122.408442 -163.481004)
			(xy 122.391424 -163.474908) (xy 122.307096 -163.474908) (xy 122.290078 -163.481004) (xy 122.28322 -163.4871)
			(xy 122.268829 -163.499111) (xy 122.238035 -163.520486) (xy 122.221752 -163.529772) (xy 122.212354 -163.534852)
			(xy 122.199654 -163.552124) (xy 122.177302 -163.64585) (xy 122.181366 -163.666932) (xy 122.187208 -163.675822)
			(xy 122.202891 -163.699729) (xy 122.227735 -163.751224) (xy 122.244629 -163.805845) (xy 122.253197 -163.862373)
			(xy 122.253756 -163.89096) (xy 122.253278 -163.918534) (xy 122.24533 -163.973107) (xy 122.229609 -164.025968)
			(xy 122.206441 -164.076014) (xy 122.17631 -164.122204) (xy 122.139843 -164.163575) (xy 122.119136 -164.18179)
			(xy 122.111016 -164.189391) (xy 122.101665 -164.209544) (xy 122.101102 -164.220652) (xy 122.101102 -164.297868)
			(xy 122.101671 -164.308978) (xy 122.111009 -164.329136) (xy 122.119136 -164.33673) (xy 122.139872 -164.354914)
			(xy 122.176339 -164.396289) (xy 122.206467 -164.442485) (xy 122.229628 -164.492538) (xy 122.24534 -164.545405)
			(xy 122.253274 -164.599984) (xy 122.253756 -164.62756) (xy 122.25327 -164.654811) (xy 122.245514 -164.708759)
			(xy 122.230159 -164.761054) (xy 122.207517 -164.810631) (xy 122.178051 -164.856481) (xy 122.14236 -164.897672)
			(xy 122.101169 -164.933363) (xy 122.055319 -164.962829) (xy 122.005742 -164.985471) (xy 121.953447 -165.000826)
			(xy 121.899499 -165.008582) (xy 121.844997 -165.008582) (xy 121.791049 -165.000826) (xy 121.738754 -164.985471)
			(xy 121.689177 -164.962829) (xy 121.643327 -164.933363) (xy 121.602136 -164.897672) (xy 121.566445 -164.856481)
			(xy 121.536979 -164.810631) (xy 121.514337 -164.761054) (xy 121.498982 -164.708759) (xy 121.491226 -164.654811)
			(xy 121.49074 -164.62756) (xy 117.896132 -164.62756) (xy 117.896132 -164.82441) (xy 117.895513 -164.849393)
			(xy 117.885773 -164.898401) (xy 117.866668 -164.944571) (xy 117.838931 -164.986132) (xy 117.82171 -165.004242)
			(xy 116.915946 -165.910006) (xy 116.909117 -165.917415) (xy 116.901389 -165.936007) (xy 116.90096 -165.946074)
			(xy 116.90096 -167.683942) (xy 116.901414 -167.693947) (xy 116.909137 -167.712411) (xy 116.915946 -167.719756)
			(xy 116.93683 -167.741374) (xy 116.972244 -167.789937) (xy 116.999601 -167.843454) (xy 117.018224 -167.9006)
			(xy 117.027651 -167.95996) (xy 117.028214 -167.990012) (xy 117.027733 -168.017263) (xy 117.019975 -168.071211)
			(xy 117.010628 -168.103042) (xy 117.269514 -168.103042) (xy 117.270022 -168.075568) (xy 117.277908 -168.021189)
			(xy 117.293523 -167.968507) (xy 117.316543 -167.918614) (xy 117.34649 -167.872544) (xy 117.364256 -167.851582)
			(xy 117.370352 -167.84447) (xy 117.376702 -167.827452) (xy 117.376702 -167.7416) (xy 117.370352 -167.724582)
			(xy 117.364256 -167.71747) (xy 117.34649 -167.69651) (xy 117.316567 -167.650427) (xy 117.293555 -167.600532)
			(xy 117.27793 -167.547855) (xy 117.270013 -167.493482) (xy 117.269514 -167.46601) (xy 117.27 -167.438759)
			(xy 117.277756 -167.384811) (xy 117.293111 -167.332516) (xy 117.315753 -167.282939) (xy 117.345219 -167.237089)
			(xy 117.38091 -167.195898) (xy 117.422101 -167.160207) (xy 117.467951 -167.130741) (xy 117.517528 -167.108099)
			(xy 117.569823 -167.092744) (xy 117.623771 -167.084988) (xy 117.678273 -167.084988) (xy 117.732221 -167.092744)
			(xy 117.784516 -167.108099) (xy 117.834093 -167.130741) (xy 117.879943 -167.160207) (xy 117.921134 -167.195898)
			(xy 117.956825 -167.237089) (xy 117.986291 -167.282939) (xy 118.008933 -167.332516) (xy 118.024288 -167.384811)
			(xy 118.032044 -167.438759) (xy 118.03253 -167.46601) (xy 118.032042 -167.493484) (xy 118.02415 -167.547864)
			(xy 118.008529 -167.600546) (xy 117.985505 -167.650439) (xy 117.955555 -167.696508) (xy 117.937788 -167.71747)
			(xy 117.931692 -167.724582) (xy 117.925342 -167.7416) (xy 117.925342 -167.827452) (xy 117.931692 -167.84447)
			(xy 117.937788 -167.851582) (xy 117.955523 -167.872568) (xy 117.985452 -167.918643) (xy 118.008471 -167.968531)
			(xy 118.024104 -168.021203) (xy 118.032027 -168.075571) (xy 118.03253 -168.103042) (xy 118.032044 -168.130293)
			(xy 118.024288 -168.184241) (xy 118.008933 -168.236536) (xy 117.986291 -168.286113) (xy 117.956825 -168.331963)
			(xy 117.921134 -168.373154) (xy 117.879943 -168.408845) (xy 117.834093 -168.438311) (xy 117.784516 -168.460953)
			(xy 117.732221 -168.476308) (xy 117.678273 -168.484064) (xy 117.623771 -168.484064) (xy 117.569823 -168.476308)
			(xy 117.517528 -168.460953) (xy 117.467951 -168.438311) (xy 117.422101 -168.408845) (xy 117.38091 -168.373154)
			(xy 117.345219 -168.331963) (xy 117.315753 -168.286113) (xy 117.293111 -168.236536) (xy 117.277756 -168.184241)
			(xy 117.27 -168.130293) (xy 117.269514 -168.103042) (xy 117.010628 -168.103042) (xy 117.004619 -168.123505)
			(xy 116.981977 -168.173082) (xy 116.95251 -168.218932) (xy 116.916818 -168.260122) (xy 116.875627 -168.295814)
			(xy 116.829777 -168.32528) (xy 116.7802 -168.347921) (xy 116.727905 -168.363277) (xy 116.673957 -168.371034)
			(xy 116.646706 -168.37152) (xy 116.621471 -168.371118) (xy 116.571437 -168.364501) (xy 116.522717 -168.351329)
			(xy 116.476165 -168.331834) (xy 116.454174 -168.31945) (xy 116.444522 -168.313608) (xy 116.422424 -168.311576)
			(xy 116.327936 -168.345104) (xy 116.311934 -168.360598) (xy 116.30787 -168.371012) (xy 116.297139 -168.397773)
			(xy 116.268855 -168.448013) (xy 116.23333 -168.493422) (xy 116.191373 -168.532965) (xy 116.143941 -168.56574)
			(xy 116.092115 -168.591001) (xy 116.037077 -168.608171) (xy 115.980081 -168.616859) (xy 115.951254 -168.617392)
			(xy 115.924001 -168.616965) (xy 115.87005 -168.609202) (xy 115.817753 -168.59384) (xy 115.768175 -168.571192)
			(xy 115.722324 -168.54172) (xy 115.681134 -168.506022) (xy 115.645443 -168.464826) (xy 115.615978 -168.418971)
			(xy 115.593338 -168.369388) (xy 115.577985 -168.317089) (xy 115.570231 -168.263137) (xy 115.569746 -168.235884)
			(xy 115.570409 -168.204321) (xy 115.580794 -168.142056) (xy 115.601279 -168.082347) (xy 115.61572 -168.054274)
			(xy 115.620546 -168.045384) (xy 115.622578 -168.025826) (xy 115.596924 -167.937688) (xy 115.584478 -167.922194)
			(xy 115.575588 -167.917114) (xy 115.550462 -167.902606) (xy 115.50458 -167.867096) (xy 115.464607 -167.825045)
			(xy 115.431465 -167.777424) (xy 115.405918 -167.725333) (xy 115.388557 -167.669972) (xy 115.379782 -167.612621)
			(xy 115.379246 -167.583612) (xy 115.379732 -167.556361) (xy 115.387488 -167.502413) (xy 115.402843 -167.450118)
			(xy 115.425485 -167.400541) (xy 115.454951 -167.354691) (xy 115.490642 -167.3135) (xy 115.531833 -167.277809)
			(xy 115.577683 -167.248343) (xy 115.62726 -167.225701) (xy 115.679555 -167.210346) (xy 115.733503 -167.20259)
			(xy 115.788005 -167.20259) (xy 115.841953 -167.210346) (xy 115.894248 -167.225701) (xy 115.943825 -167.248343)
			(xy 115.989675 -167.277809) (xy 116.030866 -167.3135) (xy 116.066557 -167.354691) (xy 116.096023 -167.400541)
			(xy 116.118665 -167.450118) (xy 116.13402 -167.502413) (xy 116.141776 -167.556361) (xy 116.142262 -167.583612)
			(xy 116.141596 -167.615175) (xy 116.131212 -167.67744) (xy 116.110729 -167.737149) (xy 116.096288 -167.765222)
			(xy 116.091462 -167.774112) (xy 116.08943 -167.79367) (xy 116.115084 -167.881808) (xy 116.12753 -167.897302)
			(xy 116.13642 -167.902382) (xy 116.143786 -167.906446) (xy 116.153438 -167.912288) (xy 116.175536 -167.91432)
			(xy 116.270024 -167.880792) (xy 116.286026 -167.865298) (xy 116.29009 -167.854884) (xy 116.300101 -167.829768)
			(xy 116.326175 -167.782403) (xy 116.358667 -167.739189) (xy 116.377466 -167.719756) (xy 116.384176 -167.712341)
			(xy 116.391906 -167.693925) (xy 116.392452 -167.683942) (xy 116.392452 -165.819582) (xy 116.39307 -165.794599)
			(xy 116.402811 -165.745591) (xy 116.421917 -165.699421) (xy 116.449653 -165.65786) (xy 116.466874 -165.63975)
			(xy 117.372638 -164.733986) (xy 117.379482 -164.726589) (xy 117.387198 -164.707987) (xy 117.387624 -164.697918)
			(xy 117.387624 -161.446464) (xy 117.387242 -161.436432) (xy 117.379593 -161.417885) (xy 117.365405 -161.4037)
			(xy 117.346857 -161.396056) (xy 117.336824 -161.395664) (xy 116.115592 -161.395664) (xy 116.090609 -161.395035)
			(xy 116.041602 -161.385296) (xy 115.995433 -161.366194) (xy 115.953871 -161.338461) (xy 115.93576 -161.321242)
			(xy 101.260402 -146.645884) (xy 101.243167 -146.627786) (xy 101.215426 -146.586223) (xy 101.196321 -146.54005)
			(xy 101.186587 -146.491037) (xy 101.18598 -146.466052) (xy 101.18598 -145.673064) (xy 101.185579 -145.662992)
			(xy 101.177842 -145.644394) (xy 101.170994 -145.636996) (xy 100.289106 -144.755362) (xy 100.260658 -144.748758)
			(xy 100.246688 -144.753838) (xy 100.245418 -144.754346) (xy 100.231448 -144.810988) (xy 100.229146 -144.822568)
			(xy 100.234194 -144.845606) (xy 100.2411 -144.855184) (xy 100.257025 -144.875622) (xy 100.283806 -144.919977)
			(xy 100.304335 -144.96755) (xy 100.318234 -145.017464) (xy 100.325248 -145.0688) (xy 100.325682 -145.094706)
			(xy 100.325346 -145.117825) (xy 100.31978 -145.163725) (xy 100.308693 -145.208614) (xy 100.30079 -145.230342)
			(xy 100.296218 -145.242026) (xy 100.298758 -145.265902) (xy 100.357178 -145.35531) (xy 100.378006 -145.367502)
			(xy 100.390198 -145.36801) (xy 100.419095 -145.370045) (xy 100.475808 -145.38185) (xy 100.530086 -145.402092)
			(xy 100.58068 -145.430305) (xy 100.626428 -145.465842) (xy 100.66628 -145.507885) (xy 100.699318 -145.555469)
			(xy 100.724785 -145.6075) (xy 100.742094 -145.662782) (xy 100.750849 -145.720046) (xy 100.751386 -145.74901)
			(xy 100.7509 -145.776261) (xy 100.743144 -145.830209) (xy 100.727789 -145.882504) (xy 100.705147 -145.932081)
			(xy 100.675681 -145.977931) (xy 100.63999 -146.019122) (xy 100.598799 -146.054813) (xy 100.552949 -146.084279)
			(xy 100.503372 -146.106921) (xy 100.451077 -146.122276) (xy 100.397129 -146.130032) (xy 100.342627 -146.130032)
			(xy 100.288679 -146.122276) (xy 100.236384 -146.106921) (xy 100.186807 -146.084279) (xy 100.140957 -146.054813)
			(xy 100.099766 -146.019122) (xy 100.064075 -145.977931) (xy 100.034609 -145.932081) (xy 100.011967 -145.882504)
			(xy 99.996612 -145.830209) (xy 99.988856 -145.776261) (xy 99.98837 -145.74901) (xy 99.988678 -145.72589)
			(xy 99.994255 -145.679989) (xy 100.005353 -145.635101) (xy 100.013262 -145.613374) (xy 100.017834 -145.60169)
			(xy 100.015294 -145.577814) (xy 99.956874 -145.488406) (xy 99.936046 -145.476214) (xy 99.923854 -145.475706)
			(xy 99.894962 -145.47361) (xy 99.838252 -145.461813) (xy 99.783976 -145.441579) (xy 99.733382 -145.413373)
			(xy 99.687633 -145.377844) (xy 99.647781 -145.335808) (xy 99.614741 -145.28823) (xy 99.589273 -145.236205)
			(xy 99.571961 -145.180927) (xy 99.563204 -145.123668) (xy 99.562666 -145.094706) (xy 99.563113 -145.068765)
			(xy 99.570142 -145.017363) (xy 99.584073 -144.967387) (xy 99.604648 -144.919759) (xy 99.631486 -144.875359)
			(xy 99.664094 -144.835006) (xy 99.70187 -144.799444) (xy 99.744116 -144.769329) (xy 99.766882 -144.756886)
			(xy 99.776788 -144.751806) (xy 99.789996 -144.735042) (xy 99.813618 -144.639792) (xy 99.809808 -144.61871)
			(xy 99.803712 -144.609566) (xy 99.788026 -144.585661) (xy 99.763183 -144.534166) (xy 99.746289 -144.479544)
			(xy 99.737722 -144.423015) (xy 99.737164 -144.394428) (xy 99.737644 -144.366755) (xy 99.745661 -144.311993)
			(xy 99.761516 -144.258966) (xy 99.784876 -144.208792) (xy 99.799648 -144.185386) (xy 99.807268 -144.173448)
			(xy 99.808538 -144.145762) (xy 99.759262 -144.054576) (xy 99.754572 -144.046745) (xy 99.740789 -144.034801)
			(xy 99.72368 -144.028485) (xy 99.714558 -144.02816) (xy 99.356926 -144.02816) (xy 99.346877 -144.028501)
			(xy 99.328281 -144.036109) (xy 99.320858 -144.042892) (xy 98.7933 -144.57045) (xy 98.786589 -144.577917)
			(xy 98.77901 -144.596487) (xy 98.778568 -144.606518) (xy 98.778568 -145.979134) (xy 98.778928 -145.989181)
			(xy 98.786522 -146.007778) (xy 98.7933 -146.015202) (xy 99.83724 -147.059142) (xy 99.844627 -147.065998)
			(xy 99.863237 -147.073707) (xy 99.873308 -147.074128) (xy 100.555552 -147.074128) (xy 100.580536 -147.074732)
			(xy 100.629544 -147.084479) (xy 100.675713 -147.103589) (xy 100.717274 -147.131328) (xy 100.735384 -147.14855)
			(xy 103.34371 -149.756876) (xy 103.360928 -149.77499) (xy 103.388672 -149.816547) (xy 103.407781 -149.862716)
			(xy 103.417522 -149.911724) (xy 103.418132 -149.936708) (xy 103.418132 -169.857674) (xy 111.593122 -169.857674)
			(xy 111.593631 -169.830101) (xy 111.601574 -169.77553) (xy 111.61729 -169.72267) (xy 111.640451 -169.672624)
			(xy 111.670577 -169.626433) (xy 111.707038 -169.585061) (xy 111.727742 -169.566844) (xy 111.735843 -169.559226)
			(xy 111.745205 -169.539086) (xy 111.745776 -169.527982) (xy 111.745776 -169.450766) (xy 111.745251 -169.439651)
			(xy 111.735883 -169.419492) (xy 111.727742 -169.411904) (xy 111.707009 -169.393718) (xy 111.670541 -169.352344)
			(xy 111.640412 -169.306151) (xy 111.617248 -169.2561) (xy 111.601533 -169.203235) (xy 111.593593 -169.148659)
			(xy 111.593596 -169.093508) (xy 111.60154 -169.038932) (xy 111.61726 -168.986069) (xy 111.640428 -168.93602)
			(xy 111.670562 -168.889829) (xy 111.707033 -168.848459) (xy 111.727742 -168.830244) (xy 111.735843 -168.822626)
			(xy 111.745205 -168.802486) (xy 111.745776 -168.791382) (xy 111.745776 -168.714166) (xy 111.745251 -168.703051)
			(xy 111.735883 -168.682892) (xy 111.727742 -168.675304) (xy 111.707038 -168.657085) (xy 111.670565 -168.615719)
			(xy 111.640431 -168.569531) (xy 111.617264 -168.519484) (xy 111.601547 -168.466623) (xy 111.593607 -168.412048)
			(xy 111.593122 -168.384474) (xy 111.593531 -168.357219) (xy 111.601292 -168.303265) (xy 111.616653 -168.250964)
			(xy 111.639301 -168.201382) (xy 111.668774 -168.155527) (xy 111.704474 -168.114334) (xy 111.745672 -168.078641)
			(xy 111.791531 -168.049174) (xy 111.841116 -168.026533) (xy 111.893419 -168.01118) (xy 111.947375 -168.003427)
			(xy 111.97463 -168.002966) (xy 112.002485 -168.003487) (xy 112.057599 -168.011614) (xy 112.110948 -168.027662)
			(xy 112.1614 -168.05129) (xy 112.207883 -168.081997) (xy 112.249412 -168.119132) (xy 112.285106 -168.161906)
			(xy 112.314206 -168.209412) (xy 112.336096 -168.260642) (xy 112.343692 -168.287446) (xy 112.345978 -168.296336)
			(xy 112.356646 -168.311576) (xy 112.428528 -168.359328) (xy 112.446562 -168.363392) (xy 112.455706 -168.362122)
			(xy 112.468723 -168.360454) (xy 112.494907 -168.358673) (xy 112.50803 -168.358566) (xy 112.522179 -168.358657)
			(xy 112.550402 -168.360693) (xy 112.564418 -168.36263) (xy 112.574578 -168.364154) (xy 112.594136 -168.359328)
			(xy 112.668558 -168.303448) (xy 112.678718 -168.285922) (xy 112.679988 -168.275762) (xy 112.684077 -168.248608)
			(xy 112.699049 -168.195778) (xy 112.72144 -168.145639) (xy 112.750787 -168.099228) (xy 112.786485 -168.057504)
			(xy 112.827794 -168.021327) (xy 112.873863 -167.991446) (xy 112.92374 -167.968477) (xy 112.976394 -167.952896)
			(xy 113.030738 -167.945024) (xy 113.058194 -167.944546) (xy 113.085443 -167.945083) (xy 113.139387 -167.952838)
			(xy 113.191677 -167.96819) (xy 113.241252 -167.990827) (xy 113.2871 -168.020288) (xy 113.328289 -168.055974)
			(xy 113.363981 -168.097158) (xy 113.393448 -168.143003) (xy 113.416092 -168.192574) (xy 113.431451 -168.244863)
			(xy 113.439213 -168.298805) (xy 113.439702 -168.326054) (xy 113.439204 -168.353627) (xy 113.431258 -168.408199)
			(xy 113.415539 -168.461058) (xy 113.392375 -168.511104) (xy 113.362249 -168.557294) (xy 113.325787 -168.598667)
			(xy 113.305082 -168.616884) (xy 113.296973 -168.624495) (xy 113.287614 -168.64464) (xy 113.287048 -168.655746)
			(xy 113.287048 -168.732962) (xy 113.287606 -168.744073) (xy 113.29695 -168.764233) (xy 113.305082 -168.771824)
			(xy 113.325804 -168.790023) (xy 113.362275 -168.831394) (xy 113.392406 -168.877586) (xy 113.41557 -168.927637)
			(xy 113.431283 -168.980502) (xy 113.439219 -169.035078) (xy 113.439702 -169.062654) (xy 113.439202 -169.089906)
			(xy 113.431451 -169.143856) (xy 113.416101 -169.196153) (xy 113.393463 -169.245734) (xy 113.363999 -169.291587)
			(xy 113.328309 -169.332781) (xy 113.28712 -169.368475) (xy 113.241269 -169.397944) (xy 113.191691 -169.420587)
			(xy 113.139395 -169.435943) (xy 113.085446 -169.443699) (xy 113.058194 -169.444162) (xy 113.023904 -169.442638)
			(xy 113.013744 -169.441622) (xy 112.99444 -169.447718) (xy 112.923828 -169.5069) (xy 112.91443 -169.524934)
			(xy 112.913414 -169.535094) (xy 112.910502 -169.563272) (xy 112.897321 -169.618365) (xy 112.876137 -169.670902)
			(xy 112.847414 -169.719728) (xy 112.811785 -169.763768) (xy 112.770033 -169.802054) (xy 112.723078 -169.833742)
			(xy 112.671952 -169.858137) (xy 112.61778 -169.874701) (xy 112.561754 -169.88307) (xy 112.53343 -169.883582)
			(xy 112.515411 -169.883366) (xy 112.479536 -169.879928) (xy 112.461802 -169.876724) (xy 112.452404 -169.874946)
			(xy 112.433354 -169.878756) (xy 112.35817 -169.926508) (xy 112.34674 -169.942256) (xy 112.344454 -169.951654)
			(xy 112.337089 -169.978708) (xy 112.315456 -170.030436) (xy 112.286488 -170.078442) (xy 112.250809 -170.121694)
			(xy 112.209185 -170.159261) (xy 112.162513 -170.190334) (xy 112.111798 -170.214244) (xy 112.05813 -170.230478)
			(xy 112.002665 -170.238685) (xy 111.97463 -170.239182) (xy 111.947377 -170.238717) (xy 111.893424 -170.230963)
			(xy 111.841125 -170.21561) (xy 111.791543 -170.192969) (xy 111.745689 -170.163501) (xy 111.704495 -170.127808)
			(xy 111.668801 -170.086614) (xy 111.639333 -170.04076) (xy 111.616692 -169.991179) (xy 111.601338 -169.938879)
			(xy 111.593584 -169.884927) (xy 111.593122 -169.857674) (xy 103.418132 -169.857674) (xy 103.418132 -171.33316)
			(xy 113.21034 -171.33316) (xy 113.210833 -171.305586) (xy 113.218778 -171.251014) (xy 113.234497 -171.198154)
			(xy 113.257662 -171.148108) (xy 113.28779 -171.101917) (xy 113.324254 -171.060546) (xy 113.34496 -171.04233)
			(xy 113.35307 -171.03472) (xy 113.362426 -171.014574) (xy 113.362994 -171.003468) (xy 113.362994 -170.926252)
			(xy 113.362414 -170.915144) (xy 113.353084 -170.894985) (xy 113.34496 -170.88739) (xy 113.324233 -170.869197)
			(xy 113.287765 -170.827823) (xy 113.257636 -170.781629) (xy 113.234474 -170.731578) (xy 113.21876 -170.678713)
			(xy 113.210824 -170.624136) (xy 113.21034 -170.59656) (xy 113.210869 -170.567888) (xy 113.219469 -170.511192)
			(xy 113.236454 -170.456421) (xy 113.261442 -170.404807) (xy 113.293871 -170.357513) (xy 113.333011 -170.315602)
			(xy 113.37798 -170.280019) (xy 113.402618 -170.265344) (xy 113.411762 -170.26001) (xy 113.423954 -170.244008)
			(xy 113.44783 -170.154092) (xy 113.445036 -170.134026) (xy 113.439702 -170.125136) (xy 113.42735 -170.103476)
			(xy 113.407872 -170.057577) (xy 113.394688 -170.00949) (xy 113.388033 -169.960075) (xy 113.387632 -169.935144)
			(xy 113.388075 -169.908525) (xy 113.395647 -169.855828) (xy 113.410642 -169.804746) (xy 113.432755 -169.756318)
			(xy 113.461537 -169.71153) (xy 113.4964 -169.671296) (xy 113.536635 -169.636433) (xy 113.581423 -169.607652)
			(xy 113.629851 -169.58554) (xy 113.680934 -169.570545) (xy 113.733631 -169.562975) (xy 113.76025 -169.562526)
			(xy 113.786672 -169.562972) (xy 113.838987 -169.570428) (xy 113.889725 -169.585196) (xy 113.937869 -169.606982)
			(xy 113.982454 -169.635348) (xy 114.00282 -169.652188) (xy 114.009678 -169.658284) (xy 114.026696 -169.66438)
			(xy 114.111024 -169.66438) (xy 114.128042 -169.658284) (xy 114.1349 -169.652188) (xy 114.155266 -169.635349)
			(xy 114.199852 -169.606984) (xy 114.247996 -169.585197) (xy 114.298733 -169.570426) (xy 114.351048 -169.562966)
			(xy 114.403892 -169.562966) (xy 114.456207 -169.570426) (xy 114.506944 -169.585197) (xy 114.555088 -169.606984)
			(xy 114.599674 -169.635349) (xy 114.62004 -169.652188) (xy 114.626898 -169.658284) (xy 114.643916 -169.66438)
			(xy 114.728244 -169.66438) (xy 114.745262 -169.658284) (xy 114.75212 -169.652188) (xy 114.772477 -169.635339)
			(xy 114.817069 -169.606986) (xy 114.865216 -169.585209) (xy 114.915954 -169.570444) (xy 114.968269 -169.562986)
			(xy 114.99469 -169.562526) (xy 115.022581 -169.562932) (xy 115.077739 -169.571245) (xy 115.131042 -169.587685)
			(xy 115.181299 -169.611887) (xy 115.227388 -169.643309) (xy 115.268279 -169.681249) (xy 115.303059 -169.72486)
			(xy 115.33095 -169.773167) (xy 115.351329 -169.825092) (xy 115.363742 -169.879475) (xy 115.367911 -169.9351)
			(xy 115.363742 -169.990725) (xy 115.351329 -170.045108) (xy 115.33095 -170.097033) (xy 115.303059 -170.14534)
			(xy 115.268279 -170.188951) (xy 115.227388 -170.226891) (xy 115.181299 -170.258313) (xy 115.131042 -170.282515)
			(xy 115.077739 -170.298955) (xy 115.022581 -170.307268) (xy 114.99469 -170.307762) (xy 114.968269 -170.307295)
			(xy 114.915954 -170.299845) (xy 114.865216 -170.285082) (xy 114.817072 -170.2633) (xy 114.772486 -170.234938)
			(xy 114.75212 -170.2181) (xy 114.745262 -170.212004) (xy 114.728244 -170.205908) (xy 114.643916 -170.205908)
			(xy 114.626898 -170.212004) (xy 114.62004 -170.2181) (xy 114.599674 -170.234939) (xy 114.555088 -170.263304)
			(xy 114.506944 -170.285091) (xy 114.456207 -170.299862) (xy 114.403892 -170.307322) (xy 114.351048 -170.307322)
			(xy 114.298733 -170.299862) (xy 114.247996 -170.285091) (xy 114.199852 -170.263304) (xy 114.155266 -170.234939)
			(xy 114.1349 -170.2181) (xy 114.128042 -170.212004) (xy 114.111024 -170.205908) (xy 114.026696 -170.205908)
			(xy 114.009678 -170.212004) (xy 114.00282 -170.2181) (xy 113.990525 -170.228404) (xy 113.964455 -170.247101)
			(xy 113.95075 -170.255438) (xy 113.94186 -170.260518) (xy 113.929922 -170.276774) (xy 113.907824 -170.367198)
			(xy 113.910872 -170.387264) (xy 113.91646 -170.3959) (xy 113.929948 -170.41862) (xy 113.951247 -170.466974)
			(xy 113.965664 -170.517806) (xy 113.972924 -170.570141) (xy 113.973356 -170.59656) (xy 113.972878 -170.624134)
			(xy 113.96493 -170.678707) (xy 113.949209 -170.731568) (xy 113.926041 -170.781614) (xy 113.89591 -170.827804)
			(xy 113.859443 -170.869175) (xy 113.838736 -170.88739) (xy 113.830616 -170.894991) (xy 113.821265 -170.915144)
			(xy 113.820702 -170.926252) (xy 113.820702 -171.003468) (xy 113.821271 -171.014578) (xy 113.830609 -171.034736)
			(xy 113.838736 -171.04233) (xy 113.859472 -171.060514) (xy 113.895939 -171.101889) (xy 113.926067 -171.148085)
			(xy 113.949228 -171.198138) (xy 113.96494 -171.251005) (xy 113.972874 -171.305584) (xy 113.973356 -171.33316)
			(xy 113.97287 -171.360411) (xy 113.965114 -171.414359) (xy 113.949759 -171.466654) (xy 113.927117 -171.516231)
			(xy 113.897651 -171.562081) (xy 113.86196 -171.603272) (xy 113.820769 -171.638963) (xy 113.774919 -171.668429)
			(xy 113.725342 -171.691071) (xy 113.673047 -171.706426) (xy 113.619099 -171.714182) (xy 113.564597 -171.714182)
			(xy 113.510649 -171.706426) (xy 113.458354 -171.691071) (xy 113.408777 -171.668429) (xy 113.362927 -171.638963)
			(xy 113.321736 -171.603272) (xy 113.286045 -171.562081) (xy 113.256579 -171.516231) (xy 113.233937 -171.466654)
			(xy 113.218582 -171.414359) (xy 113.210826 -171.360411) (xy 113.21034 -171.33316) (xy 103.418132 -171.33316)
			(xy 103.418132 -171.834556) (xy 103.418703 -171.844535) (xy 103.426425 -171.862948) (xy 103.440542 -171.877069)
			(xy 103.458953 -171.884795) (xy 103.468932 -171.885356) (xy 108.015278 -171.885356) (xy 108.040263 -171.885937)
			(xy 108.089273 -171.895689) (xy 108.135442 -171.914806) (xy 108.177001 -171.942553) (xy 108.19511 -171.959778)
			(xy 108.596938 -172.361606) (xy 108.614175 -172.379703) (xy 108.641914 -172.421266) (xy 108.661018 -172.46744)
			(xy 108.670753 -172.516453) (xy 108.67136 -172.541438) (xy 108.67136 -173.932342) (xy 108.671814 -173.942347)
			(xy 108.679537 -173.960811) (xy 108.686346 -173.968156) (xy 108.70723 -173.989774) (xy 108.742644 -174.038337)
			(xy 108.770001 -174.091854) (xy 108.788624 -174.149) (xy 108.798051 -174.20836) (xy 108.798614 -174.238412)
			(xy 108.798133 -174.265663) (xy 108.790375 -174.319611) (xy 108.781028 -174.351442) (xy 109.039914 -174.351442)
			(xy 109.040422 -174.323968) (xy 109.048308 -174.269589) (xy 109.063923 -174.216907) (xy 109.086943 -174.167014)
			(xy 109.11689 -174.120944) (xy 109.134656 -174.099982) (xy 109.140752 -174.09287) (xy 109.147102 -174.075852)
			(xy 109.147102 -173.99) (xy 109.140752 -173.972982) (xy 109.134656 -173.96587) (xy 109.11689 -173.94491)
			(xy 109.086967 -173.898827) (xy 109.063955 -173.848932) (xy 109.04833 -173.796255) (xy 109.040413 -173.741882)
			(xy 109.039914 -173.71441) (xy 109.0404 -173.687159) (xy 109.048156 -173.633211) (xy 109.063511 -173.580916)
			(xy 109.086153 -173.531339) (xy 109.115619 -173.485489) (xy 109.15131 -173.444298) (xy 109.192501 -173.408607)
			(xy 109.238351 -173.379141) (xy 109.287928 -173.356499) (xy 109.340223 -173.341144) (xy 109.394171 -173.333388)
			(xy 109.448673 -173.333388) (xy 109.502621 -173.341144) (xy 109.554916 -173.356499) (xy 109.604493 -173.379141)
			(xy 109.650343 -173.408607) (xy 109.691534 -173.444298) (xy 109.727225 -173.485489) (xy 109.756691 -173.531339)
			(xy 109.779333 -173.580916) (xy 109.794688 -173.633211) (xy 109.802444 -173.687159) (xy 109.80293 -173.71441)
			(xy 109.802442 -173.741884) (xy 109.79455 -173.796264) (xy 109.778929 -173.848946) (xy 109.755905 -173.898839)
			(xy 109.725955 -173.944908) (xy 109.708188 -173.96587) (xy 109.702092 -173.972982) (xy 109.695742 -173.99)
			(xy 109.695742 -174.075852) (xy 109.702092 -174.09287) (xy 109.708188 -174.099982) (xy 109.725923 -174.120968)
			(xy 109.755852 -174.167043) (xy 109.778871 -174.216931) (xy 109.794504 -174.269603) (xy 109.802427 -174.323971)
			(xy 109.80293 -174.351442) (xy 109.802444 -174.378693) (xy 109.794688 -174.432641) (xy 109.779333 -174.484936)
			(xy 109.756691 -174.534513) (xy 109.727225 -174.580363) (xy 109.691534 -174.621554) (xy 109.650343 -174.657245)
			(xy 109.604493 -174.686711) (xy 109.554916 -174.709353) (xy 109.502621 -174.724708) (xy 109.448673 -174.732464)
			(xy 109.394171 -174.732464) (xy 109.340223 -174.724708) (xy 109.287928 -174.709353) (xy 109.238351 -174.686711)
			(xy 109.192501 -174.657245) (xy 109.15131 -174.621554) (xy 109.115619 -174.580363) (xy 109.086153 -174.534513)
			(xy 109.063511 -174.484936) (xy 109.048156 -174.432641) (xy 109.0404 -174.378693) (xy 109.039914 -174.351442)
			(xy 108.781028 -174.351442) (xy 108.775019 -174.371905) (xy 108.752377 -174.421482) (xy 108.72291 -174.467332)
			(xy 108.687218 -174.508522) (xy 108.646027 -174.544214) (xy 108.600177 -174.57368) (xy 108.5506 -174.596321)
			(xy 108.498305 -174.611677) (xy 108.444357 -174.619434) (xy 108.417106 -174.61992) (xy 108.391871 -174.619518)
			(xy 108.341837 -174.612901) (xy 108.293117 -174.599729) (xy 108.246565 -174.580234) (xy 108.224574 -174.56785)
			(xy 108.214922 -174.562008) (xy 108.192824 -174.559976) (xy 108.098336 -174.593504) (xy 108.082334 -174.608998)
			(xy 108.07827 -174.619412) (xy 108.067539 -174.646173) (xy 108.039255 -174.696413) (xy 108.00373 -174.741822)
			(xy 107.961773 -174.781365) (xy 107.914341 -174.81414) (xy 107.862515 -174.839401) (xy 107.807477 -174.856571)
			(xy 107.750481 -174.865259) (xy 107.721654 -174.865792) (xy 107.694401 -174.865365) (xy 107.64045 -174.857602)
			(xy 107.588153 -174.84224) (xy 107.538575 -174.819592) (xy 107.492724 -174.79012) (xy 107.451534 -174.754422)
			(xy 107.415843 -174.713226) (xy 107.386378 -174.667371) (xy 107.363738 -174.617788) (xy 107.348385 -174.565489)
			(xy 107.340631 -174.511537) (xy 107.340146 -174.484284) (xy 107.340809 -174.452721) (xy 107.351194 -174.390456)
			(xy 107.371679 -174.330747) (xy 107.38612 -174.302674) (xy 107.390946 -174.293784) (xy 107.392978 -174.274226)
			(xy 107.367324 -174.186088) (xy 107.354878 -174.170594) (xy 107.345988 -174.165514) (xy 107.320862 -174.151006)
			(xy 107.27498 -174.115496) (xy 107.235007 -174.073445) (xy 107.201865 -174.025824) (xy 107.176318 -173.973733)
			(xy 107.158957 -173.918372) (xy 107.150182 -173.861021) (xy 107.149646 -173.832012) (xy 107.150132 -173.804761)
			(xy 107.157888 -173.750813) (xy 107.173243 -173.698518) (xy 107.195885 -173.648941) (xy 107.225351 -173.603091)
			(xy 107.261042 -173.5619) (xy 107.302233 -173.526209) (xy 107.348083 -173.496743) (xy 107.39766 -173.474101)
			(xy 107.449955 -173.458746) (xy 107.503903 -173.45099) (xy 107.558405 -173.45099) (xy 107.612353 -173.458746)
			(xy 107.664648 -173.474101) (xy 107.714225 -173.496743) (xy 107.760075 -173.526209) (xy 107.801266 -173.5619)
			(xy 107.836957 -173.603091) (xy 107.866423 -173.648941) (xy 107.889065 -173.698518) (xy 107.90442 -173.750813)
			(xy 107.912176 -173.804761) (xy 107.912662 -173.832012) (xy 107.911996 -173.863575) (xy 107.901612 -173.92584)
			(xy 107.881129 -173.985549) (xy 107.866688 -174.013622) (xy 107.861862 -174.022512) (xy 107.85983 -174.04207)
			(xy 107.885484 -174.130208) (xy 107.89793 -174.145702) (xy 107.90682 -174.150782) (xy 107.914186 -174.154846)
			(xy 107.923838 -174.160688) (xy 107.945936 -174.16272) (xy 108.040424 -174.129192) (xy 108.056426 -174.113698)
			(xy 108.06049 -174.103284) (xy 108.070501 -174.078168) (xy 108.096575 -174.030803) (xy 108.129067 -173.987589)
			(xy 108.147866 -173.968156) (xy 108.154576 -173.960741) (xy 108.162306 -173.942325) (xy 108.162852 -173.932342)
			(xy 108.162852 -172.66793) (xy 108.162424 -172.657861) (xy 108.154706 -172.639262) (xy 108.147866 -172.631862)
			(xy 107.924854 -172.40885) (xy 107.917424 -172.402048) (xy 107.898848 -172.394305) (xy 107.888786 -172.393864)
			(xy 103.29037 -172.393864) (xy 103.280297 -172.394257) (xy 103.261698 -172.401998) (xy 103.254302 -172.40885)
			(xy 101.324918 -174.338234) (xy 101.318073 -174.34563) (xy 101.310355 -174.364232) (xy 101.309932 -174.374302)
			(xy 101.309932 -175.92421) (xy 101.309313 -175.949193) (xy 101.299573 -175.998201) (xy 101.280468 -176.044371)
			(xy 101.252731 -176.085932) (xy 101.23551 -176.104042) (xy 101.233478 -176.106074) (xy 103.363522 -176.106074)
			(xy 103.364031 -176.078501) (xy 103.371974 -176.02393) (xy 103.38769 -175.97107) (xy 103.410851 -175.921024)
			(xy 103.440977 -175.874833) (xy 103.477438 -175.833461) (xy 103.498142 -175.815244) (xy 103.506243 -175.807626)
			(xy 103.515605 -175.787486) (xy 103.516176 -175.776382) (xy 103.516176 -175.699166) (xy 103.515651 -175.688051)
			(xy 103.506283 -175.667892) (xy 103.498142 -175.660304) (xy 103.477409 -175.642118) (xy 103.440941 -175.600744)
			(xy 103.410812 -175.554551) (xy 103.387648 -175.5045) (xy 103.371933 -175.451635) (xy 103.363993 -175.397059)
			(xy 103.363996 -175.341908) (xy 103.37194 -175.287332) (xy 103.38766 -175.234469) (xy 103.410828 -175.18442)
			(xy 103.440962 -175.138229) (xy 103.477433 -175.096859) (xy 103.498142 -175.078644) (xy 103.506243 -175.071026)
			(xy 103.515605 -175.050886) (xy 103.516176 -175.039782) (xy 103.516176 -174.962566) (xy 103.515651 -174.951451)
			(xy 103.506283 -174.931292) (xy 103.498142 -174.923704) (xy 103.477438 -174.905485) (xy 103.440965 -174.864119)
			(xy 103.410831 -174.817931) (xy 103.387664 -174.767884) (xy 103.371947 -174.715023) (xy 103.364007 -174.660448)
			(xy 103.363522 -174.632874) (xy 103.363931 -174.605619) (xy 103.371692 -174.551665) (xy 103.387053 -174.499364)
			(xy 103.409701 -174.449782) (xy 103.439174 -174.403927) (xy 103.474874 -174.362734) (xy 103.516072 -174.327041)
			(xy 103.561931 -174.297574) (xy 103.611516 -174.274933) (xy 103.663819 -174.25958) (xy 103.717775 -174.251827)
			(xy 103.74503 -174.251366) (xy 103.772885 -174.251887) (xy 103.827999 -174.260014) (xy 103.881348 -174.276062)
			(xy 103.9318 -174.29969) (xy 103.978283 -174.330397) (xy 104.019812 -174.367532) (xy 104.055506 -174.410306)
			(xy 104.084606 -174.457812) (xy 104.106496 -174.509042) (xy 104.114092 -174.535846) (xy 104.116378 -174.544736)
			(xy 104.127046 -174.559976) (xy 104.198928 -174.607728) (xy 104.216962 -174.611792) (xy 104.226106 -174.610522)
			(xy 104.239123 -174.608854) (xy 104.265307 -174.607073) (xy 104.27843 -174.606966) (xy 104.292579 -174.607057)
			(xy 104.320802 -174.609093) (xy 104.334818 -174.61103) (xy 104.344978 -174.612554) (xy 104.364536 -174.607728)
			(xy 104.438958 -174.551848) (xy 104.449118 -174.534322) (xy 104.450388 -174.524162) (xy 104.454477 -174.497008)
			(xy 104.469449 -174.444178) (xy 104.49184 -174.394039) (xy 104.521187 -174.347628) (xy 104.556885 -174.305904)
			(xy 104.598194 -174.269727) (xy 104.644263 -174.239846) (xy 104.69414 -174.216877) (xy 104.746794 -174.201296)
			(xy 104.801138 -174.193424) (xy 104.828594 -174.192946) (xy 104.855843 -174.193483) (xy 104.909787 -174.201238)
			(xy 104.962077 -174.21659) (xy 105.011652 -174.239227) (xy 105.0575 -174.268688) (xy 105.098689 -174.304374)
			(xy 105.134381 -174.345558) (xy 105.163848 -174.391403) (xy 105.186492 -174.440974) (xy 105.201851 -174.493263)
			(xy 105.209613 -174.547205) (xy 105.210102 -174.574454) (xy 105.209604 -174.602027) (xy 105.201658 -174.656599)
			(xy 105.185939 -174.709458) (xy 105.162775 -174.759504) (xy 105.132649 -174.805694) (xy 105.096187 -174.847067)
			(xy 105.075482 -174.865284) (xy 105.067373 -174.872895) (xy 105.058014 -174.89304) (xy 105.057448 -174.904146)
			(xy 105.057448 -174.981362) (xy 105.058006 -174.992473) (xy 105.06735 -175.012633) (xy 105.075482 -175.020224)
			(xy 105.096204 -175.038423) (xy 105.132675 -175.079794) (xy 105.162806 -175.125986) (xy 105.18597 -175.176037)
			(xy 105.201683 -175.228902) (xy 105.209619 -175.283478) (xy 105.210102 -175.311054) (xy 105.209602 -175.338306)
			(xy 105.201851 -175.392256) (xy 105.186501 -175.444553) (xy 105.163863 -175.494134) (xy 105.134399 -175.539987)
			(xy 105.098709 -175.581181) (xy 105.05752 -175.616875) (xy 105.011669 -175.646344) (xy 104.962091 -175.668987)
			(xy 104.909795 -175.684343) (xy 104.855846 -175.692099) (xy 104.828594 -175.692562) (xy 104.794304 -175.691038)
			(xy 104.784144 -175.690022) (xy 104.76484 -175.696118) (xy 104.694228 -175.7553) (xy 104.68483 -175.773334)
			(xy 104.683814 -175.783494) (xy 104.680902 -175.811672) (xy 104.667721 -175.866765) (xy 104.646537 -175.919302)
			(xy 104.617814 -175.968128) (xy 104.582185 -176.012168) (xy 104.540433 -176.050454) (xy 104.493478 -176.082142)
			(xy 104.442352 -176.106537) (xy 104.38818 -176.123101) (xy 104.332154 -176.13147) (xy 104.30383 -176.131982)
			(xy 104.285811 -176.131766) (xy 104.249936 -176.128328) (xy 104.232202 -176.125124) (xy 104.222804 -176.123346)
			(xy 104.203754 -176.127156) (xy 104.12857 -176.174908) (xy 104.11714 -176.190656) (xy 104.114854 -176.200054)
			(xy 104.107489 -176.227108) (xy 104.085856 -176.278836) (xy 104.056888 -176.326842) (xy 104.021209 -176.370094)
			(xy 103.979585 -176.407661) (xy 103.932913 -176.438734) (xy 103.882198 -176.462644) (xy 103.82853 -176.478878)
			(xy 103.773065 -176.487085) (xy 103.74503 -176.487582) (xy 103.717777 -176.487117) (xy 103.663824 -176.479363)
			(xy 103.611525 -176.46401) (xy 103.561943 -176.441369) (xy 103.516089 -176.411901) (xy 103.474895 -176.376208)
			(xy 103.439201 -176.335014) (xy 103.409733 -176.28916) (xy 103.387092 -176.239579) (xy 103.371738 -176.187279)
			(xy 103.363984 -176.133327) (xy 103.363522 -176.106074) (xy 101.233478 -176.106074) (xy 100.304346 -177.035206)
			(xy 100.297517 -177.042615) (xy 100.289789 -177.061207) (xy 100.28936 -177.071274) (xy 100.28936 -177.65776)
			(xy 104.95534 -177.65776) (xy 104.955833 -177.630186) (xy 104.963778 -177.575614) (xy 104.979497 -177.522754)
			(xy 105.002662 -177.472708) (xy 105.03279 -177.426517) (xy 105.069254 -177.385146) (xy 105.08996 -177.36693)
			(xy 105.09807 -177.35932) (xy 105.107426 -177.339174) (xy 105.107994 -177.328068) (xy 105.107994 -177.250852)
			(xy 105.107414 -177.239744) (xy 105.098084 -177.219585) (xy 105.08996 -177.21199) (xy 105.069233 -177.193797)
			(xy 105.032765 -177.152423) (xy 105.002636 -177.106229) (xy 104.979474 -177.056178) (xy 104.96376 -177.003313)
			(xy 104.955824 -176.948736) (xy 104.95534 -176.92116) (xy 104.955873 -176.892873) (xy 104.964232 -176.836919)
			(xy 104.980763 -176.782814) (xy 105.005102 -176.731742) (xy 105.036715 -176.684824) (xy 105.07491 -176.643089)
			(xy 105.118849 -176.607451) (xy 105.167569 -176.578693) (xy 105.193592 -176.567592) (xy 105.204768 -176.56302)
			(xy 105.220262 -176.545494) (xy 105.247694 -176.444148) (xy 105.243122 -176.42078) (xy 105.235756 -176.411382)
			(xy 105.217491 -176.38675) (xy 105.188467 -176.332735) (xy 105.168676 -176.274697) (xy 105.158649 -176.214204)
			(xy 105.158032 -176.183544) (xy 105.158475 -176.156925) (xy 105.166047 -176.104228) (xy 105.181042 -176.053146)
			(xy 105.203155 -176.004718) (xy 105.231937 -175.95993) (xy 105.2668 -175.919696) (xy 105.307035 -175.884833)
			(xy 105.351823 -175.856052) (xy 105.400251 -175.83394) (xy 105.451334 -175.818945) (xy 105.504031 -175.811375)
			(xy 105.53065 -175.810926) (xy 105.557072 -175.811372) (xy 105.609387 -175.818828) (xy 105.660125 -175.833596)
			(xy 105.708269 -175.855382) (xy 105.752854 -175.883748) (xy 105.77322 -175.900588) (xy 105.780078 -175.906684)
			(xy 105.797096 -175.91278) (xy 105.881424 -175.91278) (xy 105.898442 -175.906684) (xy 105.9053 -175.900588)
			(xy 105.925666 -175.883749) (xy 105.970252 -175.855384) (xy 106.018396 -175.833597) (xy 106.069133 -175.818826)
			(xy 106.121448 -175.811366) (xy 106.174292 -175.811366) (xy 106.226607 -175.818826) (xy 106.277344 -175.833597)
			(xy 106.325488 -175.855384) (xy 106.370074 -175.883749) (xy 106.39044 -175.900588) (xy 106.397298 -175.906684)
			(xy 106.414316 -175.91278) (xy 106.498644 -175.91278) (xy 106.515662 -175.906684) (xy 106.52252 -175.900588)
			(xy 106.542877 -175.883739) (xy 106.587469 -175.855386) (xy 106.635616 -175.833609) (xy 106.686354 -175.818844)
			(xy 106.738669 -175.811386) (xy 106.76509 -175.810926) (xy 106.792981 -175.811332) (xy 106.848139 -175.819645)
			(xy 106.901442 -175.836085) (xy 106.951699 -175.860287) (xy 106.997788 -175.891709) (xy 107.038679 -175.929649)
			(xy 107.073459 -175.97326) (xy 107.10135 -176.021567) (xy 107.121729 -176.073492) (xy 107.134142 -176.127875)
			(xy 107.138311 -176.1835) (xy 107.134142 -176.239125) (xy 107.121729 -176.293508) (xy 107.10135 -176.345433)
			(xy 107.073459 -176.39374) (xy 107.038679 -176.437351) (xy 106.997788 -176.475291) (xy 106.951699 -176.506713)
			(xy 106.901442 -176.530915) (xy 106.848139 -176.547355) (xy 106.792981 -176.555668) (xy 106.76509 -176.556162)
			(xy 106.738669 -176.555695) (xy 106.686354 -176.548245) (xy 106.635616 -176.533482) (xy 106.587472 -176.5117)
			(xy 106.542886 -176.483338) (xy 106.52252 -176.4665) (xy 106.515662 -176.460404) (xy 106.498644 -176.454308)
			(xy 106.414316 -176.454308) (xy 106.397298 -176.460404) (xy 106.39044 -176.4665) (xy 106.370074 -176.483339)
			(xy 106.325488 -176.511704) (xy 106.277344 -176.533491) (xy 106.226607 -176.548262) (xy 106.174292 -176.555722)
			(xy 106.121448 -176.555722) (xy 106.069133 -176.548262) (xy 106.018396 -176.533491) (xy 105.970252 -176.511704)
			(xy 105.925666 -176.483339) (xy 105.9053 -176.4665) (xy 105.898442 -176.460404) (xy 105.881424 -176.454308)
			(xy 105.797096 -176.454308) (xy 105.780078 -176.460404) (xy 105.77322 -176.4665) (xy 105.750945 -176.484878)
			(xy 105.701825 -176.515237) (xy 105.67543 -176.526952) (xy 105.664508 -176.531524) (xy 105.649014 -176.549558)
			(xy 105.623106 -176.651158) (xy 105.627932 -176.674272) (xy 105.635552 -176.68367) (xy 105.651203 -176.703987)
			(xy 105.677447 -176.748049) (xy 105.697545 -176.795234) (xy 105.711132 -176.844687) (xy 105.717962 -176.895517)
			(xy 105.718356 -176.92116) (xy 105.717878 -176.948734) (xy 105.70993 -177.003307) (xy 105.694209 -177.056168)
			(xy 105.671041 -177.106214) (xy 105.64091 -177.152404) (xy 105.604443 -177.193775) (xy 105.583736 -177.21199)
			(xy 105.575616 -177.219591) (xy 105.566265 -177.239744) (xy 105.565702 -177.250852) (xy 105.565702 -177.328068)
			(xy 105.566271 -177.339178) (xy 105.575609 -177.359336) (xy 105.583736 -177.36693) (xy 105.604472 -177.385114)
			(xy 105.640939 -177.426489) (xy 105.671067 -177.472685) (xy 105.694228 -177.522738) (xy 105.70994 -177.575605)
			(xy 105.717874 -177.630184) (xy 105.718356 -177.65776) (xy 105.71787 -177.685011) (xy 105.710114 -177.738959)
			(xy 105.694759 -177.791254) (xy 105.672117 -177.840831) (xy 105.642651 -177.886681) (xy 105.60696 -177.927872)
			(xy 105.565769 -177.963563) (xy 105.519919 -177.993029) (xy 105.470342 -178.015671) (xy 105.418047 -178.031026)
			(xy 105.364099 -178.038782) (xy 105.309597 -178.038782) (xy 105.255649 -178.031026) (xy 105.203354 -178.015671)
			(xy 105.153777 -177.993029) (xy 105.107927 -177.963563) (xy 105.066736 -177.927872) (xy 105.031045 -177.886681)
			(xy 105.001579 -177.840831) (xy 104.978937 -177.791254) (xy 104.963582 -177.738959) (xy 104.955826 -177.685011)
			(xy 104.95534 -177.65776) (xy 100.28936 -177.65776) (xy 100.28936 -178.453542) (xy 100.289814 -178.463547)
			(xy 100.297537 -178.482011) (xy 100.304346 -178.489356) (xy 100.32523 -178.510974) (xy 100.360644 -178.559537)
			(xy 100.388001 -178.613054) (xy 100.406624 -178.6702) (xy 100.416051 -178.72956) (xy 100.416614 -178.759612)
			(xy 100.416133 -178.786863) (xy 100.408375 -178.840811) (xy 100.399028 -178.872642) (xy 100.657914 -178.872642)
			(xy 100.658422 -178.845168) (xy 100.666308 -178.790789) (xy 100.681923 -178.738107) (xy 100.704943 -178.688214)
			(xy 100.73489 -178.642144) (xy 100.752656 -178.621182) (xy 100.758752 -178.61407) (xy 100.765102 -178.597052)
			(xy 100.765102 -178.5112) (xy 100.758752 -178.494182) (xy 100.752656 -178.48707) (xy 100.73489 -178.46611)
			(xy 100.704967 -178.420027) (xy 100.681955 -178.370132) (xy 100.66633 -178.317455) (xy 100.658413 -178.263082)
			(xy 100.657914 -178.23561) (xy 100.6584 -178.208359) (xy 100.666156 -178.154411) (xy 100.681511 -178.102116)
			(xy 100.704153 -178.052539) (xy 100.733619 -178.006689) (xy 100.76931 -177.965498) (xy 100.810501 -177.929807)
			(xy 100.856351 -177.900341) (xy 100.905928 -177.877699) (xy 100.958223 -177.862344) (xy 101.012171 -177.854588)
			(xy 101.066673 -177.854588) (xy 101.120621 -177.862344) (xy 101.172916 -177.877699) (xy 101.222493 -177.900341)
			(xy 101.268343 -177.929807) (xy 101.309534 -177.965498) (xy 101.345225 -178.006689) (xy 101.374691 -178.052539)
			(xy 101.397333 -178.102116) (xy 101.412688 -178.154411) (xy 101.420444 -178.208359) (xy 101.42093 -178.23561)
			(xy 101.420442 -178.263084) (xy 101.41255 -178.317464) (xy 101.396929 -178.370146) (xy 101.373905 -178.420039)
			(xy 101.343955 -178.466108) (xy 101.326188 -178.48707) (xy 101.320092 -178.494182) (xy 101.313742 -178.5112)
			(xy 101.313742 -178.597052) (xy 101.320092 -178.61407) (xy 101.326188 -178.621182) (xy 101.343923 -178.642168)
			(xy 101.373852 -178.688243) (xy 101.396871 -178.738131) (xy 101.412504 -178.790803) (xy 101.420427 -178.845171)
			(xy 101.42093 -178.872642) (xy 101.420444 -178.899893) (xy 101.412688 -178.953841) (xy 101.397333 -179.006136)
			(xy 101.374691 -179.055713) (xy 101.345225 -179.101563) (xy 101.309534 -179.142754) (xy 101.268343 -179.178445)
			(xy 101.222493 -179.207911) (xy 101.172916 -179.230553) (xy 101.120621 -179.245908) (xy 101.066673 -179.253664)
			(xy 101.012171 -179.253664) (xy 100.958223 -179.245908) (xy 100.905928 -179.230553) (xy 100.856351 -179.207911)
			(xy 100.810501 -179.178445) (xy 100.76931 -179.142754) (xy 100.733619 -179.101563) (xy 100.704153 -179.055713)
			(xy 100.681511 -179.006136) (xy 100.666156 -178.953841) (xy 100.6584 -178.899893) (xy 100.657914 -178.872642)
			(xy 100.399028 -178.872642) (xy 100.393019 -178.893105) (xy 100.370377 -178.942682) (xy 100.34091 -178.988532)
			(xy 100.305218 -179.029722) (xy 100.264027 -179.065414) (xy 100.218177 -179.09488) (xy 100.1686 -179.117521)
			(xy 100.116305 -179.132877) (xy 100.062357 -179.140634) (xy 100.035106 -179.14112) (xy 100.009871 -179.140718)
			(xy 99.959837 -179.134101) (xy 99.911117 -179.120929) (xy 99.864565 -179.101434) (xy 99.842574 -179.08905)
			(xy 99.832922 -179.083208) (xy 99.810824 -179.081176) (xy 99.716336 -179.114704) (xy 99.700334 -179.130198)
			(xy 99.69627 -179.140612) (xy 99.685539 -179.167373) (xy 99.657255 -179.217613) (xy 99.62173 -179.263022)
			(xy 99.579773 -179.302565) (xy 99.532341 -179.33534) (xy 99.480515 -179.360601) (xy 99.425477 -179.377771)
			(xy 99.368481 -179.386459) (xy 99.339654 -179.386992) (xy 99.312401 -179.386565) (xy 99.25845 -179.378802)
			(xy 99.206153 -179.36344) (xy 99.156575 -179.340792) (xy 99.110724 -179.31132) (xy 99.069534 -179.275622)
			(xy 99.033843 -179.234426) (xy 99.004378 -179.188571) (xy 98.981738 -179.138988) (xy 98.966385 -179.086689)
			(xy 98.958631 -179.032737) (xy 98.958146 -179.005484) (xy 98.958809 -178.973921) (xy 98.969194 -178.911656)
			(xy 98.989679 -178.851947) (xy 99.00412 -178.823874) (xy 99.008946 -178.814984) (xy 99.010978 -178.795426)
			(xy 98.985324 -178.707288) (xy 98.972878 -178.691794) (xy 98.963988 -178.686714) (xy 98.938862 -178.672206)
			(xy 98.89298 -178.636696) (xy 98.853007 -178.594645) (xy 98.819865 -178.547024) (xy 98.794318 -178.494933)
			(xy 98.776957 -178.439572) (xy 98.768182 -178.382221) (xy 98.767646 -178.353212) (xy 98.768132 -178.325961)
			(xy 98.775888 -178.272013) (xy 98.791243 -178.219718) (xy 98.813885 -178.170141) (xy 98.843351 -178.124291)
			(xy 98.879042 -178.0831) (xy 98.920233 -178.047409) (xy 98.966083 -178.017943) (xy 99.01566 -177.995301)
			(xy 99.067955 -177.979946) (xy 99.121903 -177.97219) (xy 99.176405 -177.97219) (xy 99.230353 -177.979946)
			(xy 99.282648 -177.995301) (xy 99.332225 -178.017943) (xy 99.378075 -178.047409) (xy 99.419266 -178.0831)
			(xy 99.454957 -178.124291) (xy 99.484423 -178.170141) (xy 99.507065 -178.219718) (xy 99.52242 -178.272013)
			(xy 99.530176 -178.325961) (xy 99.530662 -178.353212) (xy 99.529996 -178.384775) (xy 99.519612 -178.44704)
			(xy 99.499129 -178.506749) (xy 99.484688 -178.534822) (xy 99.479862 -178.543712) (xy 99.47783 -178.56327)
			(xy 99.503484 -178.651408) (xy 99.51593 -178.666902) (xy 99.52482 -178.671982) (xy 99.532186 -178.676046)
			(xy 99.541838 -178.681888) (xy 99.563936 -178.68392) (xy 99.658424 -178.650392) (xy 99.674426 -178.634898)
			(xy 99.67849 -178.624484) (xy 99.688501 -178.599368) (xy 99.714575 -178.552003) (xy 99.747067 -178.508789)
			(xy 99.765866 -178.489356) (xy 99.772576 -178.481941) (xy 99.780306 -178.463525) (xy 99.780852 -178.453542)
			(xy 99.780852 -177.071274) (xy 99.780453 -177.061202) (xy 99.772715 -177.042603) (xy 99.765866 -177.035206)
			(xy 99.48291 -176.75225) (xy 99.475495 -176.745429) (xy 99.456907 -176.737696) (xy 99.446842 -176.737264)
			(xy 92.29217 -176.737264) (xy 92.282097 -176.737657) (xy 92.263498 -176.745398) (xy 92.256102 -176.75225)
			(xy 91.912186 -177.096166) (xy 91.905367 -177.103582) (xy 91.897635 -177.122169) (xy 91.8972 -177.132234)
			(xy 91.8972 -178.43627) (xy 91.897628 -178.446279) (xy 91.905369 -178.464742) (xy 91.912186 -178.472084)
			(xy 91.93309 -178.493683) (xy 91.9685 -178.542252) (xy 91.995853 -178.595774) (xy 92.014471 -178.652924)
			(xy 92.023894 -178.712287) (xy 92.024454 -178.74234) (xy 92.02396 -178.76959) (xy 92.016199 -178.823535)
			(xy 92.006849 -178.85537) (xy 92.265754 -178.85537) (xy 92.266209 -178.827894) (xy 92.274107 -178.773513)
			(xy 92.289733 -178.720829) (xy 92.312765 -178.670937) (xy 92.342725 -178.62487) (xy 92.360496 -178.60391)
			(xy 92.366592 -178.596798) (xy 92.372942 -178.57978) (xy 92.372942 -178.493928) (xy 92.366592 -178.47691)
			(xy 92.360496 -178.469798) (xy 92.34275 -178.448822) (xy 92.312822 -178.402744) (xy 92.289806 -178.352853)
			(xy 92.274176 -178.300179) (xy 92.266255 -178.245809) (xy 92.265754 -178.218338) (xy 92.26624 -178.191087)
			(xy 92.273996 -178.137139) (xy 92.289351 -178.084844) (xy 92.311993 -178.035267) (xy 92.341459 -177.989417)
			(xy 92.37715 -177.948226) (xy 92.418341 -177.912535) (xy 92.464191 -177.883069) (xy 92.513768 -177.860427)
			(xy 92.566063 -177.845072) (xy 92.620011 -177.837316) (xy 92.674513 -177.837316) (xy 92.728461 -177.845072)
			(xy 92.780756 -177.860427) (xy 92.830333 -177.883069) (xy 92.876183 -177.912535) (xy 92.917374 -177.948226)
			(xy 92.953065 -177.989417) (xy 92.982531 -178.035267) (xy 93.005173 -178.084844) (xy 93.020528 -178.137139)
			(xy 93.028284 -178.191087) (xy 93.02877 -178.218338) (xy 93.028313 -178.245814) (xy 93.020415 -178.300195)
			(xy 93.004789 -178.352878) (xy 92.981757 -178.40277) (xy 92.951799 -178.448837) (xy 92.934028 -178.469798)
			(xy 92.927932 -178.47691) (xy 92.921582 -178.493928) (xy 92.921582 -178.57978) (xy 92.927932 -178.596798)
			(xy 92.934028 -178.60391) (xy 92.951782 -178.62488) (xy 92.981707 -178.67096) (xy 93.004722 -178.720852)
			(xy 93.02035 -178.773527) (xy 93.028269 -178.827898) (xy 93.02877 -178.85537) (xy 93.028284 -178.882621)
			(xy 93.020528 -178.936569) (xy 93.005173 -178.988864) (xy 92.982531 -179.038441) (xy 92.953065 -179.084291)
			(xy 92.917374 -179.125482) (xy 92.876183 -179.161173) (xy 92.830333 -179.190639) (xy 92.780756 -179.213281)
			(xy 92.728461 -179.228636) (xy 92.674513 -179.236392) (xy 92.620011 -179.236392) (xy 92.566063 -179.228636)
			(xy 92.513768 -179.213281) (xy 92.464191 -179.190639) (xy 92.418341 -179.161173) (xy 92.37715 -179.125482)
			(xy 92.341459 -179.084291) (xy 92.311993 -179.038441) (xy 92.289351 -178.988864) (xy 92.273996 -178.936569)
			(xy 92.26624 -178.882621) (xy 92.265754 -178.85537) (xy 92.006849 -178.85537) (xy 92.000841 -178.875827)
			(xy 91.978198 -178.925401) (xy 91.948732 -178.971249) (xy 91.913042 -179.012438) (xy 91.871854 -179.048129)
			(xy 91.826007 -179.077596) (xy 91.776433 -179.100239) (xy 91.724141 -179.115597) (xy 91.670196 -179.123359)
			(xy 91.642946 -179.123848) (xy 91.61771 -179.123468) (xy 91.567676 -179.116844) (xy 91.518956 -179.103666)
			(xy 91.472404 -179.084165) (xy 91.450414 -179.071778) (xy 91.440762 -179.065936) (xy 91.418664 -179.063904)
			(xy 91.324176 -179.097432) (xy 91.308174 -179.112926) (xy 91.30411 -179.12334) (xy 91.293443 -179.150129)
			(xy 91.26515 -179.20037) (xy 91.229616 -179.245779) (xy 91.187649 -179.28532) (xy 91.140208 -179.318092)
			(xy 91.088373 -179.343348) (xy 91.033327 -179.360511) (xy 90.976324 -179.369192) (xy 90.947494 -179.36972)
			(xy 90.920243 -179.369228) (xy 90.866296 -179.361471) (xy 90.814002 -179.346116) (xy 90.764426 -179.323475)
			(xy 90.718576 -179.294009) (xy 90.677386 -179.258318) (xy 90.641695 -179.217129) (xy 90.612228 -179.171279)
			(xy 90.589587 -179.121703) (xy 90.57423 -179.06941) (xy 90.566473 -179.015463) (xy 90.565986 -178.988212)
			(xy 90.566628 -178.956648) (xy 90.577023 -178.894383) (xy 90.597515 -178.834674) (xy 90.61196 -178.806602)
			(xy 90.616786 -178.797712) (xy 90.618818 -178.778154) (xy 90.593164 -178.690016) (xy 90.580718 -178.674522)
			(xy 90.571828 -178.669442) (xy 90.546724 -178.654899) (xy 90.50084 -178.619396) (xy 90.460864 -178.577351)
			(xy 90.427719 -178.529737) (xy 90.402168 -178.477651) (xy 90.384803 -178.422295) (xy 90.376024 -178.364948)
			(xy 90.375486 -178.33594) (xy 90.375972 -178.308689) (xy 90.383728 -178.254741) (xy 90.399083 -178.202446)
			(xy 90.421725 -178.152869) (xy 90.451191 -178.107019) (xy 90.486882 -178.065828) (xy 90.528073 -178.030137)
			(xy 90.573923 -178.000671) (xy 90.6235 -177.978029) (xy 90.675795 -177.962674) (xy 90.729743 -177.954918)
			(xy 90.784245 -177.954918) (xy 90.838193 -177.962674) (xy 90.890488 -177.978029) (xy 90.940065 -178.000671)
			(xy 90.985915 -178.030137) (xy 91.027106 -178.065828) (xy 91.062797 -178.107019) (xy 91.092263 -178.152869)
			(xy 91.114905 -178.202446) (xy 91.13026 -178.254741) (xy 91.138016 -178.308689) (xy 91.138502 -178.33594)
			(xy 91.137843 -178.367503) (xy 91.127455 -178.429768) (xy 91.106969 -178.489477) (xy 91.092528 -178.51755)
			(xy 91.087702 -178.52644) (xy 91.08567 -178.545998) (xy 91.111324 -178.634136) (xy 91.12377 -178.64963)
			(xy 91.13266 -178.65471) (xy 91.140026 -178.658774) (xy 91.149678 -178.664616) (xy 91.171776 -178.666648)
			(xy 91.266264 -178.63312) (xy 91.282266 -178.617626) (xy 91.28633 -178.607212) (xy 91.296341 -178.582096)
			(xy 91.322414 -178.534731) (xy 91.354907 -178.491516) (xy 91.373706 -178.472084) (xy 91.380453 -178.464699)
			(xy 91.38816 -178.44626) (xy 91.388692 -178.43627) (xy 91.388692 -177.132234) (xy 91.388251 -177.122166)
			(xy 91.380542 -177.103568) (xy 91.373706 -177.096166) (xy 90.92819 -176.65065) (xy 90.920782 -176.64382)
			(xy 90.902189 -176.636093) (xy 90.892122 -176.635664) (xy 83.98637 -176.635664) (xy 83.976297 -176.636057)
			(xy 83.957698 -176.643798) (xy 83.950302 -176.65065) (xy 83.514946 -177.086006) (xy 83.508117 -177.093415)
			(xy 83.500389 -177.112007) (xy 83.49996 -177.122074) (xy 83.49996 -178.504342) (xy 83.500414 -178.514347)
			(xy 83.508137 -178.532811) (xy 83.514946 -178.540156) (xy 83.53583 -178.561774) (xy 83.571244 -178.610337)
			(xy 83.598601 -178.663854) (xy 83.617224 -178.721) (xy 83.626651 -178.78036) (xy 83.627214 -178.810412)
			(xy 83.626733 -178.837663) (xy 83.618975 -178.891611) (xy 83.609628 -178.923442) (xy 83.868514 -178.923442)
			(xy 83.869022 -178.895968) (xy 83.876908 -178.841589) (xy 83.892523 -178.788907) (xy 83.915543 -178.739014)
			(xy 83.94549 -178.692944) (xy 83.963256 -178.671982) (xy 83.969352 -178.66487) (xy 83.975702 -178.647852)
			(xy 83.975702 -178.562) (xy 83.969352 -178.544982) (xy 83.963256 -178.53787) (xy 83.94549 -178.51691)
			(xy 83.915567 -178.470827) (xy 83.892555 -178.420932) (xy 83.87693 -178.368255) (xy 83.869013 -178.313882)
			(xy 83.868514 -178.28641) (xy 83.869 -178.259159) (xy 83.876756 -178.205211) (xy 83.892111 -178.152916)
			(xy 83.914753 -178.103339) (xy 83.944219 -178.057489) (xy 83.97991 -178.016298) (xy 84.021101 -177.980607)
			(xy 84.066951 -177.951141) (xy 84.116528 -177.928499) (xy 84.168823 -177.913144) (xy 84.222771 -177.905388)
			(xy 84.277273 -177.905388) (xy 84.331221 -177.913144) (xy 84.383516 -177.928499) (xy 84.433093 -177.951141)
			(xy 84.478943 -177.980607) (xy 84.520134 -178.016298) (xy 84.555825 -178.057489) (xy 84.585291 -178.103339)
			(xy 84.607933 -178.152916) (xy 84.623288 -178.205211) (xy 84.631044 -178.259159) (xy 84.63153 -178.28641)
			(xy 84.631042 -178.313884) (xy 84.62315 -178.368264) (xy 84.607529 -178.420946) (xy 84.584505 -178.470839)
			(xy 84.554555 -178.516908) (xy 84.536788 -178.53787) (xy 84.530692 -178.544982) (xy 84.524342 -178.562)
			(xy 84.524342 -178.647852) (xy 84.530692 -178.66487) (xy 84.536788 -178.671982) (xy 84.554523 -178.692968)
			(xy 84.584452 -178.739043) (xy 84.607471 -178.788931) (xy 84.623104 -178.841603) (xy 84.631027 -178.895971)
			(xy 84.63153 -178.923442) (xy 84.631044 -178.950693) (xy 84.623288 -179.004641) (xy 84.607933 -179.056936)
			(xy 84.585291 -179.106513) (xy 84.555825 -179.152363) (xy 84.520134 -179.193554) (xy 84.478943 -179.229245)
			(xy 84.433093 -179.258711) (xy 84.383516 -179.281353) (xy 84.331221 -179.296708) (xy 84.277273 -179.304464)
			(xy 84.222771 -179.304464) (xy 84.168823 -179.296708) (xy 84.116528 -179.281353) (xy 84.066951 -179.258711)
			(xy 84.021101 -179.229245) (xy 83.97991 -179.193554) (xy 83.944219 -179.152363) (xy 83.914753 -179.106513)
			(xy 83.892111 -179.056936) (xy 83.876756 -179.004641) (xy 83.869 -178.950693) (xy 83.868514 -178.923442)
			(xy 83.609628 -178.923442) (xy 83.603619 -178.943905) (xy 83.580977 -178.993482) (xy 83.55151 -179.039332)
			(xy 83.515818 -179.080522) (xy 83.474627 -179.116214) (xy 83.428777 -179.14568) (xy 83.3792 -179.168321)
			(xy 83.326905 -179.183677) (xy 83.272957 -179.191434) (xy 83.245706 -179.19192) (xy 83.220471 -179.191518)
			(xy 83.170437 -179.184901) (xy 83.121717 -179.171729) (xy 83.075165 -179.152234) (xy 83.053174 -179.13985)
			(xy 83.043522 -179.134008) (xy 83.021424 -179.131976) (xy 82.926936 -179.165504) (xy 82.910934 -179.180998)
			(xy 82.90687 -179.191412) (xy 82.896139 -179.218173) (xy 82.867855 -179.268413) (xy 82.83233 -179.313822)
			(xy 82.790373 -179.353365) (xy 82.742941 -179.38614) (xy 82.691115 -179.411401) (xy 82.636077 -179.428571)
			(xy 82.579081 -179.437259) (xy 82.550254 -179.437792) (xy 82.523001 -179.437365) (xy 82.46905 -179.429602)
			(xy 82.416753 -179.41424) (xy 82.367175 -179.391592) (xy 82.321324 -179.36212) (xy 82.280134 -179.326422)
			(xy 82.244443 -179.285226) (xy 82.214978 -179.239371) (xy 82.192338 -179.189788) (xy 82.176985 -179.137489)
			(xy 82.169231 -179.083537) (xy 82.168746 -179.056284) (xy 82.169409 -179.024721) (xy 82.179794 -178.962456)
			(xy 82.200279 -178.902747) (xy 82.21472 -178.874674) (xy 82.219546 -178.865784) (xy 82.221578 -178.846226)
			(xy 82.195924 -178.758088) (xy 82.183478 -178.742594) (xy 82.174588 -178.737514) (xy 82.149462 -178.723006)
			(xy 82.10358 -178.687496) (xy 82.063607 -178.645445) (xy 82.030465 -178.597824) (xy 82.004918 -178.545733)
			(xy 81.987557 -178.490372) (xy 81.978782 -178.433021) (xy 81.978246 -178.404012) (xy 81.978732 -178.376761)
			(xy 81.986488 -178.322813) (xy 82.001843 -178.270518) (xy 82.024485 -178.220941) (xy 82.053951 -178.175091)
			(xy 82.089642 -178.1339) (xy 82.130833 -178.098209) (xy 82.176683 -178.068743) (xy 82.22626 -178.046101)
			(xy 82.278555 -178.030746) (xy 82.332503 -178.02299) (xy 82.387005 -178.02299) (xy 82.440953 -178.030746)
			(xy 82.493248 -178.046101) (xy 82.542825 -178.068743) (xy 82.588675 -178.098209) (xy 82.629866 -178.1339)
			(xy 82.665557 -178.175091) (xy 82.695023 -178.220941) (xy 82.717665 -178.270518) (xy 82.73302 -178.322813)
			(xy 82.740776 -178.376761) (xy 82.741262 -178.404012) (xy 82.740596 -178.435575) (xy 82.730212 -178.49784)
			(xy 82.709729 -178.557549) (xy 82.695288 -178.585622) (xy 82.690462 -178.594512) (xy 82.68843 -178.61407)
			(xy 82.714084 -178.702208) (xy 82.72653 -178.717702) (xy 82.73542 -178.722782) (xy 82.742786 -178.726846)
			(xy 82.752438 -178.732688) (xy 82.774536 -178.73472) (xy 82.869024 -178.701192) (xy 82.885026 -178.685698)
			(xy 82.88909 -178.675284) (xy 82.899101 -178.650168) (xy 82.925175 -178.602803) (xy 82.957667 -178.559589)
			(xy 82.976466 -178.540156) (xy 82.983176 -178.532741) (xy 82.990906 -178.514325) (xy 82.991452 -178.504342)
			(xy 82.991452 -177.122074) (xy 82.991053 -177.112002) (xy 82.983315 -177.093403) (xy 82.976466 -177.086006)
			(xy 77.76591 -171.87545) (xy 77.758495 -171.868629) (xy 77.739907 -171.860896) (xy 77.729842 -171.860464)
			(xy 75.42657 -171.860464) (xy 75.416497 -171.860857) (xy 75.397898 -171.868598) (xy 75.390502 -171.87545)
			(xy 75.191366 -172.074586) (xy 75.184535 -172.081993) (xy 75.176811 -172.100587) (xy 75.17638 -172.110654)
			(xy 75.17638 -173.386242) (xy 75.176828 -173.396248) (xy 75.184555 -173.414712) (xy 75.191366 -173.422056)
			(xy 75.212253 -173.443671) (xy 75.247666 -173.492235) (xy 75.275022 -173.545753) (xy 75.293645 -173.602899)
			(xy 75.303071 -173.66226) (xy 75.303634 -173.692312) (xy 75.303133 -173.719562) (xy 75.295376 -173.773508)
			(xy 75.286028 -173.805342) (xy 75.544934 -173.805342) (xy 75.545437 -173.777868) (xy 75.553323 -173.723489)
			(xy 75.568939 -173.670806) (xy 75.59196 -173.620913) (xy 75.621909 -173.574844) (xy 75.639676 -173.553882)
			(xy 75.645772 -173.54677) (xy 75.652122 -173.529752) (xy 75.652122 -173.4439) (xy 75.645772 -173.426882)
			(xy 75.639676 -173.41977) (xy 75.621913 -173.398807) (xy 75.591989 -173.352725) (xy 75.568976 -173.302831)
			(xy 75.55335 -173.250154) (xy 75.545433 -173.195782) (xy 75.544934 -173.16831) (xy 75.54542 -173.141059)
			(xy 75.553176 -173.087111) (xy 75.568531 -173.034816) (xy 75.591173 -172.985239) (xy 75.620639 -172.939389)
			(xy 75.65633 -172.898198) (xy 75.697521 -172.862507) (xy 75.743371 -172.833041) (xy 75.792948 -172.810399)
			(xy 75.845243 -172.795044) (xy 75.899191 -172.787288) (xy 75.953693 -172.787288) (xy 76.007641 -172.795044)
			(xy 76.059936 -172.810399) (xy 76.109513 -172.833041) (xy 76.155363 -172.862507) (xy 76.196554 -172.898198)
			(xy 76.232245 -172.939389) (xy 76.261711 -172.985239) (xy 76.284353 -173.034816) (xy 76.299708 -173.087111)
			(xy 76.307464 -173.141059) (xy 76.30795 -173.16831) (xy 76.307482 -173.195785) (xy 76.299587 -173.250166)
			(xy 76.283964 -173.302849) (xy 76.260935 -173.352742) (xy 76.230978 -173.398809) (xy 76.213208 -173.41977)
			(xy 76.207112 -173.426882) (xy 76.200762 -173.4439) (xy 76.200762 -173.529752) (xy 76.207112 -173.54677)
			(xy 76.213208 -173.553882) (xy 76.230946 -173.574865) (xy 76.260874 -173.620941) (xy 76.283892 -173.67083)
			(xy 76.299524 -173.723502) (xy 76.307447 -173.777871) (xy 76.30795 -173.805342) (xy 76.307464 -173.832593)
			(xy 76.299708 -173.886541) (xy 76.284353 -173.938836) (xy 76.261711 -173.988413) (xy 76.232245 -174.034263)
			(xy 76.196554 -174.075454) (xy 76.155363 -174.111145) (xy 76.109513 -174.140611) (xy 76.059936 -174.163253)
			(xy 76.007641 -174.178608) (xy 75.953693 -174.186364) (xy 75.899191 -174.186364) (xy 75.845243 -174.178608)
			(xy 75.792948 -174.163253) (xy 75.743371 -174.140611) (xy 75.697521 -174.111145) (xy 75.65633 -174.075454)
			(xy 75.620639 -174.034263) (xy 75.591173 -173.988413) (xy 75.568531 -173.938836) (xy 75.553176 -173.886541)
			(xy 75.54542 -173.832593) (xy 75.544934 -173.805342) (xy 75.286028 -173.805342) (xy 75.280021 -173.825801)
			(xy 75.25738 -173.875377) (xy 75.227915 -173.921226) (xy 75.192225 -173.962415) (xy 75.151037 -173.998106)
			(xy 75.105189 -174.027573) (xy 75.055614 -174.050216) (xy 75.003322 -174.065573) (xy 74.949376 -174.073332)
			(xy 74.922126 -174.07382) (xy 74.89689 -174.073453) (xy 74.846855 -174.066825) (xy 74.798134 -174.053644)
			(xy 74.751584 -174.034139) (xy 74.729594 -174.02175) (xy 74.719942 -174.015908) (xy 74.697844 -174.013876)
			(xy 74.603356 -174.047404) (xy 74.587354 -174.062898) (xy 74.58329 -174.073312) (xy 74.572625 -174.100102)
			(xy 74.544334 -174.150345) (xy 74.5088 -174.195755) (xy 74.466833 -174.235297) (xy 74.419391 -174.268069)
			(xy 74.367556 -174.293325) (xy 74.312508 -174.310487) (xy 74.255504 -174.319165) (xy 74.226674 -174.319692)
			(xy 74.199421 -174.319246) (xy 74.145471 -174.311486) (xy 74.093175 -174.296127) (xy 74.043597 -174.273481)
			(xy 73.997745 -174.244011) (xy 73.956555 -174.208315) (xy 73.920864 -174.167121) (xy 73.891399 -174.121267)
			(xy 73.868759 -174.071686) (xy 73.853405 -174.019388) (xy 73.845651 -173.965437) (xy 73.845166 -173.938184)
			(xy 73.845839 -173.906622) (xy 73.856221 -173.844357) (xy 73.876701 -173.784648) (xy 73.89114 -173.756574)
			(xy 73.895966 -173.747684) (xy 73.897998 -173.728126) (xy 73.872344 -173.639988) (xy 73.859898 -173.624494)
			(xy 73.851008 -173.619414) (xy 73.825887 -173.604898) (xy 73.780004 -173.56939) (xy 73.74003 -173.527341)
			(xy 73.706886 -173.479721) (xy 73.681339 -173.427631) (xy 73.663977 -173.372272) (xy 73.655202 -173.314921)
			(xy 73.654666 -173.285912) (xy 73.655152 -173.258661) (xy 73.662908 -173.204713) (xy 73.678263 -173.152418)
			(xy 73.700905 -173.102841) (xy 73.730371 -173.056991) (xy 73.766062 -173.0158) (xy 73.807253 -172.980109)
			(xy 73.853103 -172.950643) (xy 73.90268 -172.928001) (xy 73.954975 -172.912646) (xy 74.008923 -172.90489)
			(xy 74.063425 -172.90489) (xy 74.117373 -172.912646) (xy 74.169668 -172.928001) (xy 74.219245 -172.950643)
			(xy 74.265095 -172.980109) (xy 74.306286 -173.0158) (xy 74.341977 -173.056991) (xy 74.371443 -173.102841)
			(xy 74.394085 -173.152418) (xy 74.40944 -173.204713) (xy 74.417196 -173.258661) (xy 74.417682 -173.285912)
			(xy 74.417014 -173.317474) (xy 74.40663 -173.379739) (xy 74.386148 -173.439449) (xy 74.371708 -173.467522)
			(xy 74.366882 -173.476412) (xy 74.36485 -173.49597) (xy 74.390504 -173.584108) (xy 74.40295 -173.599602)
			(xy 74.41184 -173.604682) (xy 74.419206 -173.608746) (xy 74.428858 -173.614588) (xy 74.450956 -173.61662)
			(xy 74.545444 -173.583092) (xy 74.561446 -173.567598) (xy 74.56551 -173.557184) (xy 74.575517 -173.532066)
			(xy 74.601593 -173.484702) (xy 74.634086 -173.441488) (xy 74.652886 -173.422056) (xy 74.659599 -173.414644)
			(xy 74.667326 -173.396225) (xy 74.667872 -173.386242) (xy 74.667872 -172.110654) (xy 74.667426 -172.100587)
			(xy 74.65972 -172.081989) (xy 74.652886 -172.074586) (xy 70.929246 -168.350946) (xy 70.912031 -168.33283)
			(xy 70.884288 -168.291273) (xy 70.865179 -168.245105) (xy 70.855436 -168.196097) (xy 70.854824 -168.171114)
			(xy 70.854824 -164.417502) (xy 70.854418 -164.40743) (xy 70.846686 -164.388831) (xy 70.839838 -164.381434)
			(xy 69.951854 -163.49345) (xy 69.944424 -163.486648) (xy 69.925848 -163.478905) (xy 69.915786 -163.478464)
			(xy 67.60337 -163.478464) (xy 67.593297 -163.478857) (xy 67.574698 -163.486598) (xy 67.567302 -163.49345)
			(xy 66.877946 -164.182806) (xy 66.871117 -164.190215) (xy 66.863389 -164.208807) (xy 66.86296 -164.218874)
			(xy 66.86296 -164.689028) (xy 66.863421 -164.699033) (xy 66.87114 -164.717496) (xy 66.877946 -164.724842)
			(xy 66.898823 -164.746466) (xy 66.934238 -164.795027) (xy 66.961597 -164.848543) (xy 66.980221 -164.905687)
			(xy 66.98965 -164.965046) (xy 66.990214 -164.995098) (xy 66.98972 -165.022349) (xy 66.981964 -165.076296)
			(xy 66.972618 -165.108128) (xy 67.231514 -165.108128) (xy 67.232013 -165.080654) (xy 67.239902 -165.026275)
			(xy 67.255519 -164.973592) (xy 67.27854 -164.923699) (xy 67.30849 -164.87763) (xy 67.326256 -164.856668)
			(xy 67.332352 -164.849556) (xy 67.338702 -164.832538) (xy 67.338702 -164.746686) (xy 67.332352 -164.729668)
			(xy 67.326256 -164.722556) (xy 67.308484 -164.701601) (xy 67.278561 -164.655517) (xy 67.255551 -164.60562)
			(xy 67.239927 -164.552942) (xy 67.232012 -164.498569) (xy 67.231514 -164.471096) (xy 67.232 -164.443845)
			(xy 67.239756 -164.389897) (xy 67.255111 -164.337602) (xy 67.277753 -164.288025) (xy 67.307219 -164.242175)
			(xy 67.34291 -164.200984) (xy 67.384101 -164.165293) (xy 67.429951 -164.135827) (xy 67.479528 -164.113185)
			(xy 67.531823 -164.09783) (xy 67.585771 -164.090074) (xy 67.640273 -164.090074) (xy 67.694221 -164.09783)
			(xy 67.746516 -164.113185) (xy 67.796093 -164.135827) (xy 67.841943 -164.165293) (xy 67.883134 -164.200984)
			(xy 67.918825 -164.242175) (xy 67.948291 -164.288025) (xy 67.970933 -164.337602) (xy 67.986288 -164.389897)
			(xy 67.994044 -164.443845) (xy 67.99453 -164.471096) (xy 67.994034 -164.49857) (xy 67.986143 -164.552949)
			(xy 67.970525 -164.605631) (xy 67.947503 -164.655524) (xy 67.917554 -164.701593) (xy 67.899788 -164.722556)
			(xy 67.893692 -164.729668) (xy 67.887342 -164.746686) (xy 67.887342 -164.832538) (xy 67.893692 -164.849556)
			(xy 67.899788 -164.856668) (xy 67.917516 -164.877659) (xy 67.947447 -164.923733) (xy 67.970467 -164.97362)
			(xy 67.986101 -165.02629) (xy 67.994026 -165.080658) (xy 67.99453 -165.108128) (xy 67.994044 -165.135379)
			(xy 67.986288 -165.189327) (xy 67.970933 -165.241622) (xy 67.948291 -165.291199) (xy 67.918825 -165.337049)
			(xy 67.883134 -165.37824) (xy 67.841943 -165.413931) (xy 67.796093 -165.443397) (xy 67.746516 -165.466039)
			(xy 67.694221 -165.481394) (xy 67.640273 -165.48915) (xy 67.585771 -165.48915) (xy 67.531823 -165.481394)
			(xy 67.479528 -165.466039) (xy 67.429951 -165.443397) (xy 67.384101 -165.413931) (xy 67.34291 -165.37824)
			(xy 67.307219 -165.337049) (xy 67.277753 -165.291199) (xy 67.255111 -165.241622) (xy 67.239756 -165.189327)
			(xy 67.232 -165.135379) (xy 67.231514 -165.108128) (xy 66.972618 -165.108128) (xy 66.96661 -165.12859)
			(xy 66.943969 -165.178167) (xy 66.914504 -165.224017) (xy 66.878813 -165.265207) (xy 66.837624 -165.300899)
			(xy 66.791774 -165.330365) (xy 66.742198 -165.353007) (xy 66.689904 -165.368363) (xy 66.635957 -165.37612)
			(xy 66.608706 -165.376606) (xy 66.583471 -165.376206) (xy 66.533437 -165.369588) (xy 66.484717 -165.356416)
			(xy 66.438165 -165.33692) (xy 66.416174 -165.324536) (xy 66.406522 -165.318694) (xy 66.384424 -165.316662)
			(xy 66.289936 -165.35019) (xy 66.273934 -165.365684) (xy 66.26987 -165.376098) (xy 66.259131 -165.402856)
			(xy 66.230849 -165.453096) (xy 66.195325 -165.498506) (xy 66.15337 -165.538049) (xy 66.105939 -165.570825)
			(xy 66.054114 -165.596086) (xy 65.999076 -165.613257) (xy 65.942081 -165.621945) (xy 65.913254 -165.622478)
			(xy 65.886 -165.622065) (xy 65.832048 -165.614301) (xy 65.77975 -165.598939) (xy 65.730171 -165.57629)
			(xy 65.684319 -165.546816) (xy 65.643129 -165.511117) (xy 65.607438 -165.46992) (xy 65.577973 -165.424062)
			(xy 65.555335 -165.374478) (xy 65.539982 -165.322177) (xy 65.53223 -165.268224) (xy 65.531746 -165.24097)
			(xy 65.532404 -165.209407) (xy 65.542791 -165.147142) (xy 65.563278 -165.087432) (xy 65.57772 -165.05936)
			(xy 65.582546 -165.05047) (xy 65.584578 -165.030912) (xy 65.558924 -164.942774) (xy 65.546478 -164.92728)
			(xy 65.537588 -164.9222) (xy 65.5125 -164.907631) (xy 65.466618 -164.87213) (xy 65.426643 -164.830089)
			(xy 65.393497 -164.782479) (xy 65.367944 -164.730398) (xy 65.350574 -164.675047) (xy 65.341788 -164.617704)
			(xy 65.341246 -164.588698) (xy 59.225688 -164.588698) (xy 59.225688 -166.86276) (xy 61.555122 -166.86276)
			(xy 61.555621 -166.835187) (xy 61.563566 -166.780615) (xy 61.579284 -166.727755) (xy 61.602447 -166.677709)
			(xy 61.632574 -166.631519) (xy 61.669037 -166.590146) (xy 61.689742 -166.57193) (xy 61.697849 -166.564318)
			(xy 61.707208 -166.544173) (xy 61.707776 -166.533068) (xy 61.707776 -166.455852) (xy 61.707202 -166.444743)
			(xy 61.697869 -166.424583) (xy 61.689742 -166.41699) (xy 61.668995 -166.398819) (xy 61.632527 -166.357443)
			(xy 61.602398 -166.311248) (xy 61.579235 -166.261195) (xy 61.56352 -166.208329) (xy 61.555582 -166.15375)
			(xy 61.555586 -166.098598) (xy 61.563531 -166.044021) (xy 61.579253 -165.991156) (xy 61.602423 -165.941107)
			(xy 61.632559 -165.894915) (xy 61.669032 -165.853545) (xy 61.689742 -165.83533) (xy 61.697849 -165.827718)
			(xy 61.707208 -165.807573) (xy 61.707776 -165.796468) (xy 61.707776 -165.719252) (xy 61.707202 -165.708143)
			(xy 61.697869 -165.687983) (xy 61.689742 -165.68039) (xy 61.669031 -165.662178) (xy 61.632559 -165.620811)
			(xy 61.602426 -165.574621) (xy 61.57926 -165.524573) (xy 61.563544 -165.47171) (xy 61.555606 -165.417135)
			(xy 61.555122 -165.38956) (xy 61.555541 -165.362306) (xy 61.563303 -165.308355) (xy 61.578665 -165.256057)
			(xy 61.601313 -165.206478) (xy 61.630786 -165.160626) (xy 61.666485 -165.119435) (xy 61.707682 -165.083744)
			(xy 61.753539 -165.05428) (xy 61.803123 -165.031641) (xy 61.855423 -165.016289) (xy 61.909376 -165.008536)
			(xy 61.93663 -165.008052) (xy 61.964488 -165.008509) (xy 62.019608 -165.016639) (xy 62.072962 -165.032691)
			(xy 62.123417 -165.056325) (xy 62.169903 -165.08704) (xy 62.211432 -165.124184) (xy 62.247123 -165.166968)
			(xy 62.276219 -165.214484) (xy 62.298101 -165.265723) (xy 62.305692 -165.292532) (xy 62.307978 -165.301422)
			(xy 62.318646 -165.316662) (xy 62.390528 -165.364414) (xy 62.408562 -165.368478) (xy 62.417706 -165.367208)
			(xy 62.430723 -165.36554) (xy 62.456907 -165.363759) (xy 62.47003 -165.363652) (xy 62.484179 -165.363743)
			(xy 62.512402 -165.365779) (xy 62.526418 -165.367716) (xy 62.536578 -165.36924) (xy 62.556136 -165.364414)
			(xy 62.630558 -165.308534) (xy 62.640718 -165.291008) (xy 62.641988 -165.280848) (xy 62.646066 -165.253693)
			(xy 62.66104 -165.200862) (xy 62.683433 -165.150723) (xy 62.712781 -165.104313) (xy 62.74848 -165.062588)
			(xy 62.789791 -165.026412) (xy 62.835861 -164.996531) (xy 62.885739 -164.973563) (xy 62.938393 -164.957982)
			(xy 62.992738 -164.95011) (xy 63.020194 -164.949632) (xy 63.047449 -164.950061) (xy 63.101403 -164.957818)
			(xy 63.153704 -164.973176) (xy 63.203286 -164.99582) (xy 63.249142 -165.025291) (xy 63.290335 -165.060989)
			(xy 63.326029 -165.102186) (xy 63.355496 -165.148043) (xy 63.378136 -165.197628) (xy 63.393489 -165.249931)
			(xy 63.401241 -165.303885) (xy 63.401702 -165.33114) (xy 63.401194 -165.358713) (xy 63.39325 -165.413284)
			(xy 63.377533 -165.466143) (xy 63.354371 -165.516189) (xy 63.324246 -165.56238) (xy 63.287786 -165.603753)
			(xy 63.267082 -165.62197) (xy 63.258979 -165.629586) (xy 63.249617 -165.649727) (xy 63.249048 -165.660832)
			(xy 63.249048 -165.738048) (xy 63.249614 -165.749159) (xy 63.258952 -165.769318) (xy 63.267082 -165.77691)
			(xy 63.287798 -165.795116) (xy 63.324268 -165.836486) (xy 63.3544 -165.882676) (xy 63.377566 -165.932725)
			(xy 63.393281 -165.985589) (xy 63.401218 -166.040165) (xy 63.401702 -166.06774) (xy 63.401259 -166.094993)
			(xy 63.393497 -166.148942) (xy 63.378137 -166.201238) (xy 63.355491 -166.250816) (xy 63.32602 -166.296666)
			(xy 63.290324 -166.337856) (xy 63.249129 -166.373547) (xy 63.203275 -166.403013) (xy 63.153695 -166.425653)
			(xy 63.101397 -166.441007) (xy 63.047447 -166.448763) (xy 63.020194 -166.449248) (xy 62.985904 -166.447724)
			(xy 62.975744 -166.446708) (xy 62.95644 -166.452804) (xy 62.885828 -166.511986) (xy 62.87643 -166.53002)
			(xy 62.875414 -166.54018) (xy 62.87249 -166.568356) (xy 62.859312 -166.623449) (xy 62.838129 -166.675986)
			(xy 62.809407 -166.724812) (xy 62.77378 -166.768853) (xy 62.73203 -166.807139) (xy 62.685075 -166.838828)
			(xy 62.63395 -166.863223) (xy 62.579779 -166.879787) (xy 62.523754 -166.888156) (xy 62.49543 -166.888668)
			(xy 62.477411 -166.888452) (xy 62.441536 -166.885014) (xy 62.423802 -166.88181) (xy 62.414404 -166.880032)
			(xy 62.395354 -166.883842) (xy 62.32017 -166.931594) (xy 62.30874 -166.947342) (xy 62.306454 -166.95674)
			(xy 62.29908 -166.983791) (xy 62.277449 -167.03552) (xy 62.248482 -167.083526) (xy 62.212804 -167.126779)
			(xy 62.171182 -167.164346) (xy 62.124511 -167.195419) (xy 62.073796 -167.21933) (xy 62.020129 -167.235564)
			(xy 61.964664 -167.243771) (xy 61.93663 -167.244268) (xy 61.909376 -167.243817) (xy 61.855423 -167.236063)
			(xy 61.803122 -167.220708) (xy 61.753539 -167.198067) (xy 61.707684 -167.168598) (xy 61.66649 -167.132903)
			(xy 61.630796 -167.091708) (xy 61.601329 -167.045852) (xy 61.578688 -166.996269) (xy 61.563335 -166.943968)
			(xy 61.555583 -166.890014) (xy 61.555122 -166.86276) (xy 59.225688 -166.86276) (xy 59.225688 -168.42232)
			(xy 63.19774 -168.42232) (xy 63.198205 -168.394745) (xy 63.206156 -168.340172) (xy 63.22188 -168.287311)
			(xy 63.24505 -168.237265) (xy 63.275183 -168.191076) (xy 63.311652 -168.149705) (xy 63.33236 -168.13149)
			(xy 63.340488 -168.123896) (xy 63.349834 -168.103738) (xy 63.350394 -168.092628) (xy 63.350394 -168.015412)
			(xy 63.349837 -168.004301) (xy 63.340491 -167.984142) (xy 63.33236 -167.97655) (xy 63.311662 -167.958325)
			(xy 63.275192 -167.916958) (xy 63.245059 -167.870771) (xy 63.221892 -167.820726) (xy 63.206172 -167.767866)
			(xy 63.198228 -167.713294) (xy 63.19774 -167.68572) (xy 63.198161 -167.659185) (xy 63.205502 -167.606625)
			(xy 63.22006 -167.555591) (xy 63.241552 -167.507068) (xy 63.269564 -167.461993) (xy 63.303555 -167.421238)
			(xy 63.342869 -167.385588) (xy 63.386745 -167.355734) (xy 63.410338 -167.343582) (xy 63.42126 -167.338248)
			(xy 63.43523 -167.31996) (xy 63.455804 -167.21709) (xy 63.449708 -167.194738) (xy 63.441834 -167.185594)
			(xy 63.424552 -167.165109) (xy 63.395397 -167.12014) (xy 63.372986 -167.071458) (xy 63.357783 -167.020066)
			(xy 63.350099 -166.967027) (xy 63.349632 -166.94023) (xy 63.350062 -166.913611) (xy 63.357636 -166.860913)
			(xy 63.372633 -166.809831) (xy 63.394748 -166.761403) (xy 63.423531 -166.716615) (xy 63.458395 -166.676381)
			(xy 63.498631 -166.641519) (xy 63.54342 -166.612738) (xy 63.591849 -166.590626) (xy 63.642933 -166.575631)
			(xy 63.695631 -166.568061) (xy 63.72225 -166.567612) (xy 63.748673 -166.568038) (xy 63.80099 -166.575495)
			(xy 63.851729 -166.590267) (xy 63.899873 -166.612058) (xy 63.944456 -166.640431) (xy 63.96482 -166.657274)
			(xy 63.971678 -166.66337) (xy 63.988696 -166.669466) (xy 64.073024 -166.669466) (xy 64.090042 -166.66337)
			(xy 64.0969 -166.657274) (xy 64.117266 -166.640435) (xy 64.161852 -166.61207) (xy 64.209996 -166.590283)
			(xy 64.260733 -166.575512) (xy 64.313048 -166.568052) (xy 64.365892 -166.568052) (xy 64.418207 -166.575512)
			(xy 64.468944 -166.590283) (xy 64.517088 -166.61207) (xy 64.561674 -166.640435) (xy 64.58204 -166.657274)
			(xy 64.588898 -166.66337) (xy 64.605916 -166.669466) (xy 64.690244 -166.669466) (xy 64.707262 -166.66337)
			(xy 64.71412 -166.657274) (xy 64.734487 -166.640438) (xy 64.779076 -166.61208) (xy 64.82722 -166.590299)
			(xy 64.877956 -166.575531) (xy 64.930269 -166.568072) (xy 64.95669 -166.567612) (xy 64.984579 -166.568046)
			(xy 65.039736 -166.576358) (xy 65.093037 -166.592798) (xy 65.143292 -166.616999) (xy 65.18938 -166.64842)
			(xy 65.230269 -166.686358) (xy 65.265047 -166.729968) (xy 65.292937 -166.778274) (xy 65.313316 -166.830197)
			(xy 65.325728 -166.884577) (xy 65.329897 -166.9402) (xy 65.325728 -166.995823) (xy 65.313316 -167.050203)
			(xy 65.292937 -167.102126) (xy 65.265047 -167.150432) (xy 65.230269 -167.194042) (xy 65.18938 -167.23198)
			(xy 65.143292 -167.263401) (xy 65.093037 -167.287602) (xy 65.039736 -167.304042) (xy 64.984579 -167.312354)
			(xy 64.95669 -167.312848) (xy 64.930269 -167.312385) (xy 64.877954 -167.304934) (xy 64.827216 -167.29017)
			(xy 64.779071 -167.268388) (xy 64.734486 -167.240024) (xy 64.71412 -167.223186) (xy 64.707262 -167.21709)
			(xy 64.690244 -167.210994) (xy 64.605916 -167.210994) (xy 64.588898 -167.21709) (xy 64.58204 -167.223186)
			(xy 64.561674 -167.240025) (xy 64.517088 -167.26839) (xy 64.468944 -167.290177) (xy 64.418207 -167.304948)
			(xy 64.365892 -167.312408) (xy 64.313048 -167.312408) (xy 64.260733 -167.304948) (xy 64.209996 -167.290177)
			(xy 64.161852 -167.26839) (xy 64.117266 -167.240025) (xy 64.0969 -167.223186) (xy 64.090042 -167.21709)
			(xy 64.073024 -167.210994) (xy 63.988696 -167.210994) (xy 63.971678 -167.21709) (xy 63.96482 -167.223186)
			(xy 63.947904 -167.23723) (xy 63.911358 -167.261676) (xy 63.891922 -167.271954) (xy 63.881254 -167.277542)
			(xy 63.867284 -167.296084) (xy 63.848234 -167.398954) (xy 63.854584 -167.421306) (xy 63.862712 -167.43045)
			(xy 63.881107 -167.451542) (xy 63.912082 -167.498155) (xy 63.935914 -167.548794) (xy 63.952091 -167.602371)
			(xy 63.960266 -167.657737) (xy 63.960756 -167.68572) (xy 63.960251 -167.713293) (xy 63.952308 -167.767865)
			(xy 63.936592 -167.820725) (xy 63.91343 -167.870771) (xy 63.883303 -167.916962) (xy 63.846841 -167.958334)
			(xy 63.826136 -167.97655) (xy 63.817989 -167.984126) (xy 63.808653 -168.004298) (xy 63.808102 -168.015412)
			(xy 63.808102 -168.092628) (xy 63.808638 -168.103742) (xy 63.817999 -168.1239) (xy 63.826136 -168.13149)
			(xy 63.846853 -168.149695) (xy 63.883321 -168.191066) (xy 63.913452 -168.237257) (xy 63.936616 -168.287306)
			(xy 63.952332 -168.34017) (xy 63.960271 -168.394745) (xy 63.960756 -168.42232) (xy 63.96027 -168.449571)
			(xy 63.952514 -168.503519) (xy 63.937159 -168.555814) (xy 63.914517 -168.605391) (xy 63.885051 -168.651241)
			(xy 63.84936 -168.692432) (xy 63.808169 -168.728123) (xy 63.762319 -168.757589) (xy 63.712742 -168.780231)
			(xy 63.660447 -168.795586) (xy 63.606499 -168.803342) (xy 63.551997 -168.803342) (xy 63.498049 -168.795586)
			(xy 63.445754 -168.780231) (xy 63.396177 -168.757589) (xy 63.350327 -168.728123) (xy 63.309136 -168.692432)
			(xy 63.273445 -168.651241) (xy 63.243979 -168.605391) (xy 63.221337 -168.555814) (xy 63.205982 -168.503519)
			(xy 63.198226 -168.449571) (xy 63.19774 -168.42232) (xy 59.225688 -168.42232) (xy 59.225688 -169.636694)
			(xy 59.226093 -169.646766) (xy 59.233825 -169.665365) (xy 59.240674 -169.672762) (xy 60.421266 -170.853354)
			(xy 60.438483 -170.871468) (xy 60.466225 -170.913026) (xy 60.485333 -170.959195) (xy 60.495076 -171.008203)
			(xy 60.495688 -171.033186) (xy 60.495688 -179.917852) (xy 60.495079 -179.942835) (xy 60.485333 -179.991843)
			(xy 60.466225 -180.038012) (xy 60.438487 -180.079573) (xy 60.421266 -180.097684) (xy 58.687208 -181.831742)
			(xy 58.669106 -181.848973) (xy 58.627544 -181.876713) (xy 58.581372 -181.895818) (xy 58.532361 -181.905555)
			(xy 58.507376 -181.906164) (xy 57.33542 -181.906164) (xy 57.308242 -181.926738) (xy 57.30367 -181.943502)
			(xy 57.295849 -181.969994) (xy 57.273702 -182.020595) (xy 57.244486 -182.067472) (xy 57.208812 -182.109642)
			(xy 57.167428 -182.146224) (xy 57.121198 -182.176452) (xy 57.07109 -182.199694) (xy 57.018154 -182.215463)
			(xy 56.963496 -182.223429) (xy 56.935878 -182.223918) (xy 56.908627 -182.223443) (xy 56.854679 -182.215683)
			(xy 56.802385 -182.200326) (xy 56.752808 -182.177683) (xy 56.706958 -182.148215) (xy 56.665769 -182.112523)
			(xy 56.630077 -182.071332) (xy 56.600611 -182.025481) (xy 56.57797 -181.975904) (xy 56.562614 -181.923609)
			(xy 56.554856 -181.869661) (xy 56.55437 -181.84241) (xy 47.78756 -181.84241) (xy 47.78756 -185.35904)
			(xy 62.50559 -185.35904) (xy 62.506082 -185.331671) (xy 62.513894 -185.277493) (xy 62.529377 -185.22499)
			(xy 62.552213 -185.175243) (xy 62.581932 -185.129275) (xy 62.59957 -185.108342) (xy 62.605666 -185.10123)
			(xy 62.612016 -185.084212) (xy 62.612016 -184.998868) (xy 62.605666 -184.98185) (xy 62.59957 -184.974738)
			(xy 62.581967 -184.953774) (xy 62.552237 -184.907813) (xy 62.529387 -184.858072) (xy 62.513885 -184.805574)
			(xy 62.506052 -184.751399) (xy 62.506048 -184.696661) (xy 62.513873 -184.642485) (xy 62.529365 -184.589984)
			(xy 62.552208 -184.54024) (xy 62.58193 -184.494274) (xy 62.59957 -184.473342) (xy 62.605666 -184.46623)
			(xy 62.612016 -184.449212) (xy 62.612016 -184.363868) (xy 62.605666 -184.34685) (xy 62.59957 -184.339738)
			(xy 62.581967 -184.318774) (xy 62.552237 -184.272813) (xy 62.529387 -184.223072) (xy 62.513885 -184.170574)
			(xy 62.506052 -184.116399) (xy 62.506048 -184.061661) (xy 62.513873 -184.007485) (xy 62.529365 -183.954984)
			(xy 62.552208 -183.90524) (xy 62.58193 -183.859274) (xy 62.59957 -183.838342) (xy 62.605666 -183.83123)
			(xy 62.612016 -183.814212) (xy 62.612016 -183.728868) (xy 62.605666 -183.71185) (xy 62.59957 -183.704738)
			(xy 62.581967 -183.683774) (xy 62.552237 -183.637813) (xy 62.529387 -183.588072) (xy 62.513885 -183.535574)
			(xy 62.506052 -183.481399) (xy 62.506048 -183.426661) (xy 62.513873 -183.372485) (xy 62.529365 -183.319984)
			(xy 62.552208 -183.27024) (xy 62.58193 -183.224274) (xy 62.59957 -183.203342) (xy 62.605666 -183.19623)
			(xy 62.612016 -183.179212) (xy 62.612016 -183.093868) (xy 62.605666 -183.07685) (xy 62.59957 -183.069738)
			(xy 62.581967 -183.048774) (xy 62.552237 -183.002813) (xy 62.529387 -182.953072) (xy 62.513885 -182.900574)
			(xy 62.506052 -182.846399) (xy 62.506048 -182.791661) (xy 62.513873 -182.737485) (xy 62.529365 -182.684984)
			(xy 62.552208 -182.63524) (xy 62.58193 -182.589274) (xy 62.59957 -182.568342) (xy 62.605666 -182.56123)
			(xy 62.612016 -182.544212) (xy 62.612016 -182.458868) (xy 62.605666 -182.44185) (xy 62.59957 -182.434738)
			(xy 62.581967 -182.413774) (xy 62.552237 -182.367813) (xy 62.529387 -182.318072) (xy 62.513885 -182.265574)
			(xy 62.506052 -182.211399) (xy 62.506048 -182.156661) (xy 62.513873 -182.102485) (xy 62.529365 -182.049984)
			(xy 62.552208 -182.00024) (xy 62.58193 -181.954274) (xy 62.59957 -181.933342) (xy 62.605666 -181.92623)
			(xy 62.612016 -181.909212) (xy 62.612016 -181.823868) (xy 62.605666 -181.80685) (xy 62.59957 -181.799738)
			(xy 62.581931 -181.778806) (xy 62.55222 -181.732833) (xy 62.529384 -181.683085) (xy 62.513893 -181.630585)
			(xy 62.506065 -181.576409) (xy 62.50559 -181.54904) (xy 62.506085 -181.521365) (xy 62.514084 -181.466597)
			(xy 62.529919 -181.413562) (xy 62.553258 -181.363374) (xy 62.583609 -181.317089) (xy 62.601602 -181.296056)
			(xy 62.607698 -181.288944) (xy 62.614302 -181.271672) (xy 62.614302 -181.185566) (xy 62.607698 -181.168294)
			(xy 62.601602 -181.161182) (xy 62.583608 -181.14015) (xy 62.55326 -181.093863) (xy 62.529922 -181.043675)
			(xy 62.514086 -180.99064) (xy 62.506084 -180.935872) (xy 62.50559 -180.908198) (xy 62.506076 -180.880947)
			(xy 62.513833 -180.826999) (xy 62.529188 -180.774705) (xy 62.551829 -180.725127) (xy 62.581295 -180.679277)
			(xy 62.616987 -180.638087) (xy 62.658177 -180.602395) (xy 62.704027 -180.572929) (xy 62.753605 -180.550288)
			(xy 62.805899 -180.534933) (xy 62.859847 -180.527176) (xy 62.887098 -180.52669) (xy 62.914468 -180.52716)
			(xy 62.968647 -180.534977) (xy 63.02115 -180.550465) (xy 63.070897 -180.573306) (xy 63.116864 -180.603029)
			(xy 63.137796 -180.62067) (xy 63.144908 -180.626766) (xy 63.161926 -180.633116) (xy 63.24727 -180.633116)
			(xy 63.264288 -180.626766) (xy 63.2714 -180.62067) (xy 63.292333 -180.603029) (xy 63.338301 -180.573305)
			(xy 63.388047 -180.550459) (xy 63.440549 -180.534963) (xy 63.494727 -180.527134) (xy 63.549469 -180.527134)
			(xy 63.603647 -180.534963) (xy 63.656149 -180.550459) (xy 63.705895 -180.573305) (xy 63.751863 -180.603029)
			(xy 63.772796 -180.62067) (xy 63.779908 -180.626766) (xy 63.796926 -180.633116) (xy 63.88227 -180.633116)
			(xy 63.899288 -180.626766) (xy 63.9064 -180.62067) (xy 63.927317 -180.603013) (xy 63.973295 -180.573305)
			(xy 64.023046 -180.550473) (xy 64.07555 -180.534986) (xy 64.129728 -180.527162) (xy 64.157098 -180.52669)
			(xy 64.184349 -180.52718) (xy 64.238297 -180.534936) (xy 64.290591 -180.550291) (xy 64.340168 -180.572931)
			(xy 64.386019 -180.602397) (xy 64.427209 -180.638088) (xy 64.4629 -180.679278) (xy 64.492367 -180.725128)
			(xy 64.515008 -180.774705) (xy 64.530363 -180.826999) (xy 64.53812 -180.880947) (xy 64.538606 -180.908198)
			(xy 64.538119 -180.935497) (xy 64.530348 -180.989538) (xy 64.51495 -181.041918) (xy 64.49224 -181.091568)
			(xy 64.462682 -181.137472) (xy 64.445134 -181.158388) (xy 64.438784 -181.1655) (xy 64.432688 -181.182518)
			(xy 64.432688 -181.268116) (xy 64.439038 -181.28488) (xy 64.445134 -181.291992) (xy 64.462849 -181.312952)
			(xy 64.492727 -181.358985) (xy 64.515692 -181.408827) (xy 64.531272 -181.461448) (xy 64.539144 -181.515759)
			(xy 64.539622 -181.543198) (xy 64.539174 -181.570569) (xy 64.531355 -181.62475) (xy 64.515862 -181.677254)
			(xy 64.493016 -181.727) (xy 64.463286 -181.772966) (xy 64.445642 -181.793896) (xy 64.439546 -181.801008)
			(xy 64.433196 -181.818026) (xy 64.433196 -181.90337) (xy 64.439546 -181.920388) (xy 64.445642 -181.9275)
			(xy 64.463282 -181.948434) (xy 64.493009 -181.994401) (xy 64.515857 -182.044146) (xy 64.531354 -182.096649)
			(xy 64.539184 -182.150828) (xy 64.539184 -182.205569) (xy 64.531355 -182.259748) (xy 64.515858 -182.312251)
			(xy 64.493011 -182.361997) (xy 64.463284 -182.407964) (xy 64.445642 -182.428896) (xy 64.439546 -182.436008)
			(xy 64.433196 -182.453026) (xy 64.433196 -182.53837) (xy 64.439546 -182.555388) (xy 64.445642 -182.5625)
			(xy 64.463282 -182.583434) (xy 64.493009 -182.629401) (xy 64.515857 -182.679146) (xy 64.531354 -182.731649)
			(xy 64.539184 -182.785828) (xy 64.539184 -182.840569) (xy 64.531355 -182.894748) (xy 64.515858 -182.947251)
			(xy 64.493011 -182.996997) (xy 64.463284 -183.042964) (xy 64.445642 -183.063896) (xy 64.439546 -183.071008)
			(xy 64.433196 -183.088026) (xy 64.433196 -183.17337) (xy 64.439546 -183.190388) (xy 64.445642 -183.1975)
			(xy 64.463301 -183.218416) (xy 64.493009 -183.264394) (xy 64.51584 -183.314145) (xy 64.531327 -183.366649)
			(xy 64.539151 -183.420828) (xy 64.539622 -183.448198) (xy 64.539112 -183.47594) (xy 64.531031 -183.530832)
			(xy 64.515096 -183.583979) (xy 64.491642 -183.634263) (xy 64.461163 -183.680626) (xy 64.443102 -183.70169)
			(xy 64.437006 -183.708802) (xy 64.430402 -183.726074) (xy 64.430148 -183.81218) (xy 64.436752 -183.829452)
			(xy 64.443102 -183.836564) (xy 64.461013 -183.857575) (xy 64.491205 -183.903796) (xy 64.514418 -183.953888)
			(xy 64.530166 -184.006803) (xy 64.53812 -184.061436) (xy 64.538606 -184.08904) (xy 64.538103 -184.116409)
			(xy 64.530294 -184.170586) (xy 64.514813 -184.223089) (xy 64.49198 -184.272836) (xy 64.462263 -184.318805)
			(xy 64.444626 -184.339738) (xy 64.43853 -184.34685) (xy 64.43218 -184.363868) (xy 64.43218 -184.449212)
			(xy 64.43853 -184.46623) (xy 64.444626 -184.473342) (xy 64.462308 -184.494242) (xy 64.492035 -184.540214)
			(xy 64.51488 -184.589966) (xy 64.530376 -184.642473) (xy 64.538202 -184.696657) (xy 64.538197 -184.751403)
			(xy 64.530363 -184.805586) (xy 64.514859 -184.858091) (xy 64.492006 -184.907839) (xy 64.462271 -184.953806)
			(xy 64.444626 -184.974738) (xy 64.43853 -184.98185) (xy 64.43218 -184.998868) (xy 64.43218 -185.084212)
			(xy 64.43853 -185.10123) (xy 64.444626 -185.108342) (xy 64.462255 -185.129282) (xy 64.491968 -185.175253)
			(xy 64.514805 -185.224998) (xy 64.530299 -185.277497) (xy 64.53813 -185.331671) (xy 64.538606 -185.35904)
			(xy 64.538159 -185.386292) (xy 64.530397 -185.440242) (xy 64.515037 -185.492537) (xy 64.492391 -185.542115)
			(xy 64.46292 -185.587965) (xy 64.427225 -185.629155) (xy 64.386031 -185.664846) (xy 64.340178 -185.694311)
			(xy 64.290598 -185.716952) (xy 64.2383 -185.732306) (xy 64.18435 -185.740062) (xy 64.157098 -185.740548)
			(xy 64.129727 -185.740096) (xy 64.075547 -185.732277) (xy 64.023043 -185.716785) (xy 63.973296 -185.69394)
			(xy 63.927331 -185.664211) (xy 63.9064 -185.646568) (xy 63.899288 -185.640472) (xy 63.88227 -185.634122)
			(xy 63.796926 -185.634122) (xy 63.779908 -185.640472) (xy 63.772796 -185.646568) (xy 63.751863 -185.664209)
			(xy 63.705895 -185.693933) (xy 63.656149 -185.716779) (xy 63.603647 -185.732275) (xy 63.549469 -185.740104)
			(xy 63.494727 -185.740104) (xy 63.440549 -185.732275) (xy 63.388047 -185.716779) (xy 63.338301 -185.693933)
			(xy 63.292333 -185.664209) (xy 63.2714 -185.646568) (xy 63.264288 -185.640472) (xy 63.24727 -185.634122)
			(xy 63.161926 -185.634122) (xy 63.144908 -185.640472) (xy 63.137796 -185.646568) (xy 63.116872 -185.664217)
			(xy 63.070898 -185.693929) (xy 63.021148 -185.716763) (xy 62.968645 -185.732252) (xy 62.914468 -185.740076)
			(xy 62.887098 -185.740548) (xy 62.859849 -185.740024) (xy 62.805904 -185.732268) (xy 62.753613 -185.716915)
			(xy 62.704038 -185.694277) (xy 62.65819 -185.664814) (xy 62.617 -185.629126) (xy 62.581309 -185.587941)
			(xy 62.551842 -185.542095) (xy 62.529198 -185.492523) (xy 62.51384 -185.440233) (xy 62.506079 -185.386289)
			(xy 62.50559 -185.35904) (xy 47.78756 -185.35904) (xy 47.78756 -185.452766) (xy 47.811436 -185.48096)
			(xy 47.829724 -185.484008) (xy 47.857449 -185.489216) (xy 47.911076 -185.506714) (xy 47.961544 -185.531914)
			(xy 48.007755 -185.564266) (xy 48.048701 -185.603067) (xy 48.083492 -185.64747) (xy 48.11137 -185.69651)
			(xy 48.131728 -185.749118) (xy 48.144122 -185.80415) (xy 48.148283 -185.860406) (xy 48.14412 -185.916662)
			(xy 48.131724 -185.971693) (xy 48.111365 -186.024301) (xy 48.08857 -186.064398) (xy 52.006498 -186.064398)
			(xy 52.010569 -186.008776) (xy 52.022695 -185.954339) (xy 52.042618 -185.902248) (xy 52.069914 -185.853613)
			(xy 52.104 -185.80947) (xy 52.144149 -185.770761) (xy 52.189507 -185.73831) (xy 52.239107 -185.712809)
			(xy 52.291891 -185.694802) (xy 52.346734 -185.684672) (xy 52.402468 -185.682635) (xy 52.457905 -185.688735)
			(xy 52.511862 -185.702841) (xy 52.563191 -185.724653) (xy 52.610797 -185.753707) (xy 52.653665 -185.789382)
			(xy 52.690882 -185.830919) (xy 52.721655 -185.877432) (xy 52.745327 -185.927929) (xy 52.761395 -185.981336)
			(xy 52.769515 -186.036512) (xy 52.770024 -186.064398) (xy 52.769515 -186.092284) (xy 52.761395 -186.14746)
			(xy 52.745327 -186.200867) (xy 52.721655 -186.251364) (xy 52.690882 -186.297877) (xy 52.653665 -186.339414)
			(xy 52.610797 -186.375089) (xy 52.563191 -186.404143) (xy 52.511862 -186.425955) (xy 52.457905 -186.440061)
			(xy 52.402468 -186.446161) (xy 52.346734 -186.444124) (xy 52.291891 -186.433994) (xy 52.239107 -186.415987)
			(xy 52.189507 -186.390486) (xy 52.144149 -186.358035) (xy 52.104 -186.319326) (xy 52.069914 -186.275183)
			(xy 52.042618 -186.226548) (xy 52.022695 -186.174457) (xy 52.010569 -186.12002) (xy 52.006498 -186.064398)
			(xy 48.08857 -186.064398) (xy 48.083486 -186.07334) (xy 48.048693 -186.117742) (xy 48.007745 -186.156541)
			(xy 47.961534 -186.188892) (xy 47.911065 -186.21409) (xy 47.857437 -186.231587) (xy 47.829724 -186.236864)
			(xy 47.811436 -186.239912) (xy 47.78756 -186.268106) (xy 47.78756 -187.011818) (xy 47.787988 -187.021885)
			(xy 47.795714 -187.040479) (xy 47.802546 -187.047886) (xy 48.023018 -187.268358) (xy 52.178964 -187.268358)
			(xy 52.183035 -187.212736) (xy 52.195161 -187.158299) (xy 52.215084 -187.106208) (xy 52.24238 -187.057573)
			(xy 52.276466 -187.01343) (xy 52.316615 -186.974721) (xy 52.361973 -186.94227) (xy 52.411573 -186.916769)
			(xy 52.464357 -186.898762) (xy 52.5192 -186.888632) (xy 52.574934 -186.886595) (xy 52.630371 -186.892695)
			(xy 52.684328 -186.906801) (xy 52.735657 -186.928613) (xy 52.783263 -186.957667) (xy 52.826131 -186.993342)
			(xy 52.863348 -187.034879) (xy 52.894121 -187.081392) (xy 52.917793 -187.131889) (xy 52.933861 -187.185296)
			(xy 52.941981 -187.240472) (xy 52.942411 -187.26404) (xy 66.49339 -187.26404) (xy 66.493882 -187.236671)
			(xy 66.501694 -187.182493) (xy 66.517177 -187.12999) (xy 66.540013 -187.080243) (xy 66.569732 -187.034275)
			(xy 66.58737 -187.013342) (xy 66.593466 -187.00623) (xy 66.599816 -186.989212) (xy 66.599816 -186.903868)
			(xy 66.593466 -186.88685) (xy 66.58737 -186.879738) (xy 66.569767 -186.858774) (xy 66.540037 -186.812813)
			(xy 66.517187 -186.763072) (xy 66.501685 -186.710574) (xy 66.493852 -186.656399) (xy 66.493848 -186.601661)
			(xy 66.501673 -186.547485) (xy 66.517165 -186.494984) (xy 66.540008 -186.44524) (xy 66.56973 -186.399274)
			(xy 66.58737 -186.378342) (xy 66.593466 -186.37123) (xy 66.599816 -186.354212) (xy 66.599816 -186.268868)
			(xy 66.593466 -186.25185) (xy 66.58737 -186.244738) (xy 66.569767 -186.223774) (xy 66.540037 -186.177813)
			(xy 66.517187 -186.128072) (xy 66.501685 -186.075574) (xy 66.493852 -186.021399) (xy 66.493848 -185.966661)
			(xy 66.501673 -185.912485) (xy 66.517165 -185.859984) (xy 66.540008 -185.81024) (xy 66.56973 -185.764274)
			(xy 66.58737 -185.743342) (xy 66.593466 -185.73623) (xy 66.599816 -185.719212) (xy 66.599816 -185.633868)
			(xy 66.593466 -185.61685) (xy 66.58737 -185.609738) (xy 66.569767 -185.588774) (xy 66.540037 -185.542813)
			(xy 66.517187 -185.493072) (xy 66.501685 -185.440574) (xy 66.493852 -185.386399) (xy 66.493848 -185.331661)
			(xy 66.501673 -185.277485) (xy 66.517165 -185.224984) (xy 66.540008 -185.17524) (xy 66.56973 -185.129274)
			(xy 66.58737 -185.108342) (xy 66.593466 -185.10123) (xy 66.599816 -185.084212) (xy 66.599816 -184.998868)
			(xy 66.593466 -184.98185) (xy 66.58737 -184.974738) (xy 66.569767 -184.953774) (xy 66.540037 -184.907813)
			(xy 66.517187 -184.858072) (xy 66.501685 -184.805574) (xy 66.493852 -184.751399) (xy 66.493848 -184.696661)
			(xy 66.501673 -184.642485) (xy 66.517165 -184.589984) (xy 66.540008 -184.54024) (xy 66.56973 -184.494274)
			(xy 66.58737 -184.473342) (xy 66.593466 -184.46623) (xy 66.599816 -184.449212) (xy 66.599816 -184.363868)
			(xy 66.593466 -184.34685) (xy 66.58737 -184.339738) (xy 66.569731 -184.318806) (xy 66.54002 -184.272833)
			(xy 66.517184 -184.223085) (xy 66.501693 -184.170585) (xy 66.493865 -184.116409) (xy 66.49339 -184.08904)
			(xy 66.493912 -184.059765) (xy 66.502886 -184.001906) (xy 66.520598 -183.946099) (xy 66.546633 -183.893655)
			(xy 66.580377 -183.845807) (xy 66.600324 -183.824372) (xy 66.606674 -183.817514) (xy 66.61404 -183.800496)
			(xy 66.617596 -183.71439) (xy 66.611754 -183.696864) (xy 66.605912 -183.689498) (xy 66.589705 -183.668984)
			(xy 66.562446 -183.624372) (xy 66.541541 -183.576454) (xy 66.527383 -183.526127) (xy 66.520237 -183.474338)
			(xy 66.519806 -183.448198) (xy 66.520269 -183.420828) (xy 66.528088 -183.366648) (xy 66.543577 -183.314145)
			(xy 66.56642 -183.264398) (xy 66.596145 -183.218432) (xy 66.613786 -183.1975) (xy 66.619882 -183.190388)
			(xy 66.626232 -183.17337) (xy 66.626232 -183.088026) (xy 66.619882 -183.071008) (xy 66.613786 -183.063896)
			(xy 66.596145 -183.042964) (xy 66.566423 -182.996995) (xy 66.543581 -182.947248) (xy 66.528086 -182.894747)
			(xy 66.520259 -182.840569) (xy 66.520259 -182.785828) (xy 66.528087 -182.73165) (xy 66.543582 -182.679149)
			(xy 66.566425 -182.629402) (xy 66.596147 -182.583434) (xy 66.613786 -182.5625) (xy 66.619882 -182.555388)
			(xy 66.626232 -182.53837) (xy 66.626232 -182.453026) (xy 66.619882 -182.436008) (xy 66.613786 -182.428896)
			(xy 66.596145 -182.407964) (xy 66.566423 -182.361995) (xy 66.543581 -182.312248) (xy 66.528086 -182.259747)
			(xy 66.520259 -182.205569) (xy 66.520259 -182.150828) (xy 66.528087 -182.09665) (xy 66.543582 -182.044149)
			(xy 66.566425 -181.994402) (xy 66.596147 -181.948434) (xy 66.613786 -181.9275) (xy 66.619882 -181.920388)
			(xy 66.626232 -181.90337) (xy 66.626232 -181.818026) (xy 66.619882 -181.801008) (xy 66.613786 -181.793896)
			(xy 66.596129 -181.772978) (xy 66.566421 -181.727001) (xy 66.543588 -181.67725) (xy 66.528101 -181.624746)
			(xy 66.520278 -181.570568) (xy 66.519806 -181.543198) (xy 66.520287 -181.515899) (xy 66.528059 -181.461858)
			(xy 66.543458 -181.409477) (xy 66.56617 -181.359827) (xy 66.595729 -181.313924) (xy 66.613278 -181.293008)
			(xy 66.619628 -181.285896) (xy 66.625724 -181.268878) (xy 66.625724 -181.18328) (xy 66.619374 -181.166516)
			(xy 66.613278 -181.159404) (xy 66.595563 -181.138444) (xy 66.565685 -181.092411) (xy 66.542719 -181.042569)
			(xy 66.527139 -180.989949) (xy 66.519268 -180.935637) (xy 66.51879 -180.908198) (xy 66.519276 -180.880947)
			(xy 66.527033 -180.826999) (xy 66.542388 -180.774705) (xy 66.565029 -180.725127) (xy 66.594495 -180.679277)
			(xy 66.630187 -180.638087) (xy 66.671377 -180.602395) (xy 66.717227 -180.572929) (xy 66.766805 -180.550288)
			(xy 66.819099 -180.534933) (xy 66.873047 -180.527176) (xy 66.900298 -180.52669) (xy 66.927668 -180.52716)
			(xy 66.981847 -180.534977) (xy 67.03435 -180.550465) (xy 67.084097 -180.573306) (xy 67.130064 -180.603029)
			(xy 67.150996 -180.62067) (xy 67.158108 -180.626766) (xy 67.175126 -180.633116) (xy 67.26047 -180.633116)
			(xy 67.277488 -180.626766) (xy 67.2846 -180.62067) (xy 67.308081 -180.601035) (xy 67.360066 -180.568726)
			(xy 67.416532 -180.545107) (xy 67.446144 -180.537358) (xy 67.453002 -180.53558) (xy 67.46494 -180.528976)
			(xy 67.871594 -180.122322) (xy 67.878323 -180.114923) (xy 67.886041 -180.096494) (xy 67.88658 -180.086508)
			(xy 67.88658 -167.31615) (xy 67.887065 -167.291175) (xy 67.894853 -167.241838) (xy 67.910262 -167.194325)
			(xy 67.932911 -167.149806) (xy 67.962243 -167.109378) (xy 67.979544 -167.09136) (xy 68.474844 -166.59606)
			(xy 68.481747 -166.588412) (xy 68.489428 -166.569321) (xy 68.489035 -166.548746) (xy 68.485258 -166.539164)
			(xy 68.439538 -166.437818) (xy 68.412614 -166.421816) (xy 68.396612 -166.422832) (xy 68.372228 -166.423594)
			(xy 68.344973 -166.423175) (xy 68.291017 -166.415421) (xy 68.238714 -166.400068) (xy 68.189128 -166.377427)
			(xy 68.143269 -166.34796) (xy 68.102071 -166.312266) (xy 68.066371 -166.271072) (xy 68.036898 -166.225217)
			(xy 68.01425 -166.175634) (xy 67.99889 -166.123333) (xy 67.991129 -166.069378) (xy 67.991125 -166.014868)
			(xy 67.99888 -165.960912) (xy 68.014234 -165.908609) (xy 68.036875 -165.859024) (xy 68.066343 -165.813165)
			(xy 68.102037 -165.771967) (xy 68.143232 -165.736268) (xy 68.189087 -165.706795) (xy 68.23867 -165.684149)
			(xy 68.290971 -165.668789) (xy 68.344926 -165.661028) (xy 68.399436 -165.661026) (xy 68.453392 -165.668781)
			(xy 68.505695 -165.684135) (xy 68.55528 -165.706778) (xy 68.601139 -165.736246) (xy 68.642336 -165.771941)
			(xy 68.678034 -165.813135) (xy 68.707507 -165.858991) (xy 68.730153 -165.908574) (xy 68.745512 -165.960876)
			(xy 68.753272 -166.014831) (xy 68.753736 -166.042086) (xy 68.753167 -166.073219) (xy 68.743081 -166.134662)
			(xy 68.723128 -166.193644) (xy 68.709032 -166.22141) (xy 68.701158 -166.236142) (xy 68.705984 -166.269416)
			(xy 68.717922 -166.2811) (xy 68.725356 -166.287816) (xy 68.743856 -166.295452) (xy 68.76387 -166.295452)
			(xy 68.78237 -166.287816) (xy 68.789804 -166.2811) (xy 68.909946 -166.160958) (xy 68.91671 -166.153587)
			(xy 68.924406 -166.135137) (xy 68.924932 -166.125144) (xy 68.924932 -165.590728) (xy 68.924496 -165.58072)
			(xy 68.91676 -165.562257) (xy 68.909946 -165.554914) (xy 68.88099 -165.525958) (xy 68.869052 -165.519354)
			(xy 68.862194 -165.517576) (xy 68.834787 -165.510492) (xy 68.782305 -165.48928) (xy 68.733534 -165.460544)
			(xy 68.689545 -165.424917) (xy 68.651304 -165.38318) (xy 68.619651 -165.336249) (xy 68.595281 -165.285157)
			(xy 68.578728 -165.231024) (xy 68.570358 -165.175039) (xy 68.56984 -165.146736) (xy 68.570289 -165.119482)
			(xy 68.578042 -165.065528) (xy 68.593396 -165.013227) (xy 68.616038 -164.963644) (xy 68.645507 -164.917788)
			(xy 68.681202 -164.876594) (xy 68.722398 -164.840899) (xy 68.768254 -164.811432) (xy 68.817838 -164.788792)
			(xy 68.87014 -164.77344) (xy 68.924094 -164.765688) (xy 68.951348 -164.765228) (xy 68.979654 -164.765725)
			(xy 69.035648 -164.774076) (xy 69.08979 -164.790616) (xy 69.14089 -164.814983) (xy 69.187825 -164.846639)
			(xy 69.229561 -164.884889) (xy 69.265181 -164.928891) (xy 69.293901 -164.977678) (xy 69.31509 -165.030175)
			(xy 69.322188 -165.057582) (xy 69.323966 -165.06444) (xy 69.33057 -165.076378) (xy 69.467476 -165.213284)
			(xy 69.484795 -165.231289) (xy 69.514146 -165.271711) (xy 69.536807 -165.316231) (xy 69.552216 -165.36375)
			(xy 69.559996 -165.413096) (xy 69.56044 -165.438074) (xy 69.56044 -166.277798) (xy 69.559979 -166.302773)
			(xy 69.552184 -166.352112) (xy 69.53677 -166.399625) (xy 69.514116 -166.444143) (xy 69.484779 -166.484571)
			(xy 69.467476 -166.502588) (xy 69.251068 -166.718742) (xy 69.244271 -166.726237) (xy 69.23663 -166.744951)
			(xy 69.236814 -166.765163) (xy 69.2404 -166.774622) (xy 69.283072 -166.875714) (xy 69.30898 -166.892478)
			(xy 69.324728 -166.892224) (xy 69.33057 -166.892224) (xy 69.357824 -166.892683) (xy 69.411776 -166.900437)
			(xy 69.464076 -166.915791) (xy 69.513658 -166.938432) (xy 69.559513 -166.9679) (xy 69.600707 -167.003594)
			(xy 69.636401 -167.044788) (xy 69.665869 -167.090643) (xy 69.68851 -167.140226) (xy 69.703863 -167.192526)
			(xy 69.711617 -167.246478) (xy 69.712078 -167.273732) (xy 69.711587 -167.301643) (xy 69.70345 -167.356868)
			(xy 69.687353 -167.410318) (xy 69.66364 -167.460853) (xy 69.632818 -167.507393) (xy 69.614542 -167.528494)
			(xy 69.608192 -167.535606) (xy 69.601588 -167.552878) (xy 69.601588 -167.64) (xy 69.608192 -167.657272)
			(xy 69.614542 -167.664384) (xy 69.63284 -167.685466) (xy 69.663664 -167.73201) (xy 69.687374 -167.782549)
			(xy 69.703466 -167.836004) (xy 69.711595 -167.891234) (xy 69.712078 -167.919146) (xy 69.711592 -167.946397)
			(xy 69.703836 -168.000345) (xy 69.688481 -168.05264) (xy 69.665839 -168.102217) (xy 69.636373 -168.148067)
			(xy 69.600682 -168.189258) (xy 69.559491 -168.224949) (xy 69.513641 -168.254415) (xy 69.464064 -168.277057)
			(xy 69.411769 -168.292412) (xy 69.357821 -168.300168) (xy 69.303319 -168.300168) (xy 69.249371 -168.292412)
			(xy 69.197076 -168.277057) (xy 69.147499 -168.254415) (xy 69.101649 -168.224949) (xy 69.060458 -168.189258)
			(xy 69.024767 -168.148067) (xy 68.995301 -168.102217) (xy 68.972659 -168.05264) (xy 68.957304 -168.000345)
			(xy 68.949548 -167.946397) (xy 68.949062 -167.919146) (xy 68.949529 -167.891234) (xy 68.957671 -167.836008)
			(xy 68.973773 -167.782557) (xy 68.997491 -167.732023) (xy 69.028319 -167.685484) (xy 69.046598 -167.664384)
			(xy 69.052948 -167.657272) (xy 69.059552 -167.64) (xy 69.059552 -167.552878) (xy 69.052948 -167.535606)
			(xy 69.046598 -167.528494) (xy 69.028343 -167.507376) (xy 68.997512 -167.460842) (xy 68.973792 -167.410313)
			(xy 68.957691 -167.356865) (xy 68.94955 -167.301642) (xy 68.949062 -167.273732) (xy 68.949062 -167.26789)
			(xy 68.949316 -167.252142) (xy 68.932552 -167.226234) (xy 68.83146 -167.183562) (xy 68.821985 -167.180026)
			(xy 68.801783 -167.179833) (xy 68.783062 -167.187429) (xy 68.77558 -167.19423) (xy 68.537074 -167.43299)
			(xy 68.530336 -167.440382) (xy 68.522625 -167.458816) (xy 68.522088 -167.468804) (xy 68.522088 -175.559974)
			(xy 69.868542 -175.559974) (xy 69.869044 -175.532401) (xy 69.876987 -175.477829) (xy 69.892704 -175.424969)
			(xy 69.915867 -175.374922) (xy 69.945994 -175.328732) (xy 69.982457 -175.28736) (xy 70.003162 -175.269144)
			(xy 70.011266 -175.261529) (xy 70.020626 -175.241386) (xy 70.021196 -175.230282) (xy 70.021196 -175.153066)
			(xy 70.020664 -175.141952) (xy 70.0113 -175.121793) (xy 70.003162 -175.114204) (xy 69.982428 -175.096018)
			(xy 69.945959 -175.054645) (xy 69.915827 -175.008452) (xy 69.892662 -174.958401) (xy 69.876946 -174.905536)
			(xy 69.869006 -174.850959) (xy 69.869009 -174.795807) (xy 69.876953 -174.741231) (xy 69.892674 -174.688367)
			(xy 69.915844 -174.638318) (xy 69.945979 -174.592128) (xy 69.982452 -174.550758) (xy 70.003162 -174.532544)
			(xy 70.011266 -174.524929) (xy 70.020626 -174.504786) (xy 70.021196 -174.493682) (xy 70.021196 -174.416466)
			(xy 70.020664 -174.405352) (xy 70.0113 -174.385193) (xy 70.003162 -174.377604) (xy 69.982442 -174.359403)
			(xy 69.945974 -174.318031) (xy 69.915844 -174.271839) (xy 69.89268 -174.221789) (xy 69.876965 -174.168925)
			(xy 69.869027 -174.114349) (xy 69.868542 -174.086774) (xy 69.868931 -174.059518) (xy 69.876693 -174.005562)
			(xy 69.892055 -173.95326) (xy 69.914704 -173.903676) (xy 69.944179 -173.857821) (xy 69.979881 -173.816627)
			(xy 70.021081 -173.780934) (xy 70.066943 -173.751467) (xy 70.116531 -173.728828) (xy 70.168836 -173.713476)
			(xy 70.222794 -173.705725) (xy 70.25005 -173.705266) (xy 70.277905 -173.705769) (xy 70.333021 -173.713899)
			(xy 70.38637 -173.72995) (xy 70.436822 -173.75358) (xy 70.483305 -173.78429) (xy 70.524834 -173.821426)
			(xy 70.560527 -173.864202) (xy 70.589627 -173.91171) (xy 70.611517 -173.962941) (xy 70.619112 -173.989746)
			(xy 70.621398 -173.998636) (xy 70.632066 -174.013876) (xy 70.703948 -174.061628) (xy 70.721982 -174.065692)
			(xy 70.731126 -174.064422) (xy 70.744142 -174.062752) (xy 70.770327 -174.060973) (xy 70.78345 -174.060866)
			(xy 70.797599 -174.060965) (xy 70.825822 -174.062996) (xy 70.839838 -174.06493) (xy 70.849998 -174.066454)
			(xy 70.869556 -174.061628) (xy 70.943978 -174.005748) (xy 70.954138 -173.988222) (xy 70.955408 -173.978062)
			(xy 70.959477 -173.950905) (xy 70.974451 -173.898073) (xy 70.996843 -173.847933) (xy 71.026193 -173.801521)
			(xy 71.061892 -173.759796) (xy 71.103204 -173.72362) (xy 71.149276 -173.693739) (xy 71.199155 -173.670772)
			(xy 71.251811 -173.655192) (xy 71.306158 -173.647322) (xy 71.333614 -173.646846) (xy 71.360864 -173.647365)
			(xy 71.414808 -173.655122) (xy 71.467099 -173.670476) (xy 71.516673 -173.693116) (xy 71.562521 -173.722579)
			(xy 71.60371 -173.758267) (xy 71.639401 -173.799453) (xy 71.668869 -173.845299) (xy 71.691512 -173.894871)
			(xy 71.706871 -173.947161) (xy 71.714633 -174.001105) (xy 71.715122 -174.028354) (xy 71.714617 -174.055927)
			(xy 71.706671 -174.110498) (xy 71.690954 -174.163357) (xy 71.667791 -174.213403) (xy 71.637666 -174.259593)
			(xy 71.601206 -174.300967) (xy 71.580502 -174.319184) (xy 71.572395 -174.326797) (xy 71.563034 -174.346941)
			(xy 71.562468 -174.358046) (xy 71.562468 -174.435262) (xy 71.563019 -174.446374) (xy 71.572367 -174.466534)
			(xy 71.580502 -174.474124) (xy 71.601228 -174.492319) (xy 71.637697 -174.533691) (xy 71.667828 -174.579884)
			(xy 71.690991 -174.629936) (xy 71.706704 -174.682801) (xy 71.714639 -174.737378) (xy 71.715122 -174.764954)
			(xy 71.714602 -174.792205) (xy 71.706852 -174.846153) (xy 71.691502 -174.898449) (xy 71.668866 -174.948028)
			(xy 71.639404 -174.993881) (xy 71.603716 -175.035074) (xy 71.562529 -175.070768) (xy 71.516681 -175.100237)
			(xy 71.467105 -175.122881) (xy 71.414812 -175.138239) (xy 71.360865 -175.145998) (xy 71.333614 -175.146462)
			(xy 71.299324 -175.144938) (xy 71.289164 -175.143922) (xy 71.26986 -175.150018) (xy 71.199248 -175.2092)
			(xy 71.18985 -175.227234) (xy 71.188834 -175.237394) (xy 71.185902 -175.265569) (xy 71.172723 -175.32066)
			(xy 71.151539 -175.373196) (xy 71.122818 -175.422021) (xy 71.087191 -175.466061) (xy 71.045443 -175.504346)
			(xy 70.99849 -175.536036) (xy 70.947366 -175.560432) (xy 70.893197 -175.576997) (xy 70.837173 -175.585369)
			(xy 70.80885 -175.585882) (xy 70.790831 -175.585663) (xy 70.754956 -175.582227) (xy 70.737222 -175.579024)
			(xy 70.727824 -175.577246) (xy 70.708774 -175.581056) (xy 70.63359 -175.628808) (xy 70.62216 -175.644556)
			(xy 70.619874 -175.653954) (xy 70.612491 -175.681002) (xy 70.59086 -175.732729) (xy 70.561894 -175.780735)
			(xy 70.526216 -175.823987) (xy 70.484595 -175.861553) (xy 70.437926 -175.892627) (xy 70.387213 -175.916539)
			(xy 70.333547 -175.932774) (xy 70.278084 -175.940984) (xy 70.25005 -175.941482) (xy 70.222797 -175.940998)
			(xy 70.168846 -175.933247) (xy 70.116547 -175.917896) (xy 70.066965 -175.895258) (xy 70.02111 -175.865792)
			(xy 69.979916 -175.830101) (xy 69.944222 -175.788909) (xy 69.914754 -175.743056) (xy 69.892112 -175.693476)
			(xy 69.876758 -175.641178) (xy 69.869004 -175.587227) (xy 69.868542 -175.559974) (xy 68.522088 -175.559974)
			(xy 68.522088 -177.10912) (xy 71.51116 -177.10912) (xy 71.511618 -177.081545) (xy 71.51957 -177.026971)
			(xy 71.535295 -176.97411) (xy 71.558466 -176.924064) (xy 71.588601 -176.877874) (xy 71.625071 -176.836505)
			(xy 71.64578 -176.81829) (xy 71.653911 -176.8107) (xy 71.663255 -176.790538) (xy 71.663814 -176.779428)
			(xy 71.663814 -176.702212) (xy 71.663283 -176.691097) (xy 71.653921 -176.670937) (xy 71.64578 -176.66335)
			(xy 71.625086 -176.645121) (xy 71.588615 -176.603755) (xy 71.558481 -176.557569) (xy 71.535313 -176.507525)
			(xy 71.519592 -176.454666) (xy 71.511648 -176.400094) (xy 71.51116 -176.37252) (xy 71.51163 -176.346404)
			(xy 71.518765 -176.294662) (xy 71.53289 -176.244376) (xy 71.553741 -176.196487) (xy 71.58093 -176.151889)
			(xy 71.613946 -176.111416) (xy 71.652175 -176.075824) (xy 71.6949 -176.045779) (xy 71.717916 -176.03343)
			(xy 71.72833 -176.028096) (xy 71.7423 -176.009808) (xy 71.76262 -175.909224) (xy 71.757032 -175.886872)
			(xy 71.749666 -175.877982) (xy 71.733387 -175.857795) (xy 71.705983 -175.81377) (xy 71.684951 -175.766368)
			(xy 71.670699 -175.716507) (xy 71.663502 -175.665151) (xy 71.663052 -175.639222) (xy 71.663577 -175.612608)
			(xy 71.671149 -175.55992) (xy 71.686142 -175.508847) (xy 71.708251 -175.460427) (xy 71.737025 -175.415647)
			(xy 71.77188 -175.375417) (xy 71.812105 -175.340557) (xy 71.856881 -175.311776) (xy 71.905298 -175.28966)
			(xy 71.95637 -175.27466) (xy 72.009056 -175.267081) (xy 72.03567 -175.266604) (xy 72.062091 -175.267078)
			(xy 72.114406 -175.274524) (xy 72.165144 -175.289285) (xy 72.213289 -175.311065) (xy 72.257874 -175.339428)
			(xy 72.27824 -175.356266) (xy 72.285098 -175.362362) (xy 72.302116 -175.368458) (xy 72.386444 -175.368458)
			(xy 72.403462 -175.362362) (xy 72.41032 -175.356266) (xy 72.430686 -175.339427) (xy 72.475272 -175.311062)
			(xy 72.523416 -175.289275) (xy 72.574153 -175.274504) (xy 72.626468 -175.267044) (xy 72.679312 -175.267044)
			(xy 72.731627 -175.274504) (xy 72.782364 -175.289275) (xy 72.830508 -175.311062) (xy 72.875094 -175.339427)
			(xy 72.89546 -175.356266) (xy 72.902318 -175.362362) (xy 72.919336 -175.368458) (xy 73.003664 -175.368458)
			(xy 73.020682 -175.362362) (xy 73.02754 -175.356266) (xy 73.047899 -175.339419) (xy 73.09249 -175.311063)
			(xy 73.140636 -175.289285) (xy 73.191374 -175.274519) (xy 73.243688 -175.267063) (xy 73.27011 -175.266604)
			(xy 73.297996 -175.267082) (xy 73.353145 -175.275395) (xy 73.406439 -175.291836) (xy 73.456687 -175.316035)
			(xy 73.502767 -175.347453) (xy 73.543651 -175.385389) (xy 73.578423 -175.428993) (xy 73.606309 -175.477293)
			(xy 73.626684 -175.52921) (xy 73.639095 -175.583584) (xy 73.643263 -175.6392) (xy 73.639095 -175.694816)
			(xy 73.626684 -175.74919) (xy 73.606309 -175.801107) (xy 73.578423 -175.849407) (xy 73.543651 -175.893011)
			(xy 73.502767 -175.930947) (xy 73.456687 -175.962365) (xy 73.406439 -175.986564) (xy 73.353145 -176.003005)
			(xy 73.297996 -176.011318) (xy 73.27011 -176.01184) (xy 73.243689 -176.011367) (xy 73.191374 -176.003919)
			(xy 73.140636 -175.989157) (xy 73.092492 -175.967377) (xy 73.047906 -175.939016) (xy 73.02754 -175.922178)
			(xy 73.020682 -175.916082) (xy 73.003664 -175.909986) (xy 72.919336 -175.909986) (xy 72.902318 -175.916082)
			(xy 72.89546 -175.922178) (xy 72.875094 -175.939017) (xy 72.830508 -175.967382) (xy 72.782364 -175.989169)
			(xy 72.731627 -176.00394) (xy 72.679312 -176.0114) (xy 72.626468 -176.0114) (xy 72.574153 -176.00394)
			(xy 72.523416 -175.989169) (xy 72.475272 -175.967382) (xy 72.430686 -175.939017) (xy 72.41032 -175.922178)
			(xy 72.403462 -175.916082) (xy 72.386444 -175.909986) (xy 72.302116 -175.909986) (xy 72.285098 -175.916082)
			(xy 72.27824 -175.922178) (xy 72.262606 -175.935184) (xy 72.229003 -175.958095) (xy 72.211184 -175.967898)
			(xy 72.20077 -175.973486) (xy 72.187308 -175.992028) (xy 72.168512 -176.092866) (xy 72.174354 -176.114964)
			(xy 72.181974 -176.123854) (xy 72.199282 -176.14471) (xy 72.228443 -176.190393) (xy 72.250844 -176.239745)
			(xy 72.266032 -176.29177) (xy 72.273702 -176.345421) (xy 72.274176 -176.37252) (xy 72.273664 -176.400093)
			(xy 72.265722 -176.454664) (xy 72.250007 -176.507523) (xy 72.226845 -176.55757) (xy 72.196721 -176.603761)
			(xy 72.16026 -176.645133) (xy 72.139556 -176.66335) (xy 72.131413 -176.67093) (xy 72.122074 -176.691099)
			(xy 72.121522 -176.702212) (xy 72.121522 -176.779428) (xy 72.122051 -176.790543) (xy 72.131416 -176.810701)
			(xy 72.139556 -176.81829) (xy 72.160257 -176.836513) (xy 72.19673 -176.877878) (xy 72.226864 -176.924065)
			(xy 72.250032 -176.974111) (xy 72.26575 -177.026972) (xy 72.273691 -177.081546) (xy 72.274176 -177.10912)
			(xy 72.27369 -177.136371) (xy 72.265934 -177.190319) (xy 72.250579 -177.242614) (xy 72.227937 -177.292191)
			(xy 72.198471 -177.338041) (xy 72.16278 -177.379232) (xy 72.121589 -177.414923) (xy 72.075739 -177.444389)
			(xy 72.026162 -177.467031) (xy 71.973867 -177.482386) (xy 71.919919 -177.490142) (xy 71.865417 -177.490142)
			(xy 71.811469 -177.482386) (xy 71.759174 -177.467031) (xy 71.709597 -177.444389) (xy 71.663747 -177.414923)
			(xy 71.622556 -177.379232) (xy 71.586865 -177.338041) (xy 71.557399 -177.292191) (xy 71.534757 -177.242614)
			(xy 71.519402 -177.190319) (xy 71.511646 -177.136371) (xy 71.51116 -177.10912) (xy 68.522088 -177.10912)
			(xy 68.522088 -180.239162) (xy 68.521591 -180.264136) (xy 68.513802 -180.313472) (xy 68.498396 -180.360984)
			(xy 68.47575 -180.405503) (xy 68.446422 -180.445933) (xy 68.429124 -180.463952) (xy 67.91452 -180.978556)
			(xy 67.907916 -180.990494) (xy 67.906138 -180.997352) (xy 67.898461 -181.026864) (xy 67.874992 -181.083143)
			(xy 67.842865 -181.134969) (xy 67.823334 -181.158388) (xy 67.816984 -181.1655) (xy 67.810888 -181.182518)
			(xy 67.810888 -181.268116) (xy 67.817238 -181.28488) (xy 67.823334 -181.291992) (xy 67.841049 -181.312952)
			(xy 67.870927 -181.358985) (xy 67.893892 -181.408827) (xy 67.909472 -181.461448) (xy 67.917344 -181.515759)
			(xy 67.917822 -181.543198) (xy 67.917374 -181.570569) (xy 67.909555 -181.62475) (xy 67.894062 -181.677254)
			(xy 67.871216 -181.727) (xy 67.841486 -181.772966) (xy 67.823842 -181.793896) (xy 67.817746 -181.801008)
			(xy 67.811396 -181.818026) (xy 67.811396 -181.90337) (xy 67.817746 -181.920388) (xy 67.823842 -181.9275)
			(xy 67.841482 -181.948434) (xy 67.871209 -181.994401) (xy 67.894057 -182.044146) (xy 67.909554 -182.096649)
			(xy 67.917384 -182.150828) (xy 67.917384 -182.205569) (xy 67.909555 -182.259748) (xy 67.894058 -182.312251)
			(xy 67.871211 -182.361997) (xy 67.841484 -182.407964) (xy 67.823842 -182.428896) (xy 67.817746 -182.436008)
			(xy 67.811396 -182.453026) (xy 67.811396 -182.53837) (xy 67.817746 -182.555388) (xy 67.823842 -182.5625)
			(xy 67.841482 -182.583434) (xy 67.871209 -182.629401) (xy 67.894057 -182.679146) (xy 67.909554 -182.731649)
			(xy 67.917384 -182.785828) (xy 67.917384 -182.840569) (xy 67.909555 -182.894748) (xy 67.894058 -182.947251)
			(xy 67.871211 -182.996997) (xy 67.841484 -183.042964) (xy 67.823842 -183.063896) (xy 67.817746 -183.071008)
			(xy 67.811396 -183.088026) (xy 67.811396 -183.17337) (xy 67.817746 -183.190388) (xy 67.823842 -183.1975)
			(xy 67.841501 -183.218416) (xy 67.871209 -183.264394) (xy 67.89404 -183.314145) (xy 67.909527 -183.366649)
			(xy 67.917351 -183.420828) (xy 67.917822 -183.448198) (xy 67.917258 -183.477471) (xy 67.908294 -183.535328)
			(xy 67.890592 -183.591135) (xy 67.864566 -183.643579) (xy 67.83083 -183.69143) (xy 67.810888 -183.712866)
			(xy 67.804538 -183.719724) (xy 67.797172 -183.736742) (xy 67.793616 -183.822848) (xy 67.799458 -183.840374)
			(xy 67.8053 -183.84774) (xy 67.821526 -183.86824) (xy 67.848782 -183.912855) (xy 67.869683 -183.960777)
			(xy 67.883836 -184.011107) (xy 67.890978 -184.062899) (xy 67.891406 -184.08904) (xy 67.890903 -184.116409)
			(xy 67.883094 -184.170586) (xy 67.867613 -184.223089) (xy 67.84478 -184.272836) (xy 67.815063 -184.318805)
			(xy 67.797426 -184.339738) (xy 67.79133 -184.34685) (xy 67.78498 -184.363868) (xy 67.78498 -184.449212)
			(xy 67.79133 -184.46623) (xy 67.797426 -184.473342) (xy 67.815108 -184.494242) (xy 67.844835 -184.540214)
			(xy 67.86768 -184.589966) (xy 67.883176 -184.642473) (xy 67.891002 -184.696657) (xy 67.890997 -184.751403)
			(xy 67.883163 -184.805586) (xy 67.867659 -184.858091) (xy 67.844806 -184.907839) (xy 67.815071 -184.953806)
			(xy 67.797426 -184.974738) (xy 67.79133 -184.98185) (xy 67.78498 -184.998868) (xy 67.78498 -185.084212)
			(xy 67.79133 -185.10123) (xy 67.797426 -185.108342) (xy 67.815108 -185.129242) (xy 67.844835 -185.175214)
			(xy 67.86768 -185.224966) (xy 67.883176 -185.277473) (xy 67.891002 -185.331657) (xy 67.890997 -185.386403)
			(xy 67.883163 -185.440586) (xy 67.867659 -185.493091) (xy 67.844806 -185.542839) (xy 67.815071 -185.588806)
			(xy 67.797426 -185.609738) (xy 67.79133 -185.61685) (xy 67.78498 -185.633868) (xy 67.78498 -185.719212)
			(xy 67.79133 -185.73623) (xy 67.797426 -185.743342) (xy 67.815108 -185.764242) (xy 67.844835 -185.810214)
			(xy 67.86768 -185.859966) (xy 67.883176 -185.912473) (xy 67.891002 -185.966657) (xy 67.890997 -186.021403)
			(xy 67.883163 -186.075586) (xy 67.867659 -186.128091) (xy 67.844806 -186.177839) (xy 67.815071 -186.223806)
			(xy 67.797426 -186.244738) (xy 67.79133 -186.25185) (xy 67.78498 -186.268868) (xy 67.78498 -186.354212)
			(xy 67.79133 -186.37123) (xy 67.797426 -186.378342) (xy 67.815108 -186.399242) (xy 67.844835 -186.445214)
			(xy 67.86768 -186.494966) (xy 67.883176 -186.547473) (xy 67.891002 -186.601657) (xy 67.890997 -186.656403)
			(xy 67.883163 -186.710586) (xy 67.867659 -186.763091) (xy 67.844806 -186.812839) (xy 67.815071 -186.858806)
			(xy 67.797426 -186.879738) (xy 67.79133 -186.88685) (xy 67.78498 -186.903868) (xy 67.78498 -186.989212)
			(xy 67.79133 -187.00623) (xy 67.797426 -187.013342) (xy 67.815055 -187.034282) (xy 67.844768 -187.080253)
			(xy 67.867605 -187.129998) (xy 67.883099 -187.182497) (xy 67.89093 -187.236671) (xy 67.891406 -187.26404)
			(xy 67.890959 -187.291292) (xy 67.883197 -187.345242) (xy 67.867837 -187.397537) (xy 67.845191 -187.447115)
			(xy 67.81572 -187.492965) (xy 67.780025 -187.534155) (xy 67.738831 -187.569846) (xy 67.692978 -187.599311)
			(xy 67.643398 -187.621952) (xy 67.5911 -187.637306) (xy 67.53715 -187.645062) (xy 67.509898 -187.645548)
			(xy 67.482527 -187.645096) (xy 67.428347 -187.637277) (xy 67.375843 -187.621785) (xy 67.326096 -187.59894)
			(xy 67.280131 -187.569211) (xy 67.2592 -187.551568) (xy 67.252088 -187.545472) (xy 67.23507 -187.539122)
			(xy 67.149726 -187.539122) (xy 67.132708 -187.545472) (xy 67.125596 -187.551568) (xy 67.104672 -187.569217)
			(xy 67.058698 -187.598929) (xy 67.008948 -187.621763) (xy 66.956445 -187.637252) (xy 66.902268 -187.645076)
			(xy 66.874898 -187.645548) (xy 66.847649 -187.645024) (xy 66.793704 -187.637268) (xy 66.741413 -187.621915)
			(xy 66.691838 -187.599277) (xy 66.64599 -187.569814) (xy 66.6048 -187.534126) (xy 66.569109 -187.492941)
			(xy 66.539642 -187.447095) (xy 66.516998 -187.397523) (xy 66.50164 -187.345233) (xy 66.493879 -187.291289)
			(xy 66.49339 -187.26404) (xy 52.942411 -187.26404) (xy 52.94249 -187.268358) (xy 52.941981 -187.296244)
			(xy 52.933861 -187.35142) (xy 52.917793 -187.404827) (xy 52.894121 -187.455324) (xy 52.863348 -187.501837)
			(xy 52.826131 -187.543374) (xy 52.783263 -187.579049) (xy 52.735657 -187.608103) (xy 52.684328 -187.629915)
			(xy 52.630371 -187.644021) (xy 52.574934 -187.650121) (xy 52.5192 -187.648084) (xy 52.464357 -187.637954)
			(xy 52.411573 -187.619947) (xy 52.361973 -187.594446) (xy 52.316615 -187.561995) (xy 52.276466 -187.523286)
			(xy 52.24238 -187.479143) (xy 52.215084 -187.430508) (xy 52.195161 -187.378417) (xy 52.183035 -187.32398)
			(xy 52.178964 -187.268358) (xy 48.023018 -187.268358) (xy 48.734726 -187.980066) (xy 48.735234 -187.980574)
			(xy 48.742615 -187.987157) (xy 48.760914 -187.994611) (xy 48.770794 -187.995052) (xy 61.52134 -187.995052)
			(xy 61.531181 -187.995581) (xy 61.549354 -188.003155) (xy 61.556646 -188.009784) (xy 66.995802 -193.44894)
			(xy 70.81901 -193.44894) (xy 70.819497 -193.42157) (xy 70.827309 -193.367392) (xy 70.842793 -193.314889)
			(xy 70.865631 -193.265142) (xy 70.895351 -193.219174) (xy 70.91299 -193.198242) (xy 70.919086 -193.19113)
			(xy 70.925436 -193.174112) (xy 70.925436 -193.088768) (xy 70.919086 -193.07175) (xy 70.91299 -193.064638)
			(xy 70.89539 -193.043673) (xy 70.865666 -192.99771) (xy 70.842821 -192.947969) (xy 70.827323 -192.895472)
			(xy 70.819492 -192.841298) (xy 70.819487 -192.786562) (xy 70.82731 -192.732387) (xy 70.8428 -192.679888)
			(xy 70.865637 -192.630143) (xy 70.895354 -192.584175) (xy 70.91299 -192.563242) (xy 70.919086 -192.55613)
			(xy 70.925436 -192.539112) (xy 70.925436 -192.453768) (xy 70.919086 -192.43675) (xy 70.91299 -192.429638)
			(xy 70.89539 -192.408673) (xy 70.865666 -192.36271) (xy 70.842821 -192.312969) (xy 70.827323 -192.260472)
			(xy 70.819492 -192.206298) (xy 70.819487 -192.151562) (xy 70.82731 -192.097387) (xy 70.8428 -192.044888)
			(xy 70.865637 -191.995143) (xy 70.895354 -191.949175) (xy 70.91299 -191.928242) (xy 70.919086 -191.92113)
			(xy 70.925436 -191.904112) (xy 70.925436 -191.818768) (xy 70.919086 -191.80175) (xy 70.91299 -191.794638)
			(xy 70.89539 -191.773673) (xy 70.865666 -191.72771) (xy 70.842821 -191.677969) (xy 70.827323 -191.625472)
			(xy 70.819492 -191.571298) (xy 70.819487 -191.516562) (xy 70.82731 -191.462387) (xy 70.8428 -191.409888)
			(xy 70.865637 -191.360143) (xy 70.895354 -191.314175) (xy 70.91299 -191.293242) (xy 70.919086 -191.28613)
			(xy 70.925436 -191.269112) (xy 70.925436 -191.183768) (xy 70.919086 -191.16675) (xy 70.91299 -191.159638)
			(xy 70.89539 -191.138673) (xy 70.865666 -191.09271) (xy 70.842821 -191.042969) (xy 70.827323 -190.990472)
			(xy 70.819492 -190.936298) (xy 70.819487 -190.881562) (xy 70.82731 -190.827387) (xy 70.8428 -190.774888)
			(xy 70.865637 -190.725143) (xy 70.895354 -190.679175) (xy 70.91299 -190.658242) (xy 70.919086 -190.65113)
			(xy 70.925436 -190.634112) (xy 70.925436 -190.548768) (xy 70.919086 -190.53175) (xy 70.91299 -190.524638)
			(xy 70.895354 -190.503704) (xy 70.865642 -190.457731) (xy 70.842805 -190.407984) (xy 70.827314 -190.355484)
			(xy 70.819485 -190.301309) (xy 70.81901 -190.27394) (xy 70.81956 -190.244774) (xy 70.828456 -190.187124)
			(xy 70.846032 -190.131502) (xy 70.871876 -190.079207) (xy 70.905386 -190.03146) (xy 70.925182 -190.010034)
			(xy 70.93204 -190.002668) (xy 70.939152 -189.984888) (xy 70.939152 -189.894464) (xy 70.93204 -189.876684)
			(xy 70.925182 -189.869318) (xy 70.905394 -189.847888) (xy 70.871911 -189.800128) (xy 70.84608 -189.747833)
			(xy 70.828502 -189.692217) (xy 70.819585 -189.634575) (xy 70.81901 -189.605412) (xy 70.819467 -189.578159)
			(xy 70.827222 -189.524207) (xy 70.842578 -189.471907) (xy 70.86522 -189.422326) (xy 70.894689 -189.376472)
			(xy 70.930383 -189.335279) (xy 70.971577 -189.299585) (xy 71.017431 -189.270117) (xy 71.067013 -189.247476)
			(xy 71.119312 -189.232121) (xy 71.173265 -189.224366) (xy 71.200518 -189.223904) (xy 71.227889 -189.224359)
			(xy 71.282068 -189.232179) (xy 71.334572 -189.247671) (xy 71.384318 -189.270515) (xy 71.430285 -189.300242)
			(xy 71.451216 -189.317884) (xy 71.458328 -189.32398) (xy 71.475346 -189.33033) (xy 71.56069 -189.33033)
			(xy 71.577708 -189.32398) (xy 71.58482 -189.317884) (xy 71.605753 -189.300243) (xy 71.651721 -189.270519)
			(xy 71.701467 -189.247673) (xy 71.753969 -189.232177) (xy 71.808147 -189.224348) (xy 71.862889 -189.224348)
			(xy 71.917067 -189.232177) (xy 71.969569 -189.247673) (xy 72.019315 -189.270519) (xy 72.065283 -189.300243)
			(xy 72.086216 -189.317884) (xy 72.093328 -189.32398) (xy 72.110346 -189.33033) (xy 72.19569 -189.33033)
			(xy 72.212708 -189.32398) (xy 72.21982 -189.317884) (xy 72.240769 -189.300266) (xy 72.286738 -189.270552)
			(xy 72.336481 -189.247712) (xy 72.388978 -189.232216) (xy 72.44315 -189.224382) (xy 72.470518 -189.223904)
			(xy 72.49777 -189.224361) (xy 72.55172 -189.23212) (xy 72.604016 -189.247478) (xy 72.653594 -189.270122)
			(xy 72.699445 -189.299592) (xy 72.740635 -189.335286) (xy 72.776326 -189.376479) (xy 72.805792 -189.422333)
			(xy 72.828432 -189.471913) (xy 72.843786 -189.52421) (xy 72.851541 -189.57816) (xy 72.852026 -189.605412)
			(xy 72.851543 -189.632711) (xy 72.84377 -189.686752) (xy 72.828371 -189.739132) (xy 72.805661 -189.788782)
			(xy 72.776102 -189.834686) (xy 72.758554 -189.855602) (xy 72.752204 -189.862714) (xy 72.746108 -189.879732)
			(xy 72.746108 -189.96533) (xy 72.752458 -189.982094) (xy 72.758554 -189.989206) (xy 72.776279 -190.010158)
			(xy 72.806154 -190.056193) (xy 72.829118 -190.106037) (xy 72.844695 -190.15866) (xy 72.852565 -190.212972)
			(xy 72.853042 -190.240412) (xy 72.852597 -190.267783) (xy 72.844776 -190.321964) (xy 72.829283 -190.374468)
			(xy 72.806436 -190.424214) (xy 72.776706 -190.47018) (xy 72.759062 -190.49111) (xy 72.752966 -190.498222)
			(xy 72.746616 -190.51524) (xy 72.746616 -190.600584) (xy 72.752966 -190.617602) (xy 72.759062 -190.624714)
			(xy 72.776715 -190.645637) (xy 72.80644 -190.691606) (xy 72.829285 -190.741354) (xy 72.844781 -190.793858)
			(xy 72.852609 -190.848038) (xy 72.852608 -190.90278) (xy 72.844777 -190.95696) (xy 72.829279 -191.009463)
			(xy 72.806431 -191.05921) (xy 72.776704 -191.105177) (xy 72.759062 -191.12611) (xy 72.752966 -191.133222)
			(xy 72.746616 -191.15024) (xy 72.746616 -191.235584) (xy 72.752966 -191.252602) (xy 72.759062 -191.259714)
			(xy 72.776715 -191.280637) (xy 72.80644 -191.326606) (xy 72.829285 -191.376354) (xy 72.844781 -191.428858)
			(xy 72.852609 -191.483038) (xy 72.852608 -191.53778) (xy 72.844777 -191.59196) (xy 72.829279 -191.644463)
			(xy 72.806431 -191.69421) (xy 72.776704 -191.740177) (xy 72.759062 -191.76111) (xy 72.752966 -191.768222)
			(xy 72.746616 -191.78524) (xy 72.746616 -191.870584) (xy 72.752966 -191.887602) (xy 72.759062 -191.894714)
			(xy 72.776668 -191.915673) (xy 72.806386 -191.961637) (xy 72.829229 -192.011378) (xy 72.844728 -192.063873)
			(xy 72.852564 -192.118045) (xy 72.853042 -192.145412) (xy 72.852482 -192.174636) (xy 72.84356 -192.232399)
			(xy 72.825942 -192.288129) (xy 72.800038 -192.340524) (xy 72.766455 -192.38836) (xy 72.746616 -192.409826)
			(xy 72.739758 -192.416938) (xy 72.732392 -192.434972) (xy 72.732392 -192.525142) (xy 72.739504 -192.543176)
			(xy 72.746362 -192.550288) (xy 72.766087 -192.571715) (xy 72.799442 -192.619454) (xy 72.825159 -192.671706)
			(xy 72.84264 -192.727258) (xy 72.85148 -192.784821) (xy 72.852026 -192.81394) (xy 72.851543 -192.84131)
			(xy 72.843732 -192.895489) (xy 72.828248 -192.947993) (xy 72.805409 -192.99774) (xy 72.775687 -193.043707)
			(xy 72.758046 -193.064638) (xy 72.75195 -193.07175) (xy 72.7456 -193.088768) (xy 72.7456 -193.174112)
			(xy 72.75195 -193.19113) (xy 72.758046 -193.198242) (xy 72.775663 -193.219192) (xy 72.80538 -193.265159)
			(xy 72.828221 -193.314902) (xy 72.843717 -193.367399) (xy 72.85155 -193.421572) (xy 72.852026 -193.44894)
			(xy 72.851559 -193.476191) (xy 72.843798 -193.530139) (xy 72.828439 -193.582433) (xy 72.805794 -193.632009)
			(xy 72.776325 -193.677858) (xy 72.740632 -193.719048) (xy 72.699441 -193.754739) (xy 72.65359 -193.784205)
			(xy 72.604012 -193.806846) (xy 72.551717 -193.822203) (xy 72.497769 -193.829961) (xy 72.470518 -193.830448)
			(xy 72.443148 -193.829984) (xy 72.388968 -193.822168) (xy 72.336464 -193.806679) (xy 72.286717 -193.783836)
			(xy 72.240751 -193.75411) (xy 72.21982 -193.736468) (xy 72.212708 -193.730372) (xy 72.19569 -193.724022)
			(xy 72.110346 -193.724022) (xy 72.093328 -193.730372) (xy 72.086216 -193.736468) (xy 72.065283 -193.754109)
			(xy 72.019315 -193.783833) (xy 71.969569 -193.806679) (xy 71.917067 -193.822175) (xy 71.862889 -193.830004)
			(xy 71.808147 -193.830004) (xy 71.753969 -193.822175) (xy 71.701467 -193.806679) (xy 71.651721 -193.783833)
			(xy 71.605753 -193.754109) (xy 71.58482 -193.736468) (xy 71.577708 -193.730372) (xy 71.56069 -193.724022)
			(xy 71.475346 -193.724022) (xy 71.458328 -193.730372) (xy 71.451216 -193.736468) (xy 71.430285 -193.754108)
			(xy 71.384312 -193.783821) (xy 71.334565 -193.806657) (xy 71.282063 -193.822148) (xy 71.227887 -193.829975)
			(xy 71.200518 -193.830448) (xy 71.173269 -193.829905) (xy 71.119325 -193.822152) (xy 71.067034 -193.806801)
			(xy 71.01746 -193.784165) (xy 70.971611 -193.754705) (xy 70.930422 -193.719019) (xy 70.89473 -193.677835)
			(xy 70.865263 -193.631991) (xy 70.842619 -193.58242) (xy 70.82726 -193.530131) (xy 70.819499 -193.476189)
			(xy 70.81901 -193.44894) (xy 66.995802 -193.44894) (xy 69.535802 -195.98894) (xy 74.83221 -195.98894)
			(xy 74.832697 -195.96157) (xy 74.840509 -195.907392) (xy 74.855993 -195.854889) (xy 74.878831 -195.805142)
			(xy 74.908551 -195.759174) (xy 74.92619 -195.738242) (xy 74.932286 -195.73113) (xy 74.938636 -195.714112)
			(xy 74.938636 -195.628768) (xy 74.932286 -195.61175) (xy 74.92619 -195.604638) (xy 74.90859 -195.583673)
			(xy 74.878866 -195.53771) (xy 74.856021 -195.487969) (xy 74.840523 -195.435472) (xy 74.832692 -195.381298)
			(xy 74.832687 -195.326562) (xy 74.84051 -195.272387) (xy 74.856 -195.219888) (xy 74.878837 -195.170143)
			(xy 74.908554 -195.124175) (xy 74.92619 -195.103242) (xy 74.932286 -195.09613) (xy 74.938636 -195.079112)
			(xy 74.938636 -194.993768) (xy 74.932286 -194.97675) (xy 74.92619 -194.969638) (xy 74.90859 -194.948673)
			(xy 74.878866 -194.90271) (xy 74.856021 -194.852969) (xy 74.840523 -194.800472) (xy 74.832692 -194.746298)
			(xy 74.832687 -194.691562) (xy 74.84051 -194.637387) (xy 74.856 -194.584888) (xy 74.878837 -194.535143)
			(xy 74.908554 -194.489175) (xy 74.92619 -194.468242) (xy 74.932286 -194.46113) (xy 74.938636 -194.444112)
			(xy 74.938636 -194.358768) (xy 74.932286 -194.34175) (xy 74.92619 -194.334638) (xy 74.90859 -194.313673)
			(xy 74.878866 -194.26771) (xy 74.856021 -194.217969) (xy 74.840523 -194.165472) (xy 74.832692 -194.111298)
			(xy 74.832687 -194.056562) (xy 74.84051 -194.002387) (xy 74.856 -193.949888) (xy 74.878837 -193.900143)
			(xy 74.908554 -193.854175) (xy 74.92619 -193.833242) (xy 74.932286 -193.82613) (xy 74.938636 -193.809112)
			(xy 74.938636 -193.723768) (xy 74.932286 -193.70675) (xy 74.92619 -193.699638) (xy 74.90859 -193.678673)
			(xy 74.878866 -193.63271) (xy 74.856021 -193.582969) (xy 74.840523 -193.530472) (xy 74.832692 -193.476298)
			(xy 74.832687 -193.421562) (xy 74.84051 -193.367387) (xy 74.856 -193.314888) (xy 74.878837 -193.265143)
			(xy 74.908554 -193.219175) (xy 74.92619 -193.198242) (xy 74.932286 -193.19113) (xy 74.938636 -193.174112)
			(xy 74.938636 -193.088768) (xy 74.932286 -193.07175) (xy 74.92619 -193.064638) (xy 74.908554 -193.043704)
			(xy 74.878842 -192.997731) (xy 74.856005 -192.947984) (xy 74.840514 -192.895484) (xy 74.832685 -192.841309)
			(xy 74.83221 -192.81394) (xy 74.832788 -192.784717) (xy 74.841703 -192.726953) (xy 74.859317 -192.671223)
			(xy 74.885216 -192.618828) (xy 74.918798 -192.570992) (xy 74.938636 -192.549526) (xy 74.945494 -192.542414)
			(xy 74.95286 -192.52438) (xy 74.95286 -192.43421) (xy 74.945748 -192.416176) (xy 74.93889 -192.409064)
			(xy 74.919182 -192.387623) (xy 74.885826 -192.339886) (xy 74.860107 -192.287638) (xy 74.842622 -192.232089)
			(xy 74.833776 -192.17453) (xy 74.833226 -192.145412) (xy 74.833693 -192.118042) (xy 74.841509 -192.063862)
			(xy 74.856998 -192.011359) (xy 74.87984 -191.961612) (xy 74.909565 -191.915646) (xy 74.927206 -191.894714)
			(xy 74.933302 -191.887602) (xy 74.939652 -191.870584) (xy 74.939652 -191.78524) (xy 74.933302 -191.768222)
			(xy 74.927206 -191.76111) (xy 74.909578 -191.740167) (xy 74.879854 -191.694201) (xy 74.857009 -191.644456)
			(xy 74.841513 -191.591956) (xy 74.833684 -191.537779) (xy 74.833683 -191.483039) (xy 74.841509 -191.428862)
			(xy 74.857003 -191.376361) (xy 74.879846 -191.326615) (xy 74.909567 -191.280647) (xy 74.927206 -191.259714)
			(xy 74.933302 -191.252602) (xy 74.939652 -191.235584) (xy 74.939652 -191.15024) (xy 74.933302 -191.133222)
			(xy 74.927206 -191.12611) (xy 74.909578 -191.105167) (xy 74.879854 -191.059201) (xy 74.857009 -191.009456)
			(xy 74.841513 -190.956956) (xy 74.833684 -190.902779) (xy 74.833683 -190.848039) (xy 74.841509 -190.793862)
			(xy 74.857003 -190.741361) (xy 74.879846 -190.691615) (xy 74.909567 -190.645647) (xy 74.927206 -190.624714)
			(xy 74.933302 -190.617602) (xy 74.939652 -190.600584) (xy 74.939652 -190.51524) (xy 74.933302 -190.498222)
			(xy 74.927206 -190.49111) (xy 74.909559 -190.470184) (xy 74.879848 -190.42421) (xy 74.857014 -190.374461)
			(xy 74.841524 -190.321959) (xy 74.833699 -190.267782) (xy 74.833226 -190.240412) (xy 74.833711 -190.213113)
			(xy 74.841481 -190.159072) (xy 74.856879 -190.106691) (xy 74.87959 -190.057041) (xy 74.909149 -190.011138)
			(xy 74.926698 -189.990222) (xy 74.933048 -189.98311) (xy 74.939144 -189.966092) (xy 74.939144 -189.880494)
			(xy 74.932794 -189.86373) (xy 74.926698 -189.856618) (xy 74.908992 -189.83565) (xy 74.879113 -189.78962)
			(xy 74.856144 -189.73978) (xy 74.840562 -189.687161) (xy 74.832689 -189.632851) (xy 74.83221 -189.605412)
			(xy 74.832667 -189.578159) (xy 74.840422 -189.524207) (xy 74.855778 -189.471907) (xy 74.87842 -189.422326)
			(xy 74.907889 -189.376472) (xy 74.943583 -189.335279) (xy 74.984777 -189.299585) (xy 75.030631 -189.270117)
			(xy 75.080213 -189.247476) (xy 75.132512 -189.232121) (xy 75.186465 -189.224366) (xy 75.213718 -189.223904)
			(xy 75.241089 -189.224359) (xy 75.295268 -189.232179) (xy 75.347772 -189.247671) (xy 75.397518 -189.270515)
			(xy 75.443485 -189.300242) (xy 75.464416 -189.317884) (xy 75.471528 -189.32398) (xy 75.488546 -189.33033)
			(xy 75.57389 -189.33033) (xy 75.590908 -189.32398) (xy 75.59802 -189.317884) (xy 75.618969 -189.300266)
			(xy 75.664938 -189.270552) (xy 75.714681 -189.247712) (xy 75.767178 -189.232216) (xy 75.82135 -189.224382)
			(xy 75.848718 -189.223904) (xy 75.878196 -189.224432) (xy 75.93645 -189.233504) (xy 75.992615 -189.251429)
			(xy 76.045354 -189.277781) (xy 76.093411 -189.311932) (xy 76.11491 -189.332108) (xy 76.122246 -189.338641)
			(xy 76.140405 -189.346087) (xy 76.150216 -189.346586) (xy 76.203556 -189.346586) (xy 76.208636 -189.341252)
			(xy 76.215101 -189.333891) (xy 76.222414 -189.315733) (xy 76.22286 -189.305946) (xy 76.22286 -175.990504)
			(xy 76.223322 -175.965529) (xy 76.231117 -175.91619) (xy 76.246531 -175.868677) (xy 76.269185 -175.824159)
			(xy 76.298521 -175.783731) (xy 76.315824 -175.765714) (xy 76.788264 -175.293274) (xy 76.795157 -175.285619)
			(xy 76.802839 -175.266532) (xy 76.802451 -175.24596) (xy 76.798678 -175.236378) (xy 76.752958 -175.135032)
			(xy 76.726034 -175.11903) (xy 76.710032 -175.120046) (xy 76.685648 -175.120808) (xy 76.658391 -175.120396)
			(xy 76.604431 -175.112645) (xy 76.552123 -175.097293) (xy 76.502533 -175.074652) (xy 76.456669 -175.045185)
			(xy 76.415467 -175.00949) (xy 76.379763 -174.968295) (xy 76.350286 -174.922438) (xy 76.327635 -174.872852)
			(xy 76.312272 -174.820548) (xy 76.304509 -174.766589) (xy 76.304505 -174.712075) (xy 76.312259 -174.658115)
			(xy 76.327613 -174.605808) (xy 76.350255 -174.556219) (xy 76.379725 -174.510356) (xy 76.415421 -174.469155)
			(xy 76.456618 -174.433454) (xy 76.502476 -174.403978) (xy 76.552063 -174.38133) (xy 76.604368 -174.365969)
			(xy 76.658327 -174.358208) (xy 76.712841 -174.358206) (xy 76.766801 -174.365962) (xy 76.819107 -174.381319)
			(xy 76.868695 -174.403963) (xy 76.914556 -174.433434) (xy 76.955756 -174.469133) (xy 76.991456 -174.510331)
			(xy 77.020929 -174.556191) (xy 77.043576 -174.605778) (xy 77.058935 -174.658084) (xy 77.066693 -174.712043)
			(xy 77.067156 -174.7393) (xy 77.066551 -174.770432) (xy 77.05648 -174.831874) (xy 77.036541 -174.890857)
			(xy 77.022452 -174.918624) (xy 77.014578 -174.933356) (xy 77.019404 -174.96663) (xy 77.031342 -174.978314)
			(xy 77.038776 -174.98503) (xy 77.057276 -174.992666) (xy 77.07729 -174.992666) (xy 77.09579 -174.98503)
			(xy 77.103224 -174.978314) (xy 77.223366 -174.858172) (xy 77.230113 -174.850786) (xy 77.237821 -174.832348)
			(xy 77.238352 -174.822358) (xy 77.238352 -174.287942) (xy 77.237904 -174.277936) (xy 77.230176 -174.259473)
			(xy 77.223366 -174.252128) (xy 77.19441 -174.223172) (xy 77.182472 -174.216568) (xy 77.175614 -174.21479)
			(xy 77.148214 -174.20768) (xy 77.095733 -174.186471) (xy 77.046962 -174.157739) (xy 77.002973 -174.122115)
			(xy 76.964731 -174.080382) (xy 76.933077 -174.033455) (xy 76.908705 -173.982365) (xy 76.892151 -173.928235)
			(xy 76.883779 -173.872252) (xy 76.88326 -173.84395) (xy 76.883802 -173.8167) (xy 76.891551 -173.762753)
			(xy 76.906899 -173.710459) (xy 76.929533 -173.660881) (xy 76.958993 -173.615029) (xy 76.994679 -173.573837)
			(xy 77.035864 -173.538142) (xy 77.081709 -173.508673) (xy 77.131282 -173.486028) (xy 77.183573 -173.470668)
			(xy 77.237518 -173.462908) (xy 77.264768 -173.462442) (xy 77.293073 -173.463) (xy 77.349064 -173.47134)
			(xy 77.403205 -173.487871) (xy 77.454306 -173.512228) (xy 77.501241 -173.543876) (xy 77.542979 -173.58212)
			(xy 77.5786 -173.626116) (xy 77.607321 -173.674898) (xy 77.62851 -173.727391) (xy 77.635608 -173.754796)
			(xy 77.637386 -173.761654) (xy 77.64399 -173.773592) (xy 77.780896 -173.910498) (xy 77.798225 -173.928493)
			(xy 77.827574 -173.968919) (xy 77.850232 -174.013441) (xy 77.86564 -174.060962) (xy 77.873417 -174.110309)
			(xy 77.87386 -174.135288) (xy 77.87386 -174.975012) (xy 77.873402 -174.999988) (xy 77.865606 -175.049326)
			(xy 77.85019 -175.096839) (xy 77.827535 -175.141356) (xy 77.798198 -175.181784) (xy 77.780896 -175.199802)
			(xy 77.564488 -175.415956) (xy 77.557675 -175.423437) (xy 77.550047 -175.442159) (xy 77.550235 -175.462375)
			(xy 77.55382 -175.471836) (xy 77.596492 -175.572928) (xy 77.6224 -175.589692) (xy 77.638148 -175.589438)
			(xy 77.64399 -175.589438) (xy 77.671245 -175.589865) (xy 77.725199 -175.597622) (xy 77.777501 -175.612979)
			(xy 77.827084 -175.635623) (xy 77.872939 -175.665095) (xy 77.914133 -175.700792) (xy 77.949827 -175.74199)
			(xy 77.979294 -175.787848) (xy 78.001934 -175.837433) (xy 78.017286 -175.889736) (xy 78.025038 -175.943691)
			(xy 78.025498 -175.970946) (xy 78.025011 -175.998857) (xy 78.016871 -176.054082) (xy 78.000773 -176.107532)
			(xy 77.97706 -176.158066) (xy 77.946238 -176.204607) (xy 77.927962 -176.225708) (xy 77.921612 -176.23282)
			(xy 77.915008 -176.250092) (xy 77.915008 -176.337214) (xy 77.921612 -176.354486) (xy 77.927962 -176.361598)
			(xy 77.946223 -176.382711) (xy 77.977051 -176.429247) (xy 78.000768 -176.479778) (xy 78.016869 -176.533226)
			(xy 78.025009 -176.58845) (xy 78.025498 -176.61636) (xy 78.025012 -176.643611) (xy 78.017256 -176.697559)
			(xy 78.001901 -176.749854) (xy 77.979259 -176.799431) (xy 77.949793 -176.845281) (xy 77.914102 -176.886472)
			(xy 77.872911 -176.922163) (xy 77.827061 -176.951629) (xy 77.777484 -176.974271) (xy 77.725189 -176.989626)
			(xy 77.671241 -176.997382) (xy 77.616739 -176.997382) (xy 77.562791 -176.989626) (xy 77.510496 -176.974271)
			(xy 77.460919 -176.951629) (xy 77.415069 -176.922163) (xy 77.373878 -176.886472) (xy 77.338187 -176.845281)
			(xy 77.308721 -176.799431) (xy 77.286079 -176.749854) (xy 77.270724 -176.697559) (xy 77.262968 -176.643611)
			(xy 77.262482 -176.61636) (xy 77.262953 -176.588448) (xy 77.271093 -176.533222) (xy 77.287194 -176.479771)
			(xy 77.310911 -176.429236) (xy 77.341739 -176.382697) (xy 77.360018 -176.361598) (xy 77.366368 -176.354486)
			(xy 77.372972 -176.337214) (xy 77.372972 -176.250092) (xy 77.366368 -176.23282) (xy 77.360018 -176.225708)
			(xy 77.341725 -176.204621) (xy 77.310899 -176.158079) (xy 77.287187 -176.107542) (xy 77.271094 -176.054087)
			(xy 77.262964 -175.998858) (xy 77.262482 -175.970946) (xy 77.262482 -175.965104) (xy 77.262736 -175.949356)
			(xy 77.245972 -175.923448) (xy 77.14488 -175.880776) (xy 77.135428 -175.877166) (xy 77.115207 -175.876999)
			(xy 77.09648 -175.884627) (xy 77.089 -175.891444) (xy 76.873354 -176.107344) (xy 76.866633 -176.114749)
			(xy 76.858912 -176.133173) (xy 76.858368 -176.143158) (xy 76.858368 -178.798474) (xy 78.471522 -178.798474)
			(xy 78.472085 -178.769559) (xy 78.480804 -178.712389) (xy 78.498052 -178.657191) (xy 78.523435 -178.605229)
			(xy 78.556371 -178.557694) (xy 78.596106 -178.515675) (xy 78.618588 -178.497484) (xy 78.627351 -178.489923)
			(xy 78.637534 -178.469164) (xy 78.638146 -178.457606) (xy 78.638146 -178.377342) (xy 78.63757 -178.365774)
			(xy 78.627381 -178.345002) (xy 78.618588 -178.337464) (xy 78.596085 -178.319296) (xy 78.556351 -178.277271)
			(xy 78.523415 -178.229732) (xy 78.49803 -178.177766) (xy 78.480778 -178.122564) (xy 78.472054 -178.065391)
			(xy 78.471522 -178.036474) (xy 78.471931 -178.009219) (xy 78.479692 -177.955265) (xy 78.495053 -177.902964)
			(xy 78.517701 -177.853382) (xy 78.547174 -177.807527) (xy 78.582874 -177.766334) (xy 78.624072 -177.730641)
			(xy 78.669931 -177.701174) (xy 78.719516 -177.678533) (xy 78.771819 -177.66318) (xy 78.825775 -177.655427)
			(xy 78.85303 -177.654966) (xy 78.880667 -177.655461) (xy 78.935359 -177.663462) (xy 78.988327 -177.679262)
			(xy 79.038464 -177.702533) (xy 79.084723 -177.732788) (xy 79.126137 -177.769395) (xy 79.161843 -177.81159)
			(xy 79.191093 -177.85849) (xy 79.213277 -177.909117) (xy 79.221076 -177.935636) (xy 79.223362 -177.94478)
			(xy 79.234792 -177.96002) (xy 79.308706 -178.006756) (xy 79.327248 -178.010566) (xy 79.336646 -178.008788)
			(xy 79.353146 -178.006047) (xy 79.386469 -178.003125) (xy 79.403194 -178.002946) (xy 79.430443 -178.003483)
			(xy 79.484387 -178.011238) (xy 79.536677 -178.02659) (xy 79.586252 -178.049227) (xy 79.6321 -178.078688)
			(xy 79.673289 -178.114374) (xy 79.708981 -178.155558) (xy 79.738448 -178.201403) (xy 79.761092 -178.250974)
			(xy 79.776451 -178.303263) (xy 79.784213 -178.357205) (xy 79.784702 -178.384454) (xy 79.784272 -178.40964)
			(xy 79.777658 -178.459576) (xy 79.764536 -178.508209) (xy 79.745137 -178.554696) (xy 79.719795 -178.598229)
			(xy 79.704692 -178.618388) (xy 79.696818 -178.628548) (xy 79.6925 -178.653186) (xy 79.727298 -178.757834)
			(xy 79.745586 -178.775106) (xy 79.758032 -178.778408) (xy 79.784565 -178.786174) (xy 79.835211 -178.808337)
			(xy 79.882129 -178.837577) (xy 79.924337 -178.87328) (xy 79.960951 -178.914701) (xy 79.991205 -178.960971)
			(xy 80.014465 -179.011123) (xy 80.030246 -179.064106) (xy 80.038215 -179.118812) (xy 80.038702 -179.146454)
			(xy 80.038204 -179.174027) (xy 80.030258 -179.228599) (xy 80.014539 -179.281458) (xy 79.991375 -179.331504)
			(xy 79.961249 -179.377694) (xy 79.924787 -179.419067) (xy 79.904082 -179.437284) (xy 79.895973 -179.444895)
			(xy 79.886614 -179.46504) (xy 79.886048 -179.476146) (xy 79.886048 -179.553362) (xy 79.886606 -179.564473)
			(xy 79.89595 -179.584633) (xy 79.904082 -179.592224) (xy 79.924804 -179.610423) (xy 79.961275 -179.651794)
			(xy 79.991406 -179.697986) (xy 80.01457 -179.748037) (xy 80.030283 -179.800902) (xy 80.038219 -179.855478)
			(xy 80.038702 -179.883054) (xy 80.038202 -179.910306) (xy 80.030451 -179.964256) (xy 80.015101 -180.016553)
			(xy 79.992463 -180.066134) (xy 79.962999 -180.111987) (xy 79.927309 -180.153181) (xy 79.88612 -180.188875)
			(xy 79.840269 -180.218344) (xy 79.790691 -180.240987) (xy 79.738395 -180.256343) (xy 79.684446 -180.264099)
			(xy 79.657194 -180.264562) (xy 79.622904 -180.263038) (xy 79.612744 -180.262022) (xy 79.59344 -180.268118)
			(xy 79.522828 -180.3273) (xy 79.51343 -180.345334) (xy 79.512414 -180.355494) (xy 79.509502 -180.383672)
			(xy 79.496321 -180.438765) (xy 79.475137 -180.491302) (xy 79.446414 -180.540128) (xy 79.410785 -180.584168)
			(xy 79.369033 -180.622454) (xy 79.322078 -180.654142) (xy 79.270952 -180.678537) (xy 79.21678 -180.695101)
			(xy 79.160754 -180.70347) (xy 79.13243 -180.703982) (xy 79.105177 -180.703517) (xy 79.051224 -180.695763)
			(xy 78.998925 -180.68041) (xy 78.949343 -180.657769) (xy 78.903489 -180.628301) (xy 78.862295 -180.592608)
			(xy 78.826601 -180.551414) (xy 78.797133 -180.50556) (xy 78.774492 -180.455979) (xy 78.759138 -180.403679)
			(xy 78.751384 -180.349727) (xy 78.750922 -180.322474) (xy 78.751409 -180.294612) (xy 78.759514 -180.23948)
			(xy 78.775547 -180.186112) (xy 78.799167 -180.135641) (xy 78.829874 -180.089141) (xy 78.867014 -180.047598)
			(xy 78.888082 -180.029358) (xy 78.897226 -180.021738) (xy 78.906878 -180.000656) (xy 78.903322 -179.89677)
			(xy 78.8924 -179.876196) (xy 78.882748 -179.869084) (xy 78.862203 -179.853655) (xy 78.825069 -179.818144)
			(xy 78.793037 -179.777969) (xy 78.766688 -179.733859) (xy 78.746498 -179.686611) (xy 78.732833 -179.637081)
			(xy 78.72594 -179.586164) (xy 78.725522 -179.560474) (xy 78.725907 -179.535286) (xy 78.732532 -179.485349)
			(xy 78.745663 -179.436715) (xy 78.765073 -179.390229) (xy 78.790424 -179.346698) (xy 78.805532 -179.32654)
			(xy 78.813406 -179.31638) (xy 78.817724 -179.291742) (xy 78.782926 -179.187094) (xy 78.764638 -179.169822)
			(xy 78.752192 -179.16652) (xy 78.725672 -179.158714) (xy 78.675027 -179.136556) (xy 78.628109 -179.107322)
			(xy 78.585901 -179.071623) (xy 78.549286 -179.030208) (xy 78.51903 -178.983943) (xy 78.495767 -178.933795)
			(xy 78.479984 -178.880816) (xy 78.472011 -178.826114) (xy 78.471522 -178.798474) (xy 76.858368 -178.798474)
			(xy 76.858368 -182.2196) (xy 79.86014 -182.2196) (xy 79.860592 -182.192025) (xy 79.868545 -182.137451)
			(xy 79.884272 -182.08459) (xy 79.907445 -182.034544) (xy 79.93758 -181.988355) (xy 79.974051 -181.946985)
			(xy 79.99476 -181.92877) (xy 80.002897 -181.921185) (xy 80.012238 -181.90102) (xy 80.012794 -181.889908)
			(xy 80.012794 -181.812692) (xy 80.012248 -181.801579) (xy 80.002894 -181.781421) (xy 79.99476 -181.77383)
			(xy 79.974052 -181.755616) (xy 79.937583 -181.714246) (xy 79.907452 -181.668057) (xy 79.884286 -181.61801)
			(xy 79.868568 -181.565148) (xy 79.860627 -181.510574) (xy 79.86014 -181.483) (xy 79.86071 -181.454477)
			(xy 79.869217 -181.398068) (xy 79.886025 -181.343553) (xy 79.910762 -181.292148) (xy 79.942875 -181.244998)
			(xy 79.981648 -181.203154) (xy 80.026219 -181.167547) (xy 80.05064 -181.1528) (xy 80.060546 -181.146958)
			(xy 80.073246 -181.128416) (xy 80.090264 -181.028848) (xy 80.084168 -181.007258) (xy 80.076802 -180.998622)
			(xy 80.059877 -180.978237) (xy 80.031365 -180.933582) (xy 80.009461 -180.885339) (xy 79.994606 -180.834483)
			(xy 79.9871 -180.782035) (xy 79.986632 -180.755544) (xy 79.987075 -180.728925) (xy 79.994647 -180.676228)
			(xy 80.009642 -180.625146) (xy 80.031755 -180.576718) (xy 80.060537 -180.53193) (xy 80.0954 -180.491696)
			(xy 80.135635 -180.456833) (xy 80.180423 -180.428052) (xy 80.228851 -180.40594) (xy 80.279934 -180.390945)
			(xy 80.332631 -180.383375) (xy 80.35925 -180.382926) (xy 80.385672 -180.383372) (xy 80.437987 -180.390828)
			(xy 80.488725 -180.405596) (xy 80.536869 -180.427382) (xy 80.581454 -180.455748) (xy 80.60182 -180.472588)
			(xy 80.608678 -180.478684) (xy 80.625696 -180.48478) (xy 80.710024 -180.48478) (xy 80.727042 -180.478684)
			(xy 80.7339 -180.472588) (xy 80.754266 -180.455749) (xy 80.798852 -180.427384) (xy 80.846996 -180.405597)
			(xy 80.897733 -180.390826) (xy 80.950048 -180.383366) (xy 81.002892 -180.383366) (xy 81.055207 -180.390826)
			(xy 81.105944 -180.405597) (xy 81.154088 -180.427384) (xy 81.198674 -180.455749) (xy 81.21904 -180.472588)
			(xy 81.225898 -180.478684) (xy 81.242916 -180.48478) (xy 81.327244 -180.48478) (xy 81.344262 -180.478684)
			(xy 81.35112 -180.472588) (xy 81.371477 -180.455739) (xy 81.416069 -180.427386) (xy 81.464216 -180.405609)
			(xy 81.514954 -180.390844) (xy 81.567269 -180.383386) (xy 81.59369 -180.382926) (xy 81.621581 -180.383332)
			(xy 81.676739 -180.391645) (xy 81.730042 -180.408085) (xy 81.780299 -180.432287) (xy 81.826388 -180.463709)
			(xy 81.867279 -180.501649) (xy 81.902059 -180.54526) (xy 81.92995 -180.593567) (xy 81.950329 -180.645492)
			(xy 81.962742 -180.699875) (xy 81.966911 -180.7555) (xy 81.962742 -180.811125) (xy 81.950329 -180.865508)
			(xy 81.92995 -180.917433) (xy 81.902059 -180.96574) (xy 81.867279 -181.009351) (xy 81.826388 -181.047291)
			(xy 81.780299 -181.078713) (xy 81.730042 -181.102915) (xy 81.676739 -181.119355) (xy 81.621581 -181.127668)
			(xy 81.59369 -181.128162) (xy 81.567269 -181.127695) (xy 81.514954 -181.120245) (xy 81.464216 -181.105482)
			(xy 81.416072 -181.0837) (xy 81.371486 -181.055338) (xy 81.35112 -181.0385) (xy 81.344262 -181.032404)
			(xy 81.327244 -181.026308) (xy 81.242916 -181.026308) (xy 81.225898 -181.032404) (xy 81.21904 -181.0385)
			(xy 81.198674 -181.055339) (xy 81.154088 -181.083704) (xy 81.105944 -181.105491) (xy 81.055207 -181.120262)
			(xy 81.002892 -181.127722) (xy 80.950048 -181.127722) (xy 80.897733 -181.120262) (xy 80.846996 -181.105491)
			(xy 80.798852 -181.083704) (xy 80.754266 -181.055339) (xy 80.7339 -181.0385) (xy 80.727042 -181.032404)
			(xy 80.710024 -181.026308) (xy 80.625696 -181.026308) (xy 80.608678 -181.032404) (xy 80.60182 -181.0385)
			(xy 80.589745 -181.04857) (xy 80.564186 -181.066884) (xy 80.550766 -181.075076) (xy 80.54086 -181.081172)
			(xy 80.528414 -181.099714) (xy 80.51292 -181.199536) (xy 80.519524 -181.221126) (xy 80.52689 -181.229762)
			(xy 80.544916 -181.250813) (xy 80.575348 -181.297128) (xy 80.598751 -181.347362) (xy 80.614633 -181.400456)
			(xy 80.622659 -181.455291) (xy 80.623156 -181.483) (xy 80.622706 -181.510575) (xy 80.614752 -181.56515)
			(xy 80.599025 -181.61801) (xy 80.575852 -181.668057) (xy 80.545716 -181.714246) (xy 80.509245 -181.755615)
			(xy 80.488536 -181.77383) (xy 80.480398 -181.781415) (xy 80.471057 -181.80158) (xy 80.470502 -181.812692)
			(xy 80.470502 -181.889908) (xy 80.471049 -181.90102) (xy 80.480402 -181.921179) (xy 80.488536 -181.92877)
			(xy 80.509243 -181.946985) (xy 80.545712 -181.988354) (xy 80.575844 -182.034543) (xy 80.59901 -182.08459)
			(xy 80.614728 -182.137452) (xy 80.622669 -182.192026) (xy 80.623156 -182.2196) (xy 80.62267 -182.246851)
			(xy 80.614914 -182.300799) (xy 80.599559 -182.353094) (xy 80.576917 -182.402671) (xy 80.547451 -182.448521)
			(xy 80.51176 -182.489712) (xy 80.470569 -182.525403) (xy 80.424719 -182.554869) (xy 80.375142 -182.577511)
			(xy 80.322847 -182.592866) (xy 80.268899 -182.600622) (xy 80.214397 -182.600622) (xy 80.160449 -182.592866)
			(xy 80.108154 -182.577511) (xy 80.058577 -182.554869) (xy 80.012727 -182.525403) (xy 79.971536 -182.489712)
			(xy 79.935845 -182.448521) (xy 79.906379 -182.402671) (xy 79.883737 -182.353094) (xy 79.868382 -182.300799)
			(xy 79.860626 -182.246851) (xy 79.86014 -182.2196) (xy 76.858368 -182.2196) (xy 76.858368 -189.534038)
			(xy 76.859384 -189.538356) (xy 76.862131 -189.554984) (xy 76.86506 -189.58856) (xy 76.865226 -189.605412)
			(xy 76.864734 -189.632956) (xy 76.856779 -189.687466) (xy 76.841065 -189.740265) (xy 76.817919 -189.790255)
			(xy 76.787823 -189.836394) (xy 76.769976 -189.85738) (xy 76.76388 -189.864492) (xy 76.757276 -189.881764)
			(xy 76.75753 -189.967616) (xy 76.764134 -189.985142) (xy 76.77023 -189.992) (xy 76.78822 -190.013035)
			(xy 76.818568 -190.059321) (xy 76.841906 -190.109509) (xy 76.857743 -190.162543) (xy 76.865747 -190.21731)
			(xy 76.866242 -190.244984) (xy 76.865781 -190.272355) (xy 76.857964 -190.326534) (xy 76.842474 -190.379038)
			(xy 76.819631 -190.428785) (xy 76.789905 -190.474751) (xy 76.772262 -190.495682) (xy 76.766166 -190.502794)
			(xy 76.759816 -190.519812) (xy 76.759816 -190.605156) (xy 76.766166 -190.622174) (xy 76.772262 -190.629286)
			(xy 76.789887 -190.650231) (xy 76.819614 -190.696197) (xy 76.842461 -190.745941) (xy 76.857959 -190.798441)
			(xy 76.865789 -190.852618) (xy 76.865791 -190.907358) (xy 76.857964 -190.961535) (xy 76.842469 -191.014037)
			(xy 76.819625 -191.063782) (xy 76.789902 -191.10975) (xy 76.772262 -191.130682) (xy 76.766166 -191.137794)
			(xy 76.759816 -191.154812) (xy 76.759816 -191.240156) (xy 76.766166 -191.257174) (xy 76.772262 -191.264286)
			(xy 76.789887 -191.285231) (xy 76.819614 -191.331197) (xy 76.842461 -191.380941) (xy 76.857959 -191.433441)
			(xy 76.865789 -191.487618) (xy 76.865791 -191.542358) (xy 76.857964 -191.596535) (xy 76.842469 -191.649037)
			(xy 76.819625 -191.698782) (xy 76.789902 -191.74475) (xy 76.772262 -191.765682) (xy 76.766166 -191.772794)
			(xy 76.759816 -191.789812) (xy 76.759816 -191.875156) (xy 76.766166 -191.892174) (xy 76.772262 -191.899286)
			(xy 76.789902 -191.920217) (xy 76.819615 -191.96619) (xy 76.842451 -192.015937) (xy 76.857942 -192.068438)
			(xy 76.865769 -192.122615) (xy 76.866242 -192.149984) (xy 76.865682 -192.178958) (xy 76.85693 -192.236243)
			(xy 76.839624 -192.291547) (xy 76.814162 -192.343602) (xy 76.781128 -192.391214) (xy 76.761594 -192.41262)
			(xy 76.754736 -192.419732) (xy 76.747624 -192.437766) (xy 76.74737 -192.527174) (xy 76.754482 -192.544954)
			(xy 76.76134 -192.55232) (xy 76.780724 -192.573687) (xy 76.813527 -192.621142) (xy 76.83881 -192.672996)
			(xy 76.855995 -192.728066) (xy 76.864692 -192.785096) (xy 76.865226 -192.81394) (xy 76.864743 -192.84131)
			(xy 76.856932 -192.895489) (xy 76.841448 -192.947993) (xy 76.818609 -192.99774) (xy 76.788887 -193.043707)
			(xy 76.771246 -193.064638) (xy 76.76515 -193.07175) (xy 76.7588 -193.088768) (xy 76.7588 -193.174112)
			(xy 76.76515 -193.19113) (xy 76.771246 -193.198242) (xy 76.788927 -193.219142) (xy 76.818652 -193.265115)
			(xy 76.841497 -193.314867) (xy 76.856991 -193.367374) (xy 76.864817 -193.421557) (xy 76.864812 -193.476303)
			(xy 76.856978 -193.530485) (xy 76.841476 -193.58299) (xy 76.818623 -193.632738) (xy 76.788891 -193.678706)
			(xy 76.771246 -193.699638) (xy 76.76515 -193.70675) (xy 76.7588 -193.723768) (xy 76.7588 -193.809112)
			(xy 76.76515 -193.82613) (xy 76.771246 -193.833242) (xy 76.788927 -193.854142) (xy 76.818652 -193.900115)
			(xy 76.841497 -193.949867) (xy 76.856991 -194.002374) (xy 76.864817 -194.056557) (xy 76.864812 -194.111303)
			(xy 76.856978 -194.165485) (xy 76.841476 -194.21799) (xy 76.818623 -194.267738) (xy 76.788891 -194.313706)
			(xy 76.771246 -194.334638) (xy 76.76515 -194.34175) (xy 76.7588 -194.358768) (xy 76.7588 -194.444112)
			(xy 76.76515 -194.46113) (xy 76.771246 -194.468242) (xy 76.788927 -194.489142) (xy 76.818652 -194.535115)
			(xy 76.841497 -194.584867) (xy 76.856991 -194.637374) (xy 76.864817 -194.691557) (xy 76.864812 -194.746303)
			(xy 76.856978 -194.800485) (xy 76.841476 -194.85299) (xy 76.818623 -194.902738) (xy 76.788891 -194.948706)
			(xy 76.771246 -194.969638) (xy 76.76515 -194.97675) (xy 76.7588 -194.993768) (xy 76.7588 -195.079112)
			(xy 76.76515 -195.09613) (xy 76.771246 -195.103242) (xy 76.788927 -195.124142) (xy 76.818652 -195.170115)
			(xy 76.841497 -195.219867) (xy 76.856991 -195.272374) (xy 76.864817 -195.326557) (xy 76.864812 -195.381303)
			(xy 76.856978 -195.435485) (xy 76.841476 -195.48799) (xy 76.818623 -195.537738) (xy 76.788891 -195.583706)
			(xy 76.771246 -195.604638) (xy 76.76515 -195.61175) (xy 76.7588 -195.628768) (xy 76.7588 -195.714112)
			(xy 76.76515 -195.73113) (xy 76.771246 -195.738242) (xy 76.788863 -195.759192) (xy 76.81858 -195.805159)
			(xy 76.841421 -195.854902) (xy 76.856917 -195.907399) (xy 76.86475 -195.961572) (xy 76.865226 -195.98894)
			(xy 76.864759 -196.016191) (xy 76.856998 -196.070139) (xy 76.841639 -196.122433) (xy 76.818994 -196.172009)
			(xy 76.789525 -196.217858) (xy 76.753832 -196.259048) (xy 76.712641 -196.294739) (xy 76.66679 -196.324205)
			(xy 76.617212 -196.346846) (xy 76.564917 -196.362203) (xy 76.510969 -196.369961) (xy 76.483718 -196.370448)
			(xy 76.456348 -196.369984) (xy 76.402168 -196.362168) (xy 76.349664 -196.346679) (xy 76.299917 -196.323836)
			(xy 76.253951 -196.29411) (xy 76.23302 -196.276468) (xy 76.225908 -196.270372) (xy 76.20889 -196.264022)
			(xy 76.123546 -196.264022) (xy 76.106528 -196.270372) (xy 76.099416 -196.276468) (xy 76.078483 -196.294109)
			(xy 76.032515 -196.323833) (xy 75.982769 -196.346679) (xy 75.930267 -196.362175) (xy 75.876089 -196.370004)
			(xy 75.821347 -196.370004) (xy 75.767169 -196.362175) (xy 75.714667 -196.346679) (xy 75.664921 -196.323833)
			(xy 75.618953 -196.294109) (xy 75.59802 -196.276468) (xy 75.590908 -196.270372) (xy 75.57389 -196.264022)
			(xy 75.488546 -196.264022) (xy 75.471528 -196.270372) (xy 75.464416 -196.276468) (xy 75.443485 -196.294108)
			(xy 75.397512 -196.323821) (xy 75.347765 -196.346657) (xy 75.295263 -196.362148) (xy 75.241087 -196.369975)
			(xy 75.213718 -196.370448) (xy 75.186469 -196.369905) (xy 75.132525 -196.362152) (xy 75.080234 -196.346801)
			(xy 75.03066 -196.324165) (xy 74.984811 -196.294705) (xy 74.943622 -196.259019) (xy 74.90793 -196.217835)
			(xy 74.878463 -196.171991) (xy 74.855819 -196.12242) (xy 74.84046 -196.070131) (xy 74.832699 -196.016189)
			(xy 74.83221 -195.98894) (xy 69.535802 -195.98894) (xy 74.628502 -201.08164) (xy 79.14259 -201.08164)
			(xy 79.143082 -201.054271) (xy 79.150894 -201.000093) (xy 79.166377 -200.94759) (xy 79.189213 -200.897843)
			(xy 79.218932 -200.851875) (xy 79.23657 -200.830942) (xy 79.242666 -200.82383) (xy 79.249016 -200.806812)
			(xy 79.249016 -200.721468) (xy 79.242666 -200.70445) (xy 79.23657 -200.697338) (xy 79.218967 -200.676374)
			(xy 79.189237 -200.630413) (xy 79.166387 -200.580672) (xy 79.150885 -200.528174) (xy 79.143052 -200.473999)
			(xy 79.143048 -200.419261) (xy 79.150873 -200.365085) (xy 79.166365 -200.312584) (xy 79.189208 -200.26284)
			(xy 79.21893 -200.216874) (xy 79.23657 -200.195942) (xy 79.242666 -200.18883) (xy 79.249016 -200.171812)
			(xy 79.249016 -200.086468) (xy 79.242666 -200.06945) (xy 79.23657 -200.062338) (xy 79.218967 -200.041374)
			(xy 79.189237 -199.995413) (xy 79.166387 -199.945672) (xy 79.150885 -199.893174) (xy 79.143052 -199.838999)
			(xy 79.143048 -199.784261) (xy 79.150873 -199.730085) (xy 79.166365 -199.677584) (xy 79.189208 -199.62784)
			(xy 79.21893 -199.581874) (xy 79.23657 -199.560942) (xy 79.242666 -199.55383) (xy 79.249016 -199.536812)
			(xy 79.249016 -199.451468) (xy 79.242666 -199.43445) (xy 79.23657 -199.427338) (xy 79.218967 -199.406374)
			(xy 79.189237 -199.360413) (xy 79.166387 -199.310672) (xy 79.150885 -199.258174) (xy 79.143052 -199.203999)
			(xy 79.143048 -199.149261) (xy 79.150873 -199.095085) (xy 79.166365 -199.042584) (xy 79.189208 -198.99284)
			(xy 79.21893 -198.946874) (xy 79.23657 -198.925942) (xy 79.242666 -198.91883) (xy 79.249016 -198.901812)
			(xy 79.249016 -198.816468) (xy 79.242666 -198.79945) (xy 79.23657 -198.792338) (xy 79.218967 -198.771374)
			(xy 79.189237 -198.725413) (xy 79.166387 -198.675672) (xy 79.150885 -198.623174) (xy 79.143052 -198.568999)
			(xy 79.143048 -198.514261) (xy 79.150873 -198.460085) (xy 79.166365 -198.407584) (xy 79.189208 -198.35784)
			(xy 79.21893 -198.311874) (xy 79.23657 -198.290942) (xy 79.242666 -198.28383) (xy 79.249016 -198.266812)
			(xy 79.249016 -198.181468) (xy 79.242666 -198.16445) (xy 79.23657 -198.157338) (xy 79.218967 -198.136374)
			(xy 79.189237 -198.090413) (xy 79.166387 -198.040672) (xy 79.150885 -197.988174) (xy 79.143052 -197.933999)
			(xy 79.143048 -197.879261) (xy 79.150873 -197.825085) (xy 79.166365 -197.772584) (xy 79.189208 -197.72284)
			(xy 79.21893 -197.676874) (xy 79.23657 -197.655942) (xy 79.242666 -197.64883) (xy 79.249016 -197.631812)
			(xy 79.249016 -197.546468) (xy 79.242666 -197.52945) (xy 79.23657 -197.522338) (xy 79.218967 -197.501374)
			(xy 79.189237 -197.455413) (xy 79.166387 -197.405672) (xy 79.150885 -197.353174) (xy 79.143052 -197.298999)
			(xy 79.143048 -197.244261) (xy 79.150873 -197.190085) (xy 79.166365 -197.137584) (xy 79.189208 -197.08784)
			(xy 79.21893 -197.041874) (xy 79.23657 -197.020942) (xy 79.242666 -197.01383) (xy 79.249016 -196.996812)
			(xy 79.249016 -196.911468) (xy 79.242666 -196.89445) (xy 79.23657 -196.887338) (xy 79.218967 -196.866374)
			(xy 79.189237 -196.820413) (xy 79.166387 -196.770672) (xy 79.150885 -196.718174) (xy 79.143052 -196.663999)
			(xy 79.143048 -196.609261) (xy 79.150873 -196.555085) (xy 79.166365 -196.502584) (xy 79.189208 -196.45284)
			(xy 79.21893 -196.406874) (xy 79.23657 -196.385942) (xy 79.242666 -196.37883) (xy 79.249016 -196.361812)
			(xy 79.249016 -196.276468) (xy 79.242666 -196.25945) (xy 79.23657 -196.252338) (xy 79.218967 -196.231374)
			(xy 79.189237 -196.185413) (xy 79.166387 -196.135672) (xy 79.150885 -196.083174) (xy 79.143052 -196.028999)
			(xy 79.143048 -195.974261) (xy 79.150873 -195.920085) (xy 79.166365 -195.867584) (xy 79.189208 -195.81784)
			(xy 79.21893 -195.771874) (xy 79.23657 -195.750942) (xy 79.242666 -195.74383) (xy 79.249016 -195.726812)
			(xy 79.249016 -195.641468) (xy 79.242666 -195.62445) (xy 79.23657 -195.617338) (xy 79.218931 -195.596406)
			(xy 79.18922 -195.550433) (xy 79.166384 -195.500685) (xy 79.150893 -195.448185) (xy 79.143065 -195.394009)
			(xy 79.14259 -195.36664) (xy 79.143079 -195.338836) (xy 79.151154 -195.283818) (xy 79.167124 -195.230554)
			(xy 79.190651 -195.180169) (xy 79.221239 -195.133729) (xy 79.239364 -195.11264) (xy 79.245714 -195.105528)
			(xy 79.252318 -195.088256) (xy 79.252318 -195.001896) (xy 79.245714 -194.984624) (xy 79.239364 -194.977512)
			(xy 79.221245 -194.956417) (xy 79.190657 -194.90998) (xy 79.16713 -194.859597) (xy 79.151163 -194.806332)
			(xy 79.143093 -194.751315) (xy 79.14259 -194.723512) (xy 79.143066 -194.69626) (xy 79.150822 -194.642309)
			(xy 79.166176 -194.590012) (xy 79.188817 -194.540432) (xy 79.218284 -194.494579) (xy 79.253976 -194.453386)
			(xy 79.295167 -194.417692) (xy 79.341019 -194.388224) (xy 79.390599 -194.365581) (xy 79.442895 -194.350225)
			(xy 79.496846 -194.342467) (xy 79.524098 -194.342004) (xy 79.551468 -194.34247) (xy 79.605647 -194.350288)
			(xy 79.658151 -194.365777) (xy 79.707897 -194.388619) (xy 79.753864 -194.418343) (xy 79.774796 -194.435984)
			(xy 79.781908 -194.44208) (xy 79.798926 -194.44843) (xy 79.88427 -194.44843) (xy 79.901288 -194.44208)
			(xy 79.9084 -194.435984) (xy 79.929333 -194.418343) (xy 79.975301 -194.388619) (xy 80.025047 -194.365773)
			(xy 80.077549 -194.350277) (xy 80.131727 -194.342448) (xy 80.186469 -194.342448) (xy 80.240647 -194.350277)
			(xy 80.293149 -194.365773) (xy 80.342895 -194.388619) (xy 80.388863 -194.418343) (xy 80.409796 -194.435984)
			(xy 80.416908 -194.44208) (xy 80.433926 -194.44843) (xy 80.51927 -194.44843) (xy 80.536288 -194.44208)
			(xy 80.5434 -194.435984) (xy 80.564319 -194.418329) (xy 80.610296 -194.38862) (xy 80.660047 -194.365787)
			(xy 80.71255 -194.3503) (xy 80.766728 -194.342476) (xy 80.794098 -194.342004) (xy 80.821351 -194.342457)
			(xy 80.875303 -194.350214) (xy 80.927602 -194.365571) (xy 80.977183 -194.388214) (xy 81.023037 -194.417683)
			(xy 81.06423 -194.453377) (xy 81.099923 -194.494571) (xy 81.129391 -194.540426) (xy 81.152033 -194.590007)
			(xy 81.167388 -194.642307) (xy 81.175143 -194.696259) (xy 81.175606 -194.723512) (xy 81.175128 -194.750811)
			(xy 81.167355 -194.804852) (xy 81.151955 -194.857233) (xy 81.129243 -194.906883) (xy 81.099683 -194.952786)
			(xy 81.082134 -194.973702) (xy 81.075784 -194.980814) (xy 81.069688 -194.997832) (xy 81.069688 -195.08343)
			(xy 81.076038 -195.100194) (xy 81.082134 -195.107306) (xy 81.099856 -195.128261) (xy 81.129732 -195.174295)
			(xy 81.152697 -195.224138) (xy 81.168275 -195.27676) (xy 81.176145 -195.331072) (xy 81.176622 -195.358512)
			(xy 81.176182 -195.385883) (xy 81.168361 -195.440064) (xy 81.152867 -195.492568) (xy 81.130019 -195.542315)
			(xy 81.100287 -195.58828) (xy 81.082642 -195.60921) (xy 81.076546 -195.616322) (xy 81.070196 -195.63334)
			(xy 81.070196 -195.718684) (xy 81.076546 -195.735702) (xy 81.082642 -195.742814) (xy 81.100296 -195.763737)
			(xy 81.130022 -195.809705) (xy 81.152869 -195.859453) (xy 81.168366 -195.911957) (xy 81.176194 -195.966137)
			(xy 81.176192 -196.020881) (xy 81.168362 -196.075061) (xy 81.152863 -196.127564) (xy 81.130014 -196.17731)
			(xy 81.100285 -196.223278) (xy 81.082642 -196.24421) (xy 81.076546 -196.251322) (xy 81.070196 -196.26834)
			(xy 81.070196 -196.353684) (xy 81.076546 -196.370702) (xy 81.082642 -196.377814) (xy 81.100296 -196.398737)
			(xy 81.130022 -196.444705) (xy 81.152869 -196.494453) (xy 81.168366 -196.546957) (xy 81.176194 -196.601137)
			(xy 81.176192 -196.655881) (xy 81.168362 -196.710061) (xy 81.152863 -196.762564) (xy 81.130014 -196.81231)
			(xy 81.100285 -196.858278) (xy 81.082642 -196.87921) (xy 81.076546 -196.886322) (xy 81.070196 -196.90334)
			(xy 81.070196 -196.988684) (xy 81.076546 -197.005702) (xy 81.082642 -197.012814) (xy 81.100261 -197.033762)
			(xy 81.129975 -197.079731) (xy 81.152814 -197.129475) (xy 81.16831 -197.181971) (xy 81.176145 -197.236144)
			(xy 81.176622 -197.263512) (xy 81.176097 -197.291386) (xy 81.167994 -197.346541) (xy 81.151947 -197.399929)
			(xy 81.1283 -197.450412) (xy 81.097555 -197.496915) (xy 81.07934 -197.51802) (xy 81.073244 -197.524878)
			(xy 81.066386 -197.54215) (xy 81.066386 -197.628764) (xy 81.07299 -197.646036) (xy 81.079086 -197.653148)
			(xy 81.097179 -197.674189) (xy 81.127696 -197.720538) (xy 81.151162 -197.770825) (xy 81.167081 -197.823985)
			(xy 81.175115 -197.878893) (xy 81.175606 -197.90664) (xy 81.175103 -197.934009) (xy 81.167294 -197.988186)
			(xy 81.151813 -198.040689) (xy 81.12898 -198.090436) (xy 81.099263 -198.136405) (xy 81.081626 -198.157338)
			(xy 81.07553 -198.16445) (xy 81.06918 -198.181468) (xy 81.06918 -198.266812) (xy 81.07553 -198.28383)
			(xy 81.081626 -198.290942) (xy 81.099308 -198.311842) (xy 81.129035 -198.357814) (xy 81.15188 -198.407566)
			(xy 81.167376 -198.460073) (xy 81.175202 -198.514257) (xy 81.175197 -198.569003) (xy 81.167363 -198.623186)
			(xy 81.151859 -198.675691) (xy 81.129006 -198.725439) (xy 81.099271 -198.771406) (xy 81.081626 -198.792338)
			(xy 81.07553 -198.79945) (xy 81.06918 -198.816468) (xy 81.06918 -198.901812) (xy 81.07553 -198.91883)
			(xy 81.081626 -198.925942) (xy 81.099308 -198.946842) (xy 81.129035 -198.992814) (xy 81.15188 -199.042566)
			(xy 81.167376 -199.095073) (xy 81.175202 -199.149257) (xy 81.175197 -199.204003) (xy 81.167363 -199.258186)
			(xy 81.151859 -199.310691) (xy 81.129006 -199.360439) (xy 81.099271 -199.406406) (xy 81.081626 -199.427338)
			(xy 81.07553 -199.43445) (xy 81.06918 -199.451468) (xy 81.06918 -199.536812) (xy 81.07553 -199.55383)
			(xy 81.081626 -199.560942) (xy 81.099308 -199.581842) (xy 81.129035 -199.627814) (xy 81.15188 -199.677566)
			(xy 81.167376 -199.730073) (xy 81.175202 -199.784257) (xy 81.175197 -199.839003) (xy 81.167363 -199.893186)
			(xy 81.151859 -199.945691) (xy 81.129006 -199.995439) (xy 81.099271 -200.041406) (xy 81.081626 -200.062338)
			(xy 81.07553 -200.06945) (xy 81.06918 -200.086468) (xy 81.06918 -200.171812) (xy 81.07553 -200.18883)
			(xy 81.081626 -200.195942) (xy 81.099308 -200.216842) (xy 81.129035 -200.262814) (xy 81.15188 -200.312566)
			(xy 81.167376 -200.365073) (xy 81.175202 -200.419257) (xy 81.175197 -200.474003) (xy 81.167363 -200.528186)
			(xy 81.151859 -200.580691) (xy 81.129006 -200.630439) (xy 81.099271 -200.676406) (xy 81.081626 -200.697338)
			(xy 81.07553 -200.70445) (xy 81.06918 -200.721468) (xy 81.06918 -200.806812) (xy 81.07553 -200.82383)
			(xy 81.081626 -200.830942) (xy 81.099255 -200.851882) (xy 81.128968 -200.897853) (xy 81.151805 -200.947598)
			(xy 81.167299 -201.000097) (xy 81.17513 -201.054271) (xy 81.175606 -201.08164) (xy 83.15579 -201.08164)
			(xy 83.156282 -201.054271) (xy 83.164094 -201.000093) (xy 83.179577 -200.94759) (xy 83.202413 -200.897843)
			(xy 83.232132 -200.851875) (xy 83.24977 -200.830942) (xy 83.255866 -200.82383) (xy 83.262216 -200.806812)
			(xy 83.262216 -200.721468) (xy 83.255866 -200.70445) (xy 83.24977 -200.697338) (xy 83.232167 -200.676374)
			(xy 83.202437 -200.630413) (xy 83.179587 -200.580672) (xy 83.164085 -200.528174) (xy 83.156252 -200.473999)
			(xy 83.156248 -200.419261) (xy 83.164073 -200.365085) (xy 83.179565 -200.312584) (xy 83.202408 -200.26284)
			(xy 83.23213 -200.216874) (xy 83.24977 -200.195942) (xy 83.255866 -200.18883) (xy 83.262216 -200.171812)
			(xy 83.262216 -200.086468) (xy 83.255866 -200.06945) (xy 83.24977 -200.062338) (xy 83.232167 -200.041374)
			(xy 83.202437 -199.995413) (xy 83.179587 -199.945672) (xy 83.164085 -199.893174) (xy 83.156252 -199.838999)
			(xy 83.156248 -199.784261) (xy 83.164073 -199.730085) (xy 83.179565 -199.677584) (xy 83.202408 -199.62784)
			(xy 83.23213 -199.581874) (xy 83.24977 -199.560942) (xy 83.255866 -199.55383) (xy 83.262216 -199.536812)
			(xy 83.262216 -199.451468) (xy 83.255866 -199.43445) (xy 83.24977 -199.427338) (xy 83.232167 -199.406374)
			(xy 83.202437 -199.360413) (xy 83.179587 -199.310672) (xy 83.164085 -199.258174) (xy 83.156252 -199.203999)
			(xy 83.156248 -199.149261) (xy 83.164073 -199.095085) (xy 83.179565 -199.042584) (xy 83.202408 -198.99284)
			(xy 83.23213 -198.946874) (xy 83.24977 -198.925942) (xy 83.255866 -198.91883) (xy 83.262216 -198.901812)
			(xy 83.262216 -198.816468) (xy 83.255866 -198.79945) (xy 83.24977 -198.792338) (xy 83.232167 -198.771374)
			(xy 83.202437 -198.725413) (xy 83.179587 -198.675672) (xy 83.164085 -198.623174) (xy 83.156252 -198.568999)
			(xy 83.156248 -198.514261) (xy 83.164073 -198.460085) (xy 83.179565 -198.407584) (xy 83.202408 -198.35784)
			(xy 83.23213 -198.311874) (xy 83.24977 -198.290942) (xy 83.255866 -198.28383) (xy 83.262216 -198.266812)
			(xy 83.262216 -198.181468) (xy 83.255866 -198.16445) (xy 83.24977 -198.157338) (xy 83.232131 -198.136406)
			(xy 83.20242 -198.090433) (xy 83.179584 -198.040685) (xy 83.164093 -197.988185) (xy 83.156265 -197.934009)
			(xy 83.15579 -197.90664) (xy 83.156284 -197.878765) (xy 83.164394 -197.823608) (xy 83.180447 -197.77022)
			(xy 83.204102 -197.719737) (xy 83.234854 -197.673236) (xy 83.253072 -197.652132) (xy 83.259168 -197.645274)
			(xy 83.266026 -197.628002) (xy 83.266026 -197.541388) (xy 83.259422 -197.524116) (xy 83.253326 -197.517004)
			(xy 83.235259 -197.495941) (xy 83.204738 -197.449599) (xy 83.181267 -197.399317) (xy 83.165342 -197.346161)
			(xy 83.157301 -197.291257) (xy 83.156806 -197.263512) (xy 83.157278 -197.236142) (xy 83.165094 -197.181963)
			(xy 83.180582 -197.12946) (xy 83.203422 -197.079713) (xy 83.233145 -197.033746) (xy 83.250786 -197.012814)
			(xy 83.256882 -197.005702) (xy 83.263232 -196.988684) (xy 83.263232 -196.90334) (xy 83.256882 -196.886322)
			(xy 83.250786 -196.87921) (xy 83.233159 -196.858267) (xy 83.203437 -196.8123) (xy 83.180593 -196.762555)
			(xy 83.165098 -196.710055) (xy 83.157269 -196.655879) (xy 83.157267 -196.601139) (xy 83.165094 -196.546963)
			(xy 83.180587 -196.494462) (xy 83.203428 -196.444716) (xy 83.233148 -196.398748) (xy 83.250786 -196.377814)
			(xy 83.256882 -196.370702) (xy 83.263232 -196.353684) (xy 83.263232 -196.26834) (xy 83.256882 -196.251322)
			(xy 83.250786 -196.24421) (xy 83.233159 -196.223267) (xy 83.203437 -196.1773) (xy 83.180593 -196.127555)
			(xy 83.165098 -196.075055) (xy 83.157269 -196.020879) (xy 83.157267 -195.966139) (xy 83.165094 -195.911963)
			(xy 83.180587 -195.859462) (xy 83.203428 -195.809716) (xy 83.233148 -195.763748) (xy 83.250786 -195.742814)
			(xy 83.256882 -195.735702) (xy 83.263232 -195.718684) (xy 83.263232 -195.63334) (xy 83.256882 -195.616322)
			(xy 83.250786 -195.60921) (xy 83.233136 -195.588287) (xy 83.203426 -195.542311) (xy 83.180593 -195.492562)
			(xy 83.165104 -195.440059) (xy 83.157279 -195.385882) (xy 83.156806 -195.358512) (xy 83.157296 -195.331213)
			(xy 83.165065 -195.277172) (xy 83.180463 -195.224792) (xy 83.203172 -195.175142) (xy 83.23273 -195.129238)
			(xy 83.250278 -195.108322) (xy 83.256628 -195.10121) (xy 83.262724 -195.084192) (xy 83.262724 -194.998594)
			(xy 83.256374 -194.98183) (xy 83.250278 -194.974718) (xy 83.232569 -194.953753) (xy 83.202691 -194.907721)
			(xy 83.179723 -194.857881) (xy 83.164142 -194.805261) (xy 83.156269 -194.750951) (xy 83.15579 -194.723512)
			(xy 83.156266 -194.69626) (xy 83.164022 -194.642309) (xy 83.179376 -194.590012) (xy 83.202017 -194.540432)
			(xy 83.231484 -194.494579) (xy 83.267176 -194.453386) (xy 83.308367 -194.417692) (xy 83.354219 -194.388224)
			(xy 83.403799 -194.365581) (xy 83.456095 -194.350225) (xy 83.510046 -194.342467) (xy 83.537298 -194.342004)
			(xy 83.564668 -194.34247) (xy 83.618847 -194.350288) (xy 83.671351 -194.365777) (xy 83.721097 -194.388619)
			(xy 83.767064 -194.418343) (xy 83.787996 -194.435984) (xy 83.795108 -194.44208) (xy 83.812126 -194.44843)
			(xy 83.89747 -194.44843) (xy 83.914488 -194.44208) (xy 83.9216 -194.435984) (xy 83.942519 -194.418329)
			(xy 83.988496 -194.38862) (xy 84.038247 -194.365787) (xy 84.09075 -194.3503) (xy 84.144928 -194.342476)
			(xy 84.172298 -194.342004) (xy 84.199246 -194.342435) (xy 84.252609 -194.349992) (xy 84.304373 -194.364997)
			(xy 84.353505 -194.387151) (xy 84.376514 -194.401186) (xy 84.388198 -194.408806) (xy 84.415884 -194.409568)
			(xy 84.506054 -194.359784) (xy 84.513786 -194.355077) (xy 84.525564 -194.341344) (xy 84.531848 -194.324379)
			(xy 84.532216 -194.315334) (xy 84.532216 -181.122574) (xy 84.532649 -181.097584) (xy 84.54048 -181.048222)
			(xy 84.555946 -181.000695) (xy 84.578665 -180.956177) (xy 84.608075 -180.915767) (xy 84.625434 -180.897784)
			(xy 85.111844 -180.411374) (xy 85.118736 -180.403718) (xy 85.12642 -180.384631) (xy 85.126032 -180.36406)
			(xy 85.122258 -180.354478) (xy 85.076538 -180.253132) (xy 85.049614 -180.23713) (xy 85.033612 -180.238146)
			(xy 85.009228 -180.238908) (xy 84.981973 -180.238475) (xy 84.928016 -180.230721) (xy 84.875713 -180.215367)
			(xy 84.826127 -180.192726) (xy 84.780267 -180.163258) (xy 84.739069 -180.127564) (xy 84.70337 -180.08637)
			(xy 84.673896 -180.040514) (xy 84.651249 -179.990931) (xy 84.635889 -179.938629) (xy 84.628128 -179.884674)
			(xy 84.628126 -179.830163) (xy 84.635881 -179.776207) (xy 84.651236 -179.723904) (xy 84.673878 -179.674318)
			(xy 84.703347 -179.62846) (xy 84.739042 -179.587262) (xy 84.780238 -179.551564) (xy 84.826094 -179.522092)
			(xy 84.875678 -179.499446) (xy 84.92798 -179.484087) (xy 84.981935 -179.476328) (xy 85.036446 -179.476326)
			(xy 85.090402 -179.484083) (xy 85.142705 -179.499439) (xy 85.19229 -179.522083) (xy 85.238148 -179.551553)
			(xy 85.279344 -179.587249) (xy 85.315042 -179.628445) (xy 85.344513 -179.674302) (xy 85.367158 -179.723886)
			(xy 85.382515 -179.776189) (xy 85.390273 -179.830145) (xy 85.390736 -179.8574) (xy 85.390133 -179.888532)
			(xy 85.380061 -179.949974) (xy 85.360122 -180.008957) (xy 85.346032 -180.036724) (xy 85.338158 -180.051456)
			(xy 85.342984 -180.08473) (xy 85.354922 -180.096414) (xy 85.362356 -180.10313) (xy 85.380856 -180.110766)
			(xy 85.40087 -180.110766) (xy 85.41937 -180.10313) (xy 85.426804 -180.096414) (xy 85.546946 -179.976272)
			(xy 85.553704 -179.968896) (xy 85.561403 -179.95045) (xy 85.561932 -179.940458) (xy 85.561932 -179.406042)
			(xy 85.561489 -179.396035) (xy 85.553758 -179.377572) (xy 85.546946 -179.370228) (xy 85.51799 -179.341272)
			(xy 85.506052 -179.334668) (xy 85.499194 -179.33289) (xy 85.471791 -179.325794) (xy 85.419309 -179.304582)
			(xy 85.370539 -179.275848) (xy 85.32655 -179.240222) (xy 85.288309 -179.198486) (xy 85.256656 -179.151558)
			(xy 85.232285 -179.100467) (xy 85.215731 -179.046336) (xy 85.207359 -178.990353) (xy 85.20684 -178.96205)
			(xy 85.207302 -178.934796) (xy 85.215053 -178.880843) (xy 85.230405 -178.828542) (xy 85.253046 -178.778959)
			(xy 85.282513 -178.733103) (xy 85.318207 -178.691909) (xy 85.359401 -178.656214) (xy 85.405257 -178.626747)
			(xy 85.45484 -178.604106) (xy 85.507141 -178.588754) (xy 85.561094 -178.581002) (xy 85.588348 -178.580542)
			(xy 85.616655 -178.581028) (xy 85.672649 -178.58938) (xy 85.726792 -178.605921) (xy 85.777893 -178.630288)
			(xy 85.824828 -178.661946) (xy 85.866564 -178.700197) (xy 85.902184 -178.744201) (xy 85.930904 -178.792989)
			(xy 85.952091 -178.845489) (xy 85.959188 -178.872896) (xy 85.960966 -178.879754) (xy 85.96757 -178.891692)
			(xy 86.104476 -179.028598) (xy 86.121802 -179.046597) (xy 86.151152 -179.087021) (xy 86.173811 -179.131542)
			(xy 86.189219 -179.179063) (xy 86.196997 -179.22841) (xy 86.19744 -179.253388) (xy 86.19744 -180.093112)
			(xy 86.196988 -180.118088) (xy 86.189191 -180.167427) (xy 86.173774 -180.21494) (xy 86.151118 -180.259458)
			(xy 86.121779 -180.299885) (xy 86.104476 -180.317902) (xy 85.888068 -180.534056) (xy 85.881261 -180.541543)
			(xy 85.873623 -180.560261) (xy 85.873811 -180.580476) (xy 85.8774 -180.589936) (xy 85.88587 -180.610002)
			(xy 86.589362 -180.610002) (xy 86.589807 -180.582426) (xy 86.597761 -180.527852) (xy 86.613489 -180.474991)
			(xy 86.636662 -180.424944) (xy 86.6668 -180.378755) (xy 86.703272 -180.337386) (xy 86.723982 -180.319172)
			(xy 86.732122 -180.311589) (xy 86.741461 -180.291422) (xy 86.742016 -180.28031) (xy 86.742016 -180.203094)
			(xy 86.741494 -180.191978) (xy 86.732126 -180.171818) (xy 86.723982 -180.164232) (xy 86.70328 -180.146013)
			(xy 86.666818 -180.104642) (xy 86.636692 -180.058452) (xy 86.613531 -180.008405) (xy 86.597817 -179.955546)
			(xy 86.589877 -179.900974) (xy 86.589877 -179.845828) (xy 86.597816 -179.791257) (xy 86.61353 -179.738397)
			(xy 86.636691 -179.688351) (xy 86.666816 -179.64216) (xy 86.703278 -179.600788) (xy 86.723982 -179.582572)
			(xy 86.732122 -179.574989) (xy 86.741461 -179.554822) (xy 86.742016 -179.54371) (xy 86.742016 -179.466494)
			(xy 86.741494 -179.455378) (xy 86.732126 -179.435218) (xy 86.723982 -179.427632) (xy 86.70328 -179.409412)
			(xy 86.666809 -179.368044) (xy 86.636677 -179.321856) (xy 86.613509 -179.27181) (xy 86.597791 -179.218949)
			(xy 86.589849 -179.164376) (xy 86.589362 -179.136802) (xy 86.58988 -179.109552) (xy 86.597635 -179.055607)
			(xy 86.612988 -179.003315) (xy 86.635627 -178.95374) (xy 86.66509 -178.907891) (xy 86.700778 -178.866701)
			(xy 86.741965 -178.83101) (xy 86.787811 -178.801542) (xy 86.837385 -178.7789) (xy 86.889676 -178.763542)
			(xy 86.94362 -178.755782) (xy 86.97087 -178.755294) (xy 86.998724 -178.755849) (xy 87.053838 -178.763968)
			(xy 87.107187 -178.780009) (xy 87.15764 -178.803632) (xy 87.204124 -178.834335) (xy 87.245654 -178.871466)
			(xy 87.281348 -178.914238) (xy 87.310448 -178.961742) (xy 87.332337 -179.01297) (xy 87.339932 -179.039774)
			(xy 87.342218 -179.048664) (xy 87.352886 -179.063904) (xy 87.424768 -179.111656) (xy 87.442802 -179.11572)
			(xy 87.451946 -179.11445) (xy 87.464962 -179.112778) (xy 87.491147 -179.111) (xy 87.50427 -179.110894)
			(xy 87.518419 -179.110991) (xy 87.546642 -179.113023) (xy 87.560658 -179.114958) (xy 87.570818 -179.116482)
			(xy 87.590376 -179.111656) (xy 87.664798 -179.055776) (xy 87.674958 -179.03825) (xy 87.676228 -179.02809)
			(xy 87.680396 -179.00095) (xy 87.695362 -178.948124) (xy 87.717745 -178.897989) (xy 87.747084 -178.851581)
			(xy 87.782772 -178.809856) (xy 87.824072 -178.773679) (xy 87.870132 -178.743795) (xy 87.92 -178.720823)
			(xy 87.972645 -178.705236) (xy 88.026982 -178.697356) (xy 88.054434 -178.696874) (xy 88.081685 -178.697346)
			(xy 88.135633 -178.705107) (xy 88.187926 -178.720465) (xy 88.237503 -178.743109) (xy 88.283352 -178.772577)
			(xy 88.324541 -178.80827) (xy 88.360232 -178.849461) (xy 88.389699 -178.895311) (xy 88.41234 -178.944889)
			(xy 88.427697 -178.997183) (xy 88.435455 -179.051131) (xy 88.435942 -179.078382) (xy 88.435484 -179.105957)
			(xy 88.427533 -179.160531) (xy 88.411808 -179.213392) (xy 88.388636 -179.263438) (xy 88.358501 -179.309628)
			(xy 88.322031 -179.350997) (xy 88.301322 -179.369212) (xy 88.29319 -179.376802) (xy 88.283846 -179.396963)
			(xy 88.283288 -179.408074) (xy 88.283288 -179.48529) (xy 88.283817 -179.496405) (xy 88.29318 -179.516565)
			(xy 88.301322 -179.524152) (xy 88.322018 -179.54238) (xy 88.358488 -179.583746) (xy 88.388622 -179.629932)
			(xy 88.41179 -179.679977) (xy 88.42751 -179.732836) (xy 88.435454 -179.787408) (xy 88.435942 -179.814982)
			(xy 88.435405 -179.842231) (xy 88.427652 -179.896175) (xy 88.412301 -179.948467) (xy 88.389664 -179.998042)
			(xy 88.360203 -180.043891) (xy 88.324517 -180.08508) (xy 88.283332 -180.120772) (xy 88.237487 -180.150239)
			(xy 88.187916 -180.172883) (xy 88.135626 -180.188241) (xy 88.081683 -180.196001) (xy 88.054434 -180.19649)
			(xy 88.020144 -180.194966) (xy 88.009984 -180.19395) (xy 87.99068 -180.200046) (xy 87.920068 -180.259228)
			(xy 87.91067 -180.277262) (xy 87.909654 -180.287422) (xy 87.906643 -180.315588) (xy 87.893474 -180.370676)
			(xy 87.872301 -180.423211) (xy 87.84359 -180.472035) (xy 87.807973 -180.516075) (xy 87.766233 -180.554363)
			(xy 87.719288 -180.586054) (xy 87.668172 -180.610452) (xy 87.614008 -180.627021) (xy 87.55799 -180.635395)
			(xy 87.52967 -180.63591) (xy 87.511651 -180.635689) (xy 87.475776 -180.632255) (xy 87.458042 -180.629052)
			(xy 87.448644 -180.627274) (xy 87.429594 -180.631084) (xy 87.35441 -180.678836) (xy 87.34298 -180.694584)
			(xy 87.340694 -180.703982) (xy 87.333311 -180.73103) (xy 87.311678 -180.782756) (xy 87.28271 -180.83076)
			(xy 87.247032 -180.87401) (xy 87.205411 -180.911576) (xy 87.158743 -180.94265) (xy 87.10803 -180.966562)
			(xy 87.054366 -180.982799) (xy 86.998903 -180.99101) (xy 86.97087 -180.99151) (xy 86.943618 -180.99105)
			(xy 86.88967 -180.98329) (xy 86.837374 -180.967931) (xy 86.787797 -180.945286) (xy 86.741947 -180.915817)
			(xy 86.700757 -180.880123) (xy 86.665066 -180.83893) (xy 86.6356 -180.793078) (xy 86.612959 -180.743499)
			(xy 86.597604 -180.691203) (xy 86.589848 -180.637254) (xy 86.589362 -180.610002) (xy 85.88587 -180.610002)
			(xy 85.920072 -180.691028) (xy 85.94598 -180.707792) (xy 85.961728 -180.707538) (xy 85.96757 -180.707538)
			(xy 85.994824 -180.707983) (xy 86.048778 -180.715737) (xy 86.101079 -180.731092) (xy 86.150662 -180.753734)
			(xy 86.196518 -180.783204) (xy 86.237712 -180.818899) (xy 86.273406 -180.860095) (xy 86.302873 -180.905952)
			(xy 86.325514 -180.955536) (xy 86.340866 -181.007837) (xy 86.348618 -181.061792) (xy 86.349078 -181.089046)
			(xy 86.348596 -181.116957) (xy 86.340456 -181.172183) (xy 86.324357 -181.225633) (xy 86.300643 -181.276167)
			(xy 86.269818 -181.322707) (xy 86.251542 -181.343808) (xy 86.245192 -181.35092) (xy 86.238588 -181.368192)
			(xy 86.238588 -181.455314) (xy 86.245192 -181.472586) (xy 86.251542 -181.479698) (xy 86.2698 -181.500814)
			(xy 86.300629 -181.547349) (xy 86.324347 -181.597879) (xy 86.340449 -181.651327) (xy 86.348589 -181.70655)
			(xy 86.349078 -181.73446) (xy 86.348592 -181.761711) (xy 86.340836 -181.815659) (xy 86.325481 -181.867954)
			(xy 86.302839 -181.917531) (xy 86.273373 -181.963381) (xy 86.237682 -182.004572) (xy 86.196491 -182.040263)
			(xy 86.150641 -182.069729) (xy 86.101064 -182.092371) (xy 86.048769 -182.107726) (xy 85.994821 -182.115482)
			(xy 85.940319 -182.115482) (xy 85.886371 -182.107726) (xy 85.834076 -182.092371) (xy 85.784499 -182.069729)
			(xy 85.738649 -182.040263) (xy 85.697458 -182.004572) (xy 85.661767 -181.963381) (xy 85.632301 -181.917531)
			(xy 85.609659 -181.867954) (xy 85.594304 -181.815659) (xy 85.586548 -181.761711) (xy 85.586062 -181.73446)
			(xy 85.586538 -181.706549) (xy 85.594677 -181.651322) (xy 85.610777 -181.597872) (xy 85.634494 -181.547337)
			(xy 85.66532 -181.500798) (xy 85.683598 -181.479698) (xy 85.689948 -181.472586) (xy 85.696552 -181.455314)
			(xy 85.696552 -181.368192) (xy 85.689948 -181.35092) (xy 85.683598 -181.343808) (xy 85.665302 -181.322723)
			(xy 85.634477 -181.276181) (xy 85.610765 -181.225642) (xy 85.594673 -181.172188) (xy 85.586544 -181.116958)
			(xy 85.586062 -181.089046) (xy 85.586062 -181.083204) (xy 85.586316 -181.067456) (xy 85.569552 -181.041548)
			(xy 85.46846 -180.998876) (xy 85.458986 -180.995337) (xy 85.438782 -180.995143) (xy 85.420061 -181.002741)
			(xy 85.41258 -181.009544) (xy 85.182964 -181.239414) (xy 85.176313 -181.246847) (xy 85.16872 -181.265267)
			(xy 85.168232 -181.275228) (xy 85.168232 -182.13324) (xy 88.110822 -182.13324) (xy 88.111308 -182.105666)
			(xy 88.119255 -182.051094) (xy 88.134976 -181.998234) (xy 88.158142 -181.948188) (xy 88.188271 -181.901998)
			(xy 88.224736 -181.860626) (xy 88.245442 -181.84241) (xy 88.253558 -181.834806) (xy 88.262912 -181.814655)
			(xy 88.263476 -181.803548) (xy 88.263476 -181.726332) (xy 88.262914 -181.715221) (xy 88.253572 -181.695062)
			(xy 88.245442 -181.68747) (xy 88.224722 -181.669269) (xy 88.18825 -181.627899) (xy 88.158118 -181.581707)
			(xy 88.134954 -181.531657) (xy 88.11924 -181.478792) (xy 88.111305 -181.424215) (xy 88.110822 -181.39664)
			(xy 88.111224 -181.36959) (xy 88.118875 -181.316034) (xy 88.134013 -181.264095) (xy 88.156336 -181.214816)
			(xy 88.185396 -181.169184) (xy 88.220611 -181.128114) (xy 88.261273 -181.09243) (xy 88.306569 -181.062848)
			(xy 88.355588 -181.03996) (xy 88.381332 -181.031642) (xy 88.392762 -181.028086) (xy 88.40978 -181.012338)
			(xy 88.446864 -180.914802) (xy 88.444578 -180.891688) (xy 88.438482 -180.881528) (xy 88.425555 -180.859512)
			(xy 88.405154 -180.812712) (xy 88.391321 -180.763568) (xy 88.384314 -180.712998) (xy 88.383872 -180.687472)
			(xy 88.384331 -180.660856) (xy 88.39191 -180.608165) (xy 88.40691 -180.557089) (xy 88.429026 -180.508668)
			(xy 88.457808 -180.463886) (xy 88.492669 -180.423657) (xy 88.532901 -180.388797) (xy 88.577683 -180.360018)
			(xy 88.626106 -180.337904) (xy 88.677183 -180.322906) (xy 88.729874 -180.315329) (xy 88.75649 -180.314854)
			(xy 88.782911 -180.315328) (xy 88.835225 -180.322776) (xy 88.885963 -180.337538) (xy 88.934108 -180.359318)
			(xy 88.978694 -180.387679) (xy 88.99906 -180.404516) (xy 89.005918 -180.410612) (xy 89.022936 -180.416708)
			(xy 89.107264 -180.416708) (xy 89.124282 -180.410612) (xy 89.13114 -180.404516) (xy 89.151506 -180.387677)
			(xy 89.196092 -180.359312) (xy 89.244236 -180.337525) (xy 89.294973 -180.322754) (xy 89.347288 -180.315294)
			(xy 89.400132 -180.315294) (xy 89.452447 -180.322754) (xy 89.503184 -180.337525) (xy 89.551328 -180.359312)
			(xy 89.595914 -180.387677) (xy 89.61628 -180.404516) (xy 89.623138 -180.410612) (xy 89.640156 -180.416708)
			(xy 89.724484 -180.416708) (xy 89.741502 -180.410612) (xy 89.74836 -180.404516) (xy 89.768742 -180.387699)
			(xy 89.813327 -180.35934) (xy 89.861468 -180.337557) (xy 89.912201 -180.322784) (xy 89.96451 -180.315318)
			(xy 89.99093 -180.314854) (xy 90.018811 -180.315433) (xy 90.07395 -180.323748) (xy 90.127235 -180.340188)
			(xy 90.177474 -180.364385) (xy 90.223545 -180.3958) (xy 90.264421 -180.43373) (xy 90.299186 -180.477328)
			(xy 90.327066 -180.52562) (xy 90.347438 -180.577529) (xy 90.359846 -180.631893) (xy 90.364013 -180.6875)
			(xy 90.359846 -180.743107) (xy 90.347438 -180.797471) (xy 90.327066 -180.84938) (xy 90.299186 -180.897672)
			(xy 90.264421 -180.94127) (xy 90.223545 -180.9792) (xy 90.177474 -181.010615) (xy 90.127235 -181.034812)
			(xy 90.07395 -181.051252) (xy 90.018811 -181.059567) (xy 89.99093 -181.06009) (xy 89.964509 -181.059617)
			(xy 89.912194 -181.052171) (xy 89.861455 -181.03741) (xy 89.813311 -181.015629) (xy 89.768725 -180.987266)
			(xy 89.74836 -180.970428) (xy 89.741502 -180.964332) (xy 89.724484 -180.958236) (xy 89.640156 -180.958236)
			(xy 89.623138 -180.964332) (xy 89.61628 -180.970428) (xy 89.595914 -180.987267) (xy 89.551328 -181.015632)
			(xy 89.503184 -181.037419) (xy 89.452447 -181.05219) (xy 89.400132 -181.05965) (xy 89.347288 -181.05965)
			(xy 89.294973 -181.05219) (xy 89.244236 -181.037419) (xy 89.196092 -181.015632) (xy 89.151506 -180.987267)
			(xy 89.13114 -180.970428) (xy 89.124282 -180.964332) (xy 89.107264 -180.958236) (xy 89.022936 -180.958236)
			(xy 89.005918 -180.964332) (xy 88.99906 -180.970428) (xy 88.979951 -180.986226) (xy 88.938339 -181.013183)
			(xy 88.893521 -181.034385) (xy 88.870028 -181.04231) (xy 88.858598 -181.04612) (xy 88.841834 -181.062122)
			(xy 88.806274 -181.159912) (xy 88.808814 -181.18328) (xy 88.815164 -181.193186) (xy 88.829089 -181.216128)
			(xy 88.851049 -181.265097) (xy 88.865918 -181.316663) (xy 88.873403 -181.369806) (xy 88.873838 -181.39664)
			(xy 88.873353 -181.424214) (xy 88.865407 -181.478787) (xy 88.849688 -181.531647) (xy 88.826521 -181.581694)
			(xy 88.796391 -181.627884) (xy 88.759925 -181.669255) (xy 88.739218 -181.68747) (xy 88.731105 -181.695076)
			(xy 88.721751 -181.715225) (xy 88.721184 -181.726332) (xy 88.721184 -181.803548) (xy 88.721738 -181.81466)
			(xy 88.731084 -181.834821) (xy 88.739218 -181.84241) (xy 88.759941 -181.860608) (xy 88.796409 -181.90198)
			(xy 88.82654 -181.948173) (xy 88.849703 -181.998223) (xy 88.865417 -182.051088) (xy 88.873354 -182.105665)
			(xy 88.873838 -182.13324) (xy 88.873352 -182.160491) (xy 88.865596 -182.214439) (xy 88.850241 -182.266734)
			(xy 88.827599 -182.316311) (xy 88.798133 -182.362161) (xy 88.762442 -182.403352) (xy 88.721251 -182.439043)
			(xy 88.675401 -182.468509) (xy 88.625824 -182.491151) (xy 88.573529 -182.506506) (xy 88.519581 -182.514262)
			(xy 88.465079 -182.514262) (xy 88.411131 -182.506506) (xy 88.358836 -182.491151) (xy 88.309259 -182.468509)
			(xy 88.263409 -182.439043) (xy 88.222218 -182.403352) (xy 88.186527 -182.362161) (xy 88.157061 -182.316311)
			(xy 88.134419 -182.266734) (xy 88.119064 -182.214439) (xy 88.111308 -182.160491) (xy 88.110822 -182.13324)
			(xy 85.168232 -182.13324) (xy 85.168232 -194.599306) (xy 85.170518 -194.606926) (xy 85.179059 -194.635313)
			(xy 85.188246 -194.693873) (xy 85.188806 -194.723512) (xy 85.188319 -194.751056) (xy 85.180363 -194.805567)
			(xy 85.164648 -194.858366) (xy 85.141501 -194.908355) (xy 85.111404 -194.954495) (xy 85.093556 -194.97548)
			(xy 85.08746 -194.982592) (xy 85.080856 -194.999864) (xy 85.08111 -195.085716) (xy 85.087714 -195.103242)
			(xy 85.09381 -195.1101) (xy 85.111797 -195.131137) (xy 85.142146 -195.177423) (xy 85.165485 -195.22761)
			(xy 85.181323 -195.280644) (xy 85.189327 -195.33541) (xy 85.189822 -195.363084) (xy 85.189366 -195.390455)
			(xy 85.181548 -195.444635) (xy 85.166058 -195.497139) (xy 85.143214 -195.546886) (xy 85.113485 -195.592851)
			(xy 85.095842 -195.613782) (xy 85.089746 -195.620894) (xy 85.083396 -195.637912) (xy 85.083396 -195.723256)
			(xy 85.089746 -195.740274) (xy 85.095842 -195.747386) (xy 85.113468 -195.768331) (xy 85.143196 -195.814296)
			(xy 85.166044 -195.86404) (xy 85.181543 -195.91654) (xy 85.189374 -195.970718) (xy 85.189376 -196.025458)
			(xy 85.181548 -196.079636) (xy 85.166053 -196.132138) (xy 85.143208 -196.181883) (xy 85.113483 -196.22785)
			(xy 85.095842 -196.248782) (xy 85.089746 -196.255894) (xy 85.083396 -196.272912) (xy 85.083396 -196.358256)
			(xy 85.089746 -196.375274) (xy 85.095842 -196.382386) (xy 85.113468 -196.403331) (xy 85.143196 -196.449296)
			(xy 85.166044 -196.49904) (xy 85.181543 -196.55154) (xy 85.189374 -196.605718) (xy 85.189376 -196.660458)
			(xy 85.181548 -196.714636) (xy 85.166053 -196.767138) (xy 85.143208 -196.816883) (xy 85.113483 -196.86285)
			(xy 85.095842 -196.883782) (xy 85.089746 -196.890894) (xy 85.083396 -196.907912) (xy 85.083396 -196.993256)
			(xy 85.089746 -197.010274) (xy 85.095842 -197.017386) (xy 85.113495 -197.038307) (xy 85.143203 -197.084283)
			(xy 85.166036 -197.134034) (xy 85.181524 -197.186537) (xy 85.18935 -197.240714) (xy 85.189822 -197.268084)
			(xy 85.189372 -197.295689) (xy 85.181403 -197.350321) (xy 85.165643 -197.403235) (xy 85.142422 -197.453324)
			(xy 85.112224 -197.499544) (xy 85.094318 -197.52056) (xy 85.087968 -197.527672) (xy 85.081618 -197.544944)
			(xy 85.081364 -197.630542) (xy 85.087968 -197.648068) (xy 85.094064 -197.654926) (xy 85.111846 -197.675907)
			(xy 85.1418 -197.722032) (xy 85.164824 -197.771978) (xy 85.180441 -197.824712) (xy 85.188329 -197.879141)
			(xy 85.188806 -197.90664) (xy 85.188303 -197.934009) (xy 85.180494 -197.988186) (xy 85.165013 -198.040689)
			(xy 85.14218 -198.090436) (xy 85.112463 -198.136405) (xy 85.094826 -198.157338) (xy 85.08873 -198.16445)
			(xy 85.08238 -198.181468) (xy 85.08238 -198.266812) (xy 85.08873 -198.28383) (xy 85.094826 -198.290942)
			(xy 85.112508 -198.311842) (xy 85.142235 -198.357814) (xy 85.16508 -198.407566) (xy 85.180576 -198.460073)
			(xy 85.188402 -198.514257) (xy 85.188397 -198.569003) (xy 85.180563 -198.623186) (xy 85.165059 -198.675691)
			(xy 85.142206 -198.725439) (xy 85.112471 -198.771406) (xy 85.094826 -198.792338) (xy 85.08873 -198.79945)
			(xy 85.08238 -198.816468) (xy 85.08238 -198.901812) (xy 85.08873 -198.91883) (xy 85.094826 -198.925942)
			(xy 85.112508 -198.946842) (xy 85.142235 -198.992814) (xy 85.16508 -199.042566) (xy 85.180576 -199.095073)
			(xy 85.188402 -199.149257) (xy 85.188397 -199.204003) (xy 85.180563 -199.258186) (xy 85.165059 -199.310691)
			(xy 85.142206 -199.360439) (xy 85.112471 -199.406406) (xy 85.094826 -199.427338) (xy 85.08873 -199.43445)
			(xy 85.08238 -199.451468) (xy 85.08238 -199.536812) (xy 85.08873 -199.55383) (xy 85.094826 -199.560942)
			(xy 85.112508 -199.581842) (xy 85.142235 -199.627814) (xy 85.16508 -199.677566) (xy 85.180576 -199.730073)
			(xy 85.188402 -199.784257) (xy 85.188397 -199.839003) (xy 85.180563 -199.893186) (xy 85.165059 -199.945691)
			(xy 85.142206 -199.995439) (xy 85.112471 -200.041406) (xy 85.094826 -200.062338) (xy 85.08873 -200.06945)
			(xy 85.08238 -200.086468) (xy 85.08238 -200.171812) (xy 85.08873 -200.18883) (xy 85.094826 -200.195942)
			(xy 85.112508 -200.216842) (xy 85.142235 -200.262814) (xy 85.16508 -200.312566) (xy 85.180576 -200.365073)
			(xy 85.188402 -200.419257) (xy 85.188397 -200.474003) (xy 85.180563 -200.528186) (xy 85.165059 -200.580691)
			(xy 85.142206 -200.630439) (xy 85.112471 -200.676406) (xy 85.094826 -200.697338) (xy 85.08873 -200.70445)
			(xy 85.08238 -200.721468) (xy 85.08238 -200.806812) (xy 85.08873 -200.82383) (xy 85.094826 -200.830942)
			(xy 85.112455 -200.851882) (xy 85.142168 -200.897853) (xy 85.165005 -200.947598) (xy 85.180499 -201.000097)
			(xy 85.18833 -201.054271) (xy 85.188355 -201.055732) (xy 87.515446 -201.055732) (xy 87.51592 -201.028362)
			(xy 87.523734 -200.974183) (xy 87.539221 -200.921679) (xy 87.562061 -200.871932) (xy 87.591785 -200.825965)
			(xy 87.609426 -200.805034) (xy 87.615522 -200.797922) (xy 87.621872 -200.780904) (xy 87.621872 -200.69556)
			(xy 87.615522 -200.678542) (xy 87.609426 -200.67143) (xy 87.591817 -200.650472) (xy 87.562091 -200.604508)
			(xy 87.539244 -200.554766) (xy 87.523745 -200.502268) (xy 87.515913 -200.448093) (xy 87.51591 -200.393355)
			(xy 87.523735 -200.339179) (xy 87.539227 -200.286679) (xy 87.562067 -200.236934) (xy 87.591788 -200.190967)
			(xy 87.609426 -200.170034) (xy 87.615522 -200.162922) (xy 87.621872 -200.145904) (xy 87.621872 -200.06056)
			(xy 87.615522 -200.043542) (xy 87.609426 -200.03643) (xy 87.591817 -200.015472) (xy 87.562091 -199.969508)
			(xy 87.539244 -199.919766) (xy 87.523745 -199.867268) (xy 87.515913 -199.813093) (xy 87.51591 -199.758355)
			(xy 87.523735 -199.704179) (xy 87.539227 -199.651679) (xy 87.562067 -199.601934) (xy 87.591788 -199.555967)
			(xy 87.609426 -199.535034) (xy 87.615522 -199.527922) (xy 87.621872 -199.510904) (xy 87.621872 -199.42556)
			(xy 87.615522 -199.408542) (xy 87.609426 -199.40143) (xy 87.591817 -199.380472) (xy 87.562091 -199.334508)
			(xy 87.539244 -199.284766) (xy 87.523745 -199.232268) (xy 87.515913 -199.178093) (xy 87.51591 -199.123355)
			(xy 87.523735 -199.069179) (xy 87.539227 -199.016679) (xy 87.562067 -198.966934) (xy 87.591788 -198.920967)
			(xy 87.609426 -198.900034) (xy 87.615522 -198.892922) (xy 87.621872 -198.875904) (xy 87.621872 -198.79056)
			(xy 87.615522 -198.773542) (xy 87.609426 -198.76643) (xy 87.591817 -198.745472) (xy 87.562091 -198.699508)
			(xy 87.539244 -198.649766) (xy 87.523745 -198.597268) (xy 87.515913 -198.543093) (xy 87.51591 -198.488355)
			(xy 87.523735 -198.434179) (xy 87.539227 -198.381679) (xy 87.562067 -198.331934) (xy 87.591788 -198.285967)
			(xy 87.609426 -198.265034) (xy 87.615522 -198.257922) (xy 87.621872 -198.240904) (xy 87.621872 -198.15556)
			(xy 87.615522 -198.138542) (xy 87.609426 -198.13143) (xy 87.591817 -198.110472) (xy 87.562091 -198.064508)
			(xy 87.539244 -198.014766) (xy 87.523745 -197.962268) (xy 87.515913 -197.908093) (xy 87.51591 -197.853355)
			(xy 87.523735 -197.799179) (xy 87.539227 -197.746679) (xy 87.562067 -197.696934) (xy 87.591788 -197.650967)
			(xy 87.609426 -197.630034) (xy 87.615522 -197.622922) (xy 87.621872 -197.605904) (xy 87.621872 -197.52056)
			(xy 87.615522 -197.503542) (xy 87.609426 -197.49643) (xy 87.591817 -197.475472) (xy 87.562091 -197.429508)
			(xy 87.539244 -197.379766) (xy 87.523745 -197.327268) (xy 87.515913 -197.273093) (xy 87.51591 -197.218355)
			(xy 87.523735 -197.164179) (xy 87.539227 -197.111679) (xy 87.562067 -197.061934) (xy 87.591788 -197.015967)
			(xy 87.609426 -196.995034) (xy 87.615522 -196.987922) (xy 87.621872 -196.970904) (xy 87.621872 -196.88556)
			(xy 87.615522 -196.868542) (xy 87.609426 -196.86143) (xy 87.591817 -196.840472) (xy 87.562091 -196.794508)
			(xy 87.539244 -196.744766) (xy 87.523745 -196.692268) (xy 87.515913 -196.638093) (xy 87.51591 -196.583355)
			(xy 87.523735 -196.529179) (xy 87.539227 -196.476679) (xy 87.562067 -196.426934) (xy 87.591788 -196.380967)
			(xy 87.609426 -196.360034) (xy 87.615522 -196.352922) (xy 87.621872 -196.335904) (xy 87.621872 -196.25056)
			(xy 87.615522 -196.233542) (xy 87.609426 -196.22643) (xy 87.591817 -196.205472) (xy 87.562091 -196.159508)
			(xy 87.539244 -196.109766) (xy 87.523745 -196.057268) (xy 87.515913 -196.003093) (xy 87.51591 -195.948355)
			(xy 87.523735 -195.894179) (xy 87.539227 -195.841679) (xy 87.562067 -195.791934) (xy 87.591788 -195.745967)
			(xy 87.609426 -195.725034) (xy 87.615522 -195.717922) (xy 87.621872 -195.700904) (xy 87.621872 -195.61556)
			(xy 87.615522 -195.598542) (xy 87.609426 -195.59143) (xy 87.591792 -195.570494) (xy 87.562078 -195.524523)
			(xy 87.539241 -195.474776) (xy 87.523749 -195.422276) (xy 87.51592 -195.368101) (xy 87.515446 -195.340732)
			(xy 87.515995 -195.311637) (xy 87.524837 -195.254122) (xy 87.542322 -195.19862) (xy 87.568042 -195.146422)
			(xy 87.601398 -195.098742) (xy 87.62111 -195.077334) (xy 87.62746 -195.070476) (xy 87.634572 -195.053458)
			(xy 87.637874 -194.967606) (xy 87.632032 -194.95008) (xy 87.62619 -194.942714) (xy 87.609969 -194.92217)
			(xy 87.582655 -194.877518) (xy 87.561696 -194.829555) (xy 87.547484 -194.779177) (xy 87.540285 -194.727331)
			(xy 87.53983 -194.70116) (xy 87.540241 -194.673906) (xy 87.548004 -194.619954) (xy 87.563366 -194.567655)
			(xy 87.586014 -194.518075) (xy 87.615488 -194.472223) (xy 87.651188 -194.431032) (xy 87.692386 -194.395342)
			(xy 87.738244 -194.365877) (xy 87.787828 -194.343238) (xy 87.84013 -194.327887) (xy 87.894084 -194.320135)
			(xy 87.921338 -194.319652) (xy 87.948708 -194.320142) (xy 88.002886 -194.327952) (xy 88.055389 -194.343435)
			(xy 88.105137 -194.366272) (xy 88.151104 -194.395992) (xy 88.172036 -194.413632) (xy 88.179148 -194.419728)
			(xy 88.196166 -194.426078) (xy 88.28151 -194.426078) (xy 88.298528 -194.419728) (xy 88.30564 -194.413632)
			(xy 88.326573 -194.395991) (xy 88.372541 -194.366267) (xy 88.422287 -194.343421) (xy 88.474789 -194.327925)
			(xy 88.528967 -194.320096) (xy 88.583709 -194.320096) (xy 88.637887 -194.327925) (xy 88.690389 -194.343421)
			(xy 88.740135 -194.366267) (xy 88.786103 -194.395991) (xy 88.807036 -194.413632) (xy 88.814148 -194.419728)
			(xy 88.831166 -194.426078) (xy 88.91651 -194.426078) (xy 88.933528 -194.419728) (xy 88.94064 -194.413632)
			(xy 88.961588 -194.396013) (xy 89.007556 -194.366297) (xy 89.057299 -194.343456) (xy 89.109797 -194.327961)
			(xy 89.16397 -194.320128) (xy 89.191338 -194.319652) (xy 89.218588 -194.320142) (xy 89.272534 -194.327903)
			(xy 89.324826 -194.343261) (xy 89.374401 -194.365904) (xy 89.420249 -194.39537) (xy 89.461438 -194.431061)
			(xy 89.497129 -194.472249) (xy 89.526595 -194.518097) (xy 89.549238 -194.567672) (xy 89.564597 -194.619964)
			(xy 89.572358 -194.67391) (xy 89.572846 -194.70116) (xy 91.55303 -194.70116) (xy 91.553441 -194.673906)
			(xy 91.561204 -194.619954) (xy 91.576566 -194.567655) (xy 91.599214 -194.518075) (xy 91.628688 -194.472223)
			(xy 91.664388 -194.431032) (xy 91.705586 -194.395342) (xy 91.751444 -194.365877) (xy 91.801028 -194.343238)
			(xy 91.85333 -194.327887) (xy 91.907284 -194.320135) (xy 91.934538 -194.319652) (xy 91.961908 -194.320142)
			(xy 92.016086 -194.327952) (xy 92.068589 -194.343435) (xy 92.118337 -194.366272) (xy 92.164304 -194.395992)
			(xy 92.185236 -194.413632) (xy 92.192348 -194.419728) (xy 92.209366 -194.426078) (xy 92.29471 -194.426078)
			(xy 92.311728 -194.419728) (xy 92.31884 -194.413632) (xy 92.339788 -194.396013) (xy 92.385756 -194.366297)
			(xy 92.435499 -194.343456) (xy 92.487997 -194.327961) (xy 92.54217 -194.320128) (xy 92.569538 -194.319652)
			(xy 92.599015 -194.320216) (xy 92.657268 -194.329278) (xy 92.713433 -194.347194) (xy 92.766172 -194.373538)
			(xy 92.81423 -194.407683) (xy 92.83573 -194.427856) (xy 92.843054 -194.434404) (xy 92.861223 -194.44184)
			(xy 92.871036 -194.442334) (xy 92.924376 -194.442334) (xy 92.935044 -194.431158) (xy 92.941709 -194.423735)
			(xy 92.949293 -194.405307) (xy 92.949776 -194.395344) (xy 92.949776 -182.525162) (xy 92.950276 -182.500175)
			(xy 92.958093 -182.450816) (xy 92.973544 -182.403291) (xy 92.996247 -182.358772) (xy 93.025642 -182.318358)
			(xy 93.042994 -182.300372) (xy 93.230954 -182.112412) (xy 93.237682 -182.105011) (xy 93.245401 -182.086584)
			(xy 93.24594 -182.076598) (xy 93.24594 -180.738272) (xy 93.246451 -180.713299) (xy 93.254234 -180.663962)
			(xy 93.269637 -180.61645) (xy 93.29228 -180.571932) (xy 93.321606 -180.531501) (xy 93.338904 -180.513482)
			(xy 93.509084 -180.343302) (xy 93.516033 -180.335692) (xy 93.523698 -180.316579) (xy 93.523285 -180.295992)
			(xy 93.519498 -180.286406) (xy 93.473778 -180.18506) (xy 93.446854 -180.169058) (xy 93.430852 -180.170074)
			(xy 93.406468 -180.170836) (xy 93.379219 -180.170288) (xy 93.325277 -180.162527) (xy 93.272988 -180.147169)
			(xy 93.223417 -180.124526) (xy 93.177573 -180.095058) (xy 93.136389 -180.059366) (xy 93.100704 -180.018177)
			(xy 93.071244 -179.972328) (xy 93.048609 -179.922753) (xy 93.033259 -179.870462) (xy 93.025508 -179.816518)
			(xy 93.025512 -179.762021) (xy 93.033273 -179.708078) (xy 93.04863 -179.655789) (xy 93.071274 -179.606218)
			(xy 93.100741 -179.560374) (xy 93.136433 -179.51919) (xy 93.177622 -179.483505) (xy 93.223471 -179.454045)
			(xy 93.273045 -179.43141) (xy 93.325337 -179.41606) (xy 93.37928 -179.408308) (xy 93.433778 -179.408312)
			(xy 93.487721 -179.416072) (xy 93.54001 -179.43143) (xy 93.589581 -179.454073) (xy 93.635425 -179.48354)
			(xy 93.676609 -179.519232) (xy 93.712294 -179.560421) (xy 93.741755 -179.60627) (xy 93.76439 -179.655844)
			(xy 93.77974 -179.708135) (xy 93.787492 -179.762079) (xy 93.787976 -179.789328) (xy 93.787379 -179.82046)
			(xy 93.777304 -179.881902) (xy 93.757362 -179.940885) (xy 93.743272 -179.968652) (xy 93.735398 -179.983384)
			(xy 93.740224 -180.016658) (xy 93.752162 -180.028342) (xy 93.759596 -180.035058) (xy 93.778096 -180.042694)
			(xy 93.79811 -180.042694) (xy 93.81661 -180.035058) (xy 93.824044 -180.028342) (xy 93.944186 -179.9082)
			(xy 93.950923 -179.900807) (xy 93.958637 -179.882374) (xy 93.959172 -179.872386) (xy 93.959172 -179.33797)
			(xy 93.958704 -179.327966) (xy 93.95099 -179.309504) (xy 93.944186 -179.302156) (xy 93.91523 -179.2732)
			(xy 93.903292 -179.266596) (xy 93.896434 -179.264818) (xy 93.869027 -179.257736) (xy 93.816548 -179.236519)
			(xy 93.76778 -179.20778) (xy 93.723794 -179.172151) (xy 93.685555 -179.130414) (xy 93.653902 -179.083485)
			(xy 93.629531 -179.032394) (xy 93.612976 -178.978264) (xy 93.604601 -178.922281) (xy 93.60408 -178.893978)
			(xy 93.604557 -178.866727) (xy 93.612316 -178.812779) (xy 93.627674 -178.760485) (xy 93.650317 -178.710909)
			(xy 93.679784 -178.665059) (xy 93.715476 -178.623869) (xy 93.756667 -178.588178) (xy 93.802517 -178.558712)
			(xy 93.852095 -178.53607) (xy 93.904389 -178.520714) (xy 93.958337 -178.512957) (xy 93.985588 -178.51247)
			(xy 94.013894 -178.512989) (xy 94.069888 -178.521332) (xy 94.124032 -178.537867) (xy 94.175134 -178.562229)
			(xy 94.22207 -178.593882) (xy 94.263807 -178.632131) (xy 94.299427 -178.676132) (xy 94.328146 -178.724919)
			(xy 94.349332 -178.777417) (xy 94.356428 -178.804824) (xy 94.358206 -178.811682) (xy 94.36481 -178.82362)
			(xy 94.501716 -178.960526) (xy 94.519062 -178.978506) (xy 94.548408 -179.018936) (xy 94.571063 -179.063462)
			(xy 94.586466 -179.110987) (xy 94.594239 -179.160336) (xy 94.59468 -179.185316) (xy 94.59468 -180.02504)
			(xy 94.594171 -180.050013) (xy 94.586386 -180.099349) (xy 94.570982 -180.146861) (xy 94.548339 -180.19138)
			(xy 94.519013 -180.23181) (xy 94.501716 -180.24983) (xy 94.285308 -180.465984) (xy 94.278475 -180.47345)
			(xy 94.270851 -180.49218) (xy 94.271048 -180.512402) (xy 94.27464 -180.521864) (xy 94.317312 -180.622956)
			(xy 94.323985 -180.627274) (xy 94.981522 -180.627274) (xy 94.982031 -180.599701) (xy 94.989974 -180.54513)
			(xy 95.00569 -180.49227) (xy 95.028851 -180.442224) (xy 95.058977 -180.396033) (xy 95.095438 -180.354661)
			(xy 95.116142 -180.336444) (xy 95.124243 -180.328826) (xy 95.133605 -180.308686) (xy 95.134176 -180.297582)
			(xy 95.134176 -180.220366) (xy 95.133651 -180.209251) (xy 95.124283 -180.189092) (xy 95.116142 -180.181504)
			(xy 95.095409 -180.163318) (xy 95.058941 -180.121944) (xy 95.028812 -180.075751) (xy 95.005648 -180.0257)
			(xy 94.989933 -179.972835) (xy 94.981993 -179.918259) (xy 94.981996 -179.863108) (xy 94.98994 -179.808532)
			(xy 95.00566 -179.755669) (xy 95.028828 -179.70562) (xy 95.058962 -179.659429) (xy 95.095433 -179.618059)
			(xy 95.116142 -179.599844) (xy 95.124243 -179.592226) (xy 95.133605 -179.572086) (xy 95.134176 -179.560982)
			(xy 95.134176 -179.483766) (xy 95.133651 -179.472651) (xy 95.124283 -179.452492) (xy 95.116142 -179.444904)
			(xy 95.095438 -179.426685) (xy 95.058965 -179.385319) (xy 95.028831 -179.339131) (xy 95.005664 -179.289084)
			(xy 94.989947 -179.236223) (xy 94.982007 -179.181648) (xy 94.981522 -179.154074) (xy 94.981931 -179.126819)
			(xy 94.989692 -179.072865) (xy 95.005053 -179.020564) (xy 95.027701 -178.970982) (xy 95.057174 -178.925127)
			(xy 95.092874 -178.883934) (xy 95.134072 -178.848241) (xy 95.179931 -178.818774) (xy 95.229516 -178.796133)
			(xy 95.281819 -178.78078) (xy 95.335775 -178.773027) (xy 95.36303 -178.772566) (xy 95.390885 -178.773087)
			(xy 95.445999 -178.781214) (xy 95.499348 -178.797262) (xy 95.5498 -178.82089) (xy 95.596283 -178.851597)
			(xy 95.637812 -178.888732) (xy 95.673506 -178.931506) (xy 95.702606 -178.979012) (xy 95.724496 -179.030242)
			(xy 95.732092 -179.057046) (xy 95.734378 -179.065936) (xy 95.745046 -179.081176) (xy 95.816928 -179.128928)
			(xy 95.834962 -179.132992) (xy 95.844106 -179.131722) (xy 95.857123 -179.130054) (xy 95.883307 -179.128273)
			(xy 95.89643 -179.128166) (xy 95.910579 -179.128257) (xy 95.938802 -179.130293) (xy 95.952818 -179.13223)
			(xy 95.962978 -179.133754) (xy 95.982536 -179.128928) (xy 96.056958 -179.073048) (xy 96.067118 -179.055522)
			(xy 96.068388 -179.045362) (xy 96.072477 -179.018208) (xy 96.087449 -178.965378) (xy 96.10984 -178.915239)
			(xy 96.139187 -178.868828) (xy 96.174885 -178.827104) (xy 96.216194 -178.790927) (xy 96.262263 -178.761046)
			(xy 96.31214 -178.738077) (xy 96.364794 -178.722496) (xy 96.419138 -178.714624) (xy 96.446594 -178.714146)
			(xy 96.473843 -178.714683) (xy 96.527787 -178.722438) (xy 96.580077 -178.73779) (xy 96.629652 -178.760427)
			(xy 96.6755 -178.789888) (xy 96.716689 -178.825574) (xy 96.752381 -178.866758) (xy 96.781848 -178.912603)
			(xy 96.804492 -178.962174) (xy 96.819851 -179.014463) (xy 96.827613 -179.068405) (xy 96.828102 -179.095654)
			(xy 96.827604 -179.123227) (xy 96.819658 -179.177799) (xy 96.803939 -179.230658) (xy 96.780775 -179.280704)
			(xy 96.750649 -179.326894) (xy 96.714187 -179.368267) (xy 96.693482 -179.386484) (xy 96.685373 -179.394095)
			(xy 96.676014 -179.41424) (xy 96.675448 -179.425346) (xy 96.675448 -179.502562) (xy 96.676006 -179.513673)
			(xy 96.68535 -179.533833) (xy 96.693482 -179.541424) (xy 96.714204 -179.559623) (xy 96.750675 -179.600994)
			(xy 96.780806 -179.647186) (xy 96.80397 -179.697237) (xy 96.819683 -179.750102) (xy 96.827619 -179.804678)
			(xy 96.828102 -179.832254) (xy 96.827602 -179.859506) (xy 96.819851 -179.913456) (xy 96.804501 -179.965753)
			(xy 96.781863 -180.015334) (xy 96.752399 -180.061187) (xy 96.716709 -180.102381) (xy 96.67552 -180.138075)
			(xy 96.629669 -180.167544) (xy 96.580091 -180.190187) (xy 96.527795 -180.205543) (xy 96.473846 -180.213299)
			(xy 96.446594 -180.213762) (xy 96.412304 -180.212238) (xy 96.402144 -180.211222) (xy 96.38284 -180.217318)
			(xy 96.312228 -180.2765) (xy 96.30283 -180.294534) (xy 96.301814 -180.304694) (xy 96.298902 -180.332872)
			(xy 96.285721 -180.387965) (xy 96.264537 -180.440502) (xy 96.235814 -180.489328) (xy 96.200185 -180.533368)
			(xy 96.158433 -180.571654) (xy 96.111478 -180.603342) (xy 96.060352 -180.627737) (xy 96.00618 -180.644301)
			(xy 95.950154 -180.65267) (xy 95.92183 -180.653182) (xy 95.903811 -180.652966) (xy 95.867936 -180.649528)
			(xy 95.850202 -180.646324) (xy 95.840804 -180.644546) (xy 95.821754 -180.648356) (xy 95.74657 -180.696108)
			(xy 95.73514 -180.711856) (xy 95.732854 -180.721254) (xy 95.725489 -180.748308) (xy 95.703856 -180.800036)
			(xy 95.674888 -180.848042) (xy 95.639209 -180.891294) (xy 95.597585 -180.928861) (xy 95.550913 -180.959934)
			(xy 95.500198 -180.983844) (xy 95.44653 -181.000078) (xy 95.391065 -181.008285) (xy 95.36303 -181.008782)
			(xy 95.335777 -181.008317) (xy 95.281824 -181.000563) (xy 95.229525 -180.98521) (xy 95.179943 -180.962569)
			(xy 95.134089 -180.933101) (xy 95.092895 -180.897408) (xy 95.057201 -180.856214) (xy 95.027733 -180.81036)
			(xy 95.005092 -180.760779) (xy 94.989738 -180.708479) (xy 94.981984 -180.654527) (xy 94.981522 -180.627274)
			(xy 94.323985 -180.627274) (xy 94.34322 -180.63972) (xy 94.358968 -180.639466) (xy 94.36481 -180.639466)
			(xy 94.39206 -180.639968) (xy 94.446006 -180.647726) (xy 94.498299 -180.663081) (xy 94.547874 -180.685721)
			(xy 94.593724 -180.715186) (xy 94.634913 -180.750876) (xy 94.670604 -180.792064) (xy 94.700071 -180.837911)
			(xy 94.722714 -180.887486) (xy 94.738071 -180.939778) (xy 94.74583 -180.993724) (xy 94.746318 -181.020974)
			(xy 94.745868 -181.048886) (xy 94.737722 -181.104114) (xy 94.721617 -181.157565) (xy 94.697895 -181.208099)
			(xy 94.667063 -181.254637) (xy 94.648782 -181.275736) (xy 94.642432 -181.282848) (xy 94.635828 -181.30012)
			(xy 94.635828 -181.387242) (xy 94.642432 -181.404514) (xy 94.648782 -181.411626) (xy 94.667044 -181.432739)
			(xy 94.697874 -181.479274) (xy 94.721593 -181.529805) (xy 94.737693 -181.583253) (xy 94.745831 -181.638478)
			(xy 94.746318 -181.666388) (xy 94.745832 -181.693639) (xy 94.738076 -181.747587) (xy 94.722721 -181.799882)
			(xy 94.700079 -181.849459) (xy 94.670613 -181.895309) (xy 94.634922 -181.9365) (xy 94.593731 -181.972191)
			(xy 94.547881 -182.001657) (xy 94.498304 -182.024299) (xy 94.446009 -182.039654) (xy 94.392061 -182.04741)
			(xy 94.337559 -182.04741) (xy 94.283611 -182.039654) (xy 94.231316 -182.024299) (xy 94.181739 -182.001657)
			(xy 94.135889 -181.972191) (xy 94.094698 -181.9365) (xy 94.059007 -181.895309) (xy 94.029541 -181.849459)
			(xy 94.006899 -181.799882) (xy 93.991544 -181.747587) (xy 93.983788 -181.693639) (xy 93.983302 -181.666388)
			(xy 93.98381 -181.638478) (xy 93.991944 -181.583254) (xy 94.008037 -181.529804) (xy 94.031746 -181.479269)
			(xy 94.062564 -181.432728) (xy 94.080838 -181.411626) (xy 94.087188 -181.404514) (xy 94.093792 -181.387242)
			(xy 94.093792 -181.30012) (xy 94.087188 -181.282848) (xy 94.080838 -181.275736) (xy 94.062546 -181.254648)
			(xy 94.031722 -181.208106) (xy 94.008011 -181.157568) (xy 93.991918 -181.104114) (xy 93.983786 -181.048886)
			(xy 93.983302 -181.020974) (xy 93.9837 -180.996624) (xy 93.989912 -180.948321) (xy 94.002233 -180.901205)
			(xy 94.010988 -180.87848) (xy 94.016576 -180.86451) (xy 94.01048 -180.834538) (xy 93.999558 -180.823616)
			(xy 93.992146 -180.816932) (xy 93.973713 -180.809335) (xy 93.953775 -180.809335) (xy 93.935342 -180.816932)
			(xy 93.92793 -180.823616) (xy 93.896434 -180.855112) (xy 93.889694 -180.862503) (xy 93.881982 -180.880937)
			(xy 93.881448 -180.890926) (xy 93.881448 -182.13324) (xy 96.59874 -182.13324) (xy 96.599219 -182.105666)
			(xy 96.607167 -182.051093) (xy 96.622888 -181.998233) (xy 96.646056 -181.948186) (xy 96.676187 -181.901997)
			(xy 96.712653 -181.860626) (xy 96.73336 -181.84241) (xy 96.741479 -181.834808) (xy 96.75083 -181.814656)
			(xy 96.751394 -181.803548) (xy 96.751394 -181.726332) (xy 96.750826 -181.715222) (xy 96.741488 -181.695063)
			(xy 96.73336 -181.68747) (xy 96.712623 -181.669287) (xy 96.676157 -181.627911) (xy 96.646029 -181.581715)
			(xy 96.622868 -181.531662) (xy 96.607156 -181.478795) (xy 96.599222 -181.424216) (xy 96.59874 -181.39664)
			(xy 96.599286 -181.367028) (xy 96.608433 -181.308514) (xy 96.626512 -181.252118) (xy 96.653091 -181.199192)
			(xy 96.68753 -181.151011) (xy 96.729001 -181.10873) (xy 96.776508 -181.073367) (xy 96.802448 -181.059074)
			(xy 96.8121 -181.053994) (xy 96.825308 -181.03723) (xy 96.849184 -180.942742) (xy 96.845374 -180.92166)
			(xy 96.839278 -180.912516) (xy 96.824345 -180.889347) (xy 96.800704 -180.839554) (xy 96.784649 -180.786823)
			(xy 96.77653 -180.732304) (xy 96.776032 -180.704744) (xy 96.776475 -180.678125) (xy 96.784047 -180.625428)
			(xy 96.799042 -180.574346) (xy 96.821155 -180.525918) (xy 96.849937 -180.48113) (xy 96.8848 -180.440896)
			(xy 96.925035 -180.406033) (xy 96.969823 -180.377252) (xy 97.018251 -180.35514) (xy 97.069334 -180.340145)
			(xy 97.122031 -180.332575) (xy 97.14865 -180.332126) (xy 97.175072 -180.332572) (xy 97.227387 -180.340028)
			(xy 97.278125 -180.354796) (xy 97.326269 -180.376582) (xy 97.370854 -180.404948) (xy 97.39122 -180.421788)
			(xy 97.398078 -180.427884) (xy 97.415096 -180.43398) (xy 97.499424 -180.43398) (xy 97.516442 -180.427884)
			(xy 97.5233 -180.421788) (xy 97.543666 -180.404949) (xy 97.588252 -180.376584) (xy 97.636396 -180.354797)
			(xy 97.687133 -180.340026) (xy 97.739448 -180.332566) (xy 97.792292 -180.332566) (xy 97.844607 -180.340026)
			(xy 97.895344 -180.354797) (xy 97.943488 -180.376584) (xy 97.988074 -180.404949) (xy 98.00844 -180.421788)
			(xy 98.015298 -180.427884) (xy 98.032316 -180.43398) (xy 98.116644 -180.43398) (xy 98.133662 -180.427884)
			(xy 98.14052 -180.421788) (xy 98.160877 -180.404939) (xy 98.205469 -180.376586) (xy 98.253616 -180.354809)
			(xy 98.304354 -180.340044) (xy 98.356669 -180.332586) (xy 98.38309 -180.332126) (xy 98.410981 -180.332532)
			(xy 98.466139 -180.340845) (xy 98.519442 -180.357285) (xy 98.569699 -180.381487) (xy 98.615788 -180.412909)
			(xy 98.656679 -180.450849) (xy 98.691459 -180.49446) (xy 98.71935 -180.542767) (xy 98.739729 -180.594692)
			(xy 98.752142 -180.649075) (xy 98.756311 -180.7047) (xy 98.752142 -180.760325) (xy 98.739729 -180.814708)
			(xy 98.71935 -180.866633) (xy 98.691459 -180.91494) (xy 98.656679 -180.958551) (xy 98.615788 -180.996491)
			(xy 98.569699 -181.027913) (xy 98.519442 -181.052115) (xy 98.466139 -181.068555) (xy 98.410981 -181.076868)
			(xy 98.38309 -181.077362) (xy 98.356669 -181.076895) (xy 98.304354 -181.069445) (xy 98.253616 -181.054682)
			(xy 98.205472 -181.0329) (xy 98.160886 -181.004538) (xy 98.14052 -180.9877) (xy 98.133662 -180.981604)
			(xy 98.116644 -180.975508) (xy 98.032316 -180.975508) (xy 98.015298 -180.981604) (xy 98.00844 -180.9877)
			(xy 97.988074 -181.004539) (xy 97.943488 -181.032904) (xy 97.895344 -181.054691) (xy 97.844607 -181.069462)
			(xy 97.792292 -181.076922) (xy 97.739448 -181.076922) (xy 97.687133 -181.069462) (xy 97.636396 -181.054691)
			(xy 97.588252 -181.032904) (xy 97.543666 -181.004539) (xy 97.5233 -180.9877) (xy 97.516442 -180.981604)
			(xy 97.499424 -180.975508) (xy 97.415096 -180.975508) (xy 97.398078 -180.981604) (xy 97.39122 -180.9877)
			(xy 97.376369 -181.000042) (xy 97.344556 -181.021932) (xy 97.32772 -181.031388) (xy 97.318322 -181.036722)
			(xy 97.305368 -181.05374) (xy 97.283016 -181.148736) (xy 97.28708 -181.169564) (xy 97.29343 -181.178708)
			(xy 97.309557 -181.202826) (xy 97.33509 -181.254922) (xy 97.352443 -181.310283) (xy 97.361218 -181.367632)
			(xy 97.361756 -181.39664) (xy 97.361264 -181.424214) (xy 97.353319 -181.478786) (xy 97.3376 -181.531646)
			(xy 97.314435 -181.581693) (xy 97.284307 -181.627883) (xy 97.247842 -181.669254) (xy 97.227136 -181.68747)
			(xy 97.219025 -181.695079) (xy 97.209669 -181.715226) (xy 97.209102 -181.726332) (xy 97.209102 -181.803548)
			(xy 97.209682 -181.814656) (xy 97.219012 -181.834815) (xy 97.227136 -181.84241) (xy 97.247862 -181.860604)
			(xy 97.28433 -181.901978) (xy 97.314459 -181.948171) (xy 97.337622 -181.998222) (xy 97.353336 -182.051088)
			(xy 97.361272 -182.105664) (xy 97.361756 -182.13324) (xy 97.36127 -182.160491) (xy 97.353514 -182.214439)
			(xy 97.338159 -182.266734) (xy 97.315517 -182.316311) (xy 97.286051 -182.362161) (xy 97.25036 -182.403352)
			(xy 97.209169 -182.439043) (xy 97.163319 -182.468509) (xy 97.113742 -182.491151) (xy 97.061447 -182.506506)
			(xy 97.007499 -182.514262) (xy 96.952997 -182.514262) (xy 96.899049 -182.506506) (xy 96.846754 -182.491151)
			(xy 96.797177 -182.468509) (xy 96.751327 -182.439043) (xy 96.710136 -182.403352) (xy 96.674445 -182.362161)
			(xy 96.644979 -182.316311) (xy 96.622337 -182.266734) (xy 96.606982 -182.214439) (xy 96.599226 -182.160491)
			(xy 96.59874 -182.13324) (xy 93.881448 -182.13324) (xy 93.881448 -182.229252) (xy 93.880956 -182.254226)
			(xy 93.873168 -182.303563) (xy 93.857761 -182.351076) (xy 93.835114 -182.395594) (xy 93.805784 -182.436024)
			(xy 93.788484 -182.454042) (xy 93.600524 -182.642002) (xy 93.593873 -182.649435) (xy 93.586281 -182.667855)
			(xy 93.585792 -182.677816) (xy 93.585792 -194.637914) (xy 93.584776 -194.662044) (xy 93.584776 -194.669918)
			(xy 93.586046 -194.70116) (xy 93.585518 -194.728702) (xy 93.577571 -194.783211) (xy 93.561865 -194.83601)
			(xy 93.538727 -194.886) (xy 93.508639 -194.932141) (xy 93.490796 -194.953128) (xy 93.4847 -194.96024)
			(xy 93.478096 -194.977512) (xy 93.47835 -195.063364) (xy 93.484954 -195.08089) (xy 93.49105 -195.087748)
			(xy 93.509019 -195.1088) (xy 93.539369 -195.155082) (xy 93.562711 -195.205266) (xy 93.578553 -195.258296)
			(xy 93.586563 -195.313059) (xy 93.587062 -195.340732) (xy 93.586624 -195.368103) (xy 93.578801 -195.422284)
			(xy 93.563306 -195.474788) (xy 93.540457 -195.524534) (xy 93.510726 -195.5705) (xy 93.493082 -195.59143)
			(xy 93.486986 -195.598542) (xy 93.480636 -195.61556) (xy 93.480636 -195.700904) (xy 93.486986 -195.717922)
			(xy 93.493082 -195.725034) (xy 93.510754 -195.745942) (xy 93.540476 -195.791914) (xy 93.563319 -195.841664)
			(xy 93.578813 -195.89417) (xy 93.586638 -195.948352) (xy 93.586635 -196.003096) (xy 93.578803 -196.057277)
			(xy 93.563302 -196.109781) (xy 93.540453 -196.159528) (xy 93.510725 -196.205497) (xy 93.493082 -196.22643)
			(xy 93.486986 -196.233542) (xy 93.480636 -196.25056) (xy 93.480636 -196.335904) (xy 93.486986 -196.352922)
			(xy 93.493082 -196.360034) (xy 93.510754 -196.380942) (xy 93.540476 -196.426914) (xy 93.563319 -196.476664)
			(xy 93.578813 -196.52917) (xy 93.586638 -196.583352) (xy 93.586635 -196.638096) (xy 93.578803 -196.692277)
			(xy 93.563302 -196.744781) (xy 93.540453 -196.794528) (xy 93.510725 -196.840497) (xy 93.493082 -196.86143)
			(xy 93.486986 -196.868542) (xy 93.480636 -196.88556) (xy 93.480636 -196.970904) (xy 93.486986 -196.987922)
			(xy 93.493082 -196.995034) (xy 93.510754 -197.015942) (xy 93.540476 -197.061914) (xy 93.563319 -197.111664)
			(xy 93.578813 -197.16417) (xy 93.586638 -197.218352) (xy 93.586635 -197.273096) (xy 93.578803 -197.327277)
			(xy 93.563302 -197.379781) (xy 93.540453 -197.429528) (xy 93.510725 -197.475497) (xy 93.493082 -197.49643)
			(xy 93.486986 -197.503542) (xy 93.480636 -197.52056) (xy 93.480636 -197.605904) (xy 93.486986 -197.622922)
			(xy 93.493082 -197.630034) (xy 93.510754 -197.650942) (xy 93.540476 -197.696914) (xy 93.563319 -197.746664)
			(xy 93.578813 -197.79917) (xy 93.586638 -197.853352) (xy 93.586635 -197.908096) (xy 93.578803 -197.962277)
			(xy 93.563302 -198.014781) (xy 93.540453 -198.064528) (xy 93.510725 -198.110497) (xy 93.493082 -198.13143)
			(xy 93.486986 -198.138542) (xy 93.480636 -198.15556) (xy 93.480636 -198.240904) (xy 93.486986 -198.257922)
			(xy 93.493082 -198.265034) (xy 93.510754 -198.285942) (xy 93.540476 -198.331914) (xy 93.563319 -198.381664)
			(xy 93.578813 -198.43417) (xy 93.586638 -198.488352) (xy 93.586635 -198.543096) (xy 93.578803 -198.597277)
			(xy 93.563302 -198.649781) (xy 93.540453 -198.699528) (xy 93.510725 -198.745497) (xy 93.493082 -198.76643)
			(xy 93.486986 -198.773542) (xy 93.480636 -198.79056) (xy 93.480636 -198.875904) (xy 93.486986 -198.892922)
			(xy 93.493082 -198.900034) (xy 93.510754 -198.920942) (xy 93.540476 -198.966914) (xy 93.563319 -199.016664)
			(xy 93.578813 -199.06917) (xy 93.586638 -199.123352) (xy 93.586635 -199.178096) (xy 93.578803 -199.232277)
			(xy 93.563302 -199.284781) (xy 93.540453 -199.334528) (xy 93.510725 -199.380497) (xy 93.493082 -199.40143)
			(xy 93.486986 -199.408542) (xy 93.480636 -199.42556) (xy 93.480636 -199.510904) (xy 93.486986 -199.527922)
			(xy 93.493082 -199.535034) (xy 93.510754 -199.555942) (xy 93.540476 -199.601914) (xy 93.563319 -199.651664)
			(xy 93.578813 -199.70417) (xy 93.586638 -199.758352) (xy 93.586635 -199.813096) (xy 93.578803 -199.867277)
			(xy 93.563302 -199.919781) (xy 93.540453 -199.969528) (xy 93.510725 -200.015497) (xy 93.493082 -200.03643)
			(xy 93.486986 -200.043542) (xy 93.480636 -200.06056) (xy 93.480636 -200.145904) (xy 93.486986 -200.162922)
			(xy 93.493082 -200.170034) (xy 93.510754 -200.190942) (xy 93.540476 -200.236914) (xy 93.563319 -200.286664)
			(xy 93.578813 -200.33917) (xy 93.586638 -200.393352) (xy 93.586635 -200.448096) (xy 93.578803 -200.502277)
			(xy 93.563302 -200.554781) (xy 93.540453 -200.604528) (xy 93.510725 -200.650497) (xy 93.493082 -200.67143)
			(xy 93.486986 -200.678542) (xy 93.480636 -200.69556) (xy 93.480636 -200.780904) (xy 93.486986 -200.797922)
			(xy 93.493082 -200.805034) (xy 93.510701 -200.825982) (xy 93.540416 -200.87195) (xy 93.563256 -200.921694)
			(xy 93.578752 -200.974191) (xy 93.586585 -201.028364) (xy 93.586628 -201.03084) (xy 95.93199 -201.03084)
			(xy 95.932482 -201.003471) (xy 95.940294 -200.949293) (xy 95.955777 -200.89679) (xy 95.978613 -200.847043)
			(xy 96.008332 -200.801075) (xy 96.02597 -200.780142) (xy 96.032066 -200.77303) (xy 96.038416 -200.756012)
			(xy 96.038416 -200.670668) (xy 96.032066 -200.65365) (xy 96.02597 -200.646538) (xy 96.008367 -200.625574)
			(xy 95.978637 -200.579613) (xy 95.955787 -200.529872) (xy 95.940285 -200.477374) (xy 95.932452 -200.423199)
			(xy 95.932448 -200.368461) (xy 95.940273 -200.314285) (xy 95.955765 -200.261784) (xy 95.978608 -200.21204)
			(xy 96.00833 -200.166074) (xy 96.02597 -200.145142) (xy 96.032066 -200.13803) (xy 96.038416 -200.121012)
			(xy 96.038416 -200.035668) (xy 96.032066 -200.01865) (xy 96.02597 -200.011538) (xy 96.008367 -199.990574)
			(xy 95.978637 -199.944613) (xy 95.955787 -199.894872) (xy 95.940285 -199.842374) (xy 95.932452 -199.788199)
			(xy 95.932448 -199.733461) (xy 95.940273 -199.679285) (xy 95.955765 -199.626784) (xy 95.978608 -199.57704)
			(xy 96.00833 -199.531074) (xy 96.02597 -199.510142) (xy 96.032066 -199.50303) (xy 96.038416 -199.486012)
			(xy 96.038416 -199.400668) (xy 96.032066 -199.38365) (xy 96.02597 -199.376538) (xy 96.008367 -199.355574)
			(xy 95.978637 -199.309613) (xy 95.955787 -199.259872) (xy 95.940285 -199.207374) (xy 95.932452 -199.153199)
			(xy 95.932448 -199.098461) (xy 95.940273 -199.044285) (xy 95.955765 -198.991784) (xy 95.978608 -198.94204)
			(xy 96.00833 -198.896074) (xy 96.02597 -198.875142) (xy 96.032066 -198.86803) (xy 96.038416 -198.851012)
			(xy 96.038416 -198.765668) (xy 96.032066 -198.74865) (xy 96.02597 -198.741538) (xy 96.008367 -198.720574)
			(xy 95.978637 -198.674613) (xy 95.955787 -198.624872) (xy 95.940285 -198.572374) (xy 95.932452 -198.518199)
			(xy 95.932448 -198.463461) (xy 95.940273 -198.409285) (xy 95.955765 -198.356784) (xy 95.978608 -198.30704)
			(xy 96.00833 -198.261074) (xy 96.02597 -198.240142) (xy 96.032066 -198.23303) (xy 96.038416 -198.216012)
			(xy 96.038416 -198.130668) (xy 96.032066 -198.11365) (xy 96.02597 -198.106538) (xy 96.008367 -198.085574)
			(xy 95.978637 -198.039613) (xy 95.955787 -197.989872) (xy 95.940285 -197.937374) (xy 95.932452 -197.883199)
			(xy 95.932448 -197.828461) (xy 95.940273 -197.774285) (xy 95.955765 -197.721784) (xy 95.978608 -197.67204)
			(xy 96.00833 -197.626074) (xy 96.02597 -197.605142) (xy 96.032066 -197.59803) (xy 96.038416 -197.581012)
			(xy 96.038416 -197.495668) (xy 96.032066 -197.47865) (xy 96.02597 -197.471538) (xy 96.008367 -197.450574)
			(xy 95.978637 -197.404613) (xy 95.955787 -197.354872) (xy 95.940285 -197.302374) (xy 95.932452 -197.248199)
			(xy 95.932448 -197.193461) (xy 95.940273 -197.139285) (xy 95.955765 -197.086784) (xy 95.978608 -197.03704)
			(xy 96.00833 -196.991074) (xy 96.02597 -196.970142) (xy 96.032066 -196.96303) (xy 96.038416 -196.946012)
			(xy 96.038416 -196.860668) (xy 96.032066 -196.84365) (xy 96.02597 -196.836538) (xy 96.008367 -196.815574)
			(xy 95.978637 -196.769613) (xy 95.955787 -196.719872) (xy 95.940285 -196.667374) (xy 95.932452 -196.613199)
			(xy 95.932448 -196.558461) (xy 95.940273 -196.504285) (xy 95.955765 -196.451784) (xy 95.978608 -196.40204)
			(xy 96.00833 -196.356074) (xy 96.02597 -196.335142) (xy 96.032066 -196.32803) (xy 96.038416 -196.311012)
			(xy 96.038416 -196.225668) (xy 96.032066 -196.20865) (xy 96.02597 -196.201538) (xy 96.008367 -196.180574)
			(xy 95.978637 -196.134613) (xy 95.955787 -196.084872) (xy 95.940285 -196.032374) (xy 95.932452 -195.978199)
			(xy 95.932448 -195.923461) (xy 95.940273 -195.869285) (xy 95.955765 -195.816784) (xy 95.978608 -195.76704)
			(xy 96.00833 -195.721074) (xy 96.02597 -195.700142) (xy 96.032066 -195.69303) (xy 96.038416 -195.676012)
			(xy 96.038416 -195.590668) (xy 96.032066 -195.57365) (xy 96.02597 -195.566538) (xy 96.008331 -195.545606)
			(xy 95.97862 -195.499633) (xy 95.955784 -195.449885) (xy 95.940293 -195.397385) (xy 95.932465 -195.343209)
			(xy 95.93199 -195.31584) (xy 95.932479 -195.288036) (xy 95.940554 -195.233018) (xy 95.956524 -195.179754)
			(xy 95.980051 -195.129369) (xy 96.010639 -195.082929) (xy 96.028764 -195.06184) (xy 96.035114 -195.054728)
			(xy 96.041718 -195.037456) (xy 96.041718 -194.951096) (xy 96.035114 -194.933824) (xy 96.028764 -194.926712)
			(xy 96.010645 -194.905617) (xy 95.980057 -194.85918) (xy 95.95653 -194.808797) (xy 95.940563 -194.755532)
			(xy 95.932493 -194.700515) (xy 95.93199 -194.672712) (xy 95.932466 -194.64546) (xy 95.940222 -194.591509)
			(xy 95.955576 -194.539212) (xy 95.978217 -194.489632) (xy 96.007684 -194.443779) (xy 96.043376 -194.402586)
			(xy 96.084567 -194.366892) (xy 96.130419 -194.337424) (xy 96.179999 -194.314781) (xy 96.232295 -194.299425)
			(xy 96.286246 -194.291667) (xy 96.313498 -194.291204) (xy 96.340868 -194.29167) (xy 96.395047 -194.299488)
			(xy 96.447551 -194.314977) (xy 96.497297 -194.337819) (xy 96.543264 -194.367543) (xy 96.564196 -194.385184)
			(xy 96.571308 -194.39128) (xy 96.588326 -194.39763) (xy 96.67367 -194.39763) (xy 96.690688 -194.39128)
			(xy 96.6978 -194.385184) (xy 96.718733 -194.367543) (xy 96.764701 -194.337819) (xy 96.814447 -194.314973)
			(xy 96.866949 -194.299477) (xy 96.921127 -194.291648) (xy 96.975869 -194.291648) (xy 97.030047 -194.299477)
			(xy 97.082549 -194.314973) (xy 97.132295 -194.337819) (xy 97.178263 -194.367543) (xy 97.199196 -194.385184)
			(xy 97.206308 -194.39128) (xy 97.223326 -194.39763) (xy 97.30867 -194.39763) (xy 97.325688 -194.39128)
			(xy 97.3328 -194.385184) (xy 97.353719 -194.367529) (xy 97.399696 -194.33782) (xy 97.449447 -194.314987)
			(xy 97.50195 -194.2995) (xy 97.556128 -194.291676) (xy 97.583498 -194.291204) (xy 97.610751 -194.291657)
			(xy 97.664703 -194.299414) (xy 97.717002 -194.314771) (xy 97.766583 -194.337414) (xy 97.812437 -194.366883)
			(xy 97.85363 -194.402577) (xy 97.889323 -194.443771) (xy 97.918791 -194.489626) (xy 97.941433 -194.539207)
			(xy 97.956788 -194.591507) (xy 97.964543 -194.645459) (xy 97.965006 -194.672712) (xy 97.964528 -194.700011)
			(xy 97.956755 -194.754052) (xy 97.941355 -194.806433) (xy 97.918643 -194.856083) (xy 97.889083 -194.901986)
			(xy 97.871534 -194.922902) (xy 97.865184 -194.930014) (xy 97.859088 -194.947032) (xy 97.859088 -195.03263)
			(xy 97.865438 -195.049394) (xy 97.871534 -195.056506) (xy 97.889256 -195.077461) (xy 97.919132 -195.123495)
			(xy 97.942097 -195.173338) (xy 97.957675 -195.22596) (xy 97.965545 -195.280272) (xy 97.966022 -195.307712)
			(xy 97.965582 -195.335083) (xy 97.957761 -195.389264) (xy 97.942267 -195.441768) (xy 97.919419 -195.491515)
			(xy 97.889687 -195.53748) (xy 97.872042 -195.55841) (xy 97.865946 -195.565522) (xy 97.859596 -195.58254)
			(xy 97.859596 -195.667884) (xy 97.865946 -195.684902) (xy 97.872042 -195.692014) (xy 97.889696 -195.712937)
			(xy 97.919422 -195.758905) (xy 97.942269 -195.808653) (xy 97.957766 -195.861157) (xy 97.965594 -195.915337)
			(xy 97.965592 -195.970081) (xy 97.957762 -196.024261) (xy 97.942263 -196.076764) (xy 97.919414 -196.12651)
			(xy 97.889685 -196.172478) (xy 97.872042 -196.19341) (xy 97.865946 -196.200522) (xy 97.859596 -196.21754)
			(xy 97.859596 -196.302884) (xy 97.865946 -196.319902) (xy 97.872042 -196.327014) (xy 97.889696 -196.347937)
			(xy 97.919422 -196.393905) (xy 97.942269 -196.443653) (xy 97.957766 -196.496157) (xy 97.965594 -196.550337)
			(xy 97.965592 -196.605081) (xy 97.957762 -196.659261) (xy 97.942263 -196.711764) (xy 97.919414 -196.76151)
			(xy 97.889685 -196.807478) (xy 97.872042 -196.82841) (xy 97.865946 -196.835522) (xy 97.859596 -196.85254)
			(xy 97.859596 -196.937884) (xy 97.865946 -196.954902) (xy 97.872042 -196.962014) (xy 97.889661 -196.982962)
			(xy 97.919375 -197.028931) (xy 97.942214 -197.078675) (xy 97.95771 -197.131171) (xy 97.965545 -197.185344)
			(xy 97.966022 -197.212712) (xy 97.965497 -197.240586) (xy 97.957394 -197.295741) (xy 97.941347 -197.349129)
			(xy 97.9177 -197.399612) (xy 97.886955 -197.446115) (xy 97.86874 -197.46722) (xy 97.862644 -197.474078)
			(xy 97.855786 -197.49135) (xy 97.855786 -197.577964) (xy 97.86239 -197.595236) (xy 97.868486 -197.602348)
			(xy 97.886579 -197.623389) (xy 97.917096 -197.669738) (xy 97.940562 -197.720025) (xy 97.956481 -197.773185)
			(xy 97.964515 -197.828093) (xy 97.965006 -197.85584) (xy 97.964503 -197.883209) (xy 97.956694 -197.937386)
			(xy 97.941213 -197.989889) (xy 97.91838 -198.039636) (xy 97.888663 -198.085605) (xy 97.871026 -198.106538)
			(xy 97.86493 -198.11365) (xy 97.85858 -198.130668) (xy 97.85858 -198.216012) (xy 97.86493 -198.23303)
			(xy 97.871026 -198.240142) (xy 97.888708 -198.261042) (xy 97.918435 -198.307014) (xy 97.94128 -198.356766)
			(xy 97.956776 -198.409273) (xy 97.964602 -198.463457) (xy 97.964597 -198.518203) (xy 97.956763 -198.572386)
			(xy 97.941259 -198.624891) (xy 97.918406 -198.674639) (xy 97.888671 -198.720606) (xy 97.871026 -198.741538)
			(xy 97.86493 -198.74865) (xy 97.85858 -198.765668) (xy 97.85858 -198.851012) (xy 97.86493 -198.86803)
			(xy 97.871026 -198.875142) (xy 97.888708 -198.896042) (xy 97.918435 -198.942014) (xy 97.94128 -198.991766)
			(xy 97.956776 -199.044273) (xy 97.964602 -199.098457) (xy 97.964597 -199.153203) (xy 97.956763 -199.207386)
			(xy 97.941259 -199.259891) (xy 97.918406 -199.309639) (xy 97.888671 -199.355606) (xy 97.871026 -199.376538)
			(xy 97.86493 -199.38365) (xy 97.85858 -199.400668) (xy 97.85858 -199.486012) (xy 97.86493 -199.50303)
			(xy 97.871026 -199.510142) (xy 97.888708 -199.531042) (xy 97.918435 -199.577014) (xy 97.94128 -199.626766)
			(xy 97.956776 -199.679273) (xy 97.964602 -199.733457) (xy 97.964597 -199.788203) (xy 97.956763 -199.842386)
			(xy 97.941259 -199.894891) (xy 97.918406 -199.944639) (xy 97.888671 -199.990606) (xy 97.871026 -200.011538)
			(xy 97.86493 -200.01865) (xy 97.85858 -200.035668) (xy 97.85858 -200.121012) (xy 97.86493 -200.13803)
			(xy 97.871026 -200.145142) (xy 97.888708 -200.166042) (xy 97.918435 -200.212014) (xy 97.94128 -200.261766)
			(xy 97.956776 -200.314273) (xy 97.964602 -200.368457) (xy 97.964597 -200.42124) (xy 99.94519 -200.42124)
			(xy 99.945682 -200.393871) (xy 99.953494 -200.339693) (xy 99.968977 -200.28719) (xy 99.991813 -200.237443)
			(xy 100.021532 -200.191475) (xy 100.03917 -200.170542) (xy 100.045266 -200.16343) (xy 100.051616 -200.146412)
			(xy 100.051616 -200.061068) (xy 100.045266 -200.04405) (xy 100.03917 -200.036938) (xy 100.021567 -200.015974)
			(xy 99.991837 -199.970013) (xy 99.968987 -199.920272) (xy 99.953485 -199.867774) (xy 99.945652 -199.813599)
			(xy 99.945648 -199.758861) (xy 99.953473 -199.704685) (xy 99.968965 -199.652184) (xy 99.991808 -199.60244)
			(xy 100.02153 -199.556474) (xy 100.03917 -199.535542) (xy 100.045266 -199.52843) (xy 100.051616 -199.511412)
			(xy 100.051616 -199.426068) (xy 100.045266 -199.40905) (xy 100.03917 -199.401938) (xy 100.021567 -199.380974)
			(xy 99.991837 -199.335013) (xy 99.968987 -199.285272) (xy 99.953485 -199.232774) (xy 99.945652 -199.178599)
			(xy 99.945648 -199.123861) (xy 99.953473 -199.069685) (xy 99.968965 -199.017184) (xy 99.991808 -198.96744)
			(xy 100.02153 -198.921474) (xy 100.03917 -198.900542) (xy 100.045266 -198.89343) (xy 100.051616 -198.876412)
			(xy 100.051616 -198.791068) (xy 100.045266 -198.77405) (xy 100.03917 -198.766938) (xy 100.021567 -198.745974)
			(xy 99.991837 -198.700013) (xy 99.968987 -198.650272) (xy 99.953485 -198.597774) (xy 99.945652 -198.543599)
			(xy 99.945648 -198.488861) (xy 99.953473 -198.434685) (xy 99.968965 -198.382184) (xy 99.991808 -198.33244)
			(xy 100.02153 -198.286474) (xy 100.03917 -198.265542) (xy 100.045266 -198.25843) (xy 100.051616 -198.241412)
			(xy 100.051616 -198.156068) (xy 100.045266 -198.13905) (xy 100.03917 -198.131938) (xy 100.021531 -198.111006)
			(xy 99.99182 -198.065033) (xy 99.968984 -198.015285) (xy 99.953493 -197.962785) (xy 99.945665 -197.908609)
			(xy 99.94519 -197.88124) (xy 99.945773 -197.852017) (xy 99.954688 -197.794254) (xy 99.972301 -197.738525)
			(xy 99.998199 -197.686129) (xy 100.031779 -197.638292) (xy 100.051616 -197.616826) (xy 100.058474 -197.609714)
			(xy 100.06584 -197.59168) (xy 100.06584 -197.50151) (xy 100.058728 -197.483476) (xy 100.05187 -197.476364)
			(xy 100.032158 -197.454926) (xy 99.998803 -197.407188) (xy 99.973086 -197.354939) (xy 99.955601 -197.29939)
			(xy 99.946755 -197.24183) (xy 99.946206 -197.212712) (xy 99.946678 -197.185342) (xy 99.954494 -197.131163)
			(xy 99.969982 -197.07866) (xy 99.992822 -197.028913) (xy 100.022545 -196.982946) (xy 100.040186 -196.962014)
			(xy 100.046282 -196.954902) (xy 100.052632 -196.937884) (xy 100.052632 -196.85254) (xy 100.046282 -196.835522)
			(xy 100.040186 -196.82841) (xy 100.022559 -196.807467) (xy 99.992837 -196.7615) (xy 99.969993 -196.711755)
			(xy 99.954498 -196.659255) (xy 99.946669 -196.605079) (xy 99.946667 -196.550339) (xy 99.954494 -196.496163)
			(xy 99.969987 -196.443662) (xy 99.992828 -196.393916) (xy 100.022548 -196.347948) (xy 100.040186 -196.327014)
			(xy 100.046282 -196.319902) (xy 100.052632 -196.302884) (xy 100.052632 -196.21754) (xy 100.046282 -196.200522)
			(xy 100.040186 -196.19341) (xy 100.022559 -196.172467) (xy 99.992837 -196.1265) (xy 99.969993 -196.076755)
			(xy 99.954498 -196.024255) (xy 99.946669 -195.970079) (xy 99.946667 -195.915339) (xy 99.954494 -195.861163)
			(xy 99.969987 -195.808662) (xy 99.992828 -195.758916) (xy 100.022548 -195.712948) (xy 100.040186 -195.692014)
			(xy 100.046282 -195.684902) (xy 100.052632 -195.667884) (xy 100.052632 -195.58254) (xy 100.046282 -195.565522)
			(xy 100.040186 -195.55841) (xy 100.022536 -195.537487) (xy 99.992826 -195.491511) (xy 99.969993 -195.441762)
			(xy 99.954504 -195.389259) (xy 99.946679 -195.335082) (xy 99.946206 -195.307712) (xy 99.946696 -195.280413)
			(xy 99.954465 -195.226372) (xy 99.969863 -195.173992) (xy 99.992572 -195.124342) (xy 100.02213 -195.078438)
			(xy 100.039678 -195.057522) (xy 100.046028 -195.05041) (xy 100.052124 -195.033392) (xy 100.052124 -194.947794)
			(xy 100.045774 -194.93103) (xy 100.039678 -194.923918) (xy 100.021969 -194.902953) (xy 99.992091 -194.856921)
			(xy 99.969123 -194.807081) (xy 99.953542 -194.754461) (xy 99.945669 -194.700151) (xy 99.94519 -194.672712)
			(xy 99.945666 -194.64546) (xy 99.953422 -194.591509) (xy 99.968776 -194.539212) (xy 99.991417 -194.489632)
			(xy 100.020884 -194.443779) (xy 100.056576 -194.402586) (xy 100.097767 -194.366892) (xy 100.143619 -194.337424)
			(xy 100.193199 -194.314781) (xy 100.245495 -194.299425) (xy 100.299446 -194.291667) (xy 100.326698 -194.291204)
			(xy 100.354068 -194.29167) (xy 100.408247 -194.299488) (xy 100.460751 -194.314977) (xy 100.510497 -194.337819)
			(xy 100.556464 -194.367543) (xy 100.577396 -194.385184) (xy 100.584508 -194.39128) (xy 100.601526 -194.39763)
			(xy 100.68687 -194.39763) (xy 100.703888 -194.39128) (xy 100.711 -194.385184) (xy 100.731919 -194.367529)
			(xy 100.777896 -194.33782) (xy 100.827647 -194.314987) (xy 100.88015 -194.2995) (xy 100.934328 -194.291676)
			(xy 100.961698 -194.291204) (xy 100.987077 -194.291598) (xy 101.03739 -194.298291) (xy 101.086371 -194.311597)
			(xy 101.133155 -194.331283) (xy 101.155246 -194.343782) (xy 101.16693 -194.350894) (xy 101.194362 -194.351148)
			(xy 101.282754 -194.300348) (xy 101.290294 -194.295599) (xy 101.301796 -194.282007) (xy 101.307971 -194.265306)
			(xy 101.308408 -194.256406) (xy 101.308408 -181.085236) (xy 101.308876 -181.060261) (xy 101.316667 -181.010922)
			(xy 101.332079 -180.963408) (xy 101.354732 -180.91889) (xy 101.384069 -180.878463) (xy 101.401372 -180.860446)
			(xy 101.901244 -180.360574) (xy 101.908136 -180.352918) (xy 101.91582 -180.333831) (xy 101.915432 -180.31326)
			(xy 101.911658 -180.303678) (xy 101.865938 -180.202332) (xy 101.839014 -180.18633) (xy 101.823012 -180.187346)
			(xy 101.798628 -180.188108) (xy 101.771373 -180.187675) (xy 101.717416 -180.179921) (xy 101.665113 -180.164567)
			(xy 101.615527 -180.141926) (xy 101.569667 -180.112458) (xy 101.528469 -180.076764) (xy 101.49277 -180.03557)
			(xy 101.463296 -179.989714) (xy 101.440649 -179.940131) (xy 101.425289 -179.887829) (xy 101.417528 -179.833874)
			(xy 101.417526 -179.779363) (xy 101.425281 -179.725407) (xy 101.440636 -179.673104) (xy 101.463278 -179.623518)
			(xy 101.492747 -179.57766) (xy 101.528442 -179.536462) (xy 101.569638 -179.500764) (xy 101.615494 -179.471292)
			(xy 101.665078 -179.448646) (xy 101.71738 -179.433287) (xy 101.771335 -179.425528) (xy 101.825846 -179.425526)
			(xy 101.879802 -179.433283) (xy 101.932105 -179.448639) (xy 101.98169 -179.471283) (xy 102.027548 -179.500753)
			(xy 102.068744 -179.536449) (xy 102.104442 -179.577645) (xy 102.133913 -179.623502) (xy 102.156558 -179.673086)
			(xy 102.171915 -179.725389) (xy 102.179673 -179.779345) (xy 102.180136 -179.8066) (xy 102.179533 -179.837732)
			(xy 102.169461 -179.899174) (xy 102.149522 -179.958157) (xy 102.135432 -179.985924) (xy 102.127558 -180.000656)
			(xy 102.132384 -180.03393) (xy 102.144322 -180.045614) (xy 102.151756 -180.05233) (xy 102.170256 -180.059966)
			(xy 102.19027 -180.059966) (xy 102.20877 -180.05233) (xy 102.216204 -180.045614) (xy 102.336346 -179.925472)
			(xy 102.343104 -179.918096) (xy 102.350803 -179.89965) (xy 102.351332 -179.889658) (xy 102.351332 -179.355242)
			(xy 102.350889 -179.345235) (xy 102.343158 -179.326772) (xy 102.336346 -179.319428) (xy 102.30739 -179.290472)
			(xy 102.295452 -179.283868) (xy 102.288594 -179.28209) (xy 102.261191 -179.274994) (xy 102.208709 -179.253782)
			(xy 102.159939 -179.225048) (xy 102.11595 -179.189422) (xy 102.077709 -179.147686) (xy 102.046056 -179.100758)
			(xy 102.021685 -179.049667) (xy 102.005131 -178.995536) (xy 101.996759 -178.939553) (xy 101.99624 -178.91125)
			(xy 101.996702 -178.883996) (xy 102.004453 -178.830043) (xy 102.019805 -178.777742) (xy 102.042446 -178.728159)
			(xy 102.071913 -178.682303) (xy 102.107607 -178.641109) (xy 102.148801 -178.605414) (xy 102.194657 -178.575947)
			(xy 102.24424 -178.553306) (xy 102.296541 -178.537954) (xy 102.350494 -178.530202) (xy 102.377748 -178.529742)
			(xy 102.406055 -178.530228) (xy 102.462049 -178.53858) (xy 102.516192 -178.555121) (xy 102.567293 -178.579488)
			(xy 102.614228 -178.611146) (xy 102.655964 -178.649397) (xy 102.691584 -178.693401) (xy 102.720304 -178.742189)
			(xy 102.741491 -178.794689) (xy 102.748588 -178.822096) (xy 102.750366 -178.828954) (xy 102.75697 -178.840892)
			(xy 102.893876 -178.977798) (xy 102.911202 -178.995797) (xy 102.940552 -179.036221) (xy 102.963211 -179.080742)
			(xy 102.978619 -179.128263) (xy 102.986397 -179.17761) (xy 102.98684 -179.202588) (xy 102.98684 -180.042312)
			(xy 102.986388 -180.067288) (xy 102.978591 -180.116627) (xy 102.963174 -180.16414) (xy 102.940518 -180.208658)
			(xy 102.911179 -180.249085) (xy 102.893876 -180.267102) (xy 102.677468 -180.483256) (xy 102.670661 -180.490743)
			(xy 102.663023 -180.509461) (xy 102.663211 -180.529676) (xy 102.6668 -180.539136) (xy 102.709472 -180.640228)
			(xy 102.73538 -180.656992) (xy 102.751128 -180.656738) (xy 102.75697 -180.656738) (xy 102.784224 -180.657183)
			(xy 102.838178 -180.664937) (xy 102.890479 -180.680292) (xy 102.940062 -180.702934) (xy 102.985918 -180.732404)
			(xy 103.027112 -180.768099) (xy 103.062806 -180.809295) (xy 103.092273 -180.855152) (xy 103.114914 -180.904736)
			(xy 103.130266 -180.957037) (xy 103.138018 -181.010992) (xy 103.138478 -181.038246) (xy 103.137996 -181.066157)
			(xy 103.129856 -181.121383) (xy 103.113757 -181.174833) (xy 103.090043 -181.225367) (xy 103.059218 -181.271907)
			(xy 103.040942 -181.293008) (xy 103.034592 -181.30012) (xy 103.027988 -181.317392) (xy 103.027988 -181.404514)
			(xy 103.034592 -181.421786) (xy 103.040942 -181.428898) (xy 103.0592 -181.450014) (xy 103.090029 -181.496549)
			(xy 103.113747 -181.547079) (xy 103.129849 -181.600527) (xy 103.137989 -181.65575) (xy 103.138478 -181.68366)
			(xy 103.137992 -181.710911) (xy 103.130236 -181.764859) (xy 103.114881 -181.817154) (xy 103.092239 -181.866731)
			(xy 103.062773 -181.912581) (xy 103.027082 -181.953772) (xy 102.985891 -181.989463) (xy 102.940041 -182.018929)
			(xy 102.890464 -182.041571) (xy 102.838169 -182.056926) (xy 102.784221 -182.064682) (xy 102.729719 -182.064682)
			(xy 102.675771 -182.056926) (xy 102.623476 -182.041571) (xy 102.573899 -182.018929) (xy 102.528049 -181.989463)
			(xy 102.486858 -181.953772) (xy 102.451167 -181.912581) (xy 102.421701 -181.866731) (xy 102.399059 -181.817154)
			(xy 102.383704 -181.764859) (xy 102.375948 -181.710911) (xy 102.375462 -181.68366) (xy 102.375938 -181.655749)
			(xy 102.384077 -181.600522) (xy 102.400177 -181.547072) (xy 102.423894 -181.496537) (xy 102.45472 -181.449998)
			(xy 102.472998 -181.428898) (xy 102.479348 -181.421786) (xy 102.485952 -181.404514) (xy 102.485952 -181.317392)
			(xy 102.479348 -181.30012) (xy 102.472998 -181.293008) (xy 102.454702 -181.271923) (xy 102.423877 -181.225381)
			(xy 102.400165 -181.174842) (xy 102.384073 -181.121388) (xy 102.375944 -181.066158) (xy 102.375462 -181.038246)
			(xy 102.375462 -181.032404) (xy 102.375716 -181.016656) (xy 102.358952 -180.990748) (xy 102.25786 -180.948076)
			(xy 102.248386 -180.944537) (xy 102.228182 -180.944343) (xy 102.209461 -180.951941) (xy 102.20198 -180.958744)
			(xy 101.958902 -181.202076) (xy 101.952173 -181.209476) (xy 101.944456 -181.227904) (xy 101.943916 -181.23789)
			(xy 101.943916 -194.51447) (xy 101.94798 -194.524122) (xy 101.957514 -194.547723) (xy 101.970962 -194.596817)
			(xy 101.977765 -194.647261) (xy 101.978206 -194.672712) (xy 101.977653 -194.70183) (xy 101.968808 -194.759389)
			(xy 101.951324 -194.814938) (xy 101.925607 -194.867188) (xy 101.892253 -194.914926) (xy 101.872542 -194.936364)
			(xy 101.865684 -194.943476) (xy 101.858572 -194.96151) (xy 101.858572 -195.05168) (xy 101.865938 -195.069714)
			(xy 101.872796 -195.076826) (xy 101.892649 -195.09828) (xy 101.926242 -195.146114) (xy 101.952148 -195.198511)
			(xy 101.96976 -195.254246) (xy 101.978667 -195.312014) (xy 101.979222 -195.34124) (xy 101.97874 -195.36861)
			(xy 101.970929 -195.422789) (xy 101.955445 -195.475293) (xy 101.932606 -195.52504) (xy 101.902883 -195.571007)
			(xy 101.885242 -195.591938) (xy 101.879146 -195.59905) (xy 101.872796 -195.616068) (xy 101.872796 -195.701412)
			(xy 101.879146 -195.71843) (xy 101.885242 -195.725542) (xy 101.902923 -195.746442) (xy 101.932649 -195.792415)
			(xy 101.955494 -195.842166) (xy 101.966201 -195.87845) (xy 105.068624 -195.87845) (xy 105.069114 -195.851081)
			(xy 105.076925 -195.796902) (xy 105.092408 -195.744399) (xy 105.115245 -195.694652) (xy 105.144965 -195.648684)
			(xy 105.162604 -195.627752) (xy 105.1687 -195.62064) (xy 105.17505 -195.603622) (xy 105.17505 -195.518278)
			(xy 105.1687 -195.50126) (xy 105.162604 -195.494148) (xy 105.145013 -195.473175) (xy 105.115288 -195.427214)
			(xy 105.092441 -195.377474) (xy 105.076942 -195.324978) (xy 105.069109 -195.270806) (xy 105.069104 -195.21607)
			(xy 105.076926 -195.161895) (xy 105.092415 -195.109397) (xy 105.115252 -195.059652) (xy 105.144968 -195.013685)
			(xy 105.162604 -194.992752) (xy 105.1687 -194.98564) (xy 105.17505 -194.968622) (xy 105.17505 -194.883278)
			(xy 105.1687 -194.86626) (xy 105.162604 -194.859148) (xy 105.145013 -194.838175) (xy 105.115288 -194.792214)
			(xy 105.092441 -194.742474) (xy 105.076942 -194.689978) (xy 105.069109 -194.635806) (xy 105.069104 -194.58107)
			(xy 105.076926 -194.526895) (xy 105.092415 -194.474397) (xy 105.115252 -194.424652) (xy 105.144968 -194.378685)
			(xy 105.162604 -194.357752) (xy 105.1687 -194.35064) (xy 105.17505 -194.333622) (xy 105.17505 -194.248278)
			(xy 105.1687 -194.23126) (xy 105.162604 -194.224148) (xy 105.145013 -194.203175) (xy 105.115288 -194.157214)
			(xy 105.092441 -194.107474) (xy 105.076942 -194.054978) (xy 105.069109 -194.000806) (xy 105.069104 -193.94607)
			(xy 105.076926 -193.891895) (xy 105.092415 -193.839397) (xy 105.115252 -193.789652) (xy 105.144968 -193.743685)
			(xy 105.162604 -193.722752) (xy 105.1687 -193.71564) (xy 105.17505 -193.698622) (xy 105.17505 -193.613278)
			(xy 105.1687 -193.59626) (xy 105.162604 -193.589148) (xy 105.145013 -193.568175) (xy 105.115288 -193.522214)
			(xy 105.092441 -193.472474) (xy 105.076942 -193.419978) (xy 105.069109 -193.365806) (xy 105.069104 -193.31107)
			(xy 105.076926 -193.256895) (xy 105.092415 -193.204397) (xy 105.115252 -193.154652) (xy 105.144968 -193.108685)
			(xy 105.162604 -193.087752) (xy 105.1687 -193.08064) (xy 105.17505 -193.063622) (xy 105.17505 -192.978278)
			(xy 105.1687 -192.96126) (xy 105.162604 -192.954148) (xy 105.145013 -192.933175) (xy 105.115288 -192.887214)
			(xy 105.092441 -192.837474) (xy 105.076942 -192.784978) (xy 105.069109 -192.730806) (xy 105.069104 -192.67607)
			(xy 105.076926 -192.621895) (xy 105.092415 -192.569397) (xy 105.115252 -192.519652) (xy 105.144968 -192.473685)
			(xy 105.162604 -192.452752) (xy 105.1687 -192.44564) (xy 105.17505 -192.428622) (xy 105.17505 -192.343278)
			(xy 105.1687 -192.32626) (xy 105.162604 -192.319148) (xy 105.145013 -192.298175) (xy 105.115288 -192.252214)
			(xy 105.092441 -192.202474) (xy 105.076942 -192.149978) (xy 105.069109 -192.095806) (xy 105.069104 -192.04107)
			(xy 105.076926 -191.986895) (xy 105.092415 -191.934397) (xy 105.115252 -191.884652) (xy 105.144968 -191.838685)
			(xy 105.162604 -191.817752) (xy 105.1687 -191.81064) (xy 105.17505 -191.793622) (xy 105.17505 -191.708278)
			(xy 105.1687 -191.69126) (xy 105.162604 -191.684148) (xy 105.145013 -191.663175) (xy 105.115288 -191.617214)
			(xy 105.092441 -191.567474) (xy 105.076942 -191.514978) (xy 105.069109 -191.460806) (xy 105.069104 -191.40607)
			(xy 105.076926 -191.351895) (xy 105.092415 -191.299397) (xy 105.115252 -191.249652) (xy 105.144968 -191.203685)
			(xy 105.162604 -191.182752) (xy 105.1687 -191.17564) (xy 105.17505 -191.158622) (xy 105.17505 -191.073278)
			(xy 105.1687 -191.05626) (xy 105.162604 -191.049148) (xy 105.144975 -191.028208) (xy 105.115261 -190.982238)
			(xy 105.092423 -190.932492) (xy 105.07693 -190.879993) (xy 105.069099 -190.825819) (xy 105.068624 -190.79845)
			(xy 105.069135 -190.770647) (xy 105.077207 -190.715631) (xy 105.093173 -190.662367) (xy 105.116695 -190.611982)
			(xy 105.147276 -190.565541) (xy 105.165398 -190.54445) (xy 105.171748 -190.537338) (xy 105.178352 -190.520066)
			(xy 105.178352 -190.433706) (xy 105.171748 -190.416434) (xy 105.165398 -190.409322) (xy 105.14729 -190.388219)
			(xy 105.116699 -190.341785) (xy 105.093169 -190.291403) (xy 105.0772 -190.238141) (xy 105.069128 -190.183125)
			(xy 105.068624 -190.155322) (xy 105.069076 -190.128068) (xy 105.076831 -190.074115) (xy 105.092186 -190.021815)
			(xy 105.114828 -189.972233) (xy 105.144297 -189.926378) (xy 105.179992 -189.885184) (xy 105.221186 -189.849491)
			(xy 105.267042 -189.820023) (xy 105.316625 -189.797382) (xy 105.368925 -189.782029) (xy 105.422878 -189.774275)
			(xy 105.450132 -189.773814) (xy 105.477503 -189.774258) (xy 105.531683 -189.782081) (xy 105.584187 -189.797575)
			(xy 105.633933 -189.820421) (xy 105.679899 -189.850151) (xy 105.70083 -189.867794) (xy 105.707942 -189.87389)
			(xy 105.72496 -189.88024) (xy 105.810304 -189.88024) (xy 105.827322 -189.87389) (xy 105.834434 -189.867794)
			(xy 105.855367 -189.850153) (xy 105.901335 -189.820429) (xy 105.951081 -189.797583) (xy 106.003583 -189.782087)
			(xy 106.057761 -189.774258) (xy 106.112503 -189.774258) (xy 106.166681 -189.782087) (xy 106.219183 -189.797583)
			(xy 106.268929 -189.820429) (xy 106.314897 -189.850153) (xy 106.33583 -189.867794) (xy 106.342942 -189.87389)
			(xy 106.35996 -189.88024) (xy 106.445304 -189.88024) (xy 106.462322 -189.87389) (xy 106.469434 -189.867794)
			(xy 106.490379 -189.850171) (xy 106.536349 -189.820457) (xy 106.586093 -189.797618) (xy 106.63859 -189.782123)
			(xy 106.692764 -189.774291) (xy 106.720132 -189.773814) (xy 106.747385 -189.774248) (xy 106.801336 -189.78201)
			(xy 106.853633 -189.79737) (xy 106.903212 -189.820016) (xy 106.949063 -189.849488) (xy 106.990253 -189.885185)
			(xy 107.025944 -189.92638) (xy 107.05541 -189.972236) (xy 107.078049 -190.021818) (xy 107.093402 -190.074117)
			(xy 107.101156 -190.128069) (xy 107.10164 -190.155322) (xy 109.081824 -190.155322) (xy 109.082276 -190.128068)
			(xy 109.090031 -190.074115) (xy 109.105386 -190.021815) (xy 109.128028 -189.972233) (xy 109.157497 -189.926378)
			(xy 109.193192 -189.885184) (xy 109.234386 -189.849491) (xy 109.280242 -189.820023) (xy 109.329825 -189.797382)
			(xy 109.382125 -189.782029) (xy 109.436078 -189.774275) (xy 109.463332 -189.773814) (xy 109.490576 -189.774282)
			(xy 109.544507 -189.78206) (xy 109.570774 -189.789308) (xy 109.583728 -189.793118) (xy 109.60989 -189.786768)
			(xy 109.69371 -189.708028) (xy 109.70133 -189.682374) (xy 109.698282 -189.668912) (xy 109.694558 -189.65137)
			(xy 109.690612 -189.615724) (xy 109.690408 -189.597792) (xy 109.690408 -176.564036) (xy 109.690876 -176.539061)
			(xy 109.698667 -176.489722) (xy 109.714079 -176.442208) (xy 109.736732 -176.39769) (xy 109.766069 -176.357263)
			(xy 109.783372 -176.339246) (xy 110.283244 -175.839374) (xy 110.290136 -175.831718) (xy 110.29782 -175.812631)
			(xy 110.297432 -175.79206) (xy 110.293658 -175.782478) (xy 110.247938 -175.681132) (xy 110.221014 -175.66513)
			(xy 110.205012 -175.666146) (xy 110.180628 -175.666908) (xy 110.153373 -175.666475) (xy 110.099416 -175.658721)
			(xy 110.047113 -175.643367) (xy 109.997527 -175.620726) (xy 109.951667 -175.591258) (xy 109.910469 -175.555564)
			(xy 109.87477 -175.51437) (xy 109.845296 -175.468514) (xy 109.822649 -175.418931) (xy 109.807289 -175.366629)
			(xy 109.799528 -175.312674) (xy 109.799526 -175.258163) (xy 109.807281 -175.204207) (xy 109.822636 -175.151904)
			(xy 109.845278 -175.102318) (xy 109.874747 -175.05646) (xy 109.910442 -175.015262) (xy 109.951638 -174.979564)
			(xy 109.997494 -174.950092) (xy 110.047078 -174.927446) (xy 110.09938 -174.912087) (xy 110.153335 -174.904328)
			(xy 110.207846 -174.904326) (xy 110.261802 -174.912083) (xy 110.314105 -174.927439) (xy 110.36369 -174.950083)
			(xy 110.409548 -174.979553) (xy 110.450744 -175.015249) (xy 110.486442 -175.056445) (xy 110.515913 -175.102302)
			(xy 110.538558 -175.151886) (xy 110.553915 -175.204189) (xy 110.561673 -175.258145) (xy 110.562136 -175.2854)
			(xy 110.561533 -175.316532) (xy 110.551461 -175.377974) (xy 110.531522 -175.436957) (xy 110.517432 -175.464724)
			(xy 110.509558 -175.479456) (xy 110.514384 -175.51273) (xy 110.526322 -175.524414) (xy 110.533756 -175.53113)
			(xy 110.552256 -175.538766) (xy 110.57227 -175.538766) (xy 110.59077 -175.53113) (xy 110.598204 -175.524414)
			(xy 110.718346 -175.404272) (xy 110.725104 -175.396896) (xy 110.732803 -175.37845) (xy 110.733332 -175.368458)
			(xy 110.733332 -174.834042) (xy 110.732889 -174.824035) (xy 110.725158 -174.805572) (xy 110.718346 -174.798228)
			(xy 110.68939 -174.769272) (xy 110.677452 -174.762668) (xy 110.670594 -174.76089) (xy 110.643191 -174.753794)
			(xy 110.590709 -174.732582) (xy 110.541939 -174.703848) (xy 110.49795 -174.668222) (xy 110.459709 -174.626486)
			(xy 110.428056 -174.579558) (xy 110.403685 -174.528467) (xy 110.387131 -174.474336) (xy 110.378759 -174.418353)
			(xy 110.37824 -174.39005) (xy 110.378702 -174.362796) (xy 110.386453 -174.308843) (xy 110.401805 -174.256542)
			(xy 110.424446 -174.206959) (xy 110.453913 -174.161103) (xy 110.489607 -174.119909) (xy 110.530801 -174.084214)
			(xy 110.576657 -174.054747) (xy 110.62624 -174.032106) (xy 110.678541 -174.016754) (xy 110.732494 -174.009002)
			(xy 110.759748 -174.008542) (xy 110.788055 -174.009028) (xy 110.844049 -174.01738) (xy 110.898192 -174.033921)
			(xy 110.949293 -174.058288) (xy 110.996228 -174.089946) (xy 111.037964 -174.128197) (xy 111.073584 -174.172201)
			(xy 111.102304 -174.220989) (xy 111.123491 -174.273489) (xy 111.130588 -174.300896) (xy 111.132366 -174.307754)
			(xy 111.13897 -174.319692) (xy 111.275876 -174.456598) (xy 111.293202 -174.474597) (xy 111.322552 -174.515021)
			(xy 111.345211 -174.559542) (xy 111.360619 -174.607063) (xy 111.368397 -174.65641) (xy 111.36884 -174.681388)
			(xy 111.36884 -175.521112) (xy 111.368388 -175.546088) (xy 111.360591 -175.595427) (xy 111.345174 -175.64294)
			(xy 111.322518 -175.687458) (xy 111.293179 -175.727885) (xy 111.275876 -175.745902) (xy 111.059468 -175.962056)
			(xy 111.052661 -175.969543) (xy 111.045023 -175.988261) (xy 111.045211 -176.008476) (xy 111.0488 -176.017936)
			(xy 111.091472 -176.119028) (xy 111.11738 -176.135792) (xy 111.133128 -176.135538) (xy 111.13897 -176.135538)
			(xy 111.166224 -176.135983) (xy 111.220178 -176.143737) (xy 111.272479 -176.159092) (xy 111.322062 -176.181734)
			(xy 111.367918 -176.211204) (xy 111.409112 -176.246899) (xy 111.444806 -176.288095) (xy 111.474273 -176.333952)
			(xy 111.496914 -176.383536) (xy 111.512266 -176.435837) (xy 111.520018 -176.489792) (xy 111.520478 -176.517046)
			(xy 111.519996 -176.544957) (xy 111.511856 -176.600183) (xy 111.495757 -176.653633) (xy 111.472043 -176.704167)
			(xy 111.441218 -176.750707) (xy 111.422942 -176.771808) (xy 111.416592 -176.77892) (xy 111.409988 -176.796192)
			(xy 111.409988 -176.883314) (xy 111.416592 -176.900586) (xy 111.422942 -176.907698) (xy 111.4412 -176.928814)
			(xy 111.472029 -176.975349) (xy 111.495747 -177.025879) (xy 111.511849 -177.079327) (xy 111.519989 -177.13455)
			(xy 111.520478 -177.16246) (xy 111.519992 -177.189711) (xy 111.512236 -177.243659) (xy 111.496881 -177.295954)
			(xy 111.474239 -177.345531) (xy 111.444773 -177.391381) (xy 111.409082 -177.432572) (xy 111.367891 -177.468263)
			(xy 111.322041 -177.497729) (xy 111.272464 -177.520371) (xy 111.220169 -177.535726) (xy 111.166221 -177.543482)
			(xy 111.111719 -177.543482) (xy 111.057771 -177.535726) (xy 111.005476 -177.520371) (xy 110.955899 -177.497729)
			(xy 110.910049 -177.468263) (xy 110.868858 -177.432572) (xy 110.833167 -177.391381) (xy 110.803701 -177.345531)
			(xy 110.781059 -177.295954) (xy 110.765704 -177.243659) (xy 110.757948 -177.189711) (xy 110.757462 -177.16246)
			(xy 110.757938 -177.134549) (xy 110.766077 -177.079322) (xy 110.782177 -177.025872) (xy 110.805894 -176.975337)
			(xy 110.83672 -176.928798) (xy 110.854998 -176.907698) (xy 110.861348 -176.900586) (xy 110.867952 -176.883314)
			(xy 110.867952 -176.796192) (xy 110.861348 -176.77892) (xy 110.854998 -176.771808) (xy 110.836702 -176.750723)
			(xy 110.805877 -176.704181) (xy 110.782165 -176.653642) (xy 110.766073 -176.600188) (xy 110.757944 -176.544958)
			(xy 110.757462 -176.517046) (xy 110.757462 -176.511204) (xy 110.757716 -176.495456) (xy 110.740952 -176.469548)
			(xy 110.63986 -176.426876) (xy 110.630386 -176.423337) (xy 110.610182 -176.423143) (xy 110.591461 -176.430741)
			(xy 110.58398 -176.437544) (xy 110.340902 -176.680876) (xy 110.334173 -176.688276) (xy 110.326456 -176.706704)
			(xy 110.325916 -176.71669) (xy 110.325916 -188.38164) (xy 113.076736 -188.38164) (xy 113.077217 -188.35427)
			(xy 113.08503 -188.300091) (xy 113.100515 -188.247588) (xy 113.123354 -188.197841) (xy 113.153076 -188.151874)
			(xy 113.170716 -188.130942) (xy 113.176812 -188.12383) (xy 113.183162 -188.106812) (xy 113.183162 -188.021468)
			(xy 113.176812 -188.00445) (xy 113.170716 -187.997338) (xy 113.153115 -187.976373) (xy 113.123389 -187.930411)
			(xy 113.100542 -187.88067) (xy 113.085043 -187.828173) (xy 113.077211 -187.773999) (xy 113.077207 -187.719262)
			(xy 113.085031 -187.665086) (xy 113.100521 -187.612587) (xy 113.12336 -187.562842) (xy 113.153079 -187.516875)
			(xy 113.170716 -187.495942) (xy 113.176812 -187.48883) (xy 113.183162 -187.471812) (xy 113.183162 -187.386468)
			(xy 113.176812 -187.36945) (xy 113.170716 -187.362338) (xy 113.153115 -187.341373) (xy 113.123389 -187.295411)
			(xy 113.100542 -187.24567) (xy 113.085043 -187.193173) (xy 113.077211 -187.138999) (xy 113.077207 -187.084262)
			(xy 113.085031 -187.030086) (xy 113.100521 -186.977587) (xy 113.12336 -186.927842) (xy 113.153079 -186.881875)
			(xy 113.170716 -186.860942) (xy 113.176812 -186.85383) (xy 113.183162 -186.836812) (xy 113.183162 -186.751468)
			(xy 113.176812 -186.73445) (xy 113.170716 -186.727338) (xy 113.153115 -186.706373) (xy 113.123389 -186.660411)
			(xy 113.100542 -186.61067) (xy 113.085043 -186.558173) (xy 113.077211 -186.503999) (xy 113.077207 -186.449262)
			(xy 113.085031 -186.395086) (xy 113.100521 -186.342587) (xy 113.12336 -186.292842) (xy 113.153079 -186.246875)
			(xy 113.170716 -186.225942) (xy 113.176812 -186.21883) (xy 113.183162 -186.201812) (xy 113.183162 -186.116468)
			(xy 113.176812 -186.09945) (xy 113.170716 -186.092338) (xy 113.153115 -186.071373) (xy 113.123389 -186.025411)
			(xy 113.100542 -185.97567) (xy 113.085043 -185.923173) (xy 113.077211 -185.868999) (xy 113.077207 -185.814262)
			(xy 113.085031 -185.760086) (xy 113.100521 -185.707587) (xy 113.12336 -185.657842) (xy 113.153079 -185.611875)
			(xy 113.170716 -185.590942) (xy 113.176812 -185.58383) (xy 113.183162 -185.566812) (xy 113.183162 -185.481468)
			(xy 113.176812 -185.46445) (xy 113.170716 -185.457338) (xy 113.153115 -185.436373) (xy 113.123389 -185.390411)
			(xy 113.100542 -185.34067) (xy 113.085043 -185.288173) (xy 113.077211 -185.233999) (xy 113.077207 -185.179262)
			(xy 113.085031 -185.125086) (xy 113.100521 -185.072587) (xy 113.12336 -185.022842) (xy 113.153079 -184.976875)
			(xy 113.170716 -184.955942) (xy 113.176812 -184.94883) (xy 113.183162 -184.931812) (xy 113.183162 -184.846468)
			(xy 113.176812 -184.82945) (xy 113.170716 -184.822338) (xy 113.153084 -184.8014) (xy 113.12337 -184.755429)
			(xy 113.100533 -184.705683) (xy 113.08504 -184.653184) (xy 113.077211 -184.599009) (xy 113.076736 -184.57164)
			(xy 113.077279 -184.542473) (xy 113.086176 -184.484823) (xy 113.103752 -184.429201) (xy 113.129598 -184.376906)
			(xy 113.163111 -184.32916) (xy 113.182908 -184.307734) (xy 113.189766 -184.300368) (xy 113.196878 -184.282588)
			(xy 113.196878 -184.192164) (xy 113.189766 -184.174384) (xy 113.182908 -184.167018) (xy 113.163125 -184.145584)
			(xy 113.12964 -184.097826) (xy 113.103808 -184.045531) (xy 113.086229 -183.989916) (xy 113.077311 -183.932275)
			(xy 113.076736 -183.903112) (xy 113.077167 -183.875857) (xy 113.084923 -183.821903) (xy 113.10028 -183.769602)
			(xy 113.122924 -183.720019) (xy 113.152395 -183.674164) (xy 113.188092 -183.63297) (xy 113.229289 -183.597276)
			(xy 113.275147 -183.567809) (xy 113.324732 -183.545169) (xy 113.377034 -183.529816) (xy 113.430989 -183.522064)
			(xy 113.458244 -183.521604) (xy 113.485613 -183.522102) (xy 113.539791 -183.529912) (xy 113.592294 -183.545393)
			(xy 113.642041 -183.568228) (xy 113.688009 -183.597946) (xy 113.708942 -183.615584) (xy 113.716054 -183.62168)
			(xy 113.733072 -183.62803) (xy 113.818416 -183.62803) (xy 113.835434 -183.62168) (xy 113.842546 -183.615584)
			(xy 113.863479 -183.597943) (xy 113.909447 -183.568219) (xy 113.959193 -183.545373) (xy 114.011695 -183.529877)
			(xy 114.065873 -183.522048) (xy 114.120615 -183.522048) (xy 114.174793 -183.529877) (xy 114.227295 -183.545373)
			(xy 114.277041 -183.568219) (xy 114.323009 -183.597943) (xy 114.343942 -183.615584) (xy 114.351054 -183.62168)
			(xy 114.368072 -183.62803) (xy 114.453416 -183.62803) (xy 114.470434 -183.62168) (xy 114.477546 -183.615584)
			(xy 114.498486 -183.597954) (xy 114.544457 -183.568242) (xy 114.594202 -183.545404) (xy 114.646701 -183.529911)
			(xy 114.700875 -183.52208) (xy 114.728244 -183.521604) (xy 114.755497 -183.522037) (xy 114.809447 -183.5298)
			(xy 114.861744 -183.545161) (xy 114.911322 -183.567808) (xy 114.957173 -183.59728) (xy 114.998363 -183.632977)
			(xy 115.034053 -183.674172) (xy 115.063519 -183.720027) (xy 115.086159 -183.769609) (xy 115.101512 -183.821908)
			(xy 115.109267 -183.875859) (xy 115.109752 -183.903112) (xy 117.089936 -183.903112) (xy 117.090367 -183.875857)
			(xy 117.098123 -183.821903) (xy 117.11348 -183.769602) (xy 117.136124 -183.720019) (xy 117.165595 -183.674164)
			(xy 117.201292 -183.63297) (xy 117.242489 -183.597276) (xy 117.288347 -183.567809) (xy 117.337932 -183.545169)
			(xy 117.390234 -183.529816) (xy 117.444189 -183.522064) (xy 117.471444 -183.521604) (xy 117.498813 -183.522102)
			(xy 117.552991 -183.529912) (xy 117.605494 -183.545393) (xy 117.655241 -183.568228) (xy 117.701209 -183.597946)
			(xy 117.722142 -183.615584) (xy 117.729254 -183.62168) (xy 117.746272 -183.62803) (xy 117.831616 -183.62803)
			(xy 117.848634 -183.62168) (xy 117.855746 -183.615584) (xy 117.876686 -183.597954) (xy 117.922657 -183.568242)
			(xy 117.972402 -183.545404) (xy 118.024901 -183.529911) (xy 118.079075 -183.52208) (xy 118.106444 -183.521604)
			(xy 118.135864 -183.522152) (xy 118.194004 -183.531197) (xy 118.25006 -183.549079) (xy 118.276624 -183.561736)
			(xy 118.288562 -183.567578) (xy 118.314724 -183.566308) (xy 118.39956 -183.513984) (xy 118.406658 -183.509105)
			(xy 118.417388 -183.495649) (xy 118.423089 -183.479409) (xy 118.423436 -183.470804) (xy 118.423436 -183.444388)
			(xy 118.422983 -183.434418) (xy 118.415392 -183.415982) (xy 118.408704 -183.408574) (xy 118.022624 -183.022494)
			(xy 118.005295 -183.004499) (xy 117.975944 -182.964074) (xy 117.953286 -182.919551) (xy 117.937879 -182.87203)
			(xy 117.930103 -182.822683) (xy 117.92966 -182.797704) (xy 117.92966 -170.305984) (xy 117.93011 -170.281008)
			(xy 117.937907 -170.231669) (xy 117.953324 -170.184156) (xy 117.975981 -170.139638) (xy 118.00532 -170.099211)
			(xy 118.022624 -170.081194) (xy 118.512844 -169.590974) (xy 118.519736 -169.583318) (xy 118.52742 -169.564231)
			(xy 118.527032 -169.54366) (xy 118.523258 -169.534078) (xy 118.477538 -169.432732) (xy 118.450614 -169.41673)
			(xy 118.434612 -169.417746) (xy 118.410228 -169.418508) (xy 118.382973 -169.418075) (xy 118.329016 -169.410321)
			(xy 118.276713 -169.394967) (xy 118.227127 -169.372326) (xy 118.181267 -169.342858) (xy 118.140069 -169.307164)
			(xy 118.10437 -169.26597) (xy 118.074896 -169.220114) (xy 118.052249 -169.170531) (xy 118.036889 -169.118229)
			(xy 118.029128 -169.064274) (xy 118.029126 -169.009763) (xy 118.036881 -168.955807) (xy 118.052236 -168.903504)
			(xy 118.074878 -168.853918) (xy 118.104347 -168.80806) (xy 118.140042 -168.766862) (xy 118.181238 -168.731164)
			(xy 118.227094 -168.701692) (xy 118.276678 -168.679046) (xy 118.32898 -168.663687) (xy 118.382935 -168.655928)
			(xy 118.437446 -168.655926) (xy 118.491402 -168.663683) (xy 118.543705 -168.679039) (xy 118.59329 -168.701683)
			(xy 118.639148 -168.731153) (xy 118.680344 -168.766849) (xy 118.716042 -168.808045) (xy 118.745513 -168.853902)
			(xy 118.768158 -168.903486) (xy 118.783515 -168.955789) (xy 118.791273 -169.009745) (xy 118.791736 -169.037)
			(xy 118.791133 -169.068132) (xy 118.781061 -169.129574) (xy 118.761122 -169.188557) (xy 118.747032 -169.216324)
			(xy 118.739158 -169.231056) (xy 118.743984 -169.26433) (xy 118.755922 -169.276014) (xy 118.763356 -169.28273)
			(xy 118.781856 -169.290366) (xy 118.80187 -169.290366) (xy 118.82037 -169.28273) (xy 118.827804 -169.276014)
			(xy 118.947946 -169.155872) (xy 118.954704 -169.148496) (xy 118.962403 -169.13005) (xy 118.962932 -169.120058)
			(xy 118.962932 -168.585642) (xy 118.962489 -168.575635) (xy 118.954758 -168.557172) (xy 118.947946 -168.549828)
			(xy 118.91899 -168.520872) (xy 118.907052 -168.514268) (xy 118.900194 -168.51249) (xy 118.872791 -168.505394)
			(xy 118.820309 -168.484182) (xy 118.771539 -168.455448) (xy 118.72755 -168.419822) (xy 118.689309 -168.378086)
			(xy 118.657656 -168.331158) (xy 118.633285 -168.280067) (xy 118.616731 -168.225936) (xy 118.608359 -168.169953)
			(xy 118.60784 -168.14165) (xy 118.608302 -168.114396) (xy 118.616053 -168.060443) (xy 118.631405 -168.008142)
			(xy 118.654046 -167.958559) (xy 118.683513 -167.912703) (xy 118.719207 -167.871509) (xy 118.760401 -167.835814)
			(xy 118.806257 -167.806347) (xy 118.85584 -167.783706) (xy 118.908141 -167.768354) (xy 118.962094 -167.760602)
			(xy 118.989348 -167.760142) (xy 119.017655 -167.760628) (xy 119.073649 -167.76898) (xy 119.127792 -167.785521)
			(xy 119.178893 -167.809888) (xy 119.225828 -167.841546) (xy 119.267564 -167.879797) (xy 119.303184 -167.923801)
			(xy 119.331904 -167.972589) (xy 119.353091 -168.025089) (xy 119.360188 -168.052496) (xy 119.361966 -168.059354)
			(xy 119.36857 -168.071292) (xy 119.505476 -168.208198) (xy 119.522802 -168.226197) (xy 119.552152 -168.266621)
			(xy 119.574811 -168.311142) (xy 119.590219 -168.358663) (xy 119.597997 -168.40801) (xy 119.59844 -168.432988)
			(xy 119.59844 -169.272712) (xy 119.597988 -169.297688) (xy 119.590191 -169.347027) (xy 119.574774 -169.39454)
			(xy 119.552118 -169.439058) (xy 119.522779 -169.479485) (xy 119.505476 -169.497502) (xy 119.289068 -169.713656)
			(xy 119.282261 -169.721143) (xy 119.274623 -169.739861) (xy 119.274811 -169.760076) (xy 119.2784 -169.769536)
			(xy 119.321072 -169.870628) (xy 119.34698 -169.887392) (xy 119.362728 -169.887138) (xy 119.36857 -169.887138)
			(xy 119.395824 -169.887583) (xy 119.449778 -169.895337) (xy 119.502079 -169.910692) (xy 119.551662 -169.933334)
			(xy 119.597518 -169.962804) (xy 119.638712 -169.998499) (xy 119.674406 -170.039695) (xy 119.703873 -170.085552)
			(xy 119.726514 -170.135136) (xy 119.741866 -170.187437) (xy 119.749618 -170.241392) (xy 119.750078 -170.268646)
			(xy 119.749596 -170.296557) (xy 119.741456 -170.351783) (xy 119.725357 -170.405233) (xy 119.701643 -170.455767)
			(xy 119.670818 -170.502307) (xy 119.652542 -170.523408) (xy 119.646192 -170.53052) (xy 119.639588 -170.547792)
			(xy 119.639588 -170.634914) (xy 119.646192 -170.652186) (xy 119.652542 -170.659298) (xy 119.6708 -170.680414)
			(xy 119.701629 -170.726949) (xy 119.725347 -170.777479) (xy 119.741449 -170.830927) (xy 119.749589 -170.88615)
			(xy 119.750078 -170.91406) (xy 119.749592 -170.941311) (xy 119.741836 -170.995259) (xy 119.726481 -171.047554)
			(xy 119.703839 -171.097131) (xy 119.674373 -171.142981) (xy 119.638682 -171.184172) (xy 119.597491 -171.219863)
			(xy 119.551641 -171.249329) (xy 119.502064 -171.271971) (xy 119.449769 -171.287326) (xy 119.395821 -171.295082)
			(xy 119.341319 -171.295082) (xy 119.287371 -171.287326) (xy 119.235076 -171.271971) (xy 119.185499 -171.249329)
			(xy 119.139649 -171.219863) (xy 119.098458 -171.184172) (xy 119.062767 -171.142981) (xy 119.033301 -171.097131)
			(xy 119.010659 -171.047554) (xy 118.995304 -170.995259) (xy 118.987548 -170.941311) (xy 118.987062 -170.91406)
			(xy 118.987538 -170.886149) (xy 118.995677 -170.830922) (xy 119.011777 -170.777472) (xy 119.035494 -170.726937)
			(xy 119.06632 -170.680398) (xy 119.084598 -170.659298) (xy 119.090948 -170.652186) (xy 119.097552 -170.634914)
			(xy 119.097552 -170.547792) (xy 119.090948 -170.53052) (xy 119.084598 -170.523408) (xy 119.066302 -170.502323)
			(xy 119.035477 -170.455781) (xy 119.011765 -170.405242) (xy 118.995673 -170.351788) (xy 118.987544 -170.296558)
			(xy 118.987062 -170.268646) (xy 118.987062 -170.262804) (xy 118.987316 -170.247056) (xy 118.970552 -170.221148)
			(xy 118.86946 -170.178476) (xy 118.859986 -170.174937) (xy 118.839782 -170.174743) (xy 118.821061 -170.182341)
			(xy 118.81358 -170.189144) (xy 118.580154 -170.422824) (xy 118.573398 -170.430202) (xy 118.565698 -170.448647)
			(xy 118.565168 -170.458638) (xy 118.565168 -182.28564) (xy 121.299224 -182.28564) (xy 121.299708 -182.25827)
			(xy 121.30752 -182.204092) (xy 121.323005 -182.151589) (xy 121.345843 -182.101841) (xy 121.375564 -182.055874)
			(xy 121.393204 -182.034942) (xy 121.3993 -182.02783) (xy 121.40565 -182.010812) (xy 121.40565 -181.925468)
			(xy 121.3993 -181.90845) (xy 121.393204 -181.901338) (xy 121.375603 -181.880373) (xy 121.345879 -181.83441)
			(xy 121.323032 -181.784669) (xy 121.307534 -181.732172) (xy 121.299702 -181.677999) (xy 121.299698 -181.623262)
			(xy 121.307521 -181.569087) (xy 121.323011 -181.516587) (xy 121.34585 -181.466843) (xy 121.375567 -181.420875)
			(xy 121.393204 -181.399942) (xy 121.3993 -181.39283) (xy 121.40565 -181.375812) (xy 121.40565 -181.290468)
			(xy 121.3993 -181.27345) (xy 121.393204 -181.266338) (xy 121.375603 -181.245373) (xy 121.345879 -181.19941)
			(xy 121.323032 -181.149669) (xy 121.307534 -181.097172) (xy 121.299702 -181.042999) (xy 121.299698 -180.988262)
			(xy 121.307521 -180.934087) (xy 121.323011 -180.881587) (xy 121.34585 -180.831843) (xy 121.375567 -180.785875)
			(xy 121.393204 -180.764942) (xy 121.3993 -180.75783) (xy 121.40565 -180.740812) (xy 121.40565 -180.655468)
			(xy 121.3993 -180.63845) (xy 121.393204 -180.631338) (xy 121.375603 -180.610373) (xy 121.345879 -180.56441)
			(xy 121.323032 -180.514669) (xy 121.307534 -180.462172) (xy 121.299702 -180.407999) (xy 121.299698 -180.353262)
			(xy 121.307521 -180.299087) (xy 121.323011 -180.246587) (xy 121.34585 -180.196843) (xy 121.375567 -180.150875)
			(xy 121.393204 -180.129942) (xy 121.3993 -180.12283) (xy 121.40565 -180.105812) (xy 121.40565 -180.020468)
			(xy 121.3993 -180.00345) (xy 121.393204 -179.996338) (xy 121.375603 -179.975373) (xy 121.345879 -179.92941)
			(xy 121.323032 -179.879669) (xy 121.307534 -179.827172) (xy 121.299702 -179.772999) (xy 121.299698 -179.718262)
			(xy 121.307521 -179.664087) (xy 121.323011 -179.611587) (xy 121.34585 -179.561843) (xy 121.375567 -179.515875)
			(xy 121.393204 -179.494942) (xy 121.3993 -179.48783) (xy 121.40565 -179.470812) (xy 121.40565 -179.385468)
			(xy 121.3993 -179.36845) (xy 121.393204 -179.361338) (xy 121.375603 -179.340373) (xy 121.345879 -179.29441)
			(xy 121.323032 -179.244669) (xy 121.307534 -179.192172) (xy 121.299702 -179.137999) (xy 121.299698 -179.083262)
			(xy 121.307521 -179.029087) (xy 121.323011 -178.976587) (xy 121.34585 -178.926843) (xy 121.375567 -178.880875)
			(xy 121.393204 -178.859942) (xy 121.3993 -178.85283) (xy 121.40565 -178.835812) (xy 121.40565 -178.750468)
			(xy 121.3993 -178.73345) (xy 121.393204 -178.726338) (xy 121.375603 -178.705373) (xy 121.345879 -178.65941)
			(xy 121.323032 -178.609669) (xy 121.307534 -178.557172) (xy 121.299702 -178.502999) (xy 121.299698 -178.448262)
			(xy 121.307521 -178.394087) (xy 121.323011 -178.341587) (xy 121.34585 -178.291843) (xy 121.375567 -178.245875)
			(xy 121.393204 -178.224942) (xy 121.3993 -178.21783) (xy 121.40565 -178.200812) (xy 121.40565 -178.115468)
			(xy 121.3993 -178.09845) (xy 121.393204 -178.091338) (xy 121.37557 -178.070402) (xy 121.345857 -178.02443)
			(xy 121.32302 -177.974684) (xy 121.307528 -177.922184) (xy 121.299699 -177.868009) (xy 121.299224 -177.84064)
			(xy 121.29977 -177.811474) (xy 121.308667 -177.753823) (xy 121.326243 -177.698201) (xy 121.352088 -177.645906)
			(xy 121.385599 -177.59816) (xy 121.405396 -177.576734) (xy 121.412254 -177.569368) (xy 121.419366 -177.551588)
			(xy 121.419366 -177.461164) (xy 121.412254 -177.443384) (xy 121.405396 -177.436018) (xy 121.385611 -177.414586)
			(xy 121.352127 -177.366827) (xy 121.326295 -177.314532) (xy 121.308716 -177.258917) (xy 121.299799 -177.201275)
			(xy 121.299224 -177.172112) (xy 121.299667 -177.144858) (xy 121.307423 -177.090905) (xy 121.322779 -177.038604)
			(xy 121.345422 -176.989022) (xy 121.374892 -176.943168) (xy 121.410588 -176.901974) (xy 121.451784 -176.86628)
			(xy 121.49764 -176.836813) (xy 121.547223 -176.814172) (xy 121.599524 -176.798818) (xy 121.653478 -176.791065)
			(xy 121.680732 -176.790604) (xy 121.708103 -176.79105) (xy 121.762283 -176.798873) (xy 121.814786 -176.814366)
			(xy 121.864533 -176.837213) (xy 121.910499 -176.866941) (xy 121.93143 -176.884584) (xy 121.938542 -176.89068)
			(xy 121.95556 -176.89703) (xy 122.040904 -176.89703) (xy 122.057922 -176.89068) (xy 122.065034 -176.884584)
			(xy 122.085967 -176.866943) (xy 122.131935 -176.837219) (xy 122.181681 -176.814373) (xy 122.234183 -176.798877)
			(xy 122.288361 -176.791048) (xy 122.343103 -176.791048) (xy 122.397281 -176.798877) (xy 122.449783 -176.814373)
			(xy 122.499529 -176.837219) (xy 122.545497 -176.866943) (xy 122.56643 -176.884584) (xy 122.573542 -176.89068)
			(xy 122.59056 -176.89703) (xy 122.675904 -176.89703) (xy 122.692922 -176.89068) (xy 122.700034 -176.884584)
			(xy 122.720978 -176.86696) (xy 122.766948 -176.837246) (xy 122.816692 -176.814408) (xy 122.86919 -176.798913)
			(xy 122.923364 -176.791081) (xy 122.950732 -176.790604) (xy 122.977985 -176.791048) (xy 123.031934 -176.798809)
			(xy 123.084231 -176.814169) (xy 123.133809 -176.836815) (xy 123.17966 -176.866286) (xy 123.22085 -176.901981)
			(xy 123.256541 -176.943176) (xy 123.286006 -176.98903) (xy 123.308646 -177.038611) (xy 123.324 -177.090909)
			(xy 123.331755 -177.144859) (xy 123.33224 -177.172112) (xy 125.312424 -177.172112) (xy 125.312867 -177.144858)
			(xy 125.320623 -177.090905) (xy 125.335979 -177.038604) (xy 125.358622 -176.989022) (xy 125.388092 -176.943168)
			(xy 125.423788 -176.901974) (xy 125.464984 -176.86628) (xy 125.51084 -176.836813) (xy 125.560423 -176.814172)
			(xy 125.612724 -176.798818) (xy 125.666678 -176.791065) (xy 125.693932 -176.790604) (xy 125.721303 -176.79105)
			(xy 125.775483 -176.798873) (xy 125.827986 -176.814366) (xy 125.877733 -176.837213) (xy 125.923699 -176.866941)
			(xy 125.94463 -176.884584) (xy 125.951742 -176.89068) (xy 125.96876 -176.89703) (xy 126.054104 -176.89703)
			(xy 126.071122 -176.89068) (xy 126.078234 -176.884584) (xy 126.099178 -176.86696) (xy 126.145148 -176.837246)
			(xy 126.194892 -176.814408) (xy 126.24739 -176.798913) (xy 126.301564 -176.791081) (xy 126.328932 -176.790604)
			(xy 126.358352 -176.791157) (xy 126.416492 -176.8002) (xy 126.472548 -176.81808) (xy 126.499112 -176.830736)
			(xy 126.51105 -176.836578) (xy 126.537212 -176.835308) (xy 126.622048 -176.782984) (xy 126.629143 -176.778102)
			(xy 126.639875 -176.764647) (xy 126.645577 -176.748409) (xy 126.645924 -176.739804) (xy 126.645924 -176.11344)
			(xy 126.646396 -176.088452) (xy 126.654218 -176.039091) (xy 126.669674 -175.991565) (xy 126.692384 -175.947046)
			(xy 126.721787 -175.906634) (xy 126.739142 -175.88865) (xy 128.087374 -174.540418) (xy 128.094102 -174.533017)
			(xy 128.101821 -174.51459) (xy 128.10236 -174.504604) (xy 128.10236 -164.514276) (xy 128.101917 -164.504103)
			(xy 128.093984 -164.485365) (xy 128.079408 -164.471167) (xy 128.070102 -164.467032) (xy 127.96774 -164.426392)
			(xy 127.937514 -164.43325) (xy 127.926592 -164.44468) (xy 127.908493 -164.463243) (xy 127.868166 -164.495824)
			(xy 127.823795 -164.52264) (xy 127.7762 -164.543196) (xy 127.726259 -164.557113) (xy 127.674892 -164.564134)
			(xy 127.64897 -164.564568) (xy 127.621715 -164.564173) (xy 127.567759 -164.556411) (xy 127.515457 -164.541049)
			(xy 127.465874 -164.5184) (xy 127.42002 -164.488925) (xy 127.378826 -164.453224) (xy 127.343133 -164.412024)
			(xy 127.313666 -164.366164) (xy 127.291027 -164.316577) (xy 127.275674 -164.264272) (xy 127.267922 -164.210316)
			(xy 127.267462 -164.18306) (xy 127.267938 -164.155149) (xy 127.276077 -164.099922) (xy 127.292177 -164.046472)
			(xy 127.315894 -163.995937) (xy 127.34672 -163.949398) (xy 127.364998 -163.928298) (xy 127.371348 -163.921186)
			(xy 127.377952 -163.903914) (xy 127.377952 -163.816792) (xy 127.371348 -163.79952) (xy 127.364998 -163.792408)
			(xy 127.346702 -163.771323) (xy 127.315877 -163.724781) (xy 127.292165 -163.674242) (xy 127.276073 -163.620788)
			(xy 127.267944 -163.565558) (xy 127.267462 -163.537646) (xy 127.267998 -163.510396) (xy 127.275748 -163.456449)
			(xy 127.291097 -163.404154) (xy 127.313732 -163.354576) (xy 127.343192 -163.308724) (xy 127.378878 -163.267532)
			(xy 127.420063 -163.231838) (xy 127.465909 -163.202368) (xy 127.515483 -163.179723) (xy 127.567775 -163.164364)
			(xy 127.62172 -163.156603) (xy 127.64897 -163.156138) (xy 127.674892 -163.156547) (xy 127.726257 -163.163587)
			(xy 127.776195 -163.177515) (xy 127.823789 -163.198074) (xy 127.868162 -163.224887) (xy 127.908498 -163.257458)
			(xy 127.926592 -163.276026) (xy 127.937514 -163.287456) (xy 127.96774 -163.294314) (xy 128.070102 -163.253674)
			(xy 128.079428 -163.249573) (xy 128.094015 -163.235371) (xy 128.101919 -163.21661) (xy 128.10236 -163.20643)
			(xy 128.10236 -162.71367) (xy 128.101895 -162.703666) (xy 128.094178 -162.685203) (xy 128.087374 -162.677856)
			(xy 127.19939 -161.789872) (xy 127.187452 -161.783268) (xy 127.180594 -161.78149) (xy 127.153191 -161.774394)
			(xy 127.100709 -161.753182) (xy 127.051939 -161.724448) (xy 127.00795 -161.688822) (xy 126.969709 -161.647086)
			(xy 126.938056 -161.600158) (xy 126.913685 -161.549067) (xy 126.897131 -161.494936) (xy 126.888759 -161.438953)
			(xy 126.88824 -161.41065) (xy 126.888702 -161.383396) (xy 126.896453 -161.329443) (xy 126.911805 -161.277142)
			(xy 126.934446 -161.227559) (xy 126.963913 -161.181703) (xy 126.999607 -161.140509) (xy 127.040801 -161.104814)
			(xy 127.086657 -161.075347) (xy 127.13624 -161.052706) (xy 127.188541 -161.037354) (xy 127.242494 -161.029602)
			(xy 127.269748 -161.029142) (xy 127.298055 -161.029628) (xy 127.354049 -161.03798) (xy 127.408192 -161.054521)
			(xy 127.459293 -161.078888) (xy 127.506228 -161.110546) (xy 127.547964 -161.148797) (xy 127.583584 -161.192801)
			(xy 127.612304 -161.241589) (xy 127.633491 -161.294089) (xy 127.640588 -161.321496) (xy 127.642366 -161.328354)
			(xy 127.64897 -161.340292) (xy 128.644904 -162.336226) (xy 128.662248 -162.354208) (xy 128.691595 -162.394637)
			(xy 128.71425 -162.439163) (xy 128.729654 -162.486687) (xy 128.737427 -162.536037) (xy 128.737868 -162.561016)
			(xy 128.737868 -173.59884) (xy 130.214624 -173.59884) (xy 130.215108 -173.57147) (xy 130.22292 -173.517292)
			(xy 130.238405 -173.464789) (xy 130.261243 -173.415041) (xy 130.290964 -173.369074) (xy 130.308604 -173.348142)
			(xy 130.3147 -173.34103) (xy 130.32105 -173.324012) (xy 130.32105 -173.238668) (xy 130.3147 -173.22165)
			(xy 130.308604 -173.214538) (xy 130.291003 -173.193573) (xy 130.261279 -173.14761) (xy 130.238432 -173.097869)
			(xy 130.222934 -173.045372) (xy 130.215102 -172.991199) (xy 130.215098 -172.936462) (xy 130.222921 -172.882287)
			(xy 130.238411 -172.829787) (xy 130.26125 -172.780043) (xy 130.290967 -172.734075) (xy 130.308604 -172.713142)
			(xy 130.3147 -172.70603) (xy 130.32105 -172.689012) (xy 130.32105 -172.603668) (xy 130.3147 -172.58665)
			(xy 130.308604 -172.579538) (xy 130.291003 -172.558573) (xy 130.261279 -172.51261) (xy 130.238432 -172.462869)
			(xy 130.222934 -172.410372) (xy 130.215102 -172.356199) (xy 130.215098 -172.301462) (xy 130.222921 -172.247287)
			(xy 130.238411 -172.194787) (xy 130.26125 -172.145043) (xy 130.290967 -172.099075) (xy 130.308604 -172.078142)
			(xy 130.3147 -172.07103) (xy 130.32105 -172.054012) (xy 130.32105 -171.968668) (xy 130.3147 -171.95165)
			(xy 130.308604 -171.944538) (xy 130.29097 -171.923602) (xy 130.261257 -171.87763) (xy 130.23842 -171.827884)
			(xy 130.222928 -171.775384) (xy 130.215099 -171.721209) (xy 130.214624 -171.69384) (xy 130.215109 -171.665965)
			(xy 130.22322 -171.610807) (xy 130.239275 -171.557418) (xy 130.262932 -171.506936) (xy 130.293686 -171.460435)
			(xy 130.311906 -171.439332) (xy 130.318002 -171.432474) (xy 130.32486 -171.415202) (xy 130.32486 -171.328588)
			(xy 130.318256 -171.311316) (xy 130.31216 -171.304204) (xy 130.294099 -171.283136) (xy 130.263576 -171.236796)
			(xy 130.240103 -171.186515) (xy 130.224177 -171.13336) (xy 130.216135 -171.078457) (xy 130.21564 -171.050712)
			(xy 130.216103 -171.023342) (xy 130.22392 -170.969162) (xy 130.23941 -170.916658) (xy 130.262252 -170.866912)
			(xy 130.291978 -170.820945) (xy 130.30962 -170.800014) (xy 130.315716 -170.792902) (xy 130.322066 -170.775884)
			(xy 130.322066 -170.69054) (xy 130.315716 -170.673522) (xy 130.30962 -170.66641) (xy 130.291991 -170.645468)
			(xy 130.262267 -170.599501) (xy 130.239421 -170.549757) (xy 130.223924 -170.497256) (xy 130.216095 -170.443079)
			(xy 130.216093 -170.388339) (xy 130.22392 -170.334162) (xy 130.239415 -170.28166) (xy 130.262258 -170.231915)
			(xy 130.29198 -170.185947) (xy 130.30962 -170.165014) (xy 130.315716 -170.157902) (xy 130.322066 -170.140884)
			(xy 130.322066 -170.05554) (xy 130.315716 -170.038522) (xy 130.30962 -170.03141) (xy 130.291991 -170.010468)
			(xy 130.262267 -169.964501) (xy 130.239421 -169.914757) (xy 130.223924 -169.862256) (xy 130.216095 -169.808079)
			(xy 130.216093 -169.753339) (xy 130.22392 -169.699162) (xy 130.239415 -169.64666) (xy 130.262258 -169.596915)
			(xy 130.29198 -169.550947) (xy 130.30962 -169.530014) (xy 130.315716 -169.522902) (xy 130.322066 -169.505884)
			(xy 130.322066 -169.42054) (xy 130.315716 -169.403522) (xy 130.30962 -169.39641) (xy 130.291975 -169.375482)
			(xy 130.262264 -169.329509) (xy 130.239428 -169.27976) (xy 130.223939 -169.227258) (xy 130.216113 -169.173082)
			(xy 130.21564 -169.145712) (xy 130.216121 -169.118413) (xy 130.223892 -169.064371) (xy 130.23929 -169.01199)
			(xy 130.262002 -168.96234) (xy 130.291562 -168.916437) (xy 130.309112 -168.895522) (xy 130.315462 -168.88841)
			(xy 130.321558 -168.871392) (xy 130.321558 -168.785794) (xy 130.315208 -168.76903) (xy 130.309112 -168.761918)
			(xy 130.291409 -168.740948) (xy 130.261528 -168.694919) (xy 130.238559 -168.645079) (xy 130.222977 -168.592461)
			(xy 130.215103 -168.538151) (xy 130.214624 -168.510712) (xy 130.215067 -168.483458) (xy 130.222823 -168.429505)
			(xy 130.238179 -168.377204) (xy 130.260822 -168.327622) (xy 130.290292 -168.281768) (xy 130.325988 -168.240574)
			(xy 130.367184 -168.20488) (xy 130.41304 -168.175413) (xy 130.462623 -168.152772) (xy 130.514924 -168.137418)
			(xy 130.568878 -168.129665) (xy 130.596132 -168.129204) (xy 130.623503 -168.12965) (xy 130.677683 -168.137473)
			(xy 130.730186 -168.152966) (xy 130.779933 -168.175813) (xy 130.825899 -168.205541) (xy 130.84683 -168.223184)
			(xy 130.853942 -168.22928) (xy 130.87096 -168.23563) (xy 130.956304 -168.23563) (xy 130.973322 -168.22928)
			(xy 130.980434 -168.223184) (xy 131.001378 -168.20556) (xy 131.047348 -168.175846) (xy 131.097092 -168.153008)
			(xy 131.14959 -168.137513) (xy 131.203764 -168.129681) (xy 131.231132 -168.129204) (xy 131.258385 -168.129648)
			(xy 131.312334 -168.137409) (xy 131.364631 -168.152769) (xy 131.414209 -168.175415) (xy 131.46006 -168.204886)
			(xy 131.50125 -168.240581) (xy 131.536941 -168.281776) (xy 131.566406 -168.32763) (xy 131.589046 -168.377211)
			(xy 131.6044 -168.429509) (xy 131.612155 -168.483459) (xy 131.61264 -168.510712) (xy 131.612153 -168.538011)
			(xy 131.604381 -168.592051) (xy 131.588983 -168.644432) (xy 131.566273 -168.694081) (xy 131.536716 -168.739986)
			(xy 131.519168 -168.760902) (xy 131.512818 -168.768014) (xy 131.506722 -168.785032) (xy 131.506722 -168.87063)
			(xy 131.513072 -168.887394) (xy 131.519168 -168.894506) (xy 131.53688 -168.915469) (xy 131.56676 -168.9615)
			(xy 131.589727 -169.011341) (xy 131.605308 -169.063962) (xy 131.613178 -169.118273) (xy 131.613656 -169.145712)
			(xy 131.613208 -169.173083) (xy 131.605387 -169.227263) (xy 131.589895 -169.279767) (xy 131.567049 -169.329514)
			(xy 131.53732 -169.375479) (xy 131.519676 -169.39641) (xy 131.51358 -169.403522) (xy 131.50723 -169.42054)
			(xy 131.50723 -169.505884) (xy 131.51358 -169.522902) (xy 131.519676 -169.530014) (xy 131.537328 -169.550937)
			(xy 131.567052 -169.596907) (xy 131.589897 -169.646655) (xy 131.605392 -169.699158) (xy 131.61322 -169.753338)
			(xy 131.613218 -169.80808) (xy 131.605388 -169.86226) (xy 131.589891 -169.914762) (xy 131.567044 -169.964509)
			(xy 131.537317 -170.010477) (xy 131.519676 -170.03141) (xy 131.51358 -170.038522) (xy 131.50723 -170.05554)
			(xy 131.50723 -170.140884) (xy 131.51358 -170.157902) (xy 131.519676 -170.165014) (xy 131.537328 -170.185937)
			(xy 131.567052 -170.231907) (xy 131.589897 -170.281655) (xy 131.605392 -170.334158) (xy 131.61322 -170.388338)
			(xy 131.613218 -170.44308) (xy 131.605388 -170.49726) (xy 131.589891 -170.549762) (xy 131.567044 -170.599509)
			(xy 131.537317 -170.645477) (xy 131.519676 -170.66641) (xy 131.51358 -170.673522) (xy 131.50723 -170.69054)
			(xy 131.50723 -170.775884) (xy 131.51358 -170.792902) (xy 131.519676 -170.800014) (xy 131.537285 -170.820971)
			(xy 131.567002 -170.866936) (xy 131.589844 -170.916678) (xy 131.605342 -170.969173) (xy 131.613178 -171.023344)
			(xy 131.613656 -171.050712) (xy 131.613122 -171.078585) (xy 131.60502 -171.13374) (xy 131.588975 -171.187128)
			(xy 131.56533 -171.237611) (xy 131.534587 -171.284114) (xy 131.516374 -171.30522) (xy 131.510278 -171.312078)
			(xy 131.50342 -171.32935) (xy 131.50342 -171.415964) (xy 131.510024 -171.433236) (xy 131.51612 -171.440348)
			(xy 131.534202 -171.461398) (xy 131.564723 -171.507743) (xy 131.588192 -171.558028) (xy 131.604113 -171.611187)
			(xy 131.612148 -171.666094) (xy 131.61264 -171.69384) (xy 131.612153 -171.72121) (xy 131.604343 -171.775388)
			(xy 131.588859 -171.827892) (xy 131.566022 -171.877639) (xy 131.5363 -171.923606) (xy 131.51866 -171.944538)
			(xy 131.512564 -171.95165) (xy 131.506214 -171.968668) (xy 131.506214 -172.054012) (xy 131.512564 -172.07103)
			(xy 131.51866 -172.078142) (xy 131.53634 -172.099043) (xy 131.566065 -172.145016) (xy 131.588908 -172.194767)
			(xy 131.604402 -172.247274) (xy 131.612227 -172.301457) (xy 131.612225 -172.32884) (xy 133.592824 -172.32884)
			(xy 133.593308 -172.30147) (xy 133.60112 -172.247292) (xy 133.616605 -172.194789) (xy 133.639443 -172.145041)
			(xy 133.669164 -172.099074) (xy 133.686804 -172.078142) (xy 133.6929 -172.07103) (xy 133.69925 -172.054012)
			(xy 133.69925 -171.968668) (xy 133.6929 -171.95165) (xy 133.686804 -171.944538) (xy 133.66917 -171.923602)
			(xy 133.639457 -171.87763) (xy 133.61662 -171.827884) (xy 133.601128 -171.775384) (xy 133.593299 -171.721209)
			(xy 133.592824 -171.69384) (xy 133.593309 -171.665965) (xy 133.60142 -171.610807) (xy 133.617475 -171.557418)
			(xy 133.641132 -171.506936) (xy 133.671886 -171.460435) (xy 133.690106 -171.439332) (xy 133.696202 -171.432474)
			(xy 133.70306 -171.415202) (xy 133.70306 -171.328588) (xy 133.696456 -171.311316) (xy 133.69036 -171.304204)
			(xy 133.672299 -171.283136) (xy 133.641776 -171.236796) (xy 133.618303 -171.186515) (xy 133.602377 -171.13336)
			(xy 133.594335 -171.078457) (xy 133.59384 -171.050712) (xy 133.594303 -171.023342) (xy 133.60212 -170.969162)
			(xy 133.61761 -170.916658) (xy 133.640452 -170.866912) (xy 133.670178 -170.820945) (xy 133.68782 -170.800014)
			(xy 133.693916 -170.792902) (xy 133.700266 -170.775884) (xy 133.700266 -170.69054) (xy 133.693916 -170.673522)
			(xy 133.68782 -170.66641) (xy 133.670191 -170.645468) (xy 133.640467 -170.599501) (xy 133.617621 -170.549757)
			(xy 133.602124 -170.497256) (xy 133.594295 -170.443079) (xy 133.594293 -170.388339) (xy 133.60212 -170.334162)
			(xy 133.617615 -170.28166) (xy 133.640458 -170.231915) (xy 133.67018 -170.185947) (xy 133.68782 -170.165014)
			(xy 133.693916 -170.157902) (xy 133.700266 -170.140884) (xy 133.700266 -170.05554) (xy 133.693916 -170.038522)
			(xy 133.68782 -170.03141) (xy 133.670191 -170.010468) (xy 133.640467 -169.964501) (xy 133.617621 -169.914757)
			(xy 133.602124 -169.862256) (xy 133.594295 -169.808079) (xy 133.594293 -169.753339) (xy 133.60212 -169.699162)
			(xy 133.617615 -169.64666) (xy 133.640458 -169.596915) (xy 133.67018 -169.550947) (xy 133.68782 -169.530014)
			(xy 133.693916 -169.522902) (xy 133.700266 -169.505884) (xy 133.700266 -169.42054) (xy 133.693916 -169.403522)
			(xy 133.68782 -169.39641) (xy 133.670175 -169.375482) (xy 133.640464 -169.329509) (xy 133.617628 -169.27976)
			(xy 133.602139 -169.227258) (xy 133.594313 -169.173082) (xy 133.59384 -169.145712) (xy 133.594321 -169.118413)
			(xy 133.602092 -169.064371) (xy 133.61749 -169.01199) (xy 133.640202 -168.96234) (xy 133.669762 -168.916437)
			(xy 133.687312 -168.895522) (xy 133.693662 -168.88841) (xy 133.699758 -168.871392) (xy 133.699758 -168.785794)
			(xy 133.693408 -168.76903) (xy 133.687312 -168.761918) (xy 133.669609 -168.740948) (xy 133.639728 -168.694919)
			(xy 133.616759 -168.645079) (xy 133.601177 -168.592461) (xy 133.593303 -168.538151) (xy 133.592824 -168.510712)
			(xy 133.593267 -168.483458) (xy 133.601023 -168.429505) (xy 133.616379 -168.377204) (xy 133.639022 -168.327622)
			(xy 133.668492 -168.281768) (xy 133.704188 -168.240574) (xy 133.745384 -168.20488) (xy 133.79124 -168.175413)
			(xy 133.840823 -168.152772) (xy 133.893124 -168.137418) (xy 133.947078 -168.129665) (xy 133.974332 -168.129204)
			(xy 134.001703 -168.12965) (xy 134.055883 -168.137473) (xy 134.108386 -168.152966) (xy 134.158133 -168.175813)
			(xy 134.204099 -168.205541) (xy 134.22503 -168.223184) (xy 134.232142 -168.22928) (xy 134.24916 -168.23563)
			(xy 134.334504 -168.23563) (xy 134.351522 -168.22928) (xy 134.358634 -168.223184) (xy 134.379578 -168.20556)
			(xy 134.425548 -168.175846) (xy 134.475292 -168.153008) (xy 134.52779 -168.137513) (xy 134.581964 -168.129681)
			(xy 134.609332 -168.129204) (xy 134.634784 -168.129646) (xy 134.685237 -168.136412) (xy 134.734341 -168.149834)
			(xy 134.781221 -168.169672) (xy 134.825043 -168.195573) (xy 134.845298 -168.210992) (xy 134.852156 -168.216326)
			(xy 134.867904 -168.22166) (xy 134.87654 -168.22166) (xy 134.886555 -168.221244) (xy 134.905055 -168.213564)
			(xy 134.919208 -168.199388) (xy 134.926859 -168.180876) (xy 134.92734 -168.17086) (xy 134.92734 -168.13276)
			(xy 134.9269 -168.122789) (xy 134.9193 -168.104353) (xy 134.912608 -168.096946) (xy 134.763764 -167.948102)
			(xy 134.746445 -167.930097) (xy 134.717092 -167.889675) (xy 134.694431 -167.845155) (xy 134.679021 -167.797636)
			(xy 134.671243 -167.74829) (xy 134.6708 -167.723312) (xy 134.6708 -154.911044) (xy 134.671276 -154.886069)
			(xy 134.679065 -154.83673) (xy 134.694475 -154.789217) (xy 134.717127 -154.744699) (xy 134.746462 -154.704271)
			(xy 134.763764 -154.686254) (xy 135.251444 -154.198574) (xy 135.258336 -154.190918) (xy 135.26602 -154.171831)
			(xy 135.265632 -154.15126) (xy 135.261858 -154.141678) (xy 135.216138 -154.040332) (xy 135.189214 -154.02433)
			(xy 135.173212 -154.025346) (xy 135.148828 -154.026108) (xy 135.121573 -154.025675) (xy 135.067616 -154.017921)
			(xy 135.015313 -154.002567) (xy 134.965727 -153.979926) (xy 134.919867 -153.950458) (xy 134.878669 -153.914764)
			(xy 134.84297 -153.87357) (xy 134.813496 -153.827714) (xy 134.790849 -153.778131) (xy 134.775489 -153.725829)
			(xy 134.767728 -153.671874) (xy 134.767726 -153.617363) (xy 134.775481 -153.563407) (xy 134.790836 -153.511104)
			(xy 134.813478 -153.461518) (xy 134.842947 -153.41566) (xy 134.878642 -153.374462) (xy 134.919838 -153.338764)
			(xy 134.965694 -153.309292) (xy 135.015278 -153.286646) (xy 135.06758 -153.271287) (xy 135.121535 -153.263528)
			(xy 135.176046 -153.263526) (xy 135.230002 -153.271283) (xy 135.282305 -153.286639) (xy 135.33189 -153.309283)
			(xy 135.377748 -153.338753) (xy 135.418944 -153.374449) (xy 135.454642 -153.415645) (xy 135.484113 -153.461502)
			(xy 135.506758 -153.511086) (xy 135.522115 -153.563389) (xy 135.529873 -153.617345) (xy 135.530336 -153.6446)
			(xy 135.529733 -153.675732) (xy 135.519661 -153.737174) (xy 135.499722 -153.796157) (xy 135.485632 -153.823924)
			(xy 135.477758 -153.838656) (xy 135.482584 -153.87193) (xy 135.494522 -153.883614) (xy 135.501956 -153.89033)
			(xy 135.520456 -153.897966) (xy 135.54047 -153.897966) (xy 135.55897 -153.89033) (xy 135.566404 -153.883614)
			(xy 135.686546 -153.763472) (xy 135.693304 -153.756096) (xy 135.701003 -153.73765) (xy 135.701532 -153.727658)
			(xy 135.701532 -153.193242) (xy 135.701089 -153.183235) (xy 135.693358 -153.164772) (xy 135.686546 -153.157428)
			(xy 135.65759 -153.128472) (xy 135.645652 -153.121868) (xy 135.638794 -153.12009) (xy 135.611391 -153.112994)
			(xy 135.558909 -153.091782) (xy 135.510139 -153.063048) (xy 135.46615 -153.027422) (xy 135.427909 -152.985686)
			(xy 135.396256 -152.938758) (xy 135.371885 -152.887667) (xy 135.355331 -152.833536) (xy 135.346959 -152.777553)
			(xy 135.34644 -152.74925) (xy 135.346902 -152.721996) (xy 135.354653 -152.668043) (xy 135.370005 -152.615742)
			(xy 135.392646 -152.566159) (xy 135.422113 -152.520303) (xy 135.457807 -152.479109) (xy 135.499001 -152.443414)
			(xy 135.544857 -152.413947) (xy 135.59444 -152.391306) (xy 135.646741 -152.375954) (xy 135.700694 -152.368202)
			(xy 135.727948 -152.367742) (xy 135.756255 -152.368228) (xy 135.812249 -152.37658) (xy 135.866392 -152.393121)
			(xy 135.917493 -152.417488) (xy 135.964428 -152.449146) (xy 136.006164 -152.487397) (xy 136.041784 -152.531401)
			(xy 136.070504 -152.580189) (xy 136.091691 -152.632689) (xy 136.098788 -152.660096) (xy 136.100566 -152.666954)
			(xy 136.10717 -152.678892) (xy 136.244076 -152.815798) (xy 136.261402 -152.833797) (xy 136.290752 -152.874221)
			(xy 136.313411 -152.918742) (xy 136.328819 -152.966263) (xy 136.336597 -153.01561) (xy 136.33704 -153.040588)
			(xy 136.33704 -153.880312) (xy 136.336588 -153.905288) (xy 136.328791 -153.954627) (xy 136.313374 -154.00214)
			(xy 136.290718 -154.046658) (xy 136.261379 -154.087085) (xy 136.244076 -154.105102) (xy 136.027668 -154.321256)
			(xy 136.020861 -154.328743) (xy 136.014173 -154.345132) (xy 136.69086 -154.345132) (xy 136.694931 -154.28951)
			(xy 136.707057 -154.235073) (xy 136.72698 -154.182982) (xy 136.754276 -154.134347) (xy 136.788362 -154.090204)
			(xy 136.828511 -154.051495) (xy 136.873869 -154.019044) (xy 136.923469 -153.993543) (xy 136.976253 -153.975536)
			(xy 137.031096 -153.965406) (xy 137.08683 -153.963369) (xy 137.142267 -153.969469) (xy 137.196224 -153.983575)
			(xy 137.247553 -154.005387) (xy 137.295159 -154.034441) (xy 137.338027 -154.070116) (xy 137.375244 -154.111653)
			(xy 137.406017 -154.158166) (xy 137.429689 -154.208663) (xy 137.445757 -154.26207) (xy 137.453877 -154.317246)
			(xy 137.454386 -154.345132) (xy 137.453877 -154.373018) (xy 137.445757 -154.428194) (xy 137.429689 -154.481601)
			(xy 137.406017 -154.532098) (xy 137.375244 -154.578611) (xy 137.338027 -154.620148) (xy 137.295159 -154.655823)
			(xy 137.247553 -154.684877) (xy 137.196224 -154.706689) (xy 137.142267 -154.720795) (xy 137.08683 -154.726895)
			(xy 137.031096 -154.724858) (xy 136.976253 -154.714728) (xy 136.923469 -154.696721) (xy 136.873869 -154.67122)
			(xy 136.828511 -154.638769) (xy 136.788362 -154.60006) (xy 136.754276 -154.555917) (xy 136.72698 -154.507282)
			(xy 136.707057 -154.455191) (xy 136.694931 -154.400754) (xy 136.69086 -154.345132) (xy 136.014173 -154.345132)
			(xy 136.013223 -154.347461) (xy 136.013411 -154.367676) (xy 136.017 -154.377136) (xy 136.059672 -154.478228)
			(xy 136.08558 -154.494992) (xy 136.101328 -154.494738) (xy 136.10717 -154.494738) (xy 136.134424 -154.495183)
			(xy 136.188378 -154.502937) (xy 136.240679 -154.518292) (xy 136.290262 -154.540934) (xy 136.336118 -154.570404)
			(xy 136.377312 -154.606099) (xy 136.413006 -154.647295) (xy 136.442473 -154.693152) (xy 136.465114 -154.742736)
			(xy 136.480466 -154.795037) (xy 136.488218 -154.848992) (xy 136.488678 -154.876246) (xy 136.488196 -154.904157)
			(xy 136.480056 -154.959383) (xy 136.463957 -155.012833) (xy 136.440243 -155.063367) (xy 136.409418 -155.109907)
			(xy 136.391142 -155.131008) (xy 136.384792 -155.13812) (xy 136.378188 -155.155392) (xy 136.378188 -155.242514)
			(xy 136.384792 -155.259786) (xy 136.391142 -155.266898) (xy 136.4094 -155.288014) (xy 136.440229 -155.334549)
			(xy 136.463947 -155.385079) (xy 136.480049 -155.438527) (xy 136.488189 -155.49375) (xy 136.488678 -155.52166)
			(xy 136.488192 -155.548911) (xy 136.480436 -155.602859) (xy 136.465081 -155.655154) (xy 136.442439 -155.704731)
			(xy 136.412973 -155.750581) (xy 136.377282 -155.791772) (xy 136.336091 -155.827463) (xy 136.290241 -155.856929)
			(xy 136.240664 -155.879571) (xy 136.188369 -155.894926) (xy 136.134421 -155.902682) (xy 136.079919 -155.902682)
			(xy 136.025971 -155.894926) (xy 135.973676 -155.879571) (xy 135.924099 -155.856929) (xy 135.878249 -155.827463)
			(xy 135.837058 -155.791772) (xy 135.801367 -155.750581) (xy 135.771901 -155.704731) (xy 135.749259 -155.655154)
			(xy 135.733904 -155.602859) (xy 135.726148 -155.548911) (xy 135.725662 -155.52166) (xy 135.726138 -155.493749)
			(xy 135.734277 -155.438522) (xy 135.750377 -155.385072) (xy 135.774094 -155.334537) (xy 135.80492 -155.287998)
			(xy 135.823198 -155.266898) (xy 135.829548 -155.259786) (xy 135.836152 -155.242514) (xy 135.836152 -155.155392)
			(xy 135.829548 -155.13812) (xy 135.823198 -155.131008) (xy 135.804902 -155.109923) (xy 135.774077 -155.063381)
			(xy 135.750365 -155.012842) (xy 135.734273 -154.959388) (xy 135.726144 -154.904158) (xy 135.725662 -154.876246)
			(xy 135.725662 -154.870404) (xy 135.725916 -154.854656) (xy 135.709152 -154.828748) (xy 135.60806 -154.786076)
			(xy 135.598586 -154.782537) (xy 135.578382 -154.782343) (xy 135.559661 -154.789941) (xy 135.55218 -154.796744)
			(xy 135.321294 -155.027884) (xy 135.314561 -155.03528) (xy 135.306846 -155.053711) (xy 135.306308 -155.063698)
			(xy 135.306308 -167.570658) (xy 135.306767 -167.580663) (xy 135.314489 -167.599125) (xy 135.321294 -167.606472)
			(xy 135.470138 -167.755316) (xy 135.487427 -167.773356) (xy 135.516801 -167.813772) (xy 135.539502 -167.858279)
			(xy 135.554974 -167.905785) (xy 135.562838 -167.955125) (xy 135.563356 -167.980106) (xy 135.563356 -168.015412)
			(xy 139.30757 -168.015412) (xy 139.30807 -167.986494) (xy 139.316799 -167.929321) (xy 139.334059 -167.874121)
			(xy 139.359454 -167.822158) (xy 139.392402 -167.774625) (xy 139.432148 -167.73261) (xy 139.454636 -167.714422)
			(xy 139.46339 -167.706852) (xy 139.473576 -167.686099) (xy 139.474194 -167.674544) (xy 139.474194 -167.59428)
			(xy 139.47358 -167.582718) (xy 139.463416 -167.561946) (xy 139.454636 -167.554402) (xy 139.432161 -167.536201)
			(xy 139.392424 -167.494184) (xy 139.359483 -167.446652) (xy 139.334092 -167.394692) (xy 139.316835 -167.339496)
			(xy 139.308105 -167.282328) (xy 139.30757 -167.253412) (xy 139.308056 -167.226161) (xy 139.315812 -167.172213)
			(xy 139.331167 -167.119918) (xy 139.353809 -167.070341) (xy 139.383275 -167.024491) (xy 139.418966 -166.9833)
			(xy 139.460157 -166.947609) (xy 139.506007 -166.918143) (xy 139.555584 -166.895501) (xy 139.607879 -166.880146)
			(xy 139.661827 -166.87239) (xy 139.716329 -166.87239) (xy 139.770277 -166.880146) (xy 139.822572 -166.895501)
			(xy 139.872149 -166.918143) (xy 139.917999 -166.947609) (xy 139.95919 -166.9833) (xy 139.994881 -167.024491)
			(xy 140.024347 -167.070341) (xy 140.046989 -167.119918) (xy 140.062344 -167.172213) (xy 140.0701 -167.226161)
			(xy 140.070586 -167.253412) (xy 140.07001 -167.282327) (xy 140.061294 -167.339496) (xy 140.044048 -167.394694)
			(xy 140.018667 -167.446656) (xy 139.985733 -167.494191) (xy 139.946001 -167.53621) (xy 139.92352 -167.554402)
			(xy 139.914748 -167.561954) (xy 139.904574 -167.582721) (xy 139.903962 -167.59428) (xy 139.903962 -167.674544)
			(xy 139.904543 -167.686111) (xy 139.914728 -167.706884) (xy 139.92352 -167.714422) (xy 139.946018 -167.732596)
			(xy 139.985752 -167.77462) (xy 140.018688 -167.822158) (xy 140.044074 -167.874123) (xy 140.061327 -167.929323)
			(xy 140.070053 -167.986495) (xy 140.070586 -168.015412) (xy 140.0701 -168.042663) (xy 140.062344 -168.096611)
			(xy 140.046989 -168.148906) (xy 140.024347 -168.198483) (xy 139.994881 -168.244333) (xy 139.95919 -168.285524)
			(xy 139.917999 -168.321215) (xy 139.872149 -168.350681) (xy 139.822572 -168.373323) (xy 139.770277 -168.388678)
			(xy 139.716329 -168.396434) (xy 139.661827 -168.396434) (xy 139.607879 -168.388678) (xy 139.555584 -168.373323)
			(xy 139.506007 -168.350681) (xy 139.460157 -168.321215) (xy 139.418966 -168.285524) (xy 139.383275 -168.244333)
			(xy 139.353809 -168.198483) (xy 139.331167 -168.148906) (xy 139.315812 -168.096611) (xy 139.308056 -168.042663)
			(xy 139.30757 -168.015412) (xy 135.563356 -168.015412) (xy 135.563356 -168.086532) (xy 135.563676 -168.095148)
			(xy 135.569335 -168.11142) (xy 135.580098 -168.124873) (xy 135.587232 -168.129712) (xy 135.672068 -168.182036)
			(xy 135.69823 -168.183306) (xy 135.710168 -168.177464) (xy 135.736737 -168.164822) (xy 135.792797 -168.146963)
			(xy 135.85093 -168.137899) (xy 135.880348 -168.137332) (xy 135.907602 -168.137733) (xy 135.961555 -168.145497)
			(xy 136.013854 -168.160861) (xy 136.063434 -168.18351) (xy 136.109286 -168.212985) (xy 136.150477 -168.248686)
			(xy 136.186168 -168.289885) (xy 136.215632 -168.335743) (xy 136.23827 -168.385329) (xy 136.253621 -168.437631)
			(xy 136.261373 -168.491586) (xy 136.261856 -168.51884) (xy 136.261365 -168.546209) (xy 136.253555 -168.600388)
			(xy 136.238072 -168.652891) (xy 136.215236 -168.702639) (xy 136.185515 -168.748606) (xy 136.167876 -168.769538)
			(xy 136.16178 -168.77665) (xy 136.15543 -168.793668) (xy 136.15543 -168.879012) (xy 136.16178 -168.89603)
			(xy 136.167876 -168.903142) (xy 136.185556 -168.924043) (xy 136.215279 -168.970016) (xy 136.238122 -169.019768)
			(xy 136.253615 -169.072275) (xy 136.261439 -169.126458) (xy 136.261435 -169.181203) (xy 136.253602 -169.235384)
			(xy 136.2381 -169.287889) (xy 136.21525 -169.337636) (xy 136.185519 -169.383605) (xy 136.167876 -169.404538)
			(xy 136.16178 -169.41165) (xy 136.15543 -169.428668) (xy 136.15543 -169.514012) (xy 136.16178 -169.53103)
			(xy 136.167876 -169.538142) (xy 136.185556 -169.559043) (xy 136.215279 -169.605016) (xy 136.238122 -169.654768)
			(xy 136.253615 -169.707275) (xy 136.261439 -169.761458) (xy 136.261435 -169.816203) (xy 136.253602 -169.870384)
			(xy 136.2381 -169.922889) (xy 136.21525 -169.972636) (xy 136.185519 -170.018605) (xy 136.167876 -170.039538)
			(xy 136.16178 -170.04665) (xy 136.15543 -170.063668) (xy 136.15543 -170.149012) (xy 136.16178 -170.16603)
			(xy 136.167876 -170.173142) (xy 136.185556 -170.194043) (xy 136.215279 -170.240016) (xy 136.238122 -170.289768)
			(xy 136.253615 -170.342275) (xy 136.261439 -170.396458) (xy 136.261435 -170.451203) (xy 136.253602 -170.505384)
			(xy 136.2381 -170.557889) (xy 136.21525 -170.607636) (xy 136.185519 -170.653605) (xy 136.167876 -170.674538)
			(xy 136.16178 -170.68165) (xy 136.15543 -170.698668) (xy 136.15543 -170.784012) (xy 136.16178 -170.80103)
			(xy 136.167876 -170.808142) (xy 136.185556 -170.829043) (xy 136.215279 -170.875016) (xy 136.238122 -170.924768)
			(xy 136.253615 -170.977275) (xy 136.261439 -171.031458) (xy 136.261435 -171.086203) (xy 136.253602 -171.140384)
			(xy 136.2381 -171.192889) (xy 136.21525 -171.242636) (xy 136.185519 -171.288605) (xy 136.167876 -171.309538)
			(xy 136.16178 -171.31665) (xy 136.15543 -171.333668) (xy 136.15543 -171.419012) (xy 136.16178 -171.43603)
			(xy 136.167876 -171.443142) (xy 136.185498 -171.464088) (xy 136.215213 -171.510057) (xy 136.238053 -171.559801)
			(xy 136.253548 -171.612298) (xy 136.26138 -171.666472) (xy 136.261856 -171.69384) (xy 136.26136 -171.72109)
			(xy 136.253599 -171.775035) (xy 136.238241 -171.827326) (xy 136.215599 -171.876901) (xy 136.186133 -171.922749)
			(xy 136.150443 -171.963937) (xy 136.109255 -171.999628) (xy 136.063408 -172.029095) (xy 136.013834 -172.051738)
			(xy 135.961543 -172.067097) (xy 135.907598 -172.074859) (xy 135.880348 -172.075348) (xy 135.852978 -172.074866)
			(xy 135.798799 -172.067054) (xy 135.746296 -172.05157) (xy 135.696549 -172.028731) (xy 135.650582 -171.999009)
			(xy 135.62965 -171.981368) (xy 135.622538 -171.975272) (xy 135.60552 -171.968922) (xy 135.520176 -171.968922)
			(xy 135.503158 -171.975272) (xy 135.496046 -171.981368) (xy 135.475103 -171.998994) (xy 135.429134 -172.028709)
			(xy 135.379389 -172.051548) (xy 135.326891 -172.067042) (xy 135.272717 -172.074873) (xy 135.245348 -172.075348)
			(xy 135.215799 -172.074812) (xy 135.157408 -172.065693) (xy 135.101122 -172.047679) (xy 135.048286 -172.021203)
			(xy 135.000164 -171.986897) (xy 134.978648 -171.966636) (xy 134.971299 -171.96012) (xy 134.953149 -171.952666)
			(xy 134.943342 -171.952158) (xy 134.890002 -171.952158) (xy 134.882636 -171.960032) (xy 134.876086 -171.967354)
			(xy 134.868652 -171.985524) (xy 134.868158 -171.995338) (xy 134.868158 -172.027342) (xy 134.868643 -172.037156)
			(xy 134.87609 -172.05532) (xy 134.882636 -172.062648) (xy 134.90283 -172.084129) (xy 134.936972 -172.132193)
			(xy 134.963315 -172.184937) (xy 134.981232 -172.241106) (xy 134.990294 -172.299362) (xy 134.99084 -172.32884)
			(xy 134.990359 -172.356091) (xy 134.982598 -172.410037) (xy 134.96724 -172.46233) (xy 134.944596 -172.511905)
			(xy 134.915129 -172.557754) (xy 134.879437 -172.598943) (xy 134.838247 -172.634634) (xy 134.792398 -172.6641)
			(xy 134.742822 -172.686743) (xy 134.690529 -172.7021) (xy 134.636583 -172.70986) (xy 134.609332 -172.710348)
			(xy 134.581962 -172.709876) (xy 134.527783 -172.702061) (xy 134.475279 -172.686574) (xy 134.425532 -172.663734)
			(xy 134.379565 -172.634009) (xy 134.358634 -172.616368) (xy 134.351522 -172.610272) (xy 134.334504 -172.603922)
			(xy 134.24916 -172.603922) (xy 134.232142 -172.610272) (xy 134.22503 -172.616368) (xy 134.204093 -172.634002)
			(xy 134.158122 -172.663715) (xy 134.108376 -172.686553) (xy 134.055876 -172.702045) (xy 134.001701 -172.709874)
			(xy 133.974332 -172.710348) (xy 133.947083 -172.709792) (xy 133.89314 -172.702041) (xy 133.840849 -172.686692)
			(xy 133.791275 -172.664057) (xy 133.745426 -172.634598) (xy 133.704237 -172.598914) (xy 133.668545 -172.557731)
			(xy 133.639077 -172.511888) (xy 133.616433 -172.462318) (xy 133.601074 -172.41003) (xy 133.593313 -172.356089)
			(xy 133.592824 -172.32884) (xy 131.612225 -172.32884) (xy 131.612223 -172.356203) (xy 131.604389 -172.410385)
			(xy 131.588887 -172.462889) (xy 131.566036 -172.512637) (xy 131.536304 -172.558605) (xy 131.51866 -172.579538)
			(xy 131.512564 -172.58665) (xy 131.506214 -172.603668) (xy 131.506214 -172.689012) (xy 131.512564 -172.70603)
			(xy 131.51866 -172.713142) (xy 131.53634 -172.734043) (xy 131.566065 -172.780016) (xy 131.588908 -172.829767)
			(xy 131.604402 -172.882274) (xy 131.612227 -172.936457) (xy 131.612223 -172.991203) (xy 131.604389 -173.045385)
			(xy 131.588887 -173.097889) (xy 131.566036 -173.147637) (xy 131.536304 -173.193605) (xy 131.51866 -173.214538)
			(xy 131.512564 -173.22165) (xy 131.506214 -173.238668) (xy 131.506214 -173.324012) (xy 131.512564 -173.34103)
			(xy 131.51866 -173.348142) (xy 131.536279 -173.36909) (xy 131.565995 -173.415058) (xy 131.588836 -173.464801)
			(xy 131.604331 -173.517299) (xy 131.612164 -173.571472) (xy 131.61264 -173.59884) (xy 131.612159 -173.626091)
			(xy 131.604398 -173.680037) (xy 131.58904 -173.73233) (xy 131.566396 -173.781905) (xy 131.536929 -173.827754)
			(xy 131.501237 -173.868943) (xy 131.460047 -173.904634) (xy 131.414198 -173.9341) (xy 131.364622 -173.956743)
			(xy 131.312329 -173.9721) (xy 131.258383 -173.97986) (xy 131.231132 -173.980348) (xy 131.203762 -173.979876)
			(xy 131.149583 -173.972061) (xy 131.097079 -173.956574) (xy 131.047332 -173.933734) (xy 131.001365 -173.904009)
			(xy 130.980434 -173.886368) (xy 130.973322 -173.880272) (xy 130.956304 -173.873922) (xy 130.87096 -173.873922)
			(xy 130.853942 -173.880272) (xy 130.84683 -173.886368) (xy 130.825893 -173.904002) (xy 130.779922 -173.933715)
			(xy 130.730176 -173.956553) (xy 130.677676 -173.972045) (xy 130.623501 -173.979874) (xy 130.596132 -173.980348)
			(xy 130.568883 -173.979792) (xy 130.51494 -173.972041) (xy 130.462649 -173.956692) (xy 130.413075 -173.934057)
			(xy 130.367226 -173.904598) (xy 130.326037 -173.868914) (xy 130.290345 -173.827731) (xy 130.260877 -173.781888)
			(xy 130.238233 -173.732318) (xy 130.222874 -173.68003) (xy 130.215113 -173.626089) (xy 130.214624 -173.59884)
			(xy 128.737868 -173.59884) (xy 128.737868 -174.657258) (xy 128.737374 -174.682232) (xy 128.729586 -174.731569)
			(xy 128.714179 -174.779081) (xy 128.691532 -174.823599) (xy 128.662203 -174.864029) (xy 128.644904 -174.882048)
			(xy 127.296672 -176.23028) (xy 127.289993 -176.237692) (xy 127.282416 -176.256128) (xy 127.28194 -176.266094)
			(xy 127.28194 -176.946306) (xy 127.282089 -176.95333) (xy 127.28584 -176.966864) (xy 127.289306 -176.972976)
			(xy 127.30263 -176.995541) (xy 127.323617 -177.043559) (xy 127.337832 -177.093999) (xy 127.345006 -177.14591)
			(xy 127.34544 -177.172112) (xy 127.344905 -177.201231) (xy 127.336058 -177.258792) (xy 127.31857 -177.314341)
			(xy 127.292849 -177.366591) (xy 127.25949 -177.414327) (xy 127.239776 -177.435764) (xy 127.232918 -177.442876)
			(xy 127.225806 -177.46091) (xy 127.225806 -177.55108) (xy 127.233172 -177.569114) (xy 127.24003 -177.576226)
			(xy 127.259872 -177.59769) (xy 127.293469 -177.64552) (xy 127.319378 -177.697914) (xy 127.336993 -177.753647)
			(xy 127.345901 -177.811415) (xy 127.346456 -177.84064) (xy 127.345965 -177.868009) (xy 127.338155 -177.922188)
			(xy 127.322672 -177.974691) (xy 127.299836 -178.024439) (xy 127.270115 -178.070406) (xy 127.252476 -178.091338)
			(xy 127.24638 -178.09845) (xy 127.24003 -178.115468) (xy 127.24003 -178.200812) (xy 127.24638 -178.21783)
			(xy 127.252476 -178.224942) (xy 127.270156 -178.245843) (xy 127.299879 -178.291816) (xy 127.322722 -178.341568)
			(xy 127.338215 -178.394075) (xy 127.346039 -178.448258) (xy 127.346035 -178.503003) (xy 127.338202 -178.557184)
			(xy 127.3227 -178.609689) (xy 127.29985 -178.659436) (xy 127.270119 -178.705405) (xy 127.252476 -178.726338)
			(xy 127.24638 -178.73345) (xy 127.24003 -178.750468) (xy 127.24003 -178.835812) (xy 127.24638 -178.85283)
			(xy 127.252476 -178.859942) (xy 127.270098 -178.880888) (xy 127.299813 -178.926857) (xy 127.322653 -178.976601)
			(xy 127.338148 -179.029098) (xy 127.34598 -179.083272) (xy 127.346456 -179.11064) (xy 127.34596 -179.13789)
			(xy 127.338199 -179.191835) (xy 127.322841 -179.244126) (xy 127.300199 -179.293701) (xy 127.270733 -179.339549)
			(xy 127.235043 -179.380737) (xy 127.193855 -179.416428) (xy 127.148008 -179.445895) (xy 127.098434 -179.468538)
			(xy 127.046143 -179.483897) (xy 126.992198 -179.491659) (xy 126.964948 -179.492148) (xy 126.935506 -179.4916)
			(xy 126.877322 -179.482559) (xy 126.821217 -179.464683) (xy 126.768527 -179.438398) (xy 126.720501 -179.404329)
			(xy 126.69901 -179.384198) (xy 126.692406 -179.377594) (xy 126.675642 -179.370482) (xy 126.590298 -179.36591)
			(xy 126.573026 -179.371498) (xy 126.56566 -179.377086) (xy 126.545426 -179.392476) (xy 126.501634 -179.418299)
			(xy 126.454801 -179.438076) (xy 126.405755 -179.451457) (xy 126.355367 -179.458203) (xy 126.329948 -179.45862)
			(xy 126.302578 -179.458145) (xy 126.248398 -179.450333) (xy 126.195895 -179.434847) (xy 126.146147 -179.412006)
			(xy 126.100181 -179.382282) (xy 126.07925 -179.36464) (xy 126.072138 -179.358544) (xy 126.05512 -179.352194)
			(xy 125.969776 -179.352194) (xy 125.952758 -179.358544) (xy 125.945646 -179.36464) (xy 125.924713 -179.382278)
			(xy 125.87874 -179.411988) (xy 125.828992 -179.434824) (xy 125.776492 -179.450316) (xy 125.722317 -179.458145)
			(xy 125.694948 -179.45862) (xy 125.667697 -179.4581) (xy 125.613749 -179.45035) (xy 125.561453 -179.435001)
			(xy 125.511873 -179.412365) (xy 125.466021 -179.382903) (xy 125.424828 -179.347215) (xy 125.389133 -179.306028)
			(xy 125.359664 -179.260179) (xy 125.33702 -179.210604) (xy 125.321663 -179.15831) (xy 125.313904 -179.104363)
			(xy 125.31344 -179.077112) (xy 125.313903 -179.049742) (xy 125.32172 -178.995562) (xy 125.33721 -178.943058)
			(xy 125.360052 -178.893312) (xy 125.389778 -178.847345) (xy 125.40742 -178.826414) (xy 125.413516 -178.819302)
			(xy 125.419866 -178.802284) (xy 125.419866 -178.71694) (xy 125.413516 -178.699922) (xy 125.40742 -178.69281)
			(xy 125.389791 -178.671868) (xy 125.360067 -178.625901) (xy 125.337221 -178.576157) (xy 125.321724 -178.523656)
			(xy 125.313895 -178.469479) (xy 125.313893 -178.414739) (xy 125.32172 -178.360562) (xy 125.337215 -178.30806)
			(xy 125.360058 -178.258315) (xy 125.38978 -178.212347) (xy 125.40742 -178.191414) (xy 125.413516 -178.184302)
			(xy 125.419866 -178.167284) (xy 125.419866 -178.08194) (xy 125.413516 -178.064922) (xy 125.40742 -178.05781)
			(xy 125.389775 -178.036882) (xy 125.360064 -177.990909) (xy 125.337228 -177.94116) (xy 125.321739 -177.888658)
			(xy 125.313913 -177.834482) (xy 125.31344 -177.807112) (xy 125.313921 -177.779813) (xy 125.321692 -177.725771)
			(xy 125.33709 -177.67339) (xy 125.359802 -177.62374) (xy 125.389362 -177.577837) (xy 125.406912 -177.556922)
			(xy 125.413262 -177.54981) (xy 125.419358 -177.532792) (xy 125.419358 -177.447194) (xy 125.413008 -177.43043)
			(xy 125.406912 -177.423318) (xy 125.389209 -177.402348) (xy 125.359328 -177.356319) (xy 125.336359 -177.306479)
			(xy 125.320777 -177.253861) (xy 125.312903 -177.199551) (xy 125.312424 -177.172112) (xy 123.33224 -177.172112)
			(xy 123.331753 -177.199411) (xy 123.323981 -177.253451) (xy 123.308583 -177.305832) (xy 123.285873 -177.355481)
			(xy 123.256316 -177.401386) (xy 123.238768 -177.422302) (xy 123.232418 -177.429414) (xy 123.226322 -177.446432)
			(xy 123.226322 -177.53203) (xy 123.232672 -177.548794) (xy 123.238768 -177.555906) (xy 123.25648 -177.576869)
			(xy 123.28636 -177.6229) (xy 123.309327 -177.672741) (xy 123.324908 -177.725362) (xy 123.332778 -177.779673)
			(xy 123.333256 -177.807112) (xy 123.332808 -177.834483) (xy 123.324987 -177.888663) (xy 123.309495 -177.941167)
			(xy 123.286649 -177.990914) (xy 123.25692 -178.036879) (xy 123.239276 -178.05781) (xy 123.23318 -178.064922)
			(xy 123.22683 -178.08194) (xy 123.22683 -178.167284) (xy 123.23318 -178.184302) (xy 123.239276 -178.191414)
			(xy 123.256928 -178.212337) (xy 123.286652 -178.258307) (xy 123.309497 -178.308055) (xy 123.324992 -178.360558)
			(xy 123.33282 -178.414738) (xy 123.332818 -178.46948) (xy 123.324988 -178.52366) (xy 123.309491 -178.576162)
			(xy 123.286644 -178.625909) (xy 123.256917 -178.671877) (xy 123.239276 -178.69281) (xy 123.23318 -178.699922)
			(xy 123.22683 -178.71694) (xy 123.22683 -178.802284) (xy 123.23318 -178.819302) (xy 123.239276 -178.826414)
			(xy 123.256928 -178.847337) (xy 123.286652 -178.893307) (xy 123.309497 -178.943055) (xy 123.324992 -178.995558)
			(xy 123.33282 -179.049738) (xy 123.332818 -179.10448) (xy 123.324988 -179.15866) (xy 123.309491 -179.211162)
			(xy 123.286644 -179.260909) (xy 123.256917 -179.306877) (xy 123.239276 -179.32781) (xy 123.23318 -179.334922)
			(xy 123.22683 -179.35194) (xy 123.22683 -179.437284) (xy 123.23318 -179.454302) (xy 123.239276 -179.461414)
			(xy 123.256885 -179.482371) (xy 123.286602 -179.528336) (xy 123.309444 -179.578078) (xy 123.324942 -179.630573)
			(xy 123.332778 -179.684744) (xy 123.333256 -179.712112) (xy 123.33272 -179.741337) (xy 123.323795 -179.799103)
			(xy 123.306173 -179.854833) (xy 123.280264 -179.907228) (xy 123.246673 -179.955062) (xy 123.22683 -179.976526)
			(xy 123.219972 -179.983638) (xy 123.212606 -180.001672) (xy 123.212606 -180.091842) (xy 123.219718 -180.109876)
			(xy 123.226576 -180.116988) (xy 123.246304 -180.138413) (xy 123.279658 -180.186153) (xy 123.305373 -180.238406)
			(xy 123.322854 -180.293958) (xy 123.331694 -180.351521) (xy 123.33224 -180.38064) (xy 123.331753 -180.40801)
			(xy 123.323943 -180.462188) (xy 123.308459 -180.514692) (xy 123.285622 -180.564439) (xy 123.2559 -180.610406)
			(xy 123.23826 -180.631338) (xy 123.232164 -180.63845) (xy 123.225814 -180.655468) (xy 123.225814 -180.740812)
			(xy 123.232164 -180.75783) (xy 123.23826 -180.764942) (xy 123.25594 -180.785843) (xy 123.285665 -180.831816)
			(xy 123.308508 -180.881567) (xy 123.324002 -180.934074) (xy 123.331827 -180.988257) (xy 123.331823 -181.043003)
			(xy 123.323989 -181.097185) (xy 123.308487 -181.149689) (xy 123.285636 -181.199437) (xy 123.255904 -181.245405)
			(xy 123.23826 -181.266338) (xy 123.232164 -181.27345) (xy 123.225814 -181.290468) (xy 123.225814 -181.375812)
			(xy 123.232164 -181.39283) (xy 123.23826 -181.399942) (xy 123.255879 -181.42089) (xy 123.285595 -181.466858)
			(xy 123.308436 -181.516601) (xy 123.323931 -181.569099) (xy 123.331764 -181.623272) (xy 123.33224 -181.65064)
			(xy 123.331759 -181.677891) (xy 123.323998 -181.731837) (xy 123.30864 -181.78413) (xy 123.285996 -181.833705)
			(xy 123.256529 -181.879554) (xy 123.220837 -181.920743) (xy 123.179647 -181.956434) (xy 123.133798 -181.9859)
			(xy 123.084222 -182.008543) (xy 123.031929 -182.0239) (xy 122.977983 -182.03166) (xy 122.950732 -182.032148)
			(xy 122.923362 -182.031676) (xy 122.869183 -182.023861) (xy 122.816679 -182.008374) (xy 122.766932 -181.985534)
			(xy 122.720965 -181.955809) (xy 122.700034 -181.938168) (xy 122.692922 -181.932072) (xy 122.675904 -181.925722)
			(xy 122.59056 -181.925722) (xy 122.573542 -181.932072) (xy 122.56643 -181.938168) (xy 122.545493 -181.955802)
			(xy 122.499522 -181.985515) (xy 122.449776 -182.008353) (xy 122.397276 -182.023845) (xy 122.343101 -182.031674)
			(xy 122.315732 -182.032148) (xy 122.286254 -182.031603) (xy 122.228001 -182.022537) (xy 122.171836 -182.004617)
			(xy 122.119096 -181.978268) (xy 122.071039 -181.944119) (xy 122.04954 -181.923944) (xy 122.042193 -181.917426)
			(xy 122.024042 -181.909973) (xy 122.014234 -181.909466) (xy 121.960894 -181.909466) (xy 121.954036 -181.916832)
			(xy 121.947486 -181.924154) (xy 121.940052 -181.942324) (xy 121.939558 -181.952138) (xy 121.939558 -181.984142)
			(xy 121.940043 -181.993956) (xy 121.94749 -182.01212) (xy 121.954036 -182.019448) (xy 121.97423 -182.040929)
			(xy 122.008372 -182.088993) (xy 122.034715 -182.141737) (xy 122.052632 -182.197906) (xy 122.061694 -182.256162)
			(xy 122.06224 -182.28564) (xy 122.061754 -182.312891) (xy 122.053998 -182.366839) (xy 122.038643 -182.419134)
			(xy 122.016001 -182.468711) (xy 121.986535 -182.514561) (xy 121.950844 -182.555752) (xy 121.909653 -182.591443)
			(xy 121.863803 -182.620909) (xy 121.814226 -182.643551) (xy 121.761931 -182.658906) (xy 121.707983 -182.666662)
			(xy 121.653481 -182.666662) (xy 121.599533 -182.658906) (xy 121.547238 -182.643551) (xy 121.497661 -182.620909)
			(xy 121.451811 -182.591443) (xy 121.41062 -182.555752) (xy 121.374929 -182.514561) (xy 121.345463 -182.468711)
			(xy 121.322821 -182.419134) (xy 121.307466 -182.366839) (xy 121.29971 -182.312891) (xy 121.299224 -182.28564)
			(xy 118.565168 -182.28564) (xy 118.565168 -182.64505) (xy 118.565615 -182.655056) (xy 118.573343 -182.673519)
			(xy 118.580154 -182.680864) (xy 118.966234 -183.066944) (xy 118.983536 -183.084972) (xy 119.012908 -183.125391)
			(xy 119.035607 -183.169901) (xy 119.051076 -183.21741) (xy 119.058936 -183.266753) (xy 119.059452 -183.291734)
			(xy 119.059452 -183.677306) (xy 119.0596 -183.68433) (xy 119.063352 -183.697864) (xy 119.066818 -183.703976)
			(xy 119.080143 -183.726541) (xy 119.10113 -183.774559) (xy 119.115344 -183.824999) (xy 119.122518 -183.87691)
			(xy 119.122952 -183.903112) (xy 119.122414 -183.93223) (xy 119.113567 -183.989791) (xy 119.09608 -184.045341)
			(xy 119.070359 -184.09759) (xy 119.037002 -184.145327) (xy 119.017288 -184.166764) (xy 119.01043 -184.173876)
			(xy 119.003318 -184.19191) (xy 119.003318 -184.28208) (xy 119.010684 -184.300114) (xy 119.017542 -184.307226)
			(xy 119.037386 -184.328688) (xy 119.070982 -184.376519) (xy 119.096891 -184.428914) (xy 119.114505 -184.484647)
			(xy 119.123413 -184.542415) (xy 119.123968 -184.57164) (xy 119.123559 -184.598894) (xy 119.115796 -184.652847)
			(xy 119.100434 -184.705145) (xy 119.077785 -184.754725) (xy 119.048311 -184.800577) (xy 119.012612 -184.841768)
			(xy 118.971413 -184.877459) (xy 118.925555 -184.906924) (xy 118.87597 -184.929562) (xy 118.823668 -184.944913)
			(xy 118.769714 -184.952665) (xy 118.74246 -184.953148) (xy 118.716175 -184.952671) (xy 118.664099 -184.945476)
			(xy 118.613504 -184.931202) (xy 118.565348 -184.910117) (xy 118.520541 -184.882622) (xy 118.479933 -184.849236)
			(xy 118.46179 -184.830212) (xy 118.454779 -184.823327) (xy 118.43702 -184.814961) (xy 118.427246 -184.813956)
			(xy 118.373906 -184.811162) (xy 118.366286 -184.818274) (xy 118.366286 -184.871614) (xy 118.366778 -184.881428)
			(xy 118.374219 -184.899592) (xy 118.380764 -184.90692) (xy 118.400949 -184.928409) (xy 118.435092 -184.976472)
			(xy 118.461436 -185.029214) (xy 118.479354 -185.08538) (xy 118.48842 -185.143634) (xy 118.488968 -185.173112)
			(xy 118.488556 -185.200367) (xy 118.480797 -185.254322) (xy 118.465437 -185.306623) (xy 118.44279 -185.356206)
			(xy 118.413317 -185.402061) (xy 118.377618 -185.443255) (xy 118.336419 -185.478948) (xy 118.29056 -185.508415)
			(xy 118.240974 -185.531055) (xy 118.188671 -185.546408) (xy 118.134715 -185.55416) (xy 118.10746 -185.55462)
			(xy 118.077984 -185.554037) (xy 118.019733 -185.544978) (xy 117.963569 -185.527065) (xy 117.910829 -185.500725)
			(xy 117.862769 -185.466586) (xy 117.841268 -185.446416) (xy 117.833937 -185.439877) (xy 117.815774 -185.432434)
			(xy 117.805962 -185.431938) (xy 117.752622 -185.431938) (xy 117.745764 -185.439304) (xy 117.73923 -185.446639)
			(xy 117.731786 -185.464799) (xy 117.731286 -185.47461) (xy 117.731286 -185.506614) (xy 117.731778 -185.516428)
			(xy 117.739219 -185.534592) (xy 117.745764 -185.54192) (xy 117.765949 -185.563409) (xy 117.800092 -185.611472)
			(xy 117.826436 -185.664214) (xy 117.844354 -185.72038) (xy 117.85342 -185.778634) (xy 117.853968 -185.808112)
			(xy 117.853482 -185.835363) (xy 117.845726 -185.889311) (xy 117.830371 -185.941606) (xy 117.807729 -185.991183)
			(xy 117.778263 -186.037033) (xy 117.742572 -186.078224) (xy 117.701381 -186.113915) (xy 117.655531 -186.143381)
			(xy 117.605954 -186.166023) (xy 117.553659 -186.181378) (xy 117.499711 -186.189134) (xy 117.445209 -186.189134)
			(xy 117.391261 -186.181378) (xy 117.338966 -186.166023) (xy 117.289389 -186.143381) (xy 117.243539 -186.113915)
			(xy 117.202348 -186.078224) (xy 117.166657 -186.037033) (xy 117.137191 -185.991183) (xy 117.114549 -185.941606)
			(xy 117.099194 -185.889311) (xy 117.091438 -185.835363) (xy 117.090952 -185.808112) (xy 117.091412 -185.780741)
			(xy 117.09923 -185.726562) (xy 117.114719 -185.674058) (xy 117.137563 -185.624311) (xy 117.167289 -185.578345)
			(xy 117.184932 -185.557414) (xy 117.191028 -185.550302) (xy 117.197378 -185.533284) (xy 117.197378 -185.44794)
			(xy 117.191028 -185.430922) (xy 117.184932 -185.42381) (xy 117.167303 -185.402868) (xy 117.137577 -185.356902)
			(xy 117.114731 -185.307157) (xy 117.099233 -185.254656) (xy 117.091404 -185.200479) (xy 117.091402 -185.145739)
			(xy 117.09923 -185.091561) (xy 117.114724 -185.03906) (xy 117.137568 -184.989314) (xy 117.167292 -184.943347)
			(xy 117.184932 -184.922414) (xy 117.191028 -184.915302) (xy 117.197378 -184.898284) (xy 117.197378 -184.81294)
			(xy 117.191028 -184.795922) (xy 117.184932 -184.78881) (xy 117.167289 -184.767881) (xy 117.137577 -184.721908)
			(xy 117.114741 -184.67216) (xy 117.099251 -184.619658) (xy 117.091425 -184.565481) (xy 117.090952 -184.538112)
			(xy 117.091455 -184.510814) (xy 117.099223 -184.456774) (xy 117.114618 -184.404394) (xy 117.137324 -184.354744)
			(xy 117.166878 -184.308839) (xy 117.184424 -184.287922) (xy 117.190774 -184.28081) (xy 117.19687 -184.263792)
			(xy 117.19687 -184.178194) (xy 117.19052 -184.16143) (xy 117.184424 -184.154318) (xy 117.166722 -184.133347)
			(xy 117.136841 -184.087318) (xy 117.113872 -184.037479) (xy 117.098289 -183.98486) (xy 117.090415 -183.930551)
			(xy 117.089936 -183.903112) (xy 115.109752 -183.903112) (xy 115.109287 -183.930412) (xy 115.101512 -183.984454)
			(xy 115.08611 -184.036836) (xy 115.063395 -184.086485) (xy 115.033831 -184.132387) (xy 115.01628 -184.153302)
			(xy 115.00993 -184.160414) (xy 115.003834 -184.177432) (xy 115.003834 -184.26303) (xy 115.010184 -184.279794)
			(xy 115.01628 -184.286906) (xy 115.033993 -184.307868) (xy 115.063873 -184.353899) (xy 115.08684 -184.403741)
			(xy 115.10242 -184.456361) (xy 115.110291 -184.510673) (xy 115.110768 -184.538112) (xy 115.110317 -184.565483)
			(xy 115.102497 -184.619663) (xy 115.087004 -184.672166) (xy 115.064159 -184.721913) (xy 115.034431 -184.767879)
			(xy 115.016788 -184.78881) (xy 115.010692 -184.795922) (xy 115.004342 -184.81294) (xy 115.004342 -184.898284)
			(xy 115.010692 -184.915302) (xy 115.016788 -184.922414) (xy 115.03444 -184.943338) (xy 115.064163 -184.989307)
			(xy 115.087007 -185.039055) (xy 115.102501 -185.091558) (xy 115.110329 -185.145738) (xy 115.110327 -185.20048)
			(xy 115.102498 -185.254659) (xy 115.087 -185.307162) (xy 115.064154 -185.356909) (xy 115.034429 -185.402877)
			(xy 115.016788 -185.42381) (xy 115.010692 -185.430922) (xy 115.004342 -185.44794) (xy 115.004342 -185.533284)
			(xy 115.010692 -185.550302) (xy 115.016788 -185.557414) (xy 115.03444 -185.578338) (xy 115.064163 -185.624307)
			(xy 115.087007 -185.674055) (xy 115.102501 -185.726558) (xy 115.110329 -185.780738) (xy 115.110327 -185.83548)
			(xy 115.102498 -185.889659) (xy 115.087 -185.942162) (xy 115.064154 -185.991909) (xy 115.034429 -186.037877)
			(xy 115.016788 -186.05881) (xy 115.010692 -186.065922) (xy 115.004342 -186.08294) (xy 115.004342 -186.168284)
			(xy 115.010692 -186.185302) (xy 115.016788 -186.192414) (xy 115.034398 -186.213369) (xy 115.064115 -186.259335)
			(xy 115.086957 -186.309077) (xy 115.102454 -186.361573) (xy 115.11029 -186.415744) (xy 115.110768 -186.443112)
			(xy 115.110228 -186.472337) (xy 115.101304 -186.530102) (xy 115.083683 -186.585833) (xy 115.057774 -186.638227)
			(xy 115.024184 -186.686062) (xy 115.004342 -186.707526) (xy 114.997484 -186.714638) (xy 114.990118 -186.732672)
			(xy 114.990118 -186.822842) (xy 114.99723 -186.840876) (xy 115.004088 -186.847988) (xy 115.023818 -186.869411)
			(xy 115.057171 -186.917152) (xy 115.082886 -186.969405) (xy 115.100366 -187.024958) (xy 115.109206 -187.082521)
			(xy 115.109752 -187.11164) (xy 115.109262 -187.13901) (xy 115.101452 -187.193188) (xy 115.085969 -187.245691)
			(xy 115.063132 -187.295439) (xy 115.033412 -187.341406) (xy 115.015772 -187.362338) (xy 115.009676 -187.36945)
			(xy 115.003326 -187.386468) (xy 115.003326 -187.471812) (xy 115.009676 -187.48883) (xy 115.015772 -187.495942)
			(xy 115.033452 -187.516843) (xy 115.063175 -187.562816) (xy 115.086018 -187.612568) (xy 115.101511 -187.665075)
			(xy 115.109336 -187.719258) (xy 115.109332 -187.774003) (xy 115.101499 -187.828184) (xy 115.085997 -187.880689)
			(xy 115.063146 -187.930437) (xy 115.033416 -187.976405) (xy 115.015772 -187.997338) (xy 115.009676 -188.00445)
			(xy 115.003326 -188.021468) (xy 115.003326 -188.106812) (xy 115.009676 -188.12383) (xy 115.015772 -188.130942)
			(xy 115.033393 -188.151889) (xy 115.063109 -188.197857) (xy 115.085948 -188.247601) (xy 115.101444 -188.300098)
			(xy 115.109276 -188.354272) (xy 115.109752 -188.38164) (xy 115.10926 -188.40889) (xy 115.101499 -188.462835)
			(xy 115.086141 -188.515127) (xy 115.063498 -188.564702) (xy 115.034032 -188.61055) (xy 114.998341 -188.651738)
			(xy 114.957153 -188.687429) (xy 114.911305 -188.716896) (xy 114.861731 -188.739539) (xy 114.809439 -188.754898)
			(xy 114.755494 -188.762659) (xy 114.728244 -188.763148) (xy 114.700874 -188.762669) (xy 114.646695 -188.754856)
			(xy 114.594192 -188.739371) (xy 114.544444 -188.716532) (xy 114.498478 -188.686809) (xy 114.477546 -188.669168)
			(xy 114.470434 -188.663072) (xy 114.453416 -188.656722) (xy 114.368072 -188.656722) (xy 114.351054 -188.663072)
			(xy 114.343942 -188.669168) (xy 114.323009 -188.686809) (xy 114.277041 -188.716533) (xy 114.227295 -188.739379)
			(xy 114.174793 -188.754875) (xy 114.120615 -188.762704) (xy 114.065873 -188.762704) (xy 114.011695 -188.754875)
			(xy 113.959193 -188.739379) (xy 113.909447 -188.716533) (xy 113.863479 -188.686809) (xy 113.842546 -188.669168)
			(xy 113.835434 -188.663072) (xy 113.818416 -188.656722) (xy 113.733072 -188.656722) (xy 113.716054 -188.663072)
			(xy 113.708942 -188.669168) (xy 113.688001 -188.686796) (xy 113.642031 -188.716511) (xy 113.592286 -188.739349)
			(xy 113.539787 -188.754843) (xy 113.485613 -188.762673) (xy 113.458244 -188.763148) (xy 113.430994 -188.762604)
			(xy 113.377048 -188.754854) (xy 113.324754 -188.739506) (xy 113.275177 -188.716871) (xy 113.229325 -188.687411)
			(xy 113.188133 -188.651726) (xy 113.152439 -188.610542) (xy 113.122969 -188.564697) (xy 113.100324 -188.515125)
			(xy 113.084964 -188.462834) (xy 113.077202 -188.40889) (xy 113.076736 -188.38164) (xy 110.325916 -188.38164)
			(xy 110.325916 -189.446408) (xy 110.326304 -189.455509) (xy 110.332683 -189.47256) (xy 110.338362 -189.479682)
			(xy 110.352963 -189.497109) (xy 110.377609 -189.53531) (xy 110.396557 -189.576635) (xy 110.40942 -189.620239)
			(xy 110.415935 -189.665231) (xy 110.41634 -189.687962) (xy 110.41634 -189.929516) (xy 110.416524 -189.936537)
			(xy 110.420251 -189.950072) (xy 110.423706 -189.956186) (xy 110.437034 -189.978749) (xy 110.45802 -190.026768)
			(xy 110.472234 -190.077208) (xy 110.479407 -190.12912) (xy 110.47984 -190.155322) (xy 110.479359 -190.182621)
			(xy 110.471585 -190.236662) (xy 110.456186 -190.289042) (xy 110.433475 -190.338692) (xy 110.403916 -190.384596)
			(xy 110.386368 -190.405512) (xy 110.380018 -190.412624) (xy 110.373922 -190.429642) (xy 110.373922 -190.51524)
			(xy 110.380272 -190.532004) (xy 110.386368 -190.539116) (xy 110.404084 -190.560076) (xy 110.433964 -190.606107)
			(xy 110.45693 -190.655949) (xy 110.47251 -190.708571) (xy 110.480379 -190.762882) (xy 110.480856 -190.790322)
			(xy 110.480414 -190.817693) (xy 110.472592 -190.871874) (xy 110.457098 -190.924378) (xy 110.43425 -190.974124)
			(xy 110.40452 -191.020089) (xy 110.386876 -191.04102) (xy 110.38078 -191.048132) (xy 110.37443 -191.06515)
			(xy 110.37443 -191.150494) (xy 110.38078 -191.167512) (xy 110.386876 -191.174624) (xy 110.404538 -191.195539)
			(xy 110.434262 -191.24151) (xy 110.457106 -191.291259) (xy 110.4726 -191.343764) (xy 110.480427 -191.397945)
			(xy 110.480424 -191.452688) (xy 110.472593 -191.506868) (xy 110.457094 -191.559372) (xy 110.434246 -191.609119)
			(xy 110.404518 -191.655087) (xy 110.386876 -191.67602) (xy 110.38078 -191.683132) (xy 110.37443 -191.70015)
			(xy 110.37443 -191.785494) (xy 110.38078 -191.802512) (xy 110.386876 -191.809624) (xy 110.404489 -191.830577)
			(xy 110.434206 -191.876544) (xy 110.457047 -191.926286) (xy 110.472544 -191.978782) (xy 110.480379 -192.032954)
			(xy 110.480856 -192.060322) (xy 110.480343 -192.087572) (xy 110.472585 -192.141516) (xy 110.457229 -192.193807)
			(xy 110.434589 -192.243381) (xy 110.405125 -192.289229) (xy 110.369436 -192.330418) (xy 110.32825 -192.366109)
			(xy 110.282404 -192.395576) (xy 110.232832 -192.41822) (xy 110.180541 -192.433579) (xy 110.126598 -192.441341)
			(xy 110.099348 -192.44183) (xy 110.069871 -192.441279) (xy 110.011617 -192.432216) (xy 109.955452 -192.414297)
			(xy 109.902712 -192.387949) (xy 109.854655 -192.353801) (xy 109.833156 -192.333626) (xy 109.825839 -192.327069)
			(xy 109.807665 -192.319639) (xy 109.79785 -192.319148) (xy 109.74451 -192.319148) (xy 109.737652 -192.326514)
			(xy 109.731112 -192.333844) (xy 109.723671 -192.352008) (xy 109.723174 -192.36182) (xy 109.723174 -192.393824)
			(xy 109.723664 -192.403638) (xy 109.731107 -192.421802) (xy 109.737652 -192.42913) (xy 109.75784 -192.450617)
			(xy 109.791983 -192.49868) (xy 109.818326 -192.551422) (xy 109.836244 -192.607589) (xy 109.845309 -192.665844)
			(xy 109.845856 -192.695322) (xy 109.84537 -192.722573) (xy 109.837614 -192.776521) (xy 109.822259 -192.828816)
			(xy 109.799617 -192.878393) (xy 109.770151 -192.924243) (xy 109.73446 -192.965434) (xy 109.693269 -193.001125)
			(xy 109.647419 -193.030591) (xy 109.597842 -193.053233) (xy 109.545547 -193.068588) (xy 109.491599 -193.076344)
			(xy 109.437097 -193.076344) (xy 109.383149 -193.068588) (xy 109.330854 -193.053233) (xy 109.281277 -193.030591)
			(xy 109.235427 -193.001125) (xy 109.194236 -192.965434) (xy 109.158545 -192.924243) (xy 109.129079 -192.878393)
			(xy 109.106437 -192.828816) (xy 109.091082 -192.776521) (xy 109.083326 -192.722573) (xy 109.08284 -192.695322)
			(xy 109.083309 -192.667952) (xy 109.091125 -192.613772) (xy 109.106613 -192.561269) (xy 109.129454 -192.511522)
			(xy 109.159179 -192.465555) (xy 109.17682 -192.444624) (xy 109.182916 -192.437512) (xy 109.189266 -192.420494)
			(xy 109.189266 -192.33515) (xy 109.182916 -192.318132) (xy 109.17682 -192.31102) (xy 109.159201 -192.29007)
			(xy 109.129476 -192.244105) (xy 109.10663 -192.194361) (xy 109.091132 -192.141862) (xy 109.083302 -192.087686)
			(xy 109.083299 -192.032947) (xy 109.091125 -191.97877) (xy 109.106618 -191.92627) (xy 109.12946 -191.876524)
			(xy 109.159181 -191.830557) (xy 109.17682 -191.809624) (xy 109.182916 -191.802512) (xy 109.189266 -191.785494)
			(xy 109.189266 -191.70015) (xy 109.182916 -191.683132) (xy 109.17682 -191.67602) (xy 109.159201 -191.65507)
			(xy 109.129476 -191.609105) (xy 109.10663 -191.559361) (xy 109.091132 -191.506862) (xy 109.083302 -191.452686)
			(xy 109.083299 -191.397947) (xy 109.091125 -191.34377) (xy 109.106618 -191.29127) (xy 109.12946 -191.241524)
			(xy 109.159181 -191.195557) (xy 109.17682 -191.174624) (xy 109.182916 -191.167512) (xy 109.189266 -191.150494)
			(xy 109.189266 -191.06515) (xy 109.182916 -191.048132) (xy 109.17682 -191.04102) (xy 109.15918 -191.020089)
			(xy 109.129468 -190.974116) (xy 109.106631 -190.924368) (xy 109.091141 -190.871867) (xy 109.083313 -190.817691)
			(xy 109.08284 -190.790322) (xy 109.083269 -190.763021) (xy 109.091052 -190.708977) (xy 109.106463 -190.656595)
			(xy 109.129186 -190.606947) (xy 109.158757 -190.561046) (xy 109.176312 -190.540132) (xy 109.182662 -190.53302)
			(xy 109.188758 -190.516002) (xy 109.188758 -190.430404) (xy 109.182408 -190.41364) (xy 109.176312 -190.406528)
			(xy 109.158566 -190.385592) (xy 109.128692 -190.339554) (xy 109.105731 -190.289705) (xy 109.090159 -190.237079)
			(xy 109.082297 -190.182763) (xy 109.081824 -190.155322) (xy 107.10164 -190.155322) (xy 107.101159 -190.182621)
			(xy 107.093385 -190.236662) (xy 107.077986 -190.289042) (xy 107.055275 -190.338692) (xy 107.025716 -190.384596)
			(xy 107.008168 -190.405512) (xy 107.001818 -190.412624) (xy 106.995722 -190.429642) (xy 106.995722 -190.51524)
			(xy 107.002072 -190.532004) (xy 107.008168 -190.539116) (xy 107.025884 -190.560076) (xy 107.055764 -190.606107)
			(xy 107.07873 -190.655949) (xy 107.09431 -190.708571) (xy 107.102179 -190.762882) (xy 107.102656 -190.790322)
			(xy 107.102214 -190.817693) (xy 107.094392 -190.871874) (xy 107.078898 -190.924378) (xy 107.05605 -190.974124)
			(xy 107.02632 -191.020089) (xy 107.008676 -191.04102) (xy 107.00258 -191.048132) (xy 106.99623 -191.06515)
			(xy 106.99623 -191.150494) (xy 107.00258 -191.167512) (xy 107.008676 -191.174624) (xy 107.026338 -191.195539)
			(xy 107.056062 -191.24151) (xy 107.078906 -191.291259) (xy 107.0944 -191.343764) (xy 107.102227 -191.397945)
			(xy 107.102224 -191.452688) (xy 107.094393 -191.506868) (xy 107.078894 -191.559372) (xy 107.056046 -191.609119)
			(xy 107.026318 -191.655087) (xy 107.008676 -191.67602) (xy 107.00258 -191.683132) (xy 106.99623 -191.70015)
			(xy 106.99623 -191.785494) (xy 107.00258 -191.802512) (xy 107.008676 -191.809624) (xy 107.026338 -191.830539)
			(xy 107.056062 -191.87651) (xy 107.078906 -191.926259) (xy 107.0944 -191.978764) (xy 107.102227 -192.032945)
			(xy 107.102224 -192.087688) (xy 107.094393 -192.141868) (xy 107.078894 -192.194372) (xy 107.056046 -192.244119)
			(xy 107.026318 -192.290087) (xy 107.008676 -192.31102) (xy 107.00258 -192.318132) (xy 106.99623 -192.33515)
			(xy 106.99623 -192.420494) (xy 107.00258 -192.437512) (xy 107.008676 -192.444624) (xy 107.026289 -192.465577)
			(xy 107.056006 -192.511544) (xy 107.078847 -192.561286) (xy 107.094344 -192.613782) (xy 107.102179 -192.667954)
			(xy 107.102656 -192.695322) (xy 107.102128 -192.723196) (xy 107.094024 -192.77835) (xy 107.077978 -192.831738)
			(xy 107.054332 -192.882221) (xy 107.023588 -192.928725) (xy 107.005374 -192.94983) (xy 106.999278 -192.956688)
			(xy 106.99242 -192.97396) (xy 106.99242 -193.060574) (xy 106.999024 -193.077846) (xy 107.00512 -193.084958)
			(xy 107.023207 -193.106005) (xy 107.053727 -193.152351) (xy 107.077195 -193.202636) (xy 107.093115 -193.255796)
			(xy 107.101149 -193.310704) (xy 107.10164 -193.33845) (xy 107.101159 -193.36582) (xy 107.093347 -193.419999)
			(xy 107.077862 -193.472502) (xy 107.055024 -193.52225) (xy 107.025301 -193.568216) (xy 107.00766 -193.589148)
			(xy 107.001564 -193.59626) (xy 106.995214 -193.613278) (xy 106.995214 -193.698622) (xy 107.001564 -193.71564)
			(xy 107.00766 -193.722752) (xy 107.02535 -193.743645) (xy 107.055074 -193.789619) (xy 107.077917 -193.839372)
			(xy 107.09341 -193.89188) (xy 107.101234 -193.946065) (xy 107.101229 -194.000811) (xy 107.093394 -194.054993)
			(xy 107.077891 -194.107499) (xy 107.055038 -194.157247) (xy 107.025305 -194.203215) (xy 107.00766 -194.224148)
			(xy 107.001564 -194.23126) (xy 106.995214 -194.248278) (xy 106.995214 -194.333622) (xy 107.001564 -194.35064)
			(xy 107.00766 -194.357752) (xy 107.025284 -194.378696) (xy 107.054999 -194.424665) (xy 107.077839 -194.47441)
			(xy 107.093333 -194.526908) (xy 107.101165 -194.581082) (xy 107.10164 -194.60845) (xy 107.101098 -194.6357)
			(xy 107.093349 -194.689647) (xy 107.078001 -194.741941) (xy 107.055367 -194.791519) (xy 107.025907 -194.837371)
			(xy 106.990221 -194.878563) (xy 106.949036 -194.914258) (xy 106.903191 -194.943727) (xy 106.853618 -194.966372)
			(xy 106.801327 -194.981732) (xy 106.747382 -194.989492) (xy 106.720132 -194.989958) (xy 106.690655 -194.98941)
			(xy 106.632401 -194.980344) (xy 106.576236 -194.962424) (xy 106.523497 -194.936077) (xy 106.475439 -194.901929)
			(xy 106.45394 -194.881754) (xy 106.446592 -194.875237) (xy 106.428442 -194.867783) (xy 106.418634 -194.867276)
			(xy 106.365294 -194.867276) (xy 106.358436 -194.874642) (xy 106.351881 -194.881961) (xy 106.34445 -194.900134)
			(xy 106.343958 -194.909948) (xy 106.343958 -194.941952) (xy 106.344438 -194.951767) (xy 106.351888 -194.96993)
			(xy 106.358436 -194.977258) (xy 106.378587 -194.998778) (xy 106.412735 -195.046832) (xy 106.439086 -195.099566)
			(xy 106.457013 -195.155726) (xy 106.466088 -195.213974) (xy 106.46664 -195.24345) (xy 106.466098 -195.2707)
			(xy 106.458349 -195.324647) (xy 106.443001 -195.376941) (xy 106.420367 -195.426519) (xy 106.390907 -195.472371)
			(xy 106.355221 -195.513563) (xy 106.314036 -195.549258) (xy 106.268191 -195.578727) (xy 106.218618 -195.601372)
			(xy 106.166327 -195.616732) (xy 106.112382 -195.624492) (xy 106.085132 -195.624958) (xy 106.055655 -195.62441)
			(xy 105.997401 -195.615344) (xy 105.941236 -195.597424) (xy 105.888497 -195.571077) (xy 105.840439 -195.536929)
			(xy 105.81894 -195.516754) (xy 105.811592 -195.510237) (xy 105.793442 -195.502783) (xy 105.783634 -195.502276)
			(xy 105.730294 -195.502276) (xy 105.723436 -195.509642) (xy 105.716881 -195.516961) (xy 105.70945 -195.535134)
			(xy 105.708958 -195.544948) (xy 105.708958 -195.576952) (xy 105.709438 -195.586767) (xy 105.716888 -195.60493)
			(xy 105.723436 -195.612258) (xy 105.743587 -195.633778) (xy 105.777735 -195.681832) (xy 105.804086 -195.734566)
			(xy 105.822013 -195.790726) (xy 105.831088 -195.848974) (xy 105.83164 -195.87845) (xy 105.831154 -195.905701)
			(xy 105.823398 -195.959649) (xy 105.808043 -196.011944) (xy 105.785401 -196.061521) (xy 105.755935 -196.107371)
			(xy 105.720244 -196.148562) (xy 105.679053 -196.184253) (xy 105.633203 -196.213719) (xy 105.583626 -196.236361)
			(xy 105.531331 -196.251716) (xy 105.477383 -196.259472) (xy 105.422881 -196.259472) (xy 105.368933 -196.251716)
			(xy 105.316638 -196.236361) (xy 105.267061 -196.213719) (xy 105.221211 -196.184253) (xy 105.18002 -196.148562)
			(xy 105.144329 -196.107371) (xy 105.114863 -196.061521) (xy 105.092221 -196.011944) (xy 105.076866 -195.959649)
			(xy 105.06911 -195.905701) (xy 105.068624 -195.87845) (xy 101.966201 -195.87845) (xy 101.970988 -195.894674)
			(xy 101.978814 -195.948857) (xy 101.978809 -196.003603) (xy 101.970975 -196.057785) (xy 101.955472 -196.11029)
			(xy 101.93262 -196.160038) (xy 101.902887 -196.206006) (xy 101.885242 -196.226938) (xy 101.879146 -196.23405)
			(xy 101.872796 -196.251068) (xy 101.872796 -196.336412) (xy 101.879146 -196.35343) (xy 101.885242 -196.360542)
			(xy 101.902923 -196.381442) (xy 101.932649 -196.427415) (xy 101.955494 -196.477166) (xy 101.970988 -196.529674)
			(xy 101.978814 -196.583857) (xy 101.978809 -196.638603) (xy 101.970975 -196.692785) (xy 101.955472 -196.74529)
			(xy 101.93262 -196.795038) (xy 101.902887 -196.841006) (xy 101.885242 -196.861938) (xy 101.879146 -196.86905)
			(xy 101.872796 -196.886068) (xy 101.872796 -196.971412) (xy 101.879146 -196.98843) (xy 101.885242 -196.995542)
			(xy 101.902923 -197.016442) (xy 101.932649 -197.062415) (xy 101.955494 -197.112166) (xy 101.970988 -197.164674)
			(xy 101.978814 -197.218857) (xy 101.978809 -197.273603) (xy 101.970975 -197.327785) (xy 101.955472 -197.38029)
			(xy 101.93262 -197.430038) (xy 101.902887 -197.476006) (xy 101.885242 -197.496938) (xy 101.879146 -197.50405)
			(xy 101.872796 -197.521068) (xy 101.872796 -197.606412) (xy 101.879146 -197.62343) (xy 101.885242 -197.630542)
			(xy 101.902923 -197.651442) (xy 101.932649 -197.697415) (xy 101.955494 -197.747166) (xy 101.970988 -197.799674)
			(xy 101.978814 -197.853857) (xy 101.978809 -197.908603) (xy 101.970975 -197.962785) (xy 101.955472 -198.01529)
			(xy 101.93262 -198.065038) (xy 101.902887 -198.111006) (xy 101.885242 -198.131938) (xy 101.879146 -198.13905)
			(xy 101.872796 -198.156068) (xy 101.872796 -198.241412) (xy 101.879146 -198.25843) (xy 101.885242 -198.265542)
			(xy 101.902923 -198.286442) (xy 101.932649 -198.332415) (xy 101.955494 -198.382166) (xy 101.970988 -198.434674)
			(xy 101.978814 -198.488857) (xy 101.978809 -198.543603) (xy 101.970975 -198.597785) (xy 101.955472 -198.65029)
			(xy 101.93262 -198.700038) (xy 101.902887 -198.746006) (xy 101.885242 -198.766938) (xy 101.879146 -198.77405)
			(xy 101.872796 -198.791068) (xy 101.872796 -198.876412) (xy 101.879146 -198.89343) (xy 101.885242 -198.900542)
			(xy 101.902874 -198.921479) (xy 101.932586 -198.967451) (xy 101.955422 -199.017198) (xy 101.970915 -199.069697)
			(xy 101.978747 -199.123871) (xy 101.979222 -199.15124) (xy 101.978759 -199.178492) (xy 101.970998 -199.232439)
			(xy 101.955638 -199.284734) (xy 101.932994 -199.33431) (xy 101.903524 -199.38016) (xy 101.867831 -199.421349)
			(xy 101.826639 -199.45704) (xy 101.780787 -199.486506) (xy 101.731209 -199.509147) (xy 101.678914 -199.524503)
			(xy 101.624966 -199.532261) (xy 101.597714 -199.532748) (xy 101.568166 -199.532171) (xy 101.509778 -199.523062)
			(xy 101.453492 -199.505058) (xy 101.400655 -199.478591) (xy 101.352531 -199.444293) (xy 101.331014 -199.424036)
			(xy 101.323676 -199.417506) (xy 101.305518 -199.41006) (xy 101.295708 -199.409558) (xy 101.242368 -199.409558)
			(xy 101.235002 -199.417432) (xy 101.228461 -199.424762) (xy 101.221019 -199.442926) (xy 101.220524 -199.452738)
			(xy 101.220524 -199.484742) (xy 101.220992 -199.494559) (xy 101.228449 -199.512723) (xy 101.235002 -199.520048)
			(xy 101.25519 -199.541535) (xy 101.289335 -199.589597) (xy 101.315679 -199.642339) (xy 101.333597 -199.698507)
			(xy 101.34266 -199.756762) (xy 101.343206 -199.78624) (xy 101.342759 -199.813492) (xy 101.334997 -199.867442)
			(xy 101.319637 -199.919737) (xy 101.296991 -199.969315) (xy 101.26752 -200.015165) (xy 101.231825 -200.056355)
			(xy 101.190631 -200.092046) (xy 101.144778 -200.121511) (xy 101.095198 -200.144152) (xy 101.0429 -200.159506)
			(xy 100.98895 -200.167262) (xy 100.961698 -200.167748) (xy 100.93222 -200.167224) (xy 100.873965 -200.158153)
			(xy 100.8178 -200.140227) (xy 100.765061 -200.113874) (xy 100.717004 -200.079721) (xy 100.695506 -200.059544)
			(xy 100.68817 -200.053011) (xy 100.67001 -200.045567) (xy 100.6602 -200.045066) (xy 100.60686 -200.045066)
			(xy 100.600002 -200.052432) (xy 100.593461 -200.059762) (xy 100.586019 -200.077926) (xy 100.585524 -200.087738)
			(xy 100.585524 -200.119742) (xy 100.585992 -200.129559) (xy 100.593449 -200.147723) (xy 100.600002 -200.155048)
			(xy 100.62019 -200.176535) (xy 100.654335 -200.224597) (xy 100.680679 -200.277339) (xy 100.698597 -200.333507)
			(xy 100.70766 -200.391762) (xy 100.708206 -200.42124) (xy 100.70772 -200.448491) (xy 100.699964 -200.502439)
			(xy 100.684609 -200.554734) (xy 100.661967 -200.604311) (xy 100.632501 -200.650161) (xy 100.59681 -200.691352)
			(xy 100.555619 -200.727043) (xy 100.509769 -200.756509) (xy 100.460192 -200.779151) (xy 100.407897 -200.794506)
			(xy 100.353949 -200.802262) (xy 100.299447 -200.802262) (xy 100.245499 -200.794506) (xy 100.193204 -200.779151)
			(xy 100.143627 -200.756509) (xy 100.097777 -200.727043) (xy 100.056586 -200.691352) (xy 100.020895 -200.650161)
			(xy 99.991429 -200.604311) (xy 99.968787 -200.554734) (xy 99.953432 -200.502439) (xy 99.945676 -200.448491)
			(xy 99.94519 -200.42124) (xy 97.964597 -200.42124) (xy 97.964597 -200.423203) (xy 97.956763 -200.477386)
			(xy 97.941259 -200.529891) (xy 97.918406 -200.579639) (xy 97.888671 -200.625606) (xy 97.871026 -200.646538)
			(xy 97.86493 -200.65365) (xy 97.85858 -200.670668) (xy 97.85858 -200.756012) (xy 97.86493 -200.77303)
			(xy 97.871026 -200.780142) (xy 97.888655 -200.801082) (xy 97.918368 -200.847053) (xy 97.941205 -200.896798)
			(xy 97.956699 -200.949297) (xy 97.96453 -201.003471) (xy 97.965006 -201.03084) (xy 97.964559 -201.058092)
			(xy 97.956797 -201.112042) (xy 97.941437 -201.164337) (xy 97.918791 -201.213915) (xy 97.88932 -201.259765)
			(xy 97.853625 -201.300955) (xy 97.812431 -201.336646) (xy 97.766578 -201.366111) (xy 97.716998 -201.388752)
			(xy 97.6647 -201.404106) (xy 97.61075 -201.411862) (xy 97.583498 -201.412348) (xy 97.556127 -201.411896)
			(xy 97.501947 -201.404077) (xy 97.449443 -201.388585) (xy 97.399696 -201.36574) (xy 97.353731 -201.336011)
			(xy 97.3328 -201.318368) (xy 97.325688 -201.312272) (xy 97.30867 -201.305922) (xy 97.223326 -201.305922)
			(xy 97.206308 -201.312272) (xy 97.199196 -201.318368) (xy 97.178263 -201.336009) (xy 97.132295 -201.365733)
			(xy 97.082549 -201.388579) (xy 97.030047 -201.404075) (xy 96.975869 -201.411904) (xy 96.921127 -201.411904)
			(xy 96.866949 -201.404075) (xy 96.814447 -201.388579) (xy 96.764701 -201.365733) (xy 96.718733 -201.336009)
			(xy 96.6978 -201.318368) (xy 96.690688 -201.312272) (xy 96.67367 -201.305922) (xy 96.588326 -201.305922)
			(xy 96.571308 -201.312272) (xy 96.564196 -201.318368) (xy 96.543272 -201.336017) (xy 96.497298 -201.365729)
			(xy 96.447548 -201.388563) (xy 96.395045 -201.404052) (xy 96.340868 -201.411876) (xy 96.313498 -201.412348)
			(xy 96.286249 -201.411824) (xy 96.232304 -201.404068) (xy 96.180013 -201.388715) (xy 96.130438 -201.366077)
			(xy 96.08459 -201.336614) (xy 96.0434 -201.300926) (xy 96.007709 -201.259741) (xy 95.978242 -201.213895)
			(xy 95.955598 -201.164323) (xy 95.94024 -201.112033) (xy 95.932479 -201.058089) (xy 95.93199 -201.03084)
			(xy 93.586628 -201.03084) (xy 93.587062 -201.055732) (xy 93.586675 -201.082988) (xy 93.578912 -201.136944)
			(xy 93.56355 -201.189246) (xy 93.5409 -201.238829) (xy 93.511425 -201.284685) (xy 93.475723 -201.325878)
			(xy 93.434522 -201.361571) (xy 93.388661 -201.391038) (xy 93.339073 -201.413677) (xy 93.286768 -201.429029)
			(xy 93.23281 -201.43678) (xy 93.205554 -201.43724) (xy 93.178184 -201.436757) (xy 93.124005 -201.428945)
			(xy 93.071502 -201.413461) (xy 93.021755 -201.390623) (xy 92.975788 -201.360901) (xy 92.954856 -201.34326)
			(xy 92.947744 -201.337164) (xy 92.930726 -201.330814) (xy 92.845382 -201.330814) (xy 92.828364 -201.337164)
			(xy 92.821252 -201.34326) (xy 92.800319 -201.360901) (xy 92.754351 -201.390625) (xy 92.704605 -201.413471)
			(xy 92.652103 -201.428967) (xy 92.597925 -201.436796) (xy 92.543183 -201.436796) (xy 92.489005 -201.428967)
			(xy 92.436503 -201.413471) (xy 92.386757 -201.390625) (xy 92.340789 -201.360901) (xy 92.319856 -201.34326)
			(xy 92.312744 -201.337164) (xy 92.295726 -201.330814) (xy 92.210382 -201.330814) (xy 92.193364 -201.337164)
			(xy 92.186252 -201.34326) (xy 92.165306 -201.360882) (xy 92.119338 -201.390598) (xy 92.069594 -201.413438)
			(xy 92.017096 -201.428933) (xy 91.962922 -201.436764) (xy 91.935554 -201.43724) (xy 91.908303 -201.436765)
			(xy 91.854357 -201.429003) (xy 91.802064 -201.413644) (xy 91.752488 -201.391) (xy 91.70664 -201.361532)
			(xy 91.665451 -201.325839) (xy 91.62976 -201.284649) (xy 91.600294 -201.238799) (xy 91.577651 -201.189223)
			(xy 91.562294 -201.13693) (xy 91.554534 -201.082983) (xy 91.554046 -201.055732) (xy 91.55452 -201.028362)
			(xy 91.562334 -200.974183) (xy 91.577821 -200.921679) (xy 91.600661 -200.871932) (xy 91.630385 -200.825965)
			(xy 91.648026 -200.805034) (xy 91.654122 -200.797922) (xy 91.660472 -200.780904) (xy 91.660472 -200.69556)
			(xy 91.654122 -200.678542) (xy 91.648026 -200.67143) (xy 91.630417 -200.650472) (xy 91.600691 -200.604508)
			(xy 91.577844 -200.554766) (xy 91.562345 -200.502268) (xy 91.554513 -200.448093) (xy 91.55451 -200.393355)
			(xy 91.562335 -200.339179) (xy 91.577827 -200.286679) (xy 91.600667 -200.236934) (xy 91.630388 -200.190967)
			(xy 91.648026 -200.170034) (xy 91.654122 -200.162922) (xy 91.660472 -200.145904) (xy 91.660472 -200.06056)
			(xy 91.654122 -200.043542) (xy 91.648026 -200.03643) (xy 91.630417 -200.015472) (xy 91.600691 -199.969508)
			(xy 91.577844 -199.919766) (xy 91.562345 -199.867268) (xy 91.554513 -199.813093) (xy 91.55451 -199.758355)
			(xy 91.562335 -199.704179) (xy 91.577827 -199.651679) (xy 91.600667 -199.601934) (xy 91.630388 -199.555967)
			(xy 91.648026 -199.535034) (xy 91.654122 -199.527922) (xy 91.660472 -199.510904) (xy 91.660472 -199.42556)
			(xy 91.654122 -199.408542) (xy 91.648026 -199.40143) (xy 91.630417 -199.380472) (xy 91.600691 -199.334508)
			(xy 91.577844 -199.284766) (xy 91.562345 -199.232268) (xy 91.554513 -199.178093) (xy 91.55451 -199.123355)
			(xy 91.562335 -199.069179) (xy 91.577827 -199.016679) (xy 91.600667 -198.966934) (xy 91.630388 -198.920967)
			(xy 91.648026 -198.900034) (xy 91.654122 -198.892922) (xy 91.660472 -198.875904) (xy 91.660472 -198.79056)
			(xy 91.654122 -198.773542) (xy 91.648026 -198.76643) (xy 91.630417 -198.745472) (xy 91.600691 -198.699508)
			(xy 91.577844 -198.649766) (xy 91.562345 -198.597268) (xy 91.554513 -198.543093) (xy 91.55451 -198.488355)
			(xy 91.562335 -198.434179) (xy 91.577827 -198.381679) (xy 91.600667 -198.331934) (xy 91.630388 -198.285967)
			(xy 91.648026 -198.265034) (xy 91.654122 -198.257922) (xy 91.660472 -198.240904) (xy 91.660472 -198.15556)
			(xy 91.654122 -198.138542) (xy 91.648026 -198.13143) (xy 91.630392 -198.110494) (xy 91.600678 -198.064523)
			(xy 91.577841 -198.014776) (xy 91.562349 -197.962276) (xy 91.55452 -197.908101) (xy 91.554046 -197.880732)
			(xy 91.554513 -197.853128) (xy 91.562479 -197.798496) (xy 91.578235 -197.745583) (xy 91.601453 -197.695494)
			(xy 91.631646 -197.649273) (xy 91.64955 -197.628256) (xy 91.655646 -197.621144) (xy 91.66225 -197.603872)
			(xy 91.66225 -197.51802) (xy 91.655646 -197.500748) (xy 91.64955 -197.493636) (xy 91.631632 -197.472632)
			(xy 91.601442 -197.426408) (xy 91.578232 -197.376314) (xy 91.562485 -197.323398) (xy 91.554532 -197.268765)
			(xy 91.554046 -197.24116) (xy 91.554536 -197.213791) (xy 91.562346 -197.159612) (xy 91.577829 -197.107109)
			(xy 91.600666 -197.057361) (xy 91.630386 -197.011394) (xy 91.648026 -196.990462) (xy 91.654122 -196.98335)
			(xy 91.660472 -196.966332) (xy 91.660472 -196.880988) (xy 91.654122 -196.86397) (xy 91.648026 -196.856858)
			(xy 91.630346 -196.835957) (xy 91.600623 -196.789984) (xy 91.57778 -196.740232) (xy 91.562287 -196.687725)
			(xy 91.554462 -196.633542) (xy 91.554466 -196.578797) (xy 91.5623 -196.524616) (xy 91.577801 -196.472111)
			(xy 91.600652 -196.422363) (xy 91.630383 -196.376395) (xy 91.648026 -196.355462) (xy 91.654122 -196.34835)
			(xy 91.660472 -196.331332) (xy 91.660472 -196.245988) (xy 91.654122 -196.22897) (xy 91.648026 -196.221858)
			(xy 91.630346 -196.200957) (xy 91.600623 -196.154984) (xy 91.57778 -196.105232) (xy 91.562287 -196.052725)
			(xy 91.554462 -195.998542) (xy 91.554466 -195.943797) (xy 91.5623 -195.889616) (xy 91.577801 -195.837111)
			(xy 91.600652 -195.787363) (xy 91.630383 -195.741395) (xy 91.648026 -195.720462) (xy 91.654122 -195.71335)
			(xy 91.660472 -195.696332) (xy 91.660472 -195.610988) (xy 91.654122 -195.59397) (xy 91.648026 -195.586858)
			(xy 91.630405 -195.565912) (xy 91.600689 -195.519943) (xy 91.57785 -195.470199) (xy 91.562354 -195.417702)
			(xy 91.554522 -195.363528) (xy 91.554046 -195.33616) (xy 91.554495 -195.30886) (xy 91.562274 -195.254817)
			(xy 91.577679 -195.202435) (xy 91.600398 -195.152786) (xy 91.629965 -195.106884) (xy 91.647518 -195.08597)
			(xy 91.653868 -195.078858) (xy 91.659964 -195.06184) (xy 91.659964 -194.976242) (xy 91.653614 -194.959478)
			(xy 91.647518 -194.952366) (xy 91.629791 -194.931415) (xy 91.599914 -194.885381) (xy 91.576949 -194.835536)
			(xy 91.561372 -194.782913) (xy 91.553506 -194.7286) (xy 91.55303 -194.70116) (xy 89.572846 -194.70116)
			(xy 89.572386 -194.728459) (xy 89.564607 -194.782501) (xy 89.549202 -194.834882) (xy 89.526487 -194.884531)
			(xy 89.496924 -194.930434) (xy 89.479374 -194.95135) (xy 89.473024 -194.958462) (xy 89.466928 -194.97548)
			(xy 89.466928 -195.061078) (xy 89.473278 -195.077842) (xy 89.479374 -195.084954) (xy 89.497109 -195.105898)
			(xy 89.526985 -195.151934) (xy 89.549948 -195.20178) (xy 89.565523 -195.254405) (xy 89.573388 -195.308719)
			(xy 89.573862 -195.33616) (xy 89.573382 -195.36353) (xy 89.565569 -195.417709) (xy 89.550084 -195.470212)
			(xy 89.527245 -195.519959) (xy 89.497522 -195.565926) (xy 89.479882 -195.586858) (xy 89.473786 -195.59397)
			(xy 89.467436 -195.610988) (xy 89.467436 -195.696332) (xy 89.473786 -195.71335) (xy 89.479882 -195.720462)
			(xy 89.497483 -195.741427) (xy 89.527209 -195.787389) (xy 89.550056 -195.83713) (xy 89.565555 -195.889627)
			(xy 89.573387 -195.943801) (xy 89.573391 -195.998539) (xy 89.565568 -196.052714) (xy 89.550077 -196.105213)
			(xy 89.527238 -196.154958) (xy 89.497519 -196.200925) (xy 89.479882 -196.221858) (xy 89.473786 -196.22897)
			(xy 89.467436 -196.245988) (xy 89.467436 -196.331332) (xy 89.473786 -196.34835) (xy 89.479882 -196.355462)
			(xy 89.497483 -196.376427) (xy 89.527209 -196.422389) (xy 89.550056 -196.47213) (xy 89.565555 -196.524627)
			(xy 89.573387 -196.578801) (xy 89.573391 -196.633539) (xy 89.565568 -196.687714) (xy 89.550077 -196.740213)
			(xy 89.527238 -196.789958) (xy 89.497519 -196.835925) (xy 89.479882 -196.856858) (xy 89.473786 -196.86397)
			(xy 89.467436 -196.880988) (xy 89.467436 -196.966332) (xy 89.473786 -196.98335) (xy 89.479882 -196.990462)
			(xy 89.497514 -197.0114) (xy 89.527227 -197.057371) (xy 89.550065 -197.107117) (xy 89.565558 -197.159616)
			(xy 89.573387 -197.213791) (xy 89.573862 -197.24116) (xy 89.57334 -197.270315) (xy 89.564465 -197.327945)
			(xy 89.546929 -197.383555) (xy 89.521142 -197.435853) (xy 89.487703 -197.483621) (xy 89.467944 -197.505066)
			(xy 89.46134 -197.51167) (xy 89.454228 -197.528942) (xy 89.450672 -197.614794) (xy 89.456768 -197.63232)
			(xy 89.46261 -197.639432) (xy 89.478809 -197.659942) (xy 89.506008 -197.70457) (xy 89.526855 -197.752495)
			(xy 89.540959 -197.80282) (xy 89.548055 -197.8546) (xy 89.548462 -197.880732) (xy 89.548024 -197.908103)
			(xy 89.540201 -197.962284) (xy 89.524706 -198.014788) (xy 89.501857 -198.064534) (xy 89.472126 -198.1105)
			(xy 89.454482 -198.13143) (xy 89.448386 -198.138542) (xy 89.442036 -198.15556) (xy 89.442036 -198.240904)
			(xy 89.448386 -198.257922) (xy 89.454482 -198.265034) (xy 89.472154 -198.285942) (xy 89.501876 -198.331914)
			(xy 89.524719 -198.381664) (xy 89.540213 -198.43417) (xy 89.548038 -198.488352) (xy 89.548035 -198.543096)
			(xy 89.540203 -198.597277) (xy 89.524702 -198.649781) (xy 89.501853 -198.699528) (xy 89.472125 -198.745497)
			(xy 89.454482 -198.76643) (xy 89.448386 -198.773542) (xy 89.442036 -198.79056) (xy 89.442036 -198.875904)
			(xy 89.448386 -198.892922) (xy 89.454482 -198.900034) (xy 89.472154 -198.920942) (xy 89.501876 -198.966914)
			(xy 89.524719 -199.016664) (xy 89.540213 -199.06917) (xy 89.548038 -199.123352) (xy 89.548035 -199.178096)
			(xy 89.540203 -199.232277) (xy 89.524702 -199.284781) (xy 89.501853 -199.334528) (xy 89.472125 -199.380497)
			(xy 89.454482 -199.40143) (xy 89.448386 -199.408542) (xy 89.442036 -199.42556) (xy 89.442036 -199.510904)
			(xy 89.448386 -199.527922) (xy 89.454482 -199.535034) (xy 89.472154 -199.555942) (xy 89.501876 -199.601914)
			(xy 89.524719 -199.651664) (xy 89.540213 -199.70417) (xy 89.548038 -199.758352) (xy 89.548035 -199.813096)
			(xy 89.540203 -199.867277) (xy 89.524702 -199.919781) (xy 89.501853 -199.969528) (xy 89.472125 -200.015497)
			(xy 89.454482 -200.03643) (xy 89.448386 -200.043542) (xy 89.442036 -200.06056) (xy 89.442036 -200.145904)
			(xy 89.448386 -200.162922) (xy 89.454482 -200.170034) (xy 89.472154 -200.190942) (xy 89.501876 -200.236914)
			(xy 89.524719 -200.286664) (xy 89.540213 -200.33917) (xy 89.548038 -200.393352) (xy 89.548035 -200.448096)
			(xy 89.540203 -200.502277) (xy 89.524702 -200.554781) (xy 89.501853 -200.604528) (xy 89.472125 -200.650497)
			(xy 89.454482 -200.67143) (xy 89.448386 -200.678542) (xy 89.442036 -200.69556) (xy 89.442036 -200.780904)
			(xy 89.448386 -200.797922) (xy 89.454482 -200.805034) (xy 89.472101 -200.825982) (xy 89.501816 -200.87195)
			(xy 89.524656 -200.921694) (xy 89.540152 -200.974191) (xy 89.547985 -201.028364) (xy 89.548462 -201.055732)
			(xy 89.548075 -201.082988) (xy 89.540312 -201.136944) (xy 89.52495 -201.189246) (xy 89.5023 -201.238829)
			(xy 89.472825 -201.284685) (xy 89.437123 -201.325878) (xy 89.395922 -201.361571) (xy 89.350061 -201.391038)
			(xy 89.300473 -201.413677) (xy 89.248168 -201.429029) (xy 89.19421 -201.43678) (xy 89.166954 -201.43724)
			(xy 89.139584 -201.436757) (xy 89.085405 -201.428945) (xy 89.032902 -201.413461) (xy 88.983155 -201.390623)
			(xy 88.937188 -201.360901) (xy 88.916256 -201.34326) (xy 88.909144 -201.337164) (xy 88.892126 -201.330814)
			(xy 88.806782 -201.330814) (xy 88.789764 -201.337164) (xy 88.782652 -201.34326) (xy 88.761719 -201.360901)
			(xy 88.715751 -201.390625) (xy 88.666005 -201.413471) (xy 88.613503 -201.428967) (xy 88.559325 -201.436796)
			(xy 88.504583 -201.436796) (xy 88.450405 -201.428967) (xy 88.397903 -201.413471) (xy 88.348157 -201.390625)
			(xy 88.302189 -201.360901) (xy 88.281256 -201.34326) (xy 88.274144 -201.337164) (xy 88.257126 -201.330814)
			(xy 88.171782 -201.330814) (xy 88.154764 -201.337164) (xy 88.147652 -201.34326) (xy 88.126706 -201.360882)
			(xy 88.080738 -201.390598) (xy 88.030994 -201.413438) (xy 87.978496 -201.428933) (xy 87.924322 -201.436764)
			(xy 87.896954 -201.43724) (xy 87.869703 -201.436765) (xy 87.815757 -201.429003) (xy 87.763464 -201.413644)
			(xy 87.713888 -201.391) (xy 87.66804 -201.361532) (xy 87.626851 -201.325839) (xy 87.59116 -201.284649)
			(xy 87.561694 -201.238799) (xy 87.539051 -201.189223) (xy 87.523694 -201.13693) (xy 87.515934 -201.082983)
			(xy 87.515446 -201.055732) (xy 85.188355 -201.055732) (xy 85.188806 -201.08164) (xy 85.188359 -201.108892)
			(xy 85.180597 -201.162842) (xy 85.165237 -201.215137) (xy 85.142591 -201.264715) (xy 85.11312 -201.310565)
			(xy 85.077425 -201.351755) (xy 85.036231 -201.387446) (xy 84.990378 -201.416911) (xy 84.940798 -201.439552)
			(xy 84.8885 -201.454906) (xy 84.83455 -201.462662) (xy 84.807298 -201.463148) (xy 84.779927 -201.462696)
			(xy 84.725747 -201.454877) (xy 84.673243 -201.439385) (xy 84.623496 -201.41654) (xy 84.577531 -201.386811)
			(xy 84.5566 -201.369168) (xy 84.549488 -201.363072) (xy 84.53247 -201.356722) (xy 84.447126 -201.356722)
			(xy 84.430108 -201.363072) (xy 84.422996 -201.369168) (xy 84.402063 -201.386809) (xy 84.356095 -201.416533)
			(xy 84.306349 -201.439379) (xy 84.253847 -201.454875) (xy 84.199669 -201.462704) (xy 84.144927 -201.462704)
			(xy 84.090749 -201.454875) (xy 84.038247 -201.439379) (xy 83.988501 -201.416533) (xy 83.942533 -201.386809)
			(xy 83.9216 -201.369168) (xy 83.914488 -201.363072) (xy 83.89747 -201.356722) (xy 83.812126 -201.356722)
			(xy 83.795108 -201.363072) (xy 83.787996 -201.369168) (xy 83.767072 -201.386817) (xy 83.721098 -201.416529)
			(xy 83.671348 -201.439363) (xy 83.618845 -201.454852) (xy 83.564668 -201.462676) (xy 83.537298 -201.463148)
			(xy 83.510049 -201.462624) (xy 83.456104 -201.454868) (xy 83.403813 -201.439515) (xy 83.354238 -201.416877)
			(xy 83.30839 -201.387414) (xy 83.2672 -201.351726) (xy 83.231509 -201.310541) (xy 83.202042 -201.264695)
			(xy 83.179398 -201.215123) (xy 83.16404 -201.162833) (xy 83.156279 -201.108889) (xy 83.15579 -201.08164)
			(xy 81.175606 -201.08164) (xy 81.175159 -201.108892) (xy 81.167397 -201.162842) (xy 81.152037 -201.215137)
			(xy 81.129391 -201.264715) (xy 81.09992 -201.310565) (xy 81.064225 -201.351755) (xy 81.023031 -201.387446)
			(xy 80.977178 -201.416911) (xy 80.927598 -201.439552) (xy 80.8753 -201.454906) (xy 80.82135 -201.462662)
			(xy 80.794098 -201.463148) (xy 80.766727 -201.462696) (xy 80.712547 -201.454877) (xy 80.660043 -201.439385)
			(xy 80.610296 -201.41654) (xy 80.564331 -201.386811) (xy 80.5434 -201.369168) (xy 80.536288 -201.363072)
			(xy 80.51927 -201.356722) (xy 80.433926 -201.356722) (xy 80.416908 -201.363072) (xy 80.409796 -201.369168)
			(xy 80.388863 -201.386809) (xy 80.342895 -201.416533) (xy 80.293149 -201.439379) (xy 80.240647 -201.454875)
			(xy 80.186469 -201.462704) (xy 80.131727 -201.462704) (xy 80.077549 -201.454875) (xy 80.025047 -201.439379)
			(xy 79.975301 -201.416533) (xy 79.929333 -201.386809) (xy 79.9084 -201.369168) (xy 79.901288 -201.363072)
			(xy 79.88427 -201.356722) (xy 79.798926 -201.356722) (xy 79.781908 -201.363072) (xy 79.774796 -201.369168)
			(xy 79.753872 -201.386817) (xy 79.707898 -201.416529) (xy 79.658148 -201.439363) (xy 79.605645 -201.454852)
			(xy 79.551468 -201.462676) (xy 79.524098 -201.463148) (xy 79.496849 -201.462624) (xy 79.442904 -201.454868)
			(xy 79.390613 -201.439515) (xy 79.341038 -201.416877) (xy 79.29519 -201.387414) (xy 79.254 -201.351726)
			(xy 79.218309 -201.310541) (xy 79.188842 -201.264695) (xy 79.166198 -201.215123) (xy 79.15084 -201.162833)
			(xy 79.143079 -201.108889) (xy 79.14259 -201.08164) (xy 74.628502 -201.08164) (xy 75.611228 -202.064366)
			(xy 75.611736 -202.064874) (xy 75.619117 -202.071457) (xy 75.637416 -202.07891) (xy 75.647296 -202.079352)
		)
		(stroke
			(width 0)
			(type solid)
		)
		(fill yes)
		(layer "In2.Cu")
		(net "GND")
	)
	(gr_poly
		(pts
			(xy 381.345948 -201.62774) (xy 381.356013 -201.627307) (xy 381.374599 -201.619573) (xy 381.382016 -201.612754)
			(xy 381.873252 -201.121518) (xy 381.896035 -201.099375) (xy 381.945716 -201.05977) (xy 381.999514 -201.025969)
			(xy 382.056754 -200.998397) (xy 382.116719 -200.977399) (xy 382.178656 -200.96324) (xy 382.241789 -200.956096)
			(xy 382.273556 -200.955656) (xy 391.81786 -200.955656) (xy 391.827004 -200.954894) (xy 391.834582 -200.953237)
			(xy 391.848294 -200.946001) (xy 391.853928 -200.94067) (xy 396.715996 -196.078602) (xy 396.721835 -196.072357)
			(xy 396.729308 -196.056994) (xy 396.731258 -196.040021) (xy 396.729712 -196.031612) (xy 396.72768 -196.0245)
			(xy 396.694914 -195.938394) (xy 396.692095 -195.93158) (xy 396.683184 -195.91984) (xy 396.677388 -195.91528)
			(xy 396.665196 -195.90639) (xy 396.658846 -195.905882) (xy 396.633012 -195.90444) (xy 396.582061 -195.895441)
			(xy 396.532796 -195.879628) (xy 396.486126 -195.857291) (xy 396.442909 -195.828842) (xy 396.423134 -195.812156)
			(xy 396.416022 -195.80606) (xy 396.40764 -195.803012) (xy 396.403352 -195.801488) (xy 396.394409 -195.79982)
			(xy 396.38986 -195.79971) (xy 396.322804 -195.79971) (xy 396.318257 -195.799836) (xy 396.309315 -195.801501)
			(xy 396.305024 -195.803012) (xy 396.296642 -195.80606) (xy 396.28953 -195.812156) (xy 396.268597 -195.829797)
			(xy 396.222629 -195.859521) (xy 396.172883 -195.882367) (xy 396.120381 -195.897863) (xy 396.066203 -195.905692)
			(xy 396.011461 -195.905692) (xy 395.957283 -195.897863) (xy 395.904781 -195.882367) (xy 395.855035 -195.859521)
			(xy 395.809067 -195.829797) (xy 395.788134 -195.812156) (xy 395.781022 -195.80606) (xy 395.77264 -195.803012)
			(xy 395.768352 -195.801488) (xy 395.759409 -195.79982) (xy 395.75486 -195.79971) (xy 395.687804 -195.79971)
			(xy 395.683257 -195.799836) (xy 395.674315 -195.801501) (xy 395.670024 -195.803012) (xy 395.661642 -195.80606)
			(xy 395.65453 -195.812156) (xy 395.6336 -195.829802) (xy 395.587635 -195.859535) (xy 395.537889 -195.882384)
			(xy 395.485385 -195.897881) (xy 395.431204 -195.905704) (xy 395.403832 -195.906136) (xy 395.376577 -195.905675)
			(xy 395.322621 -195.897922) (xy 395.270318 -195.882569) (xy 395.220732 -195.859929) (xy 395.174872 -195.830462)
			(xy 395.133674 -195.794769) (xy 395.097974 -195.753576) (xy 395.0685 -195.707721) (xy 395.045852 -195.658139)
			(xy 395.030491 -195.605838) (xy 395.022729 -195.551883) (xy 395.022324 -195.524628) (xy 395.022801 -195.49726)
			(xy 395.030634 -195.443087) (xy 395.04613 -195.39059) (xy 395.06897 -195.340846) (xy 395.098685 -195.294878)
			(xy 395.116304 -195.27393) (xy 395.1224 -195.266818) (xy 395.125448 -195.258436) (xy 395.126972 -195.254149)
			(xy 395.128641 -195.245205) (xy 395.12875 -195.240656) (xy 395.12875 -195.1736) (xy 395.128623 -195.169053)
			(xy 395.126957 -195.160112) (xy 395.125448 -195.15582) (xy 395.1224 -195.147438) (xy 395.116304 -195.140326)
			(xy 395.098662 -195.119393) (xy 395.068935 -195.073424) (xy 395.046087 -195.023676) (xy 395.030589 -194.971173)
			(xy 395.022757 -194.916993) (xy 395.022754 -194.862249) (xy 395.030579 -194.808068) (xy 395.046073 -194.755563)
			(xy 395.068915 -194.705813) (xy 395.098637 -194.659841) (xy 395.116304 -194.63893) (xy 395.1224 -194.631818)
			(xy 395.125448 -194.623436) (xy 395.126972 -194.619149) (xy 395.128641 -194.610205) (xy 395.12875 -194.605656)
			(xy 395.12875 -194.5386) (xy 395.128623 -194.534053) (xy 395.126957 -194.525112) (xy 395.125448 -194.52082)
			(xy 395.1224 -194.512438) (xy 395.116304 -194.505326) (xy 395.098662 -194.484393) (xy 395.068935 -194.438424)
			(xy 395.046087 -194.388676) (xy 395.030589 -194.336173) (xy 395.022757 -194.281993) (xy 395.022754 -194.227249)
			(xy 395.030579 -194.173068) (xy 395.046073 -194.120563) (xy 395.068915 -194.070813) (xy 395.098637 -194.024841)
			(xy 395.116304 -194.00393) (xy 395.1224 -193.996818) (xy 395.125448 -193.988436) (xy 395.126972 -193.984149)
			(xy 395.128641 -193.975205) (xy 395.12875 -193.970656) (xy 395.12875 -193.9036) (xy 395.128623 -193.899053)
			(xy 395.126957 -193.890112) (xy 395.125448 -193.88582) (xy 395.1224 -193.877438) (xy 395.116304 -193.870326)
			(xy 395.098662 -193.849393) (xy 395.068935 -193.803424) (xy 395.046087 -193.753676) (xy 395.030589 -193.701173)
			(xy 395.022757 -193.646993) (xy 395.022754 -193.592249) (xy 395.030579 -193.538068) (xy 395.046073 -193.485563)
			(xy 395.068915 -193.435813) (xy 395.098637 -193.389841) (xy 395.116304 -193.36893) (xy 395.1224 -193.361818)
			(xy 395.125448 -193.353436) (xy 395.126972 -193.349149) (xy 395.128641 -193.340205) (xy 395.12875 -193.335656)
			(xy 395.12875 -193.2686) (xy 395.128623 -193.264053) (xy 395.126957 -193.255112) (xy 395.125448 -193.25082)
			(xy 395.1224 -193.242438) (xy 395.116304 -193.235326) (xy 395.098662 -193.214393) (xy 395.068935 -193.168424)
			(xy 395.046087 -193.118676) (xy 395.030589 -193.066173) (xy 395.022757 -193.011993) (xy 395.022754 -192.957249)
			(xy 395.030579 -192.903068) (xy 395.046073 -192.850563) (xy 395.068915 -192.800813) (xy 395.098637 -192.754841)
			(xy 395.116304 -192.73393) (xy 395.1224 -192.726818) (xy 395.125448 -192.718436) (xy 395.126972 -192.714149)
			(xy 395.128641 -192.705205) (xy 395.12875 -192.700656) (xy 395.12875 -192.6336) (xy 395.128623 -192.629053)
			(xy 395.126957 -192.620112) (xy 395.125448 -192.61582) (xy 395.1224 -192.607438) (xy 395.116304 -192.600326)
			(xy 395.098662 -192.579393) (xy 395.068935 -192.533424) (xy 395.046087 -192.483676) (xy 395.030589 -192.431173)
			(xy 395.022757 -192.376993) (xy 395.022754 -192.322249) (xy 395.030579 -192.268068) (xy 395.046073 -192.215563)
			(xy 395.068915 -192.165813) (xy 395.098637 -192.119841) (xy 395.116304 -192.09893) (xy 395.1224 -192.091818)
			(xy 395.125448 -192.083436) (xy 395.126972 -192.079149) (xy 395.128641 -192.070205) (xy 395.12875 -192.065656)
			(xy 395.12875 -191.9986) (xy 395.128623 -191.994053) (xy 395.126957 -191.985112) (xy 395.125448 -191.98082)
			(xy 395.1224 -191.972438) (xy 395.116304 -191.965326) (xy 395.098662 -191.944393) (xy 395.068935 -191.898424)
			(xy 395.046087 -191.848676) (xy 395.030589 -191.796173) (xy 395.022757 -191.741993) (xy 395.022754 -191.687249)
			(xy 395.030579 -191.633068) (xy 395.046073 -191.580563) (xy 395.068915 -191.530813) (xy 395.098637 -191.484841)
			(xy 395.116304 -191.46393) (xy 395.1224 -191.456818) (xy 395.125448 -191.448436) (xy 395.126972 -191.444149)
			(xy 395.128641 -191.435205) (xy 395.12875 -191.430656) (xy 395.12875 -191.3636) (xy 395.128623 -191.359053)
			(xy 395.126957 -191.350112) (xy 395.125448 -191.34582) (xy 395.1224 -191.337438) (xy 395.116304 -191.330326)
			(xy 395.098662 -191.309393) (xy 395.068935 -191.263424) (xy 395.046087 -191.213676) (xy 395.030589 -191.161173)
			(xy 395.022757 -191.106993) (xy 395.022754 -191.052249) (xy 395.030579 -190.998068) (xy 395.046073 -190.945563)
			(xy 395.068915 -190.895813) (xy 395.098637 -190.849841) (xy 395.116304 -190.82893) (xy 395.1224 -190.821818)
			(xy 395.125448 -190.813436) (xy 395.126972 -190.809149) (xy 395.128641 -190.800205) (xy 395.12875 -190.795656)
			(xy 395.12875 -190.7286) (xy 395.128623 -190.724053) (xy 395.126957 -190.715112) (xy 395.125448 -190.71082)
			(xy 395.1224 -190.702438) (xy 395.116304 -190.695326) (xy 395.098662 -190.674393) (xy 395.068935 -190.628424)
			(xy 395.046087 -190.578676) (xy 395.030589 -190.526173) (xy 395.022757 -190.471993) (xy 395.022754 -190.417249)
			(xy 395.030579 -190.363068) (xy 395.046073 -190.310563) (xy 395.068915 -190.260813) (xy 395.098637 -190.214841)
			(xy 395.116304 -190.19393) (xy 395.1224 -190.186818) (xy 395.125448 -190.178436) (xy 395.126972 -190.174149)
			(xy 395.128641 -190.165205) (xy 395.12875 -190.160656) (xy 395.12875 -190.0936) (xy 395.128623 -190.089053)
			(xy 395.126957 -190.080112) (xy 395.125448 -190.07582) (xy 395.1224 -190.067438) (xy 395.116304 -190.060326)
			(xy 395.09866 -190.039395) (xy 395.068931 -189.993429) (xy 395.046084 -189.943683) (xy 395.03059 -189.891179)
			(xy 395.022768 -189.836999) (xy 395.022324 -189.809628) (xy 395.022848 -189.78127) (xy 395.031256 -189.725181)
			(xy 395.047876 -189.670955) (xy 395.072341 -189.619786) (xy 395.104112 -189.572805) (xy 395.122908 -189.551564)
			(xy 395.129512 -189.544198) (xy 395.13256 -189.536324) (xy 395.134336 -189.531697) (xy 395.13626 -189.521975)
			(xy 395.13637 -189.51702) (xy 395.135862 -189.482476) (xy 395.135862 -189.481968) (xy 395.135608 -189.447424)
			(xy 395.135481 -189.442612) (xy 395.133683 -189.433157) (xy 395.132052 -189.428628) (xy 395.128496 -189.420246)
			(xy 395.121638 -189.413134) (xy 395.10216 -189.391758) (xy 395.069221 -189.344227) (xy 395.043826 -189.292272)
			(xy 395.026556 -189.237083) (xy 395.017805 -189.17992) (xy 395.017244 -189.151006) (xy 395.017244 -189.144656)
			(xy 395.018138 -189.117688) (xy 395.026586 -189.064395) (xy 395.042459 -189.012825) (xy 395.065439 -188.964006)
			(xy 395.09507 -188.918911) (xy 395.130758 -188.878442) (xy 395.171793 -188.843405) (xy 395.217355 -188.814499)
			(xy 395.266535 -188.792301) (xy 395.318352 -188.777254) (xy 395.371773 -188.769659) (xy 395.398752 -188.769244)
			(xy 395.42612 -188.769719) (xy 395.480294 -188.777551) (xy 395.532793 -188.793045) (xy 395.582537 -188.815884)
			(xy 395.628507 -188.845599) (xy 395.64945 -188.863224) (xy 395.656562 -188.86932) (xy 395.664944 -188.872368)
			(xy 395.669233 -188.873885) (xy 395.678177 -188.875539) (xy 395.682724 -188.87567) (xy 395.74978 -188.87567)
			(xy 395.754327 -188.875545) (xy 395.76327 -188.873882) (xy 395.76756 -188.872368) (xy 395.775942 -188.86932)
			(xy 395.783054 -188.863224) (xy 395.803987 -188.845583) (xy 395.849955 -188.815859) (xy 395.899701 -188.793013)
			(xy 395.952203 -188.777517) (xy 396.006381 -188.769688) (xy 396.061123 -188.769688) (xy 396.115301 -188.777517)
			(xy 396.167803 -188.793013) (xy 396.217549 -188.815859) (xy 396.263517 -188.845583) (xy 396.28445 -188.863224)
			(xy 396.291562 -188.86932) (xy 396.299944 -188.872368) (xy 396.304233 -188.873885) (xy 396.313177 -188.875539)
			(xy 396.317724 -188.87567) (xy 396.38478 -188.87567) (xy 396.389327 -188.875545) (xy 396.39827 -188.873882)
			(xy 396.40256 -188.872368) (xy 396.410942 -188.86932) (xy 396.418054 -188.863224) (xy 396.438986 -188.845584)
			(xy 396.484953 -188.815863) (xy 396.5347 -188.793025) (xy 396.587204 -188.777541) (xy 396.641382 -188.76973)
			(xy 396.668752 -188.769244) (xy 396.696007 -188.769726) (xy 396.749962 -188.777477) (xy 396.802265 -188.792828)
			(xy 396.851852 -188.815465) (xy 396.897712 -188.84493) (xy 396.938912 -188.88062) (xy 396.974613 -188.921811)
			(xy 397.004089 -188.967664) (xy 397.026739 -189.017244) (xy 397.042102 -189.069544) (xy 397.049867 -189.123497)
			(xy 397.05026 -189.150752) (xy 399.032984 -189.150752) (xy 399.033433 -189.1235) (xy 399.041196 -189.069551)
			(xy 399.056557 -189.017256) (xy 399.079203 -188.96768) (xy 399.108673 -188.92183) (xy 399.144369 -188.88064)
			(xy 399.185562 -188.844949) (xy 399.231415 -188.815484) (xy 399.280994 -188.792843) (xy 399.33329 -188.777487)
			(xy 399.38724 -188.76973) (xy 399.414492 -188.769244) (xy 399.443913 -188.769771) (xy 399.502054 -188.778823)
			(xy 399.558109 -188.796715) (xy 399.584672 -188.809376) (xy 399.584926 -188.809376) (xy 399.59275 -188.812884)
			(xy 399.609754 -188.81499) (xy 399.626489 -188.811318) (xy 399.633948 -188.80709) (xy 399.707354 -188.761624)
			(xy 399.714531 -188.756805) (xy 399.725394 -188.743372) (xy 399.731146 -188.727082) (xy 399.731484 -188.718444)
			(xy 399.731484 -180.994304) (xy 399.731945 -180.969315) (xy 399.739771 -180.919955) (xy 399.755231 -180.872429)
			(xy 399.777943 -180.827911) (xy 399.807347 -180.787498) (xy 399.824702 -180.769514) (xy 400.061938 -180.532532)
			(xy 400.068762 -180.525119) (xy 400.07649 -180.50653) (xy 400.076924 -180.496464) (xy 400.076924 -175.544734)
			(xy 400.077404 -175.519784) (xy 400.085224 -175.470501) (xy 400.100646 -175.423045) (xy 400.123291 -175.378579)
			(xy 400.152603 -175.338197) (xy 400.169888 -175.320198) (xy 400.651472 -174.838614) (xy 400.658411 -174.830996)
			(xy 400.66608 -174.811888) (xy 400.665671 -174.791303) (xy 400.661886 -174.781718) (xy 400.616166 -174.680626)
			(xy 400.588988 -174.66437) (xy 400.57324 -174.665386) (xy 400.548856 -174.666148) (xy 400.521608 -174.665575)
			(xy 400.467668 -174.657813) (xy 400.415381 -174.642454) (xy 400.365812 -174.619809) (xy 400.31997 -174.590341)
			(xy 400.278789 -174.554649) (xy 400.243107 -174.51346) (xy 400.213649 -174.467612) (xy 400.191016 -174.418038)
			(xy 400.175669 -174.365748) (xy 400.167919 -174.311805) (xy 400.167925 -174.257309) (xy 400.175687 -174.203369)
			(xy 400.191046 -174.151082) (xy 400.21369 -174.101513) (xy 400.243158 -174.055672) (xy 400.27885 -174.01449)
			(xy 400.320039 -173.978807) (xy 400.365887 -173.94935) (xy 400.415461 -173.926717) (xy 400.467751 -173.911369)
			(xy 400.521693 -173.903619) (xy 400.576189 -173.903625) (xy 400.63013 -173.911387) (xy 400.682417 -173.926745)
			(xy 400.731986 -173.949389) (xy 400.777827 -173.978857) (xy 400.819009 -174.014549) (xy 400.854692 -174.055738)
			(xy 400.88415 -174.101586) (xy 400.906783 -174.15116) (xy 400.922131 -174.20345) (xy 400.929881 -174.257392)
			(xy 400.930364 -174.28464) (xy 400.930364 -174.284894) (xy 400.929756 -174.315984) (xy 400.919665 -174.377338)
			(xy 400.899735 -174.436236) (xy 400.88566 -174.463964) (xy 400.877786 -174.47895) (xy 400.882612 -174.51197)
			(xy 400.89455 -174.523908) (xy 400.901962 -174.530592) (xy 400.920395 -174.538189) (xy 400.940333 -174.538189)
			(xy 400.958766 -174.530592) (xy 400.966178 -174.523908) (xy 401.086574 -174.403766) (xy 401.093418 -174.396369)
			(xy 401.101136 -174.377767) (xy 401.10156 -174.367698) (xy 401.10156 -173.833282) (xy 401.101154 -173.82321)
			(xy 401.093421 -173.804612) (xy 401.086574 -173.797214) (xy 401.062698 -173.773592) (xy 401.057723 -173.768946)
			(xy 401.045874 -173.762256) (xy 401.03933 -173.760384) (xy 401.039076 -173.76013) (xy 401.038568 -173.76013)
			(xy 401.011185 -173.752998) (xy 400.958738 -173.731766) (xy 400.910002 -173.703019) (xy 400.866048 -173.667387)
			(xy 400.82784 -173.625653) (xy 400.796217 -173.578733) (xy 400.771871 -173.527656) (xy 400.755339 -173.473543)
			(xy 400.746981 -173.417581) (xy 400.746468 -173.38929) (xy 400.746968 -173.36204) (xy 400.754726 -173.308094)
			(xy 400.770081 -173.255801) (xy 400.792721 -173.206225) (xy 400.822186 -173.160376) (xy 400.857876 -173.119186)
			(xy 400.899065 -173.083495) (xy 400.944913 -173.054028) (xy 400.994487 -173.031386) (xy 401.04678 -173.016029)
			(xy 401.100726 -173.008269) (xy 401.127976 -173.007782) (xy 401.156282 -173.008303) (xy 401.212277 -173.016645)
			(xy 401.266421 -173.033178) (xy 401.317523 -173.05754) (xy 401.364459 -173.089193) (xy 401.406197 -173.127441)
			(xy 401.441817 -173.171443) (xy 401.470535 -173.22023) (xy 401.491721 -173.272729) (xy 401.498816 -173.300136)
			(xy 401.498816 -173.300644) (xy 401.500742 -173.307205) (xy 401.50758 -173.319043) (xy 401.512278 -173.324012)
			(xy 401.644104 -173.455838) (xy 401.661418 -173.473812) (xy 401.690738 -173.514194) (xy 401.713382 -173.558665)
			(xy 401.72879 -173.60613) (xy 401.736585 -173.655422) (xy 401.737068 -173.680374) (xy 401.737068 -174.520606)
			(xy 401.736552 -174.545554) (xy 401.728741 -174.594836) (xy 401.713328 -174.642292) (xy 401.690691 -174.686758)
			(xy 401.661386 -174.727142) (xy 401.644104 -174.745142) (xy 401.427696 -174.96155) (xy 401.420958 -174.969016)
			(xy 401.413411 -174.987639) (xy 401.413564 -175.007732) (xy 401.417028 -175.017176) (xy 401.453604 -175.10379)
			(xy 401.457934 -175.112948) (xy 401.472406 -175.1271) (xy 401.491228 -175.134546) (xy 401.501356 -175.134778)
			(xy 401.507198 -175.134778) (xy 401.534449 -175.13528) (xy 401.588395 -175.143035) (xy 401.640689 -175.15839)
			(xy 401.690265 -175.18103) (xy 401.736115 -175.210494) (xy 401.777305 -175.246184) (xy 401.812996 -175.287373)
			(xy 401.842463 -175.333221) (xy 401.865105 -175.382796) (xy 401.880461 -175.435089) (xy 401.888219 -175.489035)
			(xy 401.888706 -175.516286) (xy 401.888206 -175.544197) (xy 401.880074 -175.599422) (xy 401.86398 -175.652873)
			(xy 401.840269 -175.703408) (xy 401.809446 -175.749948) (xy 401.79117 -175.771048) (xy 401.785249 -175.778208)
			(xy 401.778613 -175.795546) (xy 401.778216 -175.80483) (xy 401.778216 -175.882554) (xy 401.78482 -175.899826)
			(xy 401.79117 -175.906938) (xy 401.809451 -175.928035) (xy 401.840276 -175.974575) (xy 401.863989 -176.02511)
			(xy 401.880085 -176.078562) (xy 401.88822 -176.133789) (xy 401.888706 -176.1617) (xy 401.88822 -176.188951)
			(xy 401.880464 -176.242899) (xy 401.865109 -176.295194) (xy 401.842467 -176.344771) (xy 401.813001 -176.390621)
			(xy 401.77731 -176.431812) (xy 401.736119 -176.467503) (xy 401.690269 -176.496969) (xy 401.640692 -176.519611)
			(xy 401.588397 -176.534966) (xy 401.534449 -176.542722) (xy 401.479947 -176.542722) (xy 401.425999 -176.534966)
			(xy 401.373704 -176.519611) (xy 401.324127 -176.496969) (xy 401.278277 -176.467503) (xy 401.237086 -176.431812)
			(xy 401.201395 -176.390621) (xy 401.171929 -176.344771) (xy 401.149287 -176.295194) (xy 401.133932 -176.242899)
			(xy 401.126176 -176.188951) (xy 401.12569 -176.1617) (xy 401.126182 -176.133789) (xy 401.134317 -176.078563)
			(xy 401.150413 -176.025113) (xy 401.174125 -175.974578) (xy 401.204949 -175.928038) (xy 401.223226 -175.906938)
			(xy 401.229153 -175.899782) (xy 401.235785 -175.882441) (xy 401.23618 -175.873156) (xy 401.23618 -175.795432)
			(xy 401.229576 -175.77816) (xy 401.223226 -175.771048) (xy 401.204938 -175.749957) (xy 401.174114 -175.703415)
			(xy 401.150402 -175.652878) (xy 401.134308 -175.599425) (xy 401.126175 -175.544198) (xy 401.12569 -175.516286)
			(xy 401.12569 -175.510444) (xy 401.125406 -175.500326) (xy 401.117958 -175.481525) (xy 401.103837 -175.467049)
			(xy 401.094702 -175.462692) (xy 401.008088 -175.426116) (xy 400.998668 -175.422548) (xy 400.978539 -175.422386)
			(xy 400.959901 -175.429991) (xy 400.952462 -175.436784) (xy 400.727418 -175.661574) (xy 400.720599 -175.668991)
			(xy 400.712866 -175.687577) (xy 400.712432 -175.697642) (xy 400.712432 -180.649372) (xy 400.711905 -180.67432)
			(xy 400.704099 -180.723601) (xy 400.688689 -180.771058) (xy 400.666054 -180.815524) (xy 400.63675 -180.855909)
			(xy 400.619468 -180.873908) (xy 400.382486 -181.11089) (xy 400.375656 -181.118298) (xy 400.367931 -181.136891)
			(xy 400.3675 -181.146958) (xy 400.3675 -186.947048) (xy 404.034244 -186.947048) (xy 404.034727 -186.919678)
			(xy 404.042539 -186.8655) (xy 404.058024 -186.812996) (xy 404.080862 -186.763249) (xy 404.110584 -186.717282)
			(xy 404.128224 -186.69635) (xy 404.128478 -186.696096) (xy 404.134081 -186.689021) (xy 404.140316 -186.672095)
			(xy 404.14067 -186.663076) (xy 404.14067 -186.59602) (xy 404.14031 -186.587003) (xy 404.134065 -186.570086)
			(xy 404.128478 -186.563) (xy 404.128224 -186.563) (xy 404.128224 -186.562746) (xy 404.11063 -186.541775)
			(xy 404.080904 -186.495814) (xy 404.058056 -186.446074) (xy 404.042556 -186.393578) (xy 404.034723 -186.339404)
			(xy 404.034718 -186.284668) (xy 404.042541 -186.230493) (xy 404.058031 -186.177994) (xy 404.080869 -186.12825)
			(xy 404.110587 -186.082283) (xy 404.128224 -186.06135) (xy 404.128478 -186.061096) (xy 404.134081 -186.054021)
			(xy 404.140316 -186.037095) (xy 404.14067 -186.028076) (xy 404.14067 -185.96102) (xy 404.14031 -185.952003)
			(xy 404.134065 -185.935086) (xy 404.128478 -185.928) (xy 404.128224 -185.928) (xy 404.128224 -185.927746)
			(xy 404.11063 -185.906775) (xy 404.080904 -185.860814) (xy 404.058056 -185.811074) (xy 404.042556 -185.758578)
			(xy 404.034723 -185.704404) (xy 404.034718 -185.649668) (xy 404.042541 -185.595493) (xy 404.058031 -185.542994)
			(xy 404.080869 -185.49325) (xy 404.110587 -185.447283) (xy 404.128224 -185.42635) (xy 404.128478 -185.426096)
			(xy 404.134081 -185.419021) (xy 404.140316 -185.402095) (xy 404.14067 -185.393076) (xy 404.14067 -185.32602)
			(xy 404.14031 -185.317003) (xy 404.134065 -185.300086) (xy 404.128478 -185.293) (xy 404.128224 -185.293)
			(xy 404.128224 -185.292746) (xy 404.11063 -185.271775) (xy 404.080904 -185.225814) (xy 404.058056 -185.176074)
			(xy 404.042556 -185.123578) (xy 404.034723 -185.069404) (xy 404.034718 -185.014668) (xy 404.042541 -184.960493)
			(xy 404.058031 -184.907994) (xy 404.080869 -184.85825) (xy 404.110587 -184.812283) (xy 404.128224 -184.79135)
			(xy 404.128478 -184.791096) (xy 404.134081 -184.784021) (xy 404.140316 -184.767095) (xy 404.14067 -184.758076)
			(xy 404.14067 -184.69102) (xy 404.14031 -184.682003) (xy 404.134065 -184.665086) (xy 404.128478 -184.658)
			(xy 404.128224 -184.658) (xy 404.128224 -184.657746) (xy 404.11063 -184.636775) (xy 404.080904 -184.590814)
			(xy 404.058056 -184.541074) (xy 404.042556 -184.488578) (xy 404.034723 -184.434404) (xy 404.034718 -184.379668)
			(xy 404.042541 -184.325493) (xy 404.058031 -184.272994) (xy 404.080869 -184.22325) (xy 404.110587 -184.177283)
			(xy 404.128224 -184.15635) (xy 404.128478 -184.156096) (xy 404.134081 -184.149021) (xy 404.140316 -184.132095)
			(xy 404.14067 -184.123076) (xy 404.14067 -184.05602) (xy 404.14031 -184.047003) (xy 404.134065 -184.030086)
			(xy 404.128478 -184.023) (xy 404.128224 -184.023) (xy 404.128224 -184.022746) (xy 404.110597 -184.001804)
			(xy 404.080882 -183.955835) (xy 404.058044 -183.90609) (xy 404.04255 -183.853591) (xy 404.034719 -183.799417)
			(xy 404.034244 -183.772048) (xy 404.034643 -183.746226) (xy 404.041601 -183.695052) (xy 404.055395 -183.645284)
			(xy 404.075773 -183.597831) (xy 404.102365 -183.553559) (xy 404.134683 -183.513276) (xy 404.153116 -183.495188)
			(xy 404.160228 -183.488584) (xy 404.168356 -183.471058) (xy 404.172928 -183.392064) (xy 404.173113 -183.382582)
			(xy 404.167234 -183.364565) (xy 404.161498 -183.357012) (xy 404.161498 -183.356758) (xy 404.144997 -183.336149)
			(xy 404.117263 -183.291225) (xy 404.095989 -183.242906) (xy 404.081579 -183.192116) (xy 404.07431 -183.139824)
			(xy 404.073868 -183.113426) (xy 404.074333 -183.086056) (xy 404.082148 -183.031876) (xy 404.097637 -182.979372)
			(xy 404.120479 -182.929625) (xy 404.150206 -182.883659) (xy 404.167848 -182.862728) (xy 404.168102 -182.862474)
			(xy 404.173664 -182.855371) (xy 404.179925 -182.838467) (xy 404.180294 -182.829454) (xy 404.180294 -182.762398)
			(xy 404.179939 -182.753381) (xy 404.17369 -182.736464) (xy 404.168102 -182.729378) (xy 404.167848 -182.729378)
			(xy 404.167848 -182.729124) (xy 404.150232 -182.708171) (xy 404.120504 -182.662207) (xy 404.097656 -182.612464)
			(xy 404.082157 -182.559965) (xy 404.074326 -182.505789) (xy 404.074323 -182.45105) (xy 404.082149 -182.396873)
			(xy 404.097643 -182.344372) (xy 404.120486 -182.294627) (xy 404.150208 -182.24866) (xy 404.167848 -182.227728)
			(xy 404.168102 -182.227474) (xy 404.173664 -182.220371) (xy 404.179925 -182.203467) (xy 404.180294 -182.194454)
			(xy 404.180294 -182.127398) (xy 404.179939 -182.118381) (xy 404.17369 -182.101464) (xy 404.168102 -182.094378)
			(xy 404.167848 -182.094378) (xy 404.167848 -182.094124) (xy 404.150232 -182.073171) (xy 404.120504 -182.027207)
			(xy 404.097656 -181.977464) (xy 404.082157 -181.924965) (xy 404.074326 -181.870789) (xy 404.074323 -181.81605)
			(xy 404.082149 -181.761873) (xy 404.097643 -181.709372) (xy 404.120486 -181.659627) (xy 404.150208 -181.61366)
			(xy 404.167848 -181.592728) (xy 404.168102 -181.592474) (xy 404.173664 -181.585371) (xy 404.179925 -181.568467)
			(xy 404.180294 -181.559454) (xy 404.180294 -181.492398) (xy 404.179939 -181.483381) (xy 404.17369 -181.466464)
			(xy 404.168102 -181.459378) (xy 404.167848 -181.459378) (xy 404.167848 -181.459124) (xy 404.150214 -181.438188)
			(xy 404.1205 -181.392217) (xy 404.097662 -181.34247) (xy 404.08217 -181.28997) (xy 404.074342 -181.235795)
			(xy 404.073868 -181.208426) (xy 404.074379 -181.181175) (xy 404.082132 -181.127227) (xy 404.097484 -181.074931)
			(xy 404.120121 -181.025353) (xy 404.149585 -180.979501) (xy 404.185273 -180.938309) (xy 404.226461 -180.902615)
			(xy 404.272309 -180.873145) (xy 404.321885 -180.850501) (xy 404.374178 -180.835143) (xy 404.428125 -180.827383)
			(xy 404.455376 -180.826918) (xy 404.484853 -180.827468) (xy 404.543106 -180.836534) (xy 404.599271 -180.854454)
			(xy 404.65201 -180.880801) (xy 404.700069 -180.914948) (xy 404.721568 -180.935122) (xy 404.728916 -180.941639)
			(xy 404.747066 -180.949094) (xy 404.756874 -180.9496) (xy 404.810214 -180.9496) (xy 404.814532 -180.945028)
			(xy 404.82087 -180.937623) (xy 404.827914 -180.919464) (xy 404.828248 -180.909722) (xy 404.827994 -180.877718)
			(xy 404.827431 -180.867883) (xy 404.819867 -180.849718) (xy 404.813262 -180.842412) (xy 404.792587 -180.820843)
			(xy 404.757575 -180.772433) (xy 404.73054 -180.719156) (xy 404.712144 -180.662314) (xy 404.702839 -180.603298)
			(xy 404.702264 -180.573426) (xy 404.70275 -180.546175) (xy 404.710506 -180.492227) (xy 404.725861 -180.439932)
			(xy 404.748503 -180.390355) (xy 404.777969 -180.344505) (xy 404.81366 -180.303314) (xy 404.854851 -180.267623)
			(xy 404.900701 -180.238157) (xy 404.950278 -180.215515) (xy 405.002573 -180.20016) (xy 405.056521 -180.192404)
			(xy 405.111023 -180.192404) (xy 405.164971 -180.20016) (xy 405.217266 -180.215515) (xy 405.266843 -180.238157)
			(xy 405.312693 -180.267623) (xy 405.353884 -180.303314) (xy 405.389575 -180.344505) (xy 405.419041 -180.390355)
			(xy 405.441683 -180.439932) (xy 405.457038 -180.492227) (xy 405.464794 -180.546175) (xy 405.46528 -180.573426)
			(xy 405.464827 -180.600396) (xy 405.457217 -180.653797) (xy 405.442154 -180.705592) (xy 405.419938 -180.754745)
			(xy 405.391013 -180.800274) (xy 405.37384 -180.821076) (xy 405.368308 -180.828253) (xy 405.362184 -180.845293)
			(xy 405.361902 -180.85435) (xy 405.362664 -180.930804) (xy 405.369014 -180.947568) (xy 405.375364 -180.95468)
			(xy 405.393471 -180.975739) (xy 405.423972 -181.022152) (xy 405.447429 -181.072495) (xy 405.463345 -181.125703)
			(xy 405.471387 -181.180657) (xy 405.471884 -181.208426) (xy 405.471437 -181.235797) (xy 405.463615 -181.289977)
			(xy 405.448122 -181.342481) (xy 405.425276 -181.392227) (xy 405.395547 -181.438193) (xy 405.377904 -181.459124)
			(xy 405.37765 -181.459378) (xy 405.372061 -181.466462) (xy 405.365817 -181.483381) (xy 405.365458 -181.492398)
			(xy 405.365458 -181.559454) (xy 405.365824 -181.56847) (xy 405.372064 -181.585388) (xy 405.37765 -181.592474)
			(xy 405.377904 -181.592474) (xy 405.377904 -181.592728) (xy 405.395569 -181.613641) (xy 405.42529 -181.659613)
			(xy 405.448132 -181.709363) (xy 405.463625 -181.761867) (xy 405.471451 -181.816048) (xy 405.471448 -181.870791)
			(xy 405.463617 -181.924971) (xy 405.448118 -181.977474) (xy 405.425271 -182.027222) (xy 405.395545 -182.073191)
			(xy 405.377904 -182.094124) (xy 405.37765 -182.094378) (xy 405.372061 -182.101462) (xy 405.365817 -182.118381)
			(xy 405.365458 -182.127398) (xy 405.365458 -182.194454) (xy 405.365824 -182.20347) (xy 405.372064 -182.220388)
			(xy 405.37765 -182.227474) (xy 405.377904 -182.227474) (xy 405.377904 -182.227728) (xy 405.395569 -182.248641)
			(xy 405.42529 -182.294613) (xy 405.448132 -182.344363) (xy 405.463625 -182.396867) (xy 405.471451 -182.451048)
			(xy 405.471448 -182.505791) (xy 405.463617 -182.559971) (xy 405.448118 -182.612474) (xy 405.425271 -182.662222)
			(xy 405.395545 -182.708191) (xy 405.377904 -182.729124) (xy 405.37765 -182.729378) (xy 405.372061 -182.736462)
			(xy 405.365817 -182.753381) (xy 405.365458 -182.762398) (xy 405.365458 -182.829454) (xy 405.365824 -182.83847)
			(xy 405.372064 -182.855388) (xy 405.37765 -182.862474) (xy 405.377904 -182.862474) (xy 405.377904 -182.862728)
			(xy 405.395523 -182.883676) (xy 405.425238 -182.929644) (xy 405.448078 -182.979388) (xy 405.463573 -183.031885)
			(xy 405.471407 -183.086058) (xy 405.471884 -183.113426) (xy 405.47149 -183.139249) (xy 405.464535 -183.190423)
			(xy 405.450741 -183.240192) (xy 405.430361 -183.287646) (xy 405.403768 -183.331918) (xy 405.371447 -183.372199)
			(xy 405.353012 -183.390286) (xy 405.3459 -183.39689) (xy 405.337772 -183.414416) (xy 405.3332 -183.49341)
			(xy 405.333023 -183.502892) (xy 405.338896 -183.520908) (xy 405.34463 -183.528462) (xy 405.34463 -183.528716)
			(xy 405.361123 -183.549331) (xy 405.388857 -183.594254) (xy 405.410133 -183.642571) (xy 405.424544 -183.69336)
			(xy 405.431816 -183.745651) (xy 405.43226 -183.772048) (xy 405.431773 -183.799418) (xy 405.423962 -183.853596)
			(xy 405.408478 -183.906099) (xy 405.385641 -183.955847) (xy 405.35592 -184.001814) (xy 405.33828 -184.022746)
			(xy 405.338026 -184.023) (xy 405.332425 -184.030076) (xy 405.326189 -184.047001) (xy 405.325834 -184.05602)
			(xy 405.325834 -184.123076) (xy 405.326195 -184.132093) (xy 405.332439 -184.14901) (xy 405.338026 -184.156096)
			(xy 405.33828 -184.156096) (xy 405.33828 -184.15635) (xy 405.355967 -184.177245) (xy 405.38569 -184.223219)
			(xy 405.408532 -184.272972) (xy 405.424024 -184.32548) (xy 405.431848 -184.379663) (xy 405.431843 -184.434409)
			(xy 405.424009 -184.488591) (xy 405.408506 -184.541096) (xy 405.385655 -184.590844) (xy 405.355924 -184.636813)
			(xy 405.33828 -184.657746) (xy 405.338026 -184.658) (xy 405.332425 -184.665076) (xy 405.326189 -184.682001)
			(xy 405.325834 -184.69102) (xy 405.325834 -184.758076) (xy 405.326195 -184.767093) (xy 405.332439 -184.78401)
			(xy 405.338026 -184.791096) (xy 405.33828 -184.791096) (xy 405.33828 -184.79135) (xy 405.355967 -184.812245)
			(xy 405.38569 -184.858219) (xy 405.408532 -184.907972) (xy 405.424024 -184.96048) (xy 405.431848 -185.014663)
			(xy 405.431845 -185.042048) (xy 407.445464 -185.042048) (xy 407.445943 -185.014678) (xy 407.453755 -184.960499)
			(xy 407.46924 -184.907995) (xy 407.49208 -184.858248) (xy 407.521803 -184.812281) (xy 407.539444 -184.79135)
			(xy 407.539698 -184.791096) (xy 407.545292 -184.784015) (xy 407.551534 -184.767094) (xy 407.55189 -184.758076)
			(xy 407.55189 -184.69102) (xy 407.551526 -184.682004) (xy 407.545284 -184.665087) (xy 407.539698 -184.658)
			(xy 407.539444 -184.658) (xy 407.539444 -184.657746) (xy 407.52185 -184.636776) (xy 407.492122 -184.590815)
			(xy 407.469272 -184.541075) (xy 407.453772 -184.488578) (xy 407.445938 -184.434405) (xy 407.445933 -184.379668)
			(xy 407.453756 -184.325492) (xy 407.469247 -184.272993) (xy 407.492087 -184.223249) (xy 407.521806 -184.177282)
			(xy 407.539444 -184.15635) (xy 407.539698 -184.156096) (xy 407.545292 -184.149015) (xy 407.551534 -184.132094)
			(xy 407.55189 -184.123076) (xy 407.55189 -184.05602) (xy 407.551526 -184.047004) (xy 407.545284 -184.030087)
			(xy 407.539698 -184.023) (xy 407.539444 -184.023) (xy 407.539444 -184.022746) (xy 407.52182 -184.001802)
			(xy 407.492104 -183.955833) (xy 407.469265 -183.906089) (xy 407.45377 -183.85359) (xy 407.445939 -183.799416)
			(xy 407.445464 -183.772048) (xy 407.446035 -183.743037) (xy 407.454796 -183.685682) (xy 407.472139 -183.630313)
			(xy 407.497665 -183.578209) (xy 407.530784 -183.530569) (xy 407.550366 -183.509158) (xy 407.557224 -183.5023)
			(xy 407.564336 -183.484266) (xy 407.565352 -183.39562) (xy 407.558494 -183.37784) (xy 407.55189 -183.370728)
			(xy 407.533224 -183.349514) (xy 407.501686 -183.30263) (xy 407.477407 -183.251608) (xy 407.460918 -183.197564)
			(xy 407.452581 -183.141678) (xy 407.452068 -183.113426) (xy 407.452533 -183.086056) (xy 407.460348 -183.031876)
			(xy 407.475837 -182.979372) (xy 407.498679 -182.929625) (xy 407.528406 -182.883659) (xy 407.546048 -182.862728)
			(xy 407.546302 -182.862474) (xy 407.551864 -182.855371) (xy 407.558125 -182.838467) (xy 407.558494 -182.829454)
			(xy 407.558494 -182.762398) (xy 407.558139 -182.753381) (xy 407.55189 -182.736464) (xy 407.546302 -182.729378)
			(xy 407.546048 -182.729378) (xy 407.546048 -182.729124) (xy 407.528432 -182.708171) (xy 407.498704 -182.662207)
			(xy 407.475856 -182.612464) (xy 407.460357 -182.559965) (xy 407.452526 -182.505789) (xy 407.452523 -182.45105)
			(xy 407.460349 -182.396873) (xy 407.475843 -182.344372) (xy 407.498686 -182.294627) (xy 407.528408 -182.24866)
			(xy 407.546048 -182.227728) (xy 407.546302 -182.227474) (xy 407.551864 -182.220371) (xy 407.558125 -182.203467)
			(xy 407.558494 -182.194454) (xy 407.558494 -182.127398) (xy 407.558139 -182.118381) (xy 407.55189 -182.101464)
			(xy 407.546302 -182.094378) (xy 407.546048 -182.094378) (xy 407.546048 -182.094124) (xy 407.528432 -182.073171)
			(xy 407.498704 -182.027207) (xy 407.475856 -181.977464) (xy 407.460357 -181.924965) (xy 407.452526 -181.870789)
			(xy 407.452523 -181.81605) (xy 407.460349 -181.761873) (xy 407.475843 -181.709372) (xy 407.498686 -181.659627)
			(xy 407.528408 -181.61366) (xy 407.546048 -181.592728) (xy 407.546302 -181.592474) (xy 407.551864 -181.585371)
			(xy 407.558125 -181.568467) (xy 407.558494 -181.559454) (xy 407.558494 -181.492398) (xy 407.558139 -181.483381)
			(xy 407.55189 -181.466464) (xy 407.546302 -181.459378) (xy 407.546048 -181.459378) (xy 407.546048 -181.459124)
			(xy 407.528414 -181.438188) (xy 407.4987 -181.392217) (xy 407.475862 -181.34247) (xy 407.46037 -181.28997)
			(xy 407.452542 -181.235795) (xy 407.452068 -181.208426) (xy 407.452518 -181.181291) (xy 407.460212 -181.127569)
			(xy 407.475448 -181.075482) (xy 407.497918 -181.026083) (xy 407.527168 -180.98037) (xy 407.544524 -180.959506)
			(xy 407.550184 -180.952315) (xy 407.556428 -180.935125) (xy 407.556716 -180.925978) (xy 407.556462 -180.859176)
			(xy 407.555974 -180.85012) (xy 407.549469 -180.833204) (xy 407.543762 -180.826156) (xy 407.543508 -180.825902)
			(xy 407.52563 -180.804865) (xy 407.495432 -180.758651) (xy 407.472213 -180.708566) (xy 407.456458 -180.655657)
			(xy 407.448495 -180.601029) (xy 407.448004 -180.573426) (xy 407.44848 -180.546173) (xy 407.456233 -180.492222)
			(xy 407.471587 -180.439924) (xy 407.494227 -180.390343) (xy 407.523693 -180.344489) (xy 407.559386 -180.303296)
			(xy 407.600578 -180.267602) (xy 407.646431 -180.238134) (xy 407.696011 -180.215492) (xy 407.748308 -180.200136)
			(xy 407.802259 -180.192381) (xy 407.829512 -180.191918) (xy 407.856883 -180.192373) (xy 407.911062 -180.200193)
			(xy 407.963566 -180.215684) (xy 408.013313 -180.238528) (xy 408.059279 -180.268256) (xy 408.08021 -180.285898)
			(xy 408.080464 -180.286152) (xy 408.087552 -180.291736) (xy 408.104468 -180.297983) (xy 408.113484 -180.298344)
			(xy 408.18054 -180.298344) (xy 408.18956 -180.298018) (xy 408.206478 -180.29175) (xy 408.21356 -180.286152)
			(xy 408.21356 -180.285898) (xy 408.213814 -180.285898) (xy 408.234767 -180.268285) (xy 408.280734 -180.23857)
			(xy 408.330476 -180.215729) (xy 408.382972 -180.200231) (xy 408.437144 -180.192396) (xy 408.464512 -180.191918)
			(xy 408.48788 -180.19268) (xy 408.488134 -180.19268) (xy 408.498377 -180.192789) (xy 408.51765 -180.185907)
			(xy 408.532735 -180.172076) (xy 408.53741 -180.162962) (xy 408.576526 -180.076094) (xy 408.580369 -180.066517)
			(xy 408.580828 -180.045906) (xy 408.573098 -180.026793) (xy 408.566112 -180.019198) (xy 408.501088 -179.954428)
			(xy 408.483805 -179.936427) (xy 408.45448 -179.896052) (xy 408.431831 -179.851588) (xy 408.416416 -179.804128)
			(xy 408.408612 -179.754842) (xy 408.408124 -179.729892) (xy 408.408124 -166.959788) (xy 408.408638 -166.93484)
			(xy 408.41645 -166.885558) (xy 408.431863 -166.838102) (xy 408.454501 -166.793636) (xy 408.483806 -166.753252)
			(xy 408.501088 -166.735252) (xy 408.975052 -166.261288) (xy 408.982009 -166.253684) (xy 408.989675 -166.234569)
			(xy 408.989257 -166.213978) (xy 408.985466 -166.204392) (xy 408.939746 -166.1033) (xy 408.912568 -166.087044)
			(xy 408.89682 -166.08806) (xy 408.872436 -166.088822) (xy 408.84518 -166.088384) (xy 408.791221 -166.080631)
			(xy 408.738916 -166.065277) (xy 408.689328 -166.042636) (xy 408.643467 -166.013168) (xy 408.602266 -165.977473)
			(xy 408.566565 -165.936278) (xy 408.537091 -165.890421) (xy 408.514442 -165.840836) (xy 408.499081 -165.788533)
			(xy 408.49132 -165.734576) (xy 408.491318 -165.680063) (xy 408.499073 -165.626105) (xy 408.514429 -165.5738)
			(xy 408.537072 -165.524213) (xy 408.566542 -165.478353) (xy 408.602239 -165.437154) (xy 408.643436 -165.401455)
			(xy 408.689294 -165.371983) (xy 408.73888 -165.349336) (xy 408.791184 -165.333978) (xy 408.845141 -165.326219)
			(xy 408.899654 -165.326219) (xy 408.953611 -165.333977) (xy 409.005915 -165.349335) (xy 409.055502 -165.37198)
			(xy 409.10136 -165.401452) (xy 409.142557 -165.437151) (xy 409.178255 -165.478349) (xy 409.207725 -165.524208)
			(xy 409.230369 -165.573795) (xy 409.245726 -165.6261) (xy 409.253482 -165.680058) (xy 409.253944 -165.707314)
			(xy 409.253944 -165.707568) (xy 409.253328 -165.738657) (xy 409.243241 -165.800012) (xy 409.223314 -165.85891)
			(xy 409.20924 -165.886638) (xy 409.201366 -165.901624) (xy 409.206192 -165.934644) (xy 409.21813 -165.946582)
			(xy 409.225542 -165.953266) (xy 409.243975 -165.960863) (xy 409.263913 -165.960863) (xy 409.282346 -165.953266)
			(xy 409.289758 -165.946582) (xy 409.410154 -165.82644) (xy 409.416963 -165.819015) (xy 409.424702 -165.800435)
			(xy 409.42514 -165.790372) (xy 409.42514 -165.255956) (xy 409.424753 -165.245882) (xy 409.417007 -165.227284)
			(xy 409.410154 -165.219888) (xy 409.386278 -165.196266) (xy 409.381288 -165.191638) (xy 409.36945 -165.184938)
			(xy 409.36291 -165.183058) (xy 409.362656 -165.182804) (xy 409.362148 -165.182804) (xy 409.334755 -165.17571)
			(xy 409.282306 -165.154473) (xy 409.23357 -165.12572) (xy 409.189616 -165.090084) (xy 409.151409 -165.048346)
			(xy 409.119786 -165.001421) (xy 409.095443 -164.950339) (xy 409.078913 -164.896222) (xy 409.07056 -164.840257)
			(xy 409.070048 -164.811964) (xy 409.070544 -164.784714) (xy 409.078304 -164.730769) (xy 409.093662 -164.678477)
			(xy 409.116304 -164.628903) (xy 409.14577 -164.583054) (xy 409.18146 -164.541866) (xy 409.222648 -164.506175)
			(xy 409.268495 -164.476708) (xy 409.318069 -164.454065) (xy 409.370361 -164.438706) (xy 409.424306 -164.430945)
			(xy 409.451556 -164.430456) (xy 409.479861 -164.431015) (xy 409.535853 -164.439353) (xy 409.589995 -164.455882)
			(xy 409.641096 -164.480239) (xy 409.688031 -164.511888) (xy 409.729769 -164.550131) (xy 409.76539 -164.594128)
			(xy 409.794111 -164.642911) (xy 409.815299 -164.695405) (xy 409.822396 -164.72281) (xy 409.822396 -164.723318)
			(xy 409.824335 -164.729874) (xy 409.831164 -164.741715) (xy 409.835858 -164.746686) (xy 409.967684 -164.878512)
			(xy 409.984982 -164.8965) (xy 410.014305 -164.936878) (xy 410.036952 -164.981345) (xy 410.052364 -165.028808)
			(xy 410.060163 -165.078097) (xy 410.060648 -165.103048) (xy 410.060648 -165.94328) (xy 410.060122 -165.968228)
			(xy 410.052314 -166.017509) (xy 410.036904 -166.064966) (xy 410.014269 -166.109432) (xy 409.984966 -166.149816)
			(xy 409.967684 -166.167816) (xy 409.751276 -166.384224) (xy 409.744504 -166.391672) (xy 409.736931 -166.410308)
			(xy 409.737077 -166.430423) (xy 409.740608 -166.43985) (xy 409.777184 -166.526464) (xy 409.781539 -166.535608)
			(xy 409.795999 -166.549764) (xy 409.814811 -166.557216) (xy 409.824936 -166.557452) (xy 409.830778 -166.557452)
			(xy 409.858027 -166.557999) (xy 409.91197 -166.565751) (xy 409.964261 -166.581101) (xy 410.013836 -166.603737)
			(xy 410.059684 -166.633197) (xy 410.100874 -166.668882) (xy 410.136566 -166.710066) (xy 410.166033 -166.75591)
			(xy 410.188677 -166.80548) (xy 410.204036 -166.857769) (xy 410.211797 -166.911711) (xy 410.212286 -166.93896)
			(xy 410.21181 -166.966871) (xy 410.203669 -167.022097) (xy 410.187568 -167.075547) (xy 410.163852 -167.126082)
			(xy 410.133027 -167.172621) (xy 410.11475 -167.193722) (xy 410.108838 -167.200888) (xy 410.102197 -167.218222)
			(xy 410.101796 -167.227504) (xy 410.101796 -167.305228) (xy 410.1084 -167.3225) (xy 410.11475 -167.329612)
			(xy 410.133016 -167.350721) (xy 410.163843 -167.397258) (xy 410.18756 -167.44779) (xy 410.20366 -167.501239)
			(xy 410.211798 -167.556464) (xy 410.212286 -167.584374) (xy 410.2118 -167.611625) (xy 410.204044 -167.665573)
			(xy 410.188689 -167.717868) (xy 410.166047 -167.767445) (xy 410.136581 -167.813295) (xy 410.10089 -167.854486)
			(xy 410.059699 -167.890177) (xy 410.013849 -167.919643) (xy 409.964272 -167.942285) (xy 409.911977 -167.95764)
			(xy 409.858029 -167.965396) (xy 409.803527 -167.965396) (xy 409.749579 -167.95764) (xy 409.697284 -167.942285)
			(xy 409.647707 -167.919643) (xy 409.601857 -167.890177) (xy 409.560666 -167.854486) (xy 409.524975 -167.813295)
			(xy 409.495509 -167.767445) (xy 409.472867 -167.717868) (xy 409.457512 -167.665573) (xy 409.449756 -167.611625)
			(xy 409.44927 -167.584374) (xy 409.449752 -167.556463) (xy 409.45789 -167.501237) (xy 409.473988 -167.447786)
			(xy 409.497703 -167.397252) (xy 409.528529 -167.350712) (xy 409.546806 -167.329612) (xy 409.552699 -167.322432)
			(xy 409.559352 -167.305109) (xy 409.55976 -167.29583) (xy 409.55976 -167.218106) (xy 409.553156 -167.200834)
			(xy 409.546806 -167.193722) (xy 409.528518 -167.172631) (xy 409.497692 -167.12609) (xy 409.473978 -167.075554)
			(xy 409.457884 -167.0221) (xy 409.449753 -166.966872) (xy 409.44927 -166.93896) (xy 409.44927 -166.933118)
			(xy 409.449018 -166.922997) (xy 409.441557 -166.904193) (xy 409.427423 -166.88972) (xy 409.418282 -166.885366)
			(xy 409.331668 -166.84879) (xy 409.322258 -166.845185) (xy 409.302119 -166.845029) (xy 409.283478 -166.852654)
			(xy 409.276042 -166.859458) (xy 409.058618 -167.076628) (xy 409.051776 -167.084026) (xy 409.044057 -167.102627)
			(xy 409.043632 -167.112696) (xy 409.043632 -179.576984) (xy 409.044057 -179.587053) (xy 409.051777 -179.605652)
			(xy 409.058618 -179.613052) (xy 409.324302 -179.878482) (xy 409.341634 -179.896482) (xy 409.370999 -179.93691)
			(xy 409.393691 -179.981428) (xy 409.409154 -180.028942) (xy 409.417007 -180.078289) (xy 409.41752 -180.103272)
			(xy 409.41752 -180.34762) (xy 409.417713 -180.354578) (xy 409.421452 -180.367981) (xy 409.424886 -180.374036)
			(xy 409.438198 -180.396572) (xy 409.459172 -180.444527) (xy 409.473387 -180.494902) (xy 409.480574 -180.546747)
			(xy 409.48102 -180.572918) (xy 409.48102 -180.573426) (xy 409.480529 -180.600759) (xy 409.472725 -180.654865)
			(xy 409.45728 -180.707303) (xy 409.43451 -180.757001) (xy 409.404881 -180.802942) (xy 409.387294 -180.82387)
			(xy 409.38704 -180.824124) (xy 409.381121 -180.831613) (xy 409.374859 -180.84963) (xy 409.374857 -180.851048)
			(xy 412.39821 -180.851048) (xy 412.398702 -180.823679) (xy 412.406513 -180.769501) (xy 412.421996 -180.716998)
			(xy 412.444832 -180.66725) (xy 412.474551 -180.621282) (xy 412.49219 -180.60035) (xy 412.492444 -180.600096)
			(xy 412.498044 -180.593019) (xy 412.504281 -180.576095) (xy 412.504636 -180.567076) (xy 412.504636 -180.50002)
			(xy 412.504261 -180.491005) (xy 412.498025 -180.474088) (xy 412.492444 -180.467) (xy 412.49219 -180.467)
			(xy 412.49219 -180.466746) (xy 412.474598 -180.445774) (xy 412.444874 -180.399812) (xy 412.422028 -180.350072)
			(xy 412.40653 -180.297577) (xy 412.398697 -180.243404) (xy 412.398692 -180.188668) (xy 412.406514 -180.134494)
			(xy 412.422003 -180.081995) (xy 412.444839 -180.032251) (xy 412.474554 -179.986283) (xy 412.49219 -179.96535)
			(xy 412.492444 -179.965096) (xy 412.498044 -179.958019) (xy 412.504281 -179.941095) (xy 412.504636 -179.932076)
			(xy 412.504636 -179.86502) (xy 412.504261 -179.856005) (xy 412.498025 -179.839088) (xy 412.492444 -179.832)
			(xy 412.49219 -179.832) (xy 412.49219 -179.831746) (xy 412.474598 -179.810774) (xy 412.444874 -179.764812)
			(xy 412.422028 -179.715072) (xy 412.40653 -179.662577) (xy 412.398697 -179.608404) (xy 412.398692 -179.553668)
			(xy 412.406514 -179.499494) (xy 412.422003 -179.446995) (xy 412.444839 -179.397251) (xy 412.474554 -179.351283)
			(xy 412.49219 -179.33035) (xy 412.492444 -179.330096) (xy 412.498044 -179.323019) (xy 412.504281 -179.306095)
			(xy 412.504636 -179.297076) (xy 412.504636 -179.23002) (xy 412.504261 -179.221005) (xy 412.498025 -179.204088)
			(xy 412.492444 -179.197) (xy 412.49219 -179.197) (xy 412.49219 -179.196746) (xy 412.474557 -179.175809)
			(xy 412.444845 -179.129837) (xy 412.422008 -179.080091) (xy 412.406515 -179.027592) (xy 412.398685 -178.973417)
			(xy 412.39821 -178.946048) (xy 412.398768 -178.917037) (xy 412.407531 -178.85968) (xy 412.424876 -178.804311)
			(xy 412.450405 -178.752207) (xy 412.483528 -178.704568) (xy 412.503112 -178.683158) (xy 412.50997 -178.6763)
			(xy 412.517082 -178.658266) (xy 412.518098 -178.56962) (xy 412.51124 -178.55184) (xy 412.504636 -178.544728)
			(xy 412.485962 -178.523521) (xy 412.454426 -178.476635) (xy 412.43015 -178.425611) (xy 412.413663 -178.371565)
			(xy 412.405327 -178.315678) (xy 412.404814 -178.287426) (xy 412.405292 -178.260056) (xy 412.413106 -178.205877)
			(xy 412.428592 -178.153374) (xy 412.451432 -178.103627) (xy 412.481154 -178.05766) (xy 412.498794 -178.036728)
			(xy 412.499048 -178.036474) (xy 412.504616 -178.029375) (xy 412.510872 -178.012467) (xy 412.51124 -178.003454)
			(xy 412.51124 -177.936398) (xy 412.510897 -177.927379) (xy 412.504641 -177.910462) (xy 412.499048 -177.903378)
			(xy 412.498794 -177.903378) (xy 412.498794 -177.903124) (xy 412.48118 -177.88217) (xy 412.451457 -177.836205)
			(xy 412.428612 -177.786462) (xy 412.413115 -177.733964) (xy 412.405285 -177.679789) (xy 412.405282 -177.625051)
			(xy 412.413107 -177.570875) (xy 412.428598 -177.518375) (xy 412.451438 -177.468629) (xy 412.481157 -177.422661)
			(xy 412.498794 -177.401728) (xy 412.499048 -177.401474) (xy 412.504616 -177.394375) (xy 412.510872 -177.377467)
			(xy 412.51124 -177.368454) (xy 412.51124 -177.301398) (xy 412.510897 -177.292379) (xy 412.504641 -177.275462)
			(xy 412.499048 -177.268378) (xy 412.498794 -177.268378) (xy 412.498794 -177.268124) (xy 412.48118 -177.24717)
			(xy 412.451457 -177.201205) (xy 412.428612 -177.151462) (xy 412.413115 -177.098964) (xy 412.405285 -177.044789)
			(xy 412.405282 -176.990051) (xy 412.413107 -176.935875) (xy 412.428598 -176.883375) (xy 412.451438 -176.833629)
			(xy 412.481157 -176.787661) (xy 412.498794 -176.766728) (xy 412.499048 -176.766474) (xy 412.504616 -176.759375)
			(xy 412.510872 -176.742467) (xy 412.51124 -176.733454) (xy 412.51124 -176.666398) (xy 412.510897 -176.657379)
			(xy 412.504641 -176.640462) (xy 412.499048 -176.633378) (xy 412.498794 -176.633378) (xy 412.498794 -176.633124)
			(xy 412.481152 -176.612194) (xy 412.451441 -176.566221) (xy 412.428605 -176.516473) (xy 412.413115 -176.463972)
			(xy 412.405288 -176.409795) (xy 412.404814 -176.382426) (xy 412.405298 -176.355457) (xy 412.412901 -176.302057)
			(xy 412.427957 -176.250263) (xy 412.450166 -176.20111) (xy 412.479085 -176.155579) (xy 412.496254 -176.134776)
			(xy 412.501806 -176.127612) (xy 412.507918 -176.110562) (xy 412.508192 -176.101502) (xy 412.50743 -176.025048)
			(xy 412.50108 -176.008284) (xy 412.49473 -176.001172) (xy 412.476663 -175.98008) (xy 412.446152 -175.933677)
			(xy 412.422686 -175.883344) (xy 412.406761 -175.830142) (xy 412.398711 -175.775193) (xy 412.39821 -175.747426)
			(xy 412.39868 -175.720173) (xy 412.406433 -175.666221) (xy 412.421787 -175.613922) (xy 412.444428 -175.564341)
			(xy 412.473895 -175.518487) (xy 412.509588 -175.477294) (xy 412.550781 -175.4416) (xy 412.596634 -175.412132)
			(xy 412.646215 -175.38949) (xy 412.698514 -175.374135) (xy 412.752465 -175.36638) (xy 412.779718 -175.365918)
			(xy 412.807089 -175.366369) (xy 412.861269 -175.37419) (xy 412.913772 -175.389682) (xy 412.963519 -175.412527)
			(xy 413.009485 -175.442255) (xy 413.030416 -175.459898) (xy 413.03067 -175.460152) (xy 413.037756 -175.465738)
			(xy 413.054674 -175.471984) (xy 413.06369 -175.472344) (xy 413.130746 -175.472344) (xy 413.139762 -175.471973)
			(xy 413.156679 -175.465737) (xy 413.163766 -175.460152) (xy 413.163766 -175.459898) (xy 413.16402 -175.459898)
			(xy 413.184971 -175.442283) (xy 413.230939 -175.412567) (xy 413.280681 -175.389727) (xy 413.333178 -175.37423)
			(xy 413.38735 -175.366396) (xy 413.414718 -175.365918) (xy 413.441973 -175.366338) (xy 413.495926 -175.374098)
			(xy 413.548227 -175.389458) (xy 413.597809 -175.412104) (xy 413.643663 -175.441577) (xy 413.684856 -175.477275)
			(xy 413.72055 -175.518472) (xy 413.750017 -175.56433) (xy 413.772657 -175.613915) (xy 413.788011 -175.666217)
			(xy 413.795765 -175.720171) (xy 413.796226 -175.747426) (xy 413.795786 -175.774397) (xy 413.788175 -175.827799)
			(xy 413.773109 -175.879594) (xy 413.75089 -175.928747) (xy 413.721961 -175.974275) (xy 413.704786 -175.995076)
			(xy 413.699248 -176.002249) (xy 413.693128 -176.019293) (xy 413.692848 -176.02835) (xy 413.69361 -176.104804)
			(xy 413.69996 -176.121568) (xy 413.70631 -176.12868) (xy 413.724408 -176.149746) (xy 413.754913 -176.196157)
			(xy 413.778372 -176.246497) (xy 413.79429 -176.299705) (xy 413.802333 -176.354657) (xy 413.80283 -176.382426)
			(xy 413.802396 -176.409798) (xy 413.794573 -176.463979) (xy 413.779078 -176.516483) (xy 413.756228 -176.566229)
			(xy 413.726495 -176.612194) (xy 413.70885 -176.633124) (xy 413.708596 -176.633378) (xy 413.703012 -176.640466)
			(xy 413.696764 -176.657382) (xy 413.696404 -176.666398) (xy 413.696404 -176.733454) (xy 413.696782 -176.742469)
			(xy 413.703015 -176.759386) (xy 413.708596 -176.766474) (xy 413.70885 -176.766474) (xy 413.70885 -176.766728)
			(xy 413.726517 -176.78764) (xy 413.756243 -176.833611) (xy 413.779088 -176.88336) (xy 413.794583 -176.935866)
			(xy 413.80241 -176.990047) (xy 413.802407 -177.044792) (xy 413.794575 -177.098973) (xy 413.779074 -177.151477)
			(xy 413.756224 -177.201224) (xy 413.726493 -177.247192) (xy 413.70885 -177.268124) (xy 413.708596 -177.268378)
			(xy 413.703012 -177.275466) (xy 413.696764 -177.292382) (xy 413.696404 -177.301398) (xy 413.696404 -177.368454)
			(xy 413.696782 -177.377469) (xy 413.703015 -177.394386) (xy 413.708596 -177.401474) (xy 413.70885 -177.401474)
			(xy 413.70885 -177.401728) (xy 413.726517 -177.42264) (xy 413.756243 -177.468611) (xy 413.779088 -177.51836)
			(xy 413.794583 -177.570866) (xy 413.80241 -177.625047) (xy 413.802407 -177.679792) (xy 413.794575 -177.733973)
			(xy 413.779074 -177.786477) (xy 413.756224 -177.836224) (xy 413.726493 -177.882192) (xy 413.70885 -177.903124)
			(xy 413.708596 -177.903378) (xy 413.703012 -177.910466) (xy 413.696764 -177.927382) (xy 413.696404 -177.936398)
			(xy 413.696404 -178.003454) (xy 413.696782 -178.012469) (xy 413.703015 -178.029386) (xy 413.708596 -178.036474)
			(xy 413.70885 -178.036474) (xy 413.70885 -178.036728) (xy 413.726461 -178.057683) (xy 413.756179 -178.103649)
			(xy 413.779021 -178.15339) (xy 413.794518 -178.205886) (xy 413.802353 -178.260058) (xy 413.80283 -178.287426)
			(xy 413.802306 -178.316438) (xy 413.793534 -178.373796) (xy 413.77618 -178.429165) (xy 413.750644 -178.481269)
			(xy 413.717515 -178.528906) (xy 413.697928 -178.550316) (xy 413.69107 -178.557174) (xy 413.683958 -178.575208)
			(xy 413.682942 -178.663854) (xy 413.6898 -178.681634) (xy 413.696404 -178.688746) (xy 413.715056 -178.709972)
			(xy 413.746597 -178.756852) (xy 413.770879 -178.807871) (xy 413.78737 -178.861913) (xy 413.795711 -178.917797)
			(xy 413.796226 -178.946048) (xy 413.795747 -178.973418) (xy 413.787935 -179.027597) (xy 413.77245 -179.080101)
			(xy 413.749611 -179.129848) (xy 413.719887 -179.175815) (xy 413.702246 -179.196746) (xy 413.701992 -179.197)
			(xy 413.696398 -179.204082) (xy 413.690156 -179.221002) (xy 413.6898 -179.23002) (xy 413.6898 -179.297076)
			(xy 413.690168 -179.306092) (xy 413.696408 -179.323009) (xy 413.701992 -179.330096) (xy 413.702246 -179.330096)
			(xy 413.702246 -179.33035) (xy 413.719935 -179.351244) (xy 413.74966 -179.397218) (xy 413.772504 -179.44697)
			(xy 413.787998 -179.499479) (xy 413.795822 -179.553663) (xy 413.795817 -179.608409) (xy 413.787982 -179.662592)
			(xy 413.772479 -179.715097) (xy 413.749625 -179.764846) (xy 413.719891 -179.810814) (xy 413.702246 -179.831746)
			(xy 413.701992 -179.832) (xy 413.696398 -179.839082) (xy 413.690156 -179.856002) (xy 413.6898 -179.86502)
			(xy 413.6898 -179.932076) (xy 413.690168 -179.941092) (xy 413.696408 -179.958009) (xy 413.701992 -179.965096)
			(xy 413.702246 -179.965096) (xy 413.702246 -179.96535) (xy 413.719935 -179.986244) (xy 413.74966 -180.032218)
			(xy 413.772504 -180.08197) (xy 413.787998 -180.134479) (xy 413.795822 -180.188663) (xy 413.795817 -180.243409)
			(xy 413.787982 -180.297592) (xy 413.772479 -180.350097) (xy 413.749625 -180.399846) (xy 413.719891 -180.445814)
			(xy 413.702246 -180.466746) (xy 413.701992 -180.467) (xy 413.696398 -180.474082) (xy 413.690156 -180.491002)
			(xy 413.6898 -180.50002) (xy 413.6898 -180.567076) (xy 413.690168 -180.576092) (xy 413.696408 -180.593009)
			(xy 413.701992 -180.600096) (xy 413.702246 -180.600096) (xy 413.702246 -180.60035) (xy 413.719867 -180.621297)
			(xy 413.749583 -180.667265) (xy 413.772424 -180.717008) (xy 413.787919 -180.769506) (xy 413.79575 -180.82368)
			(xy 413.796049 -180.840888) (xy 415.76625 -180.840888) (xy 415.766697 -180.813517) (xy 415.774517 -180.759337)
			(xy 415.79001 -180.706833) (xy 415.812857 -180.657086) (xy 415.842586 -180.611121) (xy 415.86023 -180.59019)
			(xy 415.860484 -180.589936) (xy 415.86606 -180.582842) (xy 415.872313 -180.565931) (xy 415.872676 -180.556916)
			(xy 415.872676 -180.48986) (xy 415.872343 -180.480841) (xy 415.866079 -180.463924) (xy 415.860484 -180.45684)
			(xy 415.86023 -180.45684) (xy 415.86023 -180.456586) (xy 415.842577 -180.435663) (xy 415.812853 -180.389693)
			(xy 415.790008 -180.339946) (xy 415.774513 -180.287442) (xy 415.766685 -180.233262) (xy 415.766686 -180.17852)
			(xy 415.774516 -180.12434) (xy 415.790014 -180.071837) (xy 415.812862 -180.022091) (xy 415.842588 -179.976123)
			(xy 415.86023 -179.95519) (xy 415.860484 -179.954936) (xy 415.86606 -179.947842) (xy 415.872313 -179.930931)
			(xy 415.872676 -179.921916) (xy 415.872676 -179.85486) (xy 415.872343 -179.845841) (xy 415.866079 -179.828924)
			(xy 415.860484 -179.82184) (xy 415.86023 -179.82184) (xy 415.86023 -179.821586) (xy 415.842577 -179.800663)
			(xy 415.812853 -179.754693) (xy 415.790008 -179.704946) (xy 415.774513 -179.652442) (xy 415.766685 -179.598262)
			(xy 415.766686 -179.54352) (xy 415.774516 -179.48934) (xy 415.790014 -179.436837) (xy 415.812862 -179.387091)
			(xy 415.842588 -179.341123) (xy 415.86023 -179.32019) (xy 415.860484 -179.319936) (xy 415.86606 -179.312842)
			(xy 415.872313 -179.295931) (xy 415.872676 -179.286916) (xy 415.872676 -179.21986) (xy 415.872343 -179.210841)
			(xy 415.866079 -179.193924) (xy 415.860484 -179.18684) (xy 415.86023 -179.18684) (xy 415.86023 -179.186586)
			(xy 415.842622 -179.165628) (xy 415.812905 -179.119663) (xy 415.790062 -179.069922) (xy 415.774564 -179.017427)
			(xy 415.766728 -178.963256) (xy 415.76625 -178.935888) (xy 415.766777 -178.906805) (xy 415.775602 -178.849312)
			(xy 415.793047 -178.793823) (xy 415.818707 -178.741622) (xy 415.851989 -178.693918) (xy 415.87166 -178.67249)
			(xy 415.877809 -178.665401) (xy 415.884971 -178.64807) (xy 415.88563 -178.638708) (xy 415.887408 -178.570382)
			(xy 415.887219 -178.561129) (xy 415.881116 -178.543677) (xy 415.87547 -178.536346) (xy 415.875216 -178.536346)
			(xy 415.875216 -178.536092) (xy 415.857881 -178.515257) (xy 415.828724 -178.469568) (xy 415.806329 -178.420211)
			(xy 415.791147 -178.368181) (xy 415.783485 -178.314526) (xy 415.783014 -178.287426) (xy 415.783492 -178.260056)
			(xy 415.791306 -178.205877) (xy 415.806792 -178.153374) (xy 415.829632 -178.103627) (xy 415.859354 -178.05766)
			(xy 415.876994 -178.036728) (xy 415.877248 -178.036474) (xy 415.882816 -178.029375) (xy 415.889072 -178.012467)
			(xy 415.88944 -178.003454) (xy 415.88944 -177.936398) (xy 415.889097 -177.927379) (xy 415.882841 -177.910462)
			(xy 415.877248 -177.903378) (xy 415.876994 -177.903378) (xy 415.876994 -177.903124) (xy 415.85938 -177.88217)
			(xy 415.829657 -177.836205) (xy 415.806812 -177.786462) (xy 415.791315 -177.733964) (xy 415.783485 -177.679789)
			(xy 415.783482 -177.625051) (xy 415.791307 -177.570875) (xy 415.806798 -177.518375) (xy 415.829638 -177.468629)
			(xy 415.859357 -177.422661) (xy 415.876994 -177.401728) (xy 415.877248 -177.401474) (xy 415.882816 -177.394375)
			(xy 415.889072 -177.377467) (xy 415.88944 -177.368454) (xy 415.88944 -177.301398) (xy 415.889097 -177.292379)
			(xy 415.882841 -177.275462) (xy 415.877248 -177.268378) (xy 415.876994 -177.268378) (xy 415.876994 -177.268124)
			(xy 415.85938 -177.24717) (xy 415.829657 -177.201205) (xy 415.806812 -177.151462) (xy 415.791315 -177.098964)
			(xy 415.783485 -177.044789) (xy 415.783482 -176.990051) (xy 415.791307 -176.935875) (xy 415.806798 -176.883375)
			(xy 415.829638 -176.833629) (xy 415.859357 -176.787661) (xy 415.876994 -176.766728) (xy 415.877248 -176.766474)
			(xy 415.882816 -176.759375) (xy 415.889072 -176.742467) (xy 415.88944 -176.733454) (xy 415.88944 -176.666398)
			(xy 415.889097 -176.657379) (xy 415.882841 -176.640462) (xy 415.877248 -176.633378) (xy 415.876994 -176.633378)
			(xy 415.876994 -176.633124) (xy 415.859352 -176.612194) (xy 415.829641 -176.566221) (xy 415.806805 -176.516473)
			(xy 415.791315 -176.463972) (xy 415.783488 -176.409795) (xy 415.783014 -176.382426) (xy 415.783477 -176.355292)
			(xy 415.79117 -176.301571) (xy 415.806404 -176.249484) (xy 415.82887 -176.200085) (xy 415.858116 -176.154371)
			(xy 415.87547 -176.133506) (xy 415.881123 -176.12631) (xy 415.887373 -176.109125) (xy 415.887662 -176.099978)
			(xy 415.887408 -176.033176) (xy 415.88691 -176.024122) (xy 415.880411 -176.007206) (xy 415.874708 -176.000156)
			(xy 415.874454 -175.999902) (xy 415.856568 -175.978872) (xy 415.826373 -175.932655) (xy 415.803156 -175.882568)
			(xy 415.787403 -175.829658) (xy 415.779441 -175.775029) (xy 415.77895 -175.747426) (xy 415.779502 -175.720177)
			(xy 415.787254 -175.666234) (xy 415.802604 -175.613943) (xy 415.825239 -175.564369) (xy 415.854699 -175.518521)
			(xy 415.890383 -175.477331) (xy 415.931566 -175.441639) (xy 415.977409 -175.412172) (xy 416.02698 -175.389528)
			(xy 416.079268 -175.374169) (xy 416.133209 -175.366407) (xy 416.160458 -175.365918) (xy 416.187828 -175.366404)
			(xy 416.242006 -175.374217) (xy 416.294509 -175.389701) (xy 416.344256 -175.412538) (xy 416.390224 -175.442259)
			(xy 416.411156 -175.459898) (xy 416.41141 -175.460152) (xy 416.418485 -175.465755) (xy 416.435411 -175.471991)
			(xy 416.44443 -175.472344) (xy 416.511486 -175.472344) (xy 416.520504 -175.471992) (xy 416.537421 -175.465742)
			(xy 416.544506 -175.460152) (xy 416.544506 -175.459898) (xy 416.54476 -175.459898) (xy 416.565696 -175.442264)
			(xy 416.611668 -175.412551) (xy 416.661414 -175.389715) (xy 416.713914 -175.374222) (xy 416.768089 -175.366393)
			(xy 416.795458 -175.365918) (xy 416.824878 -175.36646) (xy 416.883019 -175.375507) (xy 416.939075 -175.393392)
			(xy 416.965638 -175.40605) (xy 416.965892 -175.40605) (xy 416.973728 -175.409525) (xy 416.990723 -175.411637)
			(xy 417.007454 -175.407981) (xy 417.014914 -175.403764) (xy 417.088574 -175.358298) (xy 417.0958 -175.353473)
			(xy 417.106689 -175.339946) (xy 417.112408 -175.323549) (xy 417.112704 -175.314864) (xy 417.112704 -166.912544)
			(xy 417.112281 -166.902474) (xy 417.104561 -166.883875) (xy 417.097718 -166.876476) (xy 416.857688 -166.6367)
			(xy 416.840391 -166.618711) (xy 416.811069 -166.578333) (xy 416.788422 -166.533866) (xy 416.77301 -166.486404)
			(xy 416.76521 -166.437115) (xy 416.764724 -166.412164) (xy 416.764724 -162.159188) (xy 416.765238 -162.13424)
			(xy 416.77305 -162.084958) (xy 416.788463 -162.037502) (xy 416.811101 -161.993036) (xy 416.840406 -161.952652)
			(xy 416.857688 -161.934652) (xy 417.357052 -161.435288) (xy 417.364009 -161.427684) (xy 417.371675 -161.408569)
			(xy 417.371257 -161.387978) (xy 417.367466 -161.378392) (xy 417.321746 -161.2773) (xy 417.294568 -161.261044)
			(xy 417.27882 -161.26206) (xy 417.254436 -161.262822) (xy 417.22718 -161.262384) (xy 417.173221 -161.254631)
			(xy 417.120916 -161.239277) (xy 417.071328 -161.216636) (xy 417.025467 -161.187168) (xy 416.984266 -161.151473)
			(xy 416.948565 -161.110278) (xy 416.919091 -161.064421) (xy 416.896442 -161.014836) (xy 416.881081 -160.962533)
			(xy 416.87332 -160.908576) (xy 416.873318 -160.854063) (xy 416.881073 -160.800105) (xy 416.896429 -160.7478)
			(xy 416.919072 -160.698213) (xy 416.948542 -160.652353) (xy 416.984239 -160.611154) (xy 417.025436 -160.575455)
			(xy 417.071294 -160.545983) (xy 417.12088 -160.523336) (xy 417.173184 -160.507978) (xy 417.227141 -160.500219)
			(xy 417.281654 -160.500219) (xy 417.335611 -160.507977) (xy 417.387915 -160.523335) (xy 417.437502 -160.54598)
			(xy 417.48336 -160.575452) (xy 417.524557 -160.611151) (xy 417.560255 -160.652349) (xy 417.589725 -160.698208)
			(xy 417.612369 -160.747795) (xy 417.627726 -160.8001) (xy 417.635482 -160.854058) (xy 417.635944 -160.881314)
			(xy 417.635944 -160.881568) (xy 417.635328 -160.912657) (xy 417.625241 -160.974012) (xy 417.605314 -161.03291)
			(xy 417.59124 -161.060638) (xy 417.583366 -161.075624) (xy 417.588192 -161.108644) (xy 417.60013 -161.120582)
			(xy 417.607542 -161.127266) (xy 417.625975 -161.134863) (xy 417.645913 -161.134863) (xy 417.664346 -161.127266)
			(xy 417.671758 -161.120582) (xy 417.792154 -161.00044) (xy 417.798963 -160.993015) (xy 417.806702 -160.974435)
			(xy 417.80714 -160.964372) (xy 417.80714 -160.429956) (xy 417.806753 -160.419882) (xy 417.799007 -160.401284)
			(xy 417.792154 -160.393888) (xy 417.768278 -160.370266) (xy 417.763288 -160.365638) (xy 417.75145 -160.358938)
			(xy 417.74491 -160.357058) (xy 417.744656 -160.356804) (xy 417.744148 -160.356804) (xy 417.716755 -160.34971)
			(xy 417.664306 -160.328473) (xy 417.61557 -160.29972) (xy 417.571616 -160.264084) (xy 417.533409 -160.222346)
			(xy 417.501786 -160.175421) (xy 417.477443 -160.124339) (xy 417.460913 -160.070222) (xy 417.45256 -160.014257)
			(xy 417.452048 -159.985964) (xy 417.452544 -159.958714) (xy 417.460304 -159.904769) (xy 417.475662 -159.852477)
			(xy 417.498304 -159.802903) (xy 417.52777 -159.757054) (xy 417.56346 -159.715866) (xy 417.604648 -159.680175)
			(xy 417.650495 -159.650708) (xy 417.700069 -159.628065) (xy 417.752361 -159.612706) (xy 417.806306 -159.604945)
			(xy 417.833556 -159.604456) (xy 417.861861 -159.605015) (xy 417.917853 -159.613353) (xy 417.971995 -159.629882)
			(xy 418.023096 -159.654239) (xy 418.070031 -159.685888) (xy 418.111769 -159.724131) (xy 418.14739 -159.768128)
			(xy 418.176111 -159.816911) (xy 418.197299 -159.869405) (xy 418.204396 -159.89681) (xy 418.204396 -159.897318)
			(xy 418.206335 -159.903874) (xy 418.213164 -159.915715) (xy 418.217858 -159.920686) (xy 418.349684 -160.052512)
			(xy 418.366982 -160.0705) (xy 418.396305 -160.110878) (xy 418.418952 -160.155345) (xy 418.434364 -160.202808)
			(xy 418.442163 -160.252097) (xy 418.442648 -160.277048) (xy 418.442648 -161.11728) (xy 418.442122 -161.142228)
			(xy 418.434314 -161.191509) (xy 418.418904 -161.238966) (xy 418.396269 -161.283432) (xy 418.366966 -161.323816)
			(xy 418.349684 -161.341816) (xy 418.133276 -161.558224) (xy 418.126504 -161.565672) (xy 418.118931 -161.584308)
			(xy 418.119077 -161.604423) (xy 418.122608 -161.61385) (xy 418.159184 -161.700464) (xy 418.163539 -161.709608)
			(xy 418.177999 -161.723764) (xy 418.196811 -161.731216) (xy 418.206936 -161.731452) (xy 418.212778 -161.731452)
			(xy 418.240027 -161.731999) (xy 418.29397 -161.739751) (xy 418.346261 -161.755101) (xy 418.395836 -161.777737)
			(xy 418.441684 -161.807197) (xy 418.482874 -161.842882) (xy 418.518566 -161.884066) (xy 418.548033 -161.92991)
			(xy 418.570677 -161.97948) (xy 418.586036 -162.031769) (xy 418.593797 -162.085711) (xy 418.594286 -162.11296)
			(xy 418.59381 -162.140871) (xy 418.585669 -162.196097) (xy 418.569568 -162.249547) (xy 418.545852 -162.300082)
			(xy 418.515027 -162.346621) (xy 418.49675 -162.367722) (xy 418.490838 -162.374888) (xy 418.484197 -162.392222)
			(xy 418.483796 -162.401504) (xy 418.483796 -162.479228) (xy 418.4904 -162.4965) (xy 418.49675 -162.503612)
			(xy 418.515016 -162.524721) (xy 418.545843 -162.571258) (xy 418.56956 -162.62179) (xy 418.58566 -162.675239)
			(xy 418.593798 -162.730464) (xy 418.594286 -162.758374) (xy 418.5938 -162.785625) (xy 418.586044 -162.839573)
			(xy 418.570689 -162.891868) (xy 418.548047 -162.941445) (xy 418.518581 -162.987295) (xy 418.48289 -163.028486)
			(xy 418.441699 -163.064177) (xy 418.395849 -163.093643) (xy 418.346272 -163.116285) (xy 418.293977 -163.13164)
			(xy 418.240029 -163.139396) (xy 418.185527 -163.139396) (xy 418.131579 -163.13164) (xy 418.079284 -163.116285)
			(xy 418.029707 -163.093643) (xy 417.983857 -163.064177) (xy 417.942666 -163.028486) (xy 417.906975 -162.987295)
			(xy 417.877509 -162.941445) (xy 417.854867 -162.891868) (xy 417.839512 -162.839573) (xy 417.831756 -162.785625)
			(xy 417.83127 -162.758374) (xy 417.831752 -162.730463) (xy 417.83989 -162.675237) (xy 417.855988 -162.621786)
			(xy 417.879703 -162.571252) (xy 417.910529 -162.524712) (xy 417.928806 -162.503612) (xy 417.934699 -162.496432)
			(xy 417.941352 -162.479109) (xy 417.94176 -162.46983) (xy 417.94176 -162.392106) (xy 417.935156 -162.374834)
			(xy 417.928806 -162.367722) (xy 417.910518 -162.346631) (xy 417.879692 -162.30009) (xy 417.855978 -162.249554)
			(xy 417.839884 -162.1961) (xy 417.831753 -162.140872) (xy 417.83127 -162.11296) (xy 417.83127 -162.107118)
			(xy 417.831018 -162.096997) (xy 417.823557 -162.078193) (xy 417.809423 -162.06372) (xy 417.800282 -162.059366)
			(xy 417.713668 -162.02279) (xy 417.704258 -162.019185) (xy 417.684119 -162.019029) (xy 417.665478 -162.026654)
			(xy 417.658042 -162.033458) (xy 417.415218 -162.276028) (xy 417.408376 -162.283426) (xy 417.400657 -162.302027)
			(xy 417.400232 -162.312096) (xy 417.400232 -166.259256) (xy 417.400672 -166.269324) (xy 417.408382 -166.287922)
			(xy 417.415218 -166.295324) (xy 417.655248 -166.5351) (xy 417.672553 -166.553083) (xy 417.701882 -166.59346)
			(xy 417.724533 -166.637928) (xy 417.73995 -166.685392) (xy 417.747751 -166.734684) (xy 417.748212 -166.759636)
			(xy 417.748212 -175.52162) (xy 417.748512 -175.528587) (xy 417.752376 -175.541979) (xy 417.755832 -175.548036)
			(xy 417.769147 -175.570643) (xy 417.79016 -175.618717) (xy 417.804382 -175.669218) (xy 417.811545 -175.721193)
			(xy 417.811966 -175.747426) (xy 417.811488 -175.77476) (xy 417.803683 -175.828867) (xy 417.788235 -175.881306)
			(xy 417.765462 -175.931004) (xy 417.735829 -175.976943) (xy 417.71824 -175.99787) (xy 417.717986 -175.998124)
			(xy 417.712073 -176.005617) (xy 417.705806 -176.023631) (xy 417.705794 -176.033176) (xy 417.70808 -176.102264)
			(xy 417.708842 -176.111859) (xy 417.716535 -176.129484) (xy 417.723066 -176.136554) (xy 417.74386 -176.158159)
			(xy 417.779117 -176.206658) (xy 417.806349 -176.260077) (xy 417.824885 -176.317101) (xy 417.834268 -176.376322)
			(xy 417.834826 -176.406302) (xy 417.834379 -176.433673) (xy 417.826559 -176.487854) (xy 417.811067 -176.540358)
			(xy 417.78822 -176.590104) (xy 417.75849 -176.63607) (xy 417.740846 -176.657) (xy 417.740592 -176.657254)
			(xy 417.735018 -176.664349) (xy 417.728764 -176.681259) (xy 417.7284 -176.690274) (xy 417.7284 -176.75733)
			(xy 417.728743 -176.766348) (xy 417.735 -176.783265) (xy 417.740592 -176.79035) (xy 417.740846 -176.79035)
			(xy 417.740846 -176.790604) (xy 417.75849 -176.811535) (xy 417.788217 -176.857502) (xy 417.789456 -176.8602)
			(xy 421.86225 -176.8602) (xy 421.862749 -176.831282) (xy 421.87148 -176.774109) (xy 421.88874 -176.718909)
			(xy 421.914135 -176.666947) (xy 421.947083 -176.619414) (xy 421.986828 -176.577399) (xy 422.009316 -176.55921)
			(xy 422.018112 -176.551592) (xy 422.028301 -176.530699) (xy 422.028874 -176.519078) (xy 422.028874 -176.439322)
			(xy 422.028317 -176.427692) (xy 422.018142 -176.406782) (xy 422.009316 -176.39919) (xy 421.986831 -176.381001)
			(xy 421.947095 -176.338981) (xy 421.914156 -176.291446) (xy 421.888768 -176.239484) (xy 421.871512 -176.184286)
			(xy 421.862784 -176.127116) (xy 421.86225 -176.0982) (xy 421.862736 -176.070949) (xy 421.870492 -176.017001)
			(xy 421.885847 -175.964706) (xy 421.908489 -175.915129) (xy 421.937955 -175.869279) (xy 421.973646 -175.828088)
			(xy 422.014837 -175.792397) (xy 422.060687 -175.762931) (xy 422.110264 -175.740289) (xy 422.162559 -175.724934)
			(xy 422.216507 -175.717178) (xy 422.271009 -175.717178) (xy 422.324957 -175.724934) (xy 422.377252 -175.740289)
			(xy 422.426829 -175.762931) (xy 422.472679 -175.792397) (xy 422.51387 -175.828088) (xy 422.549561 -175.869279)
			(xy 422.579027 -175.915129) (xy 422.601669 -175.964706) (xy 422.617024 -176.017001) (xy 422.62478 -176.070949)
			(xy 422.625266 -176.0982) (xy 422.62476 -176.127118) (xy 422.616031 -176.18429) (xy 422.598771 -176.23949)
			(xy 422.573377 -176.291451) (xy 422.540431 -176.338985) (xy 422.500687 -176.381001) (xy 422.4782 -176.39919)
			(xy 422.469407 -176.406811) (xy 422.459216 -176.427701) (xy 422.458642 -176.439322) (xy 422.458642 -176.519078)
			(xy 422.459194 -176.530709) (xy 422.469372 -176.551619) (xy 422.4782 -176.55921) (xy 422.500688 -176.577395)
			(xy 422.540423 -176.619416) (xy 422.573362 -176.666952) (xy 422.598749 -176.718915) (xy 422.616004 -176.774113)
			(xy 422.624732 -176.831284) (xy 422.625266 -176.8602) (xy 422.62478 -176.887451) (xy 422.617024 -176.941399)
			(xy 422.601669 -176.993694) (xy 422.579027 -177.043271) (xy 422.549561 -177.089121) (xy 422.51387 -177.130312)
			(xy 422.472679 -177.166003) (xy 422.426829 -177.195469) (xy 422.377252 -177.218111) (xy 422.324957 -177.233466)
			(xy 422.271009 -177.241222) (xy 422.216507 -177.241222) (xy 422.162559 -177.233466) (xy 422.110264 -177.218111)
			(xy 422.060687 -177.195469) (xy 422.014837 -177.166003) (xy 421.973646 -177.130312) (xy 421.937955 -177.089121)
			(xy 421.908489 -177.043271) (xy 421.885847 -176.993694) (xy 421.870492 -176.941399) (xy 421.862736 -176.887451)
			(xy 421.86225 -176.8602) (xy 417.789456 -176.8602) (xy 417.811063 -176.907249) (xy 417.826561 -176.959751)
			(xy 417.83439 -177.01393) (xy 417.83439 -177.068673) (xy 417.82656 -177.122852) (xy 417.811062 -177.175354)
			(xy 417.788215 -177.225101) (xy 417.758488 -177.271068) (xy 417.740846 -177.292) (xy 417.740592 -177.292254)
			(xy 417.735018 -177.299349) (xy 417.728764 -177.316259) (xy 417.7284 -177.325274) (xy 417.7284 -177.39233)
			(xy 417.728743 -177.401348) (xy 417.735 -177.418265) (xy 417.740592 -177.42535) (xy 417.740846 -177.42535)
			(xy 417.740846 -177.425604) (xy 417.75849 -177.446535) (xy 417.788217 -177.492502) (xy 417.811063 -177.542249)
			(xy 417.826561 -177.594751) (xy 417.83439 -177.64893) (xy 417.83439 -177.703673) (xy 417.82656 -177.757852)
			(xy 417.811062 -177.810354) (xy 417.788215 -177.860101) (xy 417.758488 -177.906068) (xy 417.740846 -177.927)
			(xy 417.740592 -177.927254) (xy 417.735018 -177.934349) (xy 417.728764 -177.951259) (xy 417.7284 -177.960274)
			(xy 417.7284 -178.02733) (xy 417.728743 -178.036348) (xy 417.735 -178.053265) (xy 417.740592 -178.06035)
			(xy 417.740846 -178.06035) (xy 417.740846 -178.060604) (xy 417.758492 -178.081531) (xy 417.788205 -178.127504)
			(xy 417.81104 -178.177253) (xy 417.826529 -178.229755) (xy 417.834354 -178.283932) (xy 417.834826 -178.311302)
			(xy 417.834273 -178.340815) (xy 417.825182 -178.399136) (xy 417.807217 -178.455361) (xy 417.780808 -178.508149)
			(xy 417.746584 -178.55624) (xy 417.726368 -178.577748) (xy 417.720198 -178.584562) (xy 417.712776 -178.601364)
			(xy 417.71189 -178.610514) (xy 417.707572 -178.68646) (xy 417.712906 -178.703732) (xy 417.718748 -178.711098)
			(xy 417.73393 -178.731286) (xy 417.759435 -178.774884) (xy 417.778966 -178.821465) (xy 417.792183 -178.870216)
			(xy 417.798853 -178.920285) (xy 417.799266 -178.94554) (xy 417.798773 -178.972909) (xy 417.790963 -179.027088)
			(xy 417.775481 -179.079591) (xy 417.752645 -179.129338) (xy 417.722925 -179.175306) (xy 417.705286 -179.196238)
			(xy 417.705032 -179.196492) (xy 417.699435 -179.203571) (xy 417.693196 -179.220494) (xy 417.69284 -179.229512)
			(xy 417.69284 -179.296568) (xy 417.693204 -179.305584) (xy 417.699446 -179.322502) (xy 417.705032 -179.329588)
			(xy 417.705286 -179.329588) (xy 417.705286 -179.329842) (xy 417.722965 -179.350743) (xy 417.752688 -179.396717)
			(xy 417.77553 -179.446468) (xy 417.791022 -179.498975) (xy 417.798847 -179.553158) (xy 417.798843 -179.607902)
			(xy 417.791009 -179.662084) (xy 417.775509 -179.714588) (xy 417.752658 -179.764336) (xy 417.722929 -179.810305)
			(xy 417.705286 -179.831238) (xy 417.705032 -179.831492) (xy 417.699435 -179.838571) (xy 417.693196 -179.855494)
			(xy 417.69284 -179.864512) (xy 417.69284 -179.931568) (xy 417.693204 -179.940584) (xy 417.699446 -179.957502)
			(xy 417.705032 -179.964588) (xy 417.705286 -179.964588) (xy 417.705286 -179.964842) (xy 417.722965 -179.985743)
			(xy 417.752688 -180.031717) (xy 417.77553 -180.081468) (xy 417.791022 -180.133975) (xy 417.798847 -180.188158)
			(xy 417.798843 -180.242902) (xy 417.791009 -180.297084) (xy 417.775509 -180.349588) (xy 417.752658 -180.399336)
			(xy 417.722929 -180.445305) (xy 417.705286 -180.466238) (xy 417.705032 -180.466492) (xy 417.699435 -180.473571)
			(xy 417.693196 -180.490494) (xy 417.69284 -180.499512) (xy 417.69284 -180.566568) (xy 417.693204 -180.575584)
			(xy 417.699446 -180.592502) (xy 417.705032 -180.599588) (xy 417.705286 -180.599588) (xy 417.705286 -180.599842)
			(xy 417.722909 -180.620787) (xy 417.752624 -180.666756) (xy 417.775463 -180.7165) (xy 417.790958 -180.768998)
			(xy 417.79879 -180.823172) (xy 417.799266 -180.85054) (xy 417.798882 -180.877796) (xy 417.791119 -180.931752)
			(xy 417.775755 -180.984054) (xy 417.753105 -181.033637) (xy 417.723629 -181.079492) (xy 417.687927 -181.120685)
			(xy 417.646726 -181.156378) (xy 417.600865 -181.185845) (xy 417.551277 -181.208484) (xy 417.498972 -181.223836)
			(xy 417.445014 -181.231588) (xy 417.417758 -181.232048) (xy 417.389811 -181.231583) (xy 417.334518 -181.223411)
			(xy 417.281008 -181.207262) (xy 417.230426 -181.183481) (xy 417.183852 -181.152578) (xy 417.162742 -181.134258)
			(xy 417.162488 -181.134258) (xy 417.155531 -181.128491) (xy 417.138742 -181.121846) (xy 417.129722 -181.121304)
			(xy 417.053522 -181.120034) (xy 417.035996 -181.12613) (xy 417.029138 -181.132226) (xy 417.008385 -181.149181)
			(xy 416.96302 -181.17771) (xy 416.91411 -181.199611) (xy 416.862617 -181.214454) (xy 416.809553 -181.221946)
			(xy 416.782758 -181.222396) (xy 416.755389 -181.221897) (xy 416.701211 -181.214087) (xy 416.648708 -181.198606)
			(xy 416.598961 -181.175771) (xy 416.552993 -181.146054) (xy 416.53206 -181.128416) (xy 416.531806 -181.128162)
			(xy 416.524725 -181.122568) (xy 416.507804 -181.116327) (xy 416.498786 -181.11597) (xy 416.43173 -181.11597)
			(xy 416.422715 -181.116348) (xy 416.405799 -181.122582) (xy 416.39871 -181.128162) (xy 416.39871 -181.128416)
			(xy 416.398456 -181.128416) (xy 416.377516 -181.146045) (xy 416.331545 -181.175758) (xy 416.281799 -181.198595)
			(xy 416.229301 -181.214089) (xy 416.175127 -181.22192) (xy 416.147758 -181.222396) (xy 416.120505 -181.221961)
			(xy 416.066555 -181.214199) (xy 416.014259 -181.198838) (xy 415.96468 -181.176191) (xy 415.91883 -181.146719)
			(xy 415.87764 -181.111022) (xy 415.841949 -181.069827) (xy 415.812483 -181.023972) (xy 415.789843 -180.974391)
			(xy 415.77449 -180.922092) (xy 415.766735 -180.868141) (xy 415.76625 -180.840888) (xy 413.796049 -180.840888)
			(xy 413.796226 -180.851048) (xy 413.795767 -180.8783) (xy 413.788004 -180.932247) (xy 413.772644 -180.984541)
			(xy 413.749999 -181.034118) (xy 413.720529 -181.079967) (xy 413.684835 -181.121156) (xy 413.643643 -181.156847)
			(xy 413.597791 -181.186313) (xy 413.548213 -181.208955) (xy 413.495918 -181.224311) (xy 413.44197 -181.232069)
			(xy 413.414718 -181.232556) (xy 413.387348 -181.23209) (xy 413.333168 -181.224274) (xy 413.280665 -181.208785)
			(xy 413.230918 -181.185943) (xy 413.184951 -181.156218) (xy 413.16402 -181.138576) (xy 413.163766 -181.138322)
			(xy 413.156671 -181.132748) (xy 413.13976 -181.126496) (xy 413.130746 -181.12613) (xy 413.06369 -181.12613)
			(xy 413.054672 -181.126476) (xy 413.037755 -181.13273) (xy 413.03067 -181.138322) (xy 413.03067 -181.138576)
			(xy 413.030416 -181.138576) (xy 413.009486 -181.156217) (xy 412.963513 -181.18593) (xy 412.913765 -181.208766)
			(xy 412.861264 -181.224256) (xy 412.807087 -181.232083) (xy 412.779718 -181.232556) (xy 412.752469 -181.232005)
			(xy 412.698527 -181.224252) (xy 412.646236 -181.208902) (xy 412.596662 -181.186266) (xy 412.550814 -181.156807)
			(xy 412.509625 -181.121122) (xy 412.473933 -181.079939) (xy 412.444465 -181.034096) (xy 412.421821 -180.984526)
			(xy 412.406462 -180.932238) (xy 412.3987 -180.878297) (xy 412.39821 -180.851048) (xy 409.374857 -180.851048)
			(xy 409.374848 -180.859176) (xy 409.377134 -180.928264) (xy 409.377908 -180.937857) (xy 409.385594 -180.955482)
			(xy 409.39212 -180.962554) (xy 409.412923 -180.98415) (xy 409.448177 -181.032653) (xy 409.475406 -181.086074)
			(xy 409.49394 -181.143099) (xy 409.503322 -181.202321) (xy 409.50388 -181.232302) (xy 409.50342 -181.259673)
			(xy 409.495601 -181.313852) (xy 409.480111 -181.366355) (xy 409.457268 -181.416102) (xy 409.427542 -181.462069)
			(xy 409.4099 -181.483) (xy 409.409646 -181.483254) (xy 409.404066 -181.490345) (xy 409.397817 -181.507259)
			(xy 409.397454 -181.516274) (xy 409.397454 -181.58333) (xy 409.397785 -181.59235) (xy 409.404049 -181.609267)
			(xy 409.409646 -181.61635) (xy 409.4099 -181.61635) (xy 409.4099 -181.616604) (xy 409.427542 -181.637536)
			(xy 409.457264 -181.683504) (xy 409.480108 -181.733251) (xy 409.495603 -181.785753) (xy 409.503431 -181.839931)
			(xy 409.50343 -181.894672) (xy 409.495602 -181.94885) (xy 409.480107 -182.001352) (xy 409.457263 -182.051098)
			(xy 409.42754 -182.097067) (xy 409.4099 -182.118) (xy 409.409646 -182.118254) (xy 409.404066 -182.125345)
			(xy 409.397817 -182.142259) (xy 409.397454 -182.151274) (xy 409.397454 -182.21833) (xy 409.397785 -182.22735)
			(xy 409.404049 -182.244267) (xy 409.409646 -182.25135) (xy 409.4099 -182.25135) (xy 409.4099 -182.251604)
			(xy 409.427542 -182.272536) (xy 409.457264 -182.318504) (xy 409.480108 -182.368251) (xy 409.495603 -182.420753)
			(xy 409.503431 -182.474931) (xy 409.50343 -182.529672) (xy 409.495602 -182.58385) (xy 409.480107 -182.636352)
			(xy 409.457263 -182.686098) (xy 409.42754 -182.732067) (xy 409.4099 -182.753) (xy 409.409646 -182.753254)
			(xy 409.404066 -182.760345) (xy 409.397817 -182.777259) (xy 409.397454 -182.786274) (xy 409.397454 -182.85333)
			(xy 409.397785 -182.86235) (xy 409.404049 -182.879267) (xy 409.409646 -182.88635) (xy 409.4099 -182.88635)
			(xy 409.4099 -182.886604) (xy 409.427554 -182.907524) (xy 409.457264 -182.9535) (xy 409.480097 -183.003251)
			(xy 409.495584 -183.055754) (xy 409.503408 -183.109932) (xy 409.50388 -183.137302) (xy 409.503376 -183.16622)
			(xy 409.494639 -183.223394) (xy 409.477365 -183.278591) (xy 409.451952 -183.330545) (xy 409.418982 -183.378065)
			(xy 409.399486 -183.39943) (xy 409.393136 -183.406034) (xy 409.386024 -183.422798) (xy 409.382976 -183.498998)
			(xy 409.38293 -183.508103) (xy 409.388546 -183.525413) (xy 409.393898 -183.53278) (xy 409.394152 -183.533034)
			(xy 409.410035 -183.553429) (xy 409.436709 -183.597709) (xy 409.457164 -183.645184) (xy 409.471023 -183.694985)
			(xy 409.478034 -183.746201) (xy 409.47848 -183.772048) (xy 409.478067 -183.799302) (xy 409.470303 -183.853253)
			(xy 409.45494 -183.905551) (xy 409.432292 -183.955131) (xy 409.402818 -184.000982) (xy 409.367119 -184.042172)
			(xy 409.325921 -184.077863) (xy 409.280064 -184.107328) (xy 409.23048 -184.129967) (xy 409.178179 -184.145319)
			(xy 409.124226 -184.153072) (xy 409.096972 -184.153556) (xy 409.067496 -184.152983) (xy 409.009243 -184.143924)
			(xy 408.953078 -184.126009) (xy 408.900339 -184.099667) (xy 408.85228 -184.065524) (xy 408.83078 -184.045352)
			(xy 408.823452 -184.038809) (xy 408.805286 -184.03137) (xy 408.795474 -184.030874) (xy 408.742134 -184.030874)
			(xy 408.735276 -184.03824) (xy 408.728728 -184.045564) (xy 408.721291 -184.063733) (xy 408.720798 -184.073546)
			(xy 408.720798 -184.10555) (xy 408.721268 -184.115366) (xy 408.728724 -184.13353) (xy 408.735276 -184.140856)
			(xy 408.755433 -184.16237) (xy 408.789579 -184.210426) (xy 408.815928 -184.263162) (xy 408.833853 -184.319323)
			(xy 408.842928 -184.377572) (xy 408.84348 -184.407048) (xy 408.843067 -184.434302) (xy 408.835303 -184.488253)
			(xy 408.81994 -184.540551) (xy 408.797292 -184.590131) (xy 408.767818 -184.635982) (xy 408.732119 -184.677172)
			(xy 408.690921 -184.712863) (xy 408.645064 -184.742328) (xy 408.59548 -184.764967) (xy 408.543179 -184.780319)
			(xy 408.489226 -184.788072) (xy 408.461972 -184.788556) (xy 408.432496 -184.787983) (xy 408.374243 -184.778924)
			(xy 408.318078 -184.761009) (xy 408.265339 -184.734667) (xy 408.21728 -184.700524) (xy 408.19578 -184.680352)
			(xy 408.188452 -184.673809) (xy 408.170286 -184.66637) (xy 408.160474 -184.665874) (xy 408.107134 -184.665874)
			(xy 408.100276 -184.67324) (xy 408.093728 -184.680564) (xy 408.086291 -184.698733) (xy 408.085798 -184.708546)
			(xy 408.085798 -184.74055) (xy 408.086268 -184.750366) (xy 408.093724 -184.76853) (xy 408.100276 -184.775856)
			(xy 408.120433 -184.79737) (xy 408.154579 -184.845426) (xy 408.180928 -184.898162) (xy 408.198853 -184.954323)
			(xy 408.207928 -185.012572) (xy 408.20848 -185.042048) (xy 408.207994 -185.069299) (xy 408.200238 -185.123247)
			(xy 408.184883 -185.175542) (xy 408.162241 -185.225119) (xy 408.132775 -185.270969) (xy 408.097084 -185.31216)
			(xy 408.055893 -185.347851) (xy 408.010043 -185.377317) (xy 407.960466 -185.399959) (xy 407.908171 -185.415314)
			(xy 407.854223 -185.42307) (xy 407.799721 -185.42307) (xy 407.745773 -185.415314) (xy 407.693478 -185.399959)
			(xy 407.643901 -185.377317) (xy 407.598051 -185.347851) (xy 407.55686 -185.31216) (xy 407.521169 -185.270969)
			(xy 407.491703 -185.225119) (xy 407.469061 -185.175542) (xy 407.453706 -185.123247) (xy 407.44595 -185.069299)
			(xy 407.445464 -185.042048) (xy 405.431845 -185.042048) (xy 405.431843 -185.069409) (xy 405.424009 -185.123591)
			(xy 405.408506 -185.176096) (xy 405.385655 -185.225844) (xy 405.355924 -185.271813) (xy 405.33828 -185.292746)
			(xy 405.338026 -185.293) (xy 405.332425 -185.300076) (xy 405.326189 -185.317001) (xy 405.325834 -185.32602)
			(xy 405.325834 -185.393076) (xy 405.326195 -185.402093) (xy 405.332439 -185.41901) (xy 405.338026 -185.426096)
			(xy 405.33828 -185.426096) (xy 405.33828 -185.42635) (xy 405.355967 -185.447245) (xy 405.38569 -185.493219)
			(xy 405.408532 -185.542972) (xy 405.424024 -185.59548) (xy 405.431848 -185.649663) (xy 405.431843 -185.704409)
			(xy 405.424009 -185.758591) (xy 405.408506 -185.811096) (xy 405.385655 -185.860844) (xy 405.355924 -185.906813)
			(xy 405.33828 -185.927746) (xy 405.338026 -185.928) (xy 405.332425 -185.935076) (xy 405.326189 -185.952001)
			(xy 405.325834 -185.96102) (xy 405.325834 -186.028076) (xy 405.326195 -186.037093) (xy 405.332439 -186.05401)
			(xy 405.338026 -186.061096) (xy 405.33828 -186.061096) (xy 405.33828 -186.06135) (xy 405.355967 -186.082245)
			(xy 405.38569 -186.128219) (xy 405.408532 -186.177972) (xy 405.424024 -186.23048) (xy 405.431848 -186.284663)
			(xy 405.431843 -186.339409) (xy 405.424009 -186.393591) (xy 405.408506 -186.446096) (xy 405.385655 -186.495844)
			(xy 405.355924 -186.541813) (xy 405.33828 -186.562746) (xy 405.338026 -186.563) (xy 405.332425 -186.570076)
			(xy 405.326189 -186.587001) (xy 405.325834 -186.59602) (xy 405.325834 -186.663076) (xy 405.326195 -186.672093)
			(xy 405.332439 -186.68901) (xy 405.338026 -186.696096) (xy 405.33828 -186.696096) (xy 405.33828 -186.69635)
			(xy 405.355906 -186.717293) (xy 405.38562 -186.763262) (xy 405.408459 -186.813007) (xy 405.423953 -186.865505)
			(xy 405.431785 -186.91968) (xy 405.43226 -186.947048) (xy 405.431867 -186.974303) (xy 405.424102 -187.028256)
			(xy 405.408739 -187.080556) (xy 405.386089 -187.130136) (xy 405.356613 -187.175989) (xy 405.320912 -187.21718)
			(xy 405.279712 -187.25287) (xy 405.233852 -187.282335) (xy 405.184265 -187.304972) (xy 405.131962 -187.320323)
			(xy 405.078007 -187.328074) (xy 405.050752 -187.328556) (xy 405.023382 -187.32807) (xy 404.969204 -187.320259)
			(xy 404.9167 -187.304775) (xy 404.866953 -187.281937) (xy 404.820986 -187.252216) (xy 404.800054 -187.234576)
			(xy 404.7998 -187.234322) (xy 404.792724 -187.22872) (xy 404.775799 -187.222485) (xy 404.76678 -187.22213)
			(xy 404.699724 -187.22213) (xy 404.690708 -187.222492) (xy 404.67379 -187.228736) (xy 404.666704 -187.234322)
			(xy 404.666704 -187.234576) (xy 404.66645 -187.234576) (xy 404.645507 -187.252201) (xy 404.599537 -187.281916)
			(xy 404.549793 -187.304755) (xy 404.497294 -187.320249) (xy 404.44312 -187.328081) (xy 404.415752 -187.328556)
			(xy 404.388502 -187.328067) (xy 404.334557 -187.320305) (xy 404.282265 -187.304946) (xy 404.232691 -187.282303)
			(xy 404.186843 -187.252836) (xy 404.145654 -187.217146) (xy 404.109964 -187.175957) (xy 404.080497 -187.130109)
			(xy 404.057854 -187.080535) (xy 404.042495 -187.028243) (xy 404.034733 -186.974298) (xy 404.034244 -186.947048)
			(xy 400.3675 -186.947048) (xy 400.3675 -188.718444) (xy 400.367836 -188.727079) (xy 400.373612 -188.743357)
			(xy 400.384461 -188.756796) (xy 400.39163 -188.761624) (xy 400.465036 -188.80709) (xy 400.472498 -188.811296)
			(xy 400.489231 -188.814918) (xy 400.506227 -188.81285) (xy 400.514058 -188.809376) (xy 400.514566 -188.809376)
			(xy 400.541096 -188.796751) (xy 400.597071 -188.778904) (xy 400.655117 -188.769827) (xy 400.684492 -188.769244)
			(xy 400.711741 -188.769785) (xy 400.765684 -188.777539) (xy 400.817975 -188.792891) (xy 400.867549 -188.815528)
			(xy 400.913397 -188.844989) (xy 400.954586 -188.880674) (xy 400.990278 -188.921858) (xy 401.019745 -188.967702)
			(xy 401.042389 -189.017273) (xy 401.057749 -189.069561) (xy 401.065511 -189.123503) (xy 401.066 -189.150752)
			(xy 401.065529 -189.178086) (xy 401.057721 -189.232193) (xy 401.042271 -189.284632) (xy 401.019497 -189.334329)
			(xy 400.989863 -189.380268) (xy 400.972274 -189.401196) (xy 400.97202 -189.40145) (xy 400.966099 -189.408938)
			(xy 400.959835 -189.426956) (xy 400.959828 -189.436502) (xy 400.962114 -189.50559) (xy 400.962854 -189.515188)
			(xy 400.970562 -189.532813) (xy 400.9771 -189.53988) (xy 400.997912 -189.561467) (xy 401.033165 -189.609972)
			(xy 401.060393 -189.663396) (xy 401.078925 -189.720423) (xy 401.088304 -189.779647) (xy 401.08886 -189.809628)
			(xy 401.08842 -189.836999) (xy 401.080597 -189.89118) (xy 401.065103 -189.943684) (xy 401.042255 -189.99343)
			(xy 401.012524 -190.039395) (xy 400.99488 -190.060326) (xy 400.994626 -190.06058) (xy 400.989033 -190.067662)
			(xy 400.982792 -190.084583) (xy 400.982434 -190.0936) (xy 400.982434 -190.160656) (xy 400.982805 -190.169672)
			(xy 400.989042 -190.186589) (xy 400.994626 -190.193676) (xy 400.99488 -190.193676) (xy 400.99488 -190.19393)
			(xy 401.012548 -190.214841) (xy 401.042271 -190.260812) (xy 401.065114 -190.310562) (xy 401.080608 -190.363068)
			(xy 401.088434 -190.417249) (xy 401.088431 -190.471993) (xy 401.080599 -190.526173) (xy 401.065099 -190.578677)
			(xy 401.042251 -190.628425) (xy 401.012522 -190.674393) (xy 400.99488 -190.695326) (xy 400.994626 -190.69558)
			(xy 400.989033 -190.702662) (xy 400.982792 -190.719583) (xy 400.982434 -190.7286) (xy 400.982434 -190.795656)
			(xy 400.982805 -190.804672) (xy 400.989042 -190.821589) (xy 400.994626 -190.828676) (xy 400.99488 -190.828676)
			(xy 400.99488 -190.82893) (xy 401.012548 -190.849841) (xy 401.042271 -190.895812) (xy 401.065114 -190.945562)
			(xy 401.080608 -190.998068) (xy 401.088434 -191.052249) (xy 401.088431 -191.106993) (xy 401.080599 -191.161173)
			(xy 401.065099 -191.213677) (xy 401.042251 -191.263425) (xy 401.012522 -191.309393) (xy 400.99488 -191.330326)
			(xy 400.994626 -191.33058) (xy 400.989033 -191.337662) (xy 400.982792 -191.354583) (xy 400.982434 -191.3636)
			(xy 400.982434 -191.430656) (xy 400.982805 -191.439672) (xy 400.989042 -191.456589) (xy 400.994626 -191.463676)
			(xy 400.99488 -191.463676) (xy 400.99488 -191.46393) (xy 401.012497 -191.48488) (xy 401.042213 -191.530848)
			(xy 401.065053 -191.580591) (xy 401.080549 -191.633087) (xy 401.088383 -191.68726) (xy 401.08886 -191.714628)
			(xy 401.088471 -191.741884) (xy 401.080709 -191.79584) (xy 401.065347 -191.848142) (xy 401.042698 -191.897726)
			(xy 401.013222 -191.943581) (xy 400.977521 -191.984775) (xy 400.93632 -192.020468) (xy 400.890459 -192.049934)
			(xy 400.840871 -192.072574) (xy 400.788566 -192.087925) (xy 400.734608 -192.095676) (xy 400.707352 -192.096136)
			(xy 400.680648 -192.095706) (xy 400.627762 -192.088251) (xy 400.576432 -192.073494) (xy 400.527662 -192.051723)
			(xy 400.482405 -192.023363) (xy 400.441545 -191.98897) (xy 400.42338 -191.96939) (xy 400.416144 -191.962107)
			(xy 400.397544 -191.953459) (xy 400.387312 -191.952626) (xy 400.332956 -191.950594) (xy 400.324066 -191.959738)
			(xy 400.31713 -191.967446) (xy 400.309518 -191.98671) (xy 400.309334 -191.997076) (xy 400.310096 -192.029334)
			(xy 400.310973 -192.039653) (xy 400.319734 -192.058394) (xy 400.327114 -192.065656) (xy 400.346701 -192.083813)
			(xy 400.381094 -192.124674) (xy 400.409451 -192.169933) (xy 400.431218 -192.218705) (xy 400.445968 -192.270036)
			(xy 400.453414 -192.322924) (xy 400.45386 -192.349628) (xy 400.453471 -192.376884) (xy 400.445709 -192.43084)
			(xy 400.430347 -192.483142) (xy 400.407698 -192.532726) (xy 400.378222 -192.578581) (xy 400.342521 -192.619775)
			(xy 400.30132 -192.655468) (xy 400.255459 -192.684934) (xy 400.205871 -192.707574) (xy 400.153566 -192.722925)
			(xy 400.099608 -192.730676) (xy 400.072352 -192.731136) (xy 400.042875 -192.730581) (xy 399.984621 -192.721518)
			(xy 399.928456 -192.7036) (xy 399.875717 -192.677254) (xy 399.827659 -192.643106) (xy 399.80616 -192.622932)
			(xy 399.798841 -192.616378) (xy 399.780668 -192.608946) (xy 399.770854 -192.608454) (xy 399.717514 -192.608454)
			(xy 399.710656 -192.61582) (xy 399.704114 -192.623148) (xy 399.696674 -192.641314) (xy 399.696178 -192.651126)
			(xy 399.696178 -192.68313) (xy 399.696664 -192.692944) (xy 399.70411 -192.711108) (xy 399.710656 -192.718436)
			(xy 399.730847 -192.739919) (xy 399.76499 -192.787983) (xy 399.791333 -192.840727) (xy 399.809249 -192.896895)
			(xy 399.818314 -192.95515) (xy 399.81886 -192.984628) (xy 399.818374 -193.011879) (xy 399.810618 -193.065827)
			(xy 399.795263 -193.118122) (xy 399.772621 -193.167699) (xy 399.743155 -193.213549) (xy 399.707464 -193.25474)
			(xy 399.666273 -193.290431) (xy 399.620423 -193.319897) (xy 399.570846 -193.342539) (xy 399.518551 -193.357894)
			(xy 399.464603 -193.36565) (xy 399.410101 -193.36565) (xy 399.356153 -193.357894) (xy 399.303858 -193.342539)
			(xy 399.254281 -193.319897) (xy 399.208431 -193.290431) (xy 399.16724 -193.25474) (xy 399.131549 -193.213549)
			(xy 399.102083 -193.167699) (xy 399.079441 -193.118122) (xy 399.064086 -193.065827) (xy 399.05633 -193.011879)
			(xy 399.055844 -192.984628) (xy 399.056316 -192.957258) (xy 399.064131 -192.903079) (xy 399.079618 -192.850575)
			(xy 399.102458 -192.800828) (xy 399.132183 -192.754861) (xy 399.149824 -192.73393) (xy 399.150078 -192.733676)
			(xy 399.15569 -192.726607) (xy 399.161919 -192.709676) (xy 399.16227 -192.700656) (xy 399.16227 -192.6336)
			(xy 399.16192 -192.624582) (xy 399.155668 -192.607665) (xy 399.150078 -192.60058) (xy 399.149824 -192.60058)
			(xy 399.149824 -192.600326) (xy 399.132187 -192.579392) (xy 399.102474 -192.53342) (xy 399.079638 -192.483673)
			(xy 399.064146 -192.431173) (xy 399.056318 -192.376997) (xy 399.055844 -192.349628) (xy 399.056294 -192.322058)
			(xy 399.064231 -192.267491) (xy 399.079943 -192.214636) (xy 399.103103 -192.164595) (xy 399.133228 -192.11841)
			(xy 399.151094 -192.097406) (xy 399.157698 -192.09004) (xy 399.164048 -192.07226) (xy 399.161508 -191.983614)
			(xy 399.153888 -191.965834) (xy 399.14703 -191.958976) (xy 399.126586 -191.937422) (xy 399.091906 -191.889194)
			(xy 399.065123 -191.836172) (xy 399.046886 -191.779639) (xy 399.037635 -191.720961) (xy 399.037048 -191.69126)
			(xy 399.037048 -191.690752) (xy 399.037533 -191.663382) (xy 399.045344 -191.609204) (xy 399.060828 -191.5567)
			(xy 399.083666 -191.506953) (xy 399.113388 -191.460986) (xy 399.131028 -191.440054) (xy 399.131282 -191.4398)
			(xy 399.136872 -191.432716) (xy 399.143117 -191.415797) (xy 399.143474 -191.40678) (xy 399.143474 -191.339724)
			(xy 399.143111 -191.330708) (xy 399.136868 -191.31379) (xy 399.131282 -191.306704) (xy 399.131028 -191.306704)
			(xy 399.131028 -191.30645) (xy 399.11334 -191.285555) (xy 399.083617 -191.239581) (xy 399.060775 -191.189828)
			(xy 399.045282 -191.137321) (xy 399.037458 -191.083137) (xy 399.037463 -191.028391) (xy 399.045298 -190.974209)
			(xy 399.0608 -190.921704) (xy 399.083652 -190.871956) (xy 399.113384 -190.825987) (xy 399.131028 -190.805054)
			(xy 399.131282 -190.8048) (xy 399.136872 -190.797716) (xy 399.143117 -190.780797) (xy 399.143474 -190.77178)
			(xy 399.143474 -190.704724) (xy 399.143111 -190.695708) (xy 399.136868 -190.67879) (xy 399.131282 -190.671704)
			(xy 399.131028 -190.671704) (xy 399.131028 -190.67145) (xy 399.11334 -190.650555) (xy 399.083617 -190.604581)
			(xy 399.060775 -190.554828) (xy 399.045282 -190.502321) (xy 399.037458 -190.448137) (xy 399.037463 -190.393391)
			(xy 399.045298 -190.339209) (xy 399.0608 -190.286704) (xy 399.083652 -190.236956) (xy 399.113384 -190.190987)
			(xy 399.131028 -190.170054) (xy 399.131282 -190.1698) (xy 399.136872 -190.162716) (xy 399.143117 -190.145797)
			(xy 399.143474 -190.13678) (xy 399.143474 -190.069724) (xy 399.143111 -190.060708) (xy 399.136868 -190.04379)
			(xy 399.131282 -190.036704) (xy 399.131028 -190.036704) (xy 399.131028 -190.03645) (xy 399.113403 -190.015506)
			(xy 399.083688 -189.969537) (xy 399.060849 -189.919793) (xy 399.045355 -189.867294) (xy 399.037524 -189.81312)
			(xy 399.037048 -189.785752) (xy 399.037518 -189.758618) (xy 399.045208 -189.704897) (xy 399.06044 -189.65281)
			(xy 399.082905 -189.603411) (xy 399.11215 -189.557697) (xy 399.129504 -189.536832) (xy 399.135151 -189.529631)
			(xy 399.141403 -189.512449) (xy 399.141696 -189.503304) (xy 399.141442 -189.436502) (xy 399.140947 -189.427447)
			(xy 399.134447 -189.410531) (xy 399.128742 -189.403482) (xy 399.128488 -189.403228) (xy 399.110572 -189.382222)
			(xy 399.080381 -189.335999) (xy 399.057169 -189.285906) (xy 399.041422 -189.23299) (xy 399.033469 -189.178357)
			(xy 399.032984 -189.150752) (xy 397.05026 -189.150752) (xy 397.049771 -189.177719) (xy 397.042137 -189.23111)
			(xy 397.02707 -189.282896) (xy 397.00487 -189.33205) (xy 396.975977 -189.377592) (xy 396.95882 -189.398402)
			(xy 396.952724 -189.405768) (xy 396.94993 -189.413388) (xy 396.948368 -189.417797) (xy 396.946704 -189.427)
			(xy 396.946628 -189.431676) (xy 396.947136 -189.465712) (xy 396.947136 -189.46622) (xy 396.94739 -189.498732)
			(xy 396.947513 -189.503421) (xy 396.949305 -189.512626) (xy 396.950946 -189.51702) (xy 396.953994 -189.524894)
			(xy 396.960344 -189.532006) (xy 396.978429 -189.553084) (xy 397.008941 -189.599489) (xy 397.032406 -189.649825)
			(xy 397.048327 -189.703032) (xy 397.056369 -189.757983) (xy 397.056864 -189.785752) (xy 397.056389 -189.813121)
			(xy 397.048557 -189.867295) (xy 397.033063 -189.919793) (xy 397.010225 -189.969538) (xy 396.980511 -190.015508)
			(xy 396.962884 -190.03645) (xy 396.956788 -190.043562) (xy 396.95374 -190.051944) (xy 396.952223 -190.056233)
			(xy 396.950568 -190.065177) (xy 396.950438 -190.069724) (xy 396.950438 -190.13678) (xy 396.950563 -190.141327)
			(xy 396.952226 -190.15027) (xy 396.95374 -190.15456) (xy 396.956788 -190.162942) (xy 396.962884 -190.170054)
			(xy 396.980528 -190.190987) (xy 397.010258 -190.236956) (xy 397.03311 -190.286704) (xy 397.048612 -190.339209)
			(xy 397.056446 -190.393391) (xy 397.056451 -190.448137) (xy 397.048627 -190.50232) (xy 397.033135 -190.554828)
			(xy 397.010293 -190.60458) (xy 396.980571 -190.650555) (xy 396.962884 -190.67145) (xy 396.956788 -190.678562)
			(xy 396.95374 -190.686944) (xy 396.952223 -190.691233) (xy 396.950568 -190.700177) (xy 396.950438 -190.704724)
			(xy 396.950438 -190.77178) (xy 396.950563 -190.776327) (xy 396.952226 -190.78527) (xy 396.95374 -190.78956)
			(xy 396.956788 -190.797942) (xy 396.962884 -190.805054) (xy 396.980528 -190.825987) (xy 397.010258 -190.871956)
			(xy 397.03311 -190.921704) (xy 397.048612 -190.974209) (xy 397.056446 -191.028391) (xy 397.056451 -191.083137)
			(xy 397.048627 -191.13732) (xy 397.033135 -191.189828) (xy 397.010293 -191.23958) (xy 396.980571 -191.285555)
			(xy 396.962884 -191.30645) (xy 396.956788 -191.313562) (xy 396.95374 -191.321944) (xy 396.952223 -191.326233)
			(xy 396.950568 -191.335177) (xy 396.950438 -191.339724) (xy 396.950438 -191.40678) (xy 396.950563 -191.411327)
			(xy 396.952226 -191.42027) (xy 396.95374 -191.42456) (xy 396.956788 -191.432942) (xy 396.962884 -191.440054)
			(xy 396.980524 -191.460986) (xy 397.010244 -191.506953) (xy 397.033081 -191.556701) (xy 397.048565 -191.609204)
			(xy 397.056376 -191.663382) (xy 397.056864 -191.690752) (xy 397.056347 -191.719492) (xy 397.04773 -191.776323)
			(xy 397.030684 -191.831218) (xy 397.005594 -191.882933) (xy 396.97303 -191.930299) (xy 396.95374 -191.95161)
			(xy 396.947136 -191.958722) (xy 396.943834 -191.967104) (xy 396.942079 -191.971671) (xy 396.940161 -191.981263)
			(xy 396.940024 -191.986154) (xy 396.940024 -192.020444) (xy 396.940024 -192.020952) (xy 396.93977 -192.055242)
			(xy 396.939861 -192.060261) (xy 396.941779 -192.070114) (xy 396.94358 -192.0748) (xy 396.946882 -192.082928)
			(xy 396.953486 -192.09004) (xy 396.972516 -192.111343) (xy 397.004685 -192.158542) (xy 397.029464 -192.210007)
			(xy 397.046301 -192.264588) (xy 397.05482 -192.321068) (xy 397.05534 -192.349628) (xy 397.054866 -192.376997)
			(xy 397.047038 -192.431172) (xy 397.031546 -192.483672) (xy 397.008708 -192.533419) (xy 396.978994 -192.57939)
			(xy 396.96136 -192.600326) (xy 396.955264 -192.607438) (xy 396.952216 -192.61582) (xy 396.950697 -192.620108)
			(xy 396.949039 -192.629052) (xy 396.948914 -192.6336) (xy 396.948914 -192.700656) (xy 396.949037 -192.705204)
			(xy 396.950695 -192.714148) (xy 396.952216 -192.718436) (xy 396.955264 -192.726818) (xy 396.96136 -192.73393)
			(xy 396.978999 -192.754862) (xy 397.008721 -192.800829) (xy 397.031563 -192.850574) (xy 397.047057 -192.903075)
			(xy 397.054882 -192.957252) (xy 397.054879 -193.011991) (xy 397.047048 -193.066166) (xy 397.031549 -193.118665)
			(xy 397.008701 -193.168408) (xy 396.978974 -193.214371) (xy 396.96136 -193.235326) (xy 396.955264 -193.242438)
			(xy 396.952216 -193.25082) (xy 396.950697 -193.255108) (xy 396.949039 -193.264052) (xy 396.948914 -193.2686)
			(xy 396.948914 -193.335656) (xy 396.949037 -193.340204) (xy 396.950695 -193.349148) (xy 396.952216 -193.353436)
			(xy 396.955264 -193.361818) (xy 396.96136 -193.36893) (xy 396.978999 -193.389862) (xy 397.008721 -193.435829)
			(xy 397.031563 -193.485574) (xy 397.047057 -193.538075) (xy 397.054882 -193.592252) (xy 397.054879 -193.646991)
			(xy 397.047048 -193.701166) (xy 397.031549 -193.753665) (xy 397.008701 -193.803408) (xy 396.978974 -193.849371)
			(xy 396.96136 -193.870326) (xy 396.955264 -193.877438) (xy 396.952216 -193.88582) (xy 396.950697 -193.890108)
			(xy 396.949039 -193.899052) (xy 396.948914 -193.9036) (xy 396.948914 -193.970656) (xy 396.949037 -193.975204)
			(xy 396.950695 -193.984148) (xy 396.952216 -193.988436) (xy 396.955264 -193.996818) (xy 396.96136 -194.00393)
			(xy 396.978999 -194.024862) (xy 397.008721 -194.070829) (xy 397.031563 -194.120574) (xy 397.047057 -194.173075)
			(xy 397.054882 -194.227252) (xy 397.054879 -194.281991) (xy 397.047048 -194.336166) (xy 397.031549 -194.388665)
			(xy 397.008701 -194.438408) (xy 396.978974 -194.484371) (xy 396.96136 -194.505326) (xy 396.955264 -194.512438)
			(xy 396.952216 -194.52082) (xy 396.950697 -194.525108) (xy 396.949039 -194.534052) (xy 396.948914 -194.5386)
			(xy 396.948914 -194.605656) (xy 396.949037 -194.610204) (xy 396.950695 -194.619148) (xy 396.952216 -194.623436)
			(xy 396.955264 -194.631818) (xy 396.96136 -194.63893) (xy 396.978999 -194.659862) (xy 397.008721 -194.705829)
			(xy 397.031563 -194.755574) (xy 397.047057 -194.808075) (xy 397.054882 -194.862252) (xy 397.054879 -194.916991)
			(xy 397.047048 -194.971166) (xy 397.031549 -195.023665) (xy 397.008701 -195.073408) (xy 396.978974 -195.119371)
			(xy 396.96136 -195.140326) (xy 396.955264 -195.147438) (xy 396.952216 -195.15582) (xy 396.950697 -195.160108)
			(xy 396.949039 -195.169052) (xy 396.948914 -195.1736) (xy 396.948914 -195.240656) (xy 396.949037 -195.245204)
			(xy 396.950695 -195.254148) (xy 396.952216 -195.258436) (xy 396.955264 -195.266818) (xy 396.96136 -195.27393)
			(xy 396.977497 -195.293031) (xy 397.005157 -195.334688) (xy 397.027139 -195.379601) (xy 397.043066 -195.427001)
			(xy 397.052664 -195.476075) (xy 397.054578 -195.501006) (xy 397.054578 -195.501514) (xy 397.055315 -195.508705)
			(xy 397.060355 -195.522249) (xy 397.064484 -195.528184) (xy 397.064484 -195.528438) (xy 397.068996 -195.534156)
			(xy 397.08061 -195.542935) (xy 397.087344 -195.54571) (xy 397.173704 -195.578476) (xy 397.180816 -195.580508)
			(xy 397.18922 -195.582014) (xy 397.206164 -195.580004) (xy 397.221525 -195.572575) (xy 397.227806 -195.566792)
			(xy 397.977614 -194.816984) (xy 397.977868 -194.81673) (xy 398.00275 -194.792545) (xy 398.057409 -194.749796)
			(xy 398.116885 -194.714053) (xy 398.180286 -194.685852) (xy 398.213326 -194.675252) (xy 398.219422 -194.673474)
			(xy 398.224756 -194.670426) (xy 398.234662 -194.662552) (xy 398.343882 -194.553332) (xy 398.351283 -194.546495)
			(xy 398.369882 -194.538785) (xy 398.37995 -194.538346) (xy 400.242532 -194.538346) (xy 400.252184 -194.53733)
			(xy 400.259425 -194.535697) (xy 400.272585 -194.528846) (xy 400.278092 -194.523868) (xy 412.897066 -181.904894)
			(xy 412.904468 -181.898058) (xy 412.923066 -181.890349) (xy 412.933134 -181.889908) (xy 412.955232 -181.889908)
			(xy 412.966154 -181.887114) (xy 412.971742 -181.88432) (xy 413.003794 -181.868736) (xy 413.070921 -181.844787)
			(xy 413.1056 -181.836568) (xy 413.135885 -181.830332) (xy 413.197364 -181.823713) (xy 413.228282 -181.82336)
			(xy 420.671498 -181.82336) (xy 420.679626 -181.822852) (xy 420.687482 -181.821231) (xy 420.701721 -181.813867)
			(xy 420.707566 -181.808374) (xy 428.877984 -173.637956) (xy 428.884825 -173.630556) (xy 428.892546 -173.611958)
			(xy 428.89297 -173.601888) (xy 428.89297 -157.666944) (xy 428.892536 -157.656879) (xy 428.884804 -157.638292)
			(xy 428.877984 -157.630876) (xy 427.489874 -156.242766) (xy 427.483025 -156.235369) (xy 427.475291 -156.21677)
			(xy 427.474888 -156.206698) (xy 427.474888 -144.29359) (xy 427.474463 -144.283521) (xy 427.466744 -144.26492)
			(xy 427.459902 -144.257522) (xy 415.473896 -132.271262) (xy 415.4665 -132.264409) (xy 415.447902 -132.256666)
			(xy 415.437828 -132.256276) (xy 410.661866 -132.256276) (xy 410.651798 -132.256705) (xy 410.6332 -132.264425)
			(xy 410.625798 -132.271262) (xy 409.762452 -133.134608) (xy 409.755594 -133.161024) (xy 409.75915 -133.173978)
			(xy 409.765323 -133.198341) (xy 409.771949 -133.248162) (xy 409.772358 -133.273292) (xy 409.772358 -133.2738)
			(xy 409.771837 -133.302539) (xy 409.763214 -133.359366) (xy 409.746162 -133.414256) (xy 409.721068 -133.465966)
			(xy 409.6885 -133.513327) (xy 409.669234 -133.534658) (xy 409.66263 -133.541516) (xy 409.655518 -133.55955)
			(xy 409.655518 -133.64845) (xy 409.66263 -133.666484) (xy 409.669234 -133.673342) (xy 409.688502 -133.69467)
			(xy 409.721063 -133.742034) (xy 409.74615 -133.793746) (xy 409.763198 -133.848636) (xy 409.771819 -133.905462)
			(xy 409.772358 -133.9342) (xy 409.771915 -133.960631) (xy 409.764632 -134.012989) (xy 409.750191 -134.063841)
			(xy 409.728868 -134.112212) (xy 409.701072 -134.157176) (xy 409.667335 -134.197873) (xy 409.628303 -134.233523)
			(xy 409.584724 -134.263444) (xy 409.537431 -134.287063) (xy 409.512516 -134.295896) (xy 409.497022 -134.300976)
			(xy 409.477972 -134.327392) (xy 409.477972 -134.628128) (xy 409.478703 -134.640372) (xy 409.489991 -134.662108)
			(xy 409.499562 -134.669784) (xy 409.567888 -134.717536) (xy 409.578284 -134.723904) (xy 409.60242 -134.727077)
			(xy 409.614116 -134.723632) (xy 409.61437 -134.723632) (xy 409.645924 -134.712841) (xy 409.711585 -134.701211)
			(xy 409.744926 -134.700518) (xy 409.772174 -134.701006) (xy 409.826115 -134.708765) (xy 409.878403 -134.724121)
			(xy 409.927974 -134.746762) (xy 409.973818 -134.776227) (xy 410.015002 -134.811916) (xy 410.050688 -134.853103)
			(xy 410.08015 -134.898949) (xy 410.102788 -134.948521) (xy 410.118141 -135.00081) (xy 410.125896 -135.054752)
			(xy 410.125896 -135.109248) (xy 410.118141 -135.16319) (xy 410.102788 -135.215479) (xy 410.08015 -135.265051)
			(xy 410.050688 -135.310897) (xy 410.015002 -135.352084) (xy 409.973818 -135.387773) (xy 409.927974 -135.417238)
			(xy 409.878403 -135.439879) (xy 409.826115 -135.455235) (xy 409.772174 -135.462994) (xy 409.744926 -135.463534)
			(xy 409.711654 -135.462764) (xy 409.646132 -135.451137) (xy 409.614624 -135.44042) (xy 409.614116 -135.44042)
			(xy 409.602426 -135.436942) (xy 409.578285 -135.440137) (xy 409.567888 -135.446516) (xy 409.499562 -135.494268)
			(xy 409.489928 -135.501888) (xy 409.47864 -135.523659) (xy 409.477972 -135.535924) (xy 409.477972 -136.38657)
			(xy 409.478476 -136.396621) (xy 409.486194 -136.415185) (xy 409.492958 -136.422638) (xy 409.702254 -136.631934)
			(xy 409.719474 -136.650045) (xy 409.74721 -136.691606) (xy 409.766316 -136.737776) (xy 409.776059 -136.786783)
			(xy 409.776676 -136.811766) (xy 409.776676 -137.87628) (xy 410.808168 -137.87628) (xy 410.812239 -137.820658)
			(xy 410.824365 -137.766221) (xy 410.844288 -137.71413) (xy 410.871584 -137.665495) (xy 410.90567 -137.621352)
			(xy 410.945819 -137.582643) (xy 410.991177 -137.550192) (xy 411.040777 -137.524691) (xy 411.093561 -137.506684)
			(xy 411.148404 -137.496554) (xy 411.204138 -137.494517) (xy 411.259575 -137.500617) (xy 411.313532 -137.514723)
			(xy 411.364861 -137.536535) (xy 411.412467 -137.565589) (xy 411.455335 -137.601264) (xy 411.492552 -137.642801)
			(xy 411.523325 -137.689314) (xy 411.546997 -137.739811) (xy 411.563065 -137.793218) (xy 411.571185 -137.848394)
			(xy 411.571694 -137.87628) (xy 411.571185 -137.904166) (xy 411.563065 -137.959342) (xy 411.546997 -138.012749)
			(xy 411.523325 -138.063246) (xy 411.492552 -138.109759) (xy 411.455335 -138.151296) (xy 411.412467 -138.186971)
			(xy 411.364861 -138.216025) (xy 411.313532 -138.237837) (xy 411.259575 -138.251943) (xy 411.204138 -138.258043)
			(xy 411.148404 -138.256006) (xy 411.093561 -138.245876) (xy 411.040777 -138.227869) (xy 410.991177 -138.202368)
			(xy 410.945819 -138.169917) (xy 410.90567 -138.131208) (xy 410.871584 -138.087065) (xy 410.844288 -138.03843)
			(xy 410.824365 -137.986339) (xy 410.812239 -137.931902) (xy 410.808168 -137.87628) (xy 409.776676 -137.87628)
			(xy 409.776676 -139.47267) (xy 410.103318 -139.47267) (xy 410.107389 -139.417048) (xy 410.119515 -139.362611)
			(xy 410.139438 -139.31052) (xy 410.166734 -139.261885) (xy 410.20082 -139.217742) (xy 410.240969 -139.179033)
			(xy 410.286327 -139.146582) (xy 410.335927 -139.121081) (xy 410.388711 -139.103074) (xy 410.443554 -139.092944)
			(xy 410.499288 -139.090907) (xy 410.554725 -139.097007) (xy 410.608682 -139.111113) (xy 410.660011 -139.132925)
			(xy 410.707617 -139.161979) (xy 410.750485 -139.197654) (xy 410.787702 -139.239191) (xy 410.818475 -139.285704)
			(xy 410.842147 -139.336201) (xy 410.858215 -139.389608) (xy 410.866335 -139.444784) (xy 410.866844 -139.47267)
			(xy 410.866335 -139.500556) (xy 410.858215 -139.555732) (xy 410.842147 -139.609139) (xy 410.818475 -139.659636)
			(xy 410.787702 -139.706149) (xy 410.750485 -139.747686) (xy 410.707617 -139.783361) (xy 410.660011 -139.812415)
			(xy 410.608682 -139.834227) (xy 410.554725 -139.848333) (xy 410.499288 -139.854433) (xy 410.443554 -139.852396)
			(xy 410.388711 -139.842266) (xy 410.335927 -139.824259) (xy 410.286327 -139.798758) (xy 410.240969 -139.766307)
			(xy 410.20082 -139.727598) (xy 410.166734 -139.683455) (xy 410.139438 -139.63482) (xy 410.119515 -139.582729)
			(xy 410.107389 -139.528292) (xy 410.103318 -139.47267) (xy 409.776676 -139.47267) (xy 409.776676 -141.316456)
			(xy 410.132274 -141.316456) (xy 410.136345 -141.260834) (xy 410.148471 -141.206397) (xy 410.168394 -141.154306)
			(xy 410.19569 -141.105671) (xy 410.229776 -141.061528) (xy 410.269925 -141.022819) (xy 410.315283 -140.990368)
			(xy 410.364883 -140.964867) (xy 410.417667 -140.94686) (xy 410.47251 -140.93673) (xy 410.528244 -140.934693)
			(xy 410.583681 -140.940793) (xy 410.637638 -140.954899) (xy 410.688967 -140.976711) (xy 410.736573 -141.005765)
			(xy 410.779441 -141.04144) (xy 410.816658 -141.082977) (xy 410.847431 -141.12949) (xy 410.871103 -141.179987)
			(xy 410.887171 -141.233394) (xy 410.895291 -141.28857) (xy 410.8958 -141.316456) (xy 410.895291 -141.344342)
			(xy 410.887171 -141.399518) (xy 410.871103 -141.452925) (xy 410.847431 -141.503422) (xy 410.816658 -141.549935)
			(xy 410.779441 -141.591472) (xy 410.736573 -141.627147) (xy 410.688967 -141.656201) (xy 410.637638 -141.678013)
			(xy 410.583681 -141.692119) (xy 410.528244 -141.698219) (xy 410.47251 -141.696182) (xy 410.417667 -141.686052)
			(xy 410.364883 -141.668045) (xy 410.315283 -141.642544) (xy 410.269925 -141.610093) (xy 410.229776 -141.571384)
			(xy 410.19569 -141.527241) (xy 410.168394 -141.478606) (xy 410.148471 -141.426515) (xy 410.136345 -141.372078)
			(xy 410.132274 -141.316456) (xy 409.776676 -141.316456) (xy 409.776676 -141.35481) (xy 409.7771 -141.36488)
			(xy 409.784814 -141.383484) (xy 409.791662 -141.390878) (xy 410.91104 -142.510002) (xy 410.918441 -142.516842)
			(xy 410.937039 -142.524561) (xy 410.947108 -142.524988) (xy 415.0614 -142.524988) (xy 415.08934 -142.502128)
			(xy 415.092896 -142.484094) (xy 415.099114 -142.455607) (xy 415.119034 -142.400811) (xy 415.147058 -142.349682)
			(xy 415.182534 -142.303412) (xy 415.224635 -142.263076) (xy 415.272382 -142.229615) (xy 415.324664 -142.203806)
			(xy 415.380263 -142.18625) (xy 415.437886 -142.177356) (xy 415.467038 -142.176754) (xy 415.494303 -142.17722)
			(xy 415.548278 -142.184989) (xy 415.600597 -142.200363) (xy 415.650194 -142.223028) (xy 415.696059 -142.252524)
			(xy 415.737258 -142.288249) (xy 415.772951 -142.329475) (xy 415.802412 -142.375363) (xy 415.825039 -142.424977)
			(xy 415.840373 -142.477308) (xy 415.8481 -142.531288) (xy 415.848064 -142.585819) (xy 415.840265 -142.639789)
			(xy 415.824862 -142.692099) (xy 415.802168 -142.741684) (xy 415.772646 -142.787532) (xy 415.736898 -142.828711)
			(xy 415.695652 -142.864381) (xy 415.649747 -142.893815) (xy 415.60012 -142.916415) (xy 415.547781 -142.931719)
			(xy 415.493796 -142.939416) (xy 415.46653 -142.93977) (xy 415.466276 -142.93977) (xy 415.456207 -142.940197)
			(xy 415.437606 -142.947914) (xy 415.430208 -142.954756) (xy 415.425636 -142.959328) (xy 415.407542 -142.976587)
			(xy 415.365998 -143.004403) (xy 415.319826 -143.023583) (xy 415.270802 -143.033391) (xy 415.245804 -143.034004)
			(xy 410.820616 -143.034004) (xy 410.795621 -143.033364) (xy 410.746599 -143.02356) (xy 410.700431 -143.004385)
			(xy 410.658888 -142.976574) (xy 410.640784 -142.959328) (xy 409.34259 -141.661134) (xy 409.32537 -141.643024)
			(xy 409.297634 -141.601463) (xy 409.27853 -141.555293) (xy 409.268791 -141.506285) (xy 409.268168 -141.481302)
			(xy 409.268168 -139.810998) (xy 409.267747 -139.800979) (xy 409.260076 -139.782469) (xy 409.245903 -139.768305)
			(xy 409.227387 -139.760646) (xy 409.217368 -139.760198) (xy 389.83412 -139.760198) (xy 389.824056 -139.75976)
			(xy 389.805473 -139.752025) (xy 389.798052 -139.745212) (xy 385.797552 -135.744966) (xy 385.790154 -135.73812)
			(xy 385.771555 -135.730392) (xy 385.761484 -135.72998) (xy 377.357132 -135.72998) (xy 377.347067 -135.730415)
			(xy 377.328478 -135.738144) (xy 377.321064 -135.744966) (xy 376.546767 -136.519158) (xy 384.87426 -136.519158)
			(xy 384.878331 -136.463536) (xy 384.890457 -136.409099) (xy 384.91038 -136.357008) (xy 384.937676 -136.308373)
			(xy 384.971762 -136.26423) (xy 385.011911 -136.225521) (xy 385.057269 -136.19307) (xy 385.106869 -136.167569)
			(xy 385.159653 -136.149562) (xy 385.214496 -136.139432) (xy 385.27023 -136.137395) (xy 385.325667 -136.143495)
			(xy 385.379624 -136.157601) (xy 385.430953 -136.179413) (xy 385.478559 -136.208467) (xy 385.521427 -136.244142)
			(xy 385.558644 -136.285679) (xy 385.589417 -136.332192) (xy 385.613089 -136.382689) (xy 385.629157 -136.436096)
			(xy 385.637277 -136.491272) (xy 385.637786 -136.519158) (xy 385.637277 -136.547044) (xy 385.629157 -136.60222)
			(xy 385.613089 -136.655627) (xy 385.589417 -136.706124) (xy 385.558644 -136.752637) (xy 385.521427 -136.794174)
			(xy 385.478559 -136.829849) (xy 385.430953 -136.858903) (xy 385.379624 -136.880715) (xy 385.325667 -136.894821)
			(xy 385.27023 -136.900921) (xy 385.214496 -136.898884) (xy 385.159653 -136.888754) (xy 385.106869 -136.870747)
			(xy 385.057269 -136.845246) (xy 385.011911 -136.812795) (xy 384.971762 -136.774086) (xy 384.937676 -136.729943)
			(xy 384.91038 -136.681308) (xy 384.890457 -136.629217) (xy 384.878331 -136.57478) (xy 384.87426 -136.519158)
			(xy 376.546767 -136.519158) (xy 375.965721 -137.100125) (xy 378.717621 -137.100125) (xy 378.717624 -137.045631)
			(xy 378.725382 -136.991692) (xy 378.740737 -136.939406) (xy 378.763377 -136.889837) (xy 378.79284 -136.843995)
			(xy 378.828528 -136.802812) (xy 378.869713 -136.767127) (xy 378.915557 -136.737666) (xy 378.965126 -136.715029)
			(xy 379.017413 -136.699677) (xy 379.071353 -136.691922) (xy 379.125847 -136.691922) (xy 379.179787 -136.699677)
			(xy 379.232074 -136.715029) (xy 379.281643 -136.737666) (xy 379.327487 -136.767127) (xy 379.368672 -136.802812)
			(xy 379.40436 -136.843995) (xy 379.433823 -136.889837) (xy 379.456463 -136.939406) (xy 379.471818 -136.991692)
			(xy 379.479576 -137.045631) (xy 379.480064 -137.072878) (xy 379.480064 -137.073132) (xy 379.479736 -137.095178)
			(xy 379.474646 -137.138976) (xy 379.469904 -137.160508) (xy 379.466856 -137.17397) (xy 379.47473 -137.200386)
			(xy 379.550676 -137.269474) (xy 379.557512 -137.275303) (xy 379.574139 -137.282082) (xy 379.592086 -137.282652)
			(xy 379.600714 -137.280142) (xy 379.600968 -137.280142) (xy 379.630234 -137.271046) (xy 379.690723 -137.261217)
			(xy 379.721364 -137.260584) (xy 379.721618 -137.260584) (xy 379.748869 -137.261061) (xy 379.802817 -137.26882)
			(xy 379.855111 -137.284177) (xy 379.904688 -137.306819) (xy 379.950538 -137.336287) (xy 379.991728 -137.371979)
			(xy 380.027419 -137.41317) (xy 380.056885 -137.459021) (xy 380.079527 -137.508598) (xy 380.094882 -137.560893)
			(xy 380.10264 -137.614841) (xy 380.103126 -137.642092) (xy 380.103028 -137.652912) (xy 380.101757 -137.674515)
			(xy 380.100586 -137.685272) (xy 380.100035 -137.697457) (xy 380.108925 -137.720134) (xy 380.117604 -137.728706)
			(xy 380.18974 -137.79246) (xy 380.213616 -137.798302) (xy 380.225808 -137.795254) (xy 380.248065 -137.790152)
			(xy 380.2934 -137.78468) (xy 380.316232 -137.784332) (xy 380.31674 -137.784332) (xy 380.343987 -137.784821)
			(xy 380.397926 -137.792582) (xy 380.450211 -137.807939) (xy 380.499779 -137.830581) (xy 380.54562 -137.860047)
			(xy 380.586802 -137.895736) (xy 380.622485 -137.936922) (xy 380.651944 -137.982768) (xy 380.674579 -138.032339)
			(xy 380.68993 -138.084626) (xy 380.697683 -138.138566) (xy 380.697681 -138.19306) (xy 380.689924 -138.247)
			(xy 380.67457 -138.299286) (xy 380.651932 -138.348856) (xy 380.622469 -138.394699) (xy 380.586783 -138.435883)
			(xy 380.545599 -138.471569) (xy 380.499756 -138.501032) (xy 380.450186 -138.52367) (xy 380.3979 -138.539024)
			(xy 380.393005 -138.539728) (xy 381.147572 -138.539728) (xy 381.151643 -138.484106) (xy 381.163769 -138.429669)
			(xy 381.183692 -138.377578) (xy 381.210988 -138.328943) (xy 381.245074 -138.2848) (xy 381.285223 -138.246091)
			(xy 381.330581 -138.21364) (xy 381.380181 -138.188139) (xy 381.432965 -138.170132) (xy 381.487808 -138.160002)
			(xy 381.543542 -138.157965) (xy 381.598979 -138.164065) (xy 381.652936 -138.178171) (xy 381.704265 -138.199983)
			(xy 381.751871 -138.229037) (xy 381.794739 -138.264712) (xy 381.831956 -138.306249) (xy 381.862729 -138.352762)
			(xy 381.886401 -138.403259) (xy 381.902469 -138.456666) (xy 381.910589 -138.511842) (xy 381.911098 -138.539728)
			(xy 381.910589 -138.567614) (xy 381.902469 -138.62279) (xy 381.886401 -138.676197) (xy 381.862729 -138.726694)
			(xy 381.831956 -138.773207) (xy 381.794739 -138.814744) (xy 381.751871 -138.850419) (xy 381.704265 -138.879473)
			(xy 381.652936 -138.901285) (xy 381.598979 -138.915391) (xy 381.543542 -138.921491) (xy 381.487808 -138.919454)
			(xy 381.432965 -138.909324) (xy 381.380181 -138.891317) (xy 381.330581 -138.865816) (xy 381.285223 -138.833365)
			(xy 381.245074 -138.794656) (xy 381.210988 -138.750513) (xy 381.183692 -138.701878) (xy 381.163769 -138.649787)
			(xy 381.151643 -138.59535) (xy 381.147572 -138.539728) (xy 380.393005 -138.539728) (xy 380.34396 -138.546781)
			(xy 380.289466 -138.546783) (xy 380.235526 -138.53903) (xy 380.183239 -138.523679) (xy 380.133668 -138.501044)
			(xy 380.087822 -138.471585) (xy 380.046636 -138.435902) (xy 380.010947 -138.39472) (xy 379.981481 -138.348879)
			(xy 379.958839 -138.299311) (xy 379.943482 -138.247026) (xy 379.935721 -138.193087) (xy 379.935232 -138.16584)
			(xy 379.935333 -138.15502) (xy 379.936601 -138.133417) (xy 379.937772 -138.12266) (xy 379.938285 -138.110477)
			(xy 379.929418 -138.087803) (xy 379.920754 -138.079226) (xy 379.848618 -138.015472) (xy 379.824742 -138.00963)
			(xy 379.81255 -138.012678) (xy 379.790291 -138.017769) (xy 379.744957 -138.023248) (xy 379.722126 -138.0236)
			(xy 379.721618 -138.0236) (xy 379.694365 -138.023128) (xy 379.640414 -138.015373) (xy 379.588116 -138.000019)
			(xy 379.538535 -137.977378) (xy 379.492682 -137.947911) (xy 379.451489 -137.912218) (xy 379.415795 -137.871026)
			(xy 379.386327 -137.825173) (xy 379.363684 -137.775593) (xy 379.348329 -137.723296) (xy 379.340573 -137.669345)
			(xy 379.34011 -137.642092) (xy 379.34011 -137.641838) (xy 379.340434 -137.619792) (xy 379.345527 -137.575994)
			(xy 379.35027 -137.554462) (xy 379.353318 -137.541) (xy 379.345444 -137.514584) (xy 379.269498 -137.445496)
			(xy 379.262626 -137.439715) (xy 379.246018 -137.432925) (xy 379.228085 -137.432332) (xy 379.21946 -137.434828)
			(xy 379.219206 -137.434828) (xy 379.189942 -137.443932) (xy 379.129451 -137.453755) (xy 379.09881 -137.454386)
			(xy 379.098556 -137.454386) (xy 379.071309 -137.453875) (xy 379.01737 -137.446113) (xy 378.965085 -137.430755)
			(xy 378.915518 -137.408113) (xy 378.869677 -137.378647) (xy 378.828496 -137.342957) (xy 378.792814 -137.30177)
			(xy 378.763356 -137.255924) (xy 378.740722 -137.206353) (xy 378.725372 -137.154065) (xy 378.717621 -137.100125)
			(xy 375.965721 -137.100125) (xy 375.448068 -137.617708) (xy 375.441866 -137.624605) (xy 375.434451 -137.641588)
			(xy 375.433582 -137.6601) (xy 375.43613 -137.669016) (xy 375.441718 -137.684256) (xy 375.468134 -137.7569)
			(xy 375.470785 -137.763603) (xy 375.479293 -137.77523) (xy 375.484898 -137.77976) (xy 375.49074 -137.784332)
			(xy 375.503948 -137.789412) (xy 375.511314 -137.790174) (xy 375.540115 -137.793297) (xy 375.596368 -137.807132)
			(xy 375.649884 -137.829307) (xy 375.699437 -137.859313) (xy 375.743887 -137.896461) (xy 375.782214 -137.939898)
			(xy 375.813538 -137.988628) (xy 375.837141 -138.04153) (xy 375.845324 -138.06932) (xy 375.847102 -138.07567)
			(xy 375.852944 -138.086338) (xy 375.857008 -138.090656) (xy 375.861476 -138.095142) (xy 375.87214 -138.101957)
			(xy 375.87809 -138.104118) (xy 375.958608 -138.130788) (xy 375.96466 -138.132592) (xy 375.977251 -138.133482)
			(xy 375.9835 -138.132566) (xy 375.995184 -138.130534) (xy 376.005344 -138.12266) (xy 376.015105 -138.115228)
			(xy 376.035441 -138.101501) (xy 376.045984 -138.095228) (xy 376.046492 -138.094974) (xy 376.051318 -138.09218)
			(xy 376.059954 -138.087354) (xy 376.065796 -138.079988) (xy 376.068699 -138.076264) (xy 376.073171 -138.06795)
			(xy 376.074686 -138.063478) (xy 376.095768 -137.997438) (xy 376.097134 -137.992869) (xy 376.098293 -137.983405)
			(xy 376.098054 -137.978642) (xy 376.097546 -137.969498) (xy 376.093482 -137.960608) (xy 376.082202 -137.93523)
			(xy 376.066271 -137.88203) (xy 376.058205 -137.827085) (xy 376.057668 -137.799318) (xy 376.058153 -137.772065)
			(xy 376.065907 -137.718114) (xy 376.08126 -137.665816) (xy 376.1039 -137.616235) (xy 376.133365 -137.570381)
			(xy 376.169057 -137.529186) (xy 376.210247 -137.493491) (xy 376.256098 -137.46402) (xy 376.305677 -137.441375)
			(xy 376.357973 -137.426016) (xy 376.411923 -137.418256) (xy 376.439176 -137.41781) (xy 376.463526 -137.41821)
			(xy 376.511827 -137.424431) (xy 376.558946 -137.436738) (xy 376.58167 -137.445496) (xy 376.588528 -137.448036)
			(xy 376.597418 -137.44829) (xy 376.602213 -137.448331) (xy 376.611676 -137.446793) (xy 376.616214 -137.445242)
			(xy 376.67946 -137.422128) (xy 376.683732 -137.420473) (xy 376.691656 -137.415877) (xy 376.695208 -137.412984)
			(xy 376.702066 -137.407142) (xy 376.706638 -137.39876) (xy 376.721109 -137.373357) (xy 376.756573 -137.326882)
			(xy 376.798709 -137.286359) (xy 376.846533 -137.252736) (xy 376.898926 -137.2268) (xy 376.954661 -137.209158)
			(xy 377.012434 -137.200221) (xy 377.041664 -137.199624) (xy 377.068916 -137.200085) (xy 377.122867 -137.207837)
			(xy 377.175164 -137.223189) (xy 377.224745 -137.245827) (xy 377.270599 -137.275292) (xy 377.311792 -137.310982)
			(xy 377.347487 -137.352173) (xy 377.376956 -137.398024) (xy 377.399599 -137.447602) (xy 377.414955 -137.499898)
			(xy 377.422713 -137.553848) (xy 377.422713 -137.608352) (xy 377.414955 -137.662302) (xy 377.399599 -137.714598)
			(xy 377.376956 -137.764176) (xy 377.347487 -137.810027) (xy 377.314509 -137.848083) (xy 377.700412 -137.848083)
			(xy 377.708165 -137.794125) (xy 377.723517 -137.74182) (xy 377.746157 -137.692232) (xy 377.775624 -137.646371)
			(xy 377.811317 -137.605171) (xy 377.852511 -137.569469) (xy 377.898366 -137.539993) (xy 377.947949 -137.517344)
			(xy 378.000251 -137.501981) (xy 378.054207 -137.494218) (xy 378.108719 -137.494212) (xy 378.162676 -137.501965)
			(xy 378.214981 -137.517317) (xy 378.264569 -137.539958) (xy 378.31043 -137.569424) (xy 378.35163 -137.605118)
			(xy 378.387332 -137.646312) (xy 378.416807 -137.692167) (xy 378.439457 -137.74175) (xy 378.45482 -137.794052)
			(xy 378.462582 -137.848008) (xy 378.463048 -137.875264) (xy 378.463048 -137.884662) (xy 378.462794 -137.895584)
			(xy 378.470922 -137.91565) (xy 378.543312 -137.982452) (xy 378.563886 -137.98931) (xy 378.574554 -137.988294)
			(xy 378.612908 -137.986262) (xy 378.640161 -137.986764) (xy 378.694111 -137.994522) (xy 378.746408 -138.009879)
			(xy 378.795987 -138.032523) (xy 378.841839 -138.061992) (xy 378.88303 -138.097686) (xy 378.918722 -138.13888)
			(xy 378.948188 -138.184734) (xy 378.970829 -138.234314) (xy 378.986183 -138.286612) (xy 378.993938 -138.340563)
			(xy 378.993936 -138.395068) (xy 378.986176 -138.449018) (xy 378.970818 -138.501315) (xy 378.948174 -138.550893)
			(xy 378.918704 -138.596745) (xy 378.883008 -138.637935) (xy 378.841814 -138.673627) (xy 378.79596 -138.703092)
			(xy 378.746379 -138.725732) (xy 378.694081 -138.741084) (xy 378.64013 -138.748838) (xy 378.585625 -138.748835)
			(xy 378.531675 -138.741075) (xy 378.479378 -138.725716) (xy 378.4298 -138.70307) (xy 378.383949 -138.673599)
			(xy 378.342759 -138.637903) (xy 378.307069 -138.596708) (xy 378.277605 -138.550854) (xy 378.254966 -138.501272)
			(xy 378.239614 -138.448974) (xy 378.231861 -138.395023) (xy 378.2314 -138.36777) (xy 378.2314 -138.358372)
			(xy 378.231654 -138.34745) (xy 378.223526 -138.327384) (xy 378.151136 -138.260582) (xy 378.130562 -138.253724)
			(xy 378.119894 -138.25474) (xy 378.08154 -138.256772) (xy 378.054284 -138.256388) (xy 378.000327 -138.248636)
			(xy 377.948021 -138.233283) (xy 377.898434 -138.210644) (xy 377.852573 -138.181177) (xy 377.811372 -138.145484)
			(xy 377.77567 -138.104291) (xy 377.746194 -138.058436) (xy 377.723544 -138.008852) (xy 377.708181 -137.95655)
			(xy 377.700418 -137.902594) (xy 377.700412 -137.848083) (xy 377.314509 -137.848083) (xy 377.311792 -137.851218)
			(xy 377.270599 -137.886908) (xy 377.224745 -137.916373) (xy 377.175164 -137.939011) (xy 377.122867 -137.954363)
			(xy 377.068916 -137.962115) (xy 377.041664 -137.96264) (xy 377.017315 -137.962236) (xy 376.969017 -137.956007)
			(xy 376.921901 -137.943692) (xy 376.89917 -137.934954) (xy 376.892312 -137.932414) (xy 376.883422 -137.93216)
			(xy 376.878626 -137.932115) (xy 376.869161 -137.933648) (xy 376.864626 -137.935208) (xy 376.80138 -137.958322)
			(xy 376.797112 -137.959983) (xy 376.789196 -137.964589) (xy 376.785632 -137.967466) (xy 376.778774 -137.973308)
			(xy 376.774202 -137.98169) (xy 376.761086 -138.004807) (xy 376.729435 -138.047503) (xy 376.692171 -138.085401)
			(xy 376.650014 -138.117768) (xy 376.627136 -138.131296) (xy 376.6185 -138.136122) (xy 376.612658 -138.143488)
			(xy 376.609751 -138.14721) (xy 376.605271 -138.155521) (xy 376.603768 -138.159998) (xy 376.582686 -138.226038)
			(xy 376.581328 -138.230608) (xy 376.580185 -138.240071) (xy 376.5804 -138.244834) (xy 376.580908 -138.253978)
			(xy 376.584972 -138.262868) (xy 376.596255 -138.288245) (xy 376.612191 -138.341445) (xy 376.620262 -138.396391)
			(xy 376.620786 -138.424158) (xy 376.620326 -138.451412) (xy 376.612573 -138.505367) (xy 376.597221 -138.557668)
			(xy 376.57458 -138.607252) (xy 376.545113 -138.653109) (xy 376.509419 -138.694305) (xy 376.468225 -138.730001)
			(xy 376.42237 -138.759471) (xy 376.372787 -138.782114) (xy 376.320486 -138.797469) (xy 376.266532 -138.805224)
			(xy 376.239278 -138.805666) (xy 376.239278 -138.80592) (xy 376.211626 -138.805427) (xy 376.1569 -138.797441)
			(xy 376.103901 -138.781638) (xy 376.053737 -138.758351) (xy 376.007461 -138.728067) (xy 375.966041 -138.69142)
			(xy 375.930344 -138.649178) (xy 375.901119 -138.602225) (xy 375.878978 -138.551546) (xy 375.871232 -138.524996)
			(xy 375.869454 -138.518646) (xy 375.863612 -138.507978) (xy 375.859294 -138.503406) (xy 375.85486 -138.499018)
			(xy 375.844322 -138.49235) (xy 375.838466 -138.490198) (xy 375.774966 -138.468862) (xy 375.774458 -138.468862)
			(xy 375.758202 -138.463528) (xy 375.752205 -138.461785) (xy 375.739751 -138.460893) (xy 375.733564 -138.46175)
			(xy 375.721372 -138.463782) (xy 375.721118 -138.463782) (xy 375.711212 -138.471656) (xy 375.691075 -138.486748)
			(xy 375.64759 -138.512075) (xy 375.601156 -138.531472) (xy 375.552576 -138.544603) (xy 375.502693 -138.551242)
			(xy 375.477532 -138.551666) (xy 375.466864 -138.551666) (xy 375.46661 -138.551412) (xy 375.438906 -138.550131)
			(xy 375.38428 -138.540554) (xy 375.331616 -138.523169) (xy 375.282024 -138.498344) (xy 375.236548 -138.4666)
			(xy 375.196147 -138.428608) (xy 375.161671 -138.385167) (xy 375.133848 -138.337192) (xy 375.113263 -138.285695)
			(xy 375.10035 -138.231761) (xy 375.097294 -138.204194) (xy 375.096532 -138.196828) (xy 375.091452 -138.18362)
			(xy 375.08688 -138.177778) (xy 375.082308 -138.172213) (xy 375.070706 -138.163691) (xy 375.06402 -138.161014)
			(xy 374.97512 -138.128756) (xy 374.96621 -138.126476) (xy 374.947871 -138.127694) (xy 374.931125 -138.135267)
			(xy 374.92432 -138.141456) (xy 374.390412 -138.675364) (xy 374.382402 -138.684385) (xy 374.374975 -138.707304)
			(xy 374.376188 -138.719306) (xy 374.389396 -138.800586) (xy 374.392013 -138.812408) (xy 374.406329 -138.831893)
			(xy 374.416828 -138.837924) (xy 374.442038 -138.851142) (xy 374.488573 -138.883919) (xy 374.529714 -138.923254)
			(xy 374.564545 -138.968272) (xy 374.57888 -138.992864) (xy 374.582261 -138.99853) (xy 374.591393 -139.008048)
			(xy 374.596914 -139.01166) (xy 374.620629 -139.026553) (xy 374.663818 -139.062197) (xy 374.701328 -139.103776)
			(xy 374.714063 -139.122912) (xy 375.06732 -139.122912) (xy 375.071391 -139.06729) (xy 375.083517 -139.012853)
			(xy 375.10344 -138.960762) (xy 375.130736 -138.912127) (xy 375.164822 -138.867984) (xy 375.204971 -138.829275)
			(xy 375.250329 -138.796824) (xy 375.299929 -138.771323) (xy 375.352713 -138.753316) (xy 375.407556 -138.743186)
			(xy 375.46329 -138.741149) (xy 375.518727 -138.747249) (xy 375.572684 -138.761355) (xy 375.624013 -138.783167)
			(xy 375.671619 -138.812221) (xy 375.714487 -138.847896) (xy 375.751704 -138.889433) (xy 375.782477 -138.935946)
			(xy 375.806149 -138.986443) (xy 375.822217 -139.03985) (xy 375.830337 -139.095026) (xy 375.830846 -139.122912)
			(xy 375.830337 -139.150798) (xy 375.825133 -139.186158) (xy 384.74726 -139.186158) (xy 384.751331 -139.130536)
			(xy 384.763457 -139.076099) (xy 384.78338 -139.024008) (xy 384.810676 -138.975373) (xy 384.844762 -138.93123)
			(xy 384.884911 -138.892521) (xy 384.930269 -138.86007) (xy 384.979869 -138.834569) (xy 385.032653 -138.816562)
			(xy 385.087496 -138.806432) (xy 385.14323 -138.804395) (xy 385.198667 -138.810495) (xy 385.252624 -138.824601)
			(xy 385.303953 -138.846413) (xy 385.351559 -138.875467) (xy 385.394427 -138.911142) (xy 385.431644 -138.952679)
			(xy 385.462417 -138.999192) (xy 385.486089 -139.049689) (xy 385.502157 -139.103096) (xy 385.510277 -139.158272)
			(xy 385.510786 -139.186158) (xy 385.510277 -139.214044) (xy 385.502157 -139.26922) (xy 385.486089 -139.322627)
			(xy 385.462417 -139.373124) (xy 385.431644 -139.419637) (xy 385.394427 -139.461174) (xy 385.351559 -139.496849)
			(xy 385.303953 -139.525903) (xy 385.252624 -139.547715) (xy 385.198667 -139.561821) (xy 385.14323 -139.567921)
			(xy 385.087496 -139.565884) (xy 385.032653 -139.555754) (xy 384.979869 -139.537747) (xy 384.930269 -139.512246)
			(xy 384.884911 -139.479795) (xy 384.844762 -139.441086) (xy 384.810676 -139.396943) (xy 384.78338 -139.348308)
			(xy 384.763457 -139.296217) (xy 384.751331 -139.24178) (xy 384.74726 -139.186158) (xy 375.825133 -139.186158)
			(xy 375.822217 -139.205974) (xy 375.806149 -139.259381) (xy 375.782477 -139.309878) (xy 375.751704 -139.356391)
			(xy 375.714487 -139.397928) (xy 375.671619 -139.433603) (xy 375.624013 -139.462657) (xy 375.572684 -139.484469)
			(xy 375.518727 -139.498575) (xy 375.46329 -139.504675) (xy 375.407556 -139.502638) (xy 375.352713 -139.492508)
			(xy 375.299929 -139.474501) (xy 375.250329 -139.449) (xy 375.204971 -139.416549) (xy 375.164822 -139.37784)
			(xy 375.130736 -139.333697) (xy 375.10344 -139.285062) (xy 375.083517 -139.232971) (xy 375.071391 -139.178534)
			(xy 375.06732 -139.122912) (xy 374.714063 -139.122912) (xy 374.732352 -139.150395) (xy 374.756222 -139.201051)
			(xy 374.772423 -139.254654) (xy 374.780608 -139.310051) (xy 374.781064 -139.33805) (xy 374.780604 -139.365304)
			(xy 374.772853 -139.419258) (xy 374.7575 -139.471559) (xy 374.73486 -139.521143) (xy 374.705393 -139.566999)
			(xy 374.669699 -139.608194) (xy 374.628504 -139.643889) (xy 374.582648 -139.673357) (xy 374.533065 -139.695998)
			(xy 374.480764 -139.711351) (xy 374.455468 -139.714986) (xy 382.423668 -139.714986) (xy 382.427739 -139.659364)
			(xy 382.439865 -139.604927) (xy 382.459788 -139.552836) (xy 382.487084 -139.504201) (xy 382.52117 -139.460058)
			(xy 382.561319 -139.421349) (xy 382.606677 -139.388898) (xy 382.656277 -139.363397) (xy 382.709061 -139.34539)
			(xy 382.763904 -139.33526) (xy 382.819638 -139.333223) (xy 382.875075 -139.339323) (xy 382.929032 -139.353429)
			(xy 382.980361 -139.375241) (xy 383.027967 -139.404295) (xy 383.070835 -139.43997) (xy 383.108052 -139.481507)
			(xy 383.138825 -139.52802) (xy 383.162497 -139.578517) (xy 383.178565 -139.631924) (xy 383.186685 -139.6871)
			(xy 383.187194 -139.714986) (xy 383.186685 -139.742872) (xy 383.178565 -139.798048) (xy 383.162497 -139.851455)
			(xy 383.138825 -139.901952) (xy 383.108052 -139.948465) (xy 383.070835 -139.990002) (xy 383.027967 -140.025677)
			(xy 382.980361 -140.054731) (xy 382.929032 -140.076543) (xy 382.875075 -140.090649) (xy 382.819638 -140.096749)
			(xy 382.763904 -140.094712) (xy 382.709061 -140.084582) (xy 382.656277 -140.066575) (xy 382.606677 -140.041074)
			(xy 382.561319 -140.008623) (xy 382.52117 -139.969914) (xy 382.487084 -139.925771) (xy 382.459788 -139.877136)
			(xy 382.439865 -139.825045) (xy 382.427739 -139.770608) (xy 382.423668 -139.714986) (xy 374.455468 -139.714986)
			(xy 374.42681 -139.719104) (xy 374.399556 -139.719558) (xy 374.396 -139.719558) (xy 374.389771 -139.719776)
			(xy 374.377702 -139.722872) (xy 374.372124 -139.725654) (xy 374.366536 -139.728448) (xy 374.357392 -139.73683)
			(xy 374.306592 -139.813792) (xy 374.303276 -139.819245) (xy 374.299169 -139.831325) (xy 374.298464 -139.837668)
			(xy 374.297448 -139.84986) (xy 374.299988 -139.855702) (xy 374.302528 -139.861798) (xy 374.312709 -139.88608)
			(xy 374.327064 -139.936739) (xy 374.334337 -139.988888) (xy 374.334786 -140.015214) (xy 374.334299 -140.042463)
			(xy 374.326541 -140.096406) (xy 374.311186 -140.148696) (xy 374.288545 -140.198269) (xy 374.286046 -140.202158)
			(xy 384.767326 -140.202158) (xy 384.771397 -140.146536) (xy 384.783523 -140.092099) (xy 384.803446 -140.040008)
			(xy 384.830742 -139.991373) (xy 384.864828 -139.94723) (xy 384.904977 -139.908521) (xy 384.950335 -139.87607)
			(xy 384.999935 -139.850569) (xy 385.052719 -139.832562) (xy 385.107562 -139.822432) (xy 385.163296 -139.820395)
			(xy 385.218733 -139.826495) (xy 385.27269 -139.840601) (xy 385.324019 -139.862413) (xy 385.371625 -139.891467)
			(xy 385.414493 -139.927142) (xy 385.45171 -139.968679) (xy 385.482483 -140.015192) (xy 385.506155 -140.065689)
			(xy 385.522223 -140.119096) (xy 385.530343 -140.174272) (xy 385.530852 -140.202158) (xy 385.530343 -140.230044)
			(xy 385.522223 -140.28522) (xy 385.506155 -140.338627) (xy 385.482483 -140.389124) (xy 385.45171 -140.435637)
			(xy 385.414493 -140.477174) (xy 385.371625 -140.512849) (xy 385.324019 -140.541903) (xy 385.27269 -140.563715)
			(xy 385.218733 -140.577821) (xy 385.163296 -140.583921) (xy 385.107562 -140.581884) (xy 385.052719 -140.571754)
			(xy 384.999935 -140.553747) (xy 384.950335 -140.528246) (xy 384.904977 -140.495795) (xy 384.864828 -140.457086)
			(xy 384.830742 -140.412943) (xy 384.803446 -140.364308) (xy 384.783523 -140.312217) (xy 384.771397 -140.25778)
			(xy 384.767326 -140.202158) (xy 374.286046 -140.202158) (xy 374.25908 -140.244115) (xy 374.22339 -140.285301)
			(xy 374.182202 -140.320989) (xy 374.136355 -140.350452) (xy 374.086781 -140.373091) (xy 374.034491 -140.388444)
			(xy 373.980547 -140.3962) (xy 373.926049 -140.3962) (xy 373.872105 -140.388444) (xy 373.819815 -140.37309)
			(xy 373.770241 -140.350451) (xy 373.724394 -140.320987) (xy 373.683207 -140.285299) (xy 373.647518 -140.244112)
			(xy 373.618053 -140.198266) (xy 373.595413 -140.148693) (xy 373.580058 -140.096402) (xy 373.572301 -140.042459)
			(xy 373.572299 -139.987961) (xy 373.580054 -139.934017) (xy 373.595406 -139.881726) (xy 373.618044 -139.832152)
			(xy 373.647506 -139.786304) (xy 373.683193 -139.745116) (xy 373.724378 -139.709425) (xy 373.770224 -139.679959)
			(xy 373.819796 -139.657317) (xy 373.872086 -139.641961) (xy 373.926029 -139.634202) (xy 373.953278 -139.633706)
			(xy 373.956834 -139.633706) (xy 373.963065 -139.633497) (xy 373.975144 -139.630418) (xy 373.98071 -139.62761)
			(xy 373.986298 -139.624816) (xy 373.995442 -139.616434) (xy 374.045988 -139.539726) (xy 374.049425 -139.534244)
			(xy 374.053673 -139.522028) (xy 374.05437 -139.515596) (xy 374.054878 -139.509246) (xy 374.031107 -139.494907)
			(xy 373.987595 -139.460435) (xy 373.949521 -139.420036) (xy 373.917687 -139.374558) (xy 373.904764 -139.349988)
			(xy 373.898777 -139.339447) (xy 373.879276 -139.325109) (xy 373.867426 -139.322556) (xy 373.786146 -139.309348)
			(xy 373.774137 -139.308077) (xy 373.751198 -139.315512) (xy 373.742204 -139.323572) (xy 373.362982 -139.702794)
			(xy 373.357076 -139.710039) (xy 373.35042 -139.727491) (xy 373.350028 -139.73683) (xy 373.350028 -142.561056)
			(xy 373.69877 -142.561056) (xy 373.699236 -142.534988) (xy 373.706348 -142.483339) (xy 373.72042 -142.433137)
			(xy 373.74119 -142.385316) (xy 373.768273 -142.340766) (xy 373.801165 -142.300314) (xy 373.839253 -142.264712)
			(xy 373.881831 -142.234623) (xy 373.904764 -142.22222) (xy 373.914924 -142.21714) (xy 373.928894 -142.198852)
			(xy 373.949722 -142.099284) (xy 373.944388 -142.07744) (xy 373.937276 -142.06855) (xy 373.937276 -142.068296)
			(xy 373.921311 -142.047845) (xy 373.894452 -142.003457) (xy 373.87386 -141.955836) (xy 373.859917 -141.905863)
			(xy 373.852878 -141.854461) (xy 373.85244 -141.82852) (xy 373.852894 -141.800916) (xy 373.860837 -141.746283)
			(xy 373.876574 -141.693366) (xy 373.899777 -141.643271) (xy 373.929959 -141.597044) (xy 373.966492 -141.555653)
			(xy 374.008611 -141.519962) (xy 374.031764 -141.504924) (xy 374.042087 -141.497686) (xy 374.054605 -141.475834)
			(xy 374.05564 -141.463268) (xy 374.057926 -141.378686) (xy 374.057546 -141.365981) (xy 374.0461 -141.343326)
			(xy 374.036082 -141.335506) (xy 374.014869 -141.320146) (xy 373.976466 -141.284535) (xy 373.943296 -141.244005)
			(xy 373.91598 -141.199319) (xy 373.895034 -141.151317) (xy 373.88085 -141.100901) (xy 373.873696 -141.049019)
			(xy 373.873268 -141.022832) (xy 373.873754 -140.995581) (xy 373.88151 -140.941633) (xy 373.896865 -140.889338)
			(xy 373.919507 -140.839761) (xy 373.948973 -140.793911) (xy 373.984664 -140.75272) (xy 374.025855 -140.717029)
			(xy 374.071705 -140.687563) (xy 374.121282 -140.664921) (xy 374.173577 -140.649566) (xy 374.227525 -140.64181)
			(xy 374.282027 -140.64181) (xy 374.335975 -140.649566) (xy 374.38827 -140.664921) (xy 374.437847 -140.687563)
			(xy 374.483697 -140.717029) (xy 374.524888 -140.75272) (xy 374.560579 -140.793911) (xy 374.590045 -140.839761)
			(xy 374.612687 -140.889338) (xy 374.628042 -140.941633) (xy 374.635798 -140.995581) (xy 374.636284 -141.022832)
			(xy 374.635828 -141.050436) (xy 374.62789 -141.105071) (xy 374.612156 -141.15799) (xy 374.588955 -141.208086)
			(xy 374.558771 -141.254313) (xy 374.522237 -141.295703) (xy 374.480115 -141.331392) (xy 374.45696 -141.346428)
			(xy 374.446643 -141.353672) (xy 374.434125 -141.37552) (xy 374.433084 -141.388084) (xy 374.430798 -141.472666)
			(xy 374.431137 -141.485376) (xy 374.442611 -141.508031) (xy 374.452642 -141.515846) (xy 374.473838 -141.531228)
			(xy 374.51224 -141.566837) (xy 374.545411 -141.607363) (xy 374.572728 -141.652045) (xy 374.593677 -141.700043)
			(xy 374.607865 -141.750456) (xy 374.615025 -141.802335) (xy 374.615456 -141.82852) (xy 374.61501 -141.854589)
			(xy 374.6079 -141.906241) (xy 374.593828 -141.956445) (xy 374.573056 -142.004267) (xy 374.54597 -142.048819)
			(xy 374.513074 -142.089271) (xy 374.474981 -142.12487) (xy 374.432398 -142.154956) (xy 374.409462 -142.167356)
			(xy 374.399302 -142.172436) (xy 374.385332 -142.190724) (xy 374.364504 -142.290292) (xy 374.369838 -142.312136)
			(xy 374.37695 -142.321026) (xy 374.37695 -142.32128) (xy 374.392908 -142.341737) (xy 374.419767 -142.386124)
			(xy 374.44036 -142.433743) (xy 374.454305 -142.483714) (xy 374.461346 -142.535116) (xy 374.461786 -142.561056)
			(xy 374.4613 -142.588307) (xy 374.453544 -142.642255) (xy 374.438189 -142.69455) (xy 374.415547 -142.744127)
			(xy 374.386081 -142.789977) (xy 374.35039 -142.831168) (xy 374.309199 -142.866859) (xy 374.263349 -142.896325)
			(xy 374.213772 -142.918967) (xy 374.161477 -142.934322) (xy 374.107529 -142.942078) (xy 374.053027 -142.942078)
			(xy 373.999079 -142.934322) (xy 373.946784 -142.918967) (xy 373.897207 -142.896325) (xy 373.851357 -142.866859)
			(xy 373.810166 -142.831168) (xy 373.774475 -142.789977) (xy 373.745009 -142.744127) (xy 373.722367 -142.69455)
			(xy 373.707012 -142.642255) (xy 373.699256 -142.588307) (xy 373.69877 -142.561056) (xy 373.350028 -142.561056)
			(xy 373.350028 -143.504158) (xy 373.57126 -143.504158) (xy 373.575331 -143.448536) (xy 373.587457 -143.394099)
			(xy 373.60738 -143.342008) (xy 373.634676 -143.293373) (xy 373.668762 -143.24923) (xy 373.708911 -143.210521)
			(xy 373.754269 -143.17807) (xy 373.803869 -143.152569) (xy 373.856653 -143.134562) (xy 373.911496 -143.124432)
			(xy 373.96723 -143.122395) (xy 374.022667 -143.128495) (xy 374.076624 -143.142601) (xy 374.127953 -143.164413)
			(xy 374.175559 -143.193467) (xy 374.218427 -143.229142) (xy 374.255644 -143.270679) (xy 374.286417 -143.317192)
			(xy 374.310089 -143.367689) (xy 374.326157 -143.421096) (xy 374.334277 -143.476272) (xy 374.334786 -143.504158)
			(xy 374.334277 -143.532044) (xy 374.326157 -143.58722) (xy 374.310089 -143.640627) (xy 374.286417 -143.691124)
			(xy 374.255644 -143.737637) (xy 374.218427 -143.779174) (xy 374.175559 -143.814849) (xy 374.127953 -143.843903)
			(xy 374.076624 -143.865715) (xy 374.022667 -143.879821) (xy 373.96723 -143.885921) (xy 373.911496 -143.883884)
			(xy 373.856653 -143.873754) (xy 373.803869 -143.855747) (xy 373.754269 -143.830246) (xy 373.708911 -143.797795)
			(xy 373.668762 -143.759086) (xy 373.634676 -143.714943) (xy 373.60738 -143.666308) (xy 373.587457 -143.614217)
			(xy 373.575331 -143.55978) (xy 373.57126 -143.504158) (xy 373.350028 -143.504158) (xy 373.350028 -144.020794)
			(xy 373.350547 -144.030693) (xy 373.358129 -144.048986) (xy 373.36476 -144.056354) (xy 374.177052 -144.868646)
			(xy 374.196869 -144.889238) (xy 374.230484 -144.935452) (xy 374.256462 -144.986352) (xy 374.274166 -145.040687)
			(xy 374.283161 -145.097121) (xy 374.283732 -145.125694) (xy 374.283732 -146.456908) (xy 378.786388 -146.456908)
			(xy 378.790459 -146.401286) (xy 378.802585 -146.346849) (xy 378.822508 -146.294758) (xy 378.849804 -146.246123)
			(xy 378.88389 -146.20198) (xy 378.924039 -146.163271) (xy 378.969397 -146.13082) (xy 379.018997 -146.105319)
			(xy 379.071781 -146.087312) (xy 379.126624 -146.077182) (xy 379.182358 -146.075145) (xy 379.237795 -146.081245)
			(xy 379.291752 -146.095351) (xy 379.343081 -146.117163) (xy 379.390687 -146.146217) (xy 379.433555 -146.181892)
			(xy 379.470772 -146.223429) (xy 379.501545 -146.269942) (xy 379.525217 -146.320439) (xy 379.541285 -146.373846)
			(xy 379.549405 -146.429022) (xy 379.549914 -146.456908) (xy 379.549405 -146.484794) (xy 379.541285 -146.53997)
			(xy 379.525217 -146.593377) (xy 379.501545 -146.643874) (xy 379.470772 -146.690387) (xy 379.438275 -146.726656)
			(xy 381.080516 -146.726656) (xy 381.084587 -146.671034) (xy 381.096713 -146.616597) (xy 381.116636 -146.564506)
			(xy 381.143932 -146.515871) (xy 381.178018 -146.471728) (xy 381.218167 -146.433019) (xy 381.263525 -146.400568)
			(xy 381.313125 -146.375067) (xy 381.365909 -146.35706) (xy 381.420752 -146.34693) (xy 381.476486 -146.344893)
			(xy 381.531923 -146.350993) (xy 381.58588 -146.365099) (xy 381.637209 -146.386911) (xy 381.684815 -146.415965)
			(xy 381.727683 -146.45164) (xy 381.7649 -146.493177) (xy 381.795673 -146.53969) (xy 381.819345 -146.590187)
			(xy 381.835413 -146.643594) (xy 381.843533 -146.69877) (xy 381.844042 -146.726656) (xy 381.843533 -146.754542)
			(xy 381.835413 -146.809718) (xy 381.819345 -146.863125) (xy 381.795673 -146.913622) (xy 381.7649 -146.960135)
			(xy 381.727683 -147.001672) (xy 381.684815 -147.037347) (xy 381.637209 -147.066401) (xy 381.58588 -147.088213)
			(xy 381.531923 -147.102319) (xy 381.476486 -147.108419) (xy 381.420752 -147.106382) (xy 381.365909 -147.096252)
			(xy 381.313125 -147.078245) (xy 381.263525 -147.052744) (xy 381.218167 -147.020293) (xy 381.178018 -146.981584)
			(xy 381.143932 -146.937441) (xy 381.116636 -146.888806) (xy 381.096713 -146.836715) (xy 381.084587 -146.782278)
			(xy 381.080516 -146.726656) (xy 379.438275 -146.726656) (xy 379.433555 -146.731924) (xy 379.390687 -146.767599)
			(xy 379.343081 -146.796653) (xy 379.291752 -146.818465) (xy 379.237795 -146.832571) (xy 379.182358 -146.838671)
			(xy 379.126624 -146.836634) (xy 379.071781 -146.826504) (xy 379.018997 -146.808497) (xy 378.969397 -146.782996)
			(xy 378.924039 -146.750545) (xy 378.88389 -146.711836) (xy 378.849804 -146.667693) (xy 378.822508 -146.619058)
			(xy 378.802585 -146.566967) (xy 378.790459 -146.51253) (xy 378.786388 -146.456908) (xy 374.283732 -146.456908)
			(xy 374.283732 -147.418552) (xy 376.64212 -147.418552) (xy 376.646191 -147.36293) (xy 376.658317 -147.308493)
			(xy 376.67824 -147.256402) (xy 376.705536 -147.207767) (xy 376.739622 -147.163624) (xy 376.779771 -147.124915)
			(xy 376.825129 -147.092464) (xy 376.874729 -147.066963) (xy 376.927513 -147.048956) (xy 376.982356 -147.038826)
			(xy 377.03809 -147.036789) (xy 377.093527 -147.042889) (xy 377.147484 -147.056995) (xy 377.198813 -147.078807)
			(xy 377.246419 -147.107861) (xy 377.289287 -147.143536) (xy 377.326504 -147.185073) (xy 377.357277 -147.231586)
			(xy 377.380949 -147.282083) (xy 377.397017 -147.33549) (xy 377.405137 -147.390666) (xy 377.405646 -147.418552)
			(xy 377.405137 -147.446438) (xy 377.398027 -147.494752) (xy 378.25045 -147.494752) (xy 378.250936 -147.467501)
			(xy 378.258692 -147.413553) (xy 378.274047 -147.361258) (xy 378.296689 -147.311681) (xy 378.326155 -147.265831)
			(xy 378.361846 -147.22464) (xy 378.403037 -147.188949) (xy 378.448887 -147.159483) (xy 378.498464 -147.136841)
			(xy 378.550759 -147.121486) (xy 378.604707 -147.11373) (xy 378.659209 -147.11373) (xy 378.713157 -147.121486)
			(xy 378.765452 -147.136841) (xy 378.815029 -147.159483) (xy 378.860879 -147.188949) (xy 378.90207 -147.22464)
			(xy 378.937761 -147.265831) (xy 378.967227 -147.311681) (xy 378.989869 -147.361258) (xy 379.005224 -147.413553)
			(xy 379.01298 -147.467501) (xy 379.013466 -147.494752) (xy 379.013466 -147.49526) (xy 379.012933 -147.524122)
			(xy 379.004207 -147.581184) (xy 378.98698 -147.636278) (xy 378.961644 -147.688146) (xy 378.945648 -147.712176)
			(xy 378.93821 -147.723591) (xy 378.929195 -147.749296) (xy 378.927304 -147.776469) (xy 378.932672 -147.803174)
			(xy 378.944916 -147.827507) (xy 378.963162 -147.847732) (xy 378.98611 -147.862406) (xy 378.998988 -147.866862)
			(xy 379.024571 -147.875301) (xy 379.073263 -147.898344) (xy 379.11823 -147.928006) (xy 379.158579 -147.963697)
			(xy 379.193506 -148.004709) (xy 379.222318 -148.050226) (xy 379.244442 -148.099343) (xy 379.259437 -148.151083)
			(xy 379.267007 -148.204417) (xy 379.267466 -148.231352) (xy 379.26698 -148.258603) (xy 379.259224 -148.312551)
			(xy 379.243869 -148.364846) (xy 379.221227 -148.414423) (xy 379.191761 -148.460273) (xy 379.15607 -148.501464)
			(xy 379.114879 -148.537155) (xy 379.069029 -148.566621) (xy 379.019452 -148.589263) (xy 378.967157 -148.604618)
			(xy 378.913209 -148.612374) (xy 378.858707 -148.612374) (xy 378.804759 -148.604618) (xy 378.752464 -148.589263)
			(xy 378.702887 -148.566621) (xy 378.657037 -148.537155) (xy 378.615846 -148.501464) (xy 378.580155 -148.460273)
			(xy 378.550689 -148.414423) (xy 378.528047 -148.364846) (xy 378.512692 -148.312551) (xy 378.504936 -148.258603)
			(xy 378.50445 -148.231352) (xy 378.50445 -148.230844) (xy 378.504982 -148.201982) (xy 378.513708 -148.14492)
			(xy 378.530936 -148.089826) (xy 378.556272 -148.037958) (xy 378.572268 -148.013928) (xy 378.579693 -148.002505)
			(xy 378.588706 -147.976804) (xy 378.590597 -147.949633) (xy 378.585231 -147.92293) (xy 378.57299 -147.8986)
			(xy 378.554747 -147.878375) (xy 378.531804 -147.863699) (xy 378.518928 -147.859242) (xy 378.49335 -147.85079)
			(xy 378.444657 -147.827749) (xy 378.39969 -147.79809) (xy 378.359341 -147.7624) (xy 378.324413 -147.721389)
			(xy 378.2956 -147.675874) (xy 378.273476 -147.626759) (xy 378.25848 -147.57502) (xy 378.25091 -147.521686)
			(xy 378.25045 -147.494752) (xy 377.398027 -147.494752) (xy 377.397017 -147.501614) (xy 377.380949 -147.555021)
			(xy 377.357277 -147.605518) (xy 377.326504 -147.652031) (xy 377.289287 -147.693568) (xy 377.246419 -147.729243)
			(xy 377.198813 -147.758297) (xy 377.147484 -147.780109) (xy 377.093527 -147.794215) (xy 377.03809 -147.800315)
			(xy 376.982356 -147.798278) (xy 376.927513 -147.788148) (xy 376.874729 -147.770141) (xy 376.825129 -147.74464)
			(xy 376.779771 -147.712189) (xy 376.739622 -147.67348) (xy 376.705536 -147.629337) (xy 376.67824 -147.580702)
			(xy 376.658317 -147.528611) (xy 376.646191 -147.474174) (xy 376.64212 -147.418552) (xy 374.283732 -147.418552)
			(xy 374.283732 -147.973796) (xy 374.283185 -148.002373) (xy 374.274211 -148.058818) (xy 374.256516 -148.113163)
			(xy 374.230534 -148.16407) (xy 374.196907 -148.210284) (xy 374.177052 -148.230844) (xy 372.722648 -149.685248)
			(xy 372.702056 -149.705065) (xy 372.655842 -149.738679) (xy 372.604941 -149.764657) (xy 372.550607 -149.782361)
			(xy 372.494173 -149.791354) (xy 372.4656 -149.791928) (xy 363.333284 -149.791928) (xy 363.304708 -149.791379)
			(xy 363.248265 -149.782403) (xy 363.193921 -149.764705) (xy 363.143017 -149.738721) (xy 363.096805 -149.705092)
			(xy 363.076236 -149.685248) (xy 358.338374 -144.947386) (xy 358.330978 -144.940534) (xy 358.312379 -144.932796)
			(xy 358.302306 -144.9324) (xy 357.01732 -144.9324) (xy 357.009911 -144.925713) (xy 356.991475 -144.918123)
			(xy 356.981506 -144.917668) (xy 349.786702 -144.917668) (xy 349.775694 -144.918263) (xy 349.755725 -144.927546)
			(xy 349.741433 -144.9443) (xy 349.737934 -144.954752) (xy 349.72498 -145.001742) (xy 349.711772 -145.04924)
			(xy 349.709842 -145.057329) (xy 349.710748 -145.073922) (xy 349.71355 -145.081752) (xy 349.716598 -145.089118)
			(xy 349.727266 -145.101818) (xy 349.734632 -145.106136) (xy 349.802982 -145.147798) (xy 349.93598 -145.236909)
			(xy 350.064451 -145.332429) (xy 350.188087 -145.434131) (xy 350.306591 -145.541769) (xy 350.419678 -145.655084)
			(xy 350.527076 -145.773805) (xy 350.628528 -145.897646) (xy 350.723789 -146.02631) (xy 350.812631 -146.159487)
			(xy 350.89484 -146.296858) (xy 350.970219 -146.438092) (xy 351.038586 -146.58285) (xy 351.099777 -146.730785)
			(xy 351.153646 -146.881541) (xy 351.200063 -147.034755) (xy 351.238916 -147.190059) (xy 351.270111 -147.347081)
			(xy 351.293575 -147.505443) (xy 351.309251 -147.664764) (xy 351.3171 -147.824663) (xy 351.31756 -147.904708)
			(xy 351.31756 -147.904962) (xy 351.317052 -147.986384) (xy 351.308935 -148.149025) (xy 351.292721 -148.31106)
			(xy 351.268451 -148.472085) (xy 351.236184 -148.6317) (xy 351.196001 -148.789508) (xy 351.148002 -148.945118)
			(xy 351.092306 -149.098141) (xy 351.029052 -149.248198) (xy 350.958396 -149.394915) (xy 350.880516 -149.537928)
			(xy 350.795603 -149.676881) (xy 350.70387 -149.811429) (xy 350.605544 -149.941237) (xy 350.50087 -150.065983)
			(xy 350.390108 -150.185356) (xy 350.273534 -150.299059) (xy 350.151436 -150.406811) (xy 350.02412 -150.508342)
			(xy 349.891901 -150.603401) (xy 349.755108 -150.691752) (xy 349.614081 -150.773174) (xy 349.469171 -150.847465)
			(xy 349.320737 -150.91444) (xy 349.16915 -150.973934) (xy 349.014786 -151.025797) (xy 348.858029 -151.069902)
			(xy 348.699268 -151.106138) (xy 348.538898 -151.134416) (xy 348.377318 -151.154664) (xy 348.214929 -151.166834)
			(xy 348.052136 -151.170894) (xy 347.889343 -151.166834) (xy 347.726954 -151.154664) (xy 347.565374 -151.134416)
			(xy 347.405004 -151.106138) (xy 347.246243 -151.069902) (xy 347.089486 -151.025797) (xy 346.935122 -150.973934)
			(xy 346.783535 -150.91444) (xy 346.635101 -150.847465) (xy 346.490191 -150.773174) (xy 346.349164 -150.691752)
			(xy 346.212371 -150.603401) (xy 346.080152 -150.508342) (xy 345.952836 -150.406811) (xy 345.830738 -150.299059)
			(xy 345.714164 -150.185356) (xy 345.603402 -150.065983) (xy 345.498728 -149.941237) (xy 345.400402 -149.811429)
			(xy 345.308669 -149.676881) (xy 345.223756 -149.537928) (xy 345.145876 -149.394915) (xy 345.07522 -149.248198)
			(xy 345.011966 -149.098141) (xy 344.95627 -148.945118) (xy 344.908271 -148.789508) (xy 344.868088 -148.6317)
			(xy 344.835821 -148.472085) (xy 344.811551 -148.31106) (xy 344.795337 -148.149025) (xy 344.78722 -147.986384)
			(xy 344.786712 -147.904962) (xy 344.786712 -147.904708) (xy 344.787201 -147.824663) (xy 344.795046 -147.664765)
			(xy 344.810717 -147.505444) (xy 344.834178 -147.347082) (xy 344.86537 -147.19006) (xy 344.90422 -147.034756)
			(xy 344.950635 -146.881542) (xy 345.004502 -146.730786) (xy 345.065692 -146.582852) (xy 345.134058 -146.438094)
			(xy 345.209436 -146.29686) (xy 345.291645 -146.15949) (xy 345.380487 -146.026313) (xy 345.475749 -145.897651)
			(xy 345.577201 -145.773811) (xy 345.6846 -145.655092) (xy 345.797688 -145.541778) (xy 345.916194 -145.434143)
			(xy 346.039831 -145.332445) (xy 346.168304 -145.236928) (xy 346.301304 -145.147821) (xy 346.36964 -145.106136)
			(xy 346.369894 -145.106136) (xy 346.376761 -145.101592) (xy 346.387388 -145.089027) (xy 346.390722 -145.081498)
			(xy 346.39377 -145.073878) (xy 346.394786 -145.057368) (xy 346.379292 -145.001742) (xy 346.366338 -144.954752)
			(xy 346.362864 -144.944274) (xy 346.348599 -144.927458) (xy 346.328595 -144.918179) (xy 346.31757 -144.917668)
			(xy 346.263214 -144.917668) (xy 346.253253 -144.918157) (xy 346.23483 -144.925746) (xy 346.2274 -144.9324)
			(xy 343.699846 -147.459954) (xy 343.692447 -147.466797) (xy 343.673848 -147.474519) (xy 343.663778 -147.47494)
			(xy 331.823822 -147.47494) (xy 331.817813 -147.47511) (xy 331.806132 -147.477936) (xy 331.800708 -147.480528)
			(xy 331.797233 -147.482367) (xy 331.790854 -147.48696) (xy 331.788008 -147.489672) (xy 329.234292 -150.043388)
			(xy 329.231587 -150.04624) (xy 329.226997 -150.052619) (xy 329.225148 -150.056088) (xy 329.222568 -150.061515)
			(xy 329.219752 -150.073195) (xy 329.21956 -150.079202) (xy 329.21956 -151.819864) (xy 329.219856 -151.82855)
			(xy 329.225572 -151.84495) (xy 329.236457 -151.858483) (xy 329.24369 -151.863298) (xy 329.329034 -151.915622)
			(xy 329.355196 -151.916638) (xy 329.367134 -151.910542) (xy 329.393972 -151.897579) (xy 329.450676 -151.879235)
			(xy 329.509547 -151.869953) (xy 329.539346 -151.869394) (xy 329.5396 -151.869394) (xy 329.568517 -151.869928)
			(xy 329.625688 -151.878655) (xy 329.680888 -151.895909) (xy 329.732852 -151.921295) (xy 329.780391 -151.954231)
			(xy 329.822415 -151.993963) (xy 329.84059 -152.01646) (xy 329.848185 -152.02528) (xy 329.869094 -152.035446)
			(xy 329.880722 -152.036018) (xy 329.960478 -152.036018) (xy 329.972101 -152.035446) (xy 329.992999 -152.025263)
			(xy 330.00061 -152.01646) (xy 330.018797 -151.99397) (xy 330.060811 -151.95422) (xy 330.108343 -151.921269)
			(xy 330.160306 -151.895871) (xy 330.215507 -151.878608) (xy 330.272681 -151.869877) (xy 330.3016 -151.869394)
			(xy 330.328851 -151.86988) (xy 330.382799 -151.877636) (xy 330.435093 -151.892991) (xy 330.48467 -151.915632)
			(xy 330.53052 -151.945098) (xy 330.57171 -151.98079) (xy 330.607402 -152.02198) (xy 330.636868 -152.06783)
			(xy 330.659509 -152.117407) (xy 330.674864 -152.169701) (xy 330.68262 -152.223649) (xy 330.68262 -152.278151)
			(xy 330.674864 -152.332099) (xy 330.659509 -152.384393) (xy 330.636868 -152.43397) (xy 330.607402 -152.47982)
			(xy 330.57171 -152.52101) (xy 330.53052 -152.556702) (xy 330.48467 -152.586168) (xy 330.435093 -152.608809)
			(xy 330.382799 -152.624164) (xy 330.328851 -152.63192) (xy 330.3016 -152.63241) (xy 330.272683 -152.631876)
			(xy 330.215512 -152.623149) (xy 330.160312 -152.605895) (xy 330.108348 -152.58051) (xy 330.060809 -152.547574)
			(xy 330.018784 -152.507841) (xy 330.00061 -152.485344) (xy 329.993015 -152.476524) (xy 329.972106 -152.466357)
			(xy 329.960478 -152.465786) (xy 329.880722 -152.465786) (xy 329.869099 -152.466358) (xy 329.848202 -152.476542)
			(xy 329.84059 -152.485344) (xy 329.822402 -152.507834) (xy 329.780389 -152.547583) (xy 329.732856 -152.580534)
			(xy 329.680894 -152.605932) (xy 329.625693 -152.623195) (xy 329.568519 -152.631926) (xy 329.5396 -152.63241)
			(xy 329.539346 -152.63241) (xy 329.50955 -152.631813) (xy 329.450687 -152.622517) (xy 329.393978 -152.604205)
			(xy 329.367134 -152.591262) (xy 329.355196 -152.585166) (xy 329.329034 -152.586182) (xy 329.24369 -152.638506)
			(xy 329.236497 -152.643366) (xy 329.225634 -152.656892) (xy 329.219899 -152.673265) (xy 329.21956 -152.68194)
			(xy 329.21956 -155.7274) (xy 331.734177 -155.7274) (xy 331.737907 -155.674149) (xy 331.749022 -155.621938)
			(xy 331.767307 -155.571787) (xy 331.792405 -155.524673) (xy 331.823824 -155.481518) (xy 331.860952 -155.443164)
			(xy 331.881734 -155.42641) (xy 331.890532 -155.418795) (xy 331.900719 -155.3979) (xy 331.901292 -155.386278)
			(xy 331.901292 -155.306522) (xy 331.900729 -155.294893) (xy 331.890557 -155.273983) (xy 331.881734 -155.26639)
			(xy 331.860952 -155.249636) (xy 331.823824 -155.211282) (xy 331.792405 -155.168127) (xy 331.767307 -155.121013)
			(xy 331.749022 -155.070862) (xy 331.737907 -155.018651) (xy 331.734177 -154.9654) (xy 331.737907 -154.912149)
			(xy 331.749022 -154.859938) (xy 331.767307 -154.809787) (xy 331.792405 -154.762673) (xy 331.823824 -154.719518)
			(xy 331.860952 -154.681164) (xy 331.881734 -154.66441) (xy 331.890532 -154.656795) (xy 331.900719 -154.6359)
			(xy 331.901292 -154.624278) (xy 331.901292 -154.544522) (xy 331.900729 -154.532893) (xy 331.890557 -154.511983)
			(xy 331.881734 -154.50439) (xy 331.860952 -154.487636) (xy 331.823824 -154.449282) (xy 331.792405 -154.406127)
			(xy 331.767307 -154.359013) (xy 331.749022 -154.308862) (xy 331.737907 -154.256651) (xy 331.734177 -154.2034)
			(xy 331.737907 -154.150149) (xy 331.749022 -154.097938) (xy 331.767307 -154.047787) (xy 331.792405 -154.000673)
			(xy 331.823824 -153.957518) (xy 331.860952 -153.919164) (xy 331.881734 -153.90241) (xy 331.890532 -153.894795)
			(xy 331.900719 -153.8739) (xy 331.901292 -153.862278) (xy 331.901292 -153.782522) (xy 331.900729 -153.770893)
			(xy 331.890557 -153.749983) (xy 331.881734 -153.74239) (xy 331.859253 -153.724196) (xy 331.819516 -153.682178)
			(xy 331.786576 -153.634644) (xy 331.761187 -153.582683) (xy 331.74393 -153.527486) (xy 331.735202 -153.470316)
			(xy 331.734668 -153.4414) (xy 331.735141 -153.413574) (xy 331.743205 -153.358509) (xy 331.759192 -153.305202)
			(xy 331.782761 -153.254788) (xy 331.813411 -153.208336) (xy 331.85049 -153.166836) (xy 331.893211 -153.13117)
			(xy 331.940664 -153.102095) (xy 331.991842 -153.08023) (xy 332.045654 -153.066041) (xy 332.07325 -153.062432)
			(xy 332.073504 -153.062432) (xy 332.08422 -153.060592) (xy 332.102762 -153.049265) (xy 332.109318 -153.040588)
			(xy 332.159102 -152.967436) (xy 332.162658 -152.945592) (xy 332.159864 -152.934924) (xy 332.153701 -152.910559)
			(xy 332.147074 -152.860739) (xy 332.146656 -152.83561) (xy 332.146656 -152.835102) (xy 332.147142 -152.807127)
			(xy 332.155319 -152.751777) (xy 332.171498 -152.698217) (xy 332.195332 -152.647597) (xy 332.21041 -152.624028)
			(xy 332.215744 -152.616154) (xy 332.219554 -152.597866) (xy 332.206346 -152.511252) (xy 332.196948 -152.494742)
			(xy 332.189582 -152.4889) (xy 332.167824 -152.470683) (xy 332.129417 -152.428912) (xy 332.097623 -152.381911)
			(xy 332.073143 -152.330719) (xy 332.056518 -152.276465) (xy 332.048115 -152.220346) (xy 332.047596 -152.191974)
			(xy 332.048082 -152.164723) (xy 332.055838 -152.110775) (xy 332.071193 -152.05848) (xy 332.093835 -152.008903)
			(xy 332.123301 -151.963053) (xy 332.158992 -151.921862) (xy 332.200183 -151.886171) (xy 332.246033 -151.856705)
			(xy 332.29561 -151.834063) (xy 332.347905 -151.818708) (xy 332.401853 -151.810952) (xy 332.456355 -151.810952)
			(xy 332.510303 -151.818708) (xy 332.562598 -151.834063) (xy 332.612175 -151.856705) (xy 332.658025 -151.886171)
			(xy 332.699216 -151.921862) (xy 332.734907 -151.963053) (xy 332.764373 -152.008903) (xy 332.787015 -152.05848)
			(xy 332.80237 -152.110775) (xy 332.810126 -152.164723) (xy 332.810612 -152.191974) (xy 332.81012 -152.219949)
			(xy 332.801945 -152.275299) (xy 332.785768 -152.328859) (xy 332.761936 -152.379479) (xy 332.746858 -152.403048)
			(xy 332.741524 -152.410922) (xy 332.737714 -152.42921) (xy 332.74151 -152.454102) (xy 334.204056 -152.454102)
			(xy 334.204555 -152.425184) (xy 334.213285 -152.368011) (xy 334.230545 -152.312811) (xy 334.25594 -152.260849)
			(xy 334.288888 -152.213316) (xy 334.328634 -152.171301) (xy 334.351122 -152.153112) (xy 334.359918 -152.145494)
			(xy 334.370107 -152.124601) (xy 334.37068 -152.11298) (xy 334.37068 -152.033224) (xy 334.37012 -152.021595)
			(xy 334.359947 -152.000684) (xy 334.351122 -151.993092) (xy 334.328639 -151.9749) (xy 334.288903 -151.932881)
			(xy 334.255963 -151.885347) (xy 334.230575 -151.833385) (xy 334.213319 -151.778188) (xy 334.20459 -151.721018)
			(xy 334.204056 -151.692102) (xy 334.204542 -151.664851) (xy 334.212298 -151.610903) (xy 334.227653 -151.558608)
			(xy 334.250295 -151.509031) (xy 334.279761 -151.463181) (xy 334.315452 -151.42199) (xy 334.356643 -151.386299)
			(xy 334.402493 -151.356833) (xy 334.45207 -151.334191) (xy 334.504365 -151.318836) (xy 334.558313 -151.31108)
			(xy 334.612815 -151.31108) (xy 334.666763 -151.318836) (xy 334.719058 -151.334191) (xy 334.768635 -151.356833)
			(xy 334.814485 -151.386299) (xy 334.855676 -151.42199) (xy 334.891367 -151.463181) (xy 334.920833 -151.509031)
			(xy 334.943475 -151.558608) (xy 334.95883 -151.610903) (xy 334.966586 -151.664851) (xy 334.967072 -151.692102)
			(xy 334.966566 -151.721019) (xy 334.957836 -151.778192) (xy 334.940576 -151.833391) (xy 334.915182 -151.885353)
			(xy 334.882236 -151.932887) (xy 334.842493 -151.974903) (xy 334.820006 -151.993092) (xy 334.811213 -152.000713)
			(xy 334.801021 -152.021603) (xy 334.800448 -152.033224) (xy 334.800448 -152.11298) (xy 334.800996 -152.124611)
			(xy 334.811177 -152.145522) (xy 334.820006 -152.153112) (xy 334.842496 -152.171295) (xy 334.882231 -152.213316)
			(xy 334.915169 -152.260853) (xy 334.940556 -152.312816) (xy 334.957811 -152.368015) (xy 334.966538 -152.425186)
			(xy 334.967072 -152.454102) (xy 336.261456 -152.454102) (xy 336.261955 -152.425184) (xy 336.270685 -152.368011)
			(xy 336.287945 -152.312811) (xy 336.31334 -152.260849) (xy 336.346288 -152.213316) (xy 336.386034 -152.171301)
			(xy 336.408522 -152.153112) (xy 336.417318 -152.145494) (xy 336.427507 -152.124601) (xy 336.42808 -152.11298)
			(xy 336.42808 -152.033224) (xy 336.42752 -152.021595) (xy 336.417347 -152.000684) (xy 336.408522 -151.993092)
			(xy 336.386039 -151.9749) (xy 336.346303 -151.932881) (xy 336.313363 -151.885347) (xy 336.287975 -151.833385)
			(xy 336.270719 -151.778188) (xy 336.26199 -151.721018) (xy 336.261456 -151.692102) (xy 336.261942 -151.664851)
			(xy 336.269698 -151.610903) (xy 336.285053 -151.558608) (xy 336.307695 -151.509031) (xy 336.337161 -151.463181)
			(xy 336.372852 -151.42199) (xy 336.414043 -151.386299) (xy 336.459893 -151.356833) (xy 336.50947 -151.334191)
			(xy 336.561765 -151.318836) (xy 336.615713 -151.31108) (xy 336.670215 -151.31108) (xy 336.724163 -151.318836)
			(xy 336.776458 -151.334191) (xy 336.826035 -151.356833) (xy 336.871885 -151.386299) (xy 336.913076 -151.42199)
			(xy 336.948767 -151.463181) (xy 336.978233 -151.509031) (xy 337.000875 -151.558608) (xy 337.01623 -151.610903)
			(xy 337.023986 -151.664851) (xy 337.024472 -151.692102) (xy 337.023966 -151.721019) (xy 337.015236 -151.778192)
			(xy 336.997976 -151.833391) (xy 336.972582 -151.885353) (xy 336.939636 -151.932887) (xy 336.899893 -151.974903)
			(xy 336.877406 -151.993092) (xy 336.868613 -152.000713) (xy 336.858421 -152.021603) (xy 336.857848 -152.033224)
			(xy 336.857848 -152.11298) (xy 336.858396 -152.124611) (xy 336.868577 -152.145522) (xy 336.877406 -152.153112)
			(xy 336.899896 -152.171295) (xy 336.939631 -152.213316) (xy 336.972569 -152.260853) (xy 336.997956 -152.312816)
			(xy 337.015211 -152.368015) (xy 337.023938 -152.425186) (xy 337.024472 -152.454102) (xy 337.023986 -152.481353)
			(xy 337.01623 -152.535301) (xy 337.000875 -152.587596) (xy 336.978233 -152.637173) (xy 336.948767 -152.683023)
			(xy 336.913076 -152.724214) (xy 336.871885 -152.759905) (xy 336.826035 -152.789371) (xy 336.776458 -152.812013)
			(xy 336.724163 -152.827368) (xy 336.670215 -152.835124) (xy 336.615713 -152.835124) (xy 336.561765 -152.827368)
			(xy 336.50947 -152.812013) (xy 336.459893 -152.789371) (xy 336.414043 -152.759905) (xy 336.372852 -152.724214)
			(xy 336.337161 -152.683023) (xy 336.307695 -152.637173) (xy 336.285053 -152.587596) (xy 336.269698 -152.535301)
			(xy 336.261942 -152.481353) (xy 336.261456 -152.454102) (xy 334.967072 -152.454102) (xy 334.966586 -152.481353)
			(xy 334.95883 -152.535301) (xy 334.943475 -152.587596) (xy 334.920833 -152.637173) (xy 334.891367 -152.683023)
			(xy 334.855676 -152.724214) (xy 334.814485 -152.759905) (xy 334.768635 -152.789371) (xy 334.719058 -152.812013)
			(xy 334.666763 -152.827368) (xy 334.612815 -152.835124) (xy 334.558313 -152.835124) (xy 334.504365 -152.827368)
			(xy 334.45207 -152.812013) (xy 334.402493 -152.789371) (xy 334.356643 -152.759905) (xy 334.315452 -152.724214)
			(xy 334.279761 -152.683023) (xy 334.250295 -152.637173) (xy 334.227653 -152.587596) (xy 334.212298 -152.535301)
			(xy 334.204542 -152.481353) (xy 334.204056 -152.454102) (xy 332.74151 -152.454102) (xy 332.750922 -152.515824)
			(xy 332.76032 -152.532334) (xy 332.767686 -152.538176) (xy 332.789446 -152.556389) (xy 332.82785 -152.598163)
			(xy 332.859642 -152.645165) (xy 332.884121 -152.696358) (xy 332.900747 -152.750612) (xy 332.909152 -152.80673)
			(xy 332.909672 -152.835102) (xy 332.909672 -152.835864) (xy 332.909159 -152.863043) (xy 332.901387 -152.916842)
			(xy 332.894178 -152.943052) (xy 332.89113 -152.952958) (xy 332.89367 -152.973786) (xy 332.940914 -153.055828)
			(xy 332.957424 -153.06802) (xy 332.967584 -153.07056) (xy 332.992446 -153.076951) (xy 333.040293 -153.095547)
			(xy 333.08521 -153.120398) (xy 333.126384 -153.151054) (xy 333.163069 -153.186962) (xy 333.179166 -153.206958)
			(xy 333.186788 -153.21575) (xy 333.207678 -153.225939) (xy 333.219298 -153.226516) (xy 333.299054 -153.226516)
			(xy 333.310687 -153.225988) (xy 333.331596 -153.215791) (xy 333.339186 -153.206958) (xy 333.357374 -153.184472)
			(xy 333.399396 -153.144739) (xy 333.446932 -153.111802) (xy 333.498893 -153.086414) (xy 333.554091 -153.069158)
			(xy 333.61126 -153.060428) (xy 333.640176 -153.059892) (xy 333.667428 -153.060378) (xy 333.721378 -153.068131)
			(xy 333.773676 -153.083484) (xy 333.823256 -153.106124) (xy 333.869109 -153.13559) (xy 333.910302 -153.171281)
			(xy 333.945996 -153.212472) (xy 333.975464 -153.258323) (xy 333.998107 -153.307902) (xy 334.013464 -153.360198)
			(xy 334.021221 -153.414148) (xy 334.021684 -153.4414) (xy 334.021172 -153.470317) (xy 334.012442 -153.527489)
			(xy 333.995183 -153.582688) (xy 333.969791 -153.63465) (xy 333.936846 -153.682184) (xy 333.897104 -153.7242)
			(xy 333.874618 -153.74239) (xy 333.865811 -153.749997) (xy 333.855631 -153.770898) (xy 333.85506 -153.782522)
			(xy 333.85506 -153.862278) (xy 333.855605 -153.87391) (xy 333.865788 -153.894821) (xy 333.874618 -153.90241)
			(xy 333.895402 -153.919163) (xy 333.932535 -153.957515) (xy 333.963958 -154.000669) (xy 333.989059 -154.047783)
			(xy 334.007346 -154.097935) (xy 334.018463 -154.150148) (xy 334.022193 -154.2034) (xy 334.018463 -154.256652)
			(xy 334.007346 -154.308865) (xy 333.989059 -154.359017) (xy 333.963958 -154.406131) (xy 333.932535 -154.449285)
			(xy 333.895402 -154.487637) (xy 333.874618 -154.50439) (xy 333.865811 -154.511997) (xy 333.855631 -154.532898)
			(xy 333.85506 -154.544522) (xy 333.85506 -154.624278) (xy 333.855605 -154.63591) (xy 333.865788 -154.656821)
			(xy 333.874618 -154.66441) (xy 333.895402 -154.681163) (xy 333.932535 -154.719515) (xy 333.963958 -154.762669)
			(xy 333.989059 -154.809783) (xy 334.007346 -154.859935) (xy 334.018463 -154.912148) (xy 334.022193 -154.9654)
			(xy 334.018463 -155.018652) (xy 334.007346 -155.070865) (xy 333.989059 -155.121017) (xy 333.963958 -155.168131)
			(xy 333.932535 -155.211285) (xy 333.895402 -155.249637) (xy 333.874618 -155.26639) (xy 333.865811 -155.273997)
			(xy 333.855631 -155.294898) (xy 333.85506 -155.306522) (xy 333.85506 -155.386278) (xy 333.855605 -155.39791)
			(xy 333.865788 -155.418821) (xy 333.874618 -155.42641) (xy 333.895402 -155.443163) (xy 333.932535 -155.481515)
			(xy 333.963958 -155.524669) (xy 333.989059 -155.571783) (xy 334.007346 -155.621935) (xy 334.018463 -155.674148)
			(xy 334.022193 -155.7274) (xy 334.018463 -155.780652) (xy 334.007346 -155.832865) (xy 333.989059 -155.883017)
			(xy 333.963958 -155.930131) (xy 333.932535 -155.973285) (xy 333.895402 -156.011637) (xy 333.874618 -156.02839)
			(xy 333.865811 -156.035997) (xy 333.855631 -156.056898) (xy 333.85506 -156.068522) (xy 333.85506 -156.148278)
			(xy 333.855605 -156.15991) (xy 333.865788 -156.180821) (xy 333.874618 -156.18841) (xy 333.89711 -156.206591)
			(xy 333.936844 -156.248613) (xy 333.969781 -156.29615) (xy 333.995168 -156.348114) (xy 334.012423 -156.403313)
			(xy 334.02115 -156.460483) (xy 334.021684 -156.4894) (xy 334.021245 -156.516654) (xy 334.013487 -156.570607)
			(xy 333.99813 -156.622907) (xy 333.975486 -156.672488) (xy 333.946015 -156.718343) (xy 333.910319 -156.759536)
			(xy 333.869123 -156.79523) (xy 333.823267 -156.824697) (xy 333.773684 -156.847338) (xy 333.721383 -156.862692)
			(xy 333.66743 -156.870446) (xy 333.640176 -156.870908) (xy 333.611259 -156.87037) (xy 333.554088 -156.86165)
			(xy 333.498888 -156.844398) (xy 333.446925 -156.81901) (xy 333.399391 -156.786068) (xy 333.357375 -156.746328)
			(xy 333.339186 -156.723842) (xy 333.331585 -156.715029) (xy 333.310679 -156.704851) (xy 333.299054 -156.704284)
			(xy 333.219298 -156.704284) (xy 333.207669 -156.704842) (xy 333.186759 -156.715018) (xy 333.179166 -156.723842)
			(xy 333.162413 -156.744625) (xy 333.124059 -156.781755) (xy 333.080905 -156.813177) (xy 333.033791 -156.838276)
			(xy 332.983639 -156.856562) (xy 332.931428 -156.867679) (xy 332.878176 -156.871409) (xy 332.824924 -156.867679)
			(xy 332.772713 -156.856562) (xy 332.722561 -156.838276) (xy 332.675447 -156.813177) (xy 332.632293 -156.781755)
			(xy 332.593939 -156.744625) (xy 332.577186 -156.723842) (xy 332.569585 -156.715029) (xy 332.548679 -156.704851)
			(xy 332.537054 -156.704284) (xy 332.457044 -156.704284) (xy 332.44548 -156.704885) (xy 332.424709 -156.715059)
			(xy 332.417166 -156.723842) (xy 332.410562 -156.73197) (xy 332.401672 -156.742892) (xy 332.397354 -156.770324)
			(xy 332.44155 -156.87929) (xy 332.463902 -156.896054) (xy 332.477618 -156.897578) (xy 332.505239 -156.901191)
			(xy 332.559102 -156.91539) (xy 332.610329 -156.937267) (xy 332.657832 -156.966357) (xy 332.700602 -157.002043)
			(xy 332.737732 -157.043567) (xy 332.768432 -157.090046) (xy 332.79205 -157.140494) (xy 332.808084 -157.193839)
			(xy 332.816195 -157.248949) (xy 332.816708 -157.2768) (xy 332.816225 -157.305719) (xy 332.807493 -157.362893)
			(xy 332.790231 -157.418094) (xy 332.764833 -157.470056) (xy 332.731881 -157.517589) (xy 332.692132 -157.559603)
			(xy 332.669642 -157.57779) (xy 332.66084 -157.585401) (xy 332.650656 -157.606299) (xy 332.650084 -157.617922)
			(xy 332.650084 -157.697678) (xy 332.650656 -157.709306) (xy 332.660822 -157.730215) (xy 332.669642 -157.73781)
			(xy 332.690425 -157.754563) (xy 332.727555 -157.792917) (xy 332.758977 -157.836071) (xy 332.784076 -157.883185)
			(xy 332.802362 -157.933337) (xy 332.813478 -157.985549) (xy 332.817208 -158.0388) (xy 334.466192 -158.0388)
			(xy 334.469922 -157.985549) (xy 334.481038 -157.933337) (xy 334.499324 -157.883185) (xy 334.524423 -157.836071)
			(xy 334.555845 -157.792917) (xy 334.592975 -157.754563) (xy 334.613758 -157.73781) (xy 334.62256 -157.730199)
			(xy 334.632744 -157.709301) (xy 334.633316 -157.697678) (xy 334.633316 -157.617922) (xy 334.632744 -157.606294)
			(xy 334.622578 -157.585385) (xy 334.613758 -157.57779) (xy 334.591261 -157.559615) (xy 334.551529 -157.517591)
			(xy 334.518592 -157.470052) (xy 334.493207 -157.418088) (xy 334.475953 -157.362888) (xy 334.467226 -157.305717)
			(xy 334.466692 -157.2768) (xy 334.467178 -157.249549) (xy 334.474934 -157.195601) (xy 334.490289 -157.143306)
			(xy 334.512931 -157.093729) (xy 334.542397 -157.047879) (xy 334.578088 -157.006688) (xy 334.619279 -156.970997)
			(xy 334.665129 -156.941531) (xy 334.714706 -156.918889) (xy 334.767001 -156.903534) (xy 334.820949 -156.895778)
			(xy 334.8482 -156.895292) (xy 334.877119 -156.895775) (xy 334.934293 -156.904507) (xy 334.989494 -156.921769)
			(xy 335.041456 -156.947167) (xy 335.088989 -156.980119) (xy 335.131003 -157.019868) (xy 335.14919 -157.042358)
			(xy 335.156801 -157.05116) (xy 335.177699 -157.061344) (xy 335.189322 -157.061916) (xy 335.269078 -157.061916)
			(xy 335.280706 -157.061344) (xy 335.301615 -157.051178) (xy 335.30921 -157.042358) (xy 335.327385 -157.019861)
			(xy 335.369409 -156.980129) (xy 335.416948 -156.947192) (xy 335.468912 -156.921807) (xy 335.524112 -156.904553)
			(xy 335.581283 -156.895826) (xy 335.6102 -156.895292) (xy 335.637451 -156.895778) (xy 335.691399 -156.903534)
			(xy 335.743694 -156.918889) (xy 335.793271 -156.941531) (xy 335.839121 -156.970997) (xy 335.880312 -157.006688)
			(xy 335.916003 -157.047879) (xy 335.945469 -157.093729) (xy 335.968111 -157.143306) (xy 335.983466 -157.195601)
			(xy 335.991222 -157.249549) (xy 335.991708 -157.2768) (xy 335.991225 -157.305719) (xy 335.982493 -157.362893)
			(xy 335.965231 -157.418094) (xy 335.939833 -157.470056) (xy 335.906881 -157.517589) (xy 335.867132 -157.559603)
			(xy 335.844642 -157.57779) (xy 335.83584 -157.585401) (xy 335.825656 -157.606299) (xy 335.825084 -157.617922)
			(xy 335.825084 -157.697678) (xy 335.825656 -157.709306) (xy 335.835822 -157.730215) (xy 335.844642 -157.73781)
			(xy 335.865425 -157.754563) (xy 335.902555 -157.792917) (xy 335.933977 -157.836071) (xy 335.959076 -157.883185)
			(xy 335.977362 -157.933337) (xy 335.988478 -157.985549) (xy 335.992208 -158.0388) (xy 335.988478 -158.092051)
			(xy 335.977362 -158.144263) (xy 335.959076 -158.194415) (xy 335.933977 -158.241529) (xy 335.902555 -158.284683)
			(xy 335.865425 -158.323037) (xy 335.844642 -158.33979) (xy 335.83584 -158.347401) (xy 335.825656 -158.368299)
			(xy 335.825084 -158.379922) (xy 335.825084 -158.459678) (xy 335.825656 -158.471306) (xy 335.835822 -158.492215)
			(xy 335.844642 -158.49981) (xy 335.867139 -158.517985) (xy 335.906871 -158.560009) (xy 335.939808 -158.607548)
			(xy 335.965193 -158.659512) (xy 335.982447 -158.714712) (xy 335.991174 -158.771883) (xy 335.991708 -158.8008)
			(xy 335.991222 -158.828051) (xy 335.983466 -158.881999) (xy 335.968111 -158.934294) (xy 335.945469 -158.983871)
			(xy 335.916003 -159.029721) (xy 335.880312 -159.070912) (xy 335.839121 -159.106603) (xy 335.793271 -159.136069)
			(xy 335.743694 -159.158711) (xy 335.691399 -159.174066) (xy 335.637451 -159.181822) (xy 335.6102 -159.182308)
			(xy 335.581281 -159.181825) (xy 335.524107 -159.173093) (xy 335.468906 -159.155831) (xy 335.416944 -159.130433)
			(xy 335.369411 -159.097481) (xy 335.327397 -159.057732) (xy 335.30921 -159.035242) (xy 335.301599 -159.02644)
			(xy 335.280701 -159.016256) (xy 335.269078 -159.015684) (xy 335.189322 -159.015684) (xy 335.177694 -159.016256)
			(xy 335.156785 -159.026422) (xy 335.14919 -159.035242) (xy 335.131015 -159.057739) (xy 335.088991 -159.097471)
			(xy 335.041452 -159.130408) (xy 334.989488 -159.155793) (xy 334.934288 -159.173047) (xy 334.877117 -159.181774)
			(xy 334.8482 -159.182308) (xy 334.820949 -159.181822) (xy 334.767001 -159.174066) (xy 334.714706 -159.158711)
			(xy 334.665129 -159.136069) (xy 334.619279 -159.106603) (xy 334.578088 -159.070912) (xy 334.542397 -159.029721)
			(xy 334.512931 -158.983871) (xy 334.490289 -158.934294) (xy 334.474934 -158.881999) (xy 334.467178 -158.828051)
			(xy 334.466692 -158.8008) (xy 334.467175 -158.771881) (xy 334.475907 -158.714707) (xy 334.493169 -158.659506)
			(xy 334.518567 -158.607544) (xy 334.551519 -158.560011) (xy 334.591268 -158.517997) (xy 334.613758 -158.49981)
			(xy 334.62256 -158.492199) (xy 334.632744 -158.471301) (xy 334.633316 -158.459678) (xy 334.633316 -158.379922)
			(xy 334.632744 -158.368294) (xy 334.622578 -158.347385) (xy 334.613758 -158.33979) (xy 334.592975 -158.323037)
			(xy 334.555845 -158.284683) (xy 334.524423 -158.241529) (xy 334.499324 -158.194415) (xy 334.481038 -158.144263)
			(xy 334.469922 -158.092051) (xy 334.466192 -158.0388) (xy 332.817208 -158.0388) (xy 332.813478 -158.092051)
			(xy 332.802362 -158.144263) (xy 332.784076 -158.194415) (xy 332.758977 -158.241529) (xy 332.727555 -158.284683)
			(xy 332.690425 -158.323037) (xy 332.669642 -158.33979) (xy 332.66084 -158.347401) (xy 332.650656 -158.368299)
			(xy 332.650084 -158.379922) (xy 332.650084 -158.459678) (xy 332.650656 -158.471306) (xy 332.660822 -158.492215)
			(xy 332.669642 -158.49981) (xy 332.692139 -158.517985) (xy 332.731871 -158.560009) (xy 332.764808 -158.607548)
			(xy 332.790193 -158.659512) (xy 332.807447 -158.714712) (xy 332.816174 -158.771883) (xy 332.816708 -158.8008)
			(xy 332.816222 -158.828051) (xy 332.808466 -158.881999) (xy 332.793111 -158.934294) (xy 332.770469 -158.983871)
			(xy 332.741003 -159.029721) (xy 332.705312 -159.070912) (xy 332.664121 -159.106603) (xy 332.618271 -159.136069)
			(xy 332.568694 -159.158711) (xy 332.516399 -159.174066) (xy 332.462451 -159.181822) (xy 332.407949 -159.181822)
			(xy 332.354001 -159.174066) (xy 332.301706 -159.158711) (xy 332.252129 -159.136069) (xy 332.206279 -159.106603)
			(xy 332.165088 -159.070912) (xy 332.129397 -159.029721) (xy 332.099931 -158.983871) (xy 332.077289 -158.934294)
			(xy 332.061934 -158.881999) (xy 332.054178 -158.828051) (xy 332.053692 -158.8008) (xy 332.054175 -158.771881)
			(xy 332.062907 -158.714707) (xy 332.080169 -158.659506) (xy 332.105567 -158.607544) (xy 332.138519 -158.560011)
			(xy 332.178268 -158.517997) (xy 332.200758 -158.49981) (xy 332.20956 -158.492199) (xy 332.219744 -158.471301)
			(xy 332.220316 -158.459678) (xy 332.220316 -158.379922) (xy 332.219744 -158.368294) (xy 332.209578 -158.347385)
			(xy 332.200758 -158.33979) (xy 332.179975 -158.323037) (xy 332.142845 -158.284683) (xy 332.111423 -158.241529)
			(xy 332.086324 -158.194415) (xy 332.068038 -158.144263) (xy 332.056922 -158.092051) (xy 332.053192 -158.0388)
			(xy 332.056922 -157.985549) (xy 332.068038 -157.933337) (xy 332.086324 -157.883185) (xy 332.111423 -157.836071)
			(xy 332.142845 -157.792917) (xy 332.179975 -157.754563) (xy 332.200758 -157.73781) (xy 332.20956 -157.730199)
			(xy 332.219744 -157.709301) (xy 332.220316 -157.697678) (xy 332.220316 -157.617922) (xy 332.219744 -157.606294)
			(xy 332.209578 -157.585385) (xy 332.200758 -157.57779) (xy 332.178261 -157.559615) (xy 332.138529 -157.517591)
			(xy 332.105592 -157.470052) (xy 332.080207 -157.418088) (xy 332.062953 -157.362888) (xy 332.054226 -157.305717)
			(xy 332.053692 -157.2768) (xy 332.054147 -157.250497) (xy 332.061379 -157.198391) (xy 332.075705 -157.147774)
			(xy 332.096853 -157.099607) (xy 332.124422 -157.054805) (xy 332.140814 -157.03423) (xy 332.149704 -157.023308)
			(xy 332.154022 -156.995876) (xy 332.109826 -156.88691) (xy 332.087474 -156.870146) (xy 332.073758 -156.868622)
			(xy 332.046146 -156.864948) (xy 331.992284 -156.850759) (xy 331.941057 -156.828892) (xy 331.893552 -156.79981)
			(xy 331.85078 -156.764131) (xy 331.813649 -156.722614) (xy 331.782948 -156.67614) (xy 331.759328 -156.625696)
			(xy 331.743292 -156.572355) (xy 331.735181 -156.51725) (xy 331.734668 -156.4894) (xy 331.735161 -156.460482)
			(xy 331.743891 -156.403308) (xy 331.761153 -156.348108) (xy 331.786549 -156.296146) (xy 331.819498 -156.248613)
			(xy 331.859245 -156.206598) (xy 331.881734 -156.18841) (xy 331.890532 -156.180795) (xy 331.900719 -156.1599)
			(xy 331.901292 -156.148278) (xy 331.901292 -156.068522) (xy 331.900729 -156.056893) (xy 331.890557 -156.035983)
			(xy 331.881734 -156.02839) (xy 331.860952 -156.011636) (xy 331.823824 -155.973282) (xy 331.792405 -155.930127)
			(xy 331.767307 -155.883013) (xy 331.749022 -155.832862) (xy 331.737907 -155.780651) (xy 331.734177 -155.7274)
			(xy 329.21956 -155.7274) (xy 329.21956 -161.180018) (xy 329.220576 -161.18967) (xy 329.222208 -161.196912)
			(xy 329.229057 -161.210073) (xy 329.234038 -161.215578) (xy 331.990954 -163.972494) (xy 331.997806 -163.97989)
			(xy 332.00555 -163.998488) (xy 332.00594 -164.008562) (xy 332.00594 -166.844218) (xy 335.512662 -166.844218)
			(xy 335.516733 -166.788596) (xy 335.528859 -166.734159) (xy 335.548782 -166.682068) (xy 335.576078 -166.633433)
			(xy 335.610164 -166.58929) (xy 335.650313 -166.550581) (xy 335.695671 -166.51813) (xy 335.745271 -166.492629)
			(xy 335.798055 -166.474622) (xy 335.852898 -166.464492) (xy 335.908632 -166.462455) (xy 335.964069 -166.468555)
			(xy 336.018026 -166.482661) (xy 336.069355 -166.504473) (xy 336.116961 -166.533527) (xy 336.159829 -166.569202)
			(xy 336.197046 -166.610739) (xy 336.227819 -166.657252) (xy 336.251491 -166.707749) (xy 336.267559 -166.761156)
			(xy 336.275679 -166.816332) (xy 336.275877 -166.8272) (xy 336.583526 -166.8272) (xy 336.587597 -166.771578)
			(xy 336.599723 -166.717141) (xy 336.619646 -166.66505) (xy 336.646942 -166.616415) (xy 336.681028 -166.572272)
			(xy 336.721177 -166.533563) (xy 336.766535 -166.501112) (xy 336.816135 -166.475611) (xy 336.868919 -166.457604)
			(xy 336.923762 -166.447474) (xy 336.979496 -166.445437) (xy 337.034933 -166.451537) (xy 337.08889 -166.465643)
			(xy 337.140219 -166.487455) (xy 337.187825 -166.516509) (xy 337.230693 -166.552184) (xy 337.26791 -166.593721)
			(xy 337.298683 -166.640234) (xy 337.322355 -166.690731) (xy 337.338423 -166.744138) (xy 337.346543 -166.799314)
			(xy 337.347052 -166.8272) (xy 337.346543 -166.855086) (xy 337.338423 -166.910262) (xy 337.322355 -166.963669)
			(xy 337.298683 -167.014166) (xy 337.26791 -167.060679) (xy 337.230693 -167.102216) (xy 337.187825 -167.137891)
			(xy 337.140219 -167.166945) (xy 337.08889 -167.188757) (xy 337.034933 -167.202863) (xy 336.979496 -167.208963)
			(xy 336.923762 -167.206926) (xy 336.868919 -167.196796) (xy 336.816135 -167.178789) (xy 336.766535 -167.153288)
			(xy 336.721177 -167.120837) (xy 336.681028 -167.082128) (xy 336.646942 -167.037985) (xy 336.619646 -166.98935)
			(xy 336.599723 -166.937259) (xy 336.587597 -166.882822) (xy 336.583526 -166.8272) (xy 336.275877 -166.8272)
			(xy 336.276188 -166.844218) (xy 336.275679 -166.872104) (xy 336.267559 -166.92728) (xy 336.251491 -166.980687)
			(xy 336.227819 -167.031184) (xy 336.197046 -167.077697) (xy 336.159829 -167.119234) (xy 336.116961 -167.154909)
			(xy 336.069355 -167.183963) (xy 336.018026 -167.205775) (xy 335.964069 -167.219881) (xy 335.908632 -167.225981)
			(xy 335.852898 -167.223944) (xy 335.798055 -167.213814) (xy 335.745271 -167.195807) (xy 335.695671 -167.170306)
			(xy 335.650313 -167.137855) (xy 335.610164 -167.099146) (xy 335.576078 -167.055003) (xy 335.548782 -167.006368)
			(xy 335.528859 -166.954277) (xy 335.516733 -166.89984) (xy 335.512662 -166.844218) (xy 332.00594 -166.844218)
			(xy 332.00594 -168.327578) (xy 332.006496 -168.338273) (xy 332.015148 -168.357837) (xy 332.022704 -168.365424)
			(xy 332.078838 -168.41597) (xy 332.086984 -168.422642) (xy 332.106925 -168.429337) (xy 332.117446 -168.428924)
			(xy 332.1177 -168.428924) (xy 332.1558 -168.426892) (xy 332.183051 -168.427378) (xy 332.236999 -168.435134)
			(xy 332.289294 -168.450489) (xy 332.338871 -168.473131) (xy 332.384721 -168.502597) (xy 332.425912 -168.538288)
			(xy 332.461603 -168.579479) (xy 332.491069 -168.625329) (xy 332.513711 -168.674906) (xy 332.529066 -168.727201)
			(xy 332.536822 -168.781149) (xy 332.536822 -168.835651) (xy 332.529066 -168.889599) (xy 332.513711 -168.941894)
			(xy 332.491069 -168.991471) (xy 332.461603 -169.037321) (xy 332.425912 -169.078512) (xy 332.384721 -169.114203)
			(xy 332.338871 -169.143669) (xy 332.289294 -169.166311) (xy 332.236999 -169.181666) (xy 332.183051 -169.189422)
			(xy 332.1558 -169.189908) (xy 332.117954 -169.187876) (xy 332.117446 -169.187876) (xy 332.106778 -169.18686)
			(xy 332.086966 -169.193464) (xy 332.022704 -169.251376) (xy 332.015045 -169.258894) (xy 332.006358 -169.278498)
			(xy 332.00594 -169.289222) (xy 332.00594 -169.5958) (xy 332.256382 -169.5958) (xy 332.260453 -169.540178)
			(xy 332.272579 -169.485741) (xy 332.292502 -169.43365) (xy 332.319798 -169.385015) (xy 332.353884 -169.340872)
			(xy 332.394033 -169.302163) (xy 332.439391 -169.269712) (xy 332.488991 -169.244211) (xy 332.541775 -169.226204)
			(xy 332.596618 -169.216074) (xy 332.652352 -169.214037) (xy 332.707789 -169.220137) (xy 332.761746 -169.234243)
			(xy 332.813075 -169.256055) (xy 332.860681 -169.285109) (xy 332.903549 -169.320784) (xy 332.940766 -169.362321)
			(xy 332.971539 -169.408834) (xy 332.995211 -169.459331) (xy 333.011279 -169.512738) (xy 333.019399 -169.567914)
			(xy 333.019908 -169.5958) (xy 333.019399 -169.623686) (xy 333.011279 -169.678862) (xy 332.995211 -169.732269)
			(xy 332.971539 -169.782766) (xy 332.940766 -169.829279) (xy 332.903549 -169.870816) (xy 332.860681 -169.906491)
			(xy 332.813075 -169.935545) (xy 332.761746 -169.957357) (xy 332.707789 -169.971463) (xy 332.652352 -169.977563)
			(xy 332.596618 -169.975526) (xy 332.541775 -169.965396) (xy 332.488991 -169.947389) (xy 332.439391 -169.921888)
			(xy 332.394033 -169.889437) (xy 332.353884 -169.850728) (xy 332.319798 -169.806585) (xy 332.292502 -169.75795)
			(xy 332.272579 -169.705859) (xy 332.260453 -169.651422) (xy 332.256382 -169.5958) (xy 332.00594 -169.5958)
			(xy 332.00594 -172.15231) (xy 340.04377 -172.15231) (xy 340.044297 -172.122832) (xy 340.053366 -172.064577)
			(xy 340.071291 -172.008411) (xy 340.097643 -171.955672) (xy 340.131797 -171.907616) (xy 340.151974 -171.886118)
			(xy 340.159086 -171.879006) (xy 340.166452 -171.860718) (xy 340.166452 -171.769786) (xy 340.159086 -171.751498)
			(xy 340.151974 -171.744386) (xy 340.131798 -171.722888) (xy 340.097653 -171.674829) (xy 340.071306 -171.622089)
			(xy 340.053386 -171.565924) (xy 340.044318 -171.507671) (xy 340.04377 -171.478194) (xy 340.044272 -171.450944)
			(xy 340.052029 -171.396998) (xy 340.067384 -171.344705) (xy 340.090024 -171.295129) (xy 340.119489 -171.249279)
			(xy 340.155178 -171.20809) (xy 340.196367 -171.172398) (xy 340.242215 -171.142932) (xy 340.291789 -171.120289)
			(xy 340.344082 -171.104932) (xy 340.398028 -171.097173) (xy 340.425278 -171.096686) (xy 340.452525 -171.097141)
			(xy 340.506461 -171.104917) (xy 340.558743 -171.120286) (xy 340.608307 -171.142935) (xy 340.654145 -171.172403)
			(xy 340.695327 -171.208092) (xy 340.731013 -171.249276) (xy 340.760478 -171.295117) (xy 340.772242 -171.319698)
			(xy 340.778338 -171.33316) (xy 340.803484 -171.349416) (xy 341.012526 -171.349416) (xy 341.0226 -171.349026)
			(xy 341.041198 -171.341283) (xy 341.048594 -171.33443) (xy 341.249254 -171.133516) (xy 341.256073 -171.126099)
			(xy 341.263807 -171.107513) (xy 341.26424 -171.097448) (xy 341.26424 -163.418012) (xy 341.264878 -163.393016)
			(xy 341.274681 -163.343993) (xy 341.293854 -163.297823) (xy 341.321661 -163.256276) (xy 341.338916 -163.23818)
			(xy 342.241886 -162.334956) (xy 342.248736 -162.327564) (xy 342.25645 -162.308959) (xy 342.256872 -162.298888)
			(xy 342.256872 -160.369504) (xy 342.256452 -160.359434) (xy 342.248728 -160.340836) (xy 342.241886 -160.333436)
			(xy 341.338916 -159.430212) (xy 341.321675 -159.412103) (xy 341.293862 -159.370563) (xy 341.274684 -159.324396)
			(xy 341.26488 -159.275375) (xy 341.26424 -159.25038) (xy 341.26424 -157.583378) (xy 341.264858 -157.558381)
			(xy 341.274667 -157.509357) (xy 341.293846 -157.463187) (xy 341.321659 -157.421641) (xy 341.338916 -157.403546)
			(xy 345.20886 -153.533602) (xy 345.226982 -153.516393) (xy 345.268536 -153.488647) (xy 345.314702 -153.469536)
			(xy 345.363709 -153.459792) (xy 345.388692 -153.45918) (xy 351.475294 -153.45918) (xy 351.485364 -153.458757)
			(xy 351.503962 -153.451035) (xy 351.511362 -153.444194) (xy 355.334316 -149.62124) (xy 355.352417 -149.60399)
			(xy 355.393959 -149.576177) (xy 355.440129 -149.557002) (xy 355.489152 -149.547201) (xy 355.514148 -149.546564)
			(xy 361.511596 -149.546564) (xy 361.536593 -149.547191) (xy 361.585616 -149.556996) (xy 361.631787 -149.576172)
			(xy 361.673333 -149.603983) (xy 361.691428 -149.62124) (xy 362.142278 -150.07209) (xy 362.149693 -150.078912)
			(xy 362.168281 -150.086642) (xy 362.178346 -150.087076) (xy 373.537226 -150.087076) (xy 373.547298 -150.08667)
			(xy 373.565895 -150.078936) (xy 373.573294 -150.07209) (xy 374.088914 -149.55647) (xy 375.090944 -148.554186)
			(xy 375.0974 -148.54719) (xy 375.104967 -148.529732) (xy 375.105655 -148.510717) (xy 375.102882 -148.501608)
			(xy 375.092699 -148.470195) (xy 375.081718 -148.405083) (xy 375.081038 -148.372068) (xy 375.081543 -148.343746)
			(xy 375.089604 -148.287679) (xy 375.105562 -148.233331) (xy 375.129093 -148.181806) (xy 375.159717 -148.134154)
			(xy 375.19681 -148.091346) (xy 375.239618 -148.054253) (xy 375.28727 -148.023629) (xy 375.338795 -148.000098)
			(xy 375.393143 -147.98414) (xy 375.44921 -147.976079) (xy 375.505854 -147.976079) (xy 375.561921 -147.98414)
			(xy 375.616269 -148.000098) (xy 375.667794 -148.023629) (xy 375.715446 -148.054253) (xy 375.758254 -148.091346)
			(xy 375.795347 -148.134154) (xy 375.825971 -148.181806) (xy 375.849502 -148.233331) (xy 375.86546 -148.287679)
			(xy 375.873521 -148.343746) (xy 375.874026 -148.372068) (xy 375.873535 -148.401011) (xy 375.865102 -148.458278)
			(xy 375.848439 -148.513714) (xy 375.823899 -148.56614) (xy 375.792003 -148.614445) (xy 375.753428 -148.657604)
			(xy 375.708993 -148.694702) (xy 375.682558 -148.710904) (xy 376.020074 -148.710904) (xy 376.024145 -148.655282)
			(xy 376.036271 -148.600845) (xy 376.056194 -148.548754) (xy 376.08349 -148.500119) (xy 376.117576 -148.455976)
			(xy 376.157725 -148.417267) (xy 376.203083 -148.384816) (xy 376.252683 -148.359315) (xy 376.305467 -148.341308)
			(xy 376.36031 -148.331178) (xy 376.416044 -148.329141) (xy 376.471481 -148.335241) (xy 376.525438 -148.349347)
			(xy 376.576767 -148.371159) (xy 376.624373 -148.400213) (xy 376.667241 -148.435888) (xy 376.704458 -148.477425)
			(xy 376.735231 -148.523938) (xy 376.758903 -148.574435) (xy 376.774971 -148.627842) (xy 376.783091 -148.683018)
			(xy 376.7836 -148.710904) (xy 376.783091 -148.73879) (xy 376.777027 -148.779992) (xy 377.483622 -148.779992)
			(xy 377.487693 -148.72437) (xy 377.499819 -148.669933) (xy 377.519742 -148.617842) (xy 377.547038 -148.569207)
			(xy 377.581124 -148.525064) (xy 377.621273 -148.486355) (xy 377.666631 -148.453904) (xy 377.716231 -148.428403)
			(xy 377.769015 -148.410396) (xy 377.823858 -148.400266) (xy 377.879592 -148.398229) (xy 377.935029 -148.404329)
			(xy 377.988986 -148.418435) (xy 378.040315 -148.440247) (xy 378.087921 -148.469301) (xy 378.130789 -148.504976)
			(xy 378.168006 -148.546513) (xy 378.198779 -148.593026) (xy 378.222451 -148.643523) (xy 378.238519 -148.69693)
			(xy 378.246639 -148.752106) (xy 378.247148 -148.779992) (xy 378.246639 -148.807878) (xy 378.238519 -148.863054)
			(xy 378.222451 -148.916461) (xy 378.198779 -148.966958) (xy 378.168006 -149.013471) (xy 378.130789 -149.055008)
			(xy 378.087921 -149.090683) (xy 378.040315 -149.119737) (xy 377.988986 -149.141549) (xy 377.935029 -149.155655)
			(xy 377.879592 -149.161755) (xy 377.823858 -149.159718) (xy 377.769015 -149.149588) (xy 377.716231 -149.131581)
			(xy 377.666631 -149.10608) (xy 377.621273 -149.073629) (xy 377.581124 -149.03492) (xy 377.547038 -148.990777)
			(xy 377.519742 -148.942142) (xy 377.499819 -148.890051) (xy 377.487693 -148.835614) (xy 377.483622 -148.779992)
			(xy 376.777027 -148.779992) (xy 376.774971 -148.793966) (xy 376.758903 -148.847373) (xy 376.735231 -148.89787)
			(xy 376.704458 -148.944383) (xy 376.667241 -148.98592) (xy 376.624373 -149.021595) (xy 376.576767 -149.050649)
			(xy 376.525438 -149.072461) (xy 376.471481 -149.086567) (xy 376.416044 -149.092667) (xy 376.36031 -149.09063)
			(xy 376.305467 -149.0805) (xy 376.252683 -149.062493) (xy 376.203083 -149.036992) (xy 376.157725 -149.004541)
			(xy 376.117576 -148.965832) (xy 376.08349 -148.921689) (xy 376.056194 -148.873054) (xy 376.036271 -148.820963)
			(xy 376.024145 -148.766526) (xy 376.020074 -148.710904) (xy 375.682558 -148.710904) (xy 375.65964 -148.724951)
			(xy 375.633234 -148.736812) (xy 375.628816 -148.738795) (xy 375.620761 -148.744165) (xy 375.617232 -148.74748)
			(xy 375.52503 -148.839682) (xy 375.51898 -148.846254) (xy 375.511506 -148.862467) (xy 375.510043 -148.880259)
			(xy 375.512076 -148.888958) (xy 375.539508 -148.98751) (xy 375.558558 -149.006306) (xy 375.57202 -149.009862)
			(xy 375.599017 -149.017308) (xy 375.650668 -149.038944) (xy 375.698599 -149.067901) (xy 375.741781 -149.103557)
			(xy 375.779283 -149.145144) (xy 375.8103 -149.191769) (xy 375.834165 -149.242429) (xy 375.850364 -149.296034)
			(xy 375.858549 -149.351432) (xy 375.85904 -149.379432) (xy 375.858552 -149.406683) (xy 375.850792 -149.460629)
			(xy 375.835434 -149.512921) (xy 375.812792 -149.562497) (xy 375.783325 -149.608345) (xy 375.747634 -149.649534)
			(xy 375.706445 -149.685225) (xy 375.660597 -149.714692) (xy 375.611021 -149.737334) (xy 375.558729 -149.752692)
			(xy 375.504783 -149.760452) (xy 375.477532 -149.76094) (xy 375.44937 -149.760447) (xy 375.39366 -149.752164)
			(xy 375.33977 -149.735787) (xy 375.28887 -149.711671) (xy 375.265188 -149.696424) (xy 375.249948 -149.686264)
			(xy 375.214134 -149.68982) (xy 374.407684 -150.49627) (xy 374.001538 -150.902162) (xy 373.983427 -150.919382)
			(xy 373.941868 -150.947123) (xy 373.895698 -150.966231) (xy 373.84669 -150.975973) (xy 373.821706 -150.976584)
			(xy 361.893866 -150.976584) (xy 361.868883 -150.975965) (xy 361.819876 -150.966222) (xy 361.773707 -150.947117)
			(xy 361.732145 -150.919382) (xy 361.714034 -150.902162) (xy 361.263184 -150.451566) (xy 361.255788 -150.444722)
			(xy 361.237185 -150.437005) (xy 361.227116 -150.43658) (xy 355.798628 -150.43658) (xy 355.788558 -150.436999)
			(xy 355.769958 -150.444722) (xy 355.76256 -150.451566) (xy 353.459205 -152.754768) (xy 358.696256 -152.754768)
			(xy 358.696256 -152.670072) (xy 358.704307 -152.585758) (xy 358.720336 -152.502592) (xy 358.744197 -152.421325)
			(xy 358.775676 -152.342695) (xy 358.814487 -152.267414) (xy 358.860277 -152.196162) (xy 358.912633 -152.129586)
			(xy 358.971081 -152.068288) (xy 359.035091 -152.012823) (xy 359.104083 -151.963694) (xy 359.177433 -151.921345)
			(xy 359.254476 -151.886161) (xy 359.334515 -151.858459) (xy 359.416824 -151.838491) (xy 359.500659 -151.826438)
			(xy 359.58526 -151.822408) (xy 359.669861 -151.826438) (xy 359.753696 -151.838491) (xy 359.836005 -151.858459)
			(xy 359.916044 -151.886161) (xy 359.993087 -151.921345) (xy 360.066437 -151.963694) (xy 360.135429 -152.012823)
			(xy 360.199439 -152.068288) (xy 360.257887 -152.129586) (xy 360.310243 -152.196162) (xy 360.356033 -152.267414)
			(xy 360.394844 -152.342695) (xy 360.426323 -152.421325) (xy 360.450184 -152.502592) (xy 360.466213 -152.585758)
			(xy 360.474264 -152.670072) (xy 360.474768 -152.71242) (xy 360.474264 -152.754768) (xy 361.196378 -152.754768)
			(xy 361.196378 -152.670072) (xy 361.204429 -152.585758) (xy 361.220458 -152.502592) (xy 361.244319 -152.421325)
			(xy 361.275798 -152.342695) (xy 361.314609 -152.267414) (xy 361.360399 -152.196162) (xy 361.412755 -152.129586)
			(xy 361.471203 -152.068288) (xy 361.535213 -152.012823) (xy 361.604205 -151.963694) (xy 361.677555 -151.921345)
			(xy 361.754598 -151.886161) (xy 361.834637 -151.858459) (xy 361.916946 -151.838491) (xy 362.000781 -151.826438)
			(xy 362.085382 -151.822408) (xy 362.169983 -151.826438) (xy 362.253818 -151.838491) (xy 362.336127 -151.858459)
			(xy 362.416166 -151.886161) (xy 362.493209 -151.921345) (xy 362.566559 -151.963694) (xy 362.635551 -152.012823)
			(xy 362.699561 -152.068288) (xy 362.758009 -152.129586) (xy 362.810365 -152.196162) (xy 362.856155 -152.267414)
			(xy 362.894966 -152.342695) (xy 362.926445 -152.421325) (xy 362.950306 -152.502592) (xy 362.966335 -152.585758)
			(xy 362.974386 -152.670072) (xy 362.97489 -152.71242) (xy 362.974386 -152.754768) (xy 362.966335 -152.839082)
			(xy 362.950306 -152.922248) (xy 362.926445 -153.003515) (xy 362.894966 -153.082145) (xy 362.856155 -153.157426)
			(xy 362.810365 -153.228678) (xy 362.758009 -153.295254) (xy 362.699561 -153.356552) (xy 362.635551 -153.412017)
			(xy 362.566559 -153.461146) (xy 362.493209 -153.503495) (xy 362.416166 -153.538679) (xy 362.336127 -153.566381)
			(xy 362.253818 -153.586349) (xy 362.169983 -153.598402) (xy 362.085382 -153.602433) (xy 362.000781 -153.598402)
			(xy 361.916946 -153.586349) (xy 361.834637 -153.566381) (xy 361.754598 -153.538679) (xy 361.677555 -153.503495)
			(xy 361.604205 -153.461146) (xy 361.535213 -153.412017) (xy 361.471203 -153.356552) (xy 361.412755 -153.295254)
			(xy 361.360399 -153.228678) (xy 361.314609 -153.157426) (xy 361.275798 -153.082145) (xy 361.244319 -153.003515)
			(xy 361.220458 -152.922248) (xy 361.204429 -152.839082) (xy 361.196378 -152.754768) (xy 360.474264 -152.754768)
			(xy 360.466213 -152.839082) (xy 360.450184 -152.922248) (xy 360.426323 -153.003515) (xy 360.394844 -153.082145)
			(xy 360.356033 -153.157426) (xy 360.310243 -153.228678) (xy 360.257887 -153.295254) (xy 360.199439 -153.356552)
			(xy 360.135429 -153.412017) (xy 360.066437 -153.461146) (xy 359.993087 -153.503495) (xy 359.916044 -153.538679)
			(xy 359.836005 -153.566381) (xy 359.753696 -153.586349) (xy 359.669861 -153.598402) (xy 359.58526 -153.602433)
			(xy 359.500659 -153.598402) (xy 359.416824 -153.586349) (xy 359.334515 -153.566381) (xy 359.254476 -153.538679)
			(xy 359.177433 -153.503495) (xy 359.104083 -153.461146) (xy 359.035091 -153.412017) (xy 358.971081 -153.356552)
			(xy 358.912633 -153.295254) (xy 358.860277 -153.228678) (xy 358.814487 -153.157426) (xy 358.775676 -153.082145)
			(xy 358.744197 -153.003515) (xy 358.720336 -152.922248) (xy 358.704307 -152.839082) (xy 358.696256 -152.754768)
			(xy 353.459205 -152.754768) (xy 351.939606 -154.274266) (xy 351.921509 -154.291502) (xy 351.879945 -154.31924)
			(xy 351.833771 -154.338344) (xy 351.784759 -154.34808) (xy 351.759774 -154.348688) (xy 345.673172 -154.348688)
			(xy 345.663098 -154.349076) (xy 345.644499 -154.35682) (xy 345.637104 -154.363674) (xy 343.201422 -156.799534)
			(xy 347.421454 -156.799534) (xy 347.42194 -156.772283) (xy 347.429696 -156.718335) (xy 347.445051 -156.66604)
			(xy 347.467693 -156.616463) (xy 347.497159 -156.570613) (xy 347.53285 -156.529422) (xy 347.574041 -156.493731)
			(xy 347.619891 -156.464265) (xy 347.669468 -156.441623) (xy 347.721763 -156.426268) (xy 347.775711 -156.418512)
			(xy 347.830213 -156.418512) (xy 347.884161 -156.426268) (xy 347.936456 -156.441623) (xy 347.986033 -156.464265)
			(xy 348.031883 -156.493731) (xy 348.073074 -156.529422) (xy 348.108765 -156.570613) (xy 348.138231 -156.616463)
			(xy 348.160873 -156.66604) (xy 348.176228 -156.718335) (xy 348.183984 -156.772283) (xy 348.18447 -156.799534)
			(xy 348.183812 -156.831097) (xy 348.173425 -156.893362) (xy 348.152938 -156.953071) (xy 348.138496 -156.981144)
			(xy 348.13367 -156.990034) (xy 348.131638 -157.009592) (xy 348.154498 -157.088078) (xy 348.157756 -157.097494)
			(xy 348.170159 -157.113057) (xy 348.178628 -157.118304) (xy 348.185994 -157.122368) (xy 348.1959 -157.12821)
			(xy 348.217744 -157.130242) (xy 348.312486 -157.096714) (xy 348.328234 -157.08122) (xy 348.332298 -157.070806)
			(xy 348.342304 -157.045726) (xy 348.36838 -156.998442) (xy 348.400875 -156.955316) (xy 348.419674 -156.935932)
			(xy 348.426489 -156.928512) (xy 348.434224 -156.909928) (xy 348.43466 -156.899864) (xy 348.43466 -156.090874)
			(xy 348.435271 -156.06589) (xy 348.445014 -156.016882) (xy 348.464121 -155.970713) (xy 348.49186 -155.929152)
			(xy 348.509082 -155.911042) (xy 349.643446 -154.776678) (xy 349.66157 -154.759472) (xy 349.703124 -154.731726)
			(xy 349.74929 -154.712614) (xy 349.798295 -154.702869) (xy 349.823278 -154.702256) (xy 355.462078 -154.702256)
			(xy 355.487063 -154.702837) (xy 355.536073 -154.712589) (xy 355.582242 -154.731706) (xy 355.623801 -154.759453)
			(xy 355.64191 -154.776678) (xy 356.51567 -155.650438) (xy 356.53288 -155.668558) (xy 356.560623 -155.710114)
			(xy 356.579733 -155.756281) (xy 356.589478 -155.805287) (xy 356.590092 -155.83027) (xy 356.590092 -161.43224)
			(xy 356.590472 -161.442315) (xy 356.598222 -161.460914) (xy 356.605078 -161.468308) (xy 357.174546 -162.037776)
			(xy 357.19177 -162.055884) (xy 357.219511 -162.097444) (xy 357.238618 -162.143614) (xy 357.248358 -162.192624)
			(xy 357.248968 -162.217608) (xy 357.248968 -163.740084) (xy 357.2495 -163.750087) (xy 357.257149 -163.768572)
			(xy 357.271288 -163.782724) (xy 357.289766 -163.79039) (xy 357.299768 -163.790884) (xy 357.334566 -163.790884)
			(xy 357.344634 -163.790445) (xy 357.363232 -163.782734) (xy 357.370634 -163.775898) (xy 357.987346 -163.15944)
			(xy 358.005435 -163.142176) (xy 358.046981 -163.114365) (xy 358.093155 -163.095194) (xy 358.142181 -163.085398)
			(xy 358.167178 -163.084764) (xy 359.185972 -163.084764) (xy 359.196041 -163.084333) (xy 359.214639 -163.076617)
			(xy 359.22204 -163.069778) (xy 360.38917 -161.902648) (xy 360.395977 -161.895222) (xy 360.403717 -161.876643)
			(xy 360.404156 -161.86658) (xy 360.404156 -157.707076) (xy 360.404768 -157.682079) (xy 360.414578 -157.633054)
			(xy 360.433759 -157.586884) (xy 360.461573 -157.545339) (xy 360.478832 -157.527244) (xy 366.00765 -151.998426)
			(xy 366.025765 -151.981209) (xy 366.067323 -151.953468) (xy 366.113491 -151.93436) (xy 366.162499 -151.924617)
			(xy 366.187482 -151.924004) (xy 376.841258 -151.924004) (xy 376.851328 -151.923582) (xy 376.869927 -151.915862)
			(xy 376.877326 -151.909018) (xy 378.79655 -149.989794) (xy 378.814675 -149.972589) (xy 378.856228 -149.944842)
			(xy 378.902394 -149.92573) (xy 378.951399 -149.915985) (xy 378.976382 -149.915372) (xy 381.675386 -149.915372)
			(xy 381.685455 -149.914947) (xy 381.704054 -149.907227) (xy 381.711454 -149.900386) (xy 382.172718 -149.439122)
			(xy 382.179543 -149.43171) (xy 382.187271 -149.41312) (xy 382.187704 -149.403054) (xy 382.187704 -145.052796)
			(xy 382.187306 -145.042723) (xy 382.179569 -145.024124) (xy 382.172718 -145.016728) (xy 382.167892 -145.012156)
			(xy 382.16048 -145.005472) (xy 382.142047 -144.997875) (xy 382.122109 -144.997875) (xy 382.103676 -145.005472)
			(xy 382.096264 -145.012156) (xy 382.089406 -145.019014) (xy 382.081786 -145.036032) (xy 382.081278 -145.04543)
			(xy 382.081278 -145.045938) (xy 382.079585 -145.072328) (xy 382.069865 -145.124306) (xy 382.053057 -145.174443)
			(xy 382.029484 -145.221777) (xy 381.999597 -145.2654) (xy 381.963971 -145.304476) (xy 381.923287 -145.338255)
			(xy 381.878326 -145.36609) (xy 381.829951 -145.387446) (xy 381.77909 -145.401914) (xy 381.726718 -145.409217)
			(xy 381.700278 -145.409666) (xy 381.673023 -145.409265) (xy 381.619067 -145.401504) (xy 381.566766 -145.386143)
			(xy 381.517183 -145.363495) (xy 381.471327 -145.334021) (xy 381.430134 -145.298321) (xy 381.394441 -145.257121)
			(xy 381.364974 -145.211261) (xy 381.342334 -145.161674) (xy 381.326982 -145.10937) (xy 381.31923 -145.055413)
			(xy 381.31877 -145.028158) (xy 381.319321 -145.00045) (xy 381.327331 -144.945616) (xy 381.34319 -144.892518)
			(xy 381.366566 -144.842274) (xy 381.396966 -144.795941) (xy 381.433749 -144.754494) (xy 381.476143 -144.718805)
			(xy 381.523255 -144.689626) (xy 381.574093 -144.667571) (xy 381.60071 -144.659858) (xy 381.613918 -144.656302)
			(xy 381.632968 -144.637252) (xy 381.658876 -144.538954) (xy 381.660905 -144.530341) (xy 381.659395 -144.512718)
			(xy 381.651935 -144.49668) (xy 381.645922 -144.490186) (xy 380.944628 -143.788638) (xy 380.927354 -143.770558)
			(xy 380.899546 -143.729008) (xy 380.880377 -143.682832) (xy 380.870585 -143.633804) (xy 380.869952 -143.608806)
			(xy 380.869952 -141.93012) (xy 380.870592 -141.905124) (xy 380.880394 -141.856101) (xy 380.899566 -141.80993)
			(xy 380.927373 -141.768384) (xy 380.944628 -141.750288) (xy 381.43688 -141.258036) (xy 381.454996 -141.240802)
			(xy 381.496533 -141.212986) (xy 381.542698 -141.193807) (xy 381.591717 -141.184001) (xy 381.616712 -141.18336)
			(xy 382.542034 -141.18336) (xy 382.551198 -141.182928) (xy 382.568349 -141.176465) (xy 382.582102 -141.164351)
			(xy 382.586738 -141.156436) (xy 382.635506 -141.064488) (xy 382.633728 -141.036294) (xy 382.625854 -141.024864)
			(xy 382.610314 -141.001047) (xy 382.585726 -140.949772) (xy 382.569028 -140.895412) (xy 382.560589 -140.839175)
			(xy 382.560068 -140.810742) (xy 382.560068 -140.810488) (xy 382.560554 -140.783237) (xy 382.56831 -140.729289)
			(xy 382.583665 -140.676994) (xy 382.606307 -140.627417) (xy 382.635773 -140.581567) (xy 382.671464 -140.540376)
			(xy 382.712655 -140.504685) (xy 382.758505 -140.475219) (xy 382.808082 -140.452577) (xy 382.860377 -140.437222)
			(xy 382.914325 -140.429466) (xy 382.968827 -140.429466) (xy 383.022775 -140.437222) (xy 383.07507 -140.452577)
			(xy 383.124647 -140.475219) (xy 383.170497 -140.504685) (xy 383.211688 -140.540376) (xy 383.247379 -140.581567)
			(xy 383.276845 -140.627417) (xy 383.299487 -140.676994) (xy 383.314842 -140.729289) (xy 383.322598 -140.783237)
			(xy 383.323084 -140.810488) (xy 383.323084 -140.810742) (xy 383.322557 -140.839174) (xy 383.314102 -140.895405)
			(xy 383.2974 -140.949761) (xy 383.272821 -141.001038) (xy 383.257298 -141.024864) (xy 383.249424 -141.036294)
			(xy 383.247646 -141.064488) (xy 383.296414 -141.156436) (xy 383.301102 -141.16431) (xy 383.314857 -141.176395)
			(xy 383.331966 -141.182916) (xy 383.341118 -141.18336) (xy 383.64414 -141.18336) (xy 383.669135 -141.184022)
			(xy 383.718157 -141.193817) (xy 383.764328 -141.212983) (xy 383.805875 -141.240784) (xy 383.823972 -141.258036)
			(xy 384.005074 -141.439138) (xy 384.012484 -141.445964) (xy 384.031076 -141.453691) (xy 384.041142 -141.454124)
			(xy 385.41706 -141.454124) (xy 385.42713 -141.453698) (xy 385.445729 -141.44598) (xy 385.453128 -141.439138)
			(xy 385.545584 -141.346682) (xy 385.552422 -141.33928) (xy 385.560144 -141.320682) (xy 385.56057 -141.310614)
			(xy 385.56057 -141.31036) (xy 385.560976 -141.283083) (xy 385.56868 -141.229078) (xy 385.583997 -141.17672)
			(xy 385.606614 -141.127077) (xy 385.636072 -141.081161) (xy 385.671768 -141.039909) (xy 385.712975 -141.004161)
			(xy 385.758853 -140.974646) (xy 385.808467 -140.951965) (xy 385.860806 -140.936582) (xy 385.914802 -140.92881)
			(xy 385.942078 -140.928344) (xy 385.96934 -140.928902) (xy 386.023309 -140.936662) (xy 386.075623 -140.952027)
			(xy 386.125217 -140.974684) (xy 386.171079 -141.004172) (xy 386.212276 -141.039888) (xy 386.247968 -141.081107)
			(xy 386.277427 -141.126987) (xy 386.300054 -141.176595) (xy 386.312532 -141.219174) (xy 388.955278 -141.219174)
			(xy 388.959349 -141.163552) (xy 388.971475 -141.109115) (xy 388.991398 -141.057024) (xy 389.018694 -141.008389)
			(xy 389.05278 -140.964246) (xy 389.092929 -140.925537) (xy 389.138287 -140.893086) (xy 389.187887 -140.867585)
			(xy 389.240671 -140.849578) (xy 389.295514 -140.839448) (xy 389.351248 -140.837411) (xy 389.406685 -140.843511)
			(xy 389.460642 -140.857617) (xy 389.511971 -140.879429) (xy 389.559577 -140.908483) (xy 389.602445 -140.944158)
			(xy 389.639662 -140.985695) (xy 389.670435 -141.032208) (xy 389.694107 -141.082705) (xy 389.710175 -141.136112)
			(xy 389.718295 -141.191288) (xy 389.718804 -141.219174) (xy 389.718295 -141.24706) (xy 389.710175 -141.302236)
			(xy 389.694107 -141.355643) (xy 389.670435 -141.40614) (xy 389.639662 -141.452653) (xy 389.602445 -141.49419)
			(xy 389.559577 -141.529865) (xy 389.511971 -141.558919) (xy 389.460642 -141.580731) (xy 389.406685 -141.594837)
			(xy 389.351248 -141.600937) (xy 389.295514 -141.5989) (xy 389.240671 -141.58877) (xy 389.187887 -141.570763)
			(xy 389.138287 -141.545262) (xy 389.092929 -141.512811) (xy 389.05278 -141.474102) (xy 389.018694 -141.429959)
			(xy 388.991398 -141.381324) (xy 388.971475 -141.329233) (xy 388.959349 -141.274796) (xy 388.955278 -141.219174)
			(xy 386.312532 -141.219174) (xy 386.315387 -141.228918) (xy 386.323114 -141.282892) (xy 386.323078 -141.337416)
			(xy 386.315279 -141.391379) (xy 386.299876 -141.443682) (xy 386.277183 -141.493259) (xy 386.247663 -141.5391)
			(xy 386.211916 -141.580271) (xy 386.170672 -141.615933) (xy 386.12477 -141.645359) (xy 386.075146 -141.66795)
			(xy 386.022812 -141.683246) (xy 385.968833 -141.690934) (xy 385.94157 -141.69136) (xy 385.941316 -141.69136)
			(xy 385.931246 -141.691778) (xy 385.912647 -141.699502) (xy 385.905248 -141.706346) (xy 385.723384 -141.88821)
			(xy 385.705287 -141.905447) (xy 385.663724 -141.933187) (xy 385.61755 -141.952291) (xy 385.568537 -141.962025)
			(xy 385.543552 -141.962632) (xy 383.91465 -141.962632) (xy 383.889666 -141.962038) (xy 383.840656 -141.95229)
			(xy 383.794487 -141.933178) (xy 383.752927 -141.905434) (xy 383.734818 -141.88821) (xy 383.553716 -141.707108)
			(xy 383.54626 -141.700383) (xy 383.527681 -141.692812) (xy 383.517648 -141.692376) (xy 383.40411 -141.692376)
			(xy 383.393576 -141.692883) (xy 383.374289 -141.701367) (xy 383.360023 -141.716873) (xy 383.356104 -141.726666)
			(xy 383.347976 -141.750542) (xy 383.345213 -141.759989) (xy 383.346345 -141.779624) (xy 383.354761 -141.7974)
			(xy 383.361692 -141.80439) (xy 383.369488 -141.811644) (xy 383.384355 -141.826893) (xy 383.39141 -141.83487)
			(xy 383.395519 -141.839345) (xy 383.405403 -141.846404) (xy 383.410968 -141.84884) (xy 383.434732 -141.858978)
			(xy 383.47787 -141.887396) (xy 383.496566 -141.905228) (xy 383.898394 -142.307056) (xy 387.692644 -142.307056)
			(xy 387.696715 -142.251434) (xy 387.708841 -142.196997) (xy 387.728764 -142.144906) (xy 387.75606 -142.096271)
			(xy 387.790146 -142.052128) (xy 387.830295 -142.013419) (xy 387.875653 -141.980968) (xy 387.925253 -141.955467)
			(xy 387.978037 -141.93746) (xy 388.03288 -141.92733) (xy 388.088614 -141.925293) (xy 388.144051 -141.931393)
			(xy 388.198008 -141.945499) (xy 388.249337 -141.967311) (xy 388.256237 -141.971522) (xy 390.700004 -141.971522)
			(xy 390.704075 -141.9159) (xy 390.716201 -141.861463) (xy 390.736124 -141.809372) (xy 390.76342 -141.760737)
			(xy 390.797506 -141.716594) (xy 390.837655 -141.677885) (xy 390.883013 -141.645434) (xy 390.932613 -141.619933)
			(xy 390.985397 -141.601926) (xy 391.04024 -141.591796) (xy 391.095974 -141.589759) (xy 391.151411 -141.595859)
			(xy 391.205368 -141.609965) (xy 391.256697 -141.631777) (xy 391.304303 -141.660831) (xy 391.347171 -141.696506)
			(xy 391.384388 -141.738043) (xy 391.415161 -141.784556) (xy 391.438833 -141.835053) (xy 391.454901 -141.88846)
			(xy 391.463021 -141.943636) (xy 391.46353 -141.971522) (xy 391.463021 -141.999408) (xy 391.454901 -142.054584)
			(xy 391.438833 -142.107991) (xy 391.415161 -142.158488) (xy 391.384388 -142.205001) (xy 391.347171 -142.246538)
			(xy 391.304303 -142.282213) (xy 391.256697 -142.311267) (xy 391.205368 -142.333079) (xy 391.151411 -142.347185)
			(xy 391.095974 -142.353285) (xy 391.04024 -142.351248) (xy 390.985397 -142.341118) (xy 390.932613 -142.323111)
			(xy 390.883013 -142.29761) (xy 390.837655 -142.265159) (xy 390.797506 -142.22645) (xy 390.76342 -142.182307)
			(xy 390.736124 -142.133672) (xy 390.716201 -142.081581) (xy 390.704075 -142.027144) (xy 390.700004 -141.971522)
			(xy 388.256237 -141.971522) (xy 388.296943 -141.996365) (xy 388.339811 -142.03204) (xy 388.377028 -142.073577)
			(xy 388.407801 -142.12009) (xy 388.431473 -142.170587) (xy 388.447541 -142.223994) (xy 388.455661 -142.27917)
			(xy 388.45617 -142.307056) (xy 388.455661 -142.334942) (xy 388.447541 -142.390118) (xy 388.431473 -142.443525)
			(xy 388.407801 -142.494022) (xy 388.377028 -142.540535) (xy 388.339811 -142.582072) (xy 388.296943 -142.617747)
			(xy 388.249337 -142.646801) (xy 388.198008 -142.668613) (xy 388.144051 -142.682719) (xy 388.088614 -142.688819)
			(xy 388.03288 -142.686782) (xy 387.978037 -142.676652) (xy 387.925253 -142.658645) (xy 387.875653 -142.633144)
			(xy 387.830295 -142.600693) (xy 387.790146 -142.561984) (xy 387.75606 -142.517841) (xy 387.728764 -142.469206)
			(xy 387.708841 -142.417115) (xy 387.696715 -142.362678) (xy 387.692644 -142.307056) (xy 383.898394 -142.307056)
			(xy 384.333496 -142.742158) (xy 385.5245 -142.742158) (xy 385.528571 -142.686536) (xy 385.540697 -142.632099)
			(xy 385.56062 -142.580008) (xy 385.587916 -142.531373) (xy 385.622002 -142.48723) (xy 385.662151 -142.448521)
			(xy 385.707509 -142.41607) (xy 385.757109 -142.390569) (xy 385.809893 -142.372562) (xy 385.864736 -142.362432)
			(xy 385.92047 -142.360395) (xy 385.975907 -142.366495) (xy 386.029864 -142.380601) (xy 386.081193 -142.402413)
			(xy 386.128799 -142.431467) (xy 386.171667 -142.467142) (xy 386.208884 -142.508679) (xy 386.239657 -142.555192)
			(xy 386.263329 -142.605689) (xy 386.279397 -142.659096) (xy 386.287517 -142.714272) (xy 386.288026 -142.742158)
			(xy 386.287517 -142.770044) (xy 386.279397 -142.82522) (xy 386.263329 -142.878627) (xy 386.239657 -142.929124)
			(xy 386.208884 -142.975637) (xy 386.19687 -142.989046) (xy 388.931912 -142.989046) (xy 388.932398 -142.961795)
			(xy 388.940154 -142.907847) (xy 388.955509 -142.855552) (xy 388.978151 -142.805975) (xy 389.007617 -142.760125)
			(xy 389.043308 -142.718934) (xy 389.084499 -142.683243) (xy 389.130349 -142.653777) (xy 389.179926 -142.631135)
			(xy 389.232221 -142.61578) (xy 389.286169 -142.608024) (xy 389.340671 -142.608024) (xy 389.394619 -142.61578)
			(xy 389.446914 -142.631135) (xy 389.496491 -142.653777) (xy 389.542341 -142.683243) (xy 389.583532 -142.718934)
			(xy 389.611358 -142.751048) (xy 392.29868 -142.751048) (xy 392.302751 -142.695426) (xy 392.314877 -142.640989)
			(xy 392.3348 -142.588898) (xy 392.362096 -142.540263) (xy 392.396182 -142.49612) (xy 392.436331 -142.457411)
			(xy 392.481689 -142.42496) (xy 392.531289 -142.399459) (xy 392.584073 -142.381452) (xy 392.638916 -142.371322)
			(xy 392.69465 -142.369285) (xy 392.750087 -142.375385) (xy 392.804044 -142.389491) (xy 392.855373 -142.411303)
			(xy 392.902979 -142.440357) (xy 392.945847 -142.476032) (xy 392.983064 -142.517569) (xy 393.013837 -142.564082)
			(xy 393.037509 -142.614579) (xy 393.053577 -142.667986) (xy 393.061697 -142.723162) (xy 393.062206 -142.751048)
			(xy 393.061697 -142.778934) (xy 393.053577 -142.83411) (xy 393.037509 -142.887517) (xy 393.013837 -142.938014)
			(xy 392.983064 -142.984527) (xy 392.945847 -143.026064) (xy 392.902979 -143.061739) (xy 392.855373 -143.090793)
			(xy 392.804044 -143.112605) (xy 392.750087 -143.126711) (xy 392.69465 -143.132811) (xy 392.638916 -143.130774)
			(xy 392.584073 -143.120644) (xy 392.531289 -143.102637) (xy 392.481689 -143.077136) (xy 392.436331 -143.044685)
			(xy 392.396182 -143.005976) (xy 392.362096 -142.961833) (xy 392.3348 -142.913198) (xy 392.314877 -142.861107)
			(xy 392.302751 -142.80667) (xy 392.29868 -142.751048) (xy 389.611358 -142.751048) (xy 389.619223 -142.760125)
			(xy 389.648689 -142.805975) (xy 389.671331 -142.855552) (xy 389.686686 -142.907847) (xy 389.694442 -142.961795)
			(xy 389.694928 -142.989046) (xy 389.69442 -143.008096) (xy 389.694231 -143.021559) (xy 389.699969 -143.047851)
			(xy 389.71237 -143.071735) (xy 389.730574 -143.091555) (xy 389.75332 -143.105937) (xy 389.779032 -143.113884)
			(xy 389.792464 -143.114776) (xy 389.819095 -143.116143) (xy 389.871619 -143.125347) (xy 389.922349 -143.141777)
			(xy 389.970296 -143.165112) (xy 390.014525 -143.194899) (xy 390.054174 -143.230556) (xy 390.08847 -143.271388)
			(xy 390.116745 -143.316598) (xy 390.138446 -143.365307) (xy 390.153152 -143.416563) (xy 390.160575 -143.469368)
			(xy 390.161018 -143.49603) (xy 390.160532 -143.523281) (xy 390.152776 -143.577229) (xy 390.137421 -143.629524)
			(xy 390.114779 -143.679101) (xy 390.085313 -143.724951) (xy 390.049622 -143.766142) (xy 390.008431 -143.801833)
			(xy 389.962581 -143.831299) (xy 389.913004 -143.853941) (xy 389.860709 -143.869296) (xy 389.806761 -143.877052)
			(xy 389.752259 -143.877052) (xy 389.698311 -143.869296) (xy 389.646016 -143.853941) (xy 389.596439 -143.831299)
			(xy 389.550589 -143.801833) (xy 389.509398 -143.766142) (xy 389.473707 -143.724951) (xy 389.444241 -143.679101)
			(xy 389.421599 -143.629524) (xy 389.406244 -143.577229) (xy 389.398488 -143.523281) (xy 389.398002 -143.49603)
			(xy 389.39851 -143.47698) (xy 389.398788 -143.463515) (xy 389.39304 -143.43721) (xy 389.380624 -143.413318)
			(xy 389.362401 -143.393496) (xy 389.339635 -143.379119) (xy 389.313906 -143.371183) (xy 389.300466 -143.3703)
			(xy 389.273829 -143.36902) (xy 389.221302 -143.359806) (xy 389.170569 -143.343366) (xy 389.122621 -143.32002)
			(xy 389.078391 -143.290224) (xy 389.038743 -143.254559) (xy 389.004448 -143.213719) (xy 388.976175 -143.1685)
			(xy 388.954476 -143.119785) (xy 388.939773 -143.068522) (xy 388.932353 -143.015711) (xy 388.931912 -142.989046)
			(xy 386.19687 -142.989046) (xy 386.171667 -143.017174) (xy 386.128799 -143.052849) (xy 386.081193 -143.081903)
			(xy 386.029864 -143.103715) (xy 385.975907 -143.117821) (xy 385.92047 -143.123921) (xy 385.864736 -143.121884)
			(xy 385.809893 -143.111754) (xy 385.757109 -143.093747) (xy 385.707509 -143.068246) (xy 385.662151 -143.035795)
			(xy 385.622002 -142.997086) (xy 385.587916 -142.952943) (xy 385.56062 -142.904308) (xy 385.540697 -142.852217)
			(xy 385.528571 -142.79778) (xy 385.5245 -142.742158) (xy 384.333496 -142.742158) (xy 384.499866 -142.908528)
			(xy 384.517071 -142.926653) (xy 384.544815 -142.968208) (xy 384.563927 -143.014373) (xy 384.573673 -143.063378)
			(xy 384.574288 -143.08836) (xy 384.574288 -145.801588) (xy 399.016726 -145.801588) (xy 399.020797 -145.745966)
			(xy 399.032923 -145.691529) (xy 399.052846 -145.639438) (xy 399.080142 -145.590803) (xy 399.114228 -145.54666)
			(xy 399.154377 -145.507951) (xy 399.199735 -145.4755) (xy 399.249335 -145.449999) (xy 399.302119 -145.431992)
			(xy 399.356962 -145.421862) (xy 399.412696 -145.419825) (xy 399.468133 -145.425925) (xy 399.52209 -145.440031)
			(xy 399.573419 -145.461843) (xy 399.621025 -145.490897) (xy 399.663893 -145.526572) (xy 399.70111 -145.568109)
			(xy 399.731883 -145.614622) (xy 399.755555 -145.665119) (xy 399.771623 -145.718526) (xy 399.779743 -145.773702)
			(xy 399.780252 -145.801588) (xy 399.779743 -145.829474) (xy 399.771623 -145.88465) (xy 399.755555 -145.938057)
			(xy 399.731883 -145.988554) (xy 399.70111 -146.035067) (xy 399.663893 -146.076604) (xy 399.621025 -146.112279)
			(xy 399.573419 -146.141333) (xy 399.52209 -146.163145) (xy 399.468133 -146.177251) (xy 399.412696 -146.183351)
			(xy 399.356962 -146.181314) (xy 399.302119 -146.171184) (xy 399.249335 -146.153177) (xy 399.199735 -146.127676)
			(xy 399.154377 -146.095225) (xy 399.114228 -146.056516) (xy 399.080142 -146.012373) (xy 399.052846 -145.963738)
			(xy 399.032923 -145.911647) (xy 399.020797 -145.85721) (xy 399.016726 -145.801588) (xy 384.574288 -145.801588)
			(xy 384.574288 -147.07997) (xy 384.574706 -147.090041) (xy 384.582429 -147.10864) (xy 384.589274 -147.116038)
			(xy 385.136898 -147.663662) (xy 387.813054 -147.663662) (xy 387.81702 -147.579131) (xy 387.828885 -147.495344)
			(xy 387.848543 -147.413035) (xy 387.875823 -147.332929) (xy 387.910484 -147.25573) (xy 387.952222 -147.182115)
			(xy 388.000669 -147.112732) (xy 388.055401 -147.048191) (xy 388.115937 -146.989059) (xy 388.181743 -146.935855)
			(xy 388.252243 -146.889047) (xy 388.326815 -146.849046) (xy 388.404806 -146.816204) (xy 388.48553 -146.79081)
			(xy 388.568277 -146.773087) (xy 388.652319 -146.763189) (xy 388.73692 -146.761206) (xy 388.821334 -146.767153)
			(xy 388.904821 -146.780978) (xy 388.986646 -146.802561) (xy 389.06609 -146.831711) (xy 389.142456 -146.868172)
			(xy 389.215072 -146.911624) (xy 389.2833 -146.961685) (xy 389.34654 -147.017915) (xy 389.404237 -147.07982)
			(xy 389.455884 -147.146856) (xy 389.501026 -147.218433) (xy 389.539268 -147.293923) (xy 389.570272 -147.372662)
			(xy 389.593767 -147.453959) (xy 389.609546 -147.537098) (xy 389.61747 -147.62135) (xy 389.617966 -147.663662)
			(xy 390.353054 -147.663662) (xy 390.35702 -147.579131) (xy 390.368885 -147.495344) (xy 390.388543 -147.413035)
			(xy 390.415823 -147.332929) (xy 390.450484 -147.25573) (xy 390.492222 -147.182115) (xy 390.540669 -147.112732)
			(xy 390.595401 -147.048191) (xy 390.655937 -146.989059) (xy 390.721743 -146.935855) (xy 390.792243 -146.889047)
			(xy 390.866815 -146.849046) (xy 390.944806 -146.816204) (xy 391.02553 -146.79081) (xy 391.108277 -146.773087)
			(xy 391.192319 -146.763189) (xy 391.27692 -146.761206) (xy 391.361334 -146.767153) (xy 391.444821 -146.780978)
			(xy 391.526646 -146.802561) (xy 391.60609 -146.831711) (xy 391.682456 -146.868172) (xy 391.755072 -146.911624)
			(xy 391.8233 -146.961685) (xy 391.88654 -147.017915) (xy 391.944237 -147.07982) (xy 391.995884 -147.146856)
			(xy 392.041026 -147.218433) (xy 392.079268 -147.293923) (xy 392.110272 -147.372662) (xy 392.123901 -147.419822)
			(xy 396.174466 -147.419822) (xy 396.178537 -147.3642) (xy 396.190663 -147.309763) (xy 396.210586 -147.257672)
			(xy 396.237882 -147.209037) (xy 396.271968 -147.164894) (xy 396.312117 -147.126185) (xy 396.357475 -147.093734)
			(xy 396.407075 -147.068233) (xy 396.459859 -147.050226) (xy 396.514702 -147.040096) (xy 396.570436 -147.038059)
			(xy 396.625873 -147.044159) (xy 396.644322 -147.048982) (xy 399.016726 -147.048982) (xy 399.020797 -146.99336)
			(xy 399.032923 -146.938923) (xy 399.052846 -146.886832) (xy 399.080142 -146.838197) (xy 399.114228 -146.794054)
			(xy 399.154377 -146.755345) (xy 399.199735 -146.722894) (xy 399.249335 -146.697393) (xy 399.302119 -146.679386)
			(xy 399.356962 -146.669256) (xy 399.412696 -146.667219) (xy 399.468133 -146.673319) (xy 399.52209 -146.687425)
			(xy 399.573419 -146.709237) (xy 399.621025 -146.738291) (xy 399.663893 -146.773966) (xy 399.70111 -146.815503)
			(xy 399.731883 -146.862016) (xy 399.755555 -146.912513) (xy 399.771623 -146.96592) (xy 399.779743 -147.021096)
			(xy 399.780252 -147.048982) (xy 399.779743 -147.076868) (xy 399.771623 -147.132044) (xy 399.755555 -147.185451)
			(xy 399.731883 -147.235948) (xy 399.70111 -147.282461) (xy 399.663893 -147.323998) (xy 399.621025 -147.359673)
			(xy 399.573419 -147.388727) (xy 399.52209 -147.410539) (xy 399.468133 -147.424645) (xy 399.412696 -147.430745)
			(xy 399.356962 -147.428708) (xy 399.302119 -147.418578) (xy 399.249335 -147.400571) (xy 399.199735 -147.37507)
			(xy 399.154377 -147.342619) (xy 399.114228 -147.30391) (xy 399.080142 -147.259767) (xy 399.052846 -147.211132)
			(xy 399.032923 -147.159041) (xy 399.020797 -147.104604) (xy 399.016726 -147.048982) (xy 396.644322 -147.048982)
			(xy 396.67983 -147.058265) (xy 396.731159 -147.080077) (xy 396.778765 -147.109131) (xy 396.821633 -147.144806)
			(xy 396.85885 -147.186343) (xy 396.889623 -147.232856) (xy 396.913295 -147.283353) (xy 396.929363 -147.33676)
			(xy 396.937483 -147.391936) (xy 396.937992 -147.419822) (xy 396.937483 -147.447708) (xy 396.929363 -147.502884)
			(xy 396.913295 -147.556291) (xy 396.889623 -147.606788) (xy 396.85885 -147.653301) (xy 396.821633 -147.694838)
			(xy 396.778765 -147.730513) (xy 396.731159 -147.759567) (xy 396.67983 -147.781379) (xy 396.625873 -147.795485)
			(xy 396.570436 -147.801585) (xy 396.514702 -147.799548) (xy 396.459859 -147.789418) (xy 396.407075 -147.771411)
			(xy 396.357475 -147.74591) (xy 396.312117 -147.713459) (xy 396.271968 -147.67475) (xy 396.237882 -147.630607)
			(xy 396.210586 -147.581972) (xy 396.190663 -147.529881) (xy 396.178537 -147.475444) (xy 396.174466 -147.419822)
			(xy 392.123901 -147.419822) (xy 392.133767 -147.453959) (xy 392.149546 -147.537098) (xy 392.15747 -147.62135)
			(xy 392.157966 -147.663662) (xy 392.15747 -147.705974) (xy 392.149546 -147.790226) (xy 392.133767 -147.873365)
			(xy 392.110272 -147.954662) (xy 392.079268 -148.033401) (xy 392.041026 -148.108891) (xy 391.995884 -148.180468)
			(xy 391.944237 -148.247504) (xy 391.88654 -148.309409) (xy 391.8233 -148.365639) (xy 391.755072 -148.4157)
			(xy 391.722566 -148.435151) (xy 396.37106 -148.435151) (xy 396.37106 -148.380649) (xy 396.378816 -148.326702)
			(xy 396.39417 -148.274408) (xy 396.416809 -148.22483) (xy 396.446274 -148.17898) (xy 396.481963 -148.137788)
			(xy 396.523151 -148.102095) (xy 396.568999 -148.072627) (xy 396.618574 -148.049982) (xy 396.670867 -148.034623)
			(xy 396.724813 -148.026862) (xy 396.752064 -148.026374) (xy 396.779321 -148.026858) (xy 396.833275 -148.034645)
			(xy 396.885571 -148.050035) (xy 396.935143 -148.072716) (xy 396.958312 -148.08708) (xy 396.958566 -148.087334)
			(xy 396.96629 -148.091888) (xy 396.983796 -148.09573) (xy 397.001549 -148.093276) (xy 397.00962 -148.089366)
			(xy 397.088106 -148.04771) (xy 397.095775 -148.043174) (xy 397.107666 -148.029923) (xy 397.114329 -148.013413)
			(xy 397.11503 -148.00453) (xy 397.11503 -148.004022) (xy 397.116159 -147.977253) (xy 397.125045 -147.924417)
			(xy 397.141239 -147.873345) (xy 397.164422 -147.825043) (xy 397.194139 -147.780461) (xy 397.229803 -147.740478)
			(xy 397.270714 -147.705881) (xy 397.316064 -147.677352) (xy 397.364961 -147.655451) (xy 397.416443 -147.64061)
			(xy 397.469495 -147.633122) (xy 397.496284 -147.632674) (xy 397.523534 -147.633193) (xy 397.57748 -147.640947)
			(xy 397.629773 -147.656299) (xy 397.679348 -147.678937) (xy 397.725198 -147.7084) (xy 397.766388 -147.744088)
			(xy 397.80208 -147.785275) (xy 397.831547 -147.831122) (xy 397.854189 -147.880696) (xy 397.869546 -147.932987)
			(xy 397.877304 -147.986932) (xy 397.877792 -148.014182) (xy 398.003776 -148.014182) (xy 398.004262 -147.986931)
			(xy 398.012018 -147.932983) (xy 398.027373 -147.880688) (xy 398.050015 -147.831111) (xy 398.079481 -147.785261)
			(xy 398.115172 -147.74407) (xy 398.156363 -147.708379) (xy 398.202213 -147.678913) (xy 398.25179 -147.656271)
			(xy 398.304085 -147.640916) (xy 398.358033 -147.63316) (xy 398.412535 -147.63316) (xy 398.466483 -147.640916)
			(xy 398.518778 -147.656271) (xy 398.568355 -147.678913) (xy 398.614205 -147.708379) (xy 398.655396 -147.74407)
			(xy 398.691087 -147.785261) (xy 398.720553 -147.831111) (xy 398.743195 -147.880688) (xy 398.75855 -147.932983)
			(xy 398.759269 -147.937982) (xy 399.016726 -147.937982) (xy 399.020797 -147.88236) (xy 399.032923 -147.827923)
			(xy 399.052846 -147.775832) (xy 399.080142 -147.727197) (xy 399.114228 -147.683054) (xy 399.154377 -147.644345)
			(xy 399.199735 -147.611894) (xy 399.249335 -147.586393) (xy 399.302119 -147.568386) (xy 399.356962 -147.558256)
			(xy 399.412696 -147.556219) (xy 399.468133 -147.562319) (xy 399.52209 -147.576425) (xy 399.573419 -147.598237)
			(xy 399.621025 -147.627291) (xy 399.663893 -147.662966) (xy 399.70111 -147.704503) (xy 399.731883 -147.751016)
			(xy 399.755555 -147.801513) (xy 399.771623 -147.85492) (xy 399.779743 -147.910096) (xy 399.780252 -147.937982)
			(xy 399.779743 -147.965868) (xy 399.771623 -148.021044) (xy 399.755555 -148.074451) (xy 399.731883 -148.124948)
			(xy 399.70111 -148.171461) (xy 399.663893 -148.212998) (xy 399.621025 -148.248673) (xy 399.573419 -148.277727)
			(xy 399.52209 -148.299539) (xy 399.468133 -148.313645) (xy 399.412696 -148.319745) (xy 399.356962 -148.317708)
			(xy 399.302119 -148.307578) (xy 399.249335 -148.289571) (xy 399.199735 -148.26407) (xy 399.154377 -148.231619)
			(xy 399.114228 -148.19291) (xy 399.080142 -148.148767) (xy 399.052846 -148.100132) (xy 399.032923 -148.048041)
			(xy 399.020797 -147.993604) (xy 399.016726 -147.937982) (xy 398.759269 -147.937982) (xy 398.766306 -147.986931)
			(xy 398.766792 -148.014182) (xy 398.766326 -148.041728) (xy 398.75841 -148.096247) (xy 398.742727 -148.149059)
			(xy 398.719603 -148.199062) (xy 398.68952 -148.245215) (xy 398.653105 -148.286555) (xy 398.632426 -148.304758)
			(xy 398.621425 -148.314681) (xy 398.605327 -148.339543) (xy 398.59703 -148.367976) (xy 398.597231 -148.397594)
			(xy 398.605912 -148.425912) (xy 398.622345 -148.450554) (xy 398.645152 -148.469452) (xy 398.658588 -148.4757)
			(xy 398.684099 -148.487036) (xy 398.731775 -148.516077) (xy 398.774711 -148.551755) (xy 398.811989 -148.593309)
			(xy 398.842815 -148.639851) (xy 398.86653 -148.690388) (xy 398.882628 -148.743841) (xy 398.890765 -148.79907)
			(xy 398.891252 -148.826982) (xy 399.016726 -148.826982) (xy 399.020797 -148.77136) (xy 399.032923 -148.716923)
			(xy 399.052846 -148.664832) (xy 399.080142 -148.616197) (xy 399.114228 -148.572054) (xy 399.154377 -148.533345)
			(xy 399.199735 -148.500894) (xy 399.249335 -148.475393) (xy 399.302119 -148.457386) (xy 399.356962 -148.447256)
			(xy 399.412696 -148.445219) (xy 399.468133 -148.451319) (xy 399.52209 -148.465425) (xy 399.573419 -148.487237)
			(xy 399.621025 -148.516291) (xy 399.663893 -148.551966) (xy 399.70111 -148.593503) (xy 399.731883 -148.640016)
			(xy 399.755555 -148.690513) (xy 399.771623 -148.74392) (xy 399.779743 -148.799096) (xy 399.780252 -148.826982)
			(xy 399.779743 -148.854868) (xy 399.771623 -148.910044) (xy 399.755555 -148.963451) (xy 399.731883 -149.013948)
			(xy 399.70111 -149.060461) (xy 399.663893 -149.101998) (xy 399.621025 -149.137673) (xy 399.573419 -149.166727)
			(xy 399.52209 -149.188539) (xy 399.468133 -149.202645) (xy 399.412696 -149.208745) (xy 399.356962 -149.206708)
			(xy 399.302119 -149.196578) (xy 399.249335 -149.178571) (xy 399.199735 -149.15307) (xy 399.154377 -149.120619)
			(xy 399.114228 -149.08191) (xy 399.080142 -149.037767) (xy 399.052846 -148.989132) (xy 399.032923 -148.937041)
			(xy 399.020797 -148.882604) (xy 399.016726 -148.826982) (xy 398.891252 -148.826982) (xy 398.890766 -148.854233)
			(xy 398.88301 -148.908181) (xy 398.867655 -148.960476) (xy 398.845013 -149.010053) (xy 398.815547 -149.055903)
			(xy 398.779856 -149.097094) (xy 398.738665 -149.132785) (xy 398.692815 -149.162251) (xy 398.643238 -149.184893)
			(xy 398.590943 -149.200248) (xy 398.536995 -149.208004) (xy 398.482493 -149.208004) (xy 398.428545 -149.200248)
			(xy 398.37625 -149.184893) (xy 398.326673 -149.162251) (xy 398.280823 -149.132785) (xy 398.239632 -149.097094)
			(xy 398.203941 -149.055903) (xy 398.174475 -149.010053) (xy 398.151833 -148.960476) (xy 398.136478 -148.908181)
			(xy 398.128722 -148.854233) (xy 398.128236 -148.826982) (xy 398.128737 -148.799437) (xy 398.136644 -148.744919)
			(xy 398.15232 -148.692108) (xy 398.175437 -148.642104) (xy 398.205514 -148.595951) (xy 398.241925 -148.55461)
			(xy 398.262602 -148.536406) (xy 398.273524 -148.526404) (xy 398.289618 -148.501561) (xy 398.297918 -148.473148)
			(xy 398.297727 -148.443548) (xy 398.289062 -148.415245) (xy 398.272649 -148.390611) (xy 398.249865 -148.371715)
			(xy 398.23644 -148.365464) (xy 398.210921 -148.354143) (xy 398.163243 -148.325102) (xy 398.120306 -148.289422)
			(xy 398.083027 -148.247867) (xy 398.052202 -148.201322) (xy 398.028489 -148.150782) (xy 398.012394 -148.097326)
			(xy 398.004261 -148.042095) (xy 398.003776 -148.014182) (xy 397.877792 -148.014182) (xy 397.877326 -148.041728)
			(xy 397.86941 -148.096247) (xy 397.853727 -148.149059) (xy 397.830603 -148.199062) (xy 397.80052 -148.245215)
			(xy 397.764105 -148.286555) (xy 397.743426 -148.304758) (xy 397.733266 -148.313394) (xy 397.724122 -148.337778)
			(xy 397.74114 -148.449792) (xy 397.757396 -148.47062) (xy 397.769588 -148.4757) (xy 397.795099 -148.487036)
			(xy 397.842775 -148.516077) (xy 397.885711 -148.551755) (xy 397.922989 -148.593309) (xy 397.953815 -148.639851)
			(xy 397.97753 -148.690388) (xy 397.993628 -148.743841) (xy 398.001765 -148.79907) (xy 398.002252 -148.826982)
			(xy 398.001766 -148.854233) (xy 397.99401 -148.908181) (xy 397.978655 -148.960476) (xy 397.956013 -149.010053)
			(xy 397.926547 -149.055903) (xy 397.890856 -149.097094) (xy 397.849665 -149.132785) (xy 397.803815 -149.162251)
			(xy 397.754238 -149.184893) (xy 397.701943 -149.200248) (xy 397.647995 -149.208004) (xy 397.593493 -149.208004)
			(xy 397.539545 -149.200248) (xy 397.48725 -149.184893) (xy 397.437673 -149.162251) (xy 397.391823 -149.132785)
			(xy 397.350632 -149.097094) (xy 397.314941 -149.055903) (xy 397.285475 -149.010053) (xy 397.262833 -148.960476)
			(xy 397.247478 -148.908181) (xy 397.239722 -148.854233) (xy 397.239236 -148.826982) (xy 397.239737 -148.799437)
			(xy 397.247644 -148.744919) (xy 397.26332 -148.692108) (xy 397.286437 -148.642104) (xy 397.316514 -148.595951)
			(xy 397.352925 -148.55461) (xy 397.373602 -148.536406) (xy 397.383762 -148.52777) (xy 397.392906 -148.503386)
			(xy 397.375888 -148.391372) (xy 397.359632 -148.370544) (xy 397.34744 -148.365464) (xy 397.332538 -148.35893)
			(xy 397.303797 -148.343668) (xy 397.290036 -148.334984) (xy 397.289782 -148.33473) (xy 397.282039 -148.330214)
			(xy 397.264545 -148.326362) (xy 397.246799 -148.328799) (xy 397.238728 -148.332698) (xy 397.160242 -148.374354)
			(xy 397.152577 -148.378895) (xy 397.14069 -148.392146) (xy 397.134023 -148.408653) (xy 397.133318 -148.417534)
			(xy 397.133318 -148.418042) (xy 397.132108 -148.444806) (xy 397.123229 -148.497636) (xy 397.107042 -148.548704)
			(xy 397.083867 -148.597004) (xy 397.054158 -148.641584) (xy 397.018502 -148.681566) (xy 396.9776 -148.716164)
			(xy 396.932258 -148.744696) (xy 396.883369 -148.7666) (xy 396.831895 -148.781445) (xy 396.77885 -148.788939)
			(xy 396.752064 -148.78939) (xy 396.724813 -148.788938) (xy 396.670867 -148.781177) (xy 396.618574 -148.765818)
			(xy 396.568999 -148.743173) (xy 396.523151 -148.713705) (xy 396.481963 -148.678012) (xy 396.446274 -148.63682)
			(xy 396.416809 -148.59097) (xy 396.39417 -148.541392) (xy 396.378816 -148.489098) (xy 396.37106 -148.435151)
			(xy 391.722566 -148.435151) (xy 391.682456 -148.459152) (xy 391.60609 -148.495613) (xy 391.526646 -148.524763)
			(xy 391.444821 -148.546346) (xy 391.361334 -148.560171) (xy 391.27692 -148.566118) (xy 391.192319 -148.564135)
			(xy 391.108277 -148.554237) (xy 391.02553 -148.536514) (xy 390.944806 -148.51112) (xy 390.866815 -148.478278)
			(xy 390.792243 -148.438277) (xy 390.721743 -148.391469) (xy 390.655937 -148.338265) (xy 390.595401 -148.279133)
			(xy 390.540669 -148.214592) (xy 390.492222 -148.145209) (xy 390.450484 -148.071594) (xy 390.415823 -147.994395)
			(xy 390.388543 -147.914289) (xy 390.368885 -147.83198) (xy 390.35702 -147.748193) (xy 390.353054 -147.663662)
			(xy 389.617966 -147.663662) (xy 389.61747 -147.705974) (xy 389.609546 -147.790226) (xy 389.593767 -147.873365)
			(xy 389.570272 -147.954662) (xy 389.539268 -148.033401) (xy 389.501026 -148.108891) (xy 389.455884 -148.180468)
			(xy 389.404237 -148.247504) (xy 389.34654 -148.309409) (xy 389.2833 -148.365639) (xy 389.215072 -148.4157)
			(xy 389.142456 -148.459152) (xy 389.06609 -148.495613) (xy 388.986646 -148.524763) (xy 388.904821 -148.546346)
			(xy 388.821334 -148.560171) (xy 388.73692 -148.566118) (xy 388.652319 -148.564135) (xy 388.568277 -148.554237)
			(xy 388.48553 -148.536514) (xy 388.404806 -148.51112) (xy 388.326815 -148.478278) (xy 388.252243 -148.438277)
			(xy 388.181743 -148.391469) (xy 388.115937 -148.338265) (xy 388.055401 -148.279133) (xy 388.000669 -148.214592)
			(xy 387.952222 -148.145209) (xy 387.910484 -148.071594) (xy 387.875823 -147.994395) (xy 387.848543 -147.914289)
			(xy 387.828885 -147.83198) (xy 387.81702 -147.748193) (xy 387.813054 -147.663662) (xy 385.136898 -147.663662)
			(xy 386.770118 -149.296882) (xy 396.370046 -149.296882) (xy 396.374117 -149.24126) (xy 396.386243 -149.186823)
			(xy 396.406166 -149.134732) (xy 396.433462 -149.086097) (xy 396.467548 -149.041954) (xy 396.507697 -149.003245)
			(xy 396.553055 -148.970794) (xy 396.602655 -148.945293) (xy 396.655439 -148.927286) (xy 396.710282 -148.917156)
			(xy 396.766016 -148.915119) (xy 396.821453 -148.921219) (xy 396.87541 -148.935325) (xy 396.926739 -148.957137)
			(xy 396.974345 -148.986191) (xy 397.017213 -149.021866) (xy 397.05443 -149.063403) (xy 397.085203 -149.109916)
			(xy 397.108875 -149.160413) (xy 397.124943 -149.21382) (xy 397.133063 -149.268996) (xy 397.133572 -149.296882)
			(xy 397.133063 -149.324768) (xy 397.124943 -149.379944) (xy 397.108875 -149.433351) (xy 397.085203 -149.483848)
			(xy 397.05443 -149.530361) (xy 397.017213 -149.571898) (xy 396.974345 -149.607573) (xy 396.926739 -149.636627)
			(xy 396.87541 -149.658439) (xy 396.821453 -149.672545) (xy 396.766016 -149.678645) (xy 396.710282 -149.676608)
			(xy 396.655439 -149.666478) (xy 396.602655 -149.648471) (xy 396.553055 -149.62297) (xy 396.507697 -149.590519)
			(xy 396.467548 -149.55181) (xy 396.433462 -149.507667) (xy 396.406166 -149.459032) (xy 396.386243 -149.406941)
			(xy 396.374117 -149.352504) (xy 396.370046 -149.296882) (xy 386.770118 -149.296882) (xy 387.189218 -149.715982)
			(xy 397.238726 -149.715982) (xy 397.242797 -149.66036) (xy 397.254923 -149.605923) (xy 397.274846 -149.553832)
			(xy 397.302142 -149.505197) (xy 397.336228 -149.461054) (xy 397.376377 -149.422345) (xy 397.421735 -149.389894)
			(xy 397.471335 -149.364393) (xy 397.524119 -149.346386) (xy 397.578962 -149.336256) (xy 397.634696 -149.334219)
			(xy 397.690133 -149.340319) (xy 397.74409 -149.354425) (xy 397.795419 -149.376237) (xy 397.843025 -149.405291)
			(xy 397.885893 -149.440966) (xy 397.92311 -149.482503) (xy 397.953883 -149.529016) (xy 397.977555 -149.579513)
			(xy 397.993623 -149.63292) (xy 398.001743 -149.688096) (xy 398.002252 -149.715982) (xy 398.127726 -149.715982)
			(xy 398.131797 -149.66036) (xy 398.143923 -149.605923) (xy 398.163846 -149.553832) (xy 398.191142 -149.505197)
			(xy 398.225228 -149.461054) (xy 398.265377 -149.422345) (xy 398.310735 -149.389894) (xy 398.360335 -149.364393)
			(xy 398.413119 -149.346386) (xy 398.467962 -149.336256) (xy 398.523696 -149.334219) (xy 398.579133 -149.340319)
			(xy 398.63309 -149.354425) (xy 398.684419 -149.376237) (xy 398.732025 -149.405291) (xy 398.774893 -149.440966)
			(xy 398.81211 -149.482503) (xy 398.842883 -149.529016) (xy 398.866555 -149.579513) (xy 398.882623 -149.63292)
			(xy 398.890743 -149.688096) (xy 398.891252 -149.715982) (xy 399.016726 -149.715982) (xy 399.020797 -149.66036)
			(xy 399.032923 -149.605923) (xy 399.052846 -149.553832) (xy 399.080142 -149.505197) (xy 399.114228 -149.461054)
			(xy 399.154377 -149.422345) (xy 399.199735 -149.389894) (xy 399.249335 -149.364393) (xy 399.302119 -149.346386)
			(xy 399.356962 -149.336256) (xy 399.412696 -149.334219) (xy 399.468133 -149.340319) (xy 399.52209 -149.354425)
			(xy 399.573419 -149.376237) (xy 399.621025 -149.405291) (xy 399.663893 -149.440966) (xy 399.70111 -149.482503)
			(xy 399.731883 -149.529016) (xy 399.755555 -149.579513) (xy 399.771623 -149.63292) (xy 399.779743 -149.688096)
			(xy 399.780252 -149.715982) (xy 399.779743 -149.743868) (xy 399.771623 -149.799044) (xy 399.755555 -149.852451)
			(xy 399.731883 -149.902948) (xy 399.70111 -149.949461) (xy 399.663893 -149.990998) (xy 399.621025 -150.026673)
			(xy 399.573419 -150.055727) (xy 399.52209 -150.077539) (xy 399.468133 -150.091645) (xy 399.412696 -150.097745)
			(xy 399.356962 -150.095708) (xy 399.302119 -150.085578) (xy 399.249335 -150.067571) (xy 399.199735 -150.04207)
			(xy 399.154377 -150.009619) (xy 399.114228 -149.97091) (xy 399.080142 -149.926767) (xy 399.052846 -149.878132)
			(xy 399.032923 -149.826041) (xy 399.020797 -149.771604) (xy 399.016726 -149.715982) (xy 398.891252 -149.715982)
			(xy 398.890743 -149.743868) (xy 398.882623 -149.799044) (xy 398.866555 -149.852451) (xy 398.842883 -149.902948)
			(xy 398.81211 -149.949461) (xy 398.774893 -149.990998) (xy 398.732025 -150.026673) (xy 398.684419 -150.055727)
			(xy 398.63309 -150.077539) (xy 398.579133 -150.091645) (xy 398.523696 -150.097745) (xy 398.467962 -150.095708)
			(xy 398.413119 -150.085578) (xy 398.360335 -150.067571) (xy 398.310735 -150.04207) (xy 398.265377 -150.009619)
			(xy 398.225228 -149.97091) (xy 398.191142 -149.926767) (xy 398.163846 -149.878132) (xy 398.143923 -149.826041)
			(xy 398.131797 -149.771604) (xy 398.127726 -149.715982) (xy 398.002252 -149.715982) (xy 398.001743 -149.743868)
			(xy 397.993623 -149.799044) (xy 397.977555 -149.852451) (xy 397.953883 -149.902948) (xy 397.92311 -149.949461)
			(xy 397.885893 -149.990998) (xy 397.843025 -150.026673) (xy 397.795419 -150.055727) (xy 397.74409 -150.077539)
			(xy 397.690133 -150.091645) (xy 397.634696 -150.097745) (xy 397.578962 -150.095708) (xy 397.524119 -150.085578)
			(xy 397.471335 -150.067571) (xy 397.421735 -150.04207) (xy 397.376377 -150.009619) (xy 397.336228 -149.97091)
			(xy 397.302142 -149.926767) (xy 397.274846 -149.878132) (xy 397.254923 -149.826041) (xy 397.242797 -149.771604)
			(xy 397.238726 -149.715982) (xy 387.189218 -149.715982) (xy 390.12368 -152.650444) (xy 408.315158 -152.650444)
			(xy 408.319229 -152.594822) (xy 408.331355 -152.540385) (xy 408.351278 -152.488294) (xy 408.378574 -152.439659)
			(xy 408.41266 -152.395516) (xy 408.452809 -152.356807) (xy 408.498167 -152.324356) (xy 408.547767 -152.298855)
			(xy 408.600551 -152.280848) (xy 408.655394 -152.270718) (xy 408.711128 -152.268681) (xy 408.766565 -152.274781)
			(xy 408.820522 -152.288887) (xy 408.871851 -152.310699) (xy 408.919457 -152.339753) (xy 408.962325 -152.375428)
			(xy 408.99872 -152.416048) (xy 419.022302 -152.416048) (xy 419.022302 -152.361552) (xy 419.030058 -152.307609)
			(xy 419.04541 -152.25532) (xy 419.068048 -152.205747) (xy 419.097511 -152.159901) (xy 419.133197 -152.118714)
			(xy 419.174382 -152.083025) (xy 419.220226 -152.05356) (xy 419.269797 -152.030919) (xy 419.322086 -152.015563)
			(xy 419.376028 -152.007804) (xy 419.403276 -152.007316) (xy 419.432193 -152.007846) (xy 419.489364 -152.016571)
			(xy 419.544562 -152.033827) (xy 419.596524 -152.059216) (xy 419.644058 -152.092158) (xy 419.686076 -152.131897)
			(xy 419.704266 -152.154382) (xy 419.711884 -152.163178) (xy 419.732777 -152.173364) (xy 419.744398 -152.17394)
			(xy 419.824154 -152.17394) (xy 419.835791 -152.173439) (xy 419.856702 -152.163225) (xy 419.864286 -152.154382)
			(xy 419.881039 -152.133599) (xy 419.919393 -152.096469) (xy 419.962547 -152.065047) (xy 420.009661 -152.039948)
			(xy 420.059813 -152.021662) (xy 420.112024 -152.010545) (xy 420.165276 -152.006815) (xy 420.218528 -152.010545)
			(xy 420.270739 -152.021662) (xy 420.320891 -152.039948) (xy 420.368005 -152.065047) (xy 420.411159 -152.096469)
			(xy 420.449513 -152.133599) (xy 420.466266 -152.154382) (xy 420.473884 -152.163178) (xy 420.494777 -152.173364)
			(xy 420.506398 -152.17394) (xy 420.586154 -152.17394) (xy 420.597791 -152.173439) (xy 420.618702 -152.163225)
			(xy 420.626286 -152.154382) (xy 420.643039 -152.133599) (xy 420.681393 -152.096469) (xy 420.724547 -152.065047)
			(xy 420.771661 -152.039948) (xy 420.821813 -152.021662) (xy 420.874024 -152.010545) (xy 420.927276 -152.006815)
			(xy 420.980528 -152.010545) (xy 421.032739 -152.021662) (xy 421.082891 -152.039948) (xy 421.130005 -152.065047)
			(xy 421.173159 -152.096469) (xy 421.211513 -152.133599) (xy 421.228266 -152.154382) (xy 421.235884 -152.163178)
			(xy 421.256777 -152.173364) (xy 421.268398 -152.17394) (xy 421.348154 -152.17394) (xy 421.359791 -152.173439)
			(xy 421.380702 -152.163225) (xy 421.388286 -152.154382) (xy 421.40648 -152.131901) (xy 421.4485 -152.092167)
			(xy 421.496034 -152.059228) (xy 421.547995 -152.033839) (xy 421.603192 -152.016582) (xy 421.66036 -152.007852)
			(xy 421.689276 -152.007316) (xy 421.716532 -152.007729) (xy 421.770489 -152.015484) (xy 421.822793 -152.030839)
			(xy 421.872379 -152.053481) (xy 421.918238 -152.082951) (xy 421.959436 -152.118647) (xy 421.995135 -152.159843)
			(xy 422.024607 -152.2057) (xy 422.047253 -152.255285) (xy 422.062611 -152.307588) (xy 422.070369 -152.361544)
			(xy 422.070369 -152.416056) (xy 422.062611 -152.470012) (xy 422.047253 -152.522315) (xy 422.024607 -152.5719)
			(xy 421.995135 -152.617757) (xy 421.959436 -152.658953) (xy 421.918238 -152.694649) (xy 421.872379 -152.724119)
			(xy 421.822793 -152.746761) (xy 421.770489 -152.762116) (xy 421.716532 -152.769871) (xy 421.689276 -152.770332)
			(xy 421.66036 -152.769785) (xy 421.603189 -152.761065) (xy 421.54799 -152.743815) (xy 421.496027 -152.718429)
			(xy 421.448493 -152.685489) (xy 421.406476 -152.64575) (xy 421.388286 -152.623266) (xy 421.380681 -152.614457)
			(xy 421.359778 -152.604276) (xy 421.348154 -152.603708) (xy 421.268398 -152.603708) (xy 421.256767 -152.604257)
			(xy 421.235857 -152.614439) (xy 421.228266 -152.623266) (xy 421.211513 -152.644049) (xy 421.173159 -152.681179)
			(xy 421.130005 -152.712601) (xy 421.082891 -152.7377) (xy 421.032739 -152.755986) (xy 420.980528 -152.767103)
			(xy 420.927276 -152.770833) (xy 420.874024 -152.767103) (xy 420.821813 -152.755986) (xy 420.771661 -152.7377)
			(xy 420.724547 -152.712601) (xy 420.681393 -152.681179) (xy 420.643039 -152.644049) (xy 420.626286 -152.623266)
			(xy 420.618681 -152.614457) (xy 420.597778 -152.604276) (xy 420.586154 -152.603708) (xy 420.506398 -152.603708)
			(xy 420.494767 -152.604257) (xy 420.473857 -152.614439) (xy 420.466266 -152.623266) (xy 420.449513 -152.644049)
			(xy 420.411159 -152.681179) (xy 420.368005 -152.712601) (xy 420.320891 -152.7377) (xy 420.270739 -152.755986)
			(xy 420.218528 -152.767103) (xy 420.165276 -152.770833) (xy 420.112024 -152.767103) (xy 420.059813 -152.755986)
			(xy 420.009661 -152.7377) (xy 419.962547 -152.712601) (xy 419.919393 -152.681179) (xy 419.881039 -152.644049)
			(xy 419.864286 -152.623266) (xy 419.856681 -152.614457) (xy 419.835778 -152.604276) (xy 419.824154 -152.603708)
			(xy 419.744398 -152.603708) (xy 419.732767 -152.604257) (xy 419.711857 -152.614439) (xy 419.704266 -152.623266)
			(xy 419.686086 -152.645759) (xy 419.644065 -152.685495) (xy 419.596528 -152.718434) (xy 419.544564 -152.743821)
			(xy 419.489364 -152.761075) (xy 419.432193 -152.7698) (xy 419.403276 -152.770332) (xy 419.376028 -152.769796)
			(xy 419.322086 -152.762037) (xy 419.269797 -152.746681) (xy 419.220226 -152.72404) (xy 419.174382 -152.694575)
			(xy 419.133197 -152.658886) (xy 419.097511 -152.617699) (xy 419.068048 -152.571853) (xy 419.04541 -152.52228)
			(xy 419.030058 -152.469991) (xy 419.022302 -152.416048) (xy 408.99872 -152.416048) (xy 408.999542 -152.416965)
			(xy 409.030315 -152.463478) (xy 409.053987 -152.513975) (xy 409.070055 -152.567382) (xy 409.078175 -152.622558)
			(xy 409.078684 -152.650444) (xy 409.078175 -152.67833) (xy 409.070055 -152.733506) (xy 409.053987 -152.786913)
			(xy 409.030315 -152.83741) (xy 408.999542 -152.883923) (xy 408.962325 -152.92546) (xy 408.919457 -152.961135)
			(xy 408.871851 -152.990189) (xy 408.820522 -153.012001) (xy 408.766565 -153.026107) (xy 408.711128 -153.032207)
			(xy 408.655394 -153.03017) (xy 408.600551 -153.02004) (xy 408.547767 -153.002033) (xy 408.498167 -152.976532)
			(xy 408.452809 -152.944081) (xy 408.41266 -152.905372) (xy 408.378574 -152.861229) (xy 408.351278 -152.812594)
			(xy 408.331355 -152.760503) (xy 408.319229 -152.706066) (xy 408.315158 -152.650444) (xy 390.12368 -152.650444)
			(xy 390.639046 -153.16581) (xy 411.48203 -153.16581) (xy 411.486101 -153.110188) (xy 411.498227 -153.055751)
			(xy 411.51815 -153.00366) (xy 411.545446 -152.955025) (xy 411.579532 -152.910882) (xy 411.619681 -152.872173)
			(xy 411.665039 -152.839722) (xy 411.714639 -152.814221) (xy 411.767423 -152.796214) (xy 411.822266 -152.786084)
			(xy 411.878 -152.784047) (xy 411.933437 -152.790147) (xy 411.987394 -152.804253) (xy 412.038723 -152.826065)
			(xy 412.086329 -152.855119) (xy 412.129197 -152.890794) (xy 412.166414 -152.932331) (xy 412.197187 -152.978844)
			(xy 412.220859 -153.029341) (xy 412.236927 -153.082748) (xy 412.245047 -153.137924) (xy 412.245556 -153.16581)
			(xy 412.37103 -153.16581) (xy 412.375101 -153.110188) (xy 412.387227 -153.055751) (xy 412.40715 -153.00366)
			(xy 412.434446 -152.955025) (xy 412.468532 -152.910882) (xy 412.508681 -152.872173) (xy 412.554039 -152.839722)
			(xy 412.603639 -152.814221) (xy 412.656423 -152.796214) (xy 412.711266 -152.786084) (xy 412.767 -152.784047)
			(xy 412.822437 -152.790147) (xy 412.876394 -152.804253) (xy 412.927723 -152.826065) (xy 412.975329 -152.855119)
			(xy 413.018197 -152.890794) (xy 413.055414 -152.932331) (xy 413.086187 -152.978844) (xy 413.109859 -153.029341)
			(xy 413.125927 -153.082748) (xy 413.134047 -153.137924) (xy 413.134556 -153.16581) (xy 413.26003 -153.16581)
			(xy 413.264101 -153.110188) (xy 413.276227 -153.055751) (xy 413.29615 -153.00366) (xy 413.323446 -152.955025)
			(xy 413.357532 -152.910882) (xy 413.397681 -152.872173) (xy 413.443039 -152.839722) (xy 413.492639 -152.814221)
			(xy 413.545423 -152.796214) (xy 413.600266 -152.786084) (xy 413.656 -152.784047) (xy 413.711437 -152.790147)
			(xy 413.765394 -152.804253) (xy 413.816723 -152.826065) (xy 413.864329 -152.855119) (xy 413.907197 -152.890794)
			(xy 413.944414 -152.932331) (xy 413.975187 -152.978844) (xy 413.998859 -153.029341) (xy 414.014927 -153.082748)
			(xy 414.023047 -153.137924) (xy 414.023556 -153.16581) (xy 414.14903 -153.16581) (xy 414.153101 -153.110188)
			(xy 414.165227 -153.055751) (xy 414.18515 -153.00366) (xy 414.212446 -152.955025) (xy 414.246532 -152.910882)
			(xy 414.286681 -152.872173) (xy 414.332039 -152.839722) (xy 414.381639 -152.814221) (xy 414.434423 -152.796214)
			(xy 414.489266 -152.786084) (xy 414.545 -152.784047) (xy 414.600437 -152.790147) (xy 414.654394 -152.804253)
			(xy 414.705723 -152.826065) (xy 414.753329 -152.855119) (xy 414.796197 -152.890794) (xy 414.833414 -152.932331)
			(xy 414.864187 -152.978844) (xy 414.887859 -153.029341) (xy 414.903927 -153.082748) (xy 414.912047 -153.137924)
			(xy 414.912556 -153.16581) (xy 414.912047 -153.193696) (xy 414.903927 -153.248872) (xy 414.887859 -153.302279)
			(xy 414.864187 -153.352776) (xy 414.833414 -153.399289) (xy 414.796197 -153.440826) (xy 414.753329 -153.476501)
			(xy 414.705723 -153.505555) (xy 414.654394 -153.527367) (xy 414.600437 -153.541473) (xy 414.545 -153.547573)
			(xy 414.489266 -153.545536) (xy 414.434423 -153.535406) (xy 414.381639 -153.517399) (xy 414.332039 -153.491898)
			(xy 414.286681 -153.459447) (xy 414.246532 -153.420738) (xy 414.212446 -153.376595) (xy 414.18515 -153.32796)
			(xy 414.165227 -153.275869) (xy 414.153101 -153.221432) (xy 414.14903 -153.16581) (xy 414.023556 -153.16581)
			(xy 414.023047 -153.193696) (xy 414.014927 -153.248872) (xy 413.998859 -153.302279) (xy 413.975187 -153.352776)
			(xy 413.944414 -153.399289) (xy 413.907197 -153.440826) (xy 413.864329 -153.476501) (xy 413.816723 -153.505555)
			(xy 413.765394 -153.527367) (xy 413.711437 -153.541473) (xy 413.656 -153.547573) (xy 413.600266 -153.545536)
			(xy 413.545423 -153.535406) (xy 413.492639 -153.517399) (xy 413.443039 -153.491898) (xy 413.397681 -153.459447)
			(xy 413.357532 -153.420738) (xy 413.323446 -153.376595) (xy 413.29615 -153.32796) (xy 413.276227 -153.275869)
			(xy 413.264101 -153.221432) (xy 413.26003 -153.16581) (xy 413.134556 -153.16581) (xy 413.134047 -153.193696)
			(xy 413.125927 -153.248872) (xy 413.109859 -153.302279) (xy 413.086187 -153.352776) (xy 413.055414 -153.399289)
			(xy 413.018197 -153.440826) (xy 412.975329 -153.476501) (xy 412.927723 -153.505555) (xy 412.876394 -153.527367)
			(xy 412.822437 -153.541473) (xy 412.767 -153.547573) (xy 412.711266 -153.545536) (xy 412.656423 -153.535406)
			(xy 412.603639 -153.517399) (xy 412.554039 -153.491898) (xy 412.508681 -153.459447) (xy 412.468532 -153.420738)
			(xy 412.434446 -153.376595) (xy 412.40715 -153.32796) (xy 412.387227 -153.275869) (xy 412.375101 -153.221432)
			(xy 412.37103 -153.16581) (xy 412.245556 -153.16581) (xy 412.245047 -153.193696) (xy 412.236927 -153.248872)
			(xy 412.220859 -153.302279) (xy 412.197187 -153.352776) (xy 412.166414 -153.399289) (xy 412.129197 -153.440826)
			(xy 412.086329 -153.476501) (xy 412.038723 -153.505555) (xy 411.987394 -153.527367) (xy 411.933437 -153.541473)
			(xy 411.878 -153.547573) (xy 411.822266 -153.545536) (xy 411.767423 -153.535406) (xy 411.714639 -153.517399)
			(xy 411.665039 -153.491898) (xy 411.619681 -153.459447) (xy 411.579532 -153.420738) (xy 411.545446 -153.376595)
			(xy 411.51815 -153.32796) (xy 411.498227 -153.275869) (xy 411.486101 -153.221432) (xy 411.48203 -153.16581)
			(xy 390.639046 -153.16581) (xy 392.956034 -155.482798) (xy 410.680916 -155.482798) (xy 410.681427 -155.453881)
			(xy 410.690157 -155.396709) (xy 410.707416 -155.34151) (xy 410.732809 -155.289548) (xy 410.765754 -155.242014)
			(xy 410.805496 -155.199998) (xy 410.827982 -155.181808) (xy 410.836789 -155.174202) (xy 410.84697 -155.1533)
			(xy 410.84754 -155.141676) (xy 410.84754 -155.06192) (xy 410.846996 -155.050288) (xy 410.836813 -155.029377)
			(xy 410.827982 -155.021788) (xy 410.805489 -155.003608) (xy 410.765755 -154.961586) (xy 410.732818 -154.914048)
			(xy 410.707431 -154.862085) (xy 410.690177 -154.806886) (xy 410.68145 -154.749715) (xy 410.680916 -154.720798)
			(xy 410.681355 -154.694076) (xy 410.688826 -154.641156) (xy 410.703609 -154.589796) (xy 410.725413 -154.541001)
			(xy 410.753813 -154.495726) (xy 410.788252 -154.454857) (xy 410.828056 -154.419193) (xy 410.872448 -154.389431)
			(xy 410.896308 -154.37739) (xy 410.909262 -154.371294) (xy 410.924502 -154.347164) (xy 410.926788 -154.242262)
			(xy 410.926562 -154.233041) (xy 410.920401 -154.215674) (xy 410.908492 -154.201611) (xy 410.900626 -154.196796)
			(xy 410.900626 -154.196542) (xy 410.900118 -154.196542) (xy 410.874667 -154.182092) (xy 410.828118 -154.146621)
			(xy 410.787529 -154.104459) (xy 410.753851 -154.056597) (xy 410.727874 -154.004154) (xy 410.710207 -153.94836)
			(xy 410.701264 -153.890524) (xy 410.700728 -153.861262) (xy 410.701214 -153.834011) (xy 410.70897 -153.780063)
			(xy 410.724325 -153.727768) (xy 410.746967 -153.678191) (xy 410.776433 -153.632341) (xy 410.812124 -153.59115)
			(xy 410.853315 -153.555459) (xy 410.899165 -153.525993) (xy 410.948742 -153.503351) (xy 411.001037 -153.487996)
			(xy 411.054985 -153.48024) (xy 411.109487 -153.48024) (xy 411.163435 -153.487996) (xy 411.21573 -153.503351)
			(xy 411.265307 -153.525993) (xy 411.311157 -153.555459) (xy 411.352348 -153.59115) (xy 411.388039 -153.632341)
			(xy 411.417505 -153.678191) (xy 411.440147 -153.727768) (xy 411.455502 -153.780063) (xy 411.463258 -153.834011)
			(xy 411.463744 -153.861262) (xy 411.463294 -153.887984) (xy 411.455828 -153.940905) (xy 411.441048 -153.992265)
			(xy 411.419247 -154.041061) (xy 411.390848 -154.086337) (xy 411.35641 -154.127206) (xy 411.316605 -154.16287)
			(xy 411.272212 -154.19263) (xy 411.248352 -154.20467) (xy 411.235398 -154.210766) (xy 411.220158 -154.234896)
			(xy 411.217872 -154.339798) (xy 411.218025 -154.349025) (xy 411.224214 -154.366399) (xy 411.236154 -154.380457)
			(xy 411.244034 -154.385264) (xy 411.244034 -154.385518) (xy 411.244542 -154.385518) (xy 411.270009 -154.399941)
			(xy 411.316561 -154.435415) (xy 411.357151 -154.477579) (xy 411.390828 -154.525447) (xy 411.416802 -154.577895)
			(xy 411.434464 -154.633693) (xy 411.4434 -154.691534) (xy 411.443932 -154.720798) (xy 411.443438 -154.749716)
			(xy 411.434708 -154.80689) (xy 411.417447 -154.86209) (xy 411.39205 -154.914052) (xy 411.359101 -154.961585)
			(xy 411.319354 -155.0036) (xy 411.296866 -155.021788) (xy 411.288069 -155.029404) (xy 411.277881 -155.050298)
			(xy 411.277308 -155.06192) (xy 411.277308 -155.141676) (xy 411.277873 -155.153305) (xy 411.288043 -155.174215)
			(xy 411.296866 -155.181808) (xy 411.319346 -155.200003) (xy 411.359083 -155.242021) (xy 411.392024 -155.289555)
			(xy 411.417413 -155.341515) (xy 411.434669 -155.396713) (xy 411.443398 -155.453882) (xy 411.443932 -155.482798)
			(xy 411.443446 -155.510049) (xy 411.43569 -155.563997) (xy 411.431713 -155.57754) (xy 415.148268 -155.57754)
			(xy 415.148789 -155.548623) (xy 415.157514 -155.491451) (xy 415.17477 -155.436251) (xy 415.200161 -155.384288)
			(xy 415.233105 -155.336755) (xy 415.272847 -155.294739) (xy 415.295334 -155.27655) (xy 415.304114 -155.268917)
			(xy 415.314311 -155.248036) (xy 415.314892 -155.236418) (xy 415.314892 -155.156662) (xy 415.314363 -155.145029)
			(xy 415.304167 -155.124119) (xy 415.295334 -155.11653) (xy 415.272872 -155.098313) (xy 415.233134 -155.0563)
			(xy 415.200191 -155.008771) (xy 415.174799 -154.956814) (xy 415.157538 -154.901621) (xy 415.148805 -154.844455)
			(xy 415.148268 -154.81554) (xy 415.148712 -154.788817) (xy 415.156179 -154.735896) (xy 415.170959 -154.684535)
			(xy 415.192761 -154.635739) (xy 415.22116 -154.590464) (xy 415.2556 -154.549594) (xy 415.295406 -154.513931)
			(xy 415.339799 -154.484172) (xy 415.36366 -154.472132) (xy 415.376614 -154.466036) (xy 415.391854 -154.441906)
			(xy 415.39414 -154.337004) (xy 415.393979 -154.327778) (xy 415.387793 -154.310404) (xy 415.375856 -154.296346)
			(xy 415.367978 -154.291538) (xy 415.367978 -154.291284) (xy 415.36747 -154.291284) (xy 415.342006 -154.276855)
			(xy 415.295454 -154.241383) (xy 415.254863 -154.199219) (xy 415.221186 -154.151353) (xy 415.195211 -154.098906)
			(xy 415.177549 -154.043108) (xy 415.168612 -153.985267) (xy 415.16808 -153.956004) (xy 415.168566 -153.928753)
			(xy 415.176322 -153.874805) (xy 415.191677 -153.82251) (xy 415.214319 -153.772933) (xy 415.243785 -153.727083)
			(xy 415.279476 -153.685892) (xy 415.320667 -153.650201) (xy 415.366517 -153.620735) (xy 415.416094 -153.598093)
			(xy 415.468389 -153.582738) (xy 415.522337 -153.574982) (xy 415.576839 -153.574982) (xy 415.630787 -153.582738)
			(xy 415.683082 -153.598093) (xy 415.732659 -153.620735) (xy 415.778509 -153.650201) (xy 415.8197 -153.685892)
			(xy 415.855391 -153.727083) (xy 415.884857 -153.772933) (xy 415.907499 -153.82251) (xy 415.922854 -153.874805)
			(xy 415.93061 -153.928753) (xy 415.931096 -153.956004) (xy 415.930652 -153.982726) (xy 415.923181 -154.035646)
			(xy 415.908398 -154.087005) (xy 415.886595 -154.135799) (xy 415.858196 -154.181074) (xy 415.823758 -154.221944)
			(xy 415.783954 -154.257608) (xy 415.739563 -154.28737) (xy 415.715704 -154.299412) (xy 415.70275 -154.305508)
			(xy 415.68751 -154.329638) (xy 415.685224 -154.43454) (xy 415.685444 -154.443761) (xy 415.691606 -154.46113)
			(xy 415.703519 -154.475192) (xy 415.711386 -154.480006) (xy 415.711386 -154.48026) (xy 415.711894 -154.48026)
			(xy 415.737333 -154.494728) (xy 415.783878 -154.530198) (xy 415.824464 -154.572357) (xy 415.858138 -154.620218)
			(xy 415.884112 -154.672657) (xy 415.901777 -154.728447) (xy 415.910719 -154.78628) (xy 415.911284 -154.81554)
			(xy 415.911053 -154.82755) (xy 419.022278 -154.82755) (xy 419.022278 -154.77305) (xy 419.030034 -154.719104)
			(xy 419.045388 -154.666811) (xy 419.068027 -154.617236) (xy 419.097491 -154.571386) (xy 419.13318 -154.530197)
			(xy 419.174367 -154.494505) (xy 419.220215 -154.465038) (xy 419.269789 -154.442396) (xy 419.322081 -154.427039)
			(xy 419.376026 -154.419279) (xy 419.403276 -154.418792) (xy 419.432194 -154.419293) (xy 419.489368 -154.42802)
			(xy 419.544568 -154.445279) (xy 419.596531 -154.470674) (xy 419.644064 -154.503623) (xy 419.686078 -154.543369)
			(xy 419.704266 -154.565858) (xy 419.711888 -154.57465) (xy 419.732778 -154.584839) (xy 419.744398 -154.585416)
			(xy 419.824154 -154.585416) (xy 419.835787 -154.584888) (xy 419.856696 -154.574691) (xy 419.864286 -154.565858)
			(xy 419.881039 -154.545075) (xy 419.919393 -154.507945) (xy 419.962547 -154.476523) (xy 420.009661 -154.451424)
			(xy 420.059813 -154.433138) (xy 420.112024 -154.422021) (xy 420.165276 -154.418291) (xy 420.218528 -154.422021)
			(xy 420.270739 -154.433138) (xy 420.320891 -154.451424) (xy 420.368005 -154.476523) (xy 420.411159 -154.507945)
			(xy 420.449513 -154.545075) (xy 420.466266 -154.565858) (xy 420.473888 -154.57465) (xy 420.494778 -154.584839)
			(xy 420.506398 -154.585416) (xy 420.586154 -154.585416) (xy 420.597787 -154.584888) (xy 420.618696 -154.574691)
			(xy 420.626286 -154.565858) (xy 420.643039 -154.545075) (xy 420.681393 -154.507945) (xy 420.724547 -154.476523)
			(xy 420.771661 -154.451424) (xy 420.821813 -154.433138) (xy 420.874024 -154.422021) (xy 420.927276 -154.418291)
			(xy 420.980528 -154.422021) (xy 421.032739 -154.433138) (xy 421.082891 -154.451424) (xy 421.130005 -154.476523)
			(xy 421.173159 -154.507945) (xy 421.211513 -154.545075) (xy 421.228266 -154.565858) (xy 421.235888 -154.57465)
			(xy 421.256778 -154.584839) (xy 421.268398 -154.585416) (xy 421.348154 -154.585416) (xy 421.359787 -154.584888)
			(xy 421.380696 -154.574691) (xy 421.388286 -154.565858) (xy 421.406474 -154.543372) (xy 421.448496 -154.503639)
			(xy 421.496032 -154.470702) (xy 421.547993 -154.445314) (xy 421.603191 -154.428058) (xy 421.66036 -154.419328)
			(xy 421.689276 -154.418792) (xy 421.71653 -154.419254) (xy 421.770483 -154.427008) (xy 421.822784 -154.442362)
			(xy 421.872367 -154.465003) (xy 421.918223 -154.49447) (xy 421.959419 -154.530164) (xy 421.995115 -154.571357)
			(xy 422.024586 -154.617212) (xy 422.04723 -154.666793) (xy 422.062587 -154.719093) (xy 422.070345 -154.773046)
			(xy 422.070345 -154.827554) (xy 422.062587 -154.881507) (xy 422.04723 -154.933807) (xy 422.024586 -154.983388)
			(xy 421.995115 -155.029243) (xy 421.959419 -155.070436) (xy 421.918223 -155.10613) (xy 421.872367 -155.135597)
			(xy 421.822784 -155.158238) (xy 421.770483 -155.173592) (xy 421.71653 -155.181346) (xy 421.689276 -155.181808)
			(xy 421.660359 -155.18127) (xy 421.603188 -155.17255) (xy 421.547988 -155.155298) (xy 421.496025 -155.12991)
			(xy 421.448491 -155.096968) (xy 421.406475 -155.057228) (xy 421.388286 -155.034742) (xy 421.380685 -155.025929)
			(xy 421.359779 -155.015751) (xy 421.348154 -155.015184) (xy 421.268398 -155.015184) (xy 421.256769 -155.015742)
			(xy 421.235859 -155.025918) (xy 421.228266 -155.034742) (xy 421.211513 -155.055525) (xy 421.173159 -155.092655)
			(xy 421.130005 -155.124077) (xy 421.082891 -155.149176) (xy 421.032739 -155.167462) (xy 420.980528 -155.178579)
			(xy 420.927276 -155.182309) (xy 420.874024 -155.178579) (xy 420.821813 -155.167462) (xy 420.771661 -155.149176)
			(xy 420.724547 -155.124077) (xy 420.681393 -155.092655) (xy 420.643039 -155.055525) (xy 420.626286 -155.034742)
			(xy 420.618685 -155.025929) (xy 420.597779 -155.015751) (xy 420.586154 -155.015184) (xy 420.506398 -155.015184)
			(xy 420.494769 -155.015742) (xy 420.473859 -155.025918) (xy 420.466266 -155.034742) (xy 420.449513 -155.055525)
			(xy 420.411159 -155.092655) (xy 420.368005 -155.124077) (xy 420.320891 -155.149176) (xy 420.270739 -155.167462)
			(xy 420.218528 -155.178579) (xy 420.165276 -155.182309) (xy 420.112024 -155.178579) (xy 420.059813 -155.167462)
			(xy 420.009661 -155.149176) (xy 419.962547 -155.124077) (xy 419.919393 -155.092655) (xy 419.881039 -155.055525)
			(xy 419.864286 -155.034742) (xy 419.856685 -155.025929) (xy 419.835779 -155.015751) (xy 419.824154 -155.015184)
			(xy 419.744398 -155.015184) (xy 419.732769 -155.015742) (xy 419.711859 -155.025918) (xy 419.704266 -155.034742)
			(xy 419.686105 -155.057251) (xy 419.644078 -155.096982) (xy 419.596536 -155.129917) (xy 419.544569 -155.155301)
			(xy 419.489367 -155.172552) (xy 419.432194 -155.181276) (xy 419.403276 -155.181808) (xy 419.376026 -155.181321)
			(xy 419.322081 -155.173561) (xy 419.269789 -155.158204) (xy 419.220215 -155.135562) (xy 419.174367 -155.106095)
			(xy 419.13318 -155.070403) (xy 419.097491 -155.029214) (xy 419.068027 -154.983364) (xy 419.045388 -154.933789)
			(xy 419.030034 -154.881496) (xy 419.022278 -154.82755) (xy 415.911053 -154.82755) (xy 415.910729 -154.844456)
			(xy 415.902008 -154.901625) (xy 415.884758 -154.956824) (xy 415.859373 -155.008786) (xy 415.826436 -155.056321)
			(xy 415.786701 -155.098339) (xy 415.764218 -155.11653) (xy 415.755393 -155.12412) (xy 415.745222 -155.145034)
			(xy 415.74466 -155.156662) (xy 415.74466 -155.236418) (xy 415.745182 -155.248053) (xy 415.755381 -155.268963)
			(xy 415.764218 -155.27655) (xy 415.786681 -155.294765) (xy 415.826417 -155.33678) (xy 415.859358 -155.38431)
			(xy 415.884749 -155.436267) (xy 415.90201 -155.49146) (xy 415.910745 -155.548625) (xy 415.911284 -155.57754)
			(xy 415.910798 -155.604791) (xy 415.903042 -155.658739) (xy 415.887687 -155.711034) (xy 415.865045 -155.760611)
			(xy 415.835579 -155.806461) (xy 415.799888 -155.847652) (xy 415.758697 -155.883343) (xy 415.712847 -155.912809)
			(xy 415.66327 -155.935451) (xy 415.610975 -155.950806) (xy 415.557027 -155.958562) (xy 415.502525 -155.958562)
			(xy 415.448577 -155.950806) (xy 415.396282 -155.935451) (xy 415.346705 -155.912809) (xy 415.300855 -155.883343)
			(xy 415.259664 -155.847652) (xy 415.223973 -155.806461) (xy 415.194507 -155.760611) (xy 415.171865 -155.711034)
			(xy 415.15651 -155.658739) (xy 415.148754 -155.604791) (xy 415.148268 -155.57754) (xy 411.431713 -155.57754)
			(xy 411.420335 -155.616292) (xy 411.397693 -155.665869) (xy 411.368227 -155.711719) (xy 411.332536 -155.75291)
			(xy 411.291345 -155.788601) (xy 411.245495 -155.818067) (xy 411.195918 -155.840709) (xy 411.143623 -155.856064)
			(xy 411.089675 -155.86382) (xy 411.035173 -155.86382) (xy 410.981225 -155.856064) (xy 410.92893 -155.840709)
			(xy 410.879353 -155.818067) (xy 410.833503 -155.788601) (xy 410.792312 -155.75291) (xy 410.756621 -155.711719)
			(xy 410.727155 -155.665869) (xy 410.704513 -155.616292) (xy 410.689158 -155.563997) (xy 410.681402 -155.510049)
			(xy 410.680916 -155.482798) (xy 392.956034 -155.482798) (xy 394.070078 -156.596842) (xy 419.77132 -156.596842)
			(xy 419.775391 -156.54122) (xy 419.787517 -156.486783) (xy 419.80744 -156.434692) (xy 419.834736 -156.386057)
			(xy 419.868822 -156.341914) (xy 419.908971 -156.303205) (xy 419.954329 -156.270754) (xy 420.003929 -156.245253)
			(xy 420.056713 -156.227246) (xy 420.111556 -156.217116) (xy 420.16729 -156.215079) (xy 420.222727 -156.221179)
			(xy 420.276684 -156.235285) (xy 420.328013 -156.257097) (xy 420.375619 -156.286151) (xy 420.418487 -156.321826)
			(xy 420.455704 -156.363363) (xy 420.486477 -156.409876) (xy 420.510149 -156.460373) (xy 420.526217 -156.51378)
			(xy 420.534337 -156.568956) (xy 420.534846 -156.596842) (xy 420.534337 -156.624728) (xy 420.526217 -156.679904)
			(xy 420.510149 -156.733311) (xy 420.486477 -156.783808) (xy 420.455704 -156.830321) (xy 420.418487 -156.871858)
			(xy 420.375619 -156.907533) (xy 420.328013 -156.936587) (xy 420.276684 -156.958399) (xy 420.222727 -156.972505)
			(xy 420.16729 -156.978605) (xy 420.111556 -156.976568) (xy 420.056713 -156.966438) (xy 420.003929 -156.948431)
			(xy 419.954329 -156.92293) (xy 419.908971 -156.890479) (xy 419.868822 -156.85177) (xy 419.834736 -156.807627)
			(xy 419.80744 -156.758992) (xy 419.787517 -156.706901) (xy 419.775391 -156.652464) (xy 419.77132 -156.596842)
			(xy 394.070078 -156.596842) (xy 394.69187 -157.218634) (xy 417.996114 -157.218634) (xy 418.000185 -157.163012)
			(xy 418.012311 -157.108575) (xy 418.032234 -157.056484) (xy 418.05953 -157.007849) (xy 418.093616 -156.963706)
			(xy 418.133765 -156.924997) (xy 418.179123 -156.892546) (xy 418.228723 -156.867045) (xy 418.281507 -156.849038)
			(xy 418.33635 -156.838908) (xy 418.392084 -156.836871) (xy 418.447521 -156.842971) (xy 418.501478 -156.857077)
			(xy 418.552807 -156.878889) (xy 418.600413 -156.907943) (xy 418.643281 -156.943618) (xy 418.680498 -156.985155)
			(xy 418.711271 -157.031668) (xy 418.734943 -157.082165) (xy 418.751011 -157.135572) (xy 418.759131 -157.190748)
			(xy 418.75964 -157.218634) (xy 418.759131 -157.24652) (xy 418.751011 -157.301696) (xy 418.734943 -157.355103)
			(xy 418.711271 -157.4056) (xy 418.680498 -157.452113) (xy 418.643281 -157.49365) (xy 418.600413 -157.529325)
			(xy 418.552807 -157.558379) (xy 418.501478 -157.580191) (xy 418.447521 -157.594297) (xy 418.392084 -157.600397)
			(xy 418.33635 -157.59836) (xy 418.281507 -157.58823) (xy 418.228723 -157.570223) (xy 418.179123 -157.544722)
			(xy 418.133765 -157.512271) (xy 418.093616 -157.473562) (xy 418.05953 -157.429419) (xy 418.032234 -157.380784)
			(xy 418.012311 -157.328693) (xy 418.000185 -157.274256) (xy 417.996114 -157.218634) (xy 394.69187 -157.218634)
			(xy 394.76299 -157.289754) (xy 394.780194 -157.30788) (xy 394.807942 -157.349432) (xy 394.827055 -157.395598)
			(xy 394.8368 -157.444603) (xy 394.837412 -157.469586) (xy 394.837412 -164.461698) (xy 394.837835 -164.471767)
			(xy 394.845557 -164.490365) (xy 394.852398 -164.497766) (xy 398.839944 -168.485058) (xy 398.84734 -168.491904)
			(xy 398.865942 -168.499622) (xy 398.876012 -168.500044) (xy 399.358866 -168.500044) (xy 399.368935 -168.499616)
			(xy 399.387534 -168.491899) (xy 399.394934 -168.485058) (xy 399.978118 -167.902128) (xy 399.984941 -167.894714)
			(xy 399.99267 -167.876125) (xy 399.993104 -167.86606) (xy 399.993104 -162.328352) (xy 399.993718 -162.303369)
			(xy 400.003463 -162.254362) (xy 400.02257 -162.208193) (xy 400.050306 -162.166631) (xy 400.067526 -162.14852)
			(xy 401.910804 -160.305242) (xy 401.928898 -160.288003) (xy 401.970463 -160.260265) (xy 402.016638 -160.241162)
			(xy 402.065651 -160.231427) (xy 402.090636 -160.23082) (xy 406.982422 -160.23082) (xy 406.992495 -160.230427)
			(xy 407.011094 -160.222686) (xy 407.01849 -160.215834) (xy 408.67838 -158.555944) (xy 408.696497 -158.538712)
			(xy 408.738034 -158.510895) (xy 408.784198 -158.491715) (xy 408.833217 -158.481909) (xy 408.858212 -158.481268)
			(xy 412.751016 -158.481268) (xy 412.776013 -158.481881) (xy 412.825038 -158.491691) (xy 412.871209 -158.510871)
			(xy 412.912753 -158.538685) (xy 412.930848 -158.555944) (xy 414.03651 -159.661606) (xy 414.053742 -159.679707)
			(xy 414.081484 -159.721268) (xy 414.100589 -159.767441) (xy 414.110325 -159.816453) (xy 414.110932 -159.841438)
			(xy 414.110932 -159.939482) (xy 414.111358 -159.949551) (xy 414.119077 -159.96815) (xy 414.125918 -159.97555)
			(xy 414.244282 -160.09366) (xy 414.25129 -160.100021) (xy 414.268639 -160.107552) (xy 414.287537 -160.108305)
			(xy 414.296606 -160.105598) (xy 414.396936 -160.071054) (xy 414.41497 -160.048448) (xy 414.416748 -160.03397)
			(xy 414.420007 -160.01036) (xy 414.431623 -159.964137) (xy 414.448908 -159.919721) (xy 414.459928 -159.898588)
			(xy 414.464754 -159.889698) (xy 414.466786 -159.87014) (xy 414.443926 -159.791654) (xy 414.440723 -159.782215)
			(xy 414.428281 -159.766662) (xy 414.419796 -159.761428) (xy 414.394678 -159.746907) (xy 414.348796 -159.711399)
			(xy 414.308822 -159.66935) (xy 414.275679 -159.621732) (xy 414.250131 -159.569642) (xy 414.232768 -159.514284)
			(xy 414.223991 -159.456935) (xy 414.223454 -159.427926) (xy 414.22394 -159.400675) (xy 414.231696 -159.346727)
			(xy 414.247051 -159.294432) (xy 414.269693 -159.244855) (xy 414.299159 -159.199005) (xy 414.33485 -159.157814)
			(xy 414.376041 -159.122123) (xy 414.421891 -159.092657) (xy 414.471468 -159.070015) (xy 414.523763 -159.05466)
			(xy 414.577711 -159.046904) (xy 414.632213 -159.046904) (xy 414.686161 -159.05466) (xy 414.738456 -159.070015)
			(xy 414.788033 -159.092657) (xy 414.833883 -159.122123) (xy 414.875074 -159.157814) (xy 414.910765 -159.199005)
			(xy 414.940231 -159.244855) (xy 414.962873 -159.294432) (xy 414.978228 -159.346727) (xy 414.985984 -159.400675)
			(xy 414.98647 -159.427926) (xy 414.985809 -159.459489) (xy 414.975423 -159.521754) (xy 414.954937 -159.581463)
			(xy 414.940496 -159.609536) (xy 414.93567 -159.618426) (xy 414.933638 -159.637984) (xy 414.956498 -159.71647)
			(xy 414.959759 -159.725885) (xy 414.97216 -159.741449) (xy 414.980628 -159.746696) (xy 414.987994 -159.75076)
			(xy 414.9979 -159.756602) (xy 415.019744 -159.758634) (xy 415.114486 -159.725106) (xy 415.130234 -159.709612)
			(xy 415.134298 -159.699198) (xy 415.144978 -159.672415) (xy 415.173267 -159.622172) (xy 415.208799 -159.576762)
			(xy 415.250763 -159.537219) (xy 415.298203 -159.504446) (xy 415.350036 -159.479189) (xy 415.405082 -159.462026)
			(xy 415.462084 -159.453346) (xy 415.490914 -159.452818) (xy 415.518168 -159.453242) (xy 415.572122 -159.461001)
			(xy 415.624422 -159.476361) (xy 415.674004 -159.499007) (xy 415.719859 -159.528479) (xy 415.761052 -159.564176)
			(xy 415.796745 -159.605373) (xy 415.826213 -159.651231) (xy 415.848853 -159.700815) (xy 415.864207 -159.753117)
			(xy 415.871961 -159.807072) (xy 415.872422 -159.834326) (xy 415.871827 -159.864351) (xy 415.862371 -159.923654)
			(xy 415.854637 -159.947356) (xy 416.113722 -159.947356) (xy 416.114177 -159.91988) (xy 416.122076 -159.865499)
			(xy 416.137703 -159.812816) (xy 416.160735 -159.762924) (xy 416.190693 -159.716857) (xy 416.208464 -159.695896)
			(xy 416.208718 -159.695642) (xy 416.214295 -159.688549) (xy 416.220547 -159.671637) (xy 416.22091 -159.662622)
			(xy 416.22091 -159.595058) (xy 416.220523 -159.586044) (xy 416.214296 -159.569127) (xy 416.208718 -159.562038)
			(xy 416.20821 -159.56153) (xy 416.190496 -159.540568) (xy 416.16061 -159.49454) (xy 416.13764 -159.444699)
			(xy 416.122061 -159.392077) (xy 416.114195 -159.337764) (xy 416.113722 -159.310324) (xy 416.114208 -159.283073)
			(xy 416.121964 -159.229125) (xy 416.137319 -159.17683) (xy 416.159961 -159.127253) (xy 416.189427 -159.081403)
			(xy 416.225118 -159.040212) (xy 416.266309 -159.004521) (xy 416.312159 -158.975055) (xy 416.361736 -158.952413)
			(xy 416.414031 -158.937058) (xy 416.467979 -158.929302) (xy 416.522481 -158.929302) (xy 416.576429 -158.937058)
			(xy 416.628724 -158.952413) (xy 416.678301 -158.975055) (xy 416.724151 -159.004521) (xy 416.765342 -159.040212)
			(xy 416.801033 -159.081403) (xy 416.830499 -159.127253) (xy 416.853141 -159.17683) (xy 416.868496 -159.229125)
			(xy 416.876252 -159.283073) (xy 416.876738 -159.310324) (xy 416.876256 -159.337799) (xy 416.868362 -159.392178)
			(xy 416.85274 -159.44486) (xy 416.829715 -159.494753) (xy 416.799763 -159.540822) (xy 416.781996 -159.561784)
			(xy 416.781742 -159.562038) (xy 416.776168 -159.569133) (xy 416.769915 -159.586044) (xy 416.76955 -159.595058)
			(xy 416.76955 -159.662622) (xy 416.769885 -159.671641) (xy 416.776147 -159.688559) (xy 416.781742 -159.695642)
			(xy 416.78225 -159.69615) (xy 416.799995 -159.717087) (xy 416.829878 -159.763122) (xy 416.852842 -159.812969)
			(xy 416.868414 -159.865596) (xy 416.87627 -159.919914) (xy 416.876738 -159.947356) (xy 416.876252 -159.974607)
			(xy 416.868496 -160.028555) (xy 416.853141 -160.08085) (xy 416.830499 -160.130427) (xy 416.801033 -160.176277)
			(xy 416.765342 -160.217468) (xy 416.724151 -160.253159) (xy 416.678301 -160.282625) (xy 416.628724 -160.305267)
			(xy 416.576429 -160.320622) (xy 416.522481 -160.328378) (xy 416.467979 -160.328378) (xy 416.414031 -160.320622)
			(xy 416.361736 -160.305267) (xy 416.312159 -160.282625) (xy 416.266309 -160.253159) (xy 416.225118 -160.217468)
			(xy 416.189427 -160.176277) (xy 416.159961 -160.130427) (xy 416.137319 -160.08085) (xy 416.121964 -160.028555)
			(xy 416.114208 -159.974607) (xy 416.113722 -159.947356) (xy 415.854637 -159.947356) (xy 415.843743 -159.980744)
			(xy 415.816404 -160.034212) (xy 415.781028 -160.082738) (xy 415.760154 -160.104328) (xy 415.753303 -160.111719)
			(xy 415.745591 -160.130325) (xy 415.745168 -160.140396) (xy 415.745168 -160.315402) (xy 415.744534 -160.340384)
			(xy 415.734797 -160.389391) (xy 415.715696 -160.435561) (xy 415.687964 -160.477123) (xy 415.670746 -160.495234)
			(xy 415.329624 -160.836356) (xy 415.311505 -160.853586) (xy 415.269969 -160.881403) (xy 415.223805 -160.900584)
			(xy 415.174786 -160.910391) (xy 415.149792 -160.911032) (xy 414.447228 -160.911032) (xy 414.422232 -160.910392)
			(xy 414.373209 -160.900591) (xy 414.327038 -160.881419) (xy 414.285492 -160.853611) (xy 414.267396 -160.836356)
			(xy 413.676846 -160.245806) (xy 413.659612 -160.227707) (xy 413.631873 -160.186144) (xy 413.612769 -160.13997)
			(xy 413.603032 -160.090959) (xy 413.602424 -160.065974) (xy 413.602424 -159.96793) (xy 413.602003 -159.95786)
			(xy 413.594282 -159.939261) (xy 413.587438 -159.931862) (xy 412.660592 -159.00527) (xy 412.653192 -158.99843)
			(xy 412.634593 -158.990711) (xy 412.624524 -158.990284) (xy 408.984704 -158.990284) (xy 408.974632 -158.990689)
			(xy 408.956033 -158.998422) (xy 408.948636 -159.00527) (xy 407.378154 -160.575498) (xy 407.371316 -160.582899)
			(xy 407.363597 -160.601498) (xy 407.363168 -160.611566) (xy 407.363168 -161.701988) (xy 410.43733 -161.701988)
			(xy 410.437846 -161.674415) (xy 410.445787 -161.619844) (xy 410.461501 -161.566985) (xy 410.484662 -161.516938)
			(xy 410.514786 -161.470747) (xy 410.551246 -161.429375) (xy 410.57195 -161.411158) (xy 410.580052 -161.403628)
			(xy 410.589389 -161.383597) (xy 410.589984 -161.37255) (xy 410.589984 -161.294826) (xy 410.589406 -161.283778)
			(xy 410.580048 -161.263756) (xy 410.57195 -161.256218) (xy 410.551234 -161.238012) (xy 410.514767 -161.196641)
			(xy 410.484636 -161.150449) (xy 410.461472 -161.100401) (xy 410.445756 -161.047538) (xy 410.437816 -160.992963)
			(xy 410.43733 -160.965388) (xy 410.437846 -160.937815) (xy 410.445787 -160.883244) (xy 410.461501 -160.830385)
			(xy 410.484662 -160.780338) (xy 410.514786 -160.734147) (xy 410.551246 -160.692775) (xy 410.57195 -160.674558)
			(xy 410.580052 -160.667028) (xy 410.589389 -160.646997) (xy 410.589984 -160.63595) (xy 410.589984 -160.558226)
			(xy 410.589406 -160.547178) (xy 410.580048 -160.527156) (xy 410.57195 -160.519618) (xy 410.551234 -160.501412)
			(xy 410.514767 -160.460041) (xy 410.484636 -160.413849) (xy 410.461472 -160.363801) (xy 410.445756 -160.310938)
			(xy 410.437816 -160.256363) (xy 410.43733 -160.228788) (xy 410.437744 -160.201533) (xy 410.445503 -160.147578)
			(xy 410.460863 -160.095277) (xy 410.48351 -160.045694) (xy 410.512982 -159.99984) (xy 410.548681 -159.958646)
			(xy 410.58988 -159.922952) (xy 410.635738 -159.893486) (xy 410.685324 -159.870845) (xy 410.737627 -159.855493)
			(xy 410.791583 -159.84774) (xy 410.818838 -159.84728) (xy 410.846694 -159.847784) (xy 410.901809 -159.855912)
			(xy 410.955159 -159.871962) (xy 411.005611 -159.895592) (xy 411.052095 -159.926301) (xy 411.093624 -159.963438)
			(xy 411.129317 -160.006215) (xy 411.158417 -160.053723) (xy 411.180305 -160.104955) (xy 411.1879 -160.13176)
			(xy 411.190186 -160.14065) (xy 411.200854 -160.15589) (xy 411.272736 -160.203642) (xy 411.29077 -160.207706)
			(xy 411.299914 -160.206436) (xy 411.312931 -160.204767) (xy 411.339115 -160.202987) (xy 411.352238 -160.20288)
			(xy 411.366387 -160.20297) (xy 411.39461 -160.205007) (xy 411.408626 -160.206944) (xy 411.418532 -160.208468)
			(xy 411.438344 -160.203642) (xy 411.512766 -160.147762) (xy 411.522926 -160.130236) (xy 411.524196 -160.120076)
			(xy 411.528288 -160.092923) (xy 411.543259 -160.040092) (xy 411.565649 -159.989953) (xy 411.594995 -159.943541)
			(xy 411.630692 -159.901816) (xy 411.672002 -159.865639) (xy 411.718071 -159.835758) (xy 411.767948 -159.81279)
			(xy 411.820602 -159.797209) (xy 411.874946 -159.789337) (xy 411.902402 -159.78886) (xy 411.929652 -159.789376)
			(xy 411.983597 -159.797132) (xy 412.035889 -159.812486) (xy 412.085464 -159.835125) (xy 412.131313 -159.864588)
			(xy 412.172502 -159.900276) (xy 412.208194 -159.941463) (xy 412.237661 -159.987309) (xy 412.260304 -160.036883)
			(xy 412.275662 -160.089174) (xy 412.283422 -160.143118) (xy 412.28391 -160.170368) (xy 412.283419 -160.197942)
			(xy 412.275471 -160.252513) (xy 412.259751 -160.305372) (xy 412.236585 -160.355418) (xy 412.206458 -160.401609)
			(xy 412.169995 -160.442981) (xy 412.14929 -160.461198) (xy 412.141214 -160.468752) (xy 412.131861 -160.488764)
			(xy 412.131256 -160.499806) (xy 412.131256 -160.57753) (xy 412.131845 -160.588577) (xy 412.141194 -160.608599)
			(xy 412.14929 -160.616138) (xy 412.170021 -160.634328) (xy 412.20649 -160.675701) (xy 412.23662 -160.721895)
			(xy 412.259782 -160.771947) (xy 412.275494 -160.824814) (xy 412.283428 -160.879392) (xy 412.28391 -160.906968)
			(xy 412.283415 -160.93422) (xy 412.275662 -160.98817) (xy 412.26031 -161.040467) (xy 412.237672 -161.090047)
			(xy 412.208207 -161.1359) (xy 412.172517 -161.177093) (xy 412.131327 -161.212787) (xy 412.085477 -161.242256)
			(xy 412.035899 -161.264899) (xy 411.983603 -161.280255) (xy 411.929654 -161.288013) (xy 411.902402 -161.288476)
			(xy 411.901894 -161.288476) (xy 411.868112 -161.286952) (xy 411.857952 -161.285936) (xy 411.838648 -161.292032)
			(xy 411.775656 -161.344864) (xy 411.768354 -161.351576) (xy 411.759081 -161.369089) (xy 411.757622 -161.3789)
			(xy 411.757622 -161.379662) (xy 411.754675 -161.407824) (xy 411.741466 -161.462884) (xy 411.720262 -161.515386)
			(xy 411.691528 -161.564176) (xy 411.655897 -161.608182) (xy 411.614151 -161.646436) (xy 411.567208 -161.678098)
			(xy 411.516101 -161.702472) (xy 411.461951 -161.719022) (xy 411.405949 -161.727384) (xy 411.377638 -161.727896)
			(xy 411.359619 -161.72768) (xy 411.323744 -161.724243) (xy 411.30601 -161.721038) (xy 411.296358 -161.71926)
			(xy 411.277308 -161.722816) (xy 411.202378 -161.770822) (xy 411.190948 -161.78657) (xy 411.188662 -161.795968)
			(xy 411.181299 -161.823022) (xy 411.159665 -161.87475) (xy 411.130696 -161.922756) (xy 411.095016 -161.966007)
			(xy 411.053392 -162.003573) (xy 411.006721 -162.034646) (xy 410.956005 -162.058557) (xy 410.902338 -162.074791)
			(xy 410.846873 -162.082999) (xy 410.818838 -162.083496) (xy 410.791586 -162.083009) (xy 410.737635 -162.075257)
			(xy 410.685337 -162.059905) (xy 410.635756 -162.037266) (xy 410.589902 -162.007801) (xy 410.548709 -161.97211)
			(xy 410.513014 -161.930919) (xy 410.483546 -161.885067) (xy 410.460904 -161.835488) (xy 410.445548 -161.783191)
			(xy 410.437793 -161.72924) (xy 410.43733 -161.701988) (xy 407.363168 -161.701988) (xy 407.363168 -163.256214)
			(xy 412.105348 -163.256214) (xy 412.105858 -163.227297) (xy 412.114586 -163.170124) (xy 412.131845 -163.114924)
			(xy 412.157238 -163.062962) (xy 412.190184 -163.015429) (xy 412.229927 -162.973413) (xy 412.252414 -162.955224)
			(xy 412.261203 -162.947599) (xy 412.271396 -162.926712) (xy 412.271972 -162.915092) (xy 412.271972 -162.835336)
			(xy 412.271465 -162.8237) (xy 412.261255 -162.80279) (xy 412.252414 -162.795204) (xy 412.229935 -162.777007)
			(xy 412.190199 -162.734989) (xy 412.157259 -162.687456) (xy 412.13187 -162.635495) (xy 412.114613 -162.580299)
			(xy 412.105883 -162.52313) (xy 412.105348 -162.494214) (xy 412.105894 -162.466154) (xy 412.114126 -162.410641)
			(xy 412.1304 -162.356932) (xy 412.154364 -162.306186) (xy 412.185502 -162.259497) (xy 412.223142 -162.217872)
			(xy 412.266473 -162.182208) (xy 412.29026 -162.167316) (xy 412.299912 -162.161474) (xy 412.312104 -162.143694)
			(xy 412.32709 -162.056572) (xy 412.328437 -162.045696) (xy 412.322912 -162.024509) (xy 412.316422 -162.015678)
			(xy 412.300531 -161.995603) (xy 412.273783 -161.951945) (xy 412.253257 -161.905041) (xy 412.239338 -161.855769)
			(xy 412.232287 -161.805057) (xy 412.23184 -161.779458) (xy 412.232317 -161.752843) (xy 412.239898 -161.700154)
			(xy 412.254898 -161.649081) (xy 412.277014 -161.600662) (xy 412.305794 -161.555882) (xy 412.340653 -161.515653)
			(xy 412.380882 -161.480794) (xy 412.425662 -161.452014) (xy 412.474081 -161.429898) (xy 412.525154 -161.414898)
			(xy 412.577843 -161.407317) (xy 412.604458 -161.40684) (xy 412.63088 -161.407278) (xy 412.683196 -161.414735)
			(xy 412.733934 -161.429505) (xy 412.782078 -161.451293) (xy 412.826663 -161.479661) (xy 412.847028 -161.496502)
			(xy 412.853886 -161.502344) (xy 412.870904 -161.508694) (xy 412.955232 -161.508694) (xy 412.97225 -161.502344)
			(xy 412.979108 -161.496502) (xy 412.999474 -161.479663) (xy 413.04406 -161.451298) (xy 413.092204 -161.429511)
			(xy 413.142941 -161.41474) (xy 413.195256 -161.40728) (xy 413.2481 -161.40728) (xy 413.300415 -161.41474)
			(xy 413.351152 -161.429511) (xy 413.399296 -161.451298) (xy 413.443882 -161.479663) (xy 413.464248 -161.496502)
			(xy 413.471106 -161.502344) (xy 413.488124 -161.508694) (xy 413.572452 -161.508694) (xy 413.58947 -161.502344)
			(xy 413.596328 -161.496502) (xy 413.616683 -161.479651) (xy 413.661276 -161.451298) (xy 413.709423 -161.429521)
			(xy 413.760162 -161.414756) (xy 413.812476 -161.407299) (xy 413.838898 -161.40684) (xy 413.866782 -161.407419)
			(xy 413.921926 -161.415731) (xy 413.975216 -161.432168) (xy 414.025461 -161.456364) (xy 414.071538 -161.487779)
			(xy 414.112419 -161.525711) (xy 414.147189 -161.569311) (xy 414.175073 -161.617607) (xy 414.195447 -161.669519)
			(xy 414.207856 -161.723889) (xy 414.212024 -161.7795) (xy 414.207856 -161.835111) (xy 414.195447 -161.889481)
			(xy 414.175073 -161.941393) (xy 414.147189 -161.989689) (xy 414.112419 -162.033289) (xy 414.071538 -162.071221)
			(xy 414.025461 -162.102636) (xy 413.975216 -162.126832) (xy 413.921926 -162.143269) (xy 413.866782 -162.151581)
			(xy 413.838898 -162.152076) (xy 413.812477 -162.151601) (xy 413.760163 -162.144153) (xy 413.709425 -162.129391)
			(xy 413.661281 -162.107611) (xy 413.616695 -162.079251) (xy 413.596328 -162.062414) (xy 413.58947 -162.056572)
			(xy 413.572452 -162.050222) (xy 413.488124 -162.050222) (xy 413.471106 -162.056572) (xy 413.464248 -162.062414)
			(xy 413.443882 -162.079253) (xy 413.399296 -162.107618) (xy 413.351152 -162.129405) (xy 413.300415 -162.144176)
			(xy 413.2481 -162.151636) (xy 413.195256 -162.151636) (xy 413.142941 -162.144176) (xy 413.092204 -162.129405)
			(xy 413.04406 -162.107618) (xy 412.999474 -162.079253) (xy 412.979108 -162.062414) (xy 412.97225 -162.056572)
			(xy 412.955232 -162.050222) (xy 412.870904 -162.050222) (xy 412.853886 -162.056572) (xy 412.847028 -162.062414)
			(xy 412.836226 -162.071478) (xy 412.813466 -162.088129) (xy 412.801562 -162.095688) (xy 412.792164 -162.10153)
			(xy 412.780226 -162.119564) (xy 412.76651 -162.20694) (xy 412.765367 -162.217827) (xy 412.771292 -162.238882)
			(xy 412.77794 -162.24758) (xy 412.794941 -162.268341) (xy 412.823546 -162.31374) (xy 412.845507 -162.3627)
			(xy 412.860393 -162.414253) (xy 412.867909 -162.467384) (xy 412.868364 -162.494214) (xy 412.867797 -162.523129)
			(xy 412.85908 -162.580299) (xy 412.841833 -162.635497) (xy 412.81645 -162.687459) (xy 412.783514 -162.734994)
			(xy 412.74378 -162.777013) (xy 412.721298 -162.795204) (xy 412.712499 -162.802819) (xy 412.702311 -162.823714)
			(xy 412.70174 -162.835336) (xy 412.70174 -162.915092) (xy 412.702284 -162.926724) (xy 412.712468 -162.947634)
			(xy 412.721298 -162.955224) (xy 412.743793 -162.973402) (xy 412.783527 -163.015424) (xy 412.816465 -163.062962)
			(xy 412.841851 -163.114926) (xy 412.859105 -163.170126) (xy 412.867831 -163.227297) (xy 412.868364 -163.256214)
			(xy 412.867878 -163.283465) (xy 412.860122 -163.337413) (xy 412.844767 -163.389708) (xy 412.822125 -163.439285)
			(xy 412.792659 -163.485135) (xy 412.756968 -163.526326) (xy 412.715777 -163.562017) (xy 412.669927 -163.591483)
			(xy 412.62035 -163.614125) (xy 412.568055 -163.62948) (xy 412.514107 -163.637236) (xy 412.459605 -163.637236)
			(xy 412.405657 -163.62948) (xy 412.353362 -163.614125) (xy 412.303785 -163.591483) (xy 412.257935 -163.562017)
			(xy 412.216744 -163.526326) (xy 412.181053 -163.485135) (xy 412.151587 -163.439285) (xy 412.128945 -163.389708)
			(xy 412.11359 -163.337413) (xy 412.105834 -163.283465) (xy 412.105348 -163.256214) (xy 407.363168 -163.256214)
			(xy 407.363168 -164.354256) (xy 407.363598 -164.364325) (xy 407.371313 -164.382924) (xy 407.378154 -164.390324)
			(xy 407.399055 -164.411891) (xy 407.434441 -164.460417) (xy 407.461783 -164.513889) (xy 407.480405 -164.570987)
			(xy 407.489847 -164.630298) (xy 407.490422 -164.660326) (xy 407.489946 -164.687577) (xy 407.482187 -164.741525)
			(xy 407.472839 -164.773356) (xy 407.731722 -164.773356) (xy 407.732177 -164.74588) (xy 407.740076 -164.691499)
			(xy 407.755703 -164.638816) (xy 407.778735 -164.588924) (xy 407.808693 -164.542857) (xy 407.826464 -164.521896)
			(xy 407.826718 -164.521642) (xy 407.832295 -164.514549) (xy 407.838547 -164.497637) (xy 407.83891 -164.488622)
			(xy 407.83891 -164.421058) (xy 407.838523 -164.412044) (xy 407.832296 -164.395127) (xy 407.826718 -164.388038)
			(xy 407.82621 -164.38753) (xy 407.808496 -164.366568) (xy 407.77861 -164.32054) (xy 407.75564 -164.270699)
			(xy 407.740061 -164.218077) (xy 407.732195 -164.163764) (xy 407.731722 -164.136324) (xy 407.732208 -164.109073)
			(xy 407.739964 -164.055125) (xy 407.755319 -164.00283) (xy 407.777961 -163.953253) (xy 407.807427 -163.907403)
			(xy 407.843118 -163.866212) (xy 407.884309 -163.830521) (xy 407.930159 -163.801055) (xy 407.979736 -163.778413)
			(xy 408.032031 -163.763058) (xy 408.085979 -163.755302) (xy 408.140481 -163.755302) (xy 408.194429 -163.763058)
			(xy 408.246724 -163.778413) (xy 408.296301 -163.801055) (xy 408.342151 -163.830521) (xy 408.383342 -163.866212)
			(xy 408.419033 -163.907403) (xy 408.448499 -163.953253) (xy 408.471141 -164.00283) (xy 408.486496 -164.055125)
			(xy 408.494252 -164.109073) (xy 408.494738 -164.136324) (xy 408.494256 -164.163799) (xy 408.486362 -164.218178)
			(xy 408.47074 -164.27086) (xy 408.447715 -164.320753) (xy 408.417763 -164.366822) (xy 408.399996 -164.387784)
			(xy 408.399742 -164.388038) (xy 408.394168 -164.395133) (xy 408.387915 -164.412044) (xy 408.38755 -164.421058)
			(xy 408.38755 -164.488622) (xy 408.387885 -164.497641) (xy 408.394147 -164.514559) (xy 408.399742 -164.521642)
			(xy 408.40025 -164.52215) (xy 408.417995 -164.543087) (xy 408.447878 -164.589122) (xy 408.470842 -164.638969)
			(xy 408.486414 -164.691596) (xy 408.49427 -164.745914) (xy 408.494738 -164.773356) (xy 408.494252 -164.800607)
			(xy 408.486496 -164.854555) (xy 408.471141 -164.90685) (xy 408.448499 -164.956427) (xy 408.419033 -165.002277)
			(xy 408.383342 -165.043468) (xy 408.342151 -165.079159) (xy 408.296301 -165.108625) (xy 408.246724 -165.131267)
			(xy 408.194429 -165.146622) (xy 408.140481 -165.154378) (xy 408.085979 -165.154378) (xy 408.032031 -165.146622)
			(xy 407.979736 -165.131267) (xy 407.930159 -165.108625) (xy 407.884309 -165.079159) (xy 407.843118 -165.043468)
			(xy 407.807427 -165.002277) (xy 407.777961 -164.956427) (xy 407.755319 -164.90685) (xy 407.739964 -164.854555)
			(xy 407.732208 -164.800607) (xy 407.731722 -164.773356) (xy 407.472839 -164.773356) (xy 407.466829 -164.793819)
			(xy 407.444186 -164.843395) (xy 407.414718 -164.889245) (xy 407.379026 -164.930434) (xy 407.337835 -164.966125)
			(xy 407.291985 -164.995592) (xy 407.242407 -165.018233) (xy 407.190113 -165.033589) (xy 407.136165 -165.041347)
			(xy 407.108914 -165.041834) (xy 407.10866 -165.041834) (xy 407.083456 -165.041456) (xy 407.033487 -165.03481)
			(xy 406.984832 -165.021628) (xy 406.938343 -165.002139) (xy 406.916382 -164.989764) (xy 406.906476 -164.983922)
			(xy 406.884632 -164.98189) (xy 406.78989 -165.015418) (xy 406.774142 -165.030912) (xy 406.770078 -165.041326)
			(xy 406.759347 -165.068087) (xy 406.731063 -165.118327) (xy 406.695537 -165.163735) (xy 406.65358 -165.203277)
			(xy 406.606148 -165.236052) (xy 406.554322 -165.261313) (xy 406.499285 -165.278484) (xy 406.442289 -165.287173)
			(xy 406.413462 -165.287706) (xy 406.38621 -165.287258) (xy 406.332261 -165.279496) (xy 406.279965 -165.264136)
			(xy 406.230388 -165.24149) (xy 406.184537 -165.21202) (xy 406.143347 -165.176324) (xy 406.107656 -165.135131)
			(xy 406.078191 -165.089277) (xy 406.05555 -165.039697) (xy 406.040196 -164.9874) (xy 406.03244 -164.93345)
			(xy 406.031954 -164.906198) (xy 406.032622 -164.874636) (xy 406.043005 -164.81237) (xy 406.063487 -164.752661)
			(xy 406.077928 -164.724588) (xy 406.082754 -164.715698) (xy 406.084786 -164.69614) (xy 406.061926 -164.617654)
			(xy 406.058723 -164.608215) (xy 406.046281 -164.592662) (xy 406.037796 -164.587428) (xy 406.012678 -164.572907)
			(xy 405.966796 -164.537399) (xy 405.926822 -164.49535) (xy 405.893679 -164.447732) (xy 405.868131 -164.395642)
			(xy 405.850768 -164.340284) (xy 405.841991 -164.282935) (xy 405.841454 -164.253926) (xy 405.84194 -164.226675)
			(xy 405.849696 -164.172727) (xy 405.865051 -164.120432) (xy 405.887693 -164.070855) (xy 405.917159 -164.025005)
			(xy 405.95285 -163.983814) (xy 405.994041 -163.948123) (xy 406.039891 -163.918657) (xy 406.089468 -163.896015)
			(xy 406.141763 -163.88066) (xy 406.195711 -163.872904) (xy 406.250213 -163.872904) (xy 406.304161 -163.88066)
			(xy 406.356456 -163.896015) (xy 406.406033 -163.918657) (xy 406.451883 -163.948123) (xy 406.493074 -163.983814)
			(xy 406.528765 -164.025005) (xy 406.558231 -164.070855) (xy 406.580873 -164.120432) (xy 406.596228 -164.172727)
			(xy 406.603984 -164.226675) (xy 406.60447 -164.253926) (xy 406.603809 -164.285489) (xy 406.593423 -164.347754)
			(xy 406.572937 -164.407463) (xy 406.558496 -164.435536) (xy 406.55367 -164.444426) (xy 406.551638 -164.463984)
			(xy 406.574498 -164.54247) (xy 406.577759 -164.551885) (xy 406.59016 -164.567449) (xy 406.598628 -164.572696)
			(xy 406.605994 -164.57676) (xy 406.6159 -164.582602) (xy 406.637744 -164.584634) (xy 406.732486 -164.551106)
			(xy 406.748234 -164.535612) (xy 406.752298 -164.525198) (xy 406.762302 -164.500117) (xy 406.788379 -164.452833)
			(xy 406.820875 -164.409708) (xy 406.839674 -164.390324) (xy 406.846492 -164.382907) (xy 406.854225 -164.364321)
			(xy 406.85466 -164.354256) (xy 406.85466 -160.790128) (xy 406.854256 -160.780104) (xy 406.846588 -160.76158)
			(xy 406.83241 -160.747405) (xy 406.813885 -160.739741) (xy 406.80386 -160.739328) (xy 402.217128 -160.739328)
			(xy 402.207059 -160.739761) (xy 402.188461 -160.747476) (xy 402.18106 -160.754314) (xy 400.516598 -162.418776)
			(xy 400.509776 -162.42619) (xy 400.502046 -162.444779) (xy 400.501612 -162.454844) (xy 400.501612 -166.527988)
			(xy 402.05533 -166.527988) (xy 402.055846 -166.500415) (xy 402.063787 -166.445844) (xy 402.079501 -166.392985)
			(xy 402.102662 -166.342938) (xy 402.132786 -166.296747) (xy 402.169246 -166.255375) (xy 402.18995 -166.237158)
			(xy 402.198052 -166.229628) (xy 402.207389 -166.209597) (xy 402.207984 -166.19855) (xy 402.207984 -166.120826)
			(xy 402.207406 -166.109778) (xy 402.198048 -166.089756) (xy 402.18995 -166.082218) (xy 402.169234 -166.064012)
			(xy 402.132767 -166.022641) (xy 402.102636 -165.976449) (xy 402.079472 -165.926401) (xy 402.063756 -165.873538)
			(xy 402.055816 -165.818963) (xy 402.05533 -165.791388) (xy 402.055846 -165.763815) (xy 402.063787 -165.709244)
			(xy 402.079501 -165.656385) (xy 402.102662 -165.606338) (xy 402.132786 -165.560147) (xy 402.169246 -165.518775)
			(xy 402.18995 -165.500558) (xy 402.198052 -165.493028) (xy 402.207389 -165.472997) (xy 402.207984 -165.46195)
			(xy 402.207984 -165.384226) (xy 402.207406 -165.373178) (xy 402.198048 -165.353156) (xy 402.18995 -165.345618)
			(xy 402.169234 -165.327412) (xy 402.132767 -165.286041) (xy 402.102636 -165.239849) (xy 402.079472 -165.189801)
			(xy 402.063756 -165.136938) (xy 402.055816 -165.082363) (xy 402.05533 -165.054788) (xy 402.055744 -165.027533)
			(xy 402.063503 -164.973578) (xy 402.078863 -164.921277) (xy 402.10151 -164.871694) (xy 402.130982 -164.82584)
			(xy 402.166681 -164.784646) (xy 402.20788 -164.748952) (xy 402.253738 -164.719486) (xy 402.303324 -164.696845)
			(xy 402.355627 -164.681493) (xy 402.409583 -164.67374) (xy 402.436838 -164.67328) (xy 402.464694 -164.673784)
			(xy 402.519809 -164.681912) (xy 402.573159 -164.697962) (xy 402.623611 -164.721592) (xy 402.670095 -164.752301)
			(xy 402.711624 -164.789438) (xy 402.747317 -164.832215) (xy 402.776417 -164.879723) (xy 402.798305 -164.930955)
			(xy 402.8059 -164.95776) (xy 402.808186 -164.96665) (xy 402.818854 -164.98189) (xy 402.890736 -165.029642)
			(xy 402.90877 -165.033706) (xy 402.917914 -165.032436) (xy 402.930931 -165.030767) (xy 402.957115 -165.028987)
			(xy 402.970238 -165.02888) (xy 402.984387 -165.02897) (xy 403.01261 -165.031007) (xy 403.026626 -165.032944)
			(xy 403.036532 -165.034468) (xy 403.056344 -165.029642) (xy 403.130766 -164.973762) (xy 403.140926 -164.956236)
			(xy 403.142196 -164.946076) (xy 403.146288 -164.918923) (xy 403.161259 -164.866092) (xy 403.183649 -164.815953)
			(xy 403.212995 -164.769541) (xy 403.248692 -164.727816) (xy 403.290002 -164.691639) (xy 403.336071 -164.661758)
			(xy 403.385948 -164.63879) (xy 403.438602 -164.623209) (xy 403.492946 -164.615337) (xy 403.520402 -164.61486)
			(xy 403.547652 -164.615376) (xy 403.601597 -164.623132) (xy 403.653889 -164.638486) (xy 403.703464 -164.661125)
			(xy 403.749313 -164.690588) (xy 403.790502 -164.726276) (xy 403.826194 -164.767463) (xy 403.855661 -164.813309)
			(xy 403.878304 -164.862883) (xy 403.893662 -164.915174) (xy 403.901422 -164.969118) (xy 403.90191 -164.996368)
			(xy 403.901419 -165.023942) (xy 403.893471 -165.078513) (xy 403.877751 -165.131372) (xy 403.854585 -165.181418)
			(xy 403.824458 -165.227609) (xy 403.787995 -165.268981) (xy 403.76729 -165.287198) (xy 403.759214 -165.294752)
			(xy 403.749861 -165.314764) (xy 403.749256 -165.325806) (xy 403.749256 -165.40353) (xy 403.749845 -165.414577)
			(xy 403.759194 -165.434599) (xy 403.76729 -165.442138) (xy 403.788021 -165.460328) (xy 403.82449 -165.501701)
			(xy 403.85462 -165.547895) (xy 403.877782 -165.597947) (xy 403.893494 -165.650814) (xy 403.901428 -165.705392)
			(xy 403.90191 -165.732968) (xy 403.901415 -165.76022) (xy 403.893662 -165.81417) (xy 403.87831 -165.866467)
			(xy 403.855672 -165.916047) (xy 403.826207 -165.9619) (xy 403.790517 -166.003093) (xy 403.749327 -166.038787)
			(xy 403.703477 -166.068256) (xy 403.653899 -166.090899) (xy 403.601603 -166.106255) (xy 403.547654 -166.114013)
			(xy 403.520402 -166.114476) (xy 403.519894 -166.114476) (xy 403.486112 -166.112952) (xy 403.475952 -166.111936)
			(xy 403.456648 -166.118032) (xy 403.393656 -166.170864) (xy 403.386354 -166.177576) (xy 403.377081 -166.195089)
			(xy 403.375622 -166.2049) (xy 403.375622 -166.205662) (xy 403.372675 -166.233824) (xy 403.359466 -166.288884)
			(xy 403.338262 -166.341386) (xy 403.309528 -166.390176) (xy 403.273897 -166.434182) (xy 403.232151 -166.472436)
			(xy 403.185208 -166.504098) (xy 403.134101 -166.528472) (xy 403.079951 -166.545022) (xy 403.023949 -166.553384)
			(xy 402.995638 -166.553896) (xy 402.977619 -166.55368) (xy 402.941744 -166.550243) (xy 402.92401 -166.547038)
			(xy 402.914358 -166.54526) (xy 402.895308 -166.548816) (xy 402.820378 -166.596822) (xy 402.808948 -166.61257)
			(xy 402.806662 -166.621968) (xy 402.799299 -166.649022) (xy 402.777665 -166.70075) (xy 402.748696 -166.748756)
			(xy 402.713016 -166.792007) (xy 402.671392 -166.829573) (xy 402.624721 -166.860646) (xy 402.574005 -166.884557)
			(xy 402.520338 -166.900791) (xy 402.464873 -166.908999) (xy 402.436838 -166.909496) (xy 402.409586 -166.909009)
			(xy 402.355635 -166.901257) (xy 402.303337 -166.885905) (xy 402.253756 -166.863266) (xy 402.207902 -166.833801)
			(xy 402.166709 -166.79811) (xy 402.131014 -166.756919) (xy 402.101546 -166.711067) (xy 402.078904 -166.661488)
			(xy 402.063548 -166.609191) (xy 402.055793 -166.55524) (xy 402.05533 -166.527988) (xy 400.501612 -166.527988)
			(xy 400.501612 -167.992552) (xy 400.501025 -168.017537) (xy 400.491276 -168.066547) (xy 400.48479 -168.082214)
			(xy 403.723348 -168.082214) (xy 403.723858 -168.053297) (xy 403.732586 -167.996124) (xy 403.749845 -167.940924)
			(xy 403.775238 -167.888962) (xy 403.808184 -167.841429) (xy 403.847927 -167.799413) (xy 403.870414 -167.781224)
			(xy 403.879203 -167.773599) (xy 403.889396 -167.752712) (xy 403.889972 -167.741092) (xy 403.889972 -167.661336)
			(xy 403.889465 -167.6497) (xy 403.879255 -167.62879) (xy 403.870414 -167.621204) (xy 403.847935 -167.603007)
			(xy 403.808199 -167.560989) (xy 403.775259 -167.513456) (xy 403.74987 -167.461495) (xy 403.732613 -167.406299)
			(xy 403.723883 -167.34913) (xy 403.723348 -167.320214) (xy 403.723894 -167.292154) (xy 403.732126 -167.236641)
			(xy 403.7484 -167.182932) (xy 403.772364 -167.132186) (xy 403.803502 -167.085497) (xy 403.841142 -167.043872)
			(xy 403.884473 -167.008208) (xy 403.90826 -166.993316) (xy 403.917912 -166.987474) (xy 403.930104 -166.969694)
			(xy 403.94509 -166.882572) (xy 403.946437 -166.871696) (xy 403.940912 -166.850509) (xy 403.934422 -166.841678)
			(xy 403.918531 -166.821603) (xy 403.891783 -166.777945) (xy 403.871257 -166.731041) (xy 403.857338 -166.681769)
			(xy 403.850287 -166.631057) (xy 403.84984 -166.605458) (xy 403.850317 -166.578843) (xy 403.857898 -166.526154)
			(xy 403.872898 -166.475081) (xy 403.895014 -166.426662) (xy 403.923794 -166.381882) (xy 403.958653 -166.341653)
			(xy 403.998882 -166.306794) (xy 404.043662 -166.278014) (xy 404.092081 -166.255898) (xy 404.143154 -166.240898)
			(xy 404.195843 -166.233317) (xy 404.222458 -166.23284) (xy 404.24888 -166.233278) (xy 404.301196 -166.240735)
			(xy 404.351934 -166.255505) (xy 404.400078 -166.277293) (xy 404.444663 -166.305661) (xy 404.465028 -166.322502)
			(xy 404.471886 -166.328344) (xy 404.488904 -166.334694) (xy 404.573232 -166.334694) (xy 404.59025 -166.328344)
			(xy 404.597108 -166.322502) (xy 404.617474 -166.305663) (xy 404.66206 -166.277298) (xy 404.710204 -166.255511)
			(xy 404.760941 -166.24074) (xy 404.813256 -166.23328) (xy 404.8661 -166.23328) (xy 404.918415 -166.24074)
			(xy 404.969152 -166.255511) (xy 405.017296 -166.277298) (xy 405.061882 -166.305663) (xy 405.082248 -166.322502)
			(xy 405.089106 -166.328344) (xy 405.106124 -166.334694) (xy 405.190452 -166.334694) (xy 405.20747 -166.328344)
			(xy 405.214328 -166.322502) (xy 405.234683 -166.305651) (xy 405.279276 -166.277298) (xy 405.327423 -166.255521)
			(xy 405.378162 -166.240756) (xy 405.430476 -166.233299) (xy 405.456898 -166.23284) (xy 405.484782 -166.233419)
			(xy 405.539926 -166.241731) (xy 405.593216 -166.258168) (xy 405.643461 -166.282364) (xy 405.689538 -166.313779)
			(xy 405.730419 -166.351711) (xy 405.765189 -166.395311) (xy 405.793073 -166.443607) (xy 405.813447 -166.495519)
			(xy 405.825856 -166.549889) (xy 405.830024 -166.6055) (xy 405.825856 -166.661111) (xy 405.813447 -166.715481)
			(xy 405.793073 -166.767393) (xy 405.765189 -166.815689) (xy 405.730419 -166.859289) (xy 405.689538 -166.897221)
			(xy 405.643461 -166.928636) (xy 405.593216 -166.952832) (xy 405.539926 -166.969269) (xy 405.484782 -166.977581)
			(xy 405.456898 -166.978076) (xy 405.430477 -166.977601) (xy 405.378163 -166.970153) (xy 405.327425 -166.955391)
			(xy 405.279281 -166.933611) (xy 405.234695 -166.905251) (xy 405.214328 -166.888414) (xy 405.20747 -166.882572)
			(xy 405.190452 -166.876222) (xy 405.106124 -166.876222) (xy 405.089106 -166.882572) (xy 405.082248 -166.888414)
			(xy 405.061882 -166.905253) (xy 405.017296 -166.933618) (xy 404.969152 -166.955405) (xy 404.918415 -166.970176)
			(xy 404.8661 -166.977636) (xy 404.813256 -166.977636) (xy 404.760941 -166.970176) (xy 404.710204 -166.955405)
			(xy 404.66206 -166.933618) (xy 404.617474 -166.905253) (xy 404.597108 -166.888414) (xy 404.59025 -166.882572)
			(xy 404.573232 -166.876222) (xy 404.488904 -166.876222) (xy 404.471886 -166.882572) (xy 404.465028 -166.888414)
			(xy 404.454226 -166.897478) (xy 404.431466 -166.914129) (xy 404.419562 -166.921688) (xy 404.410164 -166.92753)
			(xy 404.398226 -166.945564) (xy 404.38451 -167.03294) (xy 404.383367 -167.043827) (xy 404.389292 -167.064882)
			(xy 404.39594 -167.07358) (xy 404.412941 -167.094341) (xy 404.441546 -167.13974) (xy 404.463507 -167.1887)
			(xy 404.478393 -167.240253) (xy 404.485909 -167.293384) (xy 404.486364 -167.320214) (xy 404.485797 -167.349129)
			(xy 404.47708 -167.406299) (xy 404.459833 -167.461497) (xy 404.43445 -167.513459) (xy 404.401514 -167.560994)
			(xy 404.36178 -167.603013) (xy 404.339298 -167.621204) (xy 404.330499 -167.628819) (xy 404.320311 -167.649714)
			(xy 404.31974 -167.661336) (xy 404.31974 -167.741092) (xy 404.320284 -167.752724) (xy 404.330468 -167.773634)
			(xy 404.339298 -167.781224) (xy 404.361793 -167.799402) (xy 404.401527 -167.841424) (xy 404.434465 -167.888962)
			(xy 404.459851 -167.940926) (xy 404.477105 -167.996126) (xy 404.485831 -168.053297) (xy 404.486364 -168.082214)
			(xy 404.485878 -168.109465) (xy 404.478122 -168.163413) (xy 404.462767 -168.215708) (xy 404.440125 -168.265285)
			(xy 404.410659 -168.311135) (xy 404.374968 -168.352326) (xy 404.333777 -168.388017) (xy 404.287927 -168.417483)
			(xy 404.23835 -168.440125) (xy 404.186055 -168.45548) (xy 404.132107 -168.463236) (xy 404.077605 -168.463236)
			(xy 404.023657 -168.45548) (xy 403.971362 -168.440125) (xy 403.921785 -168.417483) (xy 403.875935 -168.388017)
			(xy 403.834744 -168.352326) (xy 403.799053 -168.311135) (xy 403.769587 -168.265285) (xy 403.746945 -168.215708)
			(xy 403.73159 -168.163413) (xy 403.723834 -168.109465) (xy 403.723348 -168.082214) (xy 400.48479 -168.082214)
			(xy 400.472161 -168.112717) (xy 400.444415 -168.154276) (xy 400.42719 -168.172384) (xy 399.66519 -168.934384)
			(xy 399.64709 -168.951635) (xy 399.605547 -168.979447) (xy 399.559377 -168.998622) (xy 399.510354 -169.008422)
			(xy 399.485358 -169.00906) (xy 399.090388 -169.00906) (xy 399.080385 -169.009577) (xy 399.0619 -169.017233)
			(xy 399.047749 -169.031377) (xy 399.040083 -169.049857) (xy 399.039588 -169.05986) (xy 399.039588 -172.931582)
			(xy 399.039999 -172.941653) (xy 399.047727 -172.960252) (xy 399.054574 -172.96765) (xy 399.075443 -172.989247)
			(xy 399.110833 -173.037765) (xy 399.13818 -173.09123) (xy 399.15681 -173.148321) (xy 399.166261 -173.207626)
			(xy 399.166842 -173.237652) (xy 399.1663 -173.264902) (xy 399.158551 -173.318848) (xy 399.149207 -173.350682)
			(xy 399.408142 -173.350682) (xy 399.408607 -173.323206) (xy 399.416503 -173.268826) (xy 399.432127 -173.216143)
			(xy 399.455157 -173.16625) (xy 399.485114 -173.120183) (xy 399.502884 -173.099222) (xy 399.503138 -173.098968)
			(xy 399.508706 -173.091869) (xy 399.514963 -173.074962) (xy 399.51533 -173.065948) (xy 399.51533 -172.998384)
			(xy 399.514974 -172.989367) (xy 399.508725 -172.97245) (xy 399.503138 -172.965364) (xy 399.50263 -172.964856)
			(xy 399.484884 -172.943919) (xy 399.455003 -172.897884) (xy 399.432038 -172.848037) (xy 399.416467 -172.795409)
			(xy 399.40861 -172.741092) (xy 399.408142 -172.71365) (xy 399.408628 -172.686399) (xy 399.416384 -172.632451)
			(xy 399.431739 -172.580156) (xy 399.454381 -172.530579) (xy 399.483847 -172.484729) (xy 399.519538 -172.443538)
			(xy 399.560729 -172.407847) (xy 399.606579 -172.378381) (xy 399.656156 -172.355739) (xy 399.708451 -172.340384)
			(xy 399.762399 -172.332628) (xy 399.816901 -172.332628) (xy 399.870849 -172.340384) (xy 399.923144 -172.355739)
			(xy 399.972721 -172.378381) (xy 400.018571 -172.407847) (xy 400.059762 -172.443538) (xy 400.095453 -172.484729)
			(xy 400.124919 -172.530579) (xy 400.147561 -172.580156) (xy 400.162916 -172.632451) (xy 400.170672 -172.686399)
			(xy 400.171158 -172.71365) (xy 400.170711 -172.741126) (xy 400.162811 -172.795508) (xy 400.147183 -172.848191)
			(xy 400.124149 -172.898083) (xy 400.094188 -172.94415) (xy 400.076416 -172.96511) (xy 400.076162 -172.965364)
			(xy 400.07058 -172.972454) (xy 400.064332 -172.989368) (xy 400.06397 -172.998384) (xy 400.06397 -173.065948)
			(xy 400.064358 -173.074962) (xy 400.070585 -173.091878) (xy 400.076162 -173.098968) (xy 400.07667 -173.099476)
			(xy 400.094384 -173.120438) (xy 400.12427 -173.166466) (xy 400.147241 -173.216307) (xy 400.16282 -173.268929)
			(xy 400.170685 -173.323242) (xy 400.171158 -173.350682) (xy 400.170672 -173.377933) (xy 400.162916 -173.431881)
			(xy 400.147561 -173.484176) (xy 400.124919 -173.533753) (xy 400.095453 -173.579603) (xy 400.059762 -173.620794)
			(xy 400.018571 -173.656485) (xy 399.972721 -173.685951) (xy 399.923144 -173.708593) (xy 399.870849 -173.723948)
			(xy 399.816901 -173.731704) (xy 399.762399 -173.731704) (xy 399.708451 -173.723948) (xy 399.656156 -173.708593)
			(xy 399.606579 -173.685951) (xy 399.560729 -173.656485) (xy 399.519538 -173.620794) (xy 399.483847 -173.579603)
			(xy 399.454381 -173.533753) (xy 399.431739 -173.484176) (xy 399.416384 -173.431881) (xy 399.408628 -173.377933)
			(xy 399.408142 -173.350682) (xy 399.149207 -173.350682) (xy 399.143202 -173.371143) (xy 399.120568 -173.42072)
			(xy 399.091108 -173.466572) (xy 399.055423 -173.507765) (xy 399.014238 -173.543459) (xy 398.968393 -173.572929)
			(xy 398.91882 -173.595574) (xy 398.866529 -173.610933) (xy 398.812584 -173.618694) (xy 398.785334 -173.61916)
			(xy 398.78508 -173.61916) (xy 398.759876 -173.618769) (xy 398.709908 -173.612127) (xy 398.661253 -173.598948)
			(xy 398.614764 -173.579463) (xy 398.592802 -173.56709) (xy 398.582896 -173.561248) (xy 398.561052 -173.559216)
			(xy 398.46631 -173.592744) (xy 398.450562 -173.608238) (xy 398.446498 -173.618652) (xy 398.435848 -173.645448)
			(xy 398.407552 -173.695689) (xy 398.372015 -173.741098) (xy 398.330046 -173.780638) (xy 398.282602 -173.813409)
			(xy 398.230765 -173.838664) (xy 398.175717 -173.855826) (xy 398.118713 -173.864505) (xy 398.089882 -173.865032)
			(xy 398.062631 -173.864539) (xy 398.008685 -173.856781) (xy 397.956392 -173.841424) (xy 397.906816 -173.818783)
			(xy 397.860967 -173.789317) (xy 397.819778 -173.753626) (xy 397.784087 -173.712438) (xy 397.75462 -173.666589)
			(xy 397.731978 -173.617014) (xy 397.716621 -173.564721) (xy 397.708861 -173.510775) (xy 397.708374 -173.483524)
			(xy 397.709022 -173.451961) (xy 397.719415 -173.389695) (xy 397.739905 -173.329986) (xy 397.754348 -173.301914)
			(xy 397.759174 -173.293024) (xy 397.761206 -173.273466) (xy 397.738346 -173.19498) (xy 397.735125 -173.185548)
			(xy 397.722696 -173.169992) (xy 397.714216 -173.164754) (xy 397.689114 -173.150207) (xy 397.643231 -173.114704)
			(xy 397.603256 -173.07266) (xy 397.57011 -173.025046) (xy 397.544559 -172.972961) (xy 397.527193 -172.917606)
			(xy 397.518413 -172.860259) (xy 397.517874 -172.831252) (xy 397.51836 -172.804001) (xy 397.526116 -172.750053)
			(xy 397.541471 -172.697758) (xy 397.564113 -172.648181) (xy 397.593579 -172.602331) (xy 397.62927 -172.56114)
			(xy 397.670461 -172.525449) (xy 397.716311 -172.495983) (xy 397.765888 -172.473341) (xy 397.818183 -172.457986)
			(xy 397.872131 -172.45023) (xy 397.926633 -172.45023) (xy 397.980581 -172.457986) (xy 398.032876 -172.473341)
			(xy 398.082453 -172.495983) (xy 398.128303 -172.525449) (xy 398.169494 -172.56114) (xy 398.205185 -172.602331)
			(xy 398.234651 -172.648181) (xy 398.257293 -172.697758) (xy 398.272648 -172.750053) (xy 398.280404 -172.804001)
			(xy 398.28089 -172.831252) (xy 398.280237 -172.862815) (xy 398.269847 -172.925081) (xy 398.249359 -172.98479)
			(xy 398.234916 -173.012862) (xy 398.23009 -173.021752) (xy 398.228058 -173.04131) (xy 398.250918 -173.119796)
			(xy 398.254161 -173.129218) (xy 398.266575 -173.144779) (xy 398.275048 -173.150022) (xy 398.282414 -173.154086)
			(xy 398.29232 -173.159928) (xy 398.314164 -173.16196) (xy 398.408906 -173.128432) (xy 398.424654 -173.112938)
			(xy 398.428718 -173.102524) (xy 398.438743 -173.077452) (xy 398.464812 -173.030166) (xy 398.497299 -172.987037)
			(xy 398.516094 -172.96765) (xy 398.522904 -172.960226) (xy 398.530641 -172.941645) (xy 398.53108 -172.931582)
			(xy 398.53108 -168.916858) (xy 398.530682 -168.906786) (xy 398.522943 -168.888188) (xy 398.516094 -168.88079)
			(xy 394.403326 -164.768022) (xy 394.386096 -164.749919) (xy 394.358357 -164.708357) (xy 394.339252 -164.662185)
			(xy 394.329514 -164.613174) (xy 394.328904 -164.58819) (xy 394.328904 -157.596078) (xy 394.328515 -157.586004)
			(xy 394.320772 -157.567405) (xy 394.313918 -157.56001) (xy 384.140202 -147.386294) (xy 384.122972 -147.368191)
			(xy 384.095229 -147.326631) (xy 384.076124 -147.280458) (xy 384.066388 -147.231447) (xy 384.06578 -147.206462)
			(xy 384.06578 -143.214852) (xy 384.065333 -143.204785) (xy 384.057628 -143.186187) (xy 384.050794 -143.178784)
			(xy 383.315718 -142.443708) (xy 383.308166 -142.436752) (xy 383.289134 -142.429091) (xy 383.268622 -142.429509)
			(xy 383.259076 -142.433294) (xy 383.234524 -142.443807) (xy 383.183212 -142.458619) (xy 383.130332 -142.466108)
			(xy 383.103628 -142.466568) (xy 383.10312 -142.466568) (xy 383.086864 -142.466314) (xy 383.075434 -142.465806)
			(xy 383.05359 -142.475204) (xy 382.994154 -142.545054) (xy 382.987027 -142.554316) (xy 382.981339 -142.576956)
			(xy 382.983232 -142.588488) (xy 382.986892 -142.607454) (xy 382.990836 -142.645882) (xy 382.991106 -142.665196)
			(xy 382.991106 -142.665958) (xy 382.990505 -142.695943) (xy 382.981088 -142.755171) (xy 382.962541 -142.812202)
			(xy 382.94945 -142.839186) (xy 382.944869 -142.849292) (xy 382.944096 -142.871443) (xy 382.947926 -142.881858)
			(xy 382.98247 -142.9639) (xy 382.999234 -142.978886) (xy 383.009902 -142.982188) (xy 383.035496 -142.990596)
			(xy 383.084189 -143.013642) (xy 383.129157 -143.043308) (xy 383.169505 -143.079004) (xy 383.204431 -143.12002)
			(xy 383.233242 -143.165541) (xy 383.255363 -143.214661) (xy 383.270356 -143.266404) (xy 383.277922 -143.319742)
			(xy 383.27838 -143.346678) (xy 383.277894 -143.373929) (xy 383.270138 -143.427877) (xy 383.254783 -143.480172)
			(xy 383.232141 -143.529749) (xy 383.202675 -143.575599) (xy 383.166984 -143.61679) (xy 383.125793 -143.652481)
			(xy 383.079943 -143.681947) (xy 383.030366 -143.704589) (xy 382.978071 -143.719944) (xy 382.924123 -143.7277)
			(xy 382.869621 -143.7277) (xy 382.815673 -143.719944) (xy 382.763378 -143.704589) (xy 382.713801 -143.681947)
			(xy 382.667951 -143.652481) (xy 382.62676 -143.61679) (xy 382.591069 -143.575599) (xy 382.561603 -143.529749)
			(xy 382.538961 -143.480172) (xy 382.523606 -143.427877) (xy 382.51585 -143.373929) (xy 382.515364 -143.346678)
			(xy 382.515982 -143.316694) (xy 382.525393 -143.257467) (xy 382.543933 -143.200435) (xy 382.55702 -143.17345)
			(xy 382.561576 -143.163336) (xy 382.562363 -143.141193) (xy 382.558544 -143.130778) (xy 382.524 -143.048736)
			(xy 382.507236 -143.03375) (xy 382.496568 -143.030448) (xy 382.470979 -143.022027) (xy 382.422288 -142.99898)
			(xy 382.377323 -142.969314) (xy 382.336976 -142.933619) (xy 382.30205 -142.892605) (xy 382.273239 -142.847087)
			(xy 382.251116 -142.797969) (xy 382.23612 -142.746228) (xy 382.22855 -142.692893) (xy 382.22809 -142.665958)
			(xy 382.228538 -142.638717) (xy 382.236293 -142.584791) (xy 382.251641 -142.532516) (xy 382.274268 -142.482955)
			(xy 382.303715 -142.437117) (xy 382.339383 -142.395934) (xy 382.380546 -142.360244) (xy 382.426367 -142.330771)
			(xy 382.475915 -142.308116) (xy 382.528181 -142.292739) (xy 382.582104 -142.284953) (xy 382.609344 -142.28445)
			(xy 382.609852 -142.28445) (xy 382.626108 -142.284704) (xy 382.637538 -142.285212) (xy 382.659382 -142.275814)
			(xy 382.718818 -142.205964) (xy 382.725932 -142.196694) (xy 382.731629 -142.174061) (xy 382.72974 -142.16253)
			(xy 382.726084 -142.143563) (xy 382.722137 -142.105136) (xy 382.721866 -142.085822) (xy 382.721866 -142.08506)
			(xy 382.722491 -142.054195) (xy 382.732467 -141.993276) (xy 382.752121 -141.934758) (xy 382.78094 -141.880168)
			(xy 382.799082 -141.85519) (xy 382.804341 -141.847413) (xy 382.809436 -141.829365) (xy 382.807697 -141.810692)
			(xy 382.803908 -141.802104) (xy 382.763268 -141.72057) (xy 382.758725 -141.712299) (xy 382.744808 -141.699578)
			(xy 382.72723 -141.692755) (xy 382.717802 -141.692376) (xy 381.743204 -141.692376) (xy 381.733132 -141.692783)
			(xy 381.714533 -141.700515) (xy 381.707136 -141.707362) (xy 381.393954 -142.020544) (xy 381.387096 -142.02793)
			(xy 381.379388 -142.04654) (xy 381.378968 -142.056612) (xy 381.378968 -143.482314) (xy 381.379368 -143.492387)
			(xy 381.387104 -143.510985) (xy 381.393954 -143.518382) (xy 382.62179 -144.746472) (xy 382.639003 -144.76459)
			(xy 382.666749 -144.806145) (xy 382.685859 -144.852313) (xy 382.695601 -144.901321) (xy 382.696212 -144.926304)
			(xy 382.696212 -146.171158) (xy 383.09626 -146.171158) (xy 383.100331 -146.115536) (xy 383.112457 -146.061099)
			(xy 383.13238 -146.009008) (xy 383.159676 -145.960373) (xy 383.193762 -145.91623) (xy 383.233911 -145.877521)
			(xy 383.279269 -145.84507) (xy 383.328869 -145.819569) (xy 383.381653 -145.801562) (xy 383.436496 -145.791432)
			(xy 383.49223 -145.789395) (xy 383.547667 -145.795495) (xy 383.601624 -145.809601) (xy 383.652953 -145.831413)
			(xy 383.700559 -145.860467) (xy 383.743427 -145.896142) (xy 383.780644 -145.937679) (xy 383.811417 -145.984192)
			(xy 383.835089 -146.034689) (xy 383.851157 -146.088096) (xy 383.859277 -146.143272) (xy 383.859786 -146.171158)
			(xy 383.859277 -146.199044) (xy 383.851157 -146.25422) (xy 383.835089 -146.307627) (xy 383.811417 -146.358124)
			(xy 383.780644 -146.404637) (xy 383.743427 -146.446174) (xy 383.700559 -146.481849) (xy 383.652953 -146.510903)
			(xy 383.601624 -146.532715) (xy 383.547667 -146.546821) (xy 383.49223 -146.552921) (xy 383.436496 -146.550884)
			(xy 383.381653 -146.540754) (xy 383.328869 -146.522747) (xy 383.279269 -146.497246) (xy 383.233911 -146.464795)
			(xy 383.193762 -146.426086) (xy 383.159676 -146.381943) (xy 383.13238 -146.333308) (xy 383.112457 -146.281217)
			(xy 383.100331 -146.22678) (xy 383.09626 -146.171158) (xy 382.696212 -146.171158) (xy 382.696212 -149.529546)
			(xy 382.695621 -149.554531) (xy 382.685873 -149.60354) (xy 382.66676 -149.64971) (xy 382.639015 -149.691269)
			(xy 382.62179 -149.709378) (xy 381.98171 -150.349458) (xy 381.96361 -150.366691) (xy 381.922047 -150.39443)
			(xy 381.875874 -150.413534) (xy 381.826863 -150.423271) (xy 381.801878 -150.42388) (xy 379.102874 -150.42388)
			(xy 379.0928 -150.42427) (xy 379.074202 -150.432013) (xy 379.066806 -150.438866) (xy 377.147582 -152.35809)
			(xy 377.129483 -152.375325) (xy 377.087921 -152.403066) (xy 377.041748 -152.422171) (xy 376.992735 -152.431906)
			(xy 376.96775 -152.432512) (xy 366.313974 -152.432512) (xy 366.303903 -152.432921) (xy 366.285305 -152.440653)
			(xy 366.277906 -152.447498) (xy 361.257332 -157.46831) (xy 365.557825 -157.46831) (xy 365.561553 -157.415059)
			(xy 365.572669 -157.362848) (xy 365.590955 -157.312696) (xy 365.616054 -157.265584) (xy 365.647476 -157.22243)
			(xy 365.684607 -157.184079) (xy 365.70539 -157.167326) (xy 365.714174 -157.159696) (xy 365.724371 -157.138813)
			(xy 365.724948 -157.127194) (xy 365.724948 -157.047438) (xy 365.724448 -157.035801) (xy 365.714233 -157.01489)
			(xy 365.70539 -157.007306) (xy 365.684622 -156.990534) (xy 365.647489 -156.952185) (xy 365.616065 -156.909033)
			(xy 365.590963 -156.861922) (xy 365.572675 -156.811771) (xy 365.561556 -156.75956) (xy 365.557825 -156.70631)
			(xy 365.561553 -156.653059) (xy 365.572669 -156.600848) (xy 365.590955 -156.550696) (xy 365.616054 -156.503584)
			(xy 365.647476 -156.46043) (xy 365.684607 -156.422079) (xy 365.70539 -156.405326) (xy 365.714174 -156.397696)
			(xy 365.724371 -156.376813) (xy 365.724948 -156.365194) (xy 365.724948 -156.285438) (xy 365.724448 -156.273801)
			(xy 365.714233 -156.25289) (xy 365.70539 -156.245306) (xy 365.684622 -156.228534) (xy 365.647489 -156.190185)
			(xy 365.616065 -156.147033) (xy 365.590963 -156.099922) (xy 365.572675 -156.049771) (xy 365.561556 -155.99756)
			(xy 365.557825 -155.94431) (xy 365.561553 -155.891059) (xy 365.572669 -155.838848) (xy 365.590955 -155.788696)
			(xy 365.616054 -155.741584) (xy 365.647476 -155.69843) (xy 365.684607 -155.660079) (xy 365.70539 -155.643326)
			(xy 365.714174 -155.635696) (xy 365.724371 -155.614813) (xy 365.724948 -155.603194) (xy 365.724948 -155.523438)
			(xy 365.724448 -155.511801) (xy 365.714233 -155.49089) (xy 365.70539 -155.483306) (xy 365.684622 -155.466534)
			(xy 365.647489 -155.428185) (xy 365.616065 -155.385033) (xy 365.590963 -155.337922) (xy 365.572675 -155.287771)
			(xy 365.561556 -155.23556) (xy 365.557825 -155.18231) (xy 365.561553 -155.129059) (xy 365.572669 -155.076848)
			(xy 365.590955 -155.026696) (xy 365.616054 -154.979584) (xy 365.647476 -154.93643) (xy 365.684607 -154.898079)
			(xy 365.70539 -154.881326) (xy 365.714174 -154.873696) (xy 365.724371 -154.852813) (xy 365.724948 -154.841194)
			(xy 365.724948 -154.761438) (xy 365.724448 -154.749801) (xy 365.714233 -154.72889) (xy 365.70539 -154.721306)
			(xy 365.682907 -154.703114) (xy 365.643173 -154.661094) (xy 365.610234 -154.613559) (xy 365.584845 -154.561598)
			(xy 365.567589 -154.506401) (xy 365.558859 -154.449232) (xy 365.558324 -154.420316) (xy 365.55877 -154.393062)
			(xy 365.566526 -154.339109) (xy 365.581882 -154.286809) (xy 365.604525 -154.237227) (xy 365.633994 -154.191372)
			(xy 365.669689 -154.150178) (xy 365.710885 -154.114484) (xy 365.756741 -154.085017) (xy 365.806324 -154.062376)
			(xy 365.858625 -154.047023) (xy 365.912578 -154.039269) (xy 365.939832 -154.038808) (xy 365.968747 -154.039372)
			(xy 366.025916 -154.048091) (xy 366.081115 -154.06534) (xy 366.133077 -154.090723) (xy 366.180612 -154.123658)
			(xy 366.222631 -154.163392) (xy 366.240822 -154.185874) (xy 366.248417 -154.194693) (xy 366.269327 -154.204867)
			(xy 366.280954 -154.205432) (xy 366.36071 -154.205432) (xy 366.372344 -154.204908) (xy 366.393255 -154.194711)
			(xy 366.400842 -154.185874) (xy 366.417595 -154.165091) (xy 366.455949 -154.127961) (xy 366.499103 -154.096539)
			(xy 366.546217 -154.07144) (xy 366.596369 -154.053154) (xy 366.64858 -154.042037) (xy 366.701832 -154.038307)
			(xy 366.755084 -154.042037) (xy 366.807295 -154.053154) (xy 366.857447 -154.07144) (xy 366.904561 -154.096539)
			(xy 366.947715 -154.127961) (xy 366.986069 -154.165091) (xy 367.002822 -154.185874) (xy 367.010417 -154.194693)
			(xy 367.031327 -154.204867) (xy 367.042954 -154.205432) (xy 367.12271 -154.205432) (xy 367.134344 -154.204908)
			(xy 367.155255 -154.194711) (xy 367.162842 -154.185874) (xy 367.179595 -154.165091) (xy 367.217949 -154.127961)
			(xy 367.261103 -154.096539) (xy 367.308217 -154.07144) (xy 367.358369 -154.053154) (xy 367.41058 -154.042037)
			(xy 367.463832 -154.038307) (xy 367.517084 -154.042037) (xy 367.569295 -154.053154) (xy 367.619447 -154.07144)
			(xy 367.666561 -154.096539) (xy 367.709715 -154.127961) (xy 367.748069 -154.165091) (xy 367.764822 -154.185874)
			(xy 367.772417 -154.194693) (xy 367.793327 -154.204867) (xy 367.804954 -154.205432) (xy 367.88471 -154.205432)
			(xy 367.896344 -154.204908) (xy 367.917255 -154.194711) (xy 367.924842 -154.185874) (xy 367.941595 -154.165091)
			(xy 367.979949 -154.127961) (xy 368.023103 -154.096539) (xy 368.070217 -154.07144) (xy 368.120369 -154.053154)
			(xy 368.17258 -154.042037) (xy 368.225832 -154.038307) (xy 368.279084 -154.042037) (xy 368.331295 -154.053154)
			(xy 368.381447 -154.07144) (xy 368.428561 -154.096539) (xy 368.471715 -154.127961) (xy 368.510069 -154.165091)
			(xy 368.526822 -154.185874) (xy 368.534417 -154.194693) (xy 368.555327 -154.204867) (xy 368.566954 -154.205432)
			(xy 368.64671 -154.205432) (xy 368.658344 -154.204908) (xy 368.679255 -154.194711) (xy 368.686842 -154.185874)
			(xy 368.703595 -154.165091) (xy 368.741949 -154.127961) (xy 368.785103 -154.096539) (xy 368.832217 -154.07144)
			(xy 368.882369 -154.053154) (xy 368.93458 -154.042037) (xy 368.987832 -154.038307) (xy 369.041084 -154.042037)
			(xy 369.093295 -154.053154) (xy 369.143447 -154.07144) (xy 369.190561 -154.096539) (xy 369.233715 -154.127961)
			(xy 369.272069 -154.165091) (xy 369.288822 -154.185874) (xy 369.296417 -154.194693) (xy 369.317327 -154.204867)
			(xy 369.328954 -154.205432) (xy 369.40871 -154.205432) (xy 369.420344 -154.204908) (xy 369.441255 -154.194711)
			(xy 369.448842 -154.185874) (xy 369.465595 -154.165091) (xy 369.503949 -154.127961) (xy 369.547103 -154.096539)
			(xy 369.594217 -154.07144) (xy 369.644369 -154.053154) (xy 369.69658 -154.042037) (xy 369.749832 -154.038307)
			(xy 369.803084 -154.042037) (xy 369.855295 -154.053154) (xy 369.905447 -154.07144) (xy 369.952561 -154.096539)
			(xy 369.995715 -154.127961) (xy 370.034069 -154.165091) (xy 370.050822 -154.185874) (xy 370.058417 -154.194693)
			(xy 370.079327 -154.204867) (xy 370.090954 -154.205432) (xy 370.17071 -154.205432) (xy 370.182344 -154.204908)
			(xy 370.203255 -154.194711) (xy 370.210842 -154.185874) (xy 370.227595 -154.165091) (xy 370.265949 -154.127961)
			(xy 370.309103 -154.096539) (xy 370.356217 -154.07144) (xy 370.406369 -154.053154) (xy 370.45858 -154.042037)
			(xy 370.511832 -154.038307) (xy 370.565084 -154.042037) (xy 370.617295 -154.053154) (xy 370.667447 -154.07144)
			(xy 370.714561 -154.096539) (xy 370.757715 -154.127961) (xy 370.796069 -154.165091) (xy 370.812822 -154.185874)
			(xy 370.820417 -154.194693) (xy 370.841327 -154.204867) (xy 370.852954 -154.205432) (xy 370.93271 -154.205432)
			(xy 370.944344 -154.204908) (xy 370.965255 -154.194711) (xy 370.972842 -154.185874) (xy 370.989595 -154.165091)
			(xy 371.027949 -154.127961) (xy 371.071103 -154.096539) (xy 371.118217 -154.07144) (xy 371.168369 -154.053154)
			(xy 371.22058 -154.042037) (xy 371.273832 -154.038307) (xy 371.327084 -154.042037) (xy 371.379295 -154.053154)
			(xy 371.429447 -154.07144) (xy 371.476561 -154.096539) (xy 371.519715 -154.127961) (xy 371.558069 -154.165091)
			(xy 371.574822 -154.185874) (xy 371.582417 -154.194693) (xy 371.603327 -154.204867) (xy 371.614954 -154.205432)
			(xy 371.69471 -154.205432) (xy 371.706344 -154.204908) (xy 371.727255 -154.194711) (xy 371.734842 -154.185874)
			(xy 371.751595 -154.165091) (xy 371.789949 -154.127961) (xy 371.833103 -154.096539) (xy 371.880217 -154.07144)
			(xy 371.930369 -154.053154) (xy 371.98258 -154.042037) (xy 372.035832 -154.038307) (xy 372.089084 -154.042037)
			(xy 372.141295 -154.053154) (xy 372.191447 -154.07144) (xy 372.238561 -154.096539) (xy 372.281715 -154.127961)
			(xy 372.320069 -154.165091) (xy 372.336822 -154.185874) (xy 372.344417 -154.194693) (xy 372.365327 -154.204867)
			(xy 372.376954 -154.205432) (xy 372.45671 -154.205432) (xy 372.468344 -154.204908) (xy 372.489255 -154.194711)
			(xy 372.496842 -154.185874) (xy 372.515003 -154.163365) (xy 372.55703 -154.123633) (xy 372.604571 -154.090697)
			(xy 372.656538 -154.065314) (xy 372.711741 -154.048063) (xy 372.768914 -154.03934) (xy 372.797832 -154.038808)
			(xy 372.825085 -154.039248) (xy 372.879035 -154.047009) (xy 372.931332 -154.062369) (xy 372.98091 -154.085015)
			(xy 373.026761 -154.114487) (xy 373.067951 -154.150183) (xy 373.103642 -154.191378) (xy 373.133108 -154.237232)
			(xy 373.155747 -154.286813) (xy 373.171101 -154.339112) (xy 373.178855 -154.393063) (xy 373.17934 -154.420316)
			(xy 373.178784 -154.449232) (xy 373.170066 -154.506402) (xy 373.152817 -154.561601) (xy 373.127432 -154.613564)
			(xy 373.094494 -154.661098) (xy 373.054758 -154.703116) (xy 373.032274 -154.721306) (xy 373.02347 -154.728916)
			(xy 373.013285 -154.749815) (xy 373.012716 -154.761438) (xy 373.012716 -154.841194) (xy 373.013267 -154.852824)
			(xy 373.023447 -154.873734) (xy 373.032274 -154.881326) (xy 373.053071 -154.898062) (xy 373.090199 -154.936418)
			(xy 373.121617 -154.979576) (xy 373.146714 -155.026691) (xy 373.164998 -155.076845) (xy 373.176112 -155.129058)
			(xy 373.17984 -155.18231) (xy 373.17611 -155.235562) (xy 373.164992 -155.287774) (xy 373.146706 -155.337927)
			(xy 373.121607 -155.385041) (xy 373.090186 -155.428197) (xy 373.053057 -155.466552) (xy 373.032274 -155.483306)
			(xy 373.02347 -155.490916) (xy 373.013285 -155.511815) (xy 373.012716 -155.523438) (xy 373.012716 -155.603194)
			(xy 373.013267 -155.614824) (xy 373.023447 -155.635734) (xy 373.029025 -155.640532) (xy 378.748036 -155.640532)
			(xy 378.748512 -155.613162) (xy 378.756326 -155.558983) (xy 378.771812 -155.50648) (xy 378.794652 -155.456733)
			(xy 378.824375 -155.410766) (xy 378.842016 -155.389834) (xy 378.84227 -155.38958) (xy 378.847879 -155.382509)
			(xy 378.85411 -155.36558) (xy 378.854462 -155.35656) (xy 378.854462 -155.289504) (xy 378.854111 -155.280486)
			(xy 378.84786 -155.263569) (xy 378.84227 -155.256484) (xy 378.842016 -155.256484) (xy 378.842016 -155.25623)
			(xy 378.824407 -155.235272) (xy 378.794682 -155.189308) (xy 378.771835 -155.139566) (xy 378.756337 -155.087068)
			(xy 378.748506 -155.032893) (xy 378.748502 -154.978155) (xy 378.756327 -154.923979) (xy 378.771818 -154.871479)
			(xy 378.794659 -154.821734) (xy 378.824378 -154.775767) (xy 378.842016 -154.754834) (xy 378.84227 -154.75458)
			(xy 378.847879 -154.747509) (xy 378.85411 -154.73058) (xy 378.854462 -154.72156) (xy 378.854462 -154.654504)
			(xy 378.854111 -154.645486) (xy 378.84786 -154.628569) (xy 378.84227 -154.621484) (xy 378.842016 -154.621484)
			(xy 378.842016 -154.62123) (xy 378.824407 -154.600272) (xy 378.794682 -154.554308) (xy 378.771835 -154.504566)
			(xy 378.756337 -154.452068) (xy 378.748506 -154.397893) (xy 378.748502 -154.343155) (xy 378.756327 -154.288979)
			(xy 378.771818 -154.236479) (xy 378.794659 -154.186734) (xy 378.824378 -154.140767) (xy 378.842016 -154.119834)
			(xy 378.84227 -154.11958) (xy 378.847879 -154.112509) (xy 378.85411 -154.09558) (xy 378.854462 -154.08656)
			(xy 378.854462 -154.019504) (xy 378.854111 -154.010486) (xy 378.84786 -153.993569) (xy 378.84227 -153.986484)
			(xy 378.842016 -153.986484) (xy 378.842016 -153.98623) (xy 378.82438 -153.965295) (xy 378.794667 -153.919324)
			(xy 378.77183 -153.869577) (xy 378.756339 -153.817076) (xy 378.74851 -153.762901) (xy 378.748036 -153.735532)
			(xy 378.748485 -153.708278) (xy 378.756239 -153.654324) (xy 378.771593 -153.602023) (xy 378.794235 -153.55244)
			(xy 378.823704 -153.506585) (xy 378.859399 -153.465391) (xy 378.900595 -153.429697) (xy 378.946451 -153.400229)
			(xy 378.996035 -153.377589) (xy 379.048336 -153.362236) (xy 379.10229 -153.354484) (xy 379.129544 -153.354024)
			(xy 379.15945 -153.35459) (xy 379.218528 -153.363942) (xy 379.275423 -153.382394) (xy 379.328744 -153.409495)
			(xy 379.377186 -153.444582) (xy 379.398784 -153.465276) (xy 379.405642 -153.472134) (xy 379.423422 -153.479754)
			(xy 379.512576 -153.482548) (xy 379.530356 -153.476198) (xy 379.537722 -153.469594) (xy 379.545539 -153.462796)
			(xy 379.561805 -153.449962) (xy 379.570234 -153.44394) (xy 379.570488 -153.44394) (xy 379.579143 -153.437041)
			(xy 379.590074 -153.417822) (xy 379.59157 -153.406856) (xy 379.598428 -153.329386) (xy 379.598866 -153.318223)
			(xy 379.591216 -153.297262) (xy 379.583696 -153.289) (xy 379.562873 -153.267422) (xy 379.527622 -153.218915)
			(xy 379.500396 -153.165488) (xy 379.481867 -153.10846) (xy 379.47249 -153.049234) (xy 379.471936 -153.019252)
			(xy 379.472424 -152.991882) (xy 379.480235 -152.937704) (xy 379.495719 -152.885201) (xy 379.518556 -152.835453)
			(xy 379.548276 -152.789486) (xy 379.565916 -152.768554) (xy 379.56617 -152.7683) (xy 379.571771 -152.761224)
			(xy 379.578007 -152.744299) (xy 379.578362 -152.73528) (xy 379.578362 -152.668224) (xy 379.578002 -152.659207)
			(xy 379.571757 -152.64229) (xy 379.56617 -152.635204) (xy 379.565916 -152.635204) (xy 379.565916 -152.63495)
			(xy 379.548289 -152.614008) (xy 379.518575 -152.568038) (xy 379.495737 -152.518293) (xy 379.480243 -152.465795)
			(xy 379.472411 -152.411621) (xy 379.471936 -152.384252) (xy 379.472333 -152.356998) (xy 379.480097 -152.303044)
			(xy 379.495461 -152.250745) (xy 379.518111 -152.201165) (xy 379.547586 -152.155313) (xy 379.583287 -152.114122)
			(xy 379.624486 -152.078431) (xy 379.670346 -152.048967) (xy 379.719932 -152.026329) (xy 379.772234 -152.010978)
			(xy 379.826189 -152.003227) (xy 379.853444 -152.002744) (xy 379.880814 -152.003232) (xy 379.934992 -152.011043)
			(xy 379.987495 -152.026526) (xy 380.037243 -152.049363) (xy 380.08321 -152.079084) (xy 380.104142 -152.096724)
			(xy 380.104396 -152.096978) (xy 380.111473 -152.102578) (xy 380.128397 -152.108815) (xy 380.137416 -152.10917)
			(xy 380.204472 -152.10917) (xy 380.213488 -152.108806) (xy 380.230406 -152.102564) (xy 380.237492 -152.096978)
			(xy 380.237492 -152.096724) (xy 380.237746 -152.096724) (xy 380.258679 -152.079083) (xy 380.304647 -152.049359)
			(xy 380.354393 -152.026513) (xy 380.406895 -152.011017) (xy 380.461073 -152.003188) (xy 380.515815 -152.003188)
			(xy 380.569993 -152.011017) (xy 380.622495 -152.026513) (xy 380.672241 -152.049359) (xy 380.718209 -152.079083)
			(xy 380.739142 -152.096724) (xy 380.739396 -152.096978) (xy 380.746473 -152.102578) (xy 380.763397 -152.108815)
			(xy 380.772416 -152.10917) (xy 380.839472 -152.10917) (xy 380.848488 -152.108806) (xy 380.865406 -152.102564)
			(xy 380.872492 -152.096978) (xy 380.872492 -152.096724) (xy 380.872746 -152.096724) (xy 380.893679 -152.079083)
			(xy 380.939647 -152.049359) (xy 380.989393 -152.026513) (xy 381.041895 -152.011017) (xy 381.096073 -152.003188)
			(xy 381.150815 -152.003188) (xy 381.204993 -152.011017) (xy 381.257495 -152.026513) (xy 381.307241 -152.049359)
			(xy 381.353209 -152.079083) (xy 381.374142 -152.096724) (xy 381.374396 -152.096978) (xy 381.381473 -152.102578)
			(xy 381.398397 -152.108815) (xy 381.407416 -152.10917) (xy 381.474472 -152.10917) (xy 381.483488 -152.108806)
			(xy 381.500406 -152.102564) (xy 381.507492 -152.096978) (xy 381.507492 -152.096724) (xy 381.507746 -152.096724)
			(xy 381.528691 -152.0791) (xy 381.57466 -152.049385) (xy 381.624404 -152.026546) (xy 381.676902 -152.011052)
			(xy 381.731076 -152.00322) (xy 381.758444 -152.002744) (xy 381.785694 -152.003237) (xy 381.839639 -152.010998)
			(xy 381.891931 -152.026356) (xy 381.941505 -152.048999) (xy 381.987353 -152.078465) (xy 382.028541 -152.114156)
			(xy 382.064232 -152.155344) (xy 382.093699 -152.201191) (xy 382.116342 -152.250765) (xy 382.131701 -152.303057)
			(xy 382.139463 -152.357002) (xy 382.139952 -152.384252) (xy 382.139469 -152.411622) (xy 382.131657 -152.465801)
			(xy 382.116173 -152.518304) (xy 382.093334 -152.568051) (xy 382.063612 -152.614018) (xy 382.045972 -152.63495)
			(xy 382.045718 -152.635204) (xy 382.040126 -152.642287) (xy 382.033882 -152.659206) (xy 382.033526 -152.668224)
			(xy 382.033526 -152.73528) (xy 382.033887 -152.744297) (xy 382.040131 -152.761214) (xy 382.045718 -152.7683)
			(xy 382.045972 -152.7683) (xy 382.045972 -152.768554) (xy 382.063599 -152.789496) (xy 382.093313 -152.835466)
			(xy 382.116152 -152.885211) (xy 382.131646 -152.937709) (xy 382.139477 -152.991883) (xy 382.139952 -153.019252)
			(xy 382.139434 -153.048033) (xy 382.13078 -153.104939) (xy 382.113677 -153.159901) (xy 382.088512 -153.21167)
			(xy 382.055856 -153.259071) (xy 382.016451 -153.30103) (xy 381.97119 -153.336593) (xy 381.946404 -153.35123)
			(xy 381.936752 -153.356818) (xy 381.92329 -153.37536) (xy 381.90805 -153.46426) (xy 381.90673 -153.475491)
			(xy 381.912791 -153.497245) (xy 381.919734 -153.50617) (xy 381.937187 -153.527084) (xy 381.96664 -153.572906)
			(xy 381.989282 -153.622449) (xy 382.004654 -153.674706) (xy 382.012443 -153.728617) (xy 382.012952 -153.755852)
			(xy 382.012469 -153.783222) (xy 382.004657 -153.837401) (xy 381.989173 -153.889904) (xy 381.966334 -153.939651)
			(xy 381.936612 -153.985618) (xy 381.918972 -154.00655) (xy 381.918718 -154.006804) (xy 381.913126 -154.013887)
			(xy 381.906882 -154.030806) (xy 381.906526 -154.039824) (xy 381.906526 -154.10688) (xy 381.906887 -154.115897)
			(xy 381.913131 -154.132814) (xy 381.918718 -154.1399) (xy 381.918972 -154.1399) (xy 381.918972 -154.140154)
			(xy 381.936566 -154.161125) (xy 381.966293 -154.207086) (xy 381.989141 -154.256826) (xy 382.004641 -154.309322)
			(xy 382.012474 -154.363496) (xy 382.012479 -154.418232) (xy 382.004656 -154.472407) (xy 381.989166 -154.524906)
			(xy 381.966327 -154.574651) (xy 381.936609 -154.620617) (xy 381.918972 -154.64155) (xy 381.918718 -154.641804)
			(xy 381.913126 -154.648887) (xy 381.906882 -154.665806) (xy 381.906526 -154.674824) (xy 381.906526 -154.74188)
			(xy 381.906887 -154.750897) (xy 381.913131 -154.767814) (xy 381.918718 -154.7749) (xy 381.918972 -154.7749)
			(xy 381.918972 -154.775154) (xy 381.936566 -154.796125) (xy 381.966293 -154.842086) (xy 381.989141 -154.891826)
			(xy 382.004641 -154.944322) (xy 382.012474 -154.998496) (xy 382.012479 -155.053232) (xy 382.004656 -155.107407)
			(xy 381.989166 -155.159906) (xy 381.966327 -155.209651) (xy 381.936609 -155.255617) (xy 381.918972 -155.27655)
			(xy 381.918718 -155.276804) (xy 381.913126 -155.283887) (xy 381.906882 -155.300806) (xy 381.906526 -155.309824)
			(xy 381.906526 -155.37688) (xy 381.906887 -155.385897) (xy 381.913131 -155.402814) (xy 381.918718 -155.4099)
			(xy 381.918972 -155.4099) (xy 381.918972 -155.410154) (xy 381.936599 -155.431096) (xy 381.966313 -155.477066)
			(xy 381.989152 -155.526811) (xy 382.004646 -155.579309) (xy 382.012477 -155.633483) (xy 382.012952 -155.660852)
			(xy 382.012435 -155.688653) (xy 382.004382 -155.743668) (xy 381.988424 -155.79693) (xy 381.9649 -155.84731)
			(xy 381.934309 -155.89374) (xy 381.897299 -155.935234) (xy 381.8763 -155.95346) (xy 381.86815 -155.961065)
			(xy 381.858649 -155.981196) (xy 381.858012 -155.992322) (xy 381.858012 -156.071824) (xy 381.876046 -156.097732)
			(xy 381.891286 -156.10332) (xy 381.918266 -156.113936) (xy 381.968932 -156.142116) (xy 382.014751 -156.177637)
			(xy 382.054669 -156.21968) (xy 382.087768 -156.267279) (xy 382.113284 -156.319338) (xy 382.130631 -156.374657)
			(xy 382.139409 -156.431964) (xy 382.139952 -156.460952) (xy 382.139469 -156.488322) (xy 382.131657 -156.542501)
			(xy 382.116173 -156.595004) (xy 382.093334 -156.644751) (xy 382.063612 -156.690718) (xy 382.045972 -156.71165)
			(xy 382.045718 -156.711904) (xy 382.040126 -156.718987) (xy 382.033882 -156.735906) (xy 382.033526 -156.744924)
			(xy 382.033526 -156.81198) (xy 382.033887 -156.820997) (xy 382.040131 -156.837914) (xy 382.045718 -156.845)
			(xy 382.045972 -156.845) (xy 382.045972 -156.845254) (xy 382.063599 -156.866196) (xy 382.093313 -156.912166)
			(xy 382.116152 -156.961911) (xy 382.127975 -157.001972) (xy 386.91185 -157.001972) (xy 386.912287 -156.974601)
			(xy 386.92011 -156.92042) (xy 386.935605 -156.867916) (xy 386.958454 -156.818169) (xy 386.988185 -156.772204)
			(xy 387.00583 -156.751274) (xy 387.006084 -156.75102) (xy 387.011667 -156.743931) (xy 387.017916 -156.727016)
			(xy 387.018276 -156.718) (xy 387.018276 -156.650944) (xy 387.017903 -156.641929) (xy 387.011667 -156.625011)
			(xy 387.006084 -156.617924) (xy 387.00583 -156.617924) (xy 387.00583 -156.61767) (xy 386.988215 -156.596718)
			(xy 386.958498 -156.550752) (xy 386.935657 -156.501009) (xy 386.920161 -156.448512) (xy 386.912327 -156.39434)
			(xy 386.91185 -156.366972) (xy 386.912354 -156.339204) (xy 386.920393 -156.284252) (xy 386.936312 -156.231046)
			(xy 386.959775 -156.180709) (xy 386.990286 -156.134304) (xy 387.00837 -156.113226) (xy 387.014252 -156.106038)
			(xy 387.020913 -156.088721) (xy 387.021324 -156.079444) (xy 387.021324 -156.01188) (xy 387.020905 -156.002605)
			(xy 387.014247 -155.985287) (xy 387.00837 -155.978098) (xy 386.990305 -155.957004) (xy 386.959797 -155.910601)
			(xy 386.936331 -155.860268) (xy 386.920405 -155.807066) (xy 386.912353 -155.752119) (xy 386.91185 -155.724352)
			(xy 386.912334 -155.696982) (xy 386.920146 -155.642803) (xy 386.93563 -155.5903) (xy 386.958468 -155.540553)
			(xy 386.98819 -155.494586) (xy 387.00583 -155.473654) (xy 387.006084 -155.4734) (xy 387.011675 -155.466316)
			(xy 387.017919 -155.449397) (xy 387.018276 -155.44038) (xy 387.018276 -155.373324) (xy 387.017912 -155.364308)
			(xy 387.01167 -155.34739) (xy 387.006084 -155.340304) (xy 387.00583 -155.340304) (xy 387.00583 -155.34005)
			(xy 386.988206 -155.319106) (xy 386.95849 -155.273137) (xy 386.935651 -155.223393) (xy 386.920157 -155.170894)
			(xy 386.912326 -155.11672) (xy 386.91185 -155.089352) (xy 386.912358 -155.060613) (xy 386.920986 -155.003785)
			(xy 386.938041 -154.948895) (xy 386.963136 -154.897183) (xy 386.995703 -154.849821) (xy 387.014974 -154.828494)
			(xy 387.021578 -154.821636) (xy 387.02869 -154.803602) (xy 387.02869 -154.714702) (xy 387.021578 -154.696668)
			(xy 387.014974 -154.68981) (xy 386.995686 -154.668497) (xy 386.963121 -154.621132) (xy 386.938031 -154.569417)
			(xy 386.920985 -154.514523) (xy 386.912368 -154.457692) (xy 386.91185 -154.428952) (xy 386.912334 -154.401582)
			(xy 386.920146 -154.347403) (xy 386.93563 -154.2949) (xy 386.958468 -154.245153) (xy 386.98819 -154.199186)
			(xy 387.00583 -154.178254) (xy 387.006084 -154.178) (xy 387.011675 -154.170916) (xy 387.017919 -154.153997)
			(xy 387.018276 -154.14498) (xy 387.018276 -154.077924) (xy 387.017912 -154.068908) (xy 387.01167 -154.05199)
			(xy 387.006084 -154.044904) (xy 387.00583 -154.044904) (xy 387.00583 -154.04465) (xy 386.988206 -154.023706)
			(xy 386.95849 -153.977737) (xy 386.935651 -153.927993) (xy 386.920157 -153.875494) (xy 386.912326 -153.82132)
			(xy 386.91185 -153.793952) (xy 386.912333 -153.766701) (xy 386.920095 -153.712756) (xy 386.935454 -153.660464)
			(xy 386.958098 -153.610889) (xy 386.987565 -153.565041) (xy 387.023257 -153.523852) (xy 387.064446 -153.488162)
			(xy 387.110294 -153.458695) (xy 387.159869 -153.436052) (xy 387.212162 -153.420694) (xy 387.266107 -153.412933)
			(xy 387.293358 -153.412444) (xy 387.320728 -153.412924) (xy 387.374907 -153.420737) (xy 387.42741 -153.436222)
			(xy 387.477157 -153.459061) (xy 387.523124 -153.488783) (xy 387.544056 -153.506424) (xy 387.54431 -153.506678)
			(xy 387.551383 -153.512284) (xy 387.56831 -153.518517) (xy 387.57733 -153.51887) (xy 387.644386 -153.51887)
			(xy 387.653403 -153.518513) (xy 387.67032 -153.512266) (xy 387.677406 -153.506678) (xy 387.677406 -153.506424)
			(xy 387.67766 -153.506424) (xy 387.698599 -153.488794) (xy 387.74457 -153.45908) (xy 387.794315 -153.436242)
			(xy 387.846815 -153.420749) (xy 387.900989 -153.412919) (xy 387.928358 -153.412444) (xy 387.955606 -153.413017)
			(xy 388.009548 -153.420767) (xy 388.061838 -153.436114) (xy 388.111412 -153.458747) (xy 388.15726 -153.488204)
			(xy 388.19845 -153.523887) (xy 388.234142 -153.565068) (xy 388.26361 -153.610909) (xy 388.286254 -153.660477)
			(xy 388.301614 -153.712764) (xy 388.309376 -153.766704) (xy 388.309866 -153.793952) (xy 388.30938 -153.821322)
			(xy 388.301568 -153.8755) (xy 388.286084 -153.928003) (xy 388.263247 -153.977751) (xy 388.233526 -154.023718)
			(xy 388.215886 -154.04465) (xy 388.215632 -154.044904) (xy 388.21003 -154.051979) (xy 388.203794 -154.068905)
			(xy 388.20344 -154.077924) (xy 388.20344 -154.14498) (xy 388.203798 -154.153997) (xy 388.210044 -154.170914)
			(xy 388.215632 -154.178) (xy 388.215886 -154.178) (xy 388.215886 -154.178254) (xy 388.233515 -154.199194)
			(xy 388.263229 -154.245165) (xy 388.286067 -154.29491) (xy 388.30156 -154.347409) (xy 388.309391 -154.401583)
			(xy 388.309866 -154.428952) (xy 388.309356 -154.457691) (xy 388.300728 -154.514518) (xy 388.283673 -154.569409)
			(xy 388.258579 -154.62112) (xy 388.226013 -154.668483) (xy 388.206742 -154.68981) (xy 388.200138 -154.696668)
			(xy 388.193026 -154.714702) (xy 388.193026 -154.803602) (xy 388.200138 -154.821636) (xy 388.206742 -154.828494)
			(xy 388.226034 -154.849803) (xy 388.258598 -154.897169) (xy 388.283687 -154.948886) (xy 388.300732 -155.003781)
			(xy 388.309349 -155.060612) (xy 388.309866 -155.089352) (xy 388.30938 -155.116722) (xy 388.301568 -155.1709)
			(xy 388.286084 -155.223403) (xy 388.263247 -155.273151) (xy 388.233526 -155.319118) (xy 388.215886 -155.34005)
			(xy 388.215632 -155.340304) (xy 388.21003 -155.347379) (xy 388.203794 -155.364305) (xy 388.20344 -155.373324)
			(xy 388.20344 -155.44038) (xy 388.203798 -155.449397) (xy 388.210044 -155.466314) (xy 388.215632 -155.4734)
			(xy 388.215886 -155.4734) (xy 388.215886 -155.473654) (xy 388.233515 -155.494594) (xy 388.263229 -155.540565)
			(xy 388.286067 -155.59031) (xy 388.30156 -155.642809) (xy 388.309391 -155.696983) (xy 388.309866 -155.724352)
			(xy 388.309372 -155.752121) (xy 388.30133 -155.807073) (xy 388.285408 -155.860279) (xy 388.261943 -155.910615)
			(xy 388.231431 -155.95702) (xy 388.213346 -155.978098) (xy 388.207444 -155.985271) (xy 388.200797 -156.0026)
			(xy 388.200392 -156.01188) (xy 388.200392 -156.079444) (xy 388.200867 -156.088712) (xy 388.207488 -156.10603)
			(xy 388.213346 -156.113226) (xy 388.231425 -156.134308) (xy 388.261931 -156.180715) (xy 388.285393 -156.231051)
			(xy 388.301316 -156.284255) (xy 388.309365 -156.339204) (xy 388.309866 -156.366972) (xy 388.309392 -156.394342)
			(xy 388.301577 -156.448521) (xy 388.28609 -156.501024) (xy 388.26325 -156.550771) (xy 388.233527 -156.596738)
			(xy 388.215886 -156.61767) (xy 388.215632 -156.617924) (xy 388.210021 -156.624994) (xy 388.203791 -156.641924)
			(xy 388.20344 -156.650944) (xy 388.20344 -156.718) (xy 388.203789 -156.727018) (xy 388.210041 -156.743935)
			(xy 388.215632 -156.75102) (xy 388.215886 -156.75102) (xy 388.215886 -156.751274) (xy 388.233524 -156.772207)
			(xy 388.263237 -156.818179) (xy 388.286073 -156.867926) (xy 388.301564 -156.920427) (xy 388.309392 -156.974603)
			(xy 388.309866 -157.001972) (xy 388.309419 -157.029226) (xy 388.301664 -157.08318) (xy 388.28631 -157.13548)
			(xy 388.263667 -157.185063) (xy 388.234198 -157.230919) (xy 388.198503 -157.272113) (xy 388.157307 -157.307807)
			(xy 388.111451 -157.337274) (xy 388.061867 -157.359915) (xy 388.009566 -157.375267) (xy 387.955612 -157.38302)
			(xy 387.928358 -157.38348) (xy 387.900989 -157.382985) (xy 387.846811 -157.375175) (xy 387.794308 -157.359693)
			(xy 387.74456 -157.336857) (xy 387.698592 -157.307139) (xy 387.67766 -157.2895) (xy 387.677406 -157.289246)
			(xy 387.670327 -157.283649) (xy 387.653404 -157.27741) (xy 387.644386 -157.277054) (xy 387.57733 -157.277054)
			(xy 387.568313 -157.277414) (xy 387.551396 -157.283658) (xy 387.54431 -157.289246) (xy 387.54431 -157.2895)
			(xy 387.544056 -157.2895) (xy 387.523114 -157.307126) (xy 387.477144 -157.33684) (xy 387.427399 -157.359678)
			(xy 387.3749 -157.375173) (xy 387.320726 -157.383004) (xy 387.293358 -157.38348) (xy 387.266104 -157.383061)
			(xy 387.212153 -157.375298) (xy 387.159855 -157.359936) (xy 387.110276 -157.337288) (xy 387.064424 -157.307815)
			(xy 387.023234 -157.272117) (xy 386.987543 -157.23092) (xy 386.958078 -157.185063) (xy 386.935439 -157.135479)
			(xy 386.920087 -157.083179) (xy 386.912334 -157.029226) (xy 386.91185 -157.001972) (xy 382.127975 -157.001972)
			(xy 382.131646 -157.014409) (xy 382.139477 -157.068583) (xy 382.139952 -157.095952) (xy 382.1394 -157.123202)
			(xy 382.131651 -157.177147) (xy 382.116303 -157.229441) (xy 382.093669 -157.279018) (xy 382.064211 -157.324869)
			(xy 382.028526 -157.366061) (xy 381.987343 -157.401755) (xy 381.941499 -157.431225) (xy 381.891927 -157.453871)
			(xy 381.839637 -157.469231) (xy 381.785694 -157.476994) (xy 381.758444 -157.47746) (xy 381.731074 -157.476978)
			(xy 381.676895 -157.469165) (xy 381.624392 -157.453681) (xy 381.574645 -157.430842) (xy 381.528678 -157.40112)
			(xy 381.507746 -157.38348) (xy 381.507492 -157.383226) (xy 381.500418 -157.377621) (xy 381.483491 -157.371387)
			(xy 381.474472 -157.371034) (xy 381.407416 -157.371034) (xy 381.398399 -157.371391) (xy 381.381482 -157.377638)
			(xy 381.374396 -157.383226) (xy 381.374396 -157.38348) (xy 381.374142 -157.38348) (xy 381.353209 -157.401121)
			(xy 381.307241 -157.430845) (xy 381.257495 -157.453691) (xy 381.204993 -157.469187) (xy 381.150815 -157.477016)
			(xy 381.096073 -157.477016) (xy 381.041895 -157.469187) (xy 380.989393 -157.453691) (xy 380.939647 -157.430845)
			(xy 380.893679 -157.401121) (xy 380.872746 -157.38348) (xy 380.872492 -157.383226) (xy 380.865418 -157.377621)
			(xy 380.848491 -157.371387) (xy 380.839472 -157.371034) (xy 380.772416 -157.371034) (xy 380.763399 -157.371391)
			(xy 380.746482 -157.377638) (xy 380.739396 -157.383226) (xy 380.739396 -157.38348) (xy 380.739142 -157.38348)
			(xy 380.718209 -157.401121) (xy 380.672241 -157.430845) (xy 380.622495 -157.453691) (xy 380.569993 -157.469187)
			(xy 380.515815 -157.477016) (xy 380.461073 -157.477016) (xy 380.406895 -157.469187) (xy 380.354393 -157.453691)
			(xy 380.304647 -157.430845) (xy 380.258679 -157.401121) (xy 380.237746 -157.38348) (xy 380.237492 -157.383226)
			(xy 380.230418 -157.377621) (xy 380.213491 -157.371387) (xy 380.204472 -157.371034) (xy 380.137416 -157.371034)
			(xy 380.128399 -157.371391) (xy 380.111482 -157.377638) (xy 380.104396 -157.383226) (xy 380.104396 -157.38348)
			(xy 380.104142 -157.38348) (xy 380.083202 -157.40111) (xy 380.037232 -157.430824) (xy 379.987486 -157.453662)
			(xy 379.934987 -157.469155) (xy 379.880813 -157.476985) (xy 379.853444 -157.47746) (xy 379.82354 -157.476843)
			(xy 379.764464 -157.467504) (xy 379.707569 -157.449064) (xy 379.654247 -157.421974) (xy 379.605804 -157.386898)
			(xy 379.584204 -157.366208) (xy 379.577346 -157.35935) (xy 379.559566 -157.35173) (xy 379.470412 -157.348936)
			(xy 379.452632 -157.355286) (xy 379.445266 -157.36189) (xy 379.424251 -157.37974) (xy 379.378064 -157.409851)
			(xy 379.328024 -157.433002) (xy 379.275173 -157.448711) (xy 379.220612 -157.456652) (xy 379.193044 -157.45714)
			(xy 379.165794 -157.456604) (xy 379.111847 -157.448854) (xy 379.059552 -157.433505) (xy 379.009975 -157.41087)
			(xy 378.964123 -157.381409) (xy 378.92293 -157.345723) (xy 378.887236 -157.304538) (xy 378.857767 -157.258692)
			(xy 378.835122 -157.209119) (xy 378.819762 -157.156827) (xy 378.812002 -157.102882) (xy 378.811536 -157.075632)
			(xy 378.812012 -157.048262) (xy 378.819826 -156.994083) (xy 378.835312 -156.94158) (xy 378.858152 -156.891833)
			(xy 378.887875 -156.845866) (xy 378.905516 -156.824934) (xy 378.90577 -156.82468) (xy 378.911379 -156.817609)
			(xy 378.91761 -156.80068) (xy 378.917962 -156.79166) (xy 378.917962 -156.724604) (xy 378.917611 -156.715586)
			(xy 378.91136 -156.698669) (xy 378.90577 -156.691584) (xy 378.905516 -156.691584) (xy 378.905516 -156.69133)
			(xy 378.88788 -156.670395) (xy 378.858167 -156.624424) (xy 378.83533 -156.574677) (xy 378.819839 -156.522176)
			(xy 378.81201 -156.468001) (xy 378.811536 -156.440632) (xy 378.812066 -156.411956) (xy 378.820635 -156.355248)
			(xy 378.837599 -156.300463) (xy 378.862576 -156.248836) (xy 378.895002 -156.201531) (xy 378.934147 -156.159616)
			(xy 378.956316 -156.14142) (xy 378.966222 -156.133546) (xy 378.976382 -156.110432) (xy 378.967492 -156.000704)
			(xy 378.95403 -155.979622) (xy 378.942854 -155.973272) (xy 378.917936 -155.958648) (xy 378.872393 -155.923103)
			(xy 378.832729 -155.881098) (xy 378.79985 -155.833593) (xy 378.774509 -155.781675) (xy 378.757285 -155.72653)
			(xy 378.74857 -155.669418) (xy 378.748036 -155.640532) (xy 373.029025 -155.640532) (xy 373.032274 -155.643326)
			(xy 373.053071 -155.660062) (xy 373.090199 -155.698418) (xy 373.121617 -155.741576) (xy 373.146714 -155.788691)
			(xy 373.164998 -155.838845) (xy 373.176112 -155.891058) (xy 373.17984 -155.94431) (xy 373.17611 -155.997562)
			(xy 373.164992 -156.049774) (xy 373.146706 -156.099927) (xy 373.121607 -156.147041) (xy 373.090186 -156.190197)
			(xy 373.053057 -156.228552) (xy 373.032274 -156.245306) (xy 373.02347 -156.252916) (xy 373.013285 -156.273815)
			(xy 373.012716 -156.285438) (xy 373.012716 -156.365194) (xy 373.013267 -156.376824) (xy 373.023447 -156.397734)
			(xy 373.032274 -156.405326) (xy 373.053071 -156.422062) (xy 373.090199 -156.460418) (xy 373.121617 -156.503576)
			(xy 373.146714 -156.550691) (xy 373.164998 -156.600845) (xy 373.176112 -156.653058) (xy 373.17984 -156.70631)
			(xy 373.17611 -156.759562) (xy 373.164992 -156.811774) (xy 373.146706 -156.861927) (xy 373.121607 -156.909041)
			(xy 373.090186 -156.952197) (xy 373.053057 -156.990552) (xy 373.032274 -157.007306) (xy 373.02347 -157.014916)
			(xy 373.013285 -157.035815) (xy 373.012716 -157.047438) (xy 373.012716 -157.127194) (xy 373.013267 -157.138824)
			(xy 373.023447 -157.159734) (xy 373.032274 -157.167326) (xy 373.053071 -157.184062) (xy 373.090199 -157.222418)
			(xy 373.121617 -157.265576) (xy 373.146714 -157.312691) (xy 373.164998 -157.362845) (xy 373.176112 -157.415058)
			(xy 373.17984 -157.46831) (xy 373.17611 -157.521562) (xy 373.164992 -157.573774) (xy 373.146706 -157.623927)
			(xy 373.121607 -157.671041) (xy 373.090186 -157.714197) (xy 373.053057 -157.752552) (xy 373.032274 -157.769306)
			(xy 373.02347 -157.776916) (xy 373.013285 -157.797815) (xy 373.012716 -157.809438) (xy 373.012716 -157.889194)
			(xy 373.013267 -157.900824) (xy 373.023447 -157.921734) (xy 373.032274 -157.929326) (xy 373.054765 -157.947509)
			(xy 373.0945 -157.98953) (xy 373.127439 -158.037066) (xy 373.152827 -158.089029) (xy 373.170081 -158.144228)
			(xy 373.178807 -158.201399) (xy 373.17934 -158.230316) (xy 373.178837 -158.257566) (xy 373.171079 -158.311512)
			(xy 373.155724 -158.363804) (xy 373.133083 -158.413379) (xy 373.103618 -158.459228) (xy 373.067929 -158.500417)
			(xy 373.026741 -158.536109) (xy 372.980893 -158.565575) (xy 372.931319 -158.588218) (xy 372.879027 -158.603576)
			(xy 372.825082 -158.611336) (xy 372.797832 -158.611824) (xy 372.768915 -158.611312) (xy 372.711742 -158.602585)
			(xy 372.656542 -158.585328) (xy 372.604579 -158.559936) (xy 372.557046 -158.52699) (xy 372.515031 -158.487245)
			(xy 372.496842 -158.464758) (xy 372.489214 -158.455973) (xy 372.468329 -158.445779) (xy 372.45671 -158.4452)
			(xy 372.376954 -158.4452) (xy 372.365321 -158.445727) (xy 372.344411 -158.455924) (xy 372.336822 -158.464758)
			(xy 372.320069 -158.485541) (xy 372.281715 -158.522671) (xy 372.238561 -158.554093) (xy 372.191447 -158.579192)
			(xy 372.141295 -158.597478) (xy 372.089084 -158.608595) (xy 372.035832 -158.612325) (xy 371.98258 -158.608595)
			(xy 371.930369 -158.597478) (xy 371.880217 -158.579192) (xy 371.833103 -158.554093) (xy 371.789949 -158.522671)
			(xy 371.751595 -158.485541) (xy 371.734842 -158.464758) (xy 371.727214 -158.455973) (xy 371.706329 -158.445779)
			(xy 371.69471 -158.4452) (xy 371.614954 -158.4452) (xy 371.603321 -158.445727) (xy 371.582411 -158.455924)
			(xy 371.574822 -158.464758) (xy 371.556608 -158.487222) (xy 371.514594 -158.526961) (xy 371.467065 -158.559903)
			(xy 371.415108 -158.585295) (xy 371.359914 -158.602555) (xy 371.302747 -158.611287) (xy 371.273832 -158.611824)
			(xy 371.246985 -158.611383) (xy 371.19382 -158.603872) (xy 371.142233 -158.588978) (xy 371.093246 -158.566998)
			(xy 371.047824 -158.538364) (xy 371.006867 -158.503644) (xy 370.971184 -158.463523) (xy 370.941481 -158.418794)
			(xy 370.918343 -158.370342) (xy 370.90985 -158.34487) (xy 370.90985 -158.344616) (xy 370.906145 -158.334478)
			(xy 370.891796 -158.318377) (xy 370.872119 -158.309548) (xy 370.861336 -158.309056) (xy 370.430298 -158.309056)
			(xy 370.422678 -158.311596) (xy 370.394291 -158.320136) (xy 370.335731 -158.329324) (xy 370.306092 -158.329884)
			(xy 370.276456 -158.329298) (xy 370.217897 -158.320116) (xy 370.189506 -158.311596) (xy 370.181886 -158.309056)
			(xy 369.795298 -158.309056) (xy 369.787678 -158.311596) (xy 369.759291 -158.320136) (xy 369.700731 -158.329324)
			(xy 369.671092 -158.329884) (xy 369.641456 -158.329298) (xy 369.582897 -158.320116) (xy 369.554506 -158.311596)
			(xy 369.546886 -158.309056) (xy 369.160298 -158.309056) (xy 369.152678 -158.311596) (xy 369.124291 -158.320136)
			(xy 369.065731 -158.329324) (xy 369.036092 -158.329884) (xy 369.006456 -158.329298) (xy 368.947897 -158.320116)
			(xy 368.919506 -158.311596) (xy 368.911886 -158.309056) (xy 368.525298 -158.309056) (xy 368.517678 -158.311596)
			(xy 368.489291 -158.320136) (xy 368.430731 -158.329324) (xy 368.401092 -158.329884) (xy 368.371456 -158.329298)
			(xy 368.312897 -158.320116) (xy 368.284506 -158.311596) (xy 368.276886 -158.309056) (xy 367.876328 -158.309056)
			(xy 367.865542 -158.309553) (xy 367.845852 -158.31836) (xy 367.831513 -158.334474) (xy 367.827814 -158.344616)
			(xy 367.827814 -158.34487) (xy 367.81935 -158.370349) (xy 367.79619 -158.418787) (xy 367.766471 -158.463501)
			(xy 367.730779 -158.50361) (xy 367.689819 -158.538322) (xy 367.6444 -158.566952) (xy 367.595417 -158.588935)
			(xy 367.543837 -158.603838) (xy 367.490677 -158.611365) (xy 367.463832 -158.611824) (xy 367.434915 -158.611312)
			(xy 367.377742 -158.602585) (xy 367.322542 -158.585328) (xy 367.270579 -158.559936) (xy 367.223046 -158.52699)
			(xy 367.181031 -158.487245) (xy 367.162842 -158.464758) (xy 367.155214 -158.455973) (xy 367.134329 -158.445779)
			(xy 367.12271 -158.4452) (xy 367.042954 -158.4452) (xy 367.031321 -158.445727) (xy 367.010411 -158.455924)
			(xy 367.002822 -158.464758) (xy 366.986069 -158.485541) (xy 366.947715 -158.522671) (xy 366.904561 -158.554093)
			(xy 366.857447 -158.579192) (xy 366.807295 -158.597478) (xy 366.755084 -158.608595) (xy 366.701832 -158.612325)
			(xy 366.64858 -158.608595) (xy 366.596369 -158.597478) (xy 366.546217 -158.579192) (xy 366.499103 -158.554093)
			(xy 366.455949 -158.522671) (xy 366.417595 -158.485541) (xy 366.400842 -158.464758) (xy 366.393214 -158.455973)
			(xy 366.372329 -158.445779) (xy 366.36071 -158.4452) (xy 366.280954 -158.4452) (xy 366.269321 -158.445727)
			(xy 366.248411 -158.455924) (xy 366.240822 -158.464758) (xy 366.222608 -158.487222) (xy 366.180594 -158.526961)
			(xy 366.133065 -158.559903) (xy 366.081108 -158.585295) (xy 366.025914 -158.602555) (xy 365.968747 -158.611287)
			(xy 365.939832 -158.611824) (xy 365.912581 -158.611315) (xy 365.858632 -158.603563) (xy 365.806336 -158.588212)
			(xy 365.756757 -158.565574) (xy 365.710905 -158.536111) (xy 365.669712 -158.500422) (xy 365.634018 -158.459234)
			(xy 365.604549 -158.413385) (xy 365.581905 -158.363809) (xy 365.566547 -158.311515) (xy 365.558788 -158.257567)
			(xy 365.558324 -158.230316) (xy 365.558845 -158.201399) (xy 365.567572 -158.144228) (xy 365.584829 -158.089028)
			(xy 365.61022 -158.037067) (xy 365.643164 -157.989533) (xy 365.682904 -157.947516) (xy 365.70539 -157.929326)
			(xy 365.714174 -157.921696) (xy 365.724371 -157.900813) (xy 365.724948 -157.889194) (xy 365.724948 -157.809438)
			(xy 365.724448 -157.797801) (xy 365.714233 -157.77689) (xy 365.70539 -157.769306) (xy 365.684622 -157.752534)
			(xy 365.647489 -157.714185) (xy 365.616065 -157.671033) (xy 365.590963 -157.623922) (xy 365.572675 -157.573771)
			(xy 365.561556 -157.52156) (xy 365.557825 -157.46831) (xy 361.257332 -157.46831) (xy 360.928158 -157.7975)
			(xy 360.92132 -157.804901) (xy 360.9136 -157.8235) (xy 360.913172 -157.833568) (xy 360.913172 -161.993072)
			(xy 360.91252 -162.018067) (xy 360.902721 -162.067089) (xy 360.883552 -162.11326) (xy 360.855749 -162.154807)
			(xy 360.838496 -162.172904) (xy 360.372222 -162.639178) (xy 376.980954 -162.639178) (xy 376.980954 -162.554482)
			(xy 376.989005 -162.470168) (xy 377.005034 -162.387002) (xy 377.028895 -162.305735) (xy 377.060374 -162.227105)
			(xy 377.099185 -162.151824) (xy 377.144975 -162.080572) (xy 377.197331 -162.013996) (xy 377.255779 -161.952698)
			(xy 377.319789 -161.897233) (xy 377.388781 -161.848104) (xy 377.462131 -161.805755) (xy 377.539174 -161.770571)
			(xy 377.619213 -161.742869) (xy 377.701522 -161.722901) (xy 377.785357 -161.710848) (xy 377.869958 -161.706818)
			(xy 377.954559 -161.710848) (xy 378.038394 -161.722901) (xy 378.120703 -161.742869) (xy 378.200742 -161.770571)
			(xy 378.277785 -161.805755) (xy 378.351135 -161.848104) (xy 378.420127 -161.897233) (xy 378.484137 -161.952698)
			(xy 378.542585 -162.013996) (xy 378.594941 -162.080572) (xy 378.640731 -162.151824) (xy 378.679542 -162.227105)
			(xy 378.711021 -162.305735) (xy 378.734882 -162.387002) (xy 378.750911 -162.470168) (xy 378.758962 -162.554482)
			(xy 378.759466 -162.59683) (xy 378.758962 -162.639178) (xy 378.753626 -162.695058) (xy 386.317994 -162.695058)
			(xy 386.317994 -162.610362) (xy 386.326045 -162.526048) (xy 386.342074 -162.442882) (xy 386.365935 -162.361615)
			(xy 386.397414 -162.282985) (xy 386.436225 -162.207704) (xy 386.482015 -162.136452) (xy 386.534371 -162.069876)
			(xy 386.592819 -162.008578) (xy 386.656829 -161.953113) (xy 386.725821 -161.903984) (xy 386.799171 -161.861635)
			(xy 386.876214 -161.826451) (xy 386.956253 -161.798749) (xy 387.038562 -161.778781) (xy 387.122397 -161.766728)
			(xy 387.206998 -161.762698) (xy 387.291599 -161.766728) (xy 387.375434 -161.778781) (xy 387.457743 -161.798749)
			(xy 387.537782 -161.826451) (xy 387.614825 -161.861635) (xy 387.688175 -161.903984) (xy 387.757167 -161.953113)
			(xy 387.821177 -162.008578) (xy 387.879625 -162.069876) (xy 387.931981 -162.136452) (xy 387.977771 -162.207704)
			(xy 388.016582 -162.282985) (xy 388.048061 -162.361615) (xy 388.071922 -162.442882) (xy 388.087951 -162.526048)
			(xy 388.096002 -162.610362) (xy 388.096506 -162.65271) (xy 388.096002 -162.695058) (xy 388.087951 -162.779372)
			(xy 388.071922 -162.862538) (xy 388.048061 -162.943805) (xy 388.016582 -163.022435) (xy 387.977771 -163.097716)
			(xy 387.931981 -163.168968) (xy 387.879625 -163.235544) (xy 387.821177 -163.296842) (xy 387.757167 -163.352307)
			(xy 387.688175 -163.401436) (xy 387.614825 -163.443785) (xy 387.537782 -163.478969) (xy 387.457743 -163.506671)
			(xy 387.375434 -163.526639) (xy 387.291599 -163.538692) (xy 387.206998 -163.542723) (xy 387.122397 -163.538692)
			(xy 387.038562 -163.526639) (xy 386.956253 -163.506671) (xy 386.876214 -163.478969) (xy 386.799171 -163.443785)
			(xy 386.725821 -163.401436) (xy 386.656829 -163.352307) (xy 386.592819 -163.296842) (xy 386.534371 -163.235544)
			(xy 386.482015 -163.168968) (xy 386.436225 -163.097716) (xy 386.397414 -163.022435) (xy 386.365935 -162.943805)
			(xy 386.342074 -162.862538) (xy 386.326045 -162.779372) (xy 386.317994 -162.695058) (xy 378.753626 -162.695058)
			(xy 378.750911 -162.723492) (xy 378.734882 -162.806658) (xy 378.711021 -162.887925) (xy 378.679542 -162.966555)
			(xy 378.640731 -163.041836) (xy 378.594941 -163.113088) (xy 378.542585 -163.179664) (xy 378.484137 -163.240962)
			(xy 378.420127 -163.296427) (xy 378.351135 -163.345556) (xy 378.277785 -163.387905) (xy 378.200742 -163.423089)
			(xy 378.120703 -163.450791) (xy 378.038394 -163.470759) (xy 377.954559 -163.482812) (xy 377.869958 -163.486843)
			(xy 377.785357 -163.482812) (xy 377.701522 -163.470759) (xy 377.619213 -163.450791) (xy 377.539174 -163.423089)
			(xy 377.462131 -163.387905) (xy 377.388781 -163.345556) (xy 377.319789 -163.296427) (xy 377.255779 -163.240962)
			(xy 377.197331 -163.179664) (xy 377.144975 -163.113088) (xy 377.099185 -163.041836) (xy 377.060374 -162.966555)
			(xy 377.028895 -162.887925) (xy 377.005034 -162.806658) (xy 376.989005 -162.723492) (xy 376.980954 -162.639178)
			(xy 360.372222 -162.639178) (xy 359.707942 -163.303458) (xy 359.701285 -163.310892) (xy 359.693682 -163.329315)
			(xy 359.693674 -163.349246) (xy 359.701263 -163.367675) (xy 359.707942 -163.375086) (xy 360.866436 -164.53358)
			(xy 366.362996 -164.53358) (xy 366.363451 -164.506209) (xy 366.371272 -164.45203) (xy 366.386764 -164.399527)
			(xy 366.409608 -164.34978) (xy 366.439334 -164.303814) (xy 366.456976 -164.282882) (xy 366.45723 -164.282628)
			(xy 366.462814 -164.27554) (xy 366.469061 -164.258624) (xy 366.469422 -164.249608) (xy 366.469422 -164.182552)
			(xy 366.469035 -164.173538) (xy 366.462808 -164.156621) (xy 366.45723 -164.149532) (xy 366.456976 -164.149532)
			(xy 366.456976 -164.149278) (xy 366.439356 -164.12833) (xy 366.409642 -164.082361) (xy 366.386803 -164.032618)
			(xy 366.371307 -163.980121) (xy 366.363473 -163.925948) (xy 366.362996 -163.89858) (xy 366.363459 -163.871328)
			(xy 366.371219 -163.817379) (xy 366.386576 -163.765084) (xy 366.40922 -163.715506) (xy 366.438689 -163.669656)
			(xy 366.474383 -163.628466) (xy 366.515575 -163.592775) (xy 366.561427 -163.563309) (xy 366.611006 -163.540668)
			(xy 366.663303 -163.525313) (xy 366.717252 -163.517557) (xy 366.744504 -163.517072) (xy 366.771875 -163.517518)
			(xy 366.826056 -163.525338) (xy 366.87856 -163.540831) (xy 366.928306 -163.563677) (xy 366.974272 -163.593408)
			(xy 366.995202 -163.611052) (xy 366.995456 -163.611306) (xy 367.002551 -163.616881) (xy 367.019461 -163.623134)
			(xy 367.028476 -163.623498) (xy 367.095532 -163.623498) (xy 367.10455 -163.623157) (xy 367.121467 -163.616898)
			(xy 367.128552 -163.611306) (xy 367.128552 -163.611052) (xy 367.128806 -163.611052) (xy 367.149732 -163.593405)
			(xy 367.195705 -163.563692) (xy 367.245454 -163.540857) (xy 367.297957 -163.525368) (xy 367.352134 -163.517544)
			(xy 367.379504 -163.517072) (xy 367.408516 -163.517609) (xy 367.465873 -163.526378) (xy 367.521242 -163.543729)
			(xy 367.573346 -163.569262) (xy 367.620984 -163.602388) (xy 367.642394 -163.621974) (xy 367.649252 -163.628832)
			(xy 367.667286 -163.635944) (xy 367.757202 -163.635944) (xy 367.775236 -163.628832) (xy 367.782094 -163.621974)
			(xy 367.803503 -163.602389) (xy 367.851147 -163.569273) (xy 367.903252 -163.543745) (xy 367.958618 -163.526392)
			(xy 368.015973 -163.517613) (xy 368.044984 -163.517072) (xy 368.072355 -163.51753) (xy 368.126535 -163.525347)
			(xy 368.179039 -163.540837) (xy 368.228786 -163.563681) (xy 368.274751 -163.593409) (xy 368.295682 -163.611052)
			(xy 368.295936 -163.611306) (xy 368.303036 -163.616873) (xy 368.319943 -163.623131) (xy 368.328956 -163.623498)
			(xy 368.396012 -163.623498) (xy 368.405029 -163.623147) (xy 368.421946 -163.616895) (xy 368.429032 -163.611306)
			(xy 368.429032 -163.611052) (xy 368.429286 -163.611052) (xy 368.450219 -163.593411) (xy 368.496187 -163.563687)
			(xy 368.545933 -163.540841) (xy 368.598435 -163.525345) (xy 368.652613 -163.517516) (xy 368.707355 -163.517516)
			(xy 368.761533 -163.525345) (xy 368.814035 -163.540841) (xy 368.863781 -163.563687) (xy 368.909749 -163.593411)
			(xy 368.930682 -163.611052) (xy 368.930936 -163.611306) (xy 368.938036 -163.616873) (xy 368.954943 -163.623131)
			(xy 368.963956 -163.623498) (xy 369.031012 -163.623498) (xy 369.040029 -163.623147) (xy 369.056946 -163.616895)
			(xy 369.064032 -163.611306) (xy 369.064032 -163.611052) (xy 369.064286 -163.611052) (xy 369.085219 -163.593411)
			(xy 369.131187 -163.563687) (xy 369.180933 -163.540841) (xy 369.233435 -163.525345) (xy 369.287613 -163.517516)
			(xy 369.342355 -163.517516) (xy 369.396533 -163.525345) (xy 369.449035 -163.540841) (xy 369.498781 -163.563687)
			(xy 369.544749 -163.593411) (xy 369.565682 -163.611052) (xy 369.565936 -163.611306) (xy 369.573036 -163.616873)
			(xy 369.589943 -163.623131) (xy 369.598956 -163.623498) (xy 369.666012 -163.623498) (xy 369.675029 -163.623147)
			(xy 369.691946 -163.616895) (xy 369.699032 -163.611306) (xy 369.699032 -163.611052) (xy 369.699286 -163.611052)
			(xy 369.720219 -163.593414) (xy 369.766191 -163.5637) (xy 369.815938 -163.540863) (xy 369.868439 -163.525372)
			(xy 369.922615 -163.517545) (xy 369.949984 -163.517072) (xy 369.977558 -163.517558) (xy 370.032129 -163.525508)
			(xy 370.084988 -163.54123) (xy 370.135034 -163.564396) (xy 370.181224 -163.594524) (xy 370.222597 -163.630987)
			(xy 370.240814 -163.651692) (xy 370.248365 -163.659773) (xy 370.268379 -163.669124) (xy 370.279422 -163.669726)
			(xy 370.357146 -163.669726) (xy 370.368195 -163.669151) (xy 370.388218 -163.659793) (xy 370.395754 -163.651692)
			(xy 370.413984 -163.630998) (xy 370.455349 -163.594527) (xy 370.501535 -163.564393) (xy 370.551579 -163.541224)
			(xy 370.604438 -163.525504) (xy 370.65901 -163.51756) (xy 370.686584 -163.517072) (xy 370.713834 -163.517593)
			(xy 370.767779 -163.525347) (xy 370.820072 -163.540699) (xy 370.869648 -163.563337) (xy 370.915497 -163.592799)
			(xy 370.956687 -163.628487) (xy 370.992379 -163.669674) (xy 371.021846 -163.71552) (xy 371.044488 -163.765094)
			(xy 371.059845 -163.817385) (xy 371.067604 -163.87133) (xy 371.068092 -163.89858) (xy 371.067616 -163.92595)
			(xy 371.059801 -163.980129) (xy 371.044314 -164.032632) (xy 371.021475 -164.082379) (xy 370.991752 -164.128346)
			(xy 370.974112 -164.149278) (xy 370.973858 -164.149532) (xy 370.968289 -164.15663) (xy 370.962033 -164.173538)
			(xy 370.961666 -164.182552) (xy 370.961666 -164.249608) (xy 370.962026 -164.258624) (xy 370.968272 -164.275541)
			(xy 370.973858 -164.282628) (xy 370.974112 -164.282628) (xy 370.974112 -164.282882) (xy 370.991758 -164.303808)
			(xy 371.021468 -164.349783) (xy 371.044303 -164.399532) (xy 371.059792 -164.452034) (xy 371.067619 -164.50621)
			(xy 371.068092 -164.53358) (xy 371.068092 -164.533834) (xy 371.067564 -164.561813) (xy 371.059376 -164.617169)
			(xy 371.043194 -164.670737) (xy 371.019366 -164.721369) (xy 370.988402 -164.76798) (xy 370.970048 -164.789104)
			(xy 370.963698 -164.796216) (xy 370.95684 -164.81425) (xy 370.958364 -164.90315) (xy 370.965984 -164.92093)
			(xy 370.972588 -164.927788) (xy 370.992762 -164.949287) (xy 371.026905 -164.997347) (xy 371.053251 -165.050087)
			(xy 371.071172 -165.106251) (xy 371.076318 -165.1393) (xy 376.980954 -165.1393) (xy 376.980954 -165.054604)
			(xy 376.989005 -164.97029) (xy 377.005034 -164.887124) (xy 377.028895 -164.805857) (xy 377.060374 -164.727227)
			(xy 377.099185 -164.651946) (xy 377.144975 -164.580694) (xy 377.197331 -164.514118) (xy 377.255779 -164.45282)
			(xy 377.319789 -164.397355) (xy 377.388781 -164.348226) (xy 377.462131 -164.305877) (xy 377.539174 -164.270693)
			(xy 377.619213 -164.242991) (xy 377.701522 -164.223023) (xy 377.785357 -164.21097) (xy 377.869958 -164.20694)
			(xy 377.954559 -164.21097) (xy 378.038394 -164.223023) (xy 378.120703 -164.242991) (xy 378.200742 -164.270693)
			(xy 378.277785 -164.305877) (xy 378.351135 -164.348226) (xy 378.420127 -164.397355) (xy 378.484137 -164.45282)
			(xy 378.542585 -164.514118) (xy 378.594941 -164.580694) (xy 378.640731 -164.651946) (xy 378.679542 -164.727227)
			(xy 378.711021 -164.805857) (xy 378.734882 -164.887124) (xy 378.750911 -164.97029) (xy 378.758962 -165.054604)
			(xy 378.759466 -165.096952) (xy 378.758962 -165.1393) (xy 378.753626 -165.19518) (xy 386.317994 -165.19518)
			(xy 386.317994 -165.110484) (xy 386.326045 -165.02617) (xy 386.342074 -164.943004) (xy 386.365935 -164.861737)
			(xy 386.397414 -164.783107) (xy 386.436225 -164.707826) (xy 386.482015 -164.636574) (xy 386.534371 -164.569998)
			(xy 386.592819 -164.5087) (xy 386.656829 -164.453235) (xy 386.725821 -164.404106) (xy 386.799171 -164.361757)
			(xy 386.876214 -164.326573) (xy 386.956253 -164.298871) (xy 387.038562 -164.278903) (xy 387.122397 -164.26685)
			(xy 387.206998 -164.26282) (xy 387.291599 -164.26685) (xy 387.375434 -164.278903) (xy 387.457743 -164.298871)
			(xy 387.537782 -164.326573) (xy 387.614825 -164.361757) (xy 387.688175 -164.404106) (xy 387.757167 -164.453235)
			(xy 387.821177 -164.5087) (xy 387.879625 -164.569998) (xy 387.931981 -164.636574) (xy 387.977771 -164.707826)
			(xy 388.016582 -164.783107) (xy 388.048061 -164.861737) (xy 388.071922 -164.943004) (xy 388.087951 -165.02617)
			(xy 388.096002 -165.110484) (xy 388.096506 -165.152832) (xy 388.096002 -165.19518) (xy 388.087951 -165.279494)
			(xy 388.071922 -165.36266) (xy 388.048061 -165.443927) (xy 388.016582 -165.522557) (xy 387.977771 -165.597838)
			(xy 387.931981 -165.66909) (xy 387.879625 -165.735666) (xy 387.821177 -165.796964) (xy 387.757167 -165.852429)
			(xy 387.688175 -165.901558) (xy 387.614825 -165.943907) (xy 387.537782 -165.979091) (xy 387.457743 -166.006793)
			(xy 387.375434 -166.026761) (xy 387.291599 -166.038814) (xy 387.206998 -166.042845) (xy 387.122397 -166.038814)
			(xy 387.038562 -166.026761) (xy 386.956253 -166.006793) (xy 386.876214 -165.979091) (xy 386.799171 -165.943907)
			(xy 386.725821 -165.901558) (xy 386.656829 -165.852429) (xy 386.592819 -165.796964) (xy 386.534371 -165.735666)
			(xy 386.482015 -165.66909) (xy 386.436225 -165.597838) (xy 386.397414 -165.522557) (xy 386.365935 -165.443927)
			(xy 386.342074 -165.36266) (xy 386.326045 -165.279494) (xy 386.317994 -165.19518) (xy 378.753626 -165.19518)
			(xy 378.750911 -165.223614) (xy 378.734882 -165.30678) (xy 378.711021 -165.388047) (xy 378.679542 -165.466677)
			(xy 378.640731 -165.541958) (xy 378.594941 -165.61321) (xy 378.542585 -165.679786) (xy 378.484137 -165.741084)
			(xy 378.420127 -165.796549) (xy 378.351135 -165.845678) (xy 378.277785 -165.888027) (xy 378.200742 -165.923211)
			(xy 378.120703 -165.950913) (xy 378.038394 -165.970881) (xy 377.954559 -165.982934) (xy 377.869958 -165.986965)
			(xy 377.785357 -165.982934) (xy 377.701522 -165.970881) (xy 377.619213 -165.950913) (xy 377.539174 -165.923211)
			(xy 377.462131 -165.888027) (xy 377.388781 -165.845678) (xy 377.319789 -165.796549) (xy 377.255779 -165.741084)
			(xy 377.197331 -165.679786) (xy 377.144975 -165.61321) (xy 377.099185 -165.541958) (xy 377.060374 -165.466677)
			(xy 377.028895 -165.388047) (xy 377.005034 -165.30678) (xy 376.989005 -165.223614) (xy 376.980954 -165.1393)
			(xy 371.076318 -165.1393) (xy 371.080242 -165.164503) (xy 371.080792 -165.19398) (xy 371.080326 -165.221233)
			(xy 371.072571 -165.275185) (xy 371.057217 -165.327484) (xy 371.034576 -165.377065) (xy 371.005108 -165.422919)
			(xy 370.969415 -165.464112) (xy 370.928222 -165.499806) (xy 370.882368 -165.529274) (xy 370.832787 -165.551916)
			(xy 370.780489 -165.567271) (xy 370.726537 -165.575026) (xy 370.699284 -165.575488) (xy 370.671711 -165.574969)
			(xy 370.617141 -165.567028) (xy 370.564282 -165.551314) (xy 370.514235 -165.528154) (xy 370.468044 -165.49803)
			(xy 370.426671 -165.461571) (xy 370.408454 -165.440868) (xy 370.400923 -165.432767) (xy 370.380893 -165.423428)
			(xy 370.369846 -165.422834) (xy 370.292122 -165.422834) (xy 370.281073 -165.423403) (xy 370.261051 -165.432767)
			(xy 370.253514 -165.440868) (xy 370.235292 -165.461569) (xy 370.193926 -165.498042) (xy 370.147739 -165.528176)
			(xy 370.097693 -165.551344) (xy 370.044832 -165.567062) (xy 369.990258 -165.575002) (xy 369.962684 -165.575488)
			(xy 369.935313 -165.575034) (xy 369.881134 -165.567214) (xy 369.82863 -165.551722) (xy 369.778884 -165.528878)
			(xy 369.732917 -165.49915) (xy 369.711986 -165.481508) (xy 369.711732 -165.481254) (xy 369.704644 -165.475669)
			(xy 369.687728 -165.469423) (xy 369.678712 -165.469062) (xy 369.611656 -165.469062) (xy 369.602643 -165.469454)
			(xy 369.585726 -165.475678) (xy 369.578636 -165.481254) (xy 369.578636 -165.481508) (xy 369.578382 -165.481508)
			(xy 369.557449 -165.499149) (xy 369.511481 -165.528873) (xy 369.461735 -165.551719) (xy 369.409233 -165.567215)
			(xy 369.355055 -165.575044) (xy 369.300313 -165.575044) (xy 369.246135 -165.567215) (xy 369.193633 -165.551719)
			(xy 369.143887 -165.528873) (xy 369.097919 -165.499149) (xy 369.076986 -165.481508) (xy 369.076732 -165.481254)
			(xy 369.069644 -165.475669) (xy 369.052728 -165.469423) (xy 369.043712 -165.469062) (xy 368.976656 -165.469062)
			(xy 368.967643 -165.469454) (xy 368.950726 -165.475678) (xy 368.943636 -165.481254) (xy 368.943636 -165.481508)
			(xy 368.943382 -165.481508) (xy 368.922449 -165.499149) (xy 368.876481 -165.528873) (xy 368.826735 -165.551719)
			(xy 368.774233 -165.567215) (xy 368.720055 -165.575044) (xy 368.665313 -165.575044) (xy 368.611135 -165.567215)
			(xy 368.558633 -165.551719) (xy 368.508887 -165.528873) (xy 368.462919 -165.499149) (xy 368.441986 -165.481508)
			(xy 368.441732 -165.481254) (xy 368.434644 -165.475669) (xy 368.417728 -165.469423) (xy 368.408712 -165.469062)
			(xy 368.341656 -165.469062) (xy 368.332643 -165.469454) (xy 368.315726 -165.475678) (xy 368.308636 -165.481254)
			(xy 368.308636 -165.481508) (xy 368.308382 -165.481508) (xy 368.287431 -165.499123) (xy 368.241463 -165.528838)
			(xy 368.19172 -165.551679) (xy 368.139224 -165.567176) (xy 368.085052 -165.57501) (xy 368.057684 -165.575488)
			(xy 368.028671 -165.57497) (xy 367.971313 -165.566198) (xy 367.915943 -165.548843) (xy 367.86384 -165.523305)
			(xy 367.816203 -165.490174) (xy 367.794794 -165.470586) (xy 367.787936 -165.463728) (xy 367.769902 -165.456616)
			(xy 367.679986 -165.456616) (xy 367.661952 -165.463728) (xy 367.655094 -165.470586) (xy 367.633699 -165.490187)
			(xy 367.58605 -165.523298) (xy 367.533941 -165.548822) (xy 367.478572 -165.566172) (xy 367.421216 -165.574948)
			(xy 367.392204 -165.575488) (xy 367.364834 -165.575023) (xy 367.310654 -165.567205) (xy 367.258151 -165.551716)
			(xy 367.208404 -165.528874) (xy 367.162438 -165.499149) (xy 367.141506 -165.481508) (xy 367.141252 -165.481254)
			(xy 367.134159 -165.475677) (xy 367.117247 -165.469426) (xy 367.108232 -165.469062) (xy 367.041176 -165.469062)
			(xy 367.032159 -165.469416) (xy 367.015242 -165.475666) (xy 367.008156 -165.481254) (xy 367.008156 -165.481508)
			(xy 367.007902 -165.481508) (xy 366.986981 -165.499161) (xy 366.941005 -165.52887) (xy 366.891255 -165.551704)
			(xy 366.838752 -165.567191) (xy 366.784574 -165.575016) (xy 366.757204 -165.575488) (xy 366.72995 -165.575041)
			(xy 366.675998 -165.567284) (xy 366.623698 -165.551927) (xy 366.574117 -165.529284) (xy 366.528263 -165.499814)
			(xy 366.48707 -165.464119) (xy 366.451376 -165.422924) (xy 366.421908 -165.377069) (xy 366.399267 -165.327487)
			(xy 366.383913 -165.275187) (xy 366.376158 -165.221234) (xy 366.375696 -165.19398) (xy 366.375696 -165.193726)
			(xy 366.376202 -165.165746) (xy 366.384396 -165.110389) (xy 366.400583 -165.056821) (xy 366.424416 -165.006189)
			(xy 366.455384 -164.959579) (xy 366.47374 -164.938456) (xy 366.48009 -164.931344) (xy 366.486948 -164.91331)
			(xy 366.485424 -164.82441) (xy 366.477804 -164.80663) (xy 366.4712 -164.799772) (xy 366.451022 -164.778276)
			(xy 366.416876 -164.730217) (xy 366.390529 -164.677477) (xy 366.372609 -164.621311) (xy 366.363543 -164.563057)
			(xy 366.362996 -164.53358) (xy 360.866436 -164.53358) (xy 365.49711 -169.164254) (xy 365.514318 -169.182377)
			(xy 365.542064 -169.223931) (xy 365.561175 -169.270097) (xy 365.57092 -169.319103) (xy 365.571532 -169.344086)
			(xy 365.571532 -170.451018) (xy 365.57194 -170.461089) (xy 365.579672 -170.479687) (xy 365.586518 -170.487086)
			(xy 366.347502 -171.24807) (xy 366.354911 -171.254899) (xy 366.373503 -171.262626) (xy 366.38357 -171.263056)
			(xy 371.235478 -171.263056) (xy 371.260463 -171.263637) (xy 371.309473 -171.273389) (xy 371.355642 -171.292506)
			(xy 371.397201 -171.320253) (xy 371.41531 -171.337478) (xy 373.296942 -173.21911) (xy 394.24737 -173.21911)
			(xy 394.247869 -173.190192) (xy 394.256598 -173.133019) (xy 394.273858 -173.077818) (xy 394.299253 -173.025856)
			(xy 394.332202 -172.978323) (xy 394.371948 -172.936308) (xy 394.394436 -172.91812) (xy 394.40323 -172.9105)
			(xy 394.413419 -172.889609) (xy 394.413994 -172.877988) (xy 394.413994 -172.798232) (xy 394.413424 -172.786604)
			(xy 394.403257 -172.765694) (xy 394.394436 -172.7581) (xy 394.37196 -172.7399) (xy 394.332223 -172.697883)
			(xy 394.299282 -172.65035) (xy 394.273892 -172.598391) (xy 394.256634 -172.543194) (xy 394.247905 -172.486026)
			(xy 394.24737 -172.45711) (xy 394.247888 -172.42986) (xy 394.255642 -172.375915) (xy 394.270995 -172.323622)
			(xy 394.293633 -172.274046) (xy 394.323096 -172.228197) (xy 394.358784 -172.187007) (xy 394.399971 -172.151316)
			(xy 394.445818 -172.121849) (xy 394.495392 -172.099206) (xy 394.547683 -172.083849) (xy 394.601628 -172.07609)
			(xy 394.628878 -172.075602) (xy 394.657633 -172.07612) (xy 394.714492 -172.08474) (xy 394.769411 -172.101804)
			(xy 394.821143 -172.126924) (xy 394.868516 -172.15953) (xy 394.910453 -172.198882) (xy 394.946002 -172.244087)
			(xy 394.974358 -172.294119) (xy 394.994877 -172.347843) (xy 395.001496 -172.37583) (xy 395.001496 -172.376084)
			(xy 395.004254 -172.385992) (xy 395.016309 -172.402633) (xy 395.024864 -172.408342) (xy 395.097254 -172.45203)
			(xy 395.118082 -172.454824) (xy 395.128242 -172.451776) (xy 395.153267 -172.445269) (xy 395.204497 -172.438256)
			(xy 395.23035 -172.437806) (xy 395.230858 -172.437806) (xy 395.25811 -172.438294) (xy 395.312061 -172.446046)
			(xy 395.364359 -172.461397) (xy 395.41394 -172.484036) (xy 395.459794 -172.513501) (xy 395.500988 -172.549192)
			(xy 395.536682 -172.590383) (xy 395.56615 -172.636235) (xy 395.588793 -172.685814) (xy 395.604148 -172.738111)
			(xy 395.611904 -172.792062) (xy 395.612366 -172.819314) (xy 395.611926 -172.845003) (xy 395.60503 -172.895915)
			(xy 395.591363 -172.945442) (xy 395.571175 -172.992687) (xy 395.544828 -173.036795) (xy 395.512801 -173.076968)
			(xy 395.475673 -173.112481) (xy 395.45514 -173.127924) (xy 395.454886 -173.127924) (xy 395.446062 -173.1352)
			(xy 395.435389 -173.155398) (xy 395.434312 -173.166786) (xy 395.430502 -173.246034) (xy 395.430654 -173.257451)
			(xy 395.43963 -173.278416) (xy 395.447774 -173.28642) (xy 395.448028 -173.286674) (xy 395.4681 -173.304875)
			(xy 395.503432 -173.345953) (xy 395.532592 -173.39162) (xy 395.554992 -173.440956) (xy 395.570182 -173.492966)
			(xy 395.577854 -173.546603) (xy 395.57833 -173.573694) (xy 395.57785 -173.601268) (xy 395.569899 -173.65584)
			(xy 395.554176 -173.708699) (xy 395.531008 -173.758745) (xy 395.500879 -173.804935) (xy 395.464415 -173.846307)
			(xy 395.44371 -173.864524) (xy 395.435625 -173.872071) (xy 395.426276 -173.892088) (xy 395.425676 -173.903132)
			(xy 395.425676 -173.980856) (xy 395.426245 -173.991906) (xy 395.435607 -174.011928) (xy 395.44371 -174.019464)
			(xy 395.464409 -174.037688) (xy 395.50088 -174.079055) (xy 395.531013 -174.125242) (xy 395.554181 -174.175287)
			(xy 395.5699 -174.228147) (xy 395.577843 -174.28272) (xy 395.57833 -174.310294) (xy 395.577817 -174.337544)
			(xy 395.570062 -174.39149) (xy 395.554708 -174.443783) (xy 395.532069 -174.493358) (xy 395.502606 -174.539208)
			(xy 395.466917 -174.580397) (xy 395.42573 -174.616089) (xy 395.379883 -174.645556) (xy 395.330309 -174.668199)
			(xy 395.278017 -174.683556) (xy 395.224072 -174.691315) (xy 395.196822 -174.691802) (xy 395.196314 -174.691802)
			(xy 395.162532 -174.690278) (xy 395.152372 -174.689262) (xy 395.133068 -174.695358) (xy 395.070076 -174.74819)
			(xy 395.062768 -174.754896) (xy 395.053497 -174.772413) (xy 395.052042 -174.782226) (xy 395.052042 -174.782988)
			(xy 395.049098 -174.81115) (xy 395.035886 -174.866209) (xy 395.01468 -174.918709) (xy 394.985945 -174.967498)
			(xy 394.950313 -175.011503) (xy 394.908568 -175.049757) (xy 394.861626 -175.081419) (xy 394.810519 -175.105794)
			(xy 394.75637 -175.122345) (xy 394.700369 -175.130709) (xy 394.672058 -175.131222) (xy 394.644806 -175.130761)
			(xy 394.590858 -175.122999) (xy 394.538564 -175.10764) (xy 394.488988 -175.084995) (xy 394.443138 -175.055525)
			(xy 394.401949 -175.019831) (xy 394.366258 -174.978639) (xy 394.336792 -174.932788) (xy 394.314151 -174.88321)
			(xy 394.298795 -174.830914) (xy 394.291037 -174.776966) (xy 394.29055 -174.749714) (xy 394.291055 -174.721852)
			(xy 394.299155 -174.666721) (xy 394.315183 -174.613353) (xy 394.3388 -174.562882) (xy 394.369504 -174.516381)
			(xy 394.406643 -174.474838) (xy 394.42771 -174.456598) (xy 394.436854 -174.448978) (xy 394.446252 -174.427896)
			(xy 394.443204 -174.335694) (xy 394.442279 -174.324213) (xy 394.431565 -174.303847) (xy 394.42263 -174.296578)
			(xy 394.422376 -174.296324) (xy 394.401856 -174.280863) (xy 394.36472 -174.245358) (xy 394.332685 -174.20519)
			(xy 394.306333 -174.161085) (xy 394.286139 -174.113842) (xy 394.272469 -174.064316) (xy 394.26557 -174.013403)
			(xy 394.26515 -173.987714) (xy 394.265721 -173.959177) (xy 394.274209 -173.902738) (xy 394.291013 -173.848194)
			(xy 394.315757 -173.796762) (xy 394.347888 -173.749593) (xy 394.38669 -173.707738) (xy 394.40866 -173.689518)
			(xy 394.417462 -173.681699) (xy 394.427401 -173.660392) (xy 394.42771 -173.648624) (xy 394.425424 -173.555914)
			(xy 394.414502 -173.534832) (xy 394.40485 -173.527974) (xy 394.384266 -173.512553) (xy 394.347079 -173.47702)
			(xy 394.315 -173.436815) (xy 394.28861 -173.392667) (xy 394.268388 -173.345375) (xy 394.254699 -173.295795)
			(xy 394.247791 -173.244827) (xy 394.24737 -173.21911) (xy 373.296942 -173.21911) (xy 373.816118 -173.738286)
			(xy 373.833342 -173.756394) (xy 373.861085 -173.797953) (xy 373.880192 -173.844124) (xy 373.889931 -173.893134)
			(xy 373.89054 -173.918118) (xy 373.89054 -175.645826) (xy 373.890941 -175.655898) (xy 373.898678 -175.674496)
			(xy 373.905526 -175.681894) (xy 374.424702 -176.20107) (xy 374.432111 -176.207899) (xy 374.450703 -176.215626)
			(xy 374.46077 -176.216056) (xy 381.293878 -176.216056) (xy 381.318863 -176.216637) (xy 381.367873 -176.226389)
			(xy 381.414042 -176.245506) (xy 381.455601 -176.273253) (xy 381.47371 -176.290478) (xy 381.994664 -176.811432)
			(xy 382.002076 -176.818116) (xy 382.020509 -176.825713) (xy 382.040447 -176.825713) (xy 382.05888 -176.818116)
			(xy 382.066292 -176.811432) (xy 382.431036 -176.446688) (xy 382.449121 -176.42942) (xy 382.49067 -176.401613)
			(xy 382.536844 -176.382443) (xy 382.585871 -176.372647) (xy 382.610868 -176.372012) (xy 389.679688 -176.372012)
			(xy 389.704683 -176.372658) (xy 389.753705 -176.38246) (xy 389.799876 -176.401631) (xy 389.841423 -176.429435)
			(xy 389.85952 -176.446688) (xy 390.070086 -176.657254) (xy 395.399768 -176.657254) (xy 395.4003 -176.628337)
			(xy 395.409022 -176.571166) (xy 395.426276 -176.515966) (xy 395.451665 -176.464004) (xy 395.484608 -176.41647)
			(xy 395.524349 -176.374454) (xy 395.546834 -176.356264) (xy 395.555653 -176.348669) (xy 395.565829 -176.327759)
			(xy 395.566392 -176.316132) (xy 395.566392 -176.236376) (xy 395.565855 -176.224744) (xy 395.555665 -176.203834)
			(xy 395.546834 -176.196244) (xy 395.524379 -176.17802) (xy 395.48464 -176.136008) (xy 395.451697 -176.08848)
			(xy 395.426303 -176.036525) (xy 395.409041 -175.981333) (xy 395.400306 -175.924168) (xy 395.399768 -175.895254)
			(xy 395.400301 -175.86727) (xy 395.408459 -175.811899) (xy 395.424621 -175.758315) (xy 395.448442 -175.707669)
			(xy 395.479408 -175.661048) (xy 395.516856 -175.619454) (xy 395.559981 -175.583779) (xy 395.583664 -175.568864)
			(xy 395.593316 -175.563022) (xy 395.605508 -175.545242) (xy 395.622272 -175.447452) (xy 395.616684 -175.426624)
			(xy 395.609826 -175.417988) (xy 395.594097 -175.39796) (xy 395.567643 -175.354446) (xy 395.547359 -175.307735)
			(xy 395.533624 -175.258697) (xy 395.526693 -175.208246) (xy 395.52626 -175.182784) (xy 395.526742 -175.156168)
			(xy 395.534319 -175.103479) (xy 395.549317 -175.052405) (xy 395.571431 -175.003984) (xy 395.60021 -174.959203)
			(xy 395.635069 -174.918974) (xy 395.675298 -174.884114) (xy 395.720079 -174.855334) (xy 395.768499 -174.833219)
			(xy 395.819573 -174.81822) (xy 395.872262 -174.810642) (xy 395.898878 -174.810166) (xy 395.925299 -174.810644)
			(xy 395.977613 -174.818091) (xy 396.028351 -174.832851) (xy 396.076496 -174.85463) (xy 396.121082 -174.882991)
			(xy 396.141448 -174.899828) (xy 396.148306 -174.90567) (xy 396.165324 -174.91202) (xy 396.249652 -174.91202)
			(xy 396.26667 -174.90567) (xy 396.273528 -174.899828) (xy 396.293894 -174.882989) (xy 396.33848 -174.854624)
			(xy 396.386624 -174.832837) (xy 396.437361 -174.818066) (xy 396.489676 -174.810606) (xy 396.54252 -174.810606)
			(xy 396.594835 -174.818066) (xy 396.645572 -174.832837) (xy 396.693716 -174.854624) (xy 396.738302 -174.882989)
			(xy 396.758668 -174.899828) (xy 396.765526 -174.90567) (xy 396.782544 -174.91202) (xy 396.866872 -174.91202)
			(xy 396.88389 -174.90567) (xy 396.890748 -174.899828) (xy 396.911099 -174.882972) (xy 396.955693 -174.854619)
			(xy 397.003841 -174.832842) (xy 397.054581 -174.818079) (xy 397.106896 -174.810624) (xy 397.133318 -174.810166)
			(xy 397.161201 -174.81072) (xy 397.216343 -174.819034) (xy 397.26963 -174.835473) (xy 397.319873 -174.859671)
			(xy 397.365947 -174.891086) (xy 397.406825 -174.929017) (xy 397.441594 -174.972617) (xy 397.469476 -175.020912)
			(xy 397.489849 -175.072823) (xy 397.502257 -175.12719) (xy 397.506425 -175.1828) (xy 397.502257 -175.23841)
			(xy 397.489849 -175.292777) (xy 397.469476 -175.344688) (xy 397.441594 -175.392983) (xy 397.406825 -175.436583)
			(xy 397.365947 -175.474514) (xy 397.319873 -175.505929) (xy 397.26963 -175.530127) (xy 397.216343 -175.546566)
			(xy 397.161201 -175.55488) (xy 397.133318 -175.555402) (xy 397.106897 -175.554933) (xy 397.054582 -175.547486)
			(xy 397.003843 -175.532723) (xy 396.955699 -175.510942) (xy 396.911113 -175.482579) (xy 396.890748 -175.46574)
			(xy 396.88389 -175.459898) (xy 396.866872 -175.453548) (xy 396.782544 -175.453548) (xy 396.765526 -175.459898)
			(xy 396.758668 -175.46574) (xy 396.738302 -175.482579) (xy 396.693716 -175.510944) (xy 396.645572 -175.532731)
			(xy 396.594835 -175.547502) (xy 396.54252 -175.554962) (xy 396.489676 -175.554962) (xy 396.437361 -175.547502)
			(xy 396.386624 -175.532731) (xy 396.33848 -175.510944) (xy 396.293894 -175.482579) (xy 396.273528 -175.46574)
			(xy 396.26667 -175.459898) (xy 396.249652 -175.453548) (xy 396.165324 -175.453548) (xy 396.148306 -175.459898)
			(xy 396.141448 -175.46574) (xy 396.130876 -175.474582) (xy 396.108628 -175.490856) (xy 396.096998 -175.498252)
			(xy 396.096744 -175.498506) (xy 396.088015 -175.504816) (xy 396.07619 -175.522785) (xy 396.073884 -175.533304)
			(xy 396.060168 -175.620172) (xy 396.066264 -175.641254) (xy 396.073376 -175.649636) (xy 396.090176 -175.670349)
			(xy 396.11847 -175.715556) (xy 396.140188 -175.764264) (xy 396.154907 -175.815524) (xy 396.162339 -175.868334)
			(xy 396.162784 -175.895) (xy 396.162784 -175.895254) (xy 396.162239 -175.92417) (xy 396.153516 -175.98134)
			(xy 396.136264 -176.036539) (xy 396.110877 -176.088501) (xy 396.077938 -176.136035) (xy 396.038202 -176.178053)
			(xy 396.015718 -176.196244) (xy 396.006887 -176.203828) (xy 395.99672 -176.224747) (xy 395.99616 -176.236376)
			(xy 395.99616 -176.316132) (xy 395.996674 -176.327768) (xy 396.006879 -176.348678) (xy 396.015718 -176.356264)
			(xy 396.038188 -176.374471) (xy 396.077923 -176.416488) (xy 396.110863 -176.46402) (xy 396.136254 -176.515978)
			(xy 396.153513 -176.571172) (xy 396.162247 -176.628339) (xy 396.162784 -176.657254) (xy 396.162298 -176.684505)
			(xy 396.154542 -176.738453) (xy 396.139187 -176.790748) (xy 396.116545 -176.840325) (xy 396.087079 -176.886175)
			(xy 396.051388 -176.927366) (xy 396.010197 -176.963057) (xy 395.964347 -176.992523) (xy 395.91477 -177.015165)
			(xy 395.862475 -177.03052) (xy 395.808527 -177.038276) (xy 395.754025 -177.038276) (xy 395.700077 -177.03052)
			(xy 395.647782 -177.015165) (xy 395.598205 -176.992523) (xy 395.552355 -176.963057) (xy 395.511164 -176.927366)
			(xy 395.475473 -176.886175) (xy 395.446007 -176.840325) (xy 395.423365 -176.790748) (xy 395.40801 -176.738453)
			(xy 395.400254 -176.684505) (xy 395.399768 -176.657254) (xy 390.070086 -176.657254) (xy 390.550146 -177.137314)
			(xy 390.567388 -177.155406) (xy 390.595126 -177.196971) (xy 390.614228 -177.243147) (xy 390.623961 -177.292161)
			(xy 390.624568 -177.317146) (xy 390.624568 -178.504342) (xy 390.624953 -178.514416) (xy 390.6327 -178.533015)
			(xy 390.639554 -178.54041) (xy 390.660448 -178.561984) (xy 390.695835 -178.610507) (xy 390.723179 -178.663978)
			(xy 390.741802 -178.721074) (xy 390.751245 -178.780384) (xy 390.751822 -178.810412) (xy 390.751333 -178.837663)
			(xy 390.743576 -178.89161) (xy 390.734229 -178.923442) (xy 390.993122 -178.923442) (xy 390.993628 -178.895968)
			(xy 391.001514 -178.841589) (xy 391.017129 -178.788907) (xy 391.04015 -178.739014) (xy 391.070098 -178.692944)
			(xy 391.087864 -178.671982) (xy 391.088118 -178.671728) (xy 391.093701 -178.664639) (xy 391.099949 -178.647724)
			(xy 391.10031 -178.638708) (xy 391.10031 -178.571144) (xy 391.09993 -178.562129) (xy 391.093698 -178.545212)
			(xy 391.088118 -178.538124) (xy 391.08761 -178.537616) (xy 391.06989 -178.516659) (xy 391.040005 -178.470629)
			(xy 391.017036 -178.420787) (xy 391.001458 -178.368164) (xy 390.993594 -178.31385) (xy 390.993122 -178.28641)
			(xy 390.993608 -178.259159) (xy 391.001364 -178.205211) (xy 391.016719 -178.152916) (xy 391.039361 -178.103339)
			(xy 391.068827 -178.057489) (xy 391.104518 -178.016298) (xy 391.145709 -177.980607) (xy 391.191559 -177.951141)
			(xy 391.241136 -177.928499) (xy 391.293431 -177.913144) (xy 391.347379 -177.905388) (xy 391.401881 -177.905388)
			(xy 391.455829 -177.913144) (xy 391.508124 -177.928499) (xy 391.557701 -177.951141) (xy 391.603551 -177.980607)
			(xy 391.644742 -178.016298) (xy 391.680433 -178.057489) (xy 391.709899 -178.103339) (xy 391.732541 -178.152916)
			(xy 391.747896 -178.205211) (xy 391.755652 -178.259159) (xy 391.756138 -178.28641) (xy 391.755648 -178.313884)
			(xy 391.747756 -178.368263) (xy 391.732136 -178.420945) (xy 391.709112 -178.470838) (xy 391.679162 -178.516907)
			(xy 391.661396 -178.53787) (xy 391.661142 -178.538124) (xy 391.655532 -178.545195) (xy 391.649301 -178.562124)
			(xy 391.64895 -178.571144) (xy 391.64895 -178.638708) (xy 391.649293 -178.647727) (xy 391.655549 -178.664644)
			(xy 391.661142 -178.671728) (xy 391.66165 -178.672236) (xy 391.679389 -178.693178) (xy 391.709272 -178.739211)
			(xy 391.732238 -178.789057) (xy 391.747811 -178.841684) (xy 391.755669 -178.896001) (xy 391.756138 -178.923442)
			(xy 391.755652 -178.950693) (xy 391.747896 -179.004641) (xy 391.732541 -179.056936) (xy 391.709899 -179.106513)
			(xy 391.680433 -179.152363) (xy 391.644742 -179.193554) (xy 391.603551 -179.229245) (xy 391.557701 -179.258711)
			(xy 391.508124 -179.281353) (xy 391.455829 -179.296708) (xy 391.401881 -179.304464) (xy 391.347379 -179.304464)
			(xy 391.293431 -179.296708) (xy 391.241136 -179.281353) (xy 391.191559 -179.258711) (xy 391.145709 -179.229245)
			(xy 391.104518 -179.193554) (xy 391.068827 -179.152363) (xy 391.039361 -179.106513) (xy 391.016719 -179.056936)
			(xy 391.001364 -179.004641) (xy 390.993608 -178.950693) (xy 390.993122 -178.923442) (xy 390.734229 -178.923442)
			(xy 390.72822 -178.943904) (xy 390.705578 -178.99348) (xy 390.676112 -179.03933) (xy 390.640421 -179.080519)
			(xy 390.599231 -179.116211) (xy 390.553382 -179.145677) (xy 390.503806 -179.168319) (xy 390.451512 -179.183675)
			(xy 390.397565 -179.191433) (xy 390.370314 -179.19192) (xy 390.37006 -179.19192) (xy 390.344855 -179.191543)
			(xy 390.294887 -179.184898) (xy 390.246232 -179.171715) (xy 390.199743 -179.152225) (xy 390.177782 -179.13985)
			(xy 390.167876 -179.134008) (xy 390.146032 -179.131976) (xy 390.05129 -179.165504) (xy 390.035542 -179.180998)
			(xy 390.031478 -179.191412) (xy 390.02074 -179.21817) (xy 389.992457 -179.26841) (xy 389.956933 -179.313819)
			(xy 389.914977 -179.353362) (xy 389.867546 -179.386137) (xy 389.815721 -179.411399) (xy 389.760684 -179.428569)
			(xy 389.703689 -179.437259) (xy 389.674862 -179.437792) (xy 389.647609 -179.437357) (xy 389.593659 -179.429595)
			(xy 389.541362 -179.414235) (xy 389.491784 -179.391588) (xy 389.445933 -179.362116) (xy 389.404742 -179.326419)
			(xy 389.369051 -179.285224) (xy 389.339586 -179.239369) (xy 389.316946 -179.189787) (xy 389.301593 -179.137488)
			(xy 389.293839 -179.083537) (xy 389.293354 -179.056284) (xy 389.294016 -179.024721) (xy 389.304401 -178.962456)
			(xy 389.324886 -178.902747) (xy 389.339328 -178.874674) (xy 389.344154 -178.865784) (xy 389.346186 -178.846226)
			(xy 389.323326 -178.76774) (xy 389.320128 -178.758299) (xy 389.307683 -178.742748) (xy 389.299196 -178.737514)
			(xy 389.274072 -178.723003) (xy 389.22819 -178.687493) (xy 389.188216 -178.645443) (xy 389.155073 -178.597823)
			(xy 389.129526 -178.545732) (xy 389.112165 -178.490372) (xy 389.10339 -178.433021) (xy 389.102854 -178.404012)
			(xy 389.10334 -178.376761) (xy 389.111096 -178.322813) (xy 389.126451 -178.270518) (xy 389.149093 -178.220941)
			(xy 389.178559 -178.175091) (xy 389.21425 -178.1339) (xy 389.255441 -178.098209) (xy 389.301291 -178.068743)
			(xy 389.350868 -178.046101) (xy 389.403163 -178.030746) (xy 389.457111 -178.02299) (xy 389.511613 -178.02299)
			(xy 389.565561 -178.030746) (xy 389.617856 -178.046101) (xy 389.667433 -178.068743) (xy 389.713283 -178.098209)
			(xy 389.754474 -178.1339) (xy 389.790165 -178.175091) (xy 389.819631 -178.220941) (xy 389.842273 -178.270518)
			(xy 389.857628 -178.322813) (xy 389.865384 -178.376761) (xy 389.86587 -178.404012) (xy 389.865203 -178.435575)
			(xy 389.854819 -178.49784) (xy 389.834336 -178.557549) (xy 389.819896 -178.585622) (xy 389.81507 -178.594512)
			(xy 389.813038 -178.61407) (xy 389.835898 -178.692556) (xy 389.839125 -178.701985) (xy 389.851551 -178.717541)
			(xy 389.860028 -178.722782) (xy 389.867394 -178.726846) (xy 389.8773 -178.732688) (xy 389.899144 -178.73472)
			(xy 389.993886 -178.701192) (xy 390.009634 -178.685698) (xy 390.013698 -178.675284) (xy 390.023698 -178.650201)
			(xy 390.049776 -178.602918) (xy 390.082274 -178.559793) (xy 390.101074 -178.54041) (xy 390.107898 -178.532997)
			(xy 390.115628 -178.514408) (xy 390.11606 -178.504342) (xy 390.11606 -177.443638) (xy 390.115625 -177.43357)
			(xy 390.107912 -177.414971) (xy 390.101074 -177.40757) (xy 389.589264 -176.896014) (xy 389.581869 -176.889168)
			(xy 389.563266 -176.881451) (xy 389.553196 -176.881028) (xy 382.73736 -176.881028) (xy 382.727287 -176.881425)
			(xy 382.708689 -176.889165) (xy 382.701292 -176.896014) (xy 382.308354 -177.288698) (xy 382.301516 -177.296099)
			(xy 382.293797 -177.314698) (xy 382.293368 -177.324766) (xy 382.293368 -178.504342) (xy 382.293753 -178.514416)
			(xy 382.3015 -178.533015) (xy 382.308354 -178.54041) (xy 382.329248 -178.561984) (xy 382.364635 -178.610507)
			(xy 382.391979 -178.663978) (xy 382.410602 -178.721074) (xy 382.420045 -178.780384) (xy 382.420622 -178.810412)
			(xy 382.420133 -178.837663) (xy 382.412376 -178.89161) (xy 382.403029 -178.923442) (xy 382.661922 -178.923442)
			(xy 382.662428 -178.895968) (xy 382.670314 -178.841589) (xy 382.685929 -178.788907) (xy 382.70895 -178.739014)
			(xy 382.738898 -178.692944) (xy 382.756664 -178.671982) (xy 382.756918 -178.671728) (xy 382.762501 -178.664639)
			(xy 382.768749 -178.647724) (xy 382.76911 -178.638708) (xy 382.76911 -178.571144) (xy 382.76873 -178.562129)
			(xy 382.762498 -178.545212) (xy 382.756918 -178.538124) (xy 382.75641 -178.537616) (xy 382.73869 -178.516659)
			(xy 382.708805 -178.470629) (xy 382.685836 -178.420787) (xy 382.670258 -178.368164) (xy 382.662394 -178.31385)
			(xy 382.661922 -178.28641) (xy 382.662408 -178.259159) (xy 382.670164 -178.205211) (xy 382.685519 -178.152916)
			(xy 382.708161 -178.103339) (xy 382.737627 -178.057489) (xy 382.773318 -178.016298) (xy 382.814509 -177.980607)
			(xy 382.860359 -177.951141) (xy 382.909936 -177.928499) (xy 382.962231 -177.913144) (xy 383.016179 -177.905388)
			(xy 383.070681 -177.905388) (xy 383.124629 -177.913144) (xy 383.176924 -177.928499) (xy 383.226501 -177.951141)
			(xy 383.272351 -177.980607) (xy 383.313542 -178.016298) (xy 383.349233 -178.057489) (xy 383.378699 -178.103339)
			(xy 383.401341 -178.152916) (xy 383.416696 -178.205211) (xy 383.424452 -178.259159) (xy 383.424938 -178.28641)
			(xy 383.424448 -178.313884) (xy 383.416556 -178.368263) (xy 383.400936 -178.420945) (xy 383.377912 -178.470838)
			(xy 383.347962 -178.516907) (xy 383.330196 -178.53787) (xy 383.329942 -178.538124) (xy 383.324332 -178.545195)
			(xy 383.318101 -178.562124) (xy 383.31775 -178.571144) (xy 383.31775 -178.638708) (xy 383.318093 -178.647727)
			(xy 383.324349 -178.664644) (xy 383.329942 -178.671728) (xy 383.33045 -178.672236) (xy 383.348189 -178.693178)
			(xy 383.378072 -178.739211) (xy 383.401038 -178.789057) (xy 383.416611 -178.841684) (xy 383.424469 -178.896001)
			(xy 383.424938 -178.923442) (xy 383.424452 -178.950693) (xy 383.416696 -179.004641) (xy 383.401341 -179.056936)
			(xy 383.378699 -179.106513) (xy 383.349233 -179.152363) (xy 383.313542 -179.193554) (xy 383.272351 -179.229245)
			(xy 383.226501 -179.258711) (xy 383.176924 -179.281353) (xy 383.124629 -179.296708) (xy 383.070681 -179.304464)
			(xy 383.016179 -179.304464) (xy 382.962231 -179.296708) (xy 382.909936 -179.281353) (xy 382.860359 -179.258711)
			(xy 382.814509 -179.229245) (xy 382.773318 -179.193554) (xy 382.737627 -179.152363) (xy 382.708161 -179.106513)
			(xy 382.685519 -179.056936) (xy 382.670164 -179.004641) (xy 382.662408 -178.950693) (xy 382.661922 -178.923442)
			(xy 382.403029 -178.923442) (xy 382.39702 -178.943904) (xy 382.374378 -178.99348) (xy 382.344912 -179.03933)
			(xy 382.309221 -179.080519) (xy 382.268031 -179.116211) (xy 382.222182 -179.145677) (xy 382.172606 -179.168319)
			(xy 382.120312 -179.183675) (xy 382.066365 -179.191433) (xy 382.039114 -179.19192) (xy 382.03886 -179.19192)
			(xy 382.013655 -179.191543) (xy 381.963687 -179.184898) (xy 381.915032 -179.171715) (xy 381.868543 -179.152225)
			(xy 381.846582 -179.13985) (xy 381.836676 -179.134008) (xy 381.814832 -179.131976) (xy 381.72009 -179.165504)
			(xy 381.704342 -179.180998) (xy 381.700278 -179.191412) (xy 381.68954 -179.21817) (xy 381.661257 -179.26841)
			(xy 381.625733 -179.313819) (xy 381.583777 -179.353362) (xy 381.536346 -179.386137) (xy 381.484521 -179.411399)
			(xy 381.429484 -179.428569) (xy 381.372489 -179.437259) (xy 381.343662 -179.437792) (xy 381.316409 -179.437357)
			(xy 381.262459 -179.429595) (xy 381.210162 -179.414235) (xy 381.160584 -179.391588) (xy 381.114733 -179.362116)
			(xy 381.073542 -179.326419) (xy 381.037851 -179.285224) (xy 381.008386 -179.239369) (xy 380.985746 -179.189787)
			(xy 380.970393 -179.137488) (xy 380.962639 -179.083537) (xy 380.962154 -179.056284) (xy 380.962816 -179.024721)
			(xy 380.973201 -178.962456) (xy 380.993686 -178.902747) (xy 381.008128 -178.874674) (xy 381.012954 -178.865784)
			(xy 381.014986 -178.846226) (xy 380.992126 -178.76774) (xy 380.988928 -178.758299) (xy 380.976483 -178.742748)
			(xy 380.967996 -178.737514) (xy 380.942872 -178.723003) (xy 380.89699 -178.687493) (xy 380.857016 -178.645443)
			(xy 380.823873 -178.597823) (xy 380.798326 -178.545732) (xy 380.780965 -178.490372) (xy 380.77219 -178.433021)
			(xy 380.771654 -178.404012) (xy 380.77214 -178.376761) (xy 380.779896 -178.322813) (xy 380.795251 -178.270518)
			(xy 380.817893 -178.220941) (xy 380.847359 -178.175091) (xy 380.88305 -178.1339) (xy 380.924241 -178.098209)
			(xy 380.970091 -178.068743) (xy 381.019668 -178.046101) (xy 381.071963 -178.030746) (xy 381.125911 -178.02299)
			(xy 381.180413 -178.02299) (xy 381.234361 -178.030746) (xy 381.286656 -178.046101) (xy 381.336233 -178.068743)
			(xy 381.382083 -178.098209) (xy 381.423274 -178.1339) (xy 381.458965 -178.175091) (xy 381.488431 -178.220941)
			(xy 381.511073 -178.270518) (xy 381.526428 -178.322813) (xy 381.534184 -178.376761) (xy 381.53467 -178.404012)
			(xy 381.534003 -178.435575) (xy 381.523619 -178.49784) (xy 381.503136 -178.557549) (xy 381.488696 -178.585622)
			(xy 381.48387 -178.594512) (xy 381.481838 -178.61407) (xy 381.504698 -178.692556) (xy 381.507925 -178.701985)
			(xy 381.520351 -178.717541) (xy 381.528828 -178.722782) (xy 381.536194 -178.726846) (xy 381.5461 -178.732688)
			(xy 381.567944 -178.73472) (xy 381.662686 -178.701192) (xy 381.678434 -178.685698) (xy 381.682498 -178.675284)
			(xy 381.692498 -178.650201) (xy 381.718576 -178.602918) (xy 381.751074 -178.559793) (xy 381.769874 -178.54041)
			(xy 381.776698 -178.532997) (xy 381.784428 -178.514408) (xy 381.78486 -178.504342) (xy 381.78486 -177.342038)
			(xy 381.784425 -177.33197) (xy 381.776712 -177.313371) (xy 381.769874 -177.30597) (xy 381.203454 -176.73955)
			(xy 381.196024 -176.732748) (xy 381.177448 -176.725005) (xy 381.167386 -176.724564) (xy 374.46077 -176.724564)
			(xy 374.450697 -176.724957) (xy 374.432098 -176.732698) (xy 374.424702 -176.73955) (xy 373.905526 -177.258726)
			(xy 373.898686 -177.266126) (xy 373.890965 -177.284725) (xy 373.89054 -177.294794) (xy 373.89054 -178.28641)
			(xy 374.259094 -178.28641) (xy 374.25958 -178.259159) (xy 374.267336 -178.205211) (xy 374.282691 -178.152916)
			(xy 374.305333 -178.103339) (xy 374.334799 -178.057489) (xy 374.37049 -178.016298) (xy 374.411681 -177.980607)
			(xy 374.457531 -177.951141) (xy 374.507108 -177.928499) (xy 374.559403 -177.913144) (xy 374.613351 -177.905388)
			(xy 374.667853 -177.905388) (xy 374.721801 -177.913144) (xy 374.774096 -177.928499) (xy 374.823673 -177.951141)
			(xy 374.869523 -177.980607) (xy 374.910714 -178.016298) (xy 374.946405 -178.057489) (xy 374.975871 -178.103339)
			(xy 374.998513 -178.152916) (xy 375.013868 -178.205211) (xy 375.021624 -178.259159) (xy 375.02211 -178.28641)
			(xy 375.021586 -178.314084) (xy 375.013594 -178.36885) (xy 374.997766 -178.421886) (xy 374.974434 -178.472074)
			(xy 374.944088 -178.51836) (xy 374.926098 -178.539394) (xy 374.919748 -178.546506) (xy 374.913144 -178.564286)
			(xy 374.914668 -178.652424) (xy 374.922034 -178.66995) (xy 374.928638 -178.676808) (xy 374.948251 -178.698239)
			(xy 374.981448 -178.745911) (xy 375.007042 -178.798061) (xy 375.024442 -178.853486) (xy 375.033248 -178.910906)
			(xy 375.033794 -178.939952) (xy 375.033308 -178.967203) (xy 375.025552 -179.021151) (xy 375.010197 -179.073446)
			(xy 374.987555 -179.123023) (xy 374.958089 -179.168873) (xy 374.922398 -179.210064) (xy 374.881207 -179.245755)
			(xy 374.835357 -179.275221) (xy 374.78578 -179.297863) (xy 374.733485 -179.313218) (xy 374.679537 -179.320974)
			(xy 374.625035 -179.320974) (xy 374.571087 -179.313218) (xy 374.518792 -179.297863) (xy 374.469215 -179.275221)
			(xy 374.423365 -179.245755) (xy 374.382174 -179.210064) (xy 374.346483 -179.168873) (xy 374.317017 -179.123023)
			(xy 374.294375 -179.073446) (xy 374.27902 -179.021151) (xy 374.271264 -178.967203) (xy 374.270778 -178.939952)
			(xy 374.271259 -178.912277) (xy 374.279258 -178.857507) (xy 374.295095 -178.804471) (xy 374.318438 -178.754283)
			(xy 374.348794 -178.707999) (xy 374.36679 -178.686968) (xy 374.37314 -178.679856) (xy 374.379744 -178.662076)
			(xy 374.37822 -178.573938) (xy 374.370854 -178.556412) (xy 374.36425 -178.549554) (xy 374.344616 -178.528141)
			(xy 374.311423 -178.480464) (xy 374.285833 -178.428309) (xy 374.268437 -178.372881) (xy 374.259637 -178.315457)
			(xy 374.259094 -178.28641) (xy 373.89054 -178.28641) (xy 373.89054 -178.504342) (xy 373.890933 -178.514415)
			(xy 373.898675 -178.533013) (xy 373.905526 -178.54041) (xy 373.926415 -178.561989) (xy 373.961804 -178.610511)
			(xy 373.989148 -178.66398) (xy 374.007773 -178.721075) (xy 374.017217 -178.780384) (xy 374.017794 -178.810412)
			(xy 374.017356 -178.837666) (xy 374.009597 -178.891618) (xy 373.994239 -178.943918) (xy 373.971594 -178.993499)
			(xy 373.942123 -179.039353) (xy 373.906427 -179.080546) (xy 373.865232 -179.116239) (xy 373.819376 -179.145707)
			(xy 373.769793 -179.168348) (xy 373.717493 -179.183703) (xy 373.66354 -179.191458) (xy 373.636286 -179.19192)
			(xy 373.636032 -179.19192) (xy 373.610829 -179.191512) (xy 373.560861 -179.184876) (xy 373.512206 -179.171702)
			(xy 373.465716 -179.152221) (xy 373.443754 -179.13985) (xy 373.433848 -179.134008) (xy 373.412004 -179.131976)
			(xy 373.317262 -179.165504) (xy 373.301514 -179.180998) (xy 373.29745 -179.191412) (xy 373.286735 -179.21818)
			(xy 373.25845 -179.268421) (xy 373.222922 -179.31383) (xy 373.180963 -179.353373) (xy 373.133528 -179.386147)
			(xy 373.0817 -179.411407) (xy 373.02666 -179.428575) (xy 372.969662 -179.437261) (xy 372.940834 -179.437792)
			(xy 372.913581 -179.437313) (xy 372.85963 -179.42956) (xy 372.807332 -179.414208) (xy 372.75775 -179.391568)
			(xy 372.711896 -179.362102) (xy 372.670703 -179.32641) (xy 372.635009 -179.285218) (xy 372.605541 -179.239365)
			(xy 372.582899 -179.189785) (xy 372.567544 -179.137488) (xy 372.559788 -179.083537) (xy 372.559326 -179.056284)
			(xy 372.559992 -179.024721) (xy 372.570376 -178.962456) (xy 372.590859 -178.902747) (xy 372.6053 -178.874674)
			(xy 372.610126 -178.865784) (xy 372.612158 -178.846226) (xy 372.589298 -178.76774) (xy 372.586074 -178.75831)
			(xy 372.573646 -178.742755) (xy 372.565168 -178.737514) (xy 372.540061 -178.722975) (xy 372.494175 -178.687473)
			(xy 372.454197 -178.645429) (xy 372.421051 -178.597814) (xy 372.395502 -178.545726) (xy 372.378138 -178.490369)
			(xy 372.369362 -178.43302) (xy 372.368826 -178.404012) (xy 372.369312 -178.376761) (xy 372.377068 -178.322813)
			(xy 372.392423 -178.270518) (xy 372.415065 -178.220941) (xy 372.444531 -178.175091) (xy 372.480222 -178.1339)
			(xy 372.521413 -178.098209) (xy 372.567263 -178.068743) (xy 372.61684 -178.046101) (xy 372.669135 -178.030746)
			(xy 372.723083 -178.02299) (xy 372.777585 -178.02299) (xy 372.831533 -178.030746) (xy 372.883828 -178.046101)
			(xy 372.933405 -178.068743) (xy 372.979255 -178.098209) (xy 373.020446 -178.1339) (xy 373.056137 -178.175091)
			(xy 373.085603 -178.220941) (xy 373.108245 -178.270518) (xy 373.1236 -178.322813) (xy 373.131356 -178.376761)
			(xy 373.131842 -178.404012) (xy 373.131179 -178.435575) (xy 373.120794 -178.49784) (xy 373.100309 -178.557549)
			(xy 373.085868 -178.585622) (xy 373.081042 -178.594512) (xy 373.07901 -178.61407) (xy 373.10187 -178.692556)
			(xy 373.105071 -178.701996) (xy 373.117514 -178.717548) (xy 373.126 -178.722782) (xy 373.133366 -178.726846)
			(xy 373.143272 -178.732688) (xy 373.165116 -178.73472) (xy 373.259858 -178.701192) (xy 373.275606 -178.685698)
			(xy 373.27967 -178.675284) (xy 373.289675 -178.650203) (xy 373.315751 -178.602919) (xy 373.348247 -178.559794)
			(xy 373.367046 -178.54041) (xy 373.373881 -178.533006) (xy 373.381602 -178.51441) (xy 373.382032 -178.504342)
			(xy 373.382032 -177.168302) (xy 373.382668 -177.14332) (xy 373.392405 -177.094313) (xy 373.411505 -177.048144)
			(xy 373.439236 -177.006581) (xy 373.456454 -176.98847) (xy 373.9388 -176.506124) (xy 373.94547 -176.498703)
			(xy 373.953064 -176.480273) (xy 373.953067 -176.460341) (xy 373.945478 -176.441909) (xy 373.9388 -176.434496)
			(xy 373.456454 -175.95215) (xy 373.439242 -175.934031) (xy 373.411499 -175.892475) (xy 373.392388 -175.846308)
			(xy 373.382645 -175.797301) (xy 373.382032 -175.772318) (xy 373.382032 -174.04461) (xy 373.381619 -174.034539)
			(xy 373.373892 -174.01594) (xy 373.367046 -174.008542) (xy 371.145054 -171.78655) (xy 371.137624 -171.779748)
			(xy 371.119048 -171.772005) (xy 371.108986 -171.771564) (xy 366.38357 -171.771564) (xy 366.373497 -171.771957)
			(xy 366.354898 -171.779698) (xy 366.347502 -171.78655) (xy 365.586518 -172.547534) (xy 365.579673 -172.55493)
			(xy 365.571955 -172.573532) (xy 365.571532 -172.583602) (xy 365.571532 -173.313852) (xy 365.897922 -173.313852)
			(xy 365.898408 -173.286601) (xy 365.906164 -173.232653) (xy 365.921519 -173.180358) (xy 365.944161 -173.130781)
			(xy 365.973627 -173.084931) (xy 366.009318 -173.04374) (xy 366.050509 -173.008049) (xy 366.096359 -172.978583)
			(xy 366.145936 -172.955941) (xy 366.198231 -172.940586) (xy 366.252179 -172.93283) (xy 366.306681 -172.93283)
			(xy 366.360629 -172.940586) (xy 366.412924 -172.955941) (xy 366.462501 -172.978583) (xy 366.508351 -173.008049)
			(xy 366.549542 -173.04374) (xy 366.585233 -173.084931) (xy 366.614699 -173.130781) (xy 366.637341 -173.180358)
			(xy 366.652696 -173.232653) (xy 366.660452 -173.286601) (xy 366.660938 -173.313852) (xy 366.66048 -173.340646)
			(xy 366.65298 -173.393706) (xy 366.638135 -173.445197) (xy 366.616237 -173.494106) (xy 366.587715 -173.539473)
			(xy 366.570768 -173.560232) (xy 366.564672 -173.567344) (xy 366.55883 -173.584362) (xy 366.5601 -173.660816)
			(xy 366.560627 -173.669989) (xy 366.567403 -173.687051) (xy 366.573308 -173.69409) (xy 366.591915 -173.715263)
			(xy 366.623297 -173.762086) (xy 366.647447 -173.813016) (xy 366.663841 -173.866946) (xy 366.672122 -173.922701)
			(xy 366.672622 -173.950884) (xy 366.672136 -173.978135) (xy 366.66438 -174.032083) (xy 366.649025 -174.084378)
			(xy 366.626383 -174.133955) (xy 366.596917 -174.179805) (xy 366.561226 -174.220996) (xy 366.520035 -174.256687)
			(xy 366.474185 -174.286153) (xy 366.424608 -174.308795) (xy 366.372313 -174.32415) (xy 366.318365 -174.331906)
			(xy 366.263863 -174.331906) (xy 366.209915 -174.32415) (xy 366.15762 -174.308795) (xy 366.108043 -174.286153)
			(xy 366.062193 -174.256687) (xy 366.021002 -174.220996) (xy 365.985311 -174.179805) (xy 365.955845 -174.133955)
			(xy 365.933203 -174.084378) (xy 365.917848 -174.032083) (xy 365.910092 -173.978135) (xy 365.909606 -173.950884)
			(xy 365.91004 -173.924089) (xy 365.917547 -173.871028) (xy 365.932399 -173.819538) (xy 365.954302 -173.770629)
			(xy 365.982828 -173.725262) (xy 365.999776 -173.704504) (xy 366.005872 -173.697392) (xy 366.011714 -173.680374)
			(xy 366.010444 -173.60392) (xy 366.00989 -173.594751) (xy 366.003132 -173.577688) (xy 365.997236 -173.570646)
			(xy 365.978637 -173.549467) (xy 365.947256 -173.502644) (xy 365.923105 -173.451715) (xy 365.906709 -173.397788)
			(xy 365.898424 -173.342035) (xy 365.897922 -173.313852) (xy 365.571532 -173.313852) (xy 365.571532 -173.580552)
			(xy 365.571808 -173.588664) (xy 365.576855 -173.60408) (xy 365.581438 -173.610778) (xy 365.59912 -173.635552)
			(xy 365.62719 -173.689557) (xy 365.646317 -173.747337) (xy 365.656015 -173.807422) (xy 365.656622 -173.837854)
			(xy 365.656102 -173.865105) (xy 365.648352 -173.919053) (xy 365.633002 -173.971349) (xy 365.610366 -174.020928)
			(xy 365.580904 -174.066781) (xy 365.545216 -174.107974) (xy 365.504029 -174.143668) (xy 365.458181 -174.173137)
			(xy 365.408605 -174.195781) (xy 365.356312 -174.211139) (xy 365.302365 -174.218898) (xy 365.275114 -174.219362)
			(xy 365.27486 -174.219362) (xy 365.249656 -174.21898) (xy 365.199687 -174.212335) (xy 365.151033 -174.199153)
			(xy 365.104543 -174.179666) (xy 365.082582 -174.167292) (xy 365.072676 -174.16145) (xy 365.050832 -174.159418)
			(xy 364.95609 -174.192946) (xy 364.940342 -174.20844) (xy 364.936278 -174.218854) (xy 364.925562 -174.245622)
			(xy 364.897274 -174.29586) (xy 364.861745 -174.341267) (xy 364.819786 -174.380808) (xy 364.772352 -174.413582)
			(xy 364.720525 -174.438842) (xy 364.665486 -174.456012) (xy 364.608489 -174.464701) (xy 364.579662 -174.465234)
			(xy 364.552411 -174.464758) (xy 364.498464 -174.456997) (xy 364.446171 -174.441638) (xy 364.396595 -174.418994)
			(xy 364.350746 -174.389526) (xy 364.309557 -174.353834) (xy 364.273866 -174.312644) (xy 364.2444 -174.266794)
			(xy 364.221758 -174.217218) (xy 364.206401 -174.164924) (xy 364.198642 -174.110977) (xy 364.198154 -174.083726)
			(xy 364.198793 -174.052162) (xy 364.209188 -173.989896) (xy 364.229682 -173.930188) (xy 364.244128 -173.902116)
			(xy 364.248954 -173.893226) (xy 364.250986 -173.873668) (xy 364.228126 -173.795182) (xy 364.224912 -173.785747)
			(xy 364.212478 -173.770193) (xy 364.203996 -173.764956) (xy 364.17889 -173.750415) (xy 364.133008 -173.71491)
			(xy 364.093034 -173.672865) (xy 364.059889 -173.62525) (xy 364.034339 -173.573164) (xy 364.016973 -173.517809)
			(xy 364.008193 -173.460462) (xy 364.007654 -173.431454) (xy 364.00814 -173.404203) (xy 364.015896 -173.350255)
			(xy 364.031251 -173.29796) (xy 364.053893 -173.248383) (xy 364.083359 -173.202533) (xy 364.11905 -173.161342)
			(xy 364.160241 -173.125651) (xy 364.206091 -173.096185) (xy 364.255668 -173.073543) (xy 364.307963 -173.058188)
			(xy 364.361911 -173.050432) (xy 364.416413 -173.050432) (xy 364.470361 -173.058188) (xy 364.522656 -173.073543)
			(xy 364.572233 -173.096185) (xy 364.618083 -173.125651) (xy 364.659274 -173.161342) (xy 364.694965 -173.202533)
			(xy 364.724431 -173.248383) (xy 364.747073 -173.29796) (xy 364.762428 -173.350255) (xy 364.770184 -173.404203)
			(xy 364.77067 -173.431454) (xy 364.77002 -173.463017) (xy 364.759629 -173.525283) (xy 364.73914 -173.584992)
			(xy 364.724696 -173.613064) (xy 364.71987 -173.621954) (xy 364.717838 -173.641512) (xy 364.740698 -173.719998)
			(xy 364.743948 -173.729418) (xy 364.756357 -173.744979) (xy 364.764828 -173.750224) (xy 364.772194 -173.754288)
			(xy 364.7821 -173.76013) (xy 364.803944 -173.762162) (xy 364.898686 -173.728634) (xy 364.914434 -173.71314)
			(xy 364.918498 -173.702726) (xy 364.928306 -173.678139) (xy 364.953718 -173.631704) (xy 364.985311 -173.589232)
			(xy 365.022476 -173.55154) (xy 365.043212 -173.535086) (xy 365.052183 -173.527505) (xy 365.062505 -173.506435)
			(xy 365.063024 -173.4947) (xy 365.063024 -172.45711) (xy 365.063667 -172.432128) (xy 365.073402 -172.383122)
			(xy 365.0925 -172.336953) (xy 365.120229 -172.29539) (xy 365.137446 -172.277278) (xy 365.8616 -171.553124)
			(xy 365.86827 -171.545703) (xy 365.875864 -171.527273) (xy 365.875867 -171.507341) (xy 365.868278 -171.488909)
			(xy 365.8616 -171.481496) (xy 365.137446 -170.757342) (xy 365.120229 -170.739228) (xy 365.092487 -170.69767)
			(xy 365.073378 -170.651501) (xy 365.063636 -170.602493) (xy 365.063024 -170.57751) (xy 365.063024 -169.470578)
			(xy 365.06263 -169.460505) (xy 365.05489 -169.441906) (xy 365.048038 -169.43451) (xy 359.22204 -163.608766)
			(xy 359.214624 -163.601946) (xy 359.196037 -163.594216) (xy 359.185972 -163.59378) (xy 358.29367 -163.59378)
			(xy 358.283596 -163.594168) (xy 358.264997 -163.601913) (xy 358.257602 -163.608766) (xy 357.64089 -164.225224)
			(xy 357.622796 -164.242482) (xy 357.58125 -164.270291) (xy 357.535078 -164.289463) (xy 357.486054 -164.299263)
			(xy 357.461058 -164.2999) (xy 357.299768 -164.2999) (xy 357.289758 -164.300362) (xy 357.271266 -164.308032)
			(xy 357.257114 -164.322193) (xy 357.249456 -164.34069) (xy 357.248968 -164.3507) (xy 357.248968 -165.256464)
			(xy 357.249394 -165.266534) (xy 357.257112 -165.285133) (xy 357.263954 -165.292532) (xy 357.284811 -165.31414)
			(xy 357.320203 -165.362655) (xy 357.347553 -165.416117) (xy 357.366185 -165.473205) (xy 357.375639 -165.532508)
			(xy 357.376222 -165.562534) (xy 357.375754 -165.589785) (xy 357.367993 -165.643733) (xy 357.358644 -165.675564)
			(xy 357.617522 -165.675564) (xy 357.617982 -165.648088) (xy 357.625879 -165.593707) (xy 357.641505 -165.541025)
			(xy 357.664536 -165.491132) (xy 357.694494 -165.445065) (xy 357.712264 -165.424104) (xy 357.712518 -165.42385)
			(xy 357.718092 -165.416755) (xy 357.724346 -165.399845) (xy 357.72471 -165.39083) (xy 357.72471 -165.323266)
			(xy 357.724367 -165.314248) (xy 357.71811 -165.297331) (xy 357.712518 -165.290246) (xy 357.71201 -165.289738)
			(xy 357.6943 -165.268773) (xy 357.664414 -165.222745) (xy 357.641443 -165.172905) (xy 357.625863 -165.120284)
			(xy 357.617996 -165.065972) (xy 357.617522 -165.038532) (xy 357.618008 -165.011281) (xy 357.625764 -164.957333)
			(xy 357.641119 -164.905038) (xy 357.663761 -164.855461) (xy 357.693227 -164.809611) (xy 357.728918 -164.76842)
			(xy 357.770109 -164.732729) (xy 357.815959 -164.703263) (xy 357.865536 -164.680621) (xy 357.917831 -164.665266)
			(xy 357.971779 -164.65751) (xy 358.026281 -164.65751) (xy 358.080229 -164.665266) (xy 358.132524 -164.680621)
			(xy 358.182101 -164.703263) (xy 358.227951 -164.732729) (xy 358.269142 -164.76842) (xy 358.304833 -164.809611)
			(xy 358.334299 -164.855461) (xy 358.356941 -164.905038) (xy 358.372296 -164.957333) (xy 358.380052 -165.011281)
			(xy 358.380538 -165.038532) (xy 358.380062 -165.066007) (xy 358.372166 -165.120387) (xy 358.356543 -165.173069)
			(xy 358.333517 -165.222961) (xy 358.303564 -165.26903) (xy 358.285796 -165.289992) (xy 358.285542 -165.290246)
			(xy 358.279965 -165.297339) (xy 358.273714 -165.314251) (xy 358.27335 -165.323266) (xy 358.27335 -165.39083)
			(xy 358.273682 -165.39985) (xy 358.279946 -165.416767) (xy 358.285542 -165.42385) (xy 358.28605 -165.424358)
			(xy 358.303799 -165.445292) (xy 358.333681 -165.491327) (xy 358.356645 -165.541175) (xy 358.372216 -165.593804)
			(xy 358.380071 -165.648122) (xy 358.380538 -165.675564) (xy 358.380052 -165.702815) (xy 358.372296 -165.756763)
			(xy 358.356941 -165.809058) (xy 358.334299 -165.858635) (xy 358.304833 -165.904485) (xy 358.269142 -165.945676)
			(xy 358.227951 -165.981367) (xy 358.182101 -166.010833) (xy 358.132524 -166.033475) (xy 358.080229 -166.04883)
			(xy 358.026281 -166.056586) (xy 357.971779 -166.056586) (xy 357.917831 -166.04883) (xy 357.865536 -166.033475)
			(xy 357.815959 -166.010833) (xy 357.770109 -165.981367) (xy 357.728918 -165.945676) (xy 357.693227 -165.904485)
			(xy 357.663761 -165.858635) (xy 357.641119 -165.809058) (xy 357.625764 -165.756763) (xy 357.618008 -165.702815)
			(xy 357.617522 -165.675564) (xy 357.358644 -165.675564) (xy 357.352634 -165.696027) (xy 357.32999 -165.745604)
			(xy 357.300522 -165.791453) (xy 357.264829 -165.832643) (xy 357.223637 -165.868334) (xy 357.177786 -165.8978)
			(xy 357.128209 -165.920441) (xy 357.075914 -165.935797) (xy 357.021965 -165.943555) (xy 356.994714 -165.944042)
			(xy 356.99446 -165.944042) (xy 356.969256 -165.943663) (xy 356.919287 -165.937017) (xy 356.870632 -165.923835)
			(xy 356.824143 -165.904346) (xy 356.802182 -165.891972) (xy 356.792276 -165.88613) (xy 356.770432 -165.884098)
			(xy 356.67569 -165.917626) (xy 356.659942 -165.93312) (xy 356.655878 -165.943534) (xy 356.645152 -165.970297)
			(xy 356.616866 -166.020536) (xy 356.581339 -166.065944) (xy 356.539382 -166.105486) (xy 356.491949 -166.138261)
			(xy 356.440123 -166.163521) (xy 356.385085 -166.180692) (xy 356.328089 -166.189381) (xy 356.299262 -166.189914)
			(xy 356.27201 -166.189458) (xy 356.218062 -166.181696) (xy 356.165767 -166.166336) (xy 356.11619 -166.143691)
			(xy 356.07034 -166.114222) (xy 356.02915 -166.078527) (xy 355.993459 -166.037335) (xy 355.963993 -165.991482)
			(xy 355.941352 -165.941903) (xy 355.925997 -165.889607) (xy 355.91824 -165.835658) (xy 355.917754 -165.808406)
			(xy 355.918386 -165.776842) (xy 355.928784 -165.714576) (xy 355.949281 -165.654867) (xy 355.963728 -165.626796)
			(xy 355.968554 -165.617906) (xy 355.970586 -165.598348) (xy 355.947726 -165.519862) (xy 355.94452 -165.510424)
			(xy 355.93208 -165.494871) (xy 355.923596 -165.489636) (xy 355.898482 -165.475109) (xy 355.8526 -165.439602)
			(xy 355.812625 -165.397554) (xy 355.779482 -165.349937) (xy 355.753933 -165.297849) (xy 355.736569 -165.242491)
			(xy 355.727791 -165.185142) (xy 355.727254 -165.156134) (xy 355.72774 -165.128883) (xy 355.735496 -165.074935)
			(xy 355.750851 -165.02264) (xy 355.773493 -164.973063) (xy 355.802959 -164.927213) (xy 355.83865 -164.886022)
			(xy 355.879841 -164.850331) (xy 355.925691 -164.820865) (xy 355.975268 -164.798223) (xy 356.027563 -164.782868)
			(xy 356.081511 -164.775112) (xy 356.136013 -164.775112) (xy 356.189961 -164.782868) (xy 356.242256 -164.798223)
			(xy 356.291833 -164.820865) (xy 356.337683 -164.850331) (xy 356.378874 -164.886022) (xy 356.414565 -164.927213)
			(xy 356.444031 -164.973063) (xy 356.466673 -165.02264) (xy 356.482028 -165.074935) (xy 356.489784 -165.128883)
			(xy 356.49027 -165.156134) (xy 356.489612 -165.187697) (xy 356.479225 -165.249962) (xy 356.458738 -165.309671)
			(xy 356.444296 -165.337744) (xy 356.43947 -165.346634) (xy 356.437438 -165.366192) (xy 356.460298 -165.444678)
			(xy 356.463556 -165.454094) (xy 356.475959 -165.469657) (xy 356.484428 -165.474904) (xy 356.491794 -165.478968)
			(xy 356.5017 -165.48481) (xy 356.523544 -165.486842) (xy 356.618286 -165.453314) (xy 356.634034 -165.43782)
			(xy 356.638098 -165.427406) (xy 356.648104 -165.402326) (xy 356.67418 -165.355042) (xy 356.706675 -165.311916)
			(xy 356.725474 -165.292532) (xy 356.732289 -165.285112) (xy 356.740024 -165.266528) (xy 356.74046 -165.256464)
			(xy 356.74046 -162.3441) (xy 356.740045 -162.334029) (xy 356.732318 -162.315431) (xy 356.725474 -162.308032)
			(xy 356.156006 -161.738564) (xy 356.138809 -161.720431) (xy 356.111061 -161.678881) (xy 356.091946 -161.632718)
			(xy 356.082198 -161.583714) (xy 356.081584 -161.558732) (xy 356.081584 -155.956762) (xy 356.081183 -155.94669)
			(xy 356.073446 -155.928092) (xy 356.066598 -155.920694) (xy 355.371654 -155.22575) (xy 355.364224 -155.218948)
			(xy 355.345648 -155.211205) (xy 355.335586 -155.210764) (xy 349.94977 -155.210764) (xy 349.939697 -155.211157)
			(xy 349.921098 -155.218898) (xy 349.913702 -155.22575) (xy 348.958154 -156.181298) (xy 348.951316 -156.188699)
			(xy 348.943597 -156.207298) (xy 348.943168 -156.217366) (xy 348.943168 -156.681932) (xy 349.311722 -156.681932)
			(xy 349.312208 -156.654681) (xy 349.319964 -156.600733) (xy 349.335319 -156.548438) (xy 349.357961 -156.498861)
			(xy 349.387427 -156.453011) (xy 349.423118 -156.41182) (xy 349.464309 -156.376129) (xy 349.510159 -156.346663)
			(xy 349.559736 -156.324021) (xy 349.612031 -156.308666) (xy 349.665979 -156.30091) (xy 349.720481 -156.30091)
			(xy 349.774429 -156.308666) (xy 349.826724 -156.324021) (xy 349.876301 -156.346663) (xy 349.922151 -156.376129)
			(xy 349.963342 -156.41182) (xy 349.999033 -156.453011) (xy 350.028499 -156.498861) (xy 350.051141 -156.548438)
			(xy 350.066496 -156.600733) (xy 350.074252 -156.654681) (xy 350.074738 -156.681932) (xy 350.074171 -156.711027)
			(xy 350.065334 -156.768541) (xy 350.047854 -156.824042) (xy 350.022138 -156.876241) (xy 349.988784 -156.923922)
			(xy 349.969074 -156.94533) (xy 349.962216 -156.952442) (xy 349.955104 -156.970476) (xy 349.955612 -157.051248)
			(xy 349.956057 -157.060976) (xy 349.963384 -157.079004) (xy 349.969836 -157.0863) (xy 349.989942 -157.107813)
			(xy 350.024011 -157.155835) (xy 350.050299 -157.20852) (xy 350.068182 -157.264619) (xy 350.077236 -157.322798)
			(xy 350.077786 -157.352238) (xy 350.0773 -157.379489) (xy 350.069544 -157.433437) (xy 350.054189 -157.485732)
			(xy 350.031547 -157.535309) (xy 350.002081 -157.581159) (xy 349.96639 -157.62235) (xy 349.925199 -157.658041)
			(xy 349.879349 -157.687507) (xy 349.829772 -157.710149) (xy 349.777477 -157.725504) (xy 349.723529 -157.73326)
			(xy 349.669027 -157.73326) (xy 349.615079 -157.725504) (xy 349.562784 -157.710149) (xy 349.513207 -157.687507)
			(xy 349.467357 -157.658041) (xy 349.426166 -157.62235) (xy 349.390475 -157.581159) (xy 349.361009 -157.535309)
			(xy 349.338367 -157.485732) (xy 349.323012 -157.433437) (xy 349.315256 -157.379489) (xy 349.31477 -157.352238)
			(xy 349.315343 -157.323144) (xy 349.324183 -157.265631) (xy 349.341663 -157.210131) (xy 349.367376 -157.157932)
			(xy 349.400726 -157.110249) (xy 349.420434 -157.08884) (xy 349.427292 -157.081728) (xy 349.434404 -157.063694)
			(xy 349.433896 -156.982922) (xy 349.433413 -156.973198) (xy 349.426112 -156.95517) (xy 349.419672 -156.94787)
			(xy 349.399553 -156.926369) (xy 349.365486 -156.878344) (xy 349.3392 -156.825655) (xy 349.32132 -156.769554)
			(xy 349.31227 -156.711373) (xy 349.311722 -156.681932) (xy 348.943168 -156.681932) (xy 348.943168 -156.899864)
			(xy 348.943594 -156.909934) (xy 348.951312 -156.928533) (xy 348.958154 -156.935932) (xy 348.979011 -156.95754)
			(xy 349.014403 -157.006055) (xy 349.041753 -157.059517) (xy 349.060385 -157.116605) (xy 349.069839 -157.175908)
			(xy 349.070422 -157.205934) (xy 349.069954 -157.233185) (xy 349.062193 -157.287133) (xy 349.046834 -157.339427)
			(xy 349.02419 -157.389004) (xy 348.994722 -157.434853) (xy 348.959029 -157.476043) (xy 348.917837 -157.511734)
			(xy 348.871986 -157.5412) (xy 348.822409 -157.563841) (xy 348.770114 -157.579197) (xy 348.716165 -157.586955)
			(xy 348.688914 -157.587442) (xy 348.68866 -157.587442) (xy 348.663456 -157.587063) (xy 348.613487 -157.580417)
			(xy 348.564832 -157.567235) (xy 348.518343 -157.547746) (xy 348.496382 -157.535372) (xy 348.486476 -157.52953)
			(xy 348.464632 -157.527498) (xy 348.36989 -157.561026) (xy 348.354142 -157.57652) (xy 348.350078 -157.586934)
			(xy 348.339352 -157.613697) (xy 348.311066 -157.663936) (xy 348.275539 -157.709344) (xy 348.233582 -157.748886)
			(xy 348.186149 -157.781661) (xy 348.134323 -157.806921) (xy 348.079285 -157.824092) (xy 348.022289 -157.832781)
			(xy 347.993462 -157.833314) (xy 347.96621 -157.832858) (xy 347.912262 -157.825096) (xy 347.859967 -157.809736)
			(xy 347.81039 -157.787091) (xy 347.76454 -157.757622) (xy 347.72335 -157.721927) (xy 347.687659 -157.680735)
			(xy 347.658193 -157.634882) (xy 347.635552 -157.585303) (xy 347.620197 -157.533007) (xy 347.61244 -157.479058)
			(xy 347.611954 -157.451806) (xy 347.612586 -157.420242) (xy 347.622984 -157.357976) (xy 347.643481 -157.298267)
			(xy 347.657928 -157.270196) (xy 347.662754 -157.261306) (xy 347.664786 -157.241748) (xy 347.641926 -157.163262)
			(xy 347.63872 -157.153824) (xy 347.62628 -157.138271) (xy 347.617796 -157.133036) (xy 347.592682 -157.118509)
			(xy 347.5468 -157.083002) (xy 347.506825 -157.040954) (xy 347.473682 -156.993337) (xy 347.448133 -156.941249)
			(xy 347.430769 -156.885891) (xy 347.421991 -156.828542) (xy 347.421454 -156.799534) (xy 343.201422 -156.799534)
			(xy 342.169242 -157.83179) (xy 342.16242 -157.839204) (xy 342.154688 -157.857792) (xy 342.154256 -157.867858)
			(xy 342.154256 -158.9659) (xy 342.154667 -158.975971) (xy 342.162396 -158.99457) (xy 342.169242 -159.001968)
			(xy 342.24085 -159.073596) (xy 343.63533 -159.073596) (xy 343.635782 -159.046021) (xy 343.643736 -158.991447)
			(xy 343.659463 -158.938586) (xy 343.682636 -158.88854) (xy 343.712771 -158.842351) (xy 343.749241 -158.800981)
			(xy 343.76995 -158.782766) (xy 343.778049 -158.775232) (xy 343.787388 -158.755204) (xy 343.787984 -158.744158)
			(xy 343.787984 -158.666434) (xy 343.787402 -158.655386) (xy 343.778047 -158.635365) (xy 343.76995 -158.627826)
			(xy 343.749238 -158.609616) (xy 343.71277 -158.568246) (xy 343.682639 -158.522055) (xy 343.659474 -158.472007)
			(xy 343.643757 -158.419145) (xy 343.635816 -158.364571) (xy 343.63533 -158.336996) (xy 343.635782 -158.309421)
			(xy 343.643736 -158.254847) (xy 343.659463 -158.201986) (xy 343.682636 -158.15194) (xy 343.712771 -158.105751)
			(xy 343.749241 -158.064381) (xy 343.76995 -158.046166) (xy 343.778049 -158.038632) (xy 343.787388 -158.018604)
			(xy 343.787984 -158.007558) (xy 343.787984 -157.929834) (xy 343.787402 -157.918786) (xy 343.778047 -157.898765)
			(xy 343.76995 -157.891226) (xy 343.749238 -157.873016) (xy 343.71277 -157.831646) (xy 343.682639 -157.785455)
			(xy 343.659474 -157.735407) (xy 343.643757 -157.682545) (xy 343.635816 -157.627971) (xy 343.63533 -157.600396)
			(xy 343.635752 -157.573141) (xy 343.64351 -157.519187) (xy 343.658869 -157.466886) (xy 343.681514 -157.417303)
			(xy 343.710986 -157.371448) (xy 343.746685 -157.330255) (xy 343.787882 -157.294561) (xy 343.83374 -157.265094)
			(xy 343.883325 -157.242454) (xy 343.935628 -157.227101) (xy 343.989583 -157.219349) (xy 344.016838 -157.218888)
			(xy 344.044694 -157.219386) (xy 344.09981 -157.227514) (xy 344.153161 -157.243564) (xy 344.203613 -157.267195)
			(xy 344.250097 -157.297905) (xy 344.291626 -157.335043) (xy 344.327319 -157.37782) (xy 344.356418 -157.425329)
			(xy 344.378306 -157.476562) (xy 344.3859 -157.503368) (xy 344.388186 -157.512258) (xy 344.398854 -157.527498)
			(xy 344.470736 -157.57525) (xy 344.48877 -157.579314) (xy 344.497914 -157.578044) (xy 344.510931 -157.576375)
			(xy 344.537115 -157.574595) (xy 344.550238 -157.574488) (xy 344.564387 -157.574577) (xy 344.59261 -157.576615)
			(xy 344.606626 -157.578552) (xy 344.616532 -157.580076) (xy 344.636344 -157.57525) (xy 344.710766 -157.51937)
			(xy 344.720926 -157.501844) (xy 344.722196 -157.491684) (xy 344.726294 -157.464532) (xy 344.741264 -157.411701)
			(xy 344.763653 -157.361562) (xy 344.792999 -157.31515) (xy 344.828695 -157.273425) (xy 344.870004 -157.237248)
			(xy 344.916072 -157.207366) (xy 344.965949 -157.184398) (xy 345.018603 -157.168817) (xy 345.072947 -157.160945)
			(xy 345.100402 -157.160468) (xy 345.127652 -157.160976) (xy 345.181598 -157.168732) (xy 345.233891 -157.184086)
			(xy 345.283466 -157.206726) (xy 345.329316 -157.23619) (xy 345.370505 -157.271879) (xy 345.406197 -157.313067)
			(xy 345.435664 -157.358914) (xy 345.458306 -157.408489) (xy 345.473663 -157.460781) (xy 345.481423 -157.514726)
			(xy 345.48191 -157.541976) (xy 345.481424 -157.56955) (xy 345.473475 -157.624122) (xy 345.457754 -157.676981)
			(xy 345.434588 -157.727027) (xy 345.404459 -157.773217) (xy 345.367995 -157.814589) (xy 345.34729 -157.832806)
			(xy 345.33921 -157.840357) (xy 345.329859 -157.860372) (xy 345.329256 -157.871414) (xy 345.329256 -157.949138)
			(xy 345.329841 -157.960186) (xy 345.339193 -157.980208) (xy 345.34729 -157.987746) (xy 345.367976 -158.005984)
			(xy 345.404449 -158.047347) (xy 345.434584 -158.093531) (xy 345.457755 -158.143574) (xy 345.473476 -158.196432)
			(xy 345.481422 -158.251003) (xy 345.48191 -158.278576) (xy 345.481422 -158.305828) (xy 345.473669 -158.359778)
			(xy 345.458316 -158.412075) (xy 345.435676 -158.461655) (xy 345.406211 -158.507508) (xy 345.37052 -158.548701)
			(xy 345.329329 -158.584395) (xy 345.283478 -158.613864) (xy 345.2339 -158.636507) (xy 345.181604 -158.651863)
			(xy 345.127654 -158.659621) (xy 345.100402 -158.660084) (xy 345.099894 -158.660084) (xy 345.066112 -158.65856)
			(xy 345.055952 -158.657544) (xy 345.036648 -158.66364) (xy 344.973656 -158.716472) (xy 344.966351 -158.723182)
			(xy 344.957079 -158.740696) (xy 344.955622 -158.750508) (xy 344.955622 -158.75127) (xy 344.952682 -158.779432)
			(xy 344.939472 -158.834493) (xy 344.918266 -158.886995) (xy 344.889532 -158.935785) (xy 344.8539 -158.979791)
			(xy 344.812153 -159.018045) (xy 344.76521 -159.049707) (xy 344.714102 -159.07408) (xy 344.659951 -159.09063)
			(xy 344.603949 -159.098992) (xy 344.575638 -159.099504) (xy 344.557619 -159.099288) (xy 344.521744 -159.09585)
			(xy 344.50401 -159.092646) (xy 344.494358 -159.090868) (xy 344.475308 -159.094424) (xy 344.400378 -159.14243)
			(xy 344.388948 -159.158178) (xy 344.386662 -159.167576) (xy 344.379304 -159.194632) (xy 344.357669 -159.246359)
			(xy 344.328699 -159.294365) (xy 344.293018 -159.337616) (xy 344.251394 -159.375182) (xy 344.204722 -159.406254)
			(xy 344.154006 -159.430165) (xy 344.100338 -159.446399) (xy 344.044873 -159.454607) (xy 344.016838 -159.455104)
			(xy 343.989586 -159.454609) (xy 343.935636 -159.446857) (xy 343.883338 -159.431506) (xy 343.833758 -159.408868)
			(xy 343.787905 -159.379403) (xy 343.746711 -159.343713) (xy 343.711017 -159.302523) (xy 343.681549 -159.256672)
			(xy 343.658906 -159.207094) (xy 343.64355 -159.154797) (xy 343.635793 -159.100848) (xy 343.63533 -159.073596)
			(xy 342.24085 -159.073596) (xy 343.072212 -159.905192) (xy 343.089459 -159.923295) (xy 343.117271 -159.964838)
			(xy 343.136446 -160.011007) (xy 343.146249 -160.060028) (xy 343.146888 -160.085024) (xy 343.146888 -160.633156)
			(xy 345.303348 -160.633156) (xy 345.303835 -160.605582) (xy 345.311781 -160.551009) (xy 345.327501 -160.498149)
			(xy 345.350667 -160.448103) (xy 345.380796 -160.401913) (xy 345.417262 -160.360542) (xy 345.437968 -160.342326)
			(xy 345.446043 -160.334771) (xy 345.455395 -160.314759) (xy 345.456002 -160.303718) (xy 345.456002 -160.225994)
			(xy 345.455381 -160.214951) (xy 345.446053 -160.19493) (xy 345.437968 -160.187386) (xy 345.41724 -160.169193)
			(xy 345.380773 -160.127819) (xy 345.350644 -160.081626) (xy 345.327481 -160.031574) (xy 345.311768 -159.978709)
			(xy 345.303832 -159.924132) (xy 345.303348 -159.896556) (xy 345.30389 -159.867333) (xy 345.312784 -159.809567)
			(xy 345.330389 -159.753835) (xy 345.356291 -159.701441) (xy 345.389885 -159.653614) (xy 345.430382 -159.611472)
			(xy 345.476836 -159.576003) (xy 345.50223 -159.56153) (xy 345.512163 -159.555482) (xy 345.525655 -159.536569)
			(xy 345.528138 -159.525208) (xy 345.541092 -159.446214) (xy 345.542415 -159.434685) (xy 345.535812 -159.412464)
			(xy 345.528392 -159.403542) (xy 345.509985 -159.382768) (xy 345.478854 -159.336819) (xy 345.454881 -159.286762)
			(xy 345.438595 -159.233703) (xy 345.430355 -159.178817) (xy 345.42984 -159.151066) (xy 345.430325 -159.124451)
			(xy 345.437904 -159.071763) (xy 345.452904 -159.020689) (xy 345.475018 -158.97227) (xy 345.503797 -158.92749)
			(xy 345.538656 -158.887261) (xy 345.578884 -158.852402) (xy 345.623663 -158.823622) (xy 345.672082 -158.801506)
			(xy 345.723155 -158.786506) (xy 345.775843 -158.778925) (xy 345.802458 -158.778448) (xy 345.82888 -158.778884)
			(xy 345.881196 -158.786341) (xy 345.931935 -158.801112) (xy 345.980079 -158.8229) (xy 346.024663 -158.851269)
			(xy 346.045028 -158.86811) (xy 346.051886 -158.873952) (xy 346.068904 -158.880302) (xy 346.153232 -158.880302)
			(xy 346.17025 -158.873952) (xy 346.177108 -158.86811) (xy 346.197474 -158.851271) (xy 346.24206 -158.822906)
			(xy 346.290204 -158.801119) (xy 346.340941 -158.786348) (xy 346.393256 -158.778888) (xy 346.4461 -158.778888)
			(xy 346.498415 -158.786348) (xy 346.549152 -158.801119) (xy 346.597296 -158.822906) (xy 346.641882 -158.851271)
			(xy 346.662248 -158.86811) (xy 346.669106 -158.873952) (xy 346.686124 -158.880302) (xy 346.770452 -158.880302)
			(xy 346.78747 -158.873952) (xy 346.794328 -158.86811) (xy 346.814684 -158.85126) (xy 346.859277 -158.822907)
			(xy 346.907424 -158.80113) (xy 346.958162 -158.786365) (xy 347.010476 -158.778907) (xy 347.036898 -158.778448)
			(xy 347.064782 -158.779011) (xy 347.119928 -158.787323) (xy 347.173219 -158.803761) (xy 347.223465 -158.827958)
			(xy 347.269543 -158.859373) (xy 347.310424 -158.897305) (xy 347.345196 -158.940907) (xy 347.37308 -158.989204)
			(xy 347.393455 -159.041117) (xy 347.405864 -159.095487) (xy 347.410032 -159.1511) (xy 347.405864 -159.206713)
			(xy 347.393455 -159.261083) (xy 347.37308 -159.312996) (xy 347.345196 -159.361293) (xy 347.310424 -159.404895)
			(xy 347.269543 -159.442827) (xy 347.223465 -159.474242) (xy 347.173219 -159.498439) (xy 347.119928 -159.514877)
			(xy 347.064782 -159.523189) (xy 347.036898 -159.523684) (xy 347.010477 -159.523208) (xy 346.958163 -159.515759)
			(xy 346.907426 -159.500997) (xy 346.859281 -159.479218) (xy 346.814695 -159.450858) (xy 346.794328 -159.434022)
			(xy 346.78747 -159.42818) (xy 346.770452 -159.42183) (xy 346.686124 -159.42183) (xy 346.669106 -159.42818)
			(xy 346.662248 -159.434022) (xy 346.641882 -159.450861) (xy 346.597296 -159.479226) (xy 346.549152 -159.501013)
			(xy 346.498415 -159.515784) (xy 346.4461 -159.523244) (xy 346.393256 -159.523244) (xy 346.340941 -159.515784)
			(xy 346.290204 -159.501013) (xy 346.24206 -159.479226) (xy 346.197474 -159.450861) (xy 346.177108 -159.434022)
			(xy 346.17025 -159.42818) (xy 346.153232 -159.42183) (xy 346.068904 -159.42183) (xy 346.051886 -159.42818)
			(xy 346.045028 -159.434022) (xy 346.031089 -159.445692) (xy 346.001317 -159.466557) (xy 345.985592 -159.475678)
			(xy 345.975754 -159.481836) (xy 345.962534 -159.500886) (xy 345.960192 -159.512254) (xy 345.94673 -159.60344)
			(xy 345.953588 -159.625538) (xy 345.961716 -159.63392) (xy 345.981267 -159.655283) (xy 346.014311 -159.702837)
			(xy 346.039779 -159.754843) (xy 346.057086 -159.810105) (xy 346.065832 -159.867348) (xy 346.066364 -159.896302)
			(xy 346.066364 -159.896556) (xy 346.065881 -159.92413) (xy 346.057933 -159.978703) (xy 346.042213 -160.031563)
			(xy 346.019046 -160.081609) (xy 345.988916 -160.127799) (xy 345.95245 -160.16917) (xy 345.931744 -160.187386)
			(xy 345.923666 -160.194938) (xy 345.914316 -160.214952) (xy 345.91371 -160.225994) (xy 345.91371 -160.303718)
			(xy 345.914321 -160.314762) (xy 345.923656 -160.334784) (xy 345.931744 -160.342326) (xy 345.95248 -160.36051)
			(xy 345.988946 -160.401886) (xy 346.019074 -160.448082) (xy 346.042235 -160.498135) (xy 346.057947 -160.551002)
			(xy 346.065881 -160.60558) (xy 346.066364 -160.633156) (xy 346.065878 -160.660407) (xy 346.058122 -160.714355)
			(xy 346.042767 -160.76665) (xy 346.020125 -160.816227) (xy 345.990659 -160.862077) (xy 345.954968 -160.903268)
			(xy 345.913777 -160.938959) (xy 345.867927 -160.968425) (xy 345.81835 -160.991067) (xy 345.766055 -161.006422)
			(xy 345.712107 -161.014178) (xy 345.657605 -161.014178) (xy 345.603657 -161.006422) (xy 345.551362 -160.991067)
			(xy 345.501785 -160.968425) (xy 345.455935 -160.938959) (xy 345.414744 -160.903268) (xy 345.379053 -160.862077)
			(xy 345.349587 -160.816227) (xy 345.326945 -160.76665) (xy 345.31159 -160.714355) (xy 345.303834 -160.660407)
			(xy 345.303348 -160.633156) (xy 343.146888 -160.633156) (xy 343.146888 -162.583368) (xy 343.146229 -162.608363)
			(xy 343.136432 -162.657384) (xy 343.117264 -162.703555) (xy 343.089464 -162.745102) (xy 343.072212 -162.7632)
			(xy 342.169242 -163.666424) (xy 342.162405 -163.673827) (xy 342.154682 -163.692424) (xy 342.154256 -163.702492)
			(xy 342.154256 -171.381928) (xy 342.153643 -171.406925) (xy 342.143832 -171.455949) (xy 342.124652 -171.50212)
			(xy 342.096838 -171.543665) (xy 342.07958 -171.56176) (xy 341.476838 -172.164502) (xy 341.458717 -172.181712)
			(xy 341.417163 -172.209458) (xy 341.370996 -172.228569) (xy 341.321989 -172.238312) (xy 341.297006 -172.238924)
			(xy 340.835234 -172.238924) (xy 340.824616 -172.239367) (xy 340.80517 -172.247891) (xy 340.790855 -172.263572)
			(xy 340.786974 -172.273468) (xy 340.786974 -172.273722) (xy 340.778138 -172.298647) (xy 340.754545 -172.345974)
			(xy 340.724642 -172.389589) (xy 340.689002 -172.428657) (xy 340.648308 -172.462428) (xy 340.60334 -172.490255)
			(xy 340.55496 -172.511605) (xy 340.504094 -172.526069) (xy 340.451719 -172.533369) (xy 340.425278 -172.533818)
			(xy 340.398027 -172.533343) (xy 340.344079 -172.525583) (xy 340.291785 -172.510226) (xy 340.242208 -172.487583)
			(xy 340.196358 -172.458115) (xy 340.155169 -172.422423) (xy 340.119477 -172.381232) (xy 340.090011 -172.335381)
			(xy 340.06737 -172.285804) (xy 340.052014 -172.233509) (xy 340.044256 -172.179561) (xy 340.04377 -172.15231)
			(xy 332.00594 -172.15231) (xy 332.00594 -173.119542) (xy 344.660982 -173.119542) (xy 344.661494 -173.092291)
			(xy 344.669245 -173.038342) (xy 344.684596 -172.986046) (xy 344.707232 -172.936466) (xy 344.736695 -172.890613)
			(xy 344.772384 -172.849421) (xy 344.813572 -172.813726) (xy 344.859421 -172.784257) (xy 344.908997 -172.761614)
			(xy 344.961291 -172.746256) (xy 345.015239 -172.738498) (xy 345.04249 -172.738034) (xy 345.06986 -172.738498)
			(xy 345.12404 -172.746315) (xy 345.176543 -172.761804) (xy 345.22629 -172.784646) (xy 345.272257 -172.814372)
			(xy 345.293188 -172.832014) (xy 345.293442 -172.832268) (xy 345.300535 -172.837844) (xy 345.317447 -172.844095)
			(xy 345.326462 -172.84446) (xy 345.393518 -172.84446) (xy 345.402537 -172.84412) (xy 345.419454 -172.837862)
			(xy 345.426538 -172.832268) (xy 345.426538 -172.832014) (xy 345.426792 -172.832014) (xy 345.447725 -172.814373)
			(xy 345.493693 -172.784649) (xy 345.543439 -172.761803) (xy 345.595941 -172.746307) (xy 345.650119 -172.738478)
			(xy 345.704861 -172.738478) (xy 345.759039 -172.746307) (xy 345.811541 -172.761803) (xy 345.861287 -172.784649)
			(xy 345.907255 -172.814373) (xy 345.928188 -172.832014) (xy 345.928442 -172.832268) (xy 345.935535 -172.837844)
			(xy 345.952447 -172.844095) (xy 345.961462 -172.84446) (xy 346.028518 -172.84446) (xy 346.037537 -172.84412)
			(xy 346.054454 -172.837862) (xy 346.061538 -172.832268) (xy 346.061538 -172.832014) (xy 346.061792 -172.832014)
			(xy 346.082718 -172.814367) (xy 346.128692 -172.784656) (xy 346.178441 -172.761821) (xy 346.230943 -172.746332)
			(xy 346.28512 -172.738507) (xy 346.31249 -172.738034) (xy 346.339745 -172.738465) (xy 346.393699 -172.746221)
			(xy 346.446 -172.761578) (xy 346.495583 -172.784223) (xy 346.541438 -172.813694) (xy 346.582632 -172.849391)
			(xy 346.618326 -172.890588) (xy 346.647793 -172.936445) (xy 346.670433 -172.98603) (xy 346.685785 -173.038333)
			(xy 346.693538 -173.092287) (xy 346.693998 -173.119542) (xy 348.676722 -173.119542) (xy 348.677194 -173.092289)
			(xy 348.684946 -173.038337) (xy 348.700299 -172.986037) (xy 348.722939 -172.936455) (xy 348.752405 -172.8906)
			(xy 348.788098 -172.849406) (xy 348.829291 -172.813712) (xy 348.875145 -172.784244) (xy 348.924726 -172.761603)
			(xy 348.977025 -172.746249) (xy 349.030977 -172.738495) (xy 349.05823 -172.738034) (xy 349.08765 -172.738585)
			(xy 349.14579 -172.747628) (xy 349.201846 -172.765509) (xy 349.22841 -172.778166) (xy 349.228664 -172.778166)
			(xy 349.236479 -172.781694) (xy 349.253488 -172.783786) (xy 349.270225 -172.780108) (xy 349.277686 -172.77588)
			(xy 349.351346 -172.730414) (xy 349.358559 -172.725571) (xy 349.369452 -172.712053) (xy 349.375176 -172.695663)
			(xy 349.375476 -172.68698) (xy 349.375476 -165.338252) (xy 349.375953 -165.313302) (xy 349.383771 -165.264018)
			(xy 349.399193 -165.216561) (xy 349.421839 -165.172095) (xy 349.451153 -165.131714) (xy 349.46844 -165.113716)
			(xy 349.947738 -164.634672) (xy 349.954588 -164.62728) (xy 349.962301 -164.608674) (xy 349.962724 -164.598604)
			(xy 349.962724 -159.530796) (xy 349.963243 -159.505848) (xy 349.971054 -159.456567) (xy 349.986466 -159.409111)
			(xy 350.009102 -159.364644) (xy 350.038406 -159.32426) (xy 350.055688 -159.30626) (xy 350.555052 -158.806896)
			(xy 350.562003 -158.799287) (xy 350.569671 -158.780174) (xy 350.569256 -158.759585) (xy 350.565466 -158.75)
			(xy 350.519746 -158.648908) (xy 350.492568 -158.632652) (xy 350.47682 -158.633668) (xy 350.452436 -158.63443)
			(xy 350.42518 -158.633984) (xy 350.371221 -158.62623) (xy 350.318915 -158.610877) (xy 350.269327 -158.588236)
			(xy 350.223466 -158.558767) (xy 350.182265 -158.523072) (xy 350.146564 -158.481876) (xy 350.11709 -158.436019)
			(xy 350.094442 -158.386434) (xy 350.079081 -158.33413) (xy 350.07132 -158.280173) (xy 350.071318 -158.22566)
			(xy 350.079074 -158.171702) (xy 350.09443 -158.119397) (xy 350.117074 -158.06981) (xy 350.146544 -158.02395)
			(xy 350.182242 -157.982752) (xy 350.223439 -157.947053) (xy 350.269298 -157.91758) (xy 350.318884 -157.894935)
			(xy 350.371189 -157.879577) (xy 350.425146 -157.871819) (xy 350.479659 -157.871819) (xy 350.533617 -157.879578)
			(xy 350.585921 -157.894937) (xy 350.635507 -157.917583) (xy 350.681365 -157.947056) (xy 350.722562 -157.982755)
			(xy 350.758259 -158.023955) (xy 350.787729 -158.069815) (xy 350.810372 -158.119402) (xy 350.825727 -158.171707)
			(xy 350.833483 -158.225666) (xy 350.833944 -158.252922) (xy 350.833182 -158.277306) (xy 350.832166 -158.293054)
			(xy 350.848422 -158.320232) (xy 350.949514 -158.365952) (xy 350.95909 -158.369796) (xy 350.979701 -158.370251)
			(xy 350.998814 -158.362523) (xy 351.00641 -158.355538) (xy 351.08261 -158.279338) (xy 351.089427 -158.27192)
			(xy 351.09716 -158.253334) (xy 351.097596 -158.24327) (xy 351.097596 -157.894274) (xy 351.097212 -157.8842)
			(xy 351.089465 -157.865601) (xy 351.08261 -157.858206) (xy 350.966278 -157.741874) (xy 350.96133 -157.73715)
			(xy 350.949478 -157.730328) (xy 350.94291 -157.728412) (xy 350.942148 -157.728412) (xy 350.914757 -157.72131)
			(xy 350.862309 -157.700074) (xy 350.813573 -157.671322) (xy 350.769619 -157.635687) (xy 350.731412 -157.593949)
			(xy 350.699789 -157.547026) (xy 350.675446 -157.495945) (xy 350.658915 -157.441829) (xy 350.65056 -157.385864)
			(xy 350.650048 -157.357572) (xy 350.650552 -157.330322) (xy 350.658311 -157.276377) (xy 350.673667 -157.224086)
			(xy 350.696308 -157.174511) (xy 350.725774 -157.128663) (xy 350.761463 -157.087474) (xy 350.80265 -157.051783)
			(xy 350.848497 -157.022316) (xy 350.898071 -156.999673) (xy 350.950362 -156.984314) (xy 351.004306 -156.976553)
			(xy 351.031556 -156.976064) (xy 351.059861 -156.976616) (xy 351.115853 -156.984955) (xy 351.169996 -157.001485)
			(xy 351.221097 -157.025843) (xy 351.268033 -157.057492) (xy 351.309771 -157.095736) (xy 351.345392 -157.139734)
			(xy 351.374112 -157.188517) (xy 351.395299 -157.241012) (xy 351.402396 -157.268418) (xy 351.402396 -157.268926)
			(xy 351.404332 -157.275483) (xy 351.411163 -157.287323) (xy 351.415858 -157.292294) (xy 351.640394 -157.51683)
			(xy 351.6577 -157.534854) (xy 351.687069 -157.575276) (xy 351.709766 -157.619787) (xy 351.725234 -157.667296)
			(xy 351.733095 -157.716638) (xy 351.733612 -157.74162) (xy 351.733612 -158.395924) (xy 351.73317 -158.420913)
			(xy 351.725339 -158.470275) (xy 351.709875 -158.517801) (xy 351.687159 -158.562319) (xy 351.657751 -158.60273)
			(xy 351.640394 -158.620714) (xy 351.331276 -158.929832) (xy 351.324498 -158.937275) (xy 351.316927 -158.955914)
			(xy 351.317075 -158.976031) (xy 351.320608 -158.985458) (xy 351.357184 -159.072072) (xy 351.361536 -159.081218)
			(xy 351.375997 -159.095372) (xy 351.394811 -159.102824) (xy 351.404936 -159.10306) (xy 351.410778 -159.10306)
			(xy 351.438027 -159.103599) (xy 351.491971 -159.111351) (xy 351.544263 -159.126702) (xy 351.593838 -159.149338)
			(xy 351.639687 -159.178799) (xy 351.680877 -159.214485) (xy 351.716568 -159.25567) (xy 351.746036 -159.301515)
			(xy 351.768679 -159.351086) (xy 351.784037 -159.403376) (xy 351.791798 -159.457319) (xy 351.792286 -159.484568)
			(xy 351.791815 -159.512479) (xy 351.783672 -159.567705) (xy 351.767571 -159.621156) (xy 351.743854 -159.67169)
			(xy 351.713027 -159.71823) (xy 351.69475 -159.73933) (xy 351.688834 -159.746494) (xy 351.682196 -159.763829)
			(xy 351.681796 -159.773112) (xy 351.681796 -159.850836) (xy 351.6884 -159.868108) (xy 351.69475 -159.87522)
			(xy 351.71302 -159.896326) (xy 351.743847 -159.942864) (xy 351.767563 -159.993397) (xy 351.783661 -160.046846)
			(xy 351.791799 -160.102071) (xy 351.792286 -160.129982) (xy 351.7918 -160.157233) (xy 351.784044 -160.211181)
			(xy 351.768689 -160.263476) (xy 351.746047 -160.313053) (xy 351.716581 -160.358903) (xy 351.68089 -160.400094)
			(xy 351.639699 -160.435785) (xy 351.593849 -160.465251) (xy 351.544272 -160.487893) (xy 351.491977 -160.503248)
			(xy 351.438029 -160.511004) (xy 351.383527 -160.511004) (xy 351.329579 -160.503248) (xy 351.277284 -160.487893)
			(xy 351.227707 -160.465251) (xy 351.181857 -160.435785) (xy 351.140666 -160.400094) (xy 351.104975 -160.358903)
			(xy 351.075509 -160.313053) (xy 351.052867 -160.263476) (xy 351.037512 -160.211181) (xy 351.029756 -160.157233)
			(xy 351.02927 -160.129982) (xy 351.029757 -160.102071) (xy 351.037894 -160.046845) (xy 351.053991 -159.993394)
			(xy 351.077705 -159.94286) (xy 351.108529 -159.89632) (xy 351.126806 -159.87522) (xy 351.132695 -159.868037)
			(xy 351.139351 -159.850716) (xy 351.13976 -159.841438) (xy 351.13976 -159.763714) (xy 351.133156 -159.746442)
			(xy 351.126806 -159.73933) (xy 351.108522 -159.718236) (xy 351.077695 -159.671696) (xy 351.053981 -159.62116)
			(xy 351.037886 -159.567707) (xy 351.029754 -159.51248) (xy 351.02927 -159.484568) (xy 351.02927 -159.478726)
			(xy 351.029012 -159.468605) (xy 351.021554 -159.449802) (xy 351.007422 -159.435328) (xy 350.998282 -159.430974)
			(xy 350.911668 -159.394398) (xy 350.902252 -159.390816) (xy 350.88212 -159.390662) (xy 350.863482 -159.398272)
			(xy 350.856042 -159.405066) (xy 350.613218 -159.647636) (xy 350.606372 -159.655032) (xy 350.598655 -159.673634)
			(xy 350.598232 -159.683704) (xy 350.598232 -164.751512) (xy 350.59773 -164.776461) (xy 350.589918 -164.825743)
			(xy 350.574502 -164.8732) (xy 350.551861 -164.917666) (xy 350.522552 -164.958049) (xy 350.505268 -164.976048)
			(xy 350.02597 -165.455092) (xy 350.019137 -165.462497) (xy 350.011414 -165.481093) (xy 350.010984 -165.49116)
			(xy 350.010984 -167.430196) (xy 351.94113 -167.430196) (xy 351.941582 -167.402621) (xy 351.949536 -167.348047)
			(xy 351.965263 -167.295186) (xy 351.988436 -167.24514) (xy 352.018571 -167.198951) (xy 352.055041 -167.157581)
			(xy 352.07575 -167.139366) (xy 352.083849 -167.131832) (xy 352.093188 -167.111804) (xy 352.093784 -167.100758)
			(xy 352.093784 -167.023034) (xy 352.093202 -167.011986) (xy 352.083847 -166.991965) (xy 352.07575 -166.984426)
			(xy 352.055038 -166.966216) (xy 352.01857 -166.924846) (xy 351.988439 -166.878655) (xy 351.965274 -166.828607)
			(xy 351.949557 -166.775745) (xy 351.941616 -166.721171) (xy 351.94113 -166.693596) (xy 351.941582 -166.666021)
			(xy 351.949536 -166.611447) (xy 351.965263 -166.558586) (xy 351.988436 -166.50854) (xy 352.018571 -166.462351)
			(xy 352.055041 -166.420981) (xy 352.07575 -166.402766) (xy 352.083849 -166.395232) (xy 352.093188 -166.375204)
			(xy 352.093784 -166.364158) (xy 352.093784 -166.286434) (xy 352.093202 -166.275386) (xy 352.083847 -166.255365)
			(xy 352.07575 -166.247826) (xy 352.055038 -166.229616) (xy 352.01857 -166.188246) (xy 351.988439 -166.142055)
			(xy 351.965274 -166.092007) (xy 351.949557 -166.039145) (xy 351.941616 -165.984571) (xy 351.94113 -165.956996)
			(xy 351.941552 -165.929741) (xy 351.94931 -165.875787) (xy 351.964669 -165.823486) (xy 351.987314 -165.773903)
			(xy 352.016786 -165.728048) (xy 352.052485 -165.686855) (xy 352.093682 -165.651161) (xy 352.13954 -165.621694)
			(xy 352.189125 -165.599054) (xy 352.241428 -165.583701) (xy 352.295383 -165.575949) (xy 352.322638 -165.575488)
			(xy 352.350494 -165.575986) (xy 352.40561 -165.584114) (xy 352.458961 -165.600164) (xy 352.509413 -165.623795)
			(xy 352.555897 -165.654505) (xy 352.597426 -165.691643) (xy 352.633119 -165.73442) (xy 352.662218 -165.781929)
			(xy 352.684106 -165.833162) (xy 352.6917 -165.859968) (xy 352.693986 -165.868858) (xy 352.704654 -165.884098)
			(xy 352.776536 -165.93185) (xy 352.79457 -165.935914) (xy 352.803714 -165.934644) (xy 352.816731 -165.932975)
			(xy 352.842915 -165.931195) (xy 352.856038 -165.931088) (xy 352.870187 -165.931177) (xy 352.89841 -165.933215)
			(xy 352.912426 -165.935152) (xy 352.922332 -165.936676) (xy 352.942144 -165.93185) (xy 353.016566 -165.87597)
			(xy 353.026726 -165.858444) (xy 353.027996 -165.848284) (xy 353.032094 -165.821132) (xy 353.047064 -165.768301)
			(xy 353.069453 -165.718162) (xy 353.098799 -165.67175) (xy 353.134495 -165.630025) (xy 353.175804 -165.593848)
			(xy 353.221872 -165.563966) (xy 353.271749 -165.540998) (xy 353.324403 -165.525417) (xy 353.378747 -165.517545)
			(xy 353.406202 -165.517068) (xy 353.433452 -165.517576) (xy 353.487398 -165.525332) (xy 353.539691 -165.540686)
			(xy 353.589266 -165.563326) (xy 353.635116 -165.59279) (xy 353.676305 -165.628479) (xy 353.711997 -165.669667)
			(xy 353.741464 -165.715514) (xy 353.764106 -165.765089) (xy 353.779463 -165.817381) (xy 353.787223 -165.871326)
			(xy 353.78771 -165.898576) (xy 353.787224 -165.92615) (xy 353.779275 -165.980722) (xy 353.763554 -166.033581)
			(xy 353.740388 -166.083627) (xy 353.710259 -166.129817) (xy 353.673795 -166.171189) (xy 353.65309 -166.189406)
			(xy 353.64501 -166.196957) (xy 353.635659 -166.216972) (xy 353.635056 -166.228014) (xy 353.635056 -166.305738)
			(xy 353.635641 -166.316786) (xy 353.644993 -166.336808) (xy 353.65309 -166.344346) (xy 353.673776 -166.362584)
			(xy 353.710249 -166.403947) (xy 353.740384 -166.450131) (xy 353.763555 -166.500174) (xy 353.779276 -166.553032)
			(xy 353.787222 -166.607603) (xy 353.78771 -166.635176) (xy 353.787222 -166.662428) (xy 353.779469 -166.716378)
			(xy 353.764116 -166.768675) (xy 353.741476 -166.818255) (xy 353.712011 -166.864108) (xy 353.67632 -166.905301)
			(xy 353.635129 -166.940995) (xy 353.589278 -166.970464) (xy 353.5397 -166.993107) (xy 353.487404 -167.008463)
			(xy 353.433454 -167.016221) (xy 353.406202 -167.016684) (xy 353.405694 -167.016684) (xy 353.371912 -167.01516)
			(xy 353.361752 -167.014144) (xy 353.342448 -167.02024) (xy 353.279456 -167.073072) (xy 353.272151 -167.079782)
			(xy 353.262879 -167.097296) (xy 353.261422 -167.107108) (xy 353.261422 -167.10787) (xy 353.258482 -167.136032)
			(xy 353.245272 -167.191093) (xy 353.224066 -167.243595) (xy 353.195332 -167.292385) (xy 353.1597 -167.336391)
			(xy 353.117953 -167.374645) (xy 353.07101 -167.406307) (xy 353.019902 -167.43068) (xy 352.965751 -167.44723)
			(xy 352.909749 -167.455592) (xy 352.881438 -167.456104) (xy 352.863419 -167.455888) (xy 352.827544 -167.45245)
			(xy 352.80981 -167.449246) (xy 352.800158 -167.447468) (xy 352.781108 -167.451024) (xy 352.706178 -167.49903)
			(xy 352.694748 -167.514778) (xy 352.692462 -167.524176) (xy 352.685104 -167.551232) (xy 352.663469 -167.602959)
			(xy 352.634499 -167.650965) (xy 352.598818 -167.694216) (xy 352.557194 -167.731782) (xy 352.510522 -167.762854)
			(xy 352.459806 -167.786765) (xy 352.406138 -167.802999) (xy 352.350673 -167.811207) (xy 352.322638 -167.811704)
			(xy 352.295386 -167.811209) (xy 352.241436 -167.803457) (xy 352.189138 -167.788106) (xy 352.139558 -167.765468)
			(xy 352.093705 -167.736003) (xy 352.052511 -167.700313) (xy 352.016817 -167.659123) (xy 351.987349 -167.613272)
			(xy 351.964706 -167.563694) (xy 351.94935 -167.511397) (xy 351.941593 -167.457448) (xy 351.94113 -167.430196)
			(xy 350.010984 -167.430196) (xy 350.010984 -168.982136) (xy 353.609148 -168.982136) (xy 353.609622 -168.954562)
			(xy 353.61757 -168.899988) (xy 353.633293 -168.847128) (xy 353.656461 -168.797081) (xy 353.686593 -168.750892)
			(xy 353.723061 -168.709521) (xy 353.743768 -168.691306) (xy 353.751852 -168.683759) (xy 353.761199 -168.663741)
			(xy 353.761802 -168.652698) (xy 353.761802 -168.574974) (xy 353.761192 -168.56393) (xy 353.751856 -168.543909)
			(xy 353.743768 -168.536366) (xy 353.723031 -168.518183) (xy 353.686564 -168.476808) (xy 353.656436 -168.430612)
			(xy 353.633275 -168.380558) (xy 353.617564 -168.327691) (xy 353.60963 -168.273112) (xy 353.609148 -168.245536)
			(xy 353.609734 -168.216611) (xy 353.618463 -168.159423) (xy 353.635726 -168.104209) (xy 353.661127 -168.052234)
			(xy 353.694085 -168.00469) (xy 353.733843 -167.962667) (xy 353.77949 -167.927129) (xy 353.804474 -167.912542)
			(xy 353.814153 -167.906387) (xy 353.827343 -167.887661) (xy 353.829874 -167.876474) (xy 353.842828 -167.798242)
			(xy 353.844057 -167.786958) (xy 353.837729 -167.765193) (xy 353.830636 -167.756332) (xy 353.830636 -167.756078)
			(xy 353.81284 -167.73549) (xy 353.782818 -167.690102) (xy 353.759725 -167.640827) (xy 353.744052 -167.588714)
			(xy 353.736134 -167.534875) (xy 353.73564 -167.507666) (xy 353.736125 -167.481051) (xy 353.743704 -167.428363)
			(xy 353.758704 -167.377289) (xy 353.780818 -167.32887) (xy 353.809597 -167.28409) (xy 353.844456 -167.243861)
			(xy 353.884684 -167.209002) (xy 353.929463 -167.180222) (xy 353.977882 -167.158106) (xy 354.028955 -167.143106)
			(xy 354.081643 -167.135525) (xy 354.108258 -167.135048) (xy 354.13468 -167.135484) (xy 354.186996 -167.142941)
			(xy 354.237735 -167.157712) (xy 354.285879 -167.1795) (xy 354.330463 -167.207869) (xy 354.350828 -167.22471)
			(xy 354.357686 -167.230552) (xy 354.374704 -167.236902) (xy 354.459032 -167.236902) (xy 354.47605 -167.230552)
			(xy 354.482908 -167.22471) (xy 354.503274 -167.207871) (xy 354.54786 -167.179506) (xy 354.596004 -167.157719)
			(xy 354.646741 -167.142948) (xy 354.699056 -167.135488) (xy 354.7519 -167.135488) (xy 354.804215 -167.142948)
			(xy 354.854952 -167.157719) (xy 354.903096 -167.179506) (xy 354.947682 -167.207871) (xy 354.968048 -167.22471)
			(xy 354.974906 -167.230552) (xy 354.991924 -167.236902) (xy 355.076252 -167.236902) (xy 355.09327 -167.230552)
			(xy 355.100128 -167.22471) (xy 355.120484 -167.20786) (xy 355.165077 -167.179507) (xy 355.213224 -167.15773)
			(xy 355.263962 -167.142965) (xy 355.316276 -167.135507) (xy 355.342698 -167.135048) (xy 355.370582 -167.135611)
			(xy 355.425728 -167.143923) (xy 355.479019 -167.160361) (xy 355.529265 -167.184558) (xy 355.575343 -167.215973)
			(xy 355.616224 -167.253905) (xy 355.650996 -167.297507) (xy 355.67888 -167.345804) (xy 355.699255 -167.397717)
			(xy 355.711664 -167.452087) (xy 355.715832 -167.5077) (xy 355.711664 -167.563313) (xy 355.699255 -167.617683)
			(xy 355.67888 -167.669596) (xy 355.650996 -167.717893) (xy 355.616224 -167.761495) (xy 355.575343 -167.799427)
			(xy 355.529265 -167.830842) (xy 355.479019 -167.855039) (xy 355.425728 -167.871477) (xy 355.370582 -167.879789)
			(xy 355.342698 -167.880284) (xy 355.316277 -167.879808) (xy 355.263963 -167.872359) (xy 355.213226 -167.857597)
			(xy 355.165081 -167.835818) (xy 355.120495 -167.807458) (xy 355.100128 -167.790622) (xy 355.09327 -167.78478)
			(xy 355.076252 -167.77843) (xy 354.991924 -167.77843) (xy 354.974906 -167.78478) (xy 354.968048 -167.790622)
			(xy 354.947682 -167.807461) (xy 354.903096 -167.835826) (xy 354.854952 -167.857613) (xy 354.804215 -167.872384)
			(xy 354.7519 -167.879844) (xy 354.699056 -167.879844) (xy 354.646741 -167.872384) (xy 354.596004 -167.857613)
			(xy 354.54786 -167.835826) (xy 354.503274 -167.807461) (xy 354.482908 -167.790622) (xy 354.47605 -167.78478)
			(xy 354.459032 -167.77843) (xy 354.374704 -167.77843) (xy 354.357686 -167.78478) (xy 354.350828 -167.790622)
			(xy 354.337682 -167.801642) (xy 354.309697 -167.821485) (xy 354.294948 -167.830246) (xy 354.284788 -167.836088)
			(xy 354.271834 -167.854884) (xy 354.258118 -167.9448) (xy 354.257015 -167.956222) (xy 354.263754 -167.978124)
			(xy 354.271072 -167.986964) (xy 354.289974 -168.008207) (xy 354.321908 -168.055254) (xy 354.346498 -168.106522)
			(xy 354.363199 -168.160875) (xy 354.371641 -168.217106) (xy 354.372164 -168.245536) (xy 354.371667 -168.27311)
			(xy 354.363722 -168.327682) (xy 354.348005 -168.380541) (xy 354.32484 -168.430588) (xy 354.294713 -168.476778)
			(xy 354.258249 -168.51815) (xy 354.237544 -168.536366) (xy 354.229475 -168.543926) (xy 354.22012 -168.563934)
			(xy 354.21951 -168.574974) (xy 354.21951 -168.652698) (xy 354.220076 -168.663748) (xy 354.229443 -168.683769)
			(xy 354.237544 -168.691306) (xy 354.25827 -168.709501) (xy 354.294737 -168.750874) (xy 354.324866 -168.797068)
			(xy 354.348029 -168.847119) (xy 354.363743 -168.899984) (xy 354.37168 -168.954561) (xy 354.372164 -168.982136)
			(xy 354.371678 -169.009387) (xy 354.363922 -169.063335) (xy 354.348567 -169.11563) (xy 354.325925 -169.165207)
			(xy 354.296459 -169.211057) (xy 354.260768 -169.252248) (xy 354.219577 -169.287939) (xy 354.173727 -169.317405)
			(xy 354.12415 -169.340047) (xy 354.071855 -169.355402) (xy 354.017907 -169.363158) (xy 353.963405 -169.363158)
			(xy 353.909457 -169.355402) (xy 353.857162 -169.340047) (xy 353.807585 -169.317405) (xy 353.761735 -169.287939)
			(xy 353.720544 -169.252248) (xy 353.684853 -169.211057) (xy 353.655387 -169.165207) (xy 353.632745 -169.11563)
			(xy 353.61739 -169.063335) (xy 353.609634 -169.009387) (xy 353.609148 -168.982136) (xy 350.010984 -168.982136)
			(xy 350.010984 -172.893736) (xy 350.011281 -172.900703) (xy 350.015148 -172.914095) (xy 350.018604 -172.920152)
			(xy 350.031933 -172.942751) (xy 350.05294 -172.990829) (xy 350.067158 -173.041332) (xy 350.074318 -173.093308)
			(xy 350.074738 -173.119542) (xy 350.074268 -173.146676) (xy 350.066578 -173.200397) (xy 350.051347 -173.252484)
			(xy 350.028882 -173.301884) (xy 349.999636 -173.347598) (xy 349.982282 -173.368462) (xy 349.976636 -173.375663)
			(xy 349.970384 -173.392845) (xy 349.97009 -173.40199) (xy 349.970344 -173.468792) (xy 349.970845 -173.477846)
			(xy 349.977341 -173.494762) (xy 349.983044 -173.501812) (xy 349.983298 -173.502066) (xy 350.001209 -173.523076)
			(xy 350.031401 -173.569298) (xy 350.054614 -173.61939) (xy 350.070362 -173.672305) (xy 350.078316 -173.726938)
			(xy 350.078802 -173.754542) (xy 350.078301 -173.781911) (xy 350.070492 -173.836089) (xy 350.055011 -173.888591)
			(xy 350.032177 -173.938339) (xy 350.00246 -173.984307) (xy 349.984822 -174.00524) (xy 349.984568 -174.005494)
			(xy 349.978974 -174.012575) (xy 349.972733 -174.029496) (xy 349.972376 -174.038514) (xy 349.972376 -174.10557)
			(xy 349.972753 -174.114585) (xy 349.978987 -174.131502) (xy 349.984568 -174.13859) (xy 349.984822 -174.13859)
			(xy 349.984822 -174.138844) (xy 350.002502 -174.159744) (xy 350.032221 -174.205719) (xy 350.055061 -174.255471)
			(xy 350.070552 -174.307977) (xy 350.078376 -174.36216) (xy 350.078371 -174.416904) (xy 350.070538 -174.471084)
			(xy 350.055039 -174.523588) (xy 350.032191 -174.573337) (xy 350.002464 -174.619306) (xy 349.984822 -174.64024)
			(xy 349.984568 -174.640494) (xy 349.978974 -174.647575) (xy 349.972733 -174.664496) (xy 349.972376 -174.673514)
			(xy 349.972376 -174.74057) (xy 349.972753 -174.749585) (xy 349.978987 -174.766502) (xy 349.984568 -174.77359)
			(xy 349.984822 -174.77359) (xy 349.984822 -174.773844) (xy 350.002502 -174.794744) (xy 350.032221 -174.840719)
			(xy 350.055061 -174.890471) (xy 350.070552 -174.942977) (xy 350.078376 -174.99716) (xy 350.078371 -175.051904)
			(xy 350.070538 -175.106084) (xy 350.055039 -175.158588) (xy 350.032191 -175.208337) (xy 350.002464 -175.254306)
			(xy 349.984822 -175.27524) (xy 349.984568 -175.275494) (xy 349.978974 -175.282575) (xy 349.972733 -175.299496)
			(xy 349.972376 -175.308514) (xy 349.972376 -175.37557) (xy 349.972753 -175.384585) (xy 349.978987 -175.401502)
			(xy 349.984568 -175.40859) (xy 349.984822 -175.40859) (xy 349.984822 -175.408844) (xy 350.002452 -175.429784)
			(xy 350.032164 -175.475755) (xy 350.055002 -175.5255) (xy 350.070495 -175.577999) (xy 350.078326 -175.632173)
			(xy 350.078802 -175.659542) (xy 350.078284 -175.687972) (xy 350.069834 -175.744201) (xy 350.053128 -175.798551)
			(xy 350.028537 -175.849818) (xy 349.996606 -175.896866) (xy 349.97771 -175.918114) (xy 349.97136 -175.924972)
			(xy 349.964502 -175.942752) (xy 349.964502 -176.031144) (xy 349.97136 -176.048924) (xy 349.97771 -176.055782)
			(xy 349.996627 -176.077012) (xy 350.028557 -176.124063) (xy 350.053144 -176.175335) (xy 350.069842 -176.22969)
			(xy 350.07828 -176.285923) (xy 350.078802 -176.314354) (xy 350.078308 -176.341723) (xy 350.070497 -176.395901)
			(xy 350.055015 -176.448404) (xy 350.032179 -176.498151) (xy 350.00246 -176.544119) (xy 349.984822 -176.565052)
			(xy 349.984568 -176.565306) (xy 349.978969 -176.572384) (xy 349.972731 -176.589308) (xy 349.972376 -176.598326)
			(xy 349.972376 -176.665382) (xy 349.972747 -176.674397) (xy 349.978985 -176.691314) (xy 349.984568 -176.698402)
			(xy 349.984822 -176.698402) (xy 349.984822 -176.698656) (xy 350.002416 -176.719626) (xy 350.032139 -176.765589)
			(xy 350.054984 -176.815329) (xy 350.070481 -176.867825) (xy 350.078313 -176.921998) (xy 350.078318 -176.976733)
			(xy 350.070496 -177.030907) (xy 350.055008 -177.083406) (xy 350.032172 -177.13315) (xy 350.002457 -177.179118)
			(xy 349.984822 -177.200052) (xy 349.984568 -177.200306) (xy 349.978969 -177.207384) (xy 349.972731 -177.224308)
			(xy 349.972376 -177.233326) (xy 349.972376 -177.300382) (xy 349.972747 -177.309397) (xy 349.978985 -177.326314)
			(xy 349.984568 -177.333402) (xy 349.984822 -177.333402) (xy 349.984822 -177.333656) (xy 350.002416 -177.354626)
			(xy 350.032139 -177.400589) (xy 350.054984 -177.450329) (xy 350.070481 -177.502825) (xy 350.078313 -177.556998)
			(xy 350.078318 -177.611733) (xy 350.070496 -177.665907) (xy 350.055008 -177.718406) (xy 350.032172 -177.76815)
			(xy 350.002457 -177.814118) (xy 349.984822 -177.835052) (xy 349.984568 -177.835306) (xy 349.978969 -177.842384)
			(xy 349.972731 -177.859308) (xy 349.972376 -177.868326) (xy 349.972376 -177.935382) (xy 349.972747 -177.944397)
			(xy 349.978985 -177.961314) (xy 349.984568 -177.968402) (xy 349.984822 -177.968402) (xy 349.984822 -177.968656)
			(xy 350.002416 -177.989626) (xy 350.032139 -178.035589) (xy 350.054984 -178.085329) (xy 350.070481 -178.137825)
			(xy 350.078313 -178.191998) (xy 350.078318 -178.246733) (xy 350.070496 -178.300907) (xy 350.055008 -178.353406)
			(xy 350.032172 -178.40315) (xy 350.002457 -178.449118) (xy 349.984822 -178.470052) (xy 349.984568 -178.470306)
			(xy 349.978969 -178.477384) (xy 349.972731 -178.494308) (xy 349.972376 -178.503326) (xy 349.972376 -178.570382)
			(xy 349.972747 -178.579397) (xy 349.978985 -178.596314) (xy 349.984568 -178.603402) (xy 349.984822 -178.603402)
			(xy 349.984822 -178.603656) (xy 350.002416 -178.624626) (xy 350.032139 -178.670589) (xy 350.054984 -178.720329)
			(xy 350.070481 -178.772825) (xy 350.078313 -178.826998) (xy 350.078318 -178.881733) (xy 350.070496 -178.935907)
			(xy 350.055008 -178.988406) (xy 350.032172 -179.03815) (xy 350.002457 -179.084118) (xy 349.984822 -179.105052)
			(xy 349.984568 -179.105306) (xy 349.978969 -179.112384) (xy 349.972731 -179.129308) (xy 349.972376 -179.138326)
			(xy 349.972376 -179.205382) (xy 349.972747 -179.214397) (xy 349.978985 -179.231314) (xy 349.984568 -179.238402)
			(xy 349.984822 -179.238402) (xy 349.984822 -179.238656) (xy 350.002457 -179.259591) (xy 350.032169 -179.305563)
			(xy 350.055005 -179.35531) (xy 350.070497 -179.40781) (xy 350.078327 -179.461985) (xy 350.078802 -179.489354)
			(xy 350.078302 -179.516606) (xy 350.070551 -179.570556) (xy 350.055201 -179.622853) (xy 350.032563 -179.672434)
			(xy 350.003099 -179.718287) (xy 349.967409 -179.759481) (xy 349.92622 -179.795175) (xy 349.880369 -179.824644)
			(xy 349.830791 -179.847287) (xy 349.778495 -179.862643) (xy 349.724546 -179.870399) (xy 349.697294 -179.870862)
			(xy 349.669923 -179.870409) (xy 349.615743 -179.862589) (xy 349.56324 -179.847098) (xy 349.513493 -179.824253)
			(xy 349.467527 -179.794525) (xy 349.446596 -179.776882) (xy 349.446342 -179.776628) (xy 349.439254 -179.771044)
			(xy 349.422338 -179.764798) (xy 349.413322 -179.764436) (xy 349.346266 -179.764436) (xy 349.337247 -179.764769)
			(xy 349.320329 -179.771032) (xy 349.313246 -179.776628) (xy 349.313246 -179.776882) (xy 349.312992 -179.776882)
			(xy 349.292071 -179.794536) (xy 349.246096 -179.824246) (xy 349.196345 -179.847079) (xy 349.143842 -179.862567)
			(xy 349.089664 -179.870391) (xy 349.062294 -179.870862) (xy 349.035039 -179.87045) (xy 348.981084 -179.862691)
			(xy 348.928782 -179.847332) (xy 348.879199 -179.824685) (xy 348.833344 -179.795213) (xy 348.79215 -179.759513)
			(xy 348.756456 -179.718315) (xy 348.72699 -179.672455) (xy 348.70435 -179.622869) (xy 348.688998 -179.570565)
			(xy 348.681246 -179.516609) (xy 348.680786 -179.489354) (xy 348.681287 -179.461985) (xy 348.689097 -179.407808)
			(xy 348.704578 -179.355305) (xy 348.727412 -179.305558) (xy 348.757129 -179.259589) (xy 348.774766 -179.238656)
			(xy 348.77502 -179.238402) (xy 348.780614 -179.231321) (xy 348.786856 -179.2144) (xy 348.787212 -179.205382)
			(xy 348.787212 -179.138326) (xy 348.78684 -179.129311) (xy 348.780603 -179.112394) (xy 348.77502 -179.105306)
			(xy 348.774766 -179.105306) (xy 348.774766 -179.105052) (xy 348.757079 -179.084157) (xy 348.727353 -179.038183)
			(xy 348.704508 -178.988431) (xy 348.689013 -178.935923) (xy 348.681188 -178.881739) (xy 348.681193 -178.826992)
			(xy 348.689028 -178.772809) (xy 348.704532 -178.720304) (xy 348.727386 -178.670556) (xy 348.75712 -178.624588)
			(xy 348.774766 -178.603656) (xy 348.77502 -178.603402) (xy 348.780614 -178.596321) (xy 348.786856 -178.5794)
			(xy 348.787212 -178.570382) (xy 348.787212 -178.503326) (xy 348.78684 -178.494311) (xy 348.780603 -178.477394)
			(xy 348.77502 -178.470306) (xy 348.774766 -178.470306) (xy 348.774766 -178.470052) (xy 348.757079 -178.449157)
			(xy 348.727353 -178.403183) (xy 348.704508 -178.353431) (xy 348.689013 -178.300923) (xy 348.681188 -178.246739)
			(xy 348.681193 -178.191992) (xy 348.689028 -178.137809) (xy 348.704532 -178.085304) (xy 348.727386 -178.035556)
			(xy 348.75712 -177.989588) (xy 348.774766 -177.968656) (xy 348.77502 -177.968402) (xy 348.780614 -177.961321)
			(xy 348.786856 -177.9444) (xy 348.787212 -177.935382) (xy 348.787212 -177.868326) (xy 348.78684 -177.859311)
			(xy 348.780603 -177.842394) (xy 348.77502 -177.835306) (xy 348.774766 -177.835306) (xy 348.774766 -177.835052)
			(xy 348.757079 -177.814157) (xy 348.727353 -177.768183) (xy 348.704508 -177.718431) (xy 348.689013 -177.665923)
			(xy 348.681188 -177.611739) (xy 348.681193 -177.556992) (xy 348.689028 -177.502809) (xy 348.704532 -177.450304)
			(xy 348.727386 -177.400556) (xy 348.75712 -177.354588) (xy 348.774766 -177.333656) (xy 348.77502 -177.333402)
			(xy 348.780614 -177.326321) (xy 348.786856 -177.3094) (xy 348.787212 -177.300382) (xy 348.787212 -177.233326)
			(xy 348.78684 -177.224311) (xy 348.780603 -177.207394) (xy 348.77502 -177.200306) (xy 348.774766 -177.200306)
			(xy 348.774766 -177.200052) (xy 348.757079 -177.179157) (xy 348.727353 -177.133183) (xy 348.704508 -177.083431)
			(xy 348.689013 -177.030923) (xy 348.681188 -176.976739) (xy 348.681193 -176.921992) (xy 348.689028 -176.867809)
			(xy 348.704532 -176.815304) (xy 348.727386 -176.765556) (xy 348.75712 -176.719588) (xy 348.774766 -176.698656)
			(xy 348.77502 -176.698402) (xy 348.780614 -176.691321) (xy 348.786856 -176.6744) (xy 348.787212 -176.665382)
			(xy 348.787212 -176.598326) (xy 348.78684 -176.589311) (xy 348.780603 -176.572394) (xy 348.77502 -176.565306)
			(xy 348.774766 -176.565306) (xy 348.774766 -176.565052) (xy 348.757133 -176.544116) (xy 348.727421 -176.498143)
			(xy 348.704585 -176.448397) (xy 348.689092 -176.395897) (xy 348.681262 -176.341723) (xy 348.680786 -176.314354)
			(xy 348.681305 -176.285924) (xy 348.689755 -176.229696) (xy 348.706461 -176.175345) (xy 348.731052 -176.124078)
			(xy 348.762983 -176.07703) (xy 348.781878 -176.055782) (xy 348.788228 -176.048924) (xy 348.795086 -176.031144)
			(xy 348.795086 -175.942752) (xy 348.788228 -175.924972) (xy 348.781878 -175.918114) (xy 348.762957 -175.896887)
			(xy 348.731028 -175.849835) (xy 348.706442 -175.798562) (xy 348.689745 -175.744206) (xy 348.681307 -175.687973)
			(xy 348.680786 -175.659542) (xy 348.68128 -175.632173) (xy 348.689092 -175.577995) (xy 348.704574 -175.525492)
			(xy 348.72741 -175.475745) (xy 348.757128 -175.429777) (xy 348.774766 -175.408844) (xy 348.77502 -175.40859)
			(xy 348.780619 -175.401512) (xy 348.786858 -175.384589) (xy 348.787212 -175.37557) (xy 348.787212 -175.308514)
			(xy 348.786846 -175.299498) (xy 348.780604 -175.282581) (xy 348.77502 -175.275494) (xy 348.774766 -175.275494)
			(xy 348.774766 -175.27524) (xy 348.757165 -175.254275) (xy 348.727435 -175.208314) (xy 348.704585 -175.158573)
			(xy 348.689084 -175.106075) (xy 348.681251 -175.051901) (xy 348.681246 -174.997163) (xy 348.68907 -174.942986)
			(xy 348.704563 -174.890486) (xy 348.727405 -174.840742) (xy 348.757127 -174.794776) (xy 348.774766 -174.773844)
			(xy 348.77502 -174.77359) (xy 348.780619 -174.766512) (xy 348.786858 -174.749589) (xy 348.787212 -174.74057)
			(xy 348.787212 -174.673514) (xy 348.786846 -174.664498) (xy 348.780604 -174.647581) (xy 348.77502 -174.640494)
			(xy 348.774766 -174.640494) (xy 348.774766 -174.64024) (xy 348.757165 -174.619275) (xy 348.727435 -174.573314)
			(xy 348.704585 -174.523573) (xy 348.689084 -174.471075) (xy 348.681251 -174.416901) (xy 348.681246 -174.362163)
			(xy 348.68907 -174.307986) (xy 348.704563 -174.255486) (xy 348.727405 -174.205742) (xy 348.757127 -174.159776)
			(xy 348.774766 -174.138844) (xy 348.77502 -174.13859) (xy 348.780619 -174.131512) (xy 348.786858 -174.114589)
			(xy 348.787212 -174.10557) (xy 348.787212 -174.038514) (xy 348.786846 -174.029498) (xy 348.780604 -174.012581)
			(xy 348.77502 -174.005494) (xy 348.774766 -174.005494) (xy 348.774766 -174.00524) (xy 348.757127 -173.984308)
			(xy 348.727416 -173.938335) (xy 348.704581 -173.888587) (xy 348.68909 -173.836087) (xy 348.681261 -173.781911)
			(xy 348.680786 -173.754542) (xy 348.681241 -173.727407) (xy 348.688933 -173.673686) (xy 348.704168 -173.621598)
			(xy 348.726637 -173.572199) (xy 348.755886 -173.526486) (xy 348.773242 -173.505622) (xy 348.778897 -173.498428)
			(xy 348.785144 -173.481241) (xy 348.785434 -173.472094) (xy 348.78518 -173.405292) (xy 348.784681 -173.396238)
			(xy 348.778183 -173.379322) (xy 348.77248 -173.372272) (xy 348.772226 -173.372018) (xy 348.754296 -173.351024)
			(xy 348.724109 -173.304797) (xy 348.700901 -173.254701) (xy 348.685157 -173.201782) (xy 348.677207 -173.147147)
			(xy 348.676722 -173.119542) (xy 346.693998 -173.119542) (xy 346.693551 -173.146512) (xy 346.685939 -173.199914)
			(xy 346.670874 -173.251708) (xy 346.648657 -173.300861) (xy 346.619731 -173.34639) (xy 346.602558 -173.367192)
			(xy 346.597009 -173.374358) (xy 346.590897 -173.391407) (xy 346.59062 -173.400466) (xy 346.591382 -173.47692)
			(xy 346.597732 -173.493684) (xy 346.604082 -173.500796) (xy 346.622136 -173.521899) (xy 346.652648 -173.568299)
			(xy 346.676116 -173.618629) (xy 346.692045 -173.671829) (xy 346.700099 -173.726775) (xy 346.700602 -173.754542)
			(xy 346.700101 -173.781911) (xy 346.692292 -173.836089) (xy 346.676811 -173.888591) (xy 346.653977 -173.938339)
			(xy 346.62426 -173.984307) (xy 346.606622 -174.00524) (xy 346.606368 -174.005494) (xy 346.600774 -174.012575)
			(xy 346.594533 -174.029496) (xy 346.594176 -174.038514) (xy 346.594176 -174.10557) (xy 346.594553 -174.114585)
			(xy 346.600787 -174.131502) (xy 346.606368 -174.13859) (xy 346.606622 -174.13859) (xy 346.606622 -174.138844)
			(xy 346.624302 -174.159744) (xy 346.654021 -174.205719) (xy 346.676861 -174.255471) (xy 346.692352 -174.307977)
			(xy 346.700176 -174.36216) (xy 346.700171 -174.416904) (xy 346.692338 -174.471084) (xy 346.676839 -174.523588)
			(xy 346.653991 -174.573337) (xy 346.624264 -174.619306) (xy 346.606622 -174.64024) (xy 346.606368 -174.640494)
			(xy 346.600774 -174.647575) (xy 346.594533 -174.664496) (xy 346.594176 -174.673514) (xy 346.594176 -174.74057)
			(xy 346.594553 -174.749585) (xy 346.600787 -174.766502) (xy 346.606368 -174.77359) (xy 346.606622 -174.77359)
			(xy 346.606622 -174.773844) (xy 346.624302 -174.794744) (xy 346.654021 -174.840719) (xy 346.676861 -174.890471)
			(xy 346.692352 -174.942977) (xy 346.700176 -174.99716) (xy 346.700171 -175.051904) (xy 346.692338 -175.106084)
			(xy 346.676839 -175.158588) (xy 346.653991 -175.208337) (xy 346.624264 -175.254306) (xy 346.606622 -175.27524)
			(xy 346.606368 -175.275494) (xy 346.600774 -175.282575) (xy 346.594533 -175.299496) (xy 346.594176 -175.308514)
			(xy 346.594176 -175.37557) (xy 346.594553 -175.384585) (xy 346.600787 -175.401502) (xy 346.606368 -175.40859)
			(xy 346.606622 -175.40859) (xy 346.606622 -175.408844) (xy 346.624252 -175.429784) (xy 346.653964 -175.475755)
			(xy 346.676802 -175.5255) (xy 346.692295 -175.577999) (xy 346.700126 -175.632173) (xy 346.700602 -175.659542)
			(xy 346.700084 -175.687972) (xy 346.691634 -175.744201) (xy 346.674928 -175.798551) (xy 346.650337 -175.849818)
			(xy 346.618406 -175.896866) (xy 346.59951 -175.918114) (xy 346.59316 -175.924972) (xy 346.586302 -175.942752)
			(xy 346.586302 -176.031144) (xy 346.59316 -176.048924) (xy 346.59951 -176.055782) (xy 346.618427 -176.077012)
			(xy 346.650357 -176.124063) (xy 346.674944 -176.175335) (xy 346.691642 -176.22969) (xy 346.70008 -176.285923)
			(xy 346.700602 -176.314354) (xy 346.700108 -176.341723) (xy 346.692297 -176.395901) (xy 346.676815 -176.448404)
			(xy 346.653979 -176.498151) (xy 346.62426 -176.544119) (xy 346.606622 -176.565052) (xy 346.606368 -176.565306)
			(xy 346.600769 -176.572384) (xy 346.594531 -176.589308) (xy 346.594176 -176.598326) (xy 346.594176 -176.665382)
			(xy 346.594547 -176.674397) (xy 346.600785 -176.691314) (xy 346.606368 -176.698402) (xy 346.606622 -176.698402)
			(xy 346.606622 -176.698656) (xy 346.624216 -176.719626) (xy 346.653939 -176.765589) (xy 346.676784 -176.815329)
			(xy 346.692281 -176.867825) (xy 346.700113 -176.921998) (xy 346.700118 -176.976733) (xy 346.692296 -177.030907)
			(xy 346.676808 -177.083406) (xy 346.653972 -177.13315) (xy 346.624257 -177.179118) (xy 346.606622 -177.200052)
			(xy 346.606368 -177.200306) (xy 346.600769 -177.207384) (xy 346.594531 -177.224308) (xy 346.594176 -177.233326)
			(xy 346.594176 -177.300382) (xy 346.594547 -177.309397) (xy 346.600785 -177.326314) (xy 346.606368 -177.333402)
			(xy 346.606622 -177.333402) (xy 346.606622 -177.333656) (xy 346.624257 -177.354591) (xy 346.653969 -177.400563)
			(xy 346.676805 -177.45031) (xy 346.692297 -177.50281) (xy 346.700127 -177.556985) (xy 346.700602 -177.584354)
			(xy 346.700116 -177.611605) (xy 346.69236 -177.665553) (xy 346.677005 -177.717848) (xy 346.654363 -177.767425)
			(xy 346.624897 -177.813275) (xy 346.589206 -177.854466) (xy 346.548015 -177.890157) (xy 346.502165 -177.919623)
			(xy 346.452588 -177.942265) (xy 346.400293 -177.95762) (xy 346.346345 -177.965376) (xy 346.291843 -177.965376)
			(xy 346.237895 -177.95762) (xy 346.1856 -177.942265) (xy 346.136023 -177.919623) (xy 346.090173 -177.890157)
			(xy 346.048982 -177.854466) (xy 346.013291 -177.813275) (xy 345.983825 -177.767425) (xy 345.961183 -177.717848)
			(xy 345.945828 -177.665553) (xy 345.938072 -177.611605) (xy 345.937586 -177.584354) (xy 345.938163 -177.554878)
			(xy 345.947224 -177.496627) (xy 345.965138 -177.440462) (xy 345.991479 -177.387723) (xy 346.025619 -177.339663)
			(xy 346.04579 -177.318162) (xy 346.052333 -177.310834) (xy 346.059774 -177.292669) (xy 346.060268 -177.282856)
			(xy 346.060268 -177.229516) (xy 346.052902 -177.222658) (xy 346.045566 -177.216125) (xy 346.027406 -177.20868)
			(xy 346.017596 -177.20818) (xy 345.985592 -177.20818) (xy 345.975779 -177.208677) (xy 345.957615 -177.216115)
			(xy 345.950286 -177.222658) (xy 345.928793 -177.242839) (xy 345.880732 -177.276983) (xy 345.827991 -177.303328)
			(xy 345.771825 -177.321247) (xy 345.713571 -177.330314) (xy 345.684094 -177.330862) (xy 345.656839 -177.33045)
			(xy 345.602884 -177.322691) (xy 345.550582 -177.307332) (xy 345.500999 -177.284685) (xy 345.455144 -177.255213)
			(xy 345.41395 -177.219513) (xy 345.378256 -177.178315) (xy 345.34879 -177.132455) (xy 345.32615 -177.082869)
			(xy 345.310798 -177.030565) (xy 345.303046 -176.976609) (xy 345.302586 -176.949354) (xy 345.303163 -176.919878)
			(xy 345.312224 -176.861627) (xy 345.330138 -176.805462) (xy 345.356479 -176.752723) (xy 345.390619 -176.704663)
			(xy 345.41079 -176.683162) (xy 345.417333 -176.675834) (xy 345.424774 -176.657669) (xy 345.425268 -176.647856)
			(xy 345.425268 -176.594516) (xy 345.417902 -176.587658) (xy 345.410566 -176.581125) (xy 345.392406 -176.57368)
			(xy 345.382596 -176.57318) (xy 345.350592 -176.57318) (xy 345.340779 -176.573677) (xy 345.322615 -176.581115)
			(xy 345.315286 -176.587658) (xy 345.293793 -176.607839) (xy 345.245732 -176.641983) (xy 345.192991 -176.668328)
			(xy 345.136825 -176.686247) (xy 345.078571 -176.695314) (xy 345.049094 -176.695862) (xy 345.021839 -176.69545)
			(xy 344.967884 -176.687691) (xy 344.915582 -176.672332) (xy 344.865999 -176.649685) (xy 344.820144 -176.620213)
			(xy 344.77895 -176.584513) (xy 344.743256 -176.543315) (xy 344.71379 -176.497455) (xy 344.69115 -176.447869)
			(xy 344.675798 -176.395565) (xy 344.668046 -176.341609) (xy 344.667586 -176.314354) (xy 344.668087 -176.286985)
			(xy 344.675897 -176.232808) (xy 344.691378 -176.180305) (xy 344.714212 -176.130558) (xy 344.743929 -176.084589)
			(xy 344.761566 -176.063656) (xy 344.76182 -176.063402) (xy 344.767414 -176.056321) (xy 344.773656 -176.0394)
			(xy 344.774012 -176.030382) (xy 344.774012 -175.963326) (xy 344.77364 -175.954311) (xy 344.767403 -175.937394)
			(xy 344.76182 -175.930306) (xy 344.761566 -175.930306) (xy 344.761566 -175.930052) (xy 344.743879 -175.909157)
			(xy 344.714153 -175.863183) (xy 344.691308 -175.813431) (xy 344.675813 -175.760923) (xy 344.667988 -175.706739)
			(xy 344.667993 -175.651992) (xy 344.675828 -175.597809) (xy 344.691332 -175.545304) (xy 344.714186 -175.495556)
			(xy 344.74392 -175.449588) (xy 344.761566 -175.428656) (xy 344.76182 -175.428402) (xy 344.767414 -175.421321)
			(xy 344.773656 -175.4044) (xy 344.774012 -175.395382) (xy 344.774012 -175.328326) (xy 344.77364 -175.319311)
			(xy 344.767403 -175.302394) (xy 344.76182 -175.295306) (xy 344.761566 -175.295306) (xy 344.761566 -175.295052)
			(xy 344.743879 -175.274157) (xy 344.714153 -175.228183) (xy 344.691308 -175.178431) (xy 344.675813 -175.125923)
			(xy 344.667988 -175.071739) (xy 344.667993 -175.016992) (xy 344.675828 -174.962809) (xy 344.691332 -174.910304)
			(xy 344.714186 -174.860556) (xy 344.74392 -174.814588) (xy 344.761566 -174.793656) (xy 344.76182 -174.793402)
			(xy 344.767414 -174.786321) (xy 344.773656 -174.7694) (xy 344.774012 -174.760382) (xy 344.774012 -174.693326)
			(xy 344.77364 -174.684311) (xy 344.767403 -174.667394) (xy 344.76182 -174.660306) (xy 344.761566 -174.660306)
			(xy 344.761566 -174.660052) (xy 344.743879 -174.639157) (xy 344.714153 -174.593183) (xy 344.691308 -174.543431)
			(xy 344.675813 -174.490923) (xy 344.667988 -174.436739) (xy 344.667993 -174.381992) (xy 344.675828 -174.327809)
			(xy 344.691332 -174.275304) (xy 344.714186 -174.225556) (xy 344.74392 -174.179588) (xy 344.761566 -174.158656)
			(xy 344.76182 -174.158402) (xy 344.767414 -174.151321) (xy 344.773656 -174.1344) (xy 344.774012 -174.125382)
			(xy 344.774012 -174.058326) (xy 344.77364 -174.049311) (xy 344.767403 -174.032394) (xy 344.76182 -174.025306)
			(xy 344.761566 -174.025306) (xy 344.761566 -174.025052) (xy 344.743933 -174.004116) (xy 344.714221 -173.958143)
			(xy 344.691385 -173.908397) (xy 344.675892 -173.855897) (xy 344.668062 -173.801723) (xy 344.667586 -173.774354)
			(xy 344.667586 -173.7741) (xy 344.668066 -173.746084) (xy 344.676297 -173.69066) (xy 344.692536 -173.637032)
			(xy 344.716436 -173.586353) (xy 344.747484 -173.539709) (xy 344.765884 -173.518576) (xy 344.772488 -173.511464)
			(xy 344.779346 -173.493684) (xy 344.778076 -173.405292) (xy 344.771218 -173.38802) (xy 344.764614 -173.380908)
			(xy 344.745242 -173.359576) (xy 344.712517 -173.312148) (xy 344.6873 -173.260336) (xy 344.670166 -173.205321)
			(xy 344.661505 -173.148353) (xy 344.660982 -173.119542) (xy 332.00594 -173.119542) (xy 332.00594 -176.049178)
			(xy 332.006956 -176.05883) (xy 332.008582 -176.066075) (xy 332.015421 -176.079246) (xy 332.020418 -176.084738)
			(xy 338.487258 -182.551578) (xy 338.493354 -182.556658) (xy 340.667235 -184.036462) (xy 352.88347 -184.036462)
			(xy 352.883955 -184.009092) (xy 352.891766 -183.954913) (xy 352.90725 -183.90241) (xy 352.930087 -183.852662)
			(xy 352.95981 -183.806696) (xy 352.97745 -183.785764) (xy 352.977704 -183.78551) (xy 352.983293 -183.778425)
			(xy 352.989538 -183.761507) (xy 352.989896 -183.75249) (xy 352.989896 -183.685434) (xy 352.989524 -183.676419)
			(xy 352.983287 -183.659501) (xy 352.977704 -183.652414) (xy 352.97745 -183.652414) (xy 352.97745 -183.65216)
			(xy 352.959771 -183.631258) (xy 352.930046 -183.585285) (xy 352.907202 -183.535534) (xy 352.891707 -183.483027)
			(xy 352.883882 -183.428844) (xy 352.883886 -183.374099) (xy 352.891719 -183.319917) (xy 352.907222 -183.267412)
			(xy 352.930074 -183.217664) (xy 352.959806 -183.171696) (xy 352.97745 -183.150764) (xy 352.977704 -183.15051)
			(xy 352.983293 -183.143425) (xy 352.989538 -183.126507) (xy 352.989896 -183.11749) (xy 352.989896 -183.050434)
			(xy 352.989524 -183.041419) (xy 352.983287 -183.024501) (xy 352.977704 -183.017414) (xy 352.97745 -183.017414)
			(xy 352.97745 -183.01716) (xy 352.959771 -182.996258) (xy 352.930046 -182.950285) (xy 352.907202 -182.900534)
			(xy 352.891707 -182.848027) (xy 352.883882 -182.793844) (xy 352.883886 -182.739099) (xy 352.891719 -182.684917)
			(xy 352.907222 -182.632412) (xy 352.930074 -182.582664) (xy 352.959806 -182.536696) (xy 352.97745 -182.515764)
			(xy 352.977704 -182.51551) (xy 352.983293 -182.508425) (xy 352.989538 -182.491507) (xy 352.989896 -182.48249)
			(xy 352.989896 -182.415434) (xy 352.989524 -182.406419) (xy 352.983287 -182.389501) (xy 352.977704 -182.382414)
			(xy 352.97745 -182.382414) (xy 352.97745 -182.38216) (xy 352.959833 -182.36121) (xy 352.930116 -182.315243)
			(xy 352.907275 -182.2655) (xy 352.891779 -182.213003) (xy 352.883946 -182.15883) (xy 352.88347 -182.131462)
			(xy 352.884003 -182.102829) (xy 352.892542 -182.046205) (xy 352.909453 -181.991494) (xy 352.934356 -181.939927)
			(xy 352.966689 -181.892665) (xy 352.985832 -181.871366) (xy 352.992436 -181.864254) (xy 352.999294 -181.846728)
			(xy 352.999802 -181.767988) (xy 352.999426 -181.75846) (xy 352.992519 -181.740705) (xy 352.98634 -181.733444)
			(xy 352.967563 -181.712232) (xy 352.935865 -181.665281) (xy 352.911464 -181.614157) (xy 352.894894 -181.559986)
			(xy 352.886523 -181.503959) (xy 352.88601 -181.475634) (xy 352.886487 -181.448381) (xy 352.89424 -181.39443)
			(xy 352.909592 -181.342131) (xy 352.932232 -181.29255) (xy 352.961698 -181.246696) (xy 352.997391 -181.205502)
			(xy 353.038583 -181.169808) (xy 353.084436 -181.14034) (xy 353.134016 -181.117698) (xy 353.186314 -181.102343)
			(xy 353.240265 -181.094588) (xy 353.267518 -181.094126) (xy 353.294889 -181.094575) (xy 353.349069 -181.102396)
			(xy 353.401573 -181.117889) (xy 353.451319 -181.140734) (xy 353.497285 -181.170463) (xy 353.518216 -181.188106)
			(xy 353.51847 -181.18836) (xy 353.525556 -181.193947) (xy 353.542473 -181.200192) (xy 353.55149 -181.200552)
			(xy 353.618546 -181.200552) (xy 353.627562 -181.20018) (xy 353.644479 -181.193944) (xy 353.651566 -181.18836)
			(xy 353.651566 -181.188106) (xy 353.65182 -181.188106) (xy 353.672753 -181.170465) (xy 353.718721 -181.140741)
			(xy 353.768467 -181.117895) (xy 353.820969 -181.102399) (xy 353.875147 -181.09457) (xy 353.929889 -181.09457)
			(xy 353.984067 -181.102399) (xy 354.036569 -181.117895) (xy 354.086315 -181.140741) (xy 354.132283 -181.170465)
			(xy 354.153216 -181.188106) (xy 354.15347 -181.18836) (xy 354.160556 -181.193947) (xy 354.177473 -181.200192)
			(xy 354.18649 -181.200552) (xy 354.253546 -181.200552) (xy 354.262562 -181.20018) (xy 354.279479 -181.193944)
			(xy 354.286566 -181.18836) (xy 354.286566 -181.188106) (xy 354.28682 -181.188106) (xy 354.307772 -181.170492)
			(xy 354.353739 -181.140776) (xy 354.403482 -181.117935) (xy 354.455978 -181.102438) (xy 354.51015 -181.094604)
			(xy 354.537518 -181.094126) (xy 354.564773 -181.094538) (xy 354.618727 -181.102299) (xy 354.671028 -181.117659)
			(xy 354.720611 -181.140306) (xy 354.766466 -181.169779) (xy 354.807659 -181.205478) (xy 354.843352 -181.246676)
			(xy 354.872819 -181.292535) (xy 354.89546 -181.34212) (xy 354.910813 -181.394423) (xy 354.918565 -181.448379)
			(xy 354.919026 -181.475634) (xy 356.90175 -181.475634) (xy 356.90231 -181.448386) (xy 356.910061 -181.394443)
			(xy 356.925409 -181.342152) (xy 356.948043 -181.292578) (xy 356.977502 -181.246729) (xy 357.013186 -181.20554)
			(xy 357.054368 -181.169848) (xy 357.100211 -181.14038) (xy 357.149781 -181.117736) (xy 357.202068 -181.102377)
			(xy 357.25601 -181.094615) (xy 357.283258 -181.094126) (xy 357.310628 -181.09461) (xy 357.364806 -181.102423)
			(xy 357.417309 -181.117907) (xy 357.467057 -181.140745) (xy 357.513024 -181.170466) (xy 357.533956 -181.188106)
			(xy 357.53421 -181.18836) (xy 357.541284 -181.193964) (xy 357.558211 -181.200199) (xy 357.56723 -181.200552)
			(xy 357.634286 -181.200552) (xy 357.643303 -181.200199) (xy 357.660221 -181.19395) (xy 357.667306 -181.18836)
			(xy 357.66756 -181.188106) (xy 357.691054 -181.168487) (xy 357.743033 -181.136172) (xy 357.799494 -181.112546)
			(xy 357.829104 -181.104794) (xy 357.829612 -181.104794) (xy 357.836168 -181.102855) (xy 357.848009 -181.096026)
			(xy 357.85298 -181.091332) (xy 358.253538 -180.691028) (xy 358.260364 -180.683617) (xy 358.268091 -180.665026)
			(xy 358.268524 -180.65496) (xy 358.268524 -167.887396) (xy 358.269043 -167.862448) (xy 358.276854 -167.813167)
			(xy 358.292266 -167.765711) (xy 358.314902 -167.721244) (xy 358.344206 -167.68086) (xy 358.361488 -167.66286)
			(xy 358.860852 -167.163496) (xy 358.867803 -167.155887) (xy 358.875471 -167.136774) (xy 358.875056 -167.116185)
			(xy 358.871266 -167.1066) (xy 358.825546 -167.005508) (xy 358.798368 -166.989252) (xy 358.78262 -166.990268)
			(xy 358.758236 -166.99103) (xy 358.73098 -166.990584) (xy 358.677021 -166.98283) (xy 358.624715 -166.967477)
			(xy 358.575127 -166.944836) (xy 358.529266 -166.915367) (xy 358.488065 -166.879672) (xy 358.452364 -166.838476)
			(xy 358.42289 -166.792619) (xy 358.400242 -166.743034) (xy 358.384881 -166.69073) (xy 358.37712 -166.636773)
			(xy 358.377118 -166.58226) (xy 358.384874 -166.528302) (xy 358.40023 -166.475997) (xy 358.422874 -166.42641)
			(xy 358.452344 -166.38055) (xy 358.488042 -166.339352) (xy 358.529239 -166.303653) (xy 358.575098 -166.27418)
			(xy 358.624684 -166.251535) (xy 358.676989 -166.236177) (xy 358.730946 -166.228419) (xy 358.785459 -166.228419)
			(xy 358.839417 -166.236178) (xy 358.891721 -166.251537) (xy 358.941307 -166.274183) (xy 358.987165 -166.303656)
			(xy 359.028362 -166.339355) (xy 359.064059 -166.380555) (xy 359.093529 -166.426415) (xy 359.116172 -166.476002)
			(xy 359.131527 -166.528307) (xy 359.139283 -166.582266) (xy 359.139744 -166.609522) (xy 359.139744 -166.609776)
			(xy 359.139132 -166.640865) (xy 359.129043 -166.70222) (xy 359.109114 -166.761118) (xy 359.09504 -166.788846)
			(xy 359.087166 -166.803832) (xy 359.091992 -166.836852) (xy 359.10393 -166.84879) (xy 359.111342 -166.855474)
			(xy 359.129775 -166.863071) (xy 359.149713 -166.863071) (xy 359.168146 -166.855474) (xy 359.175558 -166.84879)
			(xy 359.295954 -166.728648) (xy 359.302759 -166.72122) (xy 359.310501 -166.702642) (xy 359.31094 -166.69258)
			(xy 359.31094 -166.308024) (xy 359.310518 -166.297954) (xy 359.302797 -166.279355) (xy 359.295954 -166.271956)
			(xy 359.272078 -166.248334) (xy 359.267092 -166.243702) (xy 359.255251 -166.237005) (xy 359.24871 -166.235126)
			(xy 359.248456 -166.234872) (xy 359.247948 -166.234872) (xy 359.220547 -166.227807) (xy 359.168096 -166.206567)
			(xy 359.119358 -166.177812) (xy 359.075403 -166.142172) (xy 359.037196 -166.10043) (xy 359.005575 -166.053501)
			(xy 358.981234 -166.002416) (xy 358.964707 -165.948295) (xy 358.956357 -165.892326) (xy 358.955848 -165.864032)
			(xy 358.956408 -165.836784) (xy 358.964159 -165.782841) (xy 358.979508 -165.73055) (xy 359.002142 -165.680976)
			(xy 359.031601 -165.635128) (xy 359.067284 -165.593938) (xy 359.108467 -165.558246) (xy 359.154309 -165.528778)
			(xy 359.203879 -165.506134) (xy 359.256166 -165.490775) (xy 359.310108 -165.483013) (xy 359.337356 -165.482524)
			(xy 359.36566 -165.483107) (xy 359.421649 -165.491444) (xy 359.475789 -165.507972) (xy 359.526889 -165.532327)
			(xy 359.573824 -165.563972) (xy 359.615561 -165.602212) (xy 359.651183 -165.646205) (xy 359.679906 -165.694984)
			(xy 359.701097 -165.747475) (xy 359.708196 -165.774878) (xy 359.708196 -165.775386) (xy 359.710145 -165.781939)
			(xy 359.716967 -165.793781) (xy 359.721658 -165.798754) (xy 359.853484 -165.93058) (xy 359.870766 -165.948582)
			(xy 359.900092 -165.988956) (xy 359.922741 -166.03342) (xy 359.938157 -166.080879) (xy 359.94596 -166.130166)
			(xy 359.946448 -166.155116) (xy 359.946448 -166.845488) (xy 359.945927 -166.870436) (xy 359.938118 -166.919718)
			(xy 359.922707 -166.967174) (xy 359.900071 -167.01164) (xy 359.870766 -167.052025) (xy 359.853484 -167.070024)
			(xy 359.637076 -167.286432) (xy 359.630298 -167.293875) (xy 359.622727 -167.312514) (xy 359.622875 -167.332631)
			(xy 359.626408 -167.342058) (xy 359.662984 -167.428672) (xy 359.667336 -167.437818) (xy 359.681797 -167.451972)
			(xy 359.700611 -167.459424) (xy 359.710736 -167.45966) (xy 359.716578 -167.45966) (xy 359.743827 -167.460199)
			(xy 359.797771 -167.467951) (xy 359.850063 -167.483302) (xy 359.899638 -167.505938) (xy 359.945487 -167.535399)
			(xy 359.986677 -167.571085) (xy 360.022368 -167.61227) (xy 360.051836 -167.658115) (xy 360.074479 -167.707686)
			(xy 360.089837 -167.759976) (xy 360.097598 -167.813919) (xy 360.098086 -167.841168) (xy 360.097615 -167.869079)
			(xy 360.089472 -167.924305) (xy 360.073371 -167.977756) (xy 360.049654 -168.02829) (xy 360.018827 -168.07483)
			(xy 360.00055 -168.09593) (xy 359.994634 -168.103094) (xy 359.987996 -168.120429) (xy 359.987596 -168.129712)
			(xy 359.987596 -168.207436) (xy 359.9942 -168.224708) (xy 360.00055 -168.23182) (xy 360.01882 -168.252926)
			(xy 360.049647 -168.299464) (xy 360.073363 -168.349997) (xy 360.089461 -168.403446) (xy 360.097599 -168.458671)
			(xy 360.098086 -168.486582) (xy 360.0976 -168.513833) (xy 360.089844 -168.567781) (xy 360.074489 -168.620076)
			(xy 360.051847 -168.669653) (xy 360.022381 -168.715503) (xy 359.98669 -168.756694) (xy 359.945499 -168.792385)
			(xy 359.899649 -168.821851) (xy 359.850072 -168.844493) (xy 359.797777 -168.859848) (xy 359.743829 -168.867604)
			(xy 359.689327 -168.867604) (xy 359.635379 -168.859848) (xy 359.583084 -168.844493) (xy 359.533507 -168.821851)
			(xy 359.487657 -168.792385) (xy 359.446466 -168.756694) (xy 359.410775 -168.715503) (xy 359.381309 -168.669653)
			(xy 359.358667 -168.620076) (xy 359.343312 -168.567781) (xy 359.335556 -168.513833) (xy 359.33507 -168.486582)
			(xy 359.335557 -168.458671) (xy 359.343694 -168.403445) (xy 359.359791 -168.349994) (xy 359.383505 -168.29946)
			(xy 359.414329 -168.25292) (xy 359.432606 -168.23182) (xy 359.438495 -168.224637) (xy 359.445151 -168.207316)
			(xy 359.44556 -168.198038) (xy 359.44556 -168.120314) (xy 359.438956 -168.103042) (xy 359.432606 -168.09593)
			(xy 359.414322 -168.074836) (xy 359.383495 -168.028296) (xy 359.359781 -167.97776) (xy 359.343686 -167.924307)
			(xy 359.335554 -167.86908) (xy 359.33507 -167.841168) (xy 359.33507 -167.835326) (xy 359.334812 -167.825205)
			(xy 359.327354 -167.806402) (xy 359.313222 -167.791928) (xy 359.304082 -167.787574) (xy 359.217468 -167.750998)
			(xy 359.208052 -167.747416) (xy 359.18792 -167.747262) (xy 359.169282 -167.754872) (xy 359.161842 -167.761666)
			(xy 358.919018 -168.004236) (xy 358.912172 -168.011632) (xy 358.904455 -168.030234) (xy 358.904032 -168.040304)
			(xy 358.904032 -175.705516) (xy 360.22153 -175.705516) (xy 360.221996 -175.677941) (xy 360.229947 -175.623368)
			(xy 360.245671 -175.570508) (xy 360.268841 -175.520462) (xy 360.298974 -175.474272) (xy 360.335442 -175.432901)
			(xy 360.35615 -175.414686) (xy 360.36424 -175.407144) (xy 360.373584 -175.387122) (xy 360.374184 -175.376078)
			(xy 360.374184 -175.298354) (xy 360.373591 -175.287308) (xy 360.364244 -175.267286) (xy 360.35615 -175.259746)
			(xy 360.335448 -175.241525) (xy 360.298979 -175.200157) (xy 360.268847 -175.153969) (xy 360.24568 -175.103923)
			(xy 360.229961 -175.051063) (xy 360.222018 -174.99649) (xy 360.22153 -174.968916) (xy 360.221996 -174.941341)
			(xy 360.229947 -174.886768) (xy 360.245671 -174.833908) (xy 360.268841 -174.783862) (xy 360.298974 -174.737672)
			(xy 360.335442 -174.696301) (xy 360.35615 -174.678086) (xy 360.36424 -174.670544) (xy 360.373584 -174.650522)
			(xy 360.374184 -174.639478) (xy 360.374184 -174.561754) (xy 360.373591 -174.550708) (xy 360.364244 -174.530686)
			(xy 360.35615 -174.523146) (xy 360.335448 -174.504925) (xy 360.298979 -174.463557) (xy 360.268847 -174.417369)
			(xy 360.24568 -174.367323) (xy 360.229961 -174.314463) (xy 360.222018 -174.25989) (xy 360.22153 -174.232316)
			(xy 360.22197 -174.205062) (xy 360.229726 -174.151108) (xy 360.245082 -174.098807) (xy 360.267725 -174.049225)
			(xy 360.297195 -174.00337) (xy 360.332892 -173.962176) (xy 360.374087 -173.926482) (xy 360.419944 -173.897015)
			(xy 360.469528 -173.874374) (xy 360.52183 -173.859021) (xy 360.575784 -173.851269) (xy 360.603038 -173.850808)
			(xy 360.630895 -173.851291) (xy 360.686012 -173.85942) (xy 360.739364 -173.875471) (xy 360.789817 -173.899103)
			(xy 360.836302 -173.929815) (xy 360.877831 -173.966955) (xy 360.913523 -174.009735) (xy 360.942621 -174.057246)
			(xy 360.964507 -174.108481) (xy 360.9721 -174.135288) (xy 360.974386 -174.144178) (xy 360.985054 -174.159418)
			(xy 361.056936 -174.20717) (xy 361.07497 -174.211234) (xy 361.084114 -174.209964) (xy 361.097131 -174.208295)
			(xy 361.123315 -174.206515) (xy 361.136438 -174.206408) (xy 361.150587 -174.206497) (xy 361.17881 -174.208534)
			(xy 361.192826 -174.210472) (xy 361.202732 -174.211996) (xy 361.222544 -174.20717) (xy 361.296966 -174.15129)
			(xy 361.307126 -174.133764) (xy 361.308396 -174.123604) (xy 361.312431 -174.096442) (xy 361.327412 -174.04361)
			(xy 361.349811 -173.993471) (xy 361.379165 -173.947061) (xy 361.414869 -173.905337) (xy 361.456184 -173.869162)
			(xy 361.502258 -173.839283) (xy 361.552139 -173.816316) (xy 361.604797 -173.800736) (xy 361.659145 -173.792865)
			(xy 361.686602 -173.792388) (xy 361.713853 -173.792876) (xy 361.767801 -173.800633) (xy 361.820095 -173.815988)
			(xy 361.869672 -173.838629) (xy 361.915522 -173.868095) (xy 361.956712 -173.903786) (xy 361.992404 -173.944976)
			(xy 362.02187 -173.990826) (xy 362.044512 -174.040403) (xy 362.059867 -174.092697) (xy 362.067624 -174.146645)
			(xy 362.06811 -174.173896) (xy 362.067638 -174.20147) (xy 362.059686 -174.256043) (xy 362.043962 -174.308902)
			(xy 362.020793 -174.358948) (xy 361.990662 -174.405138) (xy 361.954196 -174.44651) (xy 361.93349 -174.464726)
			(xy 361.925401 -174.472269) (xy 361.916055 -174.49229) (xy 361.915456 -174.503334) (xy 361.915456 -174.581058)
			(xy 361.91603 -174.592107) (xy 361.925389 -174.612129) (xy 361.93349 -174.619666) (xy 361.954186 -174.637894)
			(xy 361.990658 -174.679259) (xy 362.020792 -174.725445) (xy 362.043961 -174.77549) (xy 362.05968 -174.82835)
			(xy 362.067623 -174.882922) (xy 362.06811 -174.910496) (xy 362.067641 -174.937749) (xy 362.059885 -174.991699)
			(xy 362.044529 -175.043997) (xy 362.021887 -175.093577) (xy 361.99242 -175.13943) (xy 361.956727 -175.180623)
			(xy 361.915535 -175.216316) (xy 361.869682 -175.245784) (xy 361.820103 -175.268427) (xy 361.767805 -175.283783)
			(xy 361.713855 -175.291541) (xy 361.686602 -175.292004) (xy 361.686094 -175.292004) (xy 361.652312 -175.29048)
			(xy 361.642152 -175.289464) (xy 361.622848 -175.29556) (xy 361.559856 -175.348392) (xy 361.552544 -175.355094)
			(xy 361.543276 -175.372614) (xy 361.541822 -175.382428) (xy 361.541822 -175.38319) (xy 361.538899 -175.411354)
			(xy 361.525686 -175.466415) (xy 361.504478 -175.518917) (xy 361.475741 -175.567707) (xy 361.440107 -175.611713)
			(xy 361.398359 -175.649966) (xy 361.351414 -175.681628) (xy 361.300304 -175.706001) (xy 361.246153 -175.722551)
			(xy 361.19015 -175.730913) (xy 361.161838 -175.731424) (xy 361.143819 -175.731207) (xy 361.107944 -175.72777)
			(xy 361.09021 -175.724566) (xy 361.080558 -175.722788) (xy 361.061508 -175.726344) (xy 360.986578 -175.77435)
			(xy 360.975148 -175.790098) (xy 360.972862 -175.799496) (xy 360.965518 -175.826556) (xy 360.94388 -175.878283)
			(xy 360.914908 -175.926288) (xy 360.879225 -175.969538) (xy 360.837599 -176.007104) (xy 360.790925 -176.038175)
			(xy 360.740208 -176.062085) (xy 360.686539 -176.078319) (xy 360.631073 -176.086527) (xy 360.603038 -176.087024)
			(xy 360.575787 -176.086509) (xy 360.521839 -176.078758) (xy 360.469543 -176.063408) (xy 360.419964 -176.040771)
			(xy 360.374111 -176.011308) (xy 360.332918 -175.97562) (xy 360.297224 -175.934432) (xy 360.267755 -175.888584)
			(xy 360.245111 -175.839008) (xy 360.229753 -175.786714) (xy 360.221994 -175.732767) (xy 360.22153 -175.705516)
			(xy 358.904032 -175.705516) (xy 358.904032 -177.254916) (xy 361.889548 -177.254916) (xy 361.890008 -177.227341)
			(xy 361.897959 -177.172767) (xy 361.913684 -177.119906) (xy 361.936855 -177.06986) (xy 361.96699 -177.023671)
			(xy 362.00346 -176.982301) (xy 362.024168 -176.964086) (xy 362.032261 -176.956547) (xy 362.041603 -176.936523)
			(xy 362.042202 -176.925478) (xy 362.042202 -176.847754) (xy 362.041603 -176.836709) (xy 362.032259 -176.816687)
			(xy 362.024168 -176.809146) (xy 362.003469 -176.790921) (xy 361.967 -176.749555) (xy 361.936867 -176.703367)
			(xy 361.913699 -176.653322) (xy 361.897979 -176.600462) (xy 361.890036 -176.54589) (xy 361.889548 -176.518316)
			(xy 361.889957 -176.491765) (xy 361.897325 -176.439176) (xy 361.911921 -176.388119) (xy 361.933462 -176.339582)
			(xy 361.961532 -176.294504) (xy 361.995586 -176.253759) (xy 362.034966 -176.218135) (xy 362.05668 -176.202848)
			(xy 362.064535 -176.196878) (xy 362.075381 -176.180419) (xy 362.077762 -176.170844) (xy 362.091732 -176.100994)
			(xy 362.09319 -176.091233) (xy 362.089408 -176.071885) (xy 362.084366 -176.063402) (xy 362.084366 -176.063148)
			(xy 362.070021 -176.040321) (xy 362.047356 -175.991406) (xy 362.031961 -175.939739) (xy 362.024158 -175.886395)
			(xy 362.02366 -175.85944) (xy 362.02366 -175.859186) (xy 362.024144 -175.83257) (xy 362.031721 -175.779881)
			(xy 362.046719 -175.728807) (xy 362.068832 -175.680386) (xy 362.097611 -175.635605) (xy 362.13247 -175.595376)
			(xy 362.172699 -175.560516) (xy 362.217479 -175.531736) (xy 362.265899 -175.509621) (xy 362.316973 -175.494622)
			(xy 362.369662 -175.487044) (xy 362.396278 -175.486568) (xy 362.422699 -175.487046) (xy 362.475013 -175.494492)
			(xy 362.525751 -175.509253) (xy 362.573896 -175.531032) (xy 362.618482 -175.559393) (xy 362.638848 -175.57623)
			(xy 362.645706 -175.582072) (xy 362.662724 -175.588422) (xy 362.747052 -175.588422) (xy 362.76407 -175.582072)
			(xy 362.770928 -175.57623) (xy 362.791294 -175.559391) (xy 362.83588 -175.531026) (xy 362.884024 -175.509239)
			(xy 362.934761 -175.494468) (xy 362.987076 -175.487008) (xy 363.03992 -175.487008) (xy 363.092235 -175.494468)
			(xy 363.142972 -175.509239) (xy 363.191116 -175.531026) (xy 363.235702 -175.559391) (xy 363.256068 -175.57623)
			(xy 363.262926 -175.582072) (xy 363.279944 -175.588422) (xy 363.364272 -175.588422) (xy 363.38129 -175.582072)
			(xy 363.388148 -175.57623) (xy 363.408499 -175.559374) (xy 363.453093 -175.531021) (xy 363.501241 -175.509244)
			(xy 363.551981 -175.494481) (xy 363.604296 -175.487026) (xy 363.630718 -175.486568) (xy 363.658601 -175.487118)
			(xy 363.713744 -175.495432) (xy 363.767031 -175.511871) (xy 363.817274 -175.536069) (xy 363.863349 -175.567484)
			(xy 363.904227 -175.605416) (xy 363.938995 -175.649016) (xy 363.966878 -175.697311) (xy 363.987251 -175.749222)
			(xy 363.999659 -175.80359) (xy 364.003827 -175.8592) (xy 363.999659 -175.91481) (xy 363.987251 -175.969178)
			(xy 363.966878 -176.021089) (xy 363.938995 -176.069384) (xy 363.904227 -176.112984) (xy 363.863349 -176.150916)
			(xy 363.817274 -176.182331) (xy 363.767031 -176.206529) (xy 363.713744 -176.222968) (xy 363.658601 -176.231282)
			(xy 363.630718 -176.231804) (xy 363.604297 -176.231335) (xy 363.551982 -176.223888) (xy 363.501243 -176.209125)
			(xy 363.453099 -176.187344) (xy 363.408514 -176.158981) (xy 363.388148 -176.142142) (xy 363.38129 -176.1363)
			(xy 363.364272 -176.12995) (xy 363.279944 -176.12995) (xy 363.262926 -176.1363) (xy 363.256068 -176.142142)
			(xy 363.235702 -176.158981) (xy 363.191116 -176.187346) (xy 363.142972 -176.209133) (xy 363.092235 -176.223904)
			(xy 363.03992 -176.231364) (xy 362.987076 -176.231364) (xy 362.934761 -176.223904) (xy 362.884024 -176.209133)
			(xy 362.83588 -176.187346) (xy 362.791294 -176.158981) (xy 362.770928 -176.142142) (xy 362.76407 -176.1363)
			(xy 362.747052 -176.12995) (xy 362.662724 -176.12995) (xy 362.645706 -176.1363) (xy 362.638848 -176.142142)
			(xy 362.61167 -176.163224) (xy 362.611416 -176.163478) (xy 362.60372 -176.169574) (xy 362.593256 -176.18616)
			(xy 362.591096 -176.195736) (xy 362.576364 -176.276) (xy 362.580682 -176.295304) (xy 362.58627 -176.303432)
			(xy 362.601926 -176.327311) (xy 362.626709 -176.378749) (xy 362.643545 -176.433308) (xy 362.652057 -176.489767)
			(xy 362.652564 -176.518316) (xy 362.652053 -176.545889) (xy 362.644112 -176.60046) (xy 362.628396 -176.65332)
			(xy 362.605235 -176.703366) (xy 362.57511 -176.749557) (xy 362.538648 -176.79093) (xy 362.517944 -176.809146)
			(xy 362.509839 -176.816674) (xy 362.500504 -176.836706) (xy 362.49991 -176.847754) (xy 362.49991 -176.925478)
			(xy 362.500487 -176.936526) (xy 362.509846 -176.956547) (xy 362.517944 -176.964086) (xy 362.53866 -176.982291)
			(xy 362.575128 -177.023662) (xy 362.605259 -177.069854) (xy 362.628423 -177.119903) (xy 362.644139 -177.172766)
			(xy 362.652079 -177.227341) (xy 362.652564 -177.254916) (xy 362.652078 -177.282167) (xy 362.644322 -177.336115)
			(xy 362.628967 -177.38841) (xy 362.606325 -177.437987) (xy 362.576859 -177.483837) (xy 362.541168 -177.525028)
			(xy 362.499977 -177.560719) (xy 362.454127 -177.590185) (xy 362.40455 -177.612827) (xy 362.352255 -177.628182)
			(xy 362.298307 -177.635938) (xy 362.243805 -177.635938) (xy 362.189857 -177.628182) (xy 362.137562 -177.612827)
			(xy 362.087985 -177.590185) (xy 362.042135 -177.560719) (xy 362.000944 -177.525028) (xy 361.965253 -177.483837)
			(xy 361.935787 -177.437987) (xy 361.913145 -177.38841) (xy 361.89779 -177.336115) (xy 361.890034 -177.282167)
			(xy 361.889548 -177.254916) (xy 358.904032 -177.254916) (xy 358.904032 -180.807868) (xy 358.903566 -180.832818)
			(xy 358.895744 -180.882102) (xy 358.88032 -180.92956) (xy 358.857672 -180.974025) (xy 358.828355 -181.014407)
			(xy 358.811068 -181.032404) (xy 358.30256 -181.540912) (xy 358.29785 -181.545873) (xy 358.291018 -181.557715)
			(xy 358.289098 -181.56428) (xy 358.289098 -181.565042) (xy 358.281464 -181.594242) (xy 358.258256 -181.649952)
			(xy 358.226566 -181.701314) (xy 358.20731 -181.724554) (xy 358.201671 -181.73176) (xy 358.195413 -181.748938)
			(xy 358.195118 -181.758082) (xy 358.195372 -181.824884) (xy 358.195871 -181.833939) (xy 358.202368 -181.850855)
			(xy 358.208072 -181.857904) (xy 358.208326 -181.858158) (xy 358.226238 -181.879168) (xy 358.256429 -181.92539)
			(xy 358.279641 -181.975482) (xy 358.295389 -182.028397) (xy 358.303344 -182.08303) (xy 358.30383 -182.110634)
			(xy 358.303401 -182.138006) (xy 358.295577 -182.192187) (xy 358.28008 -182.244691) (xy 358.25723 -182.294438)
			(xy 358.227496 -182.340402) (xy 358.20985 -182.361332) (xy 358.209596 -182.361586) (xy 358.204009 -182.368672)
			(xy 358.197763 -182.385589) (xy 358.197404 -182.394606) (xy 358.197404 -182.461662) (xy 358.197779 -182.470677)
			(xy 358.204014 -182.487594) (xy 358.209596 -182.494682) (xy 358.20985 -182.494682) (xy 358.20985 -182.494936)
			(xy 358.227525 -182.515841) (xy 358.25725 -182.561813) (xy 358.280095 -182.611564) (xy 358.29559 -182.66407)
			(xy 358.303415 -182.718253) (xy 358.303412 -182.772998) (xy 358.295579 -182.82718) (xy 358.280077 -182.879684)
			(xy 358.257225 -182.929432) (xy 358.227494 -182.9754) (xy 358.20985 -182.996332) (xy 358.209596 -182.996586)
			(xy 358.204009 -183.003672) (xy 358.197763 -183.020589) (xy 358.197404 -183.029606) (xy 358.197404 -183.096662)
			(xy 358.197779 -183.105677) (xy 358.204014 -183.122594) (xy 358.209596 -183.129682) (xy 358.20985 -183.129682)
			(xy 358.20985 -183.129936) (xy 358.227525 -183.150841) (xy 358.25725 -183.196813) (xy 358.280095 -183.246564)
			(xy 358.29559 -183.29907) (xy 358.303415 -183.353253) (xy 358.303412 -183.407998) (xy 358.295579 -183.46218)
			(xy 358.280077 -183.514684) (xy 358.257225 -183.564432) (xy 358.227494 -183.6104) (xy 358.20985 -183.631332)
			(xy 358.209596 -183.631586) (xy 358.204009 -183.638672) (xy 358.197763 -183.655589) (xy 358.197404 -183.664606)
			(xy 358.197404 -183.731662) (xy 358.197779 -183.740677) (xy 358.204014 -183.757594) (xy 358.209596 -183.764682)
			(xy 358.20985 -183.764682) (xy 358.20985 -183.764936) (xy 358.227465 -183.785888) (xy 358.257182 -183.831854)
			(xy 358.280023 -183.881597) (xy 358.29552 -183.934093) (xy 358.303353 -183.988266) (xy 358.30383 -184.015634)
			(xy 358.303325 -184.043343) (xy 358.295298 -184.098177) (xy 358.279418 -184.151271) (xy 358.25602 -184.201507)
			(xy 358.225597 -184.247828) (xy 358.207564 -184.268872) (xy 358.207564 -184.269126) (xy 358.201701 -184.27638)
			(xy 358.195184 -184.29384) (xy 358.194864 -184.303162) (xy 358.195372 -184.371488) (xy 358.195926 -184.380747)
			(xy 358.202833 -184.397943) (xy 358.208834 -184.405016) (xy 358.208834 -184.40527) (xy 358.227749 -184.426502)
			(xy 358.259679 -184.473552) (xy 358.284265 -184.524824) (xy 358.300964 -184.579179) (xy 358.309403 -184.635411)
			(xy 358.309926 -184.663842) (xy 358.309444 -184.691212) (xy 358.301633 -184.745391) (xy 358.286148 -184.797895)
			(xy 358.26331 -184.847642) (xy 358.233587 -184.893609) (xy 358.215946 -184.91454) (xy 358.215692 -184.914794)
			(xy 358.210101 -184.921877) (xy 358.203857 -184.938797) (xy 358.2035 -184.947814) (xy 358.2035 -185.01487)
			(xy 358.203871 -185.023885) (xy 358.210109 -185.040803) (xy 358.215692 -185.04789) (xy 358.215946 -185.04789)
			(xy 358.215946 -185.048144) (xy 358.233629 -185.069043) (xy 358.263354 -185.115016) (xy 358.286199 -185.164768)
			(xy 358.301693 -185.217275) (xy 358.309518 -185.271459) (xy 358.309514 -185.326205) (xy 358.301679 -185.380387)
			(xy 358.286176 -185.432892) (xy 358.263324 -185.48264) (xy 358.233591 -185.528608) (xy 358.215946 -185.54954)
			(xy 358.215692 -185.549794) (xy 358.210101 -185.556877) (xy 358.203857 -185.573797) (xy 358.2035 -185.582814)
			(xy 358.2035 -185.64987) (xy 358.203871 -185.658885) (xy 358.210109 -185.675803) (xy 358.215692 -185.68289)
			(xy 358.215946 -185.68289) (xy 358.215946 -185.683144) (xy 358.233629 -185.704043) (xy 358.263354 -185.750016)
			(xy 358.286199 -185.799768) (xy 358.301693 -185.852275) (xy 358.309518 -185.906459) (xy 358.309514 -185.961205)
			(xy 358.301679 -186.015387) (xy 358.286176 -186.067892) (xy 358.263324 -186.11764) (xy 358.233591 -186.163608)
			(xy 358.215946 -186.18454) (xy 358.215692 -186.184794) (xy 358.210101 -186.191877) (xy 358.203857 -186.208797)
			(xy 358.2035 -186.217814) (xy 358.2035 -186.28487) (xy 358.203871 -186.293885) (xy 358.210109 -186.310803)
			(xy 358.215692 -186.31789) (xy 358.215946 -186.31789) (xy 358.215946 -186.318144) (xy 358.233629 -186.339043)
			(xy 358.263354 -186.385016) (xy 358.286199 -186.434768) (xy 358.301693 -186.487275) (xy 358.309518 -186.541459)
			(xy 358.309514 -186.596205) (xy 358.301679 -186.650387) (xy 358.286176 -186.702892) (xy 358.263324 -186.75264)
			(xy 358.233591 -186.798608) (xy 358.215946 -186.81954) (xy 358.215692 -186.819794) (xy 358.210101 -186.826877)
			(xy 358.203857 -186.843797) (xy 358.2035 -186.852814) (xy 358.2035 -186.91987) (xy 358.203871 -186.928885)
			(xy 358.210109 -186.945803) (xy 358.215692 -186.95289) (xy 358.215946 -186.95289) (xy 358.215946 -186.953144)
			(xy 358.233629 -186.974043) (xy 358.263354 -187.020016) (xy 358.286199 -187.069768) (xy 358.301693 -187.122275)
			(xy 358.309518 -187.176459) (xy 358.309514 -187.231205) (xy 358.301679 -187.285387) (xy 358.286176 -187.337892)
			(xy 358.263324 -187.38764) (xy 358.233591 -187.433608) (xy 358.215946 -187.45454) (xy 358.215692 -187.454794)
			(xy 358.210101 -187.461877) (xy 358.203857 -187.478797) (xy 358.2035 -187.487814) (xy 358.2035 -187.55487)
			(xy 358.203871 -187.563885) (xy 358.210109 -187.580803) (xy 358.215692 -187.58789) (xy 358.215946 -187.58789)
			(xy 358.215946 -187.588144) (xy 358.233564 -187.609093) (xy 358.263281 -187.655061) (xy 358.286122 -187.704804)
			(xy 358.301618 -187.757301) (xy 358.30945 -187.811474) (xy 358.309926 -187.838842) (xy 358.309461 -187.866093)
			(xy 358.3017 -187.920041) (xy 358.28634 -187.972335) (xy 358.263695 -188.021911) (xy 358.234226 -188.067761)
			(xy 358.198533 -188.10895) (xy 358.157341 -188.144641) (xy 358.11149 -188.174107) (xy 358.061913 -188.196748)
			(xy 358.009618 -188.212105) (xy 357.955669 -188.219863) (xy 357.928418 -188.22035) (xy 357.901048 -188.219886)
			(xy 357.846868 -188.212069) (xy 357.794364 -188.19658) (xy 357.744617 -188.173738) (xy 357.698651 -188.144012)
			(xy 357.67772 -188.12637) (xy 357.677466 -188.126116) (xy 357.670363 -188.120553) (xy 357.653459 -188.114292)
			(xy 357.644446 -188.113924) (xy 357.57739 -188.113924) (xy 357.568372 -188.114271) (xy 357.551455 -188.120525)
			(xy 357.54437 -188.126116) (xy 357.54437 -188.12637) (xy 357.544116 -188.12637) (xy 357.523185 -188.14401)
			(xy 357.477212 -188.173723) (xy 357.427465 -188.196559) (xy 357.374964 -188.21205) (xy 357.320787 -188.219877)
			(xy 357.293418 -188.22035) (xy 357.266169 -188.219805) (xy 357.212226 -188.212052) (xy 357.159935 -188.196701)
			(xy 357.11036 -188.174065) (xy 357.064512 -188.144605) (xy 357.023323 -188.10892) (xy 356.987631 -188.067736)
			(xy 356.958163 -188.021892) (xy 356.93552 -187.972322) (xy 356.920161 -187.920033) (xy 356.912399 -187.866091)
			(xy 356.91191 -187.838842) (xy 356.912398 -187.811473) (xy 356.92021 -187.757294) (xy 356.935694 -187.704791)
			(xy 356.958531 -187.655044) (xy 356.988251 -187.609076) (xy 357.00589 -187.588144) (xy 357.006144 -187.58789)
			(xy 357.011746 -187.580814) (xy 357.017982 -187.563889) (xy 357.018336 -187.55487) (xy 357.018336 -187.487814)
			(xy 357.017964 -187.478799) (xy 357.011726 -187.461882) (xy 357.006144 -187.454794) (xy 357.00589 -187.454794)
			(xy 357.00589 -187.45454) (xy 356.988292 -187.433573) (xy 356.958568 -187.38761) (xy 356.935723 -187.33787)
			(xy 356.920225 -187.285373) (xy 356.912393 -187.2312) (xy 356.912389 -187.176463) (xy 356.920211 -187.122289)
			(xy 356.935701 -187.06979) (xy 356.958538 -187.020045) (xy 356.988254 -186.974077) (xy 357.00589 -186.953144)
			(xy 357.006144 -186.95289) (xy 357.011746 -186.945814) (xy 357.017982 -186.928889) (xy 357.018336 -186.91987)
			(xy 357.018336 -186.852814) (xy 357.017964 -186.843799) (xy 357.011726 -186.826882) (xy 357.006144 -186.819794)
			(xy 357.00589 -186.819794) (xy 357.00589 -186.81954) (xy 356.988292 -186.798573) (xy 356.958568 -186.75261)
			(xy 356.935723 -186.70287) (xy 356.920225 -186.650373) (xy 356.912393 -186.5962) (xy 356.912389 -186.541463)
			(xy 356.920211 -186.487289) (xy 356.935701 -186.43479) (xy 356.958538 -186.385045) (xy 356.988254 -186.339077)
			(xy 357.00589 -186.318144) (xy 357.006144 -186.31789) (xy 357.011746 -186.310814) (xy 357.017982 -186.293889)
			(xy 357.018336 -186.28487) (xy 357.018336 -186.217814) (xy 357.017964 -186.208799) (xy 357.011726 -186.191882)
			(xy 357.006144 -186.184794) (xy 357.00589 -186.184794) (xy 357.00589 -186.18454) (xy 356.988292 -186.163573)
			(xy 356.958568 -186.11761) (xy 356.935723 -186.06787) (xy 356.920225 -186.015373) (xy 356.912393 -185.9612)
			(xy 356.912389 -185.906463) (xy 356.920211 -185.852289) (xy 356.935701 -185.79979) (xy 356.958538 -185.750045)
			(xy 356.988254 -185.704077) (xy 357.00589 -185.683144) (xy 357.006144 -185.68289) (xy 357.011746 -185.675814)
			(xy 357.017982 -185.658889) (xy 357.018336 -185.64987) (xy 357.018336 -185.582814) (xy 357.017964 -185.573799)
			(xy 357.011726 -185.556882) (xy 357.006144 -185.549794) (xy 357.00589 -185.549794) (xy 357.00589 -185.54954)
			(xy 356.988292 -185.528573) (xy 356.958568 -185.48261) (xy 356.935723 -185.43287) (xy 356.920225 -185.380373)
			(xy 356.912393 -185.3262) (xy 356.912389 -185.271463) (xy 356.920211 -185.217289) (xy 356.935701 -185.16479)
			(xy 356.958538 -185.115045) (xy 356.988254 -185.069077) (xy 357.00589 -185.048144) (xy 357.006144 -185.04789)
			(xy 357.011746 -185.040814) (xy 357.017982 -185.023889) (xy 357.018336 -185.01487) (xy 357.018336 -184.947814)
			(xy 357.017964 -184.938799) (xy 357.011726 -184.921882) (xy 357.006144 -184.914794) (xy 357.00589 -184.914794)
			(xy 357.00589 -184.91454) (xy 356.988255 -184.893605) (xy 356.958543 -184.847633) (xy 356.935706 -184.797886)
			(xy 356.920214 -184.745386) (xy 356.912385 -184.691211) (xy 356.91191 -184.663842) (xy 356.912391 -184.636132)
			(xy 356.920422 -184.581297) (xy 356.936307 -184.528202) (xy 356.959711 -184.477966) (xy 356.99014 -184.431647)
			(xy 357.008176 -184.410604) (xy 357.008176 -184.41035) (xy 357.014043 -184.403097) (xy 357.020559 -184.385637)
			(xy 357.020876 -184.376314) (xy 357.020368 -184.307988) (xy 357.019816 -184.298729) (xy 357.012906 -184.281533)
			(xy 357.006906 -184.27446) (xy 357.006906 -184.274206) (xy 356.988033 -184.252938) (xy 356.956096 -184.205898)
			(xy 356.931501 -184.154636) (xy 356.914793 -184.100289) (xy 356.906342 -184.044063) (xy 356.905814 -184.015634)
			(xy 356.906297 -183.988264) (xy 356.91411 -183.934086) (xy 356.929595 -183.881583) (xy 356.952433 -183.831836)
			(xy 356.982154 -183.785868) (xy 356.999794 -183.764936) (xy 357.000048 -183.764682) (xy 357.005654 -183.757609)
			(xy 357.011888 -183.740682) (xy 357.01224 -183.731662) (xy 357.01224 -183.664606) (xy 357.011893 -183.655588)
			(xy 357.00564 -183.63867) (xy 357.000048 -183.631586) (xy 356.999794 -183.631586) (xy 356.999794 -183.631332)
			(xy 356.982188 -183.610372) (xy 356.952464 -183.564408) (xy 356.929619 -183.514666) (xy 356.914122 -183.462168)
			(xy 356.90629 -183.407994) (xy 356.906287 -183.353257) (xy 356.914111 -183.299082) (xy 356.929601 -183.246582)
			(xy 356.95244 -183.196837) (xy 356.982157 -183.150869) (xy 356.999794 -183.129936) (xy 357.000048 -183.129682)
			(xy 357.005654 -183.122609) (xy 357.011888 -183.105682) (xy 357.01224 -183.096662) (xy 357.01224 -183.029606)
			(xy 357.011893 -183.020588) (xy 357.00564 -183.00367) (xy 357.000048 -182.996586) (xy 356.999794 -182.996586)
			(xy 356.999794 -182.996332) (xy 356.982188 -182.975372) (xy 356.952464 -182.929408) (xy 356.929619 -182.879666)
			(xy 356.914122 -182.827168) (xy 356.90629 -182.772994) (xy 356.906287 -182.718257) (xy 356.914111 -182.664082)
			(xy 356.929601 -182.611582) (xy 356.95244 -182.561837) (xy 356.982157 -182.515869) (xy 356.999794 -182.494936)
			(xy 357.000048 -182.494682) (xy 357.005654 -182.487609) (xy 357.011888 -182.470682) (xy 357.01224 -182.461662)
			(xy 357.01224 -182.394606) (xy 357.011893 -182.385588) (xy 357.00564 -182.36867) (xy 357.000048 -182.361586)
			(xy 356.999794 -182.361586) (xy 356.999794 -182.361332) (xy 356.982156 -182.340399) (xy 356.952444 -182.294427)
			(xy 356.929608 -182.244679) (xy 356.914117 -182.192179) (xy 356.906288 -182.138003) (xy 356.905814 -182.110634)
			(xy 356.906282 -182.0835) (xy 356.913973 -182.029779) (xy 356.929206 -181.977693) (xy 356.951672 -181.928293)
			(xy 356.980916 -181.882579) (xy 356.99827 -181.861714) (xy 357.00392 -181.854516) (xy 357.010171 -181.837332)
			(xy 357.010462 -181.828186) (xy 357.010208 -181.761384) (xy 357.009706 -181.75233) (xy 357.003209 -181.735414)
			(xy 356.997508 -181.728364) (xy 356.997254 -181.72811) (xy 356.979371 -181.707077) (xy 356.949176 -181.660861)
			(xy 356.925959 -181.610775) (xy 356.910204 -181.557865) (xy 356.902241 -181.503237) (xy 356.90175 -181.475634)
			(xy 354.919026 -181.475634) (xy 354.918591 -181.502605) (xy 354.910979 -181.556007) (xy 354.895912 -181.607803)
			(xy 354.873691 -181.656955) (xy 354.844761 -181.702483) (xy 354.827586 -181.723284) (xy 354.822044 -181.730454)
			(xy 354.815927 -181.7475) (xy 354.815648 -181.756558) (xy 354.81641 -181.833012) (xy 354.82276 -181.849776)
			(xy 354.82911 -181.856888) (xy 354.847212 -181.877951) (xy 354.877716 -181.924363) (xy 354.901174 -181.974703)
			(xy 354.917092 -182.027912) (xy 354.925133 -182.082865) (xy 354.92563 -182.110634) (xy 354.925201 -182.138006)
			(xy 354.917377 -182.192187) (xy 354.90188 -182.244691) (xy 354.87903 -182.294438) (xy 354.849296 -182.340402)
			(xy 354.83165 -182.361332) (xy 354.831396 -182.361586) (xy 354.825809 -182.368672) (xy 354.819563 -182.385589)
			(xy 354.819204 -182.394606) (xy 354.819204 -182.461662) (xy 354.819579 -182.470677) (xy 354.825814 -182.487594)
			(xy 354.831396 -182.494682) (xy 354.83165 -182.494682) (xy 354.83165 -182.494936) (xy 354.849325 -182.515841)
			(xy 354.87905 -182.561813) (xy 354.901895 -182.611564) (xy 354.91739 -182.66407) (xy 354.925215 -182.718253)
			(xy 354.925212 -182.772998) (xy 354.917379 -182.82718) (xy 354.901877 -182.879684) (xy 354.879025 -182.929432)
			(xy 354.849294 -182.9754) (xy 354.83165 -182.996332) (xy 354.831396 -182.996586) (xy 354.825809 -183.003672)
			(xy 354.819563 -183.020589) (xy 354.819204 -183.029606) (xy 354.819204 -183.096662) (xy 354.819579 -183.105677)
			(xy 354.825814 -183.122594) (xy 354.831396 -183.129682) (xy 354.83165 -183.129682) (xy 354.83165 -183.129936)
			(xy 354.849325 -183.150841) (xy 354.87905 -183.196813) (xy 354.901895 -183.246564) (xy 354.91739 -183.29907)
			(xy 354.925215 -183.353253) (xy 354.925212 -183.407998) (xy 354.917379 -183.46218) (xy 354.901877 -183.514684)
			(xy 354.879025 -183.564432) (xy 354.849294 -183.6104) (xy 354.83165 -183.631332) (xy 354.831396 -183.631586)
			(xy 354.825809 -183.638672) (xy 354.819563 -183.655589) (xy 354.819204 -183.664606) (xy 354.819204 -183.731662)
			(xy 354.819579 -183.740677) (xy 354.825814 -183.757594) (xy 354.831396 -183.764682) (xy 354.83165 -183.764682)
			(xy 354.83165 -183.764936) (xy 354.849265 -183.785888) (xy 354.878982 -183.831854) (xy 354.901823 -183.881597)
			(xy 354.91732 -183.934093) (xy 354.925153 -183.988266) (xy 354.92563 -184.015634) (xy 354.925125 -184.043343)
			(xy 354.917098 -184.098177) (xy 354.901218 -184.151271) (xy 354.87782 -184.201507) (xy 354.847397 -184.247828)
			(xy 354.829364 -184.268872) (xy 354.829364 -184.269126) (xy 354.823501 -184.27638) (xy 354.816984 -184.29384)
			(xy 354.816664 -184.303162) (xy 354.817172 -184.371488) (xy 354.817726 -184.380747) (xy 354.824633 -184.397943)
			(xy 354.830634 -184.405016) (xy 354.830634 -184.40527) (xy 354.849549 -184.426502) (xy 354.881479 -184.473552)
			(xy 354.906065 -184.524824) (xy 354.922764 -184.579179) (xy 354.931203 -184.635411) (xy 354.931726 -184.663842)
			(xy 354.931244 -184.691212) (xy 354.923433 -184.745391) (xy 354.907948 -184.797895) (xy 354.88511 -184.847642)
			(xy 354.855387 -184.893609) (xy 354.837746 -184.91454) (xy 354.837492 -184.914794) (xy 354.831901 -184.921877)
			(xy 354.825657 -184.938797) (xy 354.8253 -184.947814) (xy 354.8253 -185.01487) (xy 354.825671 -185.023885)
			(xy 354.831909 -185.040803) (xy 354.837492 -185.04789) (xy 354.837746 -185.04789) (xy 354.837746 -185.048144)
			(xy 354.855429 -185.069043) (xy 354.885154 -185.115016) (xy 354.907999 -185.164768) (xy 354.923493 -185.217275)
			(xy 354.931318 -185.271459) (xy 354.931314 -185.326205) (xy 354.923479 -185.380387) (xy 354.907976 -185.432892)
			(xy 354.885124 -185.48264) (xy 354.855391 -185.528608) (xy 354.837746 -185.54954) (xy 354.837492 -185.549794)
			(xy 354.831901 -185.556877) (xy 354.825657 -185.573797) (xy 354.8253 -185.582814) (xy 354.8253 -185.64987)
			(xy 354.825671 -185.658885) (xy 354.831909 -185.675803) (xy 354.837492 -185.68289) (xy 354.837746 -185.68289)
			(xy 354.837746 -185.683144) (xy 354.855364 -185.704093) (xy 354.885081 -185.750061) (xy 354.907922 -185.799804)
			(xy 354.923418 -185.852301) (xy 354.93125 -185.906474) (xy 354.931726 -185.933842) (xy 354.93124 -185.961093)
			(xy 354.923484 -186.015041) (xy 354.908129 -186.067336) (xy 354.885487 -186.116913) (xy 354.856021 -186.162763)
			(xy 354.82033 -186.203954) (xy 354.779139 -186.239645) (xy 354.733289 -186.269111) (xy 354.683712 -186.291753)
			(xy 354.631417 -186.307108) (xy 354.577469 -186.314864) (xy 354.522967 -186.314864) (xy 354.469019 -186.307108)
			(xy 354.416724 -186.291753) (xy 354.367147 -186.269111) (xy 354.321297 -186.239645) (xy 354.280106 -186.203954)
			(xy 354.244415 -186.162763) (xy 354.214949 -186.116913) (xy 354.192307 -186.067336) (xy 354.176952 -186.015041)
			(xy 354.169196 -185.961093) (xy 354.16871 -185.933842) (xy 354.169273 -185.904365) (xy 354.178336 -185.846113)
			(xy 354.196253 -185.789948) (xy 354.222597 -185.737209) (xy 354.256742 -185.68915) (xy 354.276914 -185.66765)
			(xy 354.283422 -185.660295) (xy 354.290882 -185.64215) (xy 354.291392 -185.632344) (xy 354.291392 -185.579004)
			(xy 354.284026 -185.572146) (xy 354.276683 -185.565622) (xy 354.258529 -185.558172) (xy 354.24872 -185.557668)
			(xy 354.216716 -185.557668) (xy 354.206899 -185.558128) (xy 354.188735 -185.565592) (xy 354.18141 -185.572146)
			(xy 354.159905 -185.592314) (xy 354.111847 -185.62646) (xy 354.059109 -185.652807) (xy 354.002946 -185.67073)
			(xy 353.944695 -185.6798) (xy 353.915218 -185.68035) (xy 353.887969 -185.679805) (xy 353.834026 -185.672052)
			(xy 353.781735 -185.656701) (xy 353.73216 -185.634065) (xy 353.686312 -185.604605) (xy 353.645123 -185.56892)
			(xy 353.609431 -185.527736) (xy 353.579963 -185.481892) (xy 353.55732 -185.432322) (xy 353.541961 -185.380033)
			(xy 353.534199 -185.326091) (xy 353.53371 -185.298842) (xy 353.534273 -185.269365) (xy 353.543336 -185.211113)
			(xy 353.561253 -185.154948) (xy 353.587597 -185.102209) (xy 353.621742 -185.05415) (xy 353.641914 -185.03265)
			(xy 353.648422 -185.025295) (xy 353.655882 -185.00715) (xy 353.656392 -184.997344) (xy 353.656392 -184.944004)
			(xy 353.650804 -184.93867) (xy 353.643363 -184.932239) (xy 353.625073 -184.925056) (xy 353.615244 -184.9247)
			(xy 353.582986 -184.924954) (xy 353.573059 -184.925507) (xy 353.554757 -184.933223) (xy 353.547426 -184.93994)
			(xy 353.525806 -184.960943) (xy 353.477204 -184.996588) (xy 353.423595 -185.024132) (xy 353.366316 -185.04289)
			(xy 353.306798 -185.052392) (xy 353.276662 -185.05297) (xy 353.249408 -185.052557) (xy 353.195456 -185.044795)
			(xy 353.143157 -185.029433) (xy 353.093577 -185.006785) (xy 353.047725 -184.977311) (xy 353.006535 -184.941612)
			(xy 352.970844 -184.900414) (xy 352.941379 -184.854556) (xy 352.918741 -184.804971) (xy 352.903389 -184.75267)
			(xy 352.895637 -184.698716) (xy 352.895154 -184.671462) (xy 352.895604 -184.644797) (xy 352.903045 -184.591989)
			(xy 352.917765 -184.54073) (xy 352.939475 -184.492019) (xy 352.967754 -184.446803) (xy 352.984562 -184.426098)
			(xy 352.984816 -184.425844) (xy 352.990308 -184.418663) (xy 352.996278 -184.401609) (xy 352.9965 -184.39257)
			(xy 352.99523 -184.325768) (xy 352.994704 -184.316595) (xy 352.987927 -184.299533) (xy 352.982022 -184.292494)
			(xy 352.963583 -184.271317) (xy 352.93244 -184.224596) (xy 352.908474 -184.173819) (xy 352.892201 -184.120079)
			(xy 352.883971 -184.064537) (xy 352.88347 -184.036462) (xy 340.667235 -184.036462) (xy 352.823954 -192.311782)
			(xy 361.16387 -192.311782) (xy 361.164308 -192.284411) (xy 361.17213 -192.23023) (xy 361.187625 -192.177726)
			(xy 361.210473 -192.127979) (xy 361.240205 -192.082014) (xy 361.25785 -192.061084) (xy 361.258104 -192.06083)
			(xy 361.263685 -192.053739) (xy 361.269935 -192.036826) (xy 361.270296 -192.02781) (xy 361.270296 -191.960754)
			(xy 361.269914 -191.95174) (xy 361.263684 -191.934823) (xy 361.258104 -191.927734) (xy 361.25785 -191.927734)
			(xy 361.25785 -191.92748) (xy 361.240191 -191.906562) (xy 361.210465 -191.860592) (xy 361.187619 -191.810844)
			(xy 361.172123 -191.758339) (xy 361.164296 -191.704158) (xy 361.164298 -191.649415) (xy 361.172129 -191.595234)
			(xy 361.187629 -191.542731) (xy 361.210478 -191.492984) (xy 361.240207 -191.447016) (xy 361.25785 -191.426084)
			(xy 361.258104 -191.42583) (xy 361.263685 -191.418739) (xy 361.269935 -191.401826) (xy 361.270296 -191.39281)
			(xy 361.270296 -191.325754) (xy 361.269914 -191.31674) (xy 361.263684 -191.299823) (xy 361.258104 -191.292734)
			(xy 361.25785 -191.292734) (xy 361.25785 -191.29248) (xy 361.240191 -191.271562) (xy 361.210465 -191.225592)
			(xy 361.187619 -191.175844) (xy 361.172123 -191.123339) (xy 361.164296 -191.069158) (xy 361.164298 -191.014415)
			(xy 361.172129 -190.960234) (xy 361.187629 -190.907731) (xy 361.210478 -190.857984) (xy 361.240207 -190.812016)
			(xy 361.25785 -190.791084) (xy 361.258104 -190.79083) (xy 361.263685 -190.783739) (xy 361.269935 -190.766826)
			(xy 361.270296 -190.75781) (xy 361.270296 -190.690754) (xy 361.269914 -190.68174) (xy 361.263684 -190.664823)
			(xy 361.258104 -190.657734) (xy 361.25785 -190.657734) (xy 361.25785 -190.65748) (xy 361.240243 -190.636522)
			(xy 361.210524 -190.590557) (xy 361.187682 -190.540816) (xy 361.172183 -190.488321) (xy 361.164348 -190.43415)
			(xy 361.16387 -190.406782) (xy 361.164354 -190.378148) (xy 361.172906 -190.321521) (xy 361.189828 -190.26681)
			(xy 361.214741 -190.215244) (xy 361.247085 -190.167983) (xy 361.266232 -190.146686) (xy 361.272836 -190.139574)
			(xy 361.279694 -190.122048) (xy 361.280202 -190.043308) (xy 361.279816 -190.033781) (xy 361.272916 -190.016026)
			(xy 361.26674 -190.008764) (xy 361.247972 -189.987544) (xy 361.216273 -189.940595) (xy 361.19187 -189.889473)
			(xy 361.175299 -189.835304) (xy 361.166924 -189.779278) (xy 361.16641 -189.750954) (xy 361.166835 -189.723701)
			(xy 361.174598 -189.66975) (xy 361.18996 -189.617453) (xy 361.212608 -189.567874) (xy 361.242081 -189.522023)
			(xy 361.277779 -189.480833) (xy 361.318975 -189.445142) (xy 361.364831 -189.415677) (xy 361.414413 -189.393038)
			(xy 361.466713 -189.377685) (xy 361.520665 -189.369931) (xy 361.547918 -189.369446) (xy 361.575289 -189.36989)
			(xy 361.62947 -189.377712) (xy 361.681973 -189.393205) (xy 361.73172 -189.416052) (xy 361.777685 -189.445782)
			(xy 361.798616 -189.463426) (xy 361.79887 -189.46368) (xy 361.805954 -189.469269) (xy 361.822873 -189.475512)
			(xy 361.83189 -189.475872) (xy 361.898946 -189.475872) (xy 361.907961 -189.475495) (xy 361.924878 -189.469262)
			(xy 361.931966 -189.46368) (xy 361.931966 -189.463426) (xy 361.93222 -189.463426) (xy 361.953153 -189.445785)
			(xy 361.999121 -189.416061) (xy 362.048867 -189.393215) (xy 362.101369 -189.377719) (xy 362.155547 -189.36989)
			(xy 362.210289 -189.36989) (xy 362.264467 -189.377719) (xy 362.316969 -189.393215) (xy 362.366715 -189.416061)
			(xy 362.412683 -189.445785) (xy 362.433616 -189.463426) (xy 362.43387 -189.46368) (xy 362.440954 -189.469269)
			(xy 362.457873 -189.475512) (xy 362.46689 -189.475872) (xy 362.533946 -189.475872) (xy 362.542961 -189.475495)
			(xy 362.559878 -189.469262) (xy 362.566966 -189.46368) (xy 362.566966 -189.463426) (xy 362.56722 -189.463426)
			(xy 362.588175 -189.445815) (xy 362.634141 -189.416098) (xy 362.683883 -189.393256) (xy 362.736378 -189.377759)
			(xy 362.79055 -189.369924) (xy 362.817918 -189.369446) (xy 362.845168 -189.369961) (xy 362.899112 -189.377719)
			(xy 362.951403 -189.393074) (xy 363.000978 -189.415714) (xy 363.046826 -189.445178) (xy 363.088014 -189.480866)
			(xy 363.123706 -189.522052) (xy 363.153173 -189.567898) (xy 363.175816 -189.61747) (xy 363.191175 -189.669761)
			(xy 363.198937 -189.723704) (xy 363.199426 -189.750954) (xy 365.18215 -189.750954) (xy 365.182635 -189.723704)
			(xy 365.190397 -189.669758) (xy 365.205755 -189.617466) (xy 365.228399 -189.567891) (xy 365.257866 -189.522043)
			(xy 365.293557 -189.480854) (xy 365.334746 -189.445164) (xy 365.380595 -189.415697) (xy 365.43017 -189.393054)
			(xy 365.482462 -189.377696) (xy 365.536408 -189.369935) (xy 365.563658 -189.369446) (xy 365.591028 -189.369925)
			(xy 365.645207 -189.377738) (xy 365.69771 -189.393224) (xy 365.747457 -189.416063) (xy 365.793424 -189.445785)
			(xy 365.814356 -189.463426) (xy 365.81461 -189.46368) (xy 365.821683 -189.469286) (xy 365.83861 -189.475519)
			(xy 365.84763 -189.475872) (xy 365.914686 -189.475872) (xy 365.923703 -189.475514) (xy 365.94062 -189.469268)
			(xy 365.947706 -189.46368) (xy 365.94796 -189.463426) (xy 365.971446 -189.443796) (xy 366.023429 -189.411487)
			(xy 366.079893 -189.387865) (xy 366.109504 -189.380114) (xy 366.110012 -189.380114) (xy 366.116567 -189.378171)
			(xy 366.128408 -189.371345) (xy 366.13338 -189.366652) (xy 366.533938 -188.966348) (xy 366.540697 -188.958891)
			(xy 366.548418 -188.940331) (xy 366.548924 -188.93028) (xy 366.548924 -176.162716) (xy 366.549456 -176.137769)
			(xy 366.557263 -176.088488) (xy 366.572673 -176.041032) (xy 366.595306 -175.996565) (xy 366.624608 -175.95618)
			(xy 366.641888 -175.93818) (xy 367.141252 -175.438816) (xy 367.148188 -175.431195) (xy 367.15586 -175.412089)
			(xy 367.155452 -175.391504) (xy 367.151666 -175.38192) (xy 367.105946 -175.280828) (xy 367.078768 -175.264572)
			(xy 367.06302 -175.265588) (xy 367.038636 -175.26635) (xy 367.011379 -175.265884) (xy 366.95742 -175.25813)
			(xy 366.905114 -175.242776) (xy 366.855525 -175.220135) (xy 366.809664 -175.190666) (xy 366.768463 -175.15497)
			(xy 366.732762 -175.113773) (xy 366.703288 -175.067915) (xy 366.68064 -175.018329) (xy 366.66528 -174.966025)
			(xy 366.65752 -174.912067) (xy 366.657518 -174.857553) (xy 366.665275 -174.803595) (xy 366.680633 -174.751289)
			(xy 366.703278 -174.701702) (xy 366.73275 -174.655843) (xy 366.768449 -174.614645) (xy 366.809648 -174.578946)
			(xy 366.855508 -174.549475) (xy 366.905095 -174.526831) (xy 366.957401 -174.511474) (xy 367.011359 -174.503718)
			(xy 367.065873 -174.50372) (xy 367.119831 -174.511481) (xy 367.172135 -174.526842) (xy 367.221721 -174.54949)
			(xy 367.267578 -174.578966) (xy 367.308774 -174.614667) (xy 367.344469 -174.655868) (xy 367.373937 -174.70173)
			(xy 367.396578 -174.751319) (xy 367.411932 -174.803626) (xy 367.419684 -174.857585) (xy 367.420144 -174.884842)
			(xy 367.420144 -174.885096) (xy 367.419539 -174.916186) (xy 367.409448 -174.97754) (xy 367.389516 -175.036438)
			(xy 367.37544 -175.064166) (xy 367.367566 -175.079152) (xy 367.372392 -175.112172) (xy 367.38433 -175.12411)
			(xy 367.391742 -175.130794) (xy 367.410175 -175.138391) (xy 367.430113 -175.138391) (xy 367.448546 -175.130794)
			(xy 367.455958 -175.12411) (xy 367.576354 -175.003968) (xy 367.583194 -174.996568) (xy 367.590915 -174.977969)
			(xy 367.59134 -174.9679) (xy 367.59134 -174.433484) (xy 367.590939 -174.423412) (xy 367.583203 -174.404813)
			(xy 367.576354 -174.397416) (xy 367.552478 -174.373794) (xy 367.547485 -174.369171) (xy 367.535649 -174.362467)
			(xy 367.52911 -174.360586) (xy 367.528856 -174.360332) (xy 367.528348 -174.360332) (xy 367.500962 -174.353212)
			(xy 367.448515 -174.331977) (xy 367.39978 -174.303228) (xy 367.355827 -174.267594) (xy 367.317619 -174.225859)
			(xy 367.285996 -174.178938) (xy 367.261651 -174.12786) (xy 367.245119 -174.073746) (xy 367.236762 -174.017784)
			(xy 367.236248 -173.989492) (xy 367.23677 -173.962243) (xy 367.244527 -173.908298) (xy 367.259881 -173.856007)
			(xy 367.282519 -173.806433) (xy 367.311982 -173.760584) (xy 367.34767 -173.719395) (xy 367.388856 -173.683704)
			(xy 367.434701 -173.654237) (xy 367.484273 -173.631593) (xy 367.536563 -173.616234) (xy 367.590507 -173.608473)
			(xy 367.617756 -173.607984) (xy 367.646062 -173.608521) (xy 367.702055 -173.61686) (xy 367.756199 -173.633391)
			(xy 367.807302 -173.65775) (xy 367.854238 -173.689401) (xy 367.895976 -173.727648) (xy 367.931596 -173.771648)
			(xy 367.960315 -173.820434) (xy 367.9815 -173.872931) (xy 367.988596 -173.900338) (xy 367.988596 -173.900846)
			(xy 367.990526 -173.907405) (xy 367.997361 -173.919244) (xy 368.002058 -173.924214) (xy 368.133884 -174.05604)
			(xy 368.151195 -174.074016) (xy 368.180517 -174.114397) (xy 368.203161 -174.158867) (xy 368.21857 -174.206333)
			(xy 368.226365 -174.255624) (xy 368.226848 -174.280576) (xy 368.226848 -175.120808) (xy 368.226339 -175.145757)
			(xy 368.218528 -175.195039) (xy 368.203113 -175.242495) (xy 368.180474 -175.286961) (xy 368.151167 -175.327345)
			(xy 368.133884 -175.345344) (xy 367.917476 -175.561752) (xy 367.910683 -175.569184) (xy 367.903116 -175.587828)
			(xy 367.903271 -175.60795) (xy 367.906808 -175.617378) (xy 367.943384 -175.703992) (xy 367.947728 -175.713142)
			(xy 367.962194 -175.727294) (xy 367.98101 -175.734744) (xy 367.991136 -175.73498) (xy 367.996978 -175.73498)
			(xy 368.02423 -175.735476) (xy 368.078179 -175.743229) (xy 368.130475 -175.758582) (xy 368.180055 -175.781221)
			(xy 368.225907 -175.810686) (xy 368.2671 -175.846376) (xy 368.302794 -175.887565) (xy 368.332263 -175.933415)
			(xy 368.354906 -175.982993) (xy 368.370263 -176.035288) (xy 368.378022 -176.089236) (xy 368.378486 -176.116488)
			(xy 368.377967 -176.144398) (xy 368.369836 -176.199621) (xy 368.353746 -176.253071) (xy 368.330039 -176.303606)
			(xy 368.299223 -176.350148) (xy 368.28095 -176.37125) (xy 368.275026 -176.378407) (xy 368.268393 -176.395748)
			(xy 368.267996 -176.405032) (xy 368.267996 -176.482756) (xy 368.2746 -176.500028) (xy 368.28095 -176.50714)
			(xy 368.299229 -176.528239) (xy 368.330055 -176.574778) (xy 368.353769 -176.625313) (xy 368.369865 -176.678764)
			(xy 368.378 -176.733991) (xy 368.378486 -176.761902) (xy 368.378 -176.789153) (xy 368.370244 -176.843101)
			(xy 368.354889 -176.895396) (xy 368.332247 -176.944973) (xy 368.302781 -176.990823) (xy 368.26709 -177.032014)
			(xy 368.225899 -177.067705) (xy 368.180049 -177.097171) (xy 368.130472 -177.119813) (xy 368.078177 -177.135168)
			(xy 368.024229 -177.142924) (xy 367.969727 -177.142924) (xy 367.915779 -177.135168) (xy 367.863484 -177.119813)
			(xy 367.813907 -177.097171) (xy 367.768057 -177.067705) (xy 367.726866 -177.032014) (xy 367.691175 -176.990823)
			(xy 367.661709 -176.944973) (xy 367.639067 -176.895396) (xy 367.623712 -176.843101) (xy 367.615956 -176.789153)
			(xy 367.61547 -176.761902) (xy 367.615969 -176.733991) (xy 367.624103 -176.678766) (xy 367.640197 -176.625316)
			(xy 367.663908 -176.574781) (xy 367.69473 -176.528241) (xy 367.713006 -176.50714) (xy 367.718929 -176.499982)
			(xy 367.725565 -176.482642) (xy 367.72596 -176.473358) (xy 367.72596 -176.395634) (xy 367.719356 -176.378362)
			(xy 367.713006 -176.37125) (xy 367.694731 -176.350148) (xy 367.663903 -176.30361) (xy 367.640187 -176.253076)
			(xy 367.62409 -176.199625) (xy 367.615955 -176.144399) (xy 367.61547 -176.116488) (xy 367.61547 -176.110646)
			(xy 367.615197 -176.100527) (xy 367.607745 -176.081724) (xy 367.593619 -176.067249) (xy 367.584482 -176.062894)
			(xy 367.497868 -176.026318) (xy 367.488453 -176.022732) (xy 367.46832 -176.022577) (xy 367.449681 -176.03019)
			(xy 367.442242 -176.036986) (xy 367.199418 -176.279556) (xy 367.192607 -176.286979) (xy 367.18487 -176.305561)
			(xy 367.184432 -176.315624) (xy 367.184432 -179.232155) (xy 368.583129 -179.232155) (xy 368.583129 -179.177645)
			(xy 368.590887 -179.123689) (xy 368.606244 -179.071387) (xy 368.628889 -179.021803) (xy 368.65836 -178.975946)
			(xy 368.694057 -178.93475) (xy 368.735254 -178.899054) (xy 368.781112 -178.869584) (xy 368.830696 -178.846941)
			(xy 368.882999 -178.831585) (xy 368.936955 -178.823828) (xy 368.96421 -178.823366) (xy 368.964718 -178.823366)
			(xy 368.975665 -178.82345) (xy 368.997523 -178.824722) (xy 369.008406 -178.825906) (xy 369.018157 -178.826551)
			(xy 369.03697 -178.82134) (xy 369.044982 -178.815746) (xy 369.10899 -178.766978) (xy 369.118896 -178.750214)
			(xy 369.12042 -178.740562) (xy 369.125354 -178.712096) (xy 369.142666 -178.656979) (xy 369.168078 -178.605095)
			(xy 369.201009 -178.557628) (xy 369.24071 -178.515659) (xy 369.263168 -178.497484) (xy 369.271984 -178.489886)
			(xy 369.28216 -178.468978) (xy 369.282726 -178.457352) (xy 369.282726 -178.377596) (xy 369.2822 -178.365962)
			(xy 369.272005 -178.345051) (xy 369.263168 -178.337464) (xy 369.240661 -178.319301) (xy 369.200928 -178.277275)
			(xy 369.167993 -178.229734) (xy 369.142609 -178.177767) (xy 369.125358 -178.122565) (xy 369.116634 -178.065392)
			(xy 369.116102 -178.036474) (xy 369.116588 -178.009223) (xy 369.124344 -177.955275) (xy 369.139699 -177.90298)
			(xy 369.162341 -177.853403) (xy 369.191807 -177.807553) (xy 369.227498 -177.766362) (xy 369.268689 -177.730671)
			(xy 369.314539 -177.701205) (xy 369.364116 -177.678563) (xy 369.416411 -177.663208) (xy 369.470359 -177.655452)
			(xy 369.524861 -177.655452) (xy 369.578809 -177.663208) (xy 369.631104 -177.678563) (xy 369.680681 -177.701205)
			(xy 369.726531 -177.730671) (xy 369.767722 -177.766362) (xy 369.803413 -177.807553) (xy 369.832879 -177.853403)
			(xy 369.855521 -177.90298) (xy 369.870876 -177.955275) (xy 369.878632 -178.009223) (xy 369.879118 -178.036474)
			(xy 369.878612 -178.065392) (xy 369.869885 -178.122565) (xy 369.852627 -178.177765) (xy 369.827233 -178.229728)
			(xy 369.794286 -178.277261) (xy 369.75454 -178.319276) (xy 369.732052 -178.337464) (xy 369.723263 -178.345089)
			(xy 369.713072 -178.365976) (xy 369.712494 -178.377596) (xy 369.712494 -178.457352) (xy 369.71302 -178.468985)
			(xy 369.723218 -178.489895) (xy 369.732052 -178.497484) (xy 369.75586 -178.516753) (xy 369.797577 -178.561593)
			(xy 369.831578 -178.612534) (xy 369.856986 -178.66826) (xy 369.865656 -178.697636) (xy 369.868196 -178.70678)
			(xy 369.879372 -178.72202) (xy 369.953286 -178.76901) (xy 369.971828 -178.772566) (xy 369.981226 -178.770788)
			(xy 369.997726 -178.76805) (xy 370.031049 -178.765125) (xy 370.047774 -178.764946) (xy 370.075022 -178.765502)
			(xy 370.128965 -178.773254) (xy 370.181256 -178.788604) (xy 370.23083 -178.811238) (xy 370.276678 -178.840698)
			(xy 370.317867 -178.876382) (xy 370.353559 -178.917564) (xy 370.383027 -178.963407) (xy 370.405671 -179.012977)
			(xy 370.421031 -179.065264) (xy 370.428793 -179.119206) (xy 370.429282 -179.146454) (xy 370.428791 -179.174028)
			(xy 370.420844 -179.2286) (xy 370.405125 -179.281459) (xy 370.38196 -179.331506) (xy 370.351831 -179.377696)
			(xy 370.315367 -179.419068) (xy 370.294662 -179.437284) (xy 370.286588 -179.44484) (xy 370.277234 -179.464851)
			(xy 370.276628 -179.475892) (xy 370.276628 -179.553616) (xy 370.277234 -179.564661) (xy 370.286572 -179.584683)
			(xy 370.294662 -179.592224) (xy 370.31538 -179.610428) (xy 370.351852 -179.651797) (xy 370.381984 -179.697988)
			(xy 370.405149 -179.748038) (xy 370.420863 -179.800902) (xy 370.428799 -179.855479) (xy 370.429282 -179.883054)
			(xy 370.428802 -179.910307) (xy 370.42105 -179.964259) (xy 370.405699 -180.016558) (xy 370.38306 -180.066139)
			(xy 370.353594 -180.111994) (xy 370.317902 -180.153188) (xy 370.27671 -180.188882) (xy 370.230857 -180.21835)
			(xy 370.181276 -180.240992) (xy 370.128978 -180.256346) (xy 370.075027 -180.2641) (xy 370.047774 -180.264562)
			(xy 370.047266 -180.264562) (xy 370.013484 -180.263038) (xy 370.003324 -180.262022) (xy 369.98402 -180.268118)
			(xy 369.921028 -180.32095) (xy 369.913727 -180.327663) (xy 369.904454 -180.345176) (xy 369.902994 -180.354986)
			(xy 369.902994 -180.355748) (xy 369.900063 -180.383912) (xy 369.886854 -180.438974) (xy 369.86565 -180.491478)
			(xy 369.836915 -180.54027) (xy 369.801282 -180.584277) (xy 369.759534 -180.622532) (xy 369.712589 -180.654193)
			(xy 369.661479 -180.678566) (xy 369.607326 -180.695113) (xy 369.551322 -180.703472) (xy 369.52301 -180.703982)
			(xy 369.495756 -180.703535) (xy 369.441803 -180.695779) (xy 369.389504 -180.680423) (xy 369.339922 -180.65778)
			(xy 369.294067 -180.62831) (xy 369.252874 -180.592615) (xy 369.21718 -180.55142) (xy 369.187713 -180.505564)
			(xy 369.165071 -180.455981) (xy 369.149718 -180.403681) (xy 369.141964 -180.349728) (xy 369.141502 -180.322474)
			(xy 369.141961 -180.29461) (xy 369.150067 -180.239476) (xy 369.166104 -180.186106) (xy 369.189729 -180.135635)
			(xy 369.220443 -180.089136) (xy 369.25759 -180.047596) (xy 369.278662 -180.029358) (xy 369.287806 -180.021738)
			(xy 369.297204 -180.000656) (xy 369.294156 -179.908454) (xy 369.293235 -179.896973) (xy 369.282516 -179.876609)
			(xy 369.273582 -179.869338) (xy 369.273328 -179.869084) (xy 369.252417 -179.853361) (xy 369.214661 -179.817144)
			(xy 369.182219 -179.7761) (xy 369.155703 -179.730999) (xy 369.135611 -179.682693) (xy 369.128548 -179.657502)
			(xy 369.126262 -179.648612) (xy 369.115594 -179.633372) (xy 369.043712 -179.58562) (xy 369.025678 -179.581556)
			(xy 369.016534 -179.582826) (xy 369.003706 -179.584469) (xy 368.977904 -179.586252) (xy 368.964972 -179.586382)
			(xy 368.96421 -179.586382) (xy 368.936955 -179.585972) (xy 368.882999 -179.578215) (xy 368.830696 -179.562859)
			(xy 368.781112 -179.540216) (xy 368.735254 -179.510746) (xy 368.694057 -179.47505) (xy 368.65836 -179.433854)
			(xy 368.628889 -179.387997) (xy 368.606244 -179.338413) (xy 368.590887 -179.286111) (xy 368.583129 -179.232155)
			(xy 367.184432 -179.232155) (xy 367.184432 -182.141876) (xy 370.14785 -182.141876) (xy 370.148351 -182.114302)
			(xy 370.156294 -182.05973) (xy 370.17201 -182.00687) (xy 370.195174 -181.956824) (xy 370.225301 -181.910634)
			(xy 370.261765 -181.869262) (xy 370.28247 -181.851046) (xy 370.290536 -181.843483) (xy 370.299893 -181.823477)
			(xy 370.300504 -181.812438) (xy 370.300504 -181.734714) (xy 370.299926 -181.723666) (xy 370.290568 -181.703645)
			(xy 370.28247 -181.696106) (xy 370.261753 -181.677902) (xy 370.225284 -181.636531) (xy 370.195153 -181.590339)
			(xy 370.171989 -181.54029) (xy 370.156274 -181.487427) (xy 370.148335 -181.432851) (xy 370.14785 -181.405276)
			(xy 370.148454 -181.37583) (xy 370.157513 -181.317638) (xy 370.175399 -181.261528) (xy 370.201686 -181.208827)
			(xy 370.235752 -181.160788) (xy 370.276789 -181.118547) (xy 370.323824 -181.083106) (xy 370.349526 -181.068726)
			(xy 370.357493 -181.064037) (xy 370.369602 -181.050086) (xy 370.373148 -181.041548) (xy 370.399818 -180.969158)
			(xy 370.399564 -180.950616) (xy 370.396008 -180.941726) (xy 370.387651 -180.919747) (xy 370.375909 -180.874215)
			(xy 370.369969 -180.827569) (xy 370.369592 -180.804058) (xy 370.369592 -180.803804) (xy 370.370038 -180.777186)
			(xy 370.377614 -180.724491) (xy 370.392612 -180.673411) (xy 370.414727 -180.624986) (xy 370.443509 -180.580201)
			(xy 370.478372 -180.539967) (xy 370.518605 -180.505105) (xy 370.563391 -180.476324) (xy 370.611817 -180.45421)
			(xy 370.662897 -180.439213) (xy 370.715592 -180.431637) (xy 370.74221 -180.431186) (xy 370.768632 -180.431641)
			(xy 370.820947 -180.439092) (xy 370.871686 -180.453858) (xy 370.91983 -180.475642) (xy 370.964415 -180.504008)
			(xy 370.98478 -180.520848) (xy 370.991638 -180.52669) (xy 371.008656 -180.53304) (xy 371.092984 -180.53304)
			(xy 371.110002 -180.52669) (xy 371.11686 -180.520848) (xy 371.137226 -180.504009) (xy 371.181812 -180.475644)
			(xy 371.229956 -180.453857) (xy 371.280693 -180.439086) (xy 371.333008 -180.431626) (xy 371.385852 -180.431626)
			(xy 371.438167 -180.439086) (xy 371.488904 -180.453857) (xy 371.537048 -180.475644) (xy 371.581634 -180.504009)
			(xy 371.602 -180.520848) (xy 371.608858 -180.52669) (xy 371.625876 -180.53304) (xy 371.710204 -180.53304)
			(xy 371.727222 -180.52669) (xy 371.73408 -180.520848) (xy 371.754459 -180.504027) (xy 371.799044 -180.475668)
			(xy 371.847186 -180.453884) (xy 371.897919 -180.439113) (xy 371.95023 -180.431649) (xy 371.97665 -180.431186)
			(xy 372.00454 -180.431669) (xy 372.059696 -180.439976) (xy 372.112999 -180.456411) (xy 372.163256 -180.480608)
			(xy 372.209346 -180.512026) (xy 372.250237 -180.549962) (xy 372.285017 -180.59357) (xy 372.312909 -180.641874)
			(xy 372.333289 -180.693797) (xy 372.345702 -180.748177) (xy 372.349871 -180.8038) (xy 372.345702 -180.859423)
			(xy 372.333289 -180.913803) (xy 372.312909 -180.965726) (xy 372.285017 -181.01403) (xy 372.250237 -181.057638)
			(xy 372.209346 -181.095574) (xy 372.163256 -181.126992) (xy 372.112999 -181.151189) (xy 372.059696 -181.167624)
			(xy 372.00454 -181.175931) (xy 371.97665 -181.176422) (xy 371.950227 -181.175988) (xy 371.897911 -181.168532)
			(xy 371.847172 -181.153761) (xy 371.799029 -181.131972) (xy 371.754445 -181.103602) (xy 371.73408 -181.08676)
			(xy 371.727222 -181.080918) (xy 371.710204 -181.074568) (xy 371.625876 -181.074568) (xy 371.608858 -181.080918)
			(xy 371.602 -181.08676) (xy 371.581634 -181.103599) (xy 371.537048 -181.131964) (xy 371.488904 -181.153751)
			(xy 371.438167 -181.168522) (xy 371.385852 -181.175982) (xy 371.333008 -181.175982) (xy 371.280693 -181.168522)
			(xy 371.229956 -181.153751) (xy 371.181812 -181.131964) (xy 371.137226 -181.103599) (xy 371.11686 -181.08676)
			(xy 371.110002 -181.080918) (xy 371.092984 -181.074568) (xy 371.008656 -181.074568) (xy 370.991638 -181.080918)
			(xy 370.98478 -181.08676) (xy 370.970662 -181.098517) (xy 370.94051 -181.119513) (xy 370.924582 -181.12867)
			(xy 370.924328 -181.128924) (xy 370.916612 -181.133784) (xy 370.905035 -181.147859) (xy 370.901722 -181.156356)
			(xy 370.879624 -181.220618) (xy 370.876992 -181.229503) (xy 370.877646 -181.248007) (xy 370.880894 -181.256686)
			(xy 370.880894 -181.25694) (xy 370.890347 -181.280473) (xy 370.903678 -181.329403) (xy 370.910429 -181.379666)
			(xy 370.910866 -181.405022) (xy 370.910866 -181.405276) (xy 370.910396 -181.432851) (xy 370.902446 -181.487424)
			(xy 370.886722 -181.540284) (xy 370.863553 -181.59033) (xy 370.833421 -181.63652) (xy 370.796953 -181.677891)
			(xy 370.776246 -181.696106) (xy 370.768159 -181.70365) (xy 370.758814 -181.72367) (xy 370.758212 -181.734714)
			(xy 370.758212 -181.812438) (xy 370.758811 -181.823484) (xy 370.768154 -181.843505) (xy 370.776246 -181.851046)
			(xy 370.796943 -181.869272) (xy 370.833413 -181.910639) (xy 370.863546 -181.956826) (xy 370.886713 -182.006871)
			(xy 370.902433 -182.05973) (xy 370.910378 -182.114302) (xy 370.910866 -182.141876) (xy 370.91038 -182.169127)
			(xy 370.902624 -182.223075) (xy 370.887269 -182.27537) (xy 370.864627 -182.324947) (xy 370.835161 -182.370797)
			(xy 370.79947 -182.411988) (xy 370.758279 -182.447679) (xy 370.712429 -182.477145) (xy 370.662852 -182.499787)
			(xy 370.610557 -182.515142) (xy 370.556609 -182.522898) (xy 370.502107 -182.522898) (xy 370.448159 -182.515142)
			(xy 370.395864 -182.499787) (xy 370.346287 -182.477145) (xy 370.300437 -182.447679) (xy 370.259246 -182.411988)
			(xy 370.223555 -182.370797) (xy 370.194089 -182.324947) (xy 370.171447 -182.27537) (xy 370.156092 -182.223075)
			(xy 370.148336 -182.169127) (xy 370.14785 -182.141876) (xy 367.184432 -182.141876) (xy 367.184432 -189.083188)
			(xy 367.183915 -189.108136) (xy 367.176106 -189.157418) (xy 367.160694 -189.204875) (xy 367.138057 -189.249341)
			(xy 367.108751 -189.289725) (xy 367.091468 -189.307724) (xy 366.58296 -189.816232) (xy 366.578245 -189.821188)
			(xy 366.571415 -189.833034) (xy 366.569498 -189.8396) (xy 366.569498 -189.840362) (xy 366.561871 -189.869564)
			(xy 366.538659 -189.925273) (xy 366.506967 -189.976635) (xy 366.48771 -189.999874) (xy 366.482062 -190.007074)
			(xy 366.47581 -190.024256) (xy 366.475518 -190.033402) (xy 366.475772 -190.100204) (xy 366.476261 -190.10926)
			(xy 366.482765 -190.126176) (xy 366.488472 -190.133224) (xy 366.488726 -190.133478) (xy 366.506647 -190.15448)
			(xy 366.536837 -190.200704) (xy 366.560047 -190.250798) (xy 366.575793 -190.303715) (xy 366.583745 -190.358349)
			(xy 366.58423 -190.385954) (xy 366.583754 -190.413324) (xy 366.575941 -190.467503) (xy 366.560455 -190.520007)
			(xy 366.537615 -190.569754) (xy 366.507891 -190.615721) (xy 366.49025 -190.636652) (xy 366.489996 -190.636906)
			(xy 366.4844 -190.643986) (xy 366.478159 -190.660908) (xy 366.477804 -190.669926) (xy 366.477804 -190.736982)
			(xy 366.478169 -190.745998) (xy 366.484411 -190.762915) (xy 366.489996 -190.770002) (xy 366.49025 -190.770002)
			(xy 366.49025 -190.770256) (xy 366.507847 -190.791225) (xy 366.537575 -190.837186) (xy 366.560424 -190.886926)
			(xy 366.575925 -190.939423) (xy 366.583759 -190.993597) (xy 366.583764 -191.048334) (xy 366.57594 -191.10251)
			(xy 366.560449 -191.155009) (xy 366.537608 -191.204753) (xy 366.507888 -191.25072) (xy 366.49025 -191.271652)
			(xy 366.489996 -191.271906) (xy 366.4844 -191.278986) (xy 366.478159 -191.295908) (xy 366.477804 -191.304926)
			(xy 366.477804 -191.371982) (xy 366.478169 -191.380998) (xy 366.484411 -191.397915) (xy 366.489996 -191.405002)
			(xy 366.49025 -191.405002) (xy 366.49025 -191.405256) (xy 366.507874 -191.4262) (xy 366.53759 -191.472169)
			(xy 366.56043 -191.521913) (xy 366.575924 -191.574412) (xy 366.583755 -191.628586) (xy 366.58423 -191.655954)
			(xy 366.583681 -191.685431) (xy 366.574617 -191.743685) (xy 366.556697 -191.79985) (xy 366.530349 -191.85259)
			(xy 366.496201 -191.900647) (xy 366.476026 -191.922146) (xy 366.469469 -191.929463) (xy 366.462039 -191.947637)
			(xy 366.461548 -191.957452) (xy 366.461548 -192.010792) (xy 366.464088 -192.013078) (xy 366.470946 -192.019428)
			(xy 366.487964 -192.02654) (xy 366.573816 -192.029588) (xy 366.591342 -192.023492) (xy 366.598454 -192.017396)
			(xy 366.61901 -192.000977) (xy 366.663813 -191.973401) (xy 366.711984 -191.952251) (xy 366.762607 -191.937929)
			(xy 366.814719 -191.930708) (xy 366.841024 -191.930274) (xy 366.841278 -191.930274) (xy 366.868529 -191.930776)
			(xy 366.922478 -191.938529) (xy 366.974774 -191.953882) (xy 367.024353 -191.97652) (xy 367.070205 -192.005984)
			(xy 367.111398 -192.041674) (xy 367.147092 -192.082863) (xy 367.176561 -192.128712) (xy 367.199204 -192.178288)
			(xy 367.214562 -192.230583) (xy 367.222321 -192.284531) (xy 367.222786 -192.311782) (xy 367.222313 -192.339152)
			(xy 367.214497 -192.393331) (xy 367.19901 -192.445834) (xy 367.17617 -192.495581) (xy 367.146447 -192.541548)
			(xy 367.128806 -192.56248) (xy 367.128552 -192.562734) (xy 367.122981 -192.569831) (xy 367.116726 -192.58674)
			(xy 367.11636 -192.595754) (xy 367.11636 -192.66281) (xy 367.116699 -192.671829) (xy 367.122958 -192.688746)
			(xy 367.128552 -192.69583) (xy 367.128806 -192.69583) (xy 367.128806 -192.696084) (xy 367.146428 -192.717032)
			(xy 367.176151 -192.762998) (xy 367.198995 -192.812742) (xy 367.214491 -192.865241) (xy 367.222321 -192.919417)
			(xy 367.222323 -192.974156) (xy 367.214497 -193.028332) (xy 367.199005 -193.080833) (xy 367.176164 -193.130579)
			(xy 367.146444 -193.176547) (xy 367.128806 -193.19748) (xy 367.128552 -193.197734) (xy 367.122981 -193.204831)
			(xy 367.116726 -193.22174) (xy 367.11636 -193.230754) (xy 367.11636 -193.29781) (xy 367.116699 -193.306829)
			(xy 367.122958 -193.323746) (xy 367.128552 -193.33083) (xy 367.128806 -193.33083) (xy 367.128806 -193.331084)
			(xy 367.146428 -193.352032) (xy 367.176151 -193.397998) (xy 367.198995 -193.447742) (xy 367.214491 -193.500241)
			(xy 367.222321 -193.554417) (xy 367.222323 -193.609156) (xy 367.214497 -193.663332) (xy 367.199005 -193.715833)
			(xy 367.176164 -193.765579) (xy 367.146444 -193.811547) (xy 367.128806 -193.83248) (xy 367.128552 -193.832734)
			(xy 367.122981 -193.839831) (xy 367.116726 -193.85674) (xy 367.11636 -193.865754) (xy 367.11636 -193.93281)
			(xy 367.116699 -193.941829) (xy 367.122958 -193.958746) (xy 367.128552 -193.96583) (xy 367.128806 -193.96583)
			(xy 367.128806 -193.966084) (xy 367.146428 -193.987032) (xy 367.176151 -194.032998) (xy 367.198995 -194.082742)
			(xy 367.214491 -194.135241) (xy 367.222321 -194.189417) (xy 367.222323 -194.244156) (xy 367.214497 -194.298332)
			(xy 367.199005 -194.350833) (xy 367.176164 -194.400579) (xy 367.146444 -194.446547) (xy 367.128806 -194.46748)
			(xy 367.128552 -194.467734) (xy 367.122981 -194.474831) (xy 367.116726 -194.49174) (xy 367.11636 -194.500754)
			(xy 367.11636 -194.56781) (xy 367.116699 -194.576829) (xy 367.122958 -194.593746) (xy 367.128552 -194.60083)
			(xy 367.128806 -194.60083) (xy 367.128806 -194.601084) (xy 367.146428 -194.622032) (xy 367.176151 -194.667998)
			(xy 367.198995 -194.717742) (xy 367.214491 -194.770241) (xy 367.222321 -194.824417) (xy 367.222323 -194.879156)
			(xy 367.214497 -194.933332) (xy 367.199005 -194.985833) (xy 367.176164 -195.035579) (xy 367.146444 -195.081547)
			(xy 367.128806 -195.10248) (xy 367.128552 -195.102734) (xy 367.122981 -195.109831) (xy 367.116726 -195.12674)
			(xy 367.11636 -195.135754) (xy 367.11636 -195.20281) (xy 367.116699 -195.211829) (xy 367.122958 -195.228746)
			(xy 367.128552 -195.23583) (xy 367.128806 -195.23583) (xy 367.128806 -195.236084) (xy 367.146428 -195.257032)
			(xy 367.176151 -195.302998) (xy 367.198995 -195.352742) (xy 367.214491 -195.405241) (xy 367.222321 -195.459417)
			(xy 367.222323 -195.514156) (xy 367.214497 -195.568332) (xy 367.199005 -195.620833) (xy 367.176164 -195.670579)
			(xy 367.146444 -195.716547) (xy 367.128806 -195.73748) (xy 367.128552 -195.737734) (xy 367.122981 -195.744831)
			(xy 367.116726 -195.76174) (xy 367.11636 -195.770754) (xy 367.11636 -195.83781) (xy 367.116699 -195.846829)
			(xy 367.122958 -195.863746) (xy 367.128552 -195.87083) (xy 367.128806 -195.87083) (xy 367.128806 -195.871084)
			(xy 367.146452 -195.89201) (xy 367.176163 -195.937985) (xy 367.198997 -195.987734) (xy 367.214487 -196.040236)
			(xy 367.222313 -196.094412) (xy 367.222786 -196.121782) (xy 367.222328 -196.149035) (xy 367.214573 -196.202988)
			(xy 367.199218 -196.255287) (xy 367.176576 -196.304868) (xy 367.147108 -196.350723) (xy 367.111413 -196.391916)
			(xy 367.07022 -196.42761) (xy 367.024365 -196.457078) (xy 366.974783 -196.479719) (xy 366.922484 -196.495074)
			(xy 366.868531 -196.502828) (xy 366.841278 -196.50329) (xy 366.813907 -196.502839) (xy 366.759727 -196.495018)
			(xy 366.707224 -196.479526) (xy 366.657477 -196.45668) (xy 366.611511 -196.426953) (xy 366.59058 -196.40931)
			(xy 366.590326 -196.409056) (xy 366.58324 -196.403469) (xy 366.566323 -196.397224) (xy 366.557306 -196.396864)
			(xy 366.49025 -196.396864) (xy 366.481236 -196.397253) (xy 366.46432 -196.403479) (xy 366.45723 -196.409056)
			(xy 366.45723 -196.40931) (xy 366.456976 -196.40931) (xy 366.436027 -196.426928) (xy 366.390059 -196.456643)
			(xy 366.340316 -196.479483) (xy 366.287819 -196.494979) (xy 366.233646 -196.502813) (xy 366.206278 -196.50329)
			(xy 366.179025 -196.502843) (xy 366.125075 -196.495083) (xy 366.072779 -196.479724) (xy 366.0232 -196.457079)
			(xy 365.977349 -196.427609) (xy 365.936159 -196.391913) (xy 365.900467 -196.350719) (xy 365.871002 -196.304865)
			(xy 365.848362 -196.255284) (xy 365.833009 -196.202986) (xy 365.825255 -196.149035) (xy 365.82477 -196.121782)
			(xy 365.825279 -196.092303) (xy 365.834353 -196.034047) (xy 365.852282 -195.977882) (xy 365.878638 -195.925143)
			(xy 365.912795 -195.877087) (xy 365.932974 -195.85559) (xy 365.939516 -195.848261) (xy 365.946955 -195.830096)
			(xy 365.947452 -195.820284) (xy 365.947452 -195.766944) (xy 365.940086 -195.760086) (xy 365.932752 -195.75355)
			(xy 365.914591 -195.746106) (xy 365.90478 -195.745608) (xy 365.872776 -195.745608) (xy 365.862961 -195.746089)
			(xy 365.844797 -195.753537) (xy 365.83747 -195.760086) (xy 365.815989 -195.78028) (xy 365.767924 -195.81442)
			(xy 365.71518 -195.840762) (xy 365.659012 -195.858679) (xy 365.600756 -195.867743) (xy 365.571278 -195.86829)
			(xy 365.544025 -195.867843) (xy 365.490075 -195.860083) (xy 365.437779 -195.844724) (xy 365.3882 -195.822079)
			(xy 365.342349 -195.792609) (xy 365.301159 -195.756913) (xy 365.265467 -195.715719) (xy 365.236002 -195.669865)
			(xy 365.213362 -195.620284) (xy 365.198009 -195.567986) (xy 365.190255 -195.514035) (xy 365.18977 -195.486782)
			(xy 365.190208 -195.459411) (xy 365.19803 -195.40523) (xy 365.213525 -195.352726) (xy 365.236373 -195.302979)
			(xy 365.266105 -195.257014) (xy 365.28375 -195.236084) (xy 365.284004 -195.23583) (xy 365.289585 -195.228739)
			(xy 365.295835 -195.211826) (xy 365.296196 -195.20281) (xy 365.296196 -195.135754) (xy 365.295814 -195.12674)
			(xy 365.289584 -195.109823) (xy 365.284004 -195.102734) (xy 365.28375 -195.102734) (xy 365.28375 -195.10248)
			(xy 365.266091 -195.081562) (xy 365.236365 -195.035592) (xy 365.213519 -194.985844) (xy 365.198023 -194.933339)
			(xy 365.190196 -194.879158) (xy 365.190198 -194.824415) (xy 365.198029 -194.770234) (xy 365.213529 -194.717731)
			(xy 365.236378 -194.667984) (xy 365.266107 -194.622016) (xy 365.28375 -194.601084) (xy 365.284004 -194.60083)
			(xy 365.289585 -194.593739) (xy 365.295835 -194.576826) (xy 365.296196 -194.56781) (xy 365.296196 -194.500754)
			(xy 365.295814 -194.49174) (xy 365.289584 -194.474823) (xy 365.284004 -194.467734) (xy 365.28375 -194.467734)
			(xy 365.28375 -194.46748) (xy 365.266091 -194.446562) (xy 365.236365 -194.400592) (xy 365.213519 -194.350844)
			(xy 365.198023 -194.298339) (xy 365.190196 -194.244158) (xy 365.190198 -194.189415) (xy 365.198029 -194.135234)
			(xy 365.213529 -194.082731) (xy 365.236378 -194.032984) (xy 365.266107 -193.987016) (xy 365.28375 -193.966084)
			(xy 365.284004 -193.96583) (xy 365.289585 -193.958739) (xy 365.295835 -193.941826) (xy 365.296196 -193.93281)
			(xy 365.296196 -193.865754) (xy 365.295814 -193.85674) (xy 365.289584 -193.839823) (xy 365.284004 -193.832734)
			(xy 365.28375 -193.832734) (xy 365.28375 -193.83248) (xy 365.266091 -193.811562) (xy 365.236365 -193.765592)
			(xy 365.213519 -193.715844) (xy 365.198023 -193.663339) (xy 365.190196 -193.609158) (xy 365.190198 -193.554415)
			(xy 365.198029 -193.500234) (xy 365.213529 -193.447731) (xy 365.236378 -193.397984) (xy 365.266107 -193.352016)
			(xy 365.28375 -193.331084) (xy 365.284004 -193.33083) (xy 365.289585 -193.323739) (xy 365.295835 -193.306826)
			(xy 365.296196 -193.29781) (xy 365.296196 -193.230754) (xy 365.295814 -193.22174) (xy 365.289584 -193.204823)
			(xy 365.284004 -193.197734) (xy 365.28375 -193.197734) (xy 365.28375 -193.19748) (xy 365.266143 -193.176522)
			(xy 365.236424 -193.130557) (xy 365.213582 -193.080816) (xy 365.198083 -193.028321) (xy 365.190248 -192.97415)
			(xy 365.18977 -192.946782) (xy 365.190317 -192.918496) (xy 365.198672 -192.862543) (xy 365.215196 -192.808438)
			(xy 365.239527 -192.757364) (xy 365.271132 -192.710443) (xy 365.289846 -192.689226) (xy 365.296196 -192.682368)
			(xy 365.303054 -192.664588) (xy 365.302546 -192.585594) (xy 365.302105 -192.576233) (xy 365.295311 -192.558781)
			(xy 365.289338 -192.551558) (xy 365.28883 -192.55105) (xy 365.269645 -192.529775) (xy 365.237265 -192.482517)
			(xy 365.212312 -192.430951) (xy 365.195345 -192.376235) (xy 365.186746 -192.319597) (xy 365.186214 -192.290954)
			(xy 365.186708 -192.263585) (xy 365.194519 -192.209407) (xy 365.210001 -192.156904) (xy 365.232837 -192.107156)
			(xy 365.262555 -192.061188) (xy 365.280194 -192.040256) (xy 365.280448 -192.040002) (xy 365.286046 -192.032923)
			(xy 365.292285 -192.016) (xy 365.29264 -192.006982) (xy 365.29264 -191.939926) (xy 365.292284 -191.930909)
			(xy 365.286037 -191.913991) (xy 365.280448 -191.906906) (xy 365.280194 -191.906906) (xy 365.280194 -191.906652)
			(xy 365.26251 -191.885755) (xy 365.232789 -191.83978) (xy 365.209949 -191.790028) (xy 365.194457 -191.737521)
			(xy 365.186634 -191.683338) (xy 365.186639 -191.628593) (xy 365.194472 -191.574412) (xy 365.209973 -191.521907)
			(xy 365.232823 -191.472159) (xy 365.262551 -191.426189) (xy 365.280194 -191.405256) (xy 365.280448 -191.405002)
			(xy 365.286046 -191.397923) (xy 365.292285 -191.381) (xy 365.29264 -191.371982) (xy 365.29264 -191.304926)
			(xy 365.292284 -191.295909) (xy 365.286037 -191.278991) (xy 365.280448 -191.271906) (xy 365.280194 -191.271906)
			(xy 365.280194 -191.271652) (xy 365.26251 -191.250755) (xy 365.232789 -191.20478) (xy 365.209949 -191.155028)
			(xy 365.194457 -191.102521) (xy 365.186634 -191.048338) (xy 365.186639 -190.993593) (xy 365.194472 -190.939412)
			(xy 365.209973 -190.886907) (xy 365.232823 -190.837159) (xy 365.262551 -190.791189) (xy 365.280194 -190.770256)
			(xy 365.280448 -190.770002) (xy 365.286046 -190.762923) (xy 365.292285 -190.746) (xy 365.29264 -190.736982)
			(xy 365.29264 -190.669926) (xy 365.292284 -190.660909) (xy 365.286037 -190.643991) (xy 365.280448 -190.636906)
			(xy 365.280194 -190.636906) (xy 365.280194 -190.636652) (xy 365.262565 -190.615712) (xy 365.232852 -190.569741)
			(xy 365.210014 -190.519996) (xy 365.194521 -190.467497) (xy 365.18669 -190.413323) (xy 365.186214 -190.385954)
			(xy 365.186693 -190.35882) (xy 365.194382 -190.3051) (xy 365.209612 -190.253014) (xy 365.232075 -190.203614)
			(xy 365.261318 -190.157899) (xy 365.27867 -190.137034) (xy 365.284312 -190.12983) (xy 365.290568 -190.112651)
			(xy 365.290862 -190.103506) (xy 365.290608 -190.036704) (xy 365.290097 -190.027651) (xy 365.283607 -190.010735)
			(xy 365.277908 -190.003684) (xy 365.277654 -190.00343) (xy 365.259734 -189.982428) (xy 365.229544 -189.936203)
			(xy 365.206334 -189.886109) (xy 365.190588 -189.833193) (xy 365.182635 -189.778559) (xy 365.18215 -189.750954)
			(xy 363.199426 -189.750954) (xy 363.198944 -189.777923) (xy 363.191343 -189.831324) (xy 363.176288 -189.883118)
			(xy 363.154077 -189.932272) (xy 363.125157 -189.977802) (xy 363.107986 -189.998604) (xy 363.102436 -190.005769)
			(xy 363.096324 -190.022819) (xy 363.096048 -190.031878) (xy 363.09681 -190.108332) (xy 363.10316 -190.125096)
			(xy 363.10951 -190.132208) (xy 363.127574 -190.153302) (xy 363.158084 -190.199705) (xy 363.181549 -190.250038)
			(xy 363.197476 -190.30324) (xy 363.205528 -190.358187) (xy 363.20603 -190.385954) (xy 363.205554 -190.413324)
			(xy 363.197741 -190.467503) (xy 363.182255 -190.520007) (xy 363.159415 -190.569754) (xy 363.129691 -190.615721)
			(xy 363.11205 -190.636652) (xy 363.111796 -190.636906) (xy 363.1062 -190.643986) (xy 363.099959 -190.660908)
			(xy 363.099604 -190.669926) (xy 363.099604 -190.736982) (xy 363.099969 -190.745998) (xy 363.106211 -190.762915)
			(xy 363.111796 -190.770002) (xy 363.11205 -190.770002) (xy 363.11205 -190.770256) (xy 363.129647 -190.791225)
			(xy 363.159375 -190.837186) (xy 363.182224 -190.886926) (xy 363.197725 -190.939423) (xy 363.205559 -190.993597)
			(xy 363.205564 -191.048334) (xy 363.19774 -191.10251) (xy 363.182249 -191.155009) (xy 363.159408 -191.204753)
			(xy 363.129688 -191.25072) (xy 363.11205 -191.271652) (xy 363.111796 -191.271906) (xy 363.1062 -191.278986)
			(xy 363.099959 -191.295908) (xy 363.099604 -191.304926) (xy 363.099604 -191.371982) (xy 363.099969 -191.380998)
			(xy 363.106211 -191.397915) (xy 363.111796 -191.405002) (xy 363.11205 -191.405002) (xy 363.11205 -191.405256)
			(xy 363.129647 -191.426225) (xy 363.159375 -191.472186) (xy 363.182224 -191.521926) (xy 363.197725 -191.574423)
			(xy 363.205559 -191.628597) (xy 363.205564 -191.683334) (xy 363.19774 -191.73751) (xy 363.182249 -191.790009)
			(xy 363.159408 -191.839753) (xy 363.129688 -191.88572) (xy 363.11205 -191.906652) (xy 363.111796 -191.906906)
			(xy 363.1062 -191.913986) (xy 363.099959 -191.930908) (xy 363.099604 -191.939926) (xy 363.099604 -192.006982)
			(xy 363.099969 -192.015998) (xy 363.106211 -192.032915) (xy 363.111796 -192.040002) (xy 363.11205 -192.040002)
			(xy 363.11205 -192.040256) (xy 363.129674 -192.0612) (xy 363.15939 -192.107169) (xy 363.18223 -192.156913)
			(xy 363.197724 -192.209412) (xy 363.205555 -192.263586) (xy 363.20603 -192.290954) (xy 363.205462 -192.319965)
			(xy 363.1967 -192.377321) (xy 363.179357 -192.432689) (xy 363.153831 -192.484793) (xy 363.120711 -192.532433)
			(xy 363.101128 -192.553844) (xy 363.094895 -192.561035) (xy 363.087703 -192.578635) (xy 363.087158 -192.588134)
			(xy 363.086142 -192.666874) (xy 363.092746 -192.684654) (xy 363.099096 -192.691766) (xy 363.117437 -192.712859)
			(xy 363.148343 -192.759433) (xy 363.172118 -192.81002) (xy 363.188253 -192.863536) (xy 363.196402 -192.918834)
			(xy 363.196886 -192.946782) (xy 363.196413 -192.974152) (xy 363.188597 -193.028331) (xy 363.17311 -193.080834)
			(xy 363.15027 -193.130581) (xy 363.120547 -193.176548) (xy 363.102906 -193.19748) (xy 363.102652 -193.197734)
			(xy 363.097081 -193.204831) (xy 363.090826 -193.22174) (xy 363.09046 -193.230754) (xy 363.09046 -193.29781)
			(xy 363.090799 -193.306829) (xy 363.097058 -193.323746) (xy 363.102652 -193.33083) (xy 363.102906 -193.33083)
			(xy 363.102906 -193.331084) (xy 363.120552 -193.35201) (xy 363.150263 -193.397985) (xy 363.173097 -193.447734)
			(xy 363.188587 -193.500236) (xy 363.196413 -193.554412) (xy 363.196886 -193.581782) (xy 363.1964 -193.609033)
			(xy 363.188644 -193.662981) (xy 363.173289 -193.715276) (xy 363.150647 -193.764853) (xy 363.121181 -193.810703)
			(xy 363.08549 -193.851894) (xy 363.044299 -193.887585) (xy 362.998449 -193.917051) (xy 362.948872 -193.939693)
			(xy 362.896577 -193.955048) (xy 362.842629 -193.962804) (xy 362.788127 -193.962804) (xy 362.734179 -193.955048)
			(xy 362.681884 -193.939693) (xy 362.632307 -193.917051) (xy 362.586457 -193.887585) (xy 362.545266 -193.851894)
			(xy 362.509575 -193.810703) (xy 362.480109 -193.764853) (xy 362.457467 -193.715276) (xy 362.442112 -193.662981)
			(xy 362.434356 -193.609033) (xy 362.43387 -193.581782) (xy 362.434379 -193.552303) (xy 362.443453 -193.494047)
			(xy 362.461382 -193.437882) (xy 362.487738 -193.385143) (xy 362.521895 -193.337087) (xy 362.542074 -193.31559)
			(xy 362.548616 -193.308261) (xy 362.556055 -193.290096) (xy 362.556552 -193.280284) (xy 362.556552 -193.226944)
			(xy 362.549186 -193.220086) (xy 362.541852 -193.21355) (xy 362.523691 -193.206106) (xy 362.51388 -193.205608)
			(xy 362.481876 -193.205608) (xy 362.472061 -193.206089) (xy 362.453897 -193.213537) (xy 362.44657 -193.220086)
			(xy 362.425089 -193.24028) (xy 362.377024 -193.27442) (xy 362.32428 -193.300762) (xy 362.268112 -193.318679)
			(xy 362.209856 -193.327743) (xy 362.180378 -193.32829) (xy 362.153125 -193.327843) (xy 362.099175 -193.320083)
			(xy 362.046879 -193.304724) (xy 361.9973 -193.282079) (xy 361.951449 -193.252609) (xy 361.910259 -193.216913)
			(xy 361.874567 -193.175719) (xy 361.845102 -193.129865) (xy 361.822462 -193.080284) (xy 361.807109 -193.027986)
			(xy 361.799355 -192.974035) (xy 361.79887 -192.946782) (xy 361.799306 -192.920708) (xy 361.8064 -192.869043)
			(xy 361.820466 -192.818828) (xy 361.841242 -192.770996) (xy 361.868342 -192.726441) (xy 361.901258 -192.685994)
			(xy 361.920028 -192.66789) (xy 361.927144 -192.66052) (xy 361.935405 -192.641793) (xy 361.93603 -192.631568)
			(xy 361.937046 -192.576958) (xy 361.927902 -192.56883) (xy 361.920282 -192.562348) (xy 361.901583 -192.555295)
			(xy 361.89158 -192.555114) (xy 361.859576 -192.55613) (xy 361.849539 -192.55684) (xy 361.831204 -192.565091)
			(xy 361.824016 -192.572132) (xy 361.805905 -192.590864) (xy 361.765495 -192.623754) (xy 361.720986 -192.65084)
			(xy 361.673206 -192.671617) (xy 361.623042 -192.685701) (xy 361.571429 -192.692828) (xy 361.545378 -192.69329)
			(xy 361.518125 -192.692843) (xy 361.464175 -192.685083) (xy 361.411879 -192.669724) (xy 361.3623 -192.647079)
			(xy 361.316449 -192.617609) (xy 361.275259 -192.581913) (xy 361.239567 -192.540719) (xy 361.210102 -192.494865)
			(xy 361.187462 -192.445284) (xy 361.172109 -192.392986) (xy 361.164355 -192.339035) (xy 361.16387 -192.311782)
			(xy 352.823954 -192.311782) (xy 360.128807 -197.28434) (xy 369.527582 -197.28434) (xy 369.528052 -197.25697)
			(xy 369.535865 -197.20279) (xy 369.551353 -197.150286) (xy 369.574194 -197.100539) (xy 369.60392 -197.054573)
			(xy 369.621562 -197.033642) (xy 369.621816 -197.033388) (xy 369.627416 -197.02631) (xy 369.633654 -197.009387)
			(xy 369.634008 -197.000368) (xy 369.634008 -196.933312) (xy 369.633644 -196.924296) (xy 369.627401 -196.907379)
			(xy 369.621816 -196.900292) (xy 369.621562 -196.900292) (xy 369.621562 -196.900038) (xy 369.603959 -196.879074)
			(xy 369.57423 -196.833113) (xy 369.55138 -196.783372) (xy 369.535879 -196.730874) (xy 369.528046 -196.676699)
			(xy 369.528042 -196.621961) (xy 369.535866 -196.567785) (xy 369.551359 -196.515285) (xy 369.574201 -196.46554)
			(xy 369.603923 -196.419574) (xy 369.621562 -196.398642) (xy 369.621816 -196.398388) (xy 369.627416 -196.39131)
			(xy 369.633654 -196.374387) (xy 369.634008 -196.365368) (xy 369.634008 -196.298312) (xy 369.633644 -196.289296)
			(xy 369.627401 -196.272379) (xy 369.621816 -196.265292) (xy 369.621562 -196.265292) (xy 369.621562 -196.265038)
			(xy 369.603959 -196.244074) (xy 369.57423 -196.198113) (xy 369.55138 -196.148372) (xy 369.535879 -196.095874)
			(xy 369.528046 -196.041699) (xy 369.528042 -195.986961) (xy 369.535866 -195.932785) (xy 369.551359 -195.880285)
			(xy 369.574201 -195.83054) (xy 369.603923 -195.784574) (xy 369.621562 -195.763642) (xy 369.621816 -195.763388)
			(xy 369.627416 -195.75631) (xy 369.633654 -195.739387) (xy 369.634008 -195.730368) (xy 369.634008 -195.663312)
			(xy 369.633644 -195.654296) (xy 369.627401 -195.637379) (xy 369.621816 -195.630292) (xy 369.621562 -195.630292)
			(xy 369.621562 -195.630038) (xy 369.603921 -195.609108) (xy 369.574211 -195.563134) (xy 369.551376 -195.513386)
			(xy 369.535885 -195.460885) (xy 369.528056 -195.406709) (xy 369.527582 -195.37934) (xy 369.528079 -195.35085)
			(xy 369.536545 -195.294502) (xy 369.553294 -195.240039) (xy 369.577955 -195.188671) (xy 369.609979 -195.141541)
			(xy 369.628928 -195.12026) (xy 369.635532 -195.113148) (xy 369.64239 -195.095622) (xy 369.64239 -195.00723)
			(xy 369.635532 -194.989704) (xy 369.628928 -194.982592) (xy 369.609976 -194.961315) (xy 369.577969 -194.914177)
			(xy 369.55332 -194.862808) (xy 369.536577 -194.808346) (xy 369.52811 -194.752001) (xy 369.527582 -194.723512)
			(xy 369.528066 -194.69626) (xy 369.535822 -194.64231) (xy 369.551176 -194.590013) (xy 369.573816 -194.540434)
			(xy 369.603282 -194.494581) (xy 369.638973 -194.453389) (xy 369.680164 -194.417695) (xy 369.726015 -194.388226)
			(xy 369.775593 -194.365583) (xy 369.827889 -194.350226) (xy 369.881838 -194.342468) (xy 369.90909 -194.342004)
			(xy 369.93646 -194.342475) (xy 369.990639 -194.350291) (xy 370.043142 -194.365779) (xy 370.092889 -194.38862)
			(xy 370.138856 -194.418343) (xy 370.159788 -194.435984) (xy 370.160042 -194.436238) (xy 370.167138 -194.441811)
			(xy 370.184048 -194.448065) (xy 370.193062 -194.44843) (xy 370.260118 -194.44843) (xy 370.269135 -194.448075)
			(xy 370.286052 -194.441826) (xy 370.293138 -194.436238) (xy 370.293138 -194.435984) (xy 370.293392 -194.435984)
			(xy 370.314325 -194.418343) (xy 370.360293 -194.388619) (xy 370.410039 -194.365773) (xy 370.462541 -194.350277)
			(xy 370.516719 -194.342448) (xy 370.571461 -194.342448) (xy 370.625639 -194.350277) (xy 370.678141 -194.365773)
			(xy 370.727887 -194.388619) (xy 370.773855 -194.418343) (xy 370.794788 -194.435984) (xy 370.795042 -194.436238)
			(xy 370.802138 -194.441811) (xy 370.819048 -194.448065) (xy 370.828062 -194.44843) (xy 370.895118 -194.44843)
			(xy 370.904135 -194.448075) (xy 370.921052 -194.441826) (xy 370.928138 -194.436238) (xy 370.928138 -194.435984)
			(xy 370.928392 -194.435984) (xy 370.949314 -194.418333) (xy 370.99529 -194.388623) (xy 371.04504 -194.36579)
			(xy 371.097543 -194.350302) (xy 371.15172 -194.342476) (xy 371.17909 -194.342004) (xy 371.206343 -194.342465)
			(xy 371.260295 -194.350221) (xy 371.312593 -194.365576) (xy 371.362174 -194.388218) (xy 371.408028 -194.417686)
			(xy 371.449221 -194.45338) (xy 371.484915 -194.494574) (xy 371.514383 -194.540427) (xy 371.537025 -194.590008)
			(xy 371.55238 -194.642307) (xy 371.560135 -194.696259) (xy 371.560598 -194.723512) (xy 373.543322 -194.723512)
			(xy 373.543767 -194.696258) (xy 373.551523 -194.642305) (xy 373.566879 -194.590005) (xy 373.589522 -194.540423)
			(xy 373.618992 -194.494568) (xy 373.654687 -194.453375) (xy 373.695883 -194.417681) (xy 373.741739 -194.388213)
			(xy 373.791322 -194.365572) (xy 373.843623 -194.350219) (xy 373.897576 -194.342465) (xy 373.92483 -194.342004)
			(xy 373.952201 -194.342452) (xy 374.006381 -194.350274) (xy 374.058884 -194.365767) (xy 374.108631 -194.388613)
			(xy 374.154597 -194.418341) (xy 374.175528 -194.435984) (xy 374.175782 -194.436238) (xy 374.182866 -194.441827)
			(xy 374.199785 -194.448071) (xy 374.208802 -194.44843) (xy 374.275858 -194.44843) (xy 374.284872 -194.448046)
			(xy 374.301789 -194.441817) (xy 374.308878 -194.436238) (xy 374.308878 -194.435984) (xy 374.309132 -194.435984)
			(xy 374.330077 -194.418361) (xy 374.376046 -194.388647) (xy 374.425791 -194.365808) (xy 374.478288 -194.350314)
			(xy 374.532462 -194.342481) (xy 374.55983 -194.342004) (xy 374.589306 -194.342586) (xy 374.647557 -194.351645)
			(xy 374.703722 -194.369558) (xy 374.756462 -194.395897) (xy 374.804521 -194.430037) (xy 374.826022 -194.450208)
			(xy 374.833354 -194.456746) (xy 374.851516 -194.464189) (xy 374.861328 -194.464686) (xy 374.914668 -194.464686)
			(xy 374.916954 -194.462146) (xy 374.923266 -194.454856) (xy 374.930453 -194.436979) (xy 374.930924 -194.427348)
			(xy 374.930924 -181.114446) (xy 374.931412 -181.089497) (xy 374.93923 -181.040214) (xy 374.95465 -180.992757)
			(xy 374.977293 -180.948292) (xy 375.006604 -180.907909) (xy 375.023888 -180.88991) (xy 375.502424 -180.411374)
			(xy 375.509321 -180.403723) (xy 375.516995 -180.384633) (xy 375.516608 -180.364061) (xy 375.512838 -180.354478)
			(xy 375.467118 -180.253386) (xy 375.43994 -180.23713) (xy 375.424192 -180.238146) (xy 375.399808 -180.238908)
			(xy 375.372554 -180.238453) (xy 375.318602 -180.230697) (xy 375.266303 -180.215342) (xy 375.216721 -180.1927)
			(xy 375.170866 -180.163232) (xy 375.129672 -180.127538) (xy 375.093976 -180.086345) (xy 375.064507 -180.040491)
			(xy 375.041863 -179.99091) (xy 375.026506 -179.938611) (xy 375.018748 -179.884659) (xy 375.018747 -179.830152)
			(xy 375.026503 -179.776199) (xy 375.041859 -179.7239) (xy 375.064502 -179.674318) (xy 375.09397 -179.628464)
			(xy 375.129664 -179.58727) (xy 375.170857 -179.551575) (xy 375.216711 -179.522105) (xy 375.266293 -179.499462)
			(xy 375.318592 -179.484105) (xy 375.372544 -179.476348) (xy 375.427051 -179.476347) (xy 375.481003 -179.484104)
			(xy 375.533302 -179.49946) (xy 375.582884 -179.522103) (xy 375.628738 -179.551571) (xy 375.669932 -179.587266)
			(xy 375.705627 -179.628459) (xy 375.735096 -179.674314) (xy 375.757739 -179.723895) (xy 375.773095 -179.776194)
			(xy 375.780853 -179.830146) (xy 375.781316 -179.8574) (xy 375.781316 -179.857654) (xy 375.780698 -179.888743)
			(xy 375.770612 -179.950098) (xy 375.750686 -180.008996) (xy 375.736612 -180.036724) (xy 375.728738 -180.05171)
			(xy 375.733564 -180.08473) (xy 375.745502 -180.096668) (xy 375.752914 -180.103352) (xy 375.771347 -180.110949)
			(xy 375.791285 -180.110949) (xy 375.809718 -180.103352) (xy 375.81713 -180.096668) (xy 375.937526 -179.976526)
			(xy 375.944351 -179.969114) (xy 375.952079 -179.950524) (xy 375.952512 -179.940458) (xy 375.952512 -179.406042)
			(xy 375.952088 -179.395972) (xy 375.944369 -179.377373) (xy 375.937526 -179.369974) (xy 375.91365 -179.346352)
			(xy 375.908668 -179.341715) (xy 375.896824 -179.33502) (xy 375.890282 -179.333144) (xy 375.890028 -179.33289)
			(xy 375.88952 -179.33289) (xy 375.862137 -179.32576) (xy 375.809686 -179.304531) (xy 375.760948 -179.275786)
			(xy 375.716991 -179.240156) (xy 375.678782 -179.198421) (xy 375.647158 -179.1515) (xy 375.622814 -179.100421)
			(xy 375.606284 -179.046306) (xy 375.597931 -178.990342) (xy 375.59742 -178.96205) (xy 375.597902 -178.934797)
			(xy 375.605653 -178.880845) (xy 375.621004 -178.828546) (xy 375.643643 -178.778964) (xy 375.673108 -178.73311)
			(xy 375.7088 -178.691916) (xy 375.749992 -178.656221) (xy 375.795845 -178.626753) (xy 375.845426 -178.604112)
			(xy 375.897724 -178.588757) (xy 375.951675 -178.581003) (xy 375.978928 -178.580542) (xy 376.007234 -178.581046)
			(xy 376.063228 -178.589395) (xy 376.11737 -178.605933) (xy 376.168471 -178.630298) (xy 376.215406 -178.661954)
			(xy 376.257143 -178.700203) (xy 376.292763 -178.744205) (xy 376.321483 -178.792991) (xy 376.342671 -178.845489)
			(xy 376.349768 -178.872896) (xy 376.349768 -178.873404) (xy 376.351717 -178.879957) (xy 376.358539 -178.891799)
			(xy 376.36323 -178.896772) (xy 376.495056 -179.028598) (xy 376.512342 -179.046597) (xy 376.541668 -179.086971)
			(xy 376.564318 -179.131436) (xy 376.579733 -179.178896) (xy 376.587533 -179.228184) (xy 376.58802 -179.253134)
			(xy 376.58802 -180.093366) (xy 376.587556 -180.118316) (xy 376.579734 -180.167601) (xy 376.56431 -180.215058)
			(xy 376.541661 -180.259524) (xy 376.512344 -180.299905) (xy 376.495056 -180.317902) (xy 376.278648 -180.53431)
			(xy 376.271885 -180.541764) (xy 376.264312 -180.560397) (xy 376.264453 -180.580509) (xy 376.26798 -180.589936)
			(xy 376.304556 -180.67655) (xy 376.305287 -180.678074) (xy 376.98553 -180.678074) (xy 376.986036 -180.650501)
			(xy 376.993979 -180.595929) (xy 377.009695 -180.54307) (xy 377.032858 -180.493023) (xy 377.062984 -180.446833)
			(xy 377.099445 -180.40546) (xy 377.12015 -180.387244) (xy 377.128214 -180.379679) (xy 377.137572 -180.359675)
			(xy 377.138184 -180.348636) (xy 377.138184 -180.270912) (xy 377.137614 -180.259863) (xy 377.128251 -180.239842)
			(xy 377.12015 -180.232304) (xy 377.099428 -180.214105) (xy 377.06296 -180.172733) (xy 377.032831 -180.12654)
			(xy 377.009667 -180.07649) (xy 376.993953 -180.023625) (xy 376.986015 -179.969049) (xy 376.98553 -179.941474)
			(xy 376.986036 -179.913901) (xy 376.993979 -179.859329) (xy 377.009695 -179.80647) (xy 377.032858 -179.756423)
			(xy 377.062984 -179.710233) (xy 377.099445 -179.66886) (xy 377.12015 -179.650644) (xy 377.128214 -179.643079)
			(xy 377.137572 -179.623075) (xy 377.138184 -179.612036) (xy 377.138184 -179.534312) (xy 377.137614 -179.523263)
			(xy 377.128251 -179.503242) (xy 377.12015 -179.495704) (xy 377.099428 -179.477505) (xy 377.06296 -179.436133)
			(xy 377.032831 -179.38994) (xy 377.009667 -179.33989) (xy 376.993953 -179.287025) (xy 376.986015 -179.232449)
			(xy 376.98553 -179.204874) (xy 376.985931 -179.177619) (xy 376.993692 -179.123664) (xy 377.009054 -179.071362)
			(xy 377.031702 -179.021779) (xy 377.061176 -178.975924) (xy 377.096876 -178.934731) (xy 377.138076 -178.899038)
			(xy 377.183936 -178.869571) (xy 377.233522 -178.846931) (xy 377.285826 -178.831579) (xy 377.339783 -178.823826)
			(xy 377.367038 -178.823366) (xy 377.394893 -178.82388) (xy 377.450008 -178.832008) (xy 377.503357 -178.848057)
			(xy 377.553809 -178.871686) (xy 377.600292 -178.902394) (xy 377.641821 -178.93953) (xy 377.677514 -178.982305)
			(xy 377.706615 -179.029811) (xy 377.728505 -179.081041) (xy 377.7361 -179.107846) (xy 377.738386 -179.116736)
			(xy 377.749054 -179.131976) (xy 377.820936 -179.179728) (xy 377.83897 -179.183792) (xy 377.848114 -179.182522)
			(xy 377.861131 -179.180854) (xy 377.887315 -179.179073) (xy 377.900438 -179.178966) (xy 377.914587 -179.179056)
			(xy 377.94281 -179.181093) (xy 377.956826 -179.18303) (xy 377.966732 -179.184554) (xy 377.986544 -179.179728)
			(xy 378.060966 -179.123848) (xy 378.071126 -179.106322) (xy 378.072396 -179.096162) (xy 378.076477 -179.069007)
			(xy 378.09145 -179.016176) (xy 378.113841 -178.966037) (xy 378.143189 -178.919625) (xy 378.178888 -178.877901)
			(xy 378.220198 -178.841724) (xy 378.266268 -178.811843) (xy 378.316146 -178.788875) (xy 378.368801 -178.773295)
			(xy 378.423146 -178.765423) (xy 378.450602 -178.764946) (xy 378.477851 -178.765476) (xy 378.531795 -178.773231)
			(xy 378.584086 -178.788584) (xy 378.63366 -178.811222) (xy 378.679508 -178.840685) (xy 378.720697 -178.876371)
			(xy 378.756389 -178.917556) (xy 378.785856 -178.963401) (xy 378.8085 -179.012973) (xy 378.823859 -179.065262)
			(xy 378.831621 -179.119205) (xy 378.83211 -179.146454) (xy 378.831609 -179.174027) (xy 378.823663 -179.228598)
			(xy 378.807945 -179.281457) (xy 378.784782 -179.331503) (xy 378.754655 -179.377694) (xy 378.718194 -179.419067)
			(xy 378.69749 -179.437284) (xy 378.68942 -179.444844) (xy 378.680063 -179.464852) (xy 378.679456 -179.475892)
			(xy 378.679456 -179.553616) (xy 378.680053 -179.564662) (xy 378.689396 -179.584685) (xy 378.69749 -179.592224)
			(xy 378.718214 -179.610421) (xy 378.754684 -179.651793) (xy 378.784814 -179.697985) (xy 378.807978 -179.748036)
			(xy 378.823692 -179.800901) (xy 378.831627 -179.855478) (xy 378.83211 -179.883054) (xy 378.831602 -179.910306)
			(xy 378.823851 -179.964255) (xy 378.808501 -180.016552) (xy 378.785864 -180.066132) (xy 378.756401 -180.111985)
			(xy 378.720712 -180.153178) (xy 378.679523 -180.188872) (xy 378.633674 -180.218341) (xy 378.584097 -180.240984)
			(xy 378.531802 -180.256341) (xy 378.477854 -180.264098) (xy 378.450602 -180.264562) (xy 378.450094 -180.264562)
			(xy 378.416312 -180.263038) (xy 378.406152 -180.262022) (xy 378.386848 -180.268118) (xy 378.323856 -180.32095)
			(xy 378.31656 -180.327668) (xy 378.307283 -180.345176) (xy 378.305822 -180.354986) (xy 378.305822 -180.355748)
			(xy 378.302864 -180.383908) (xy 378.289656 -180.438968) (xy 378.268454 -180.49147) (xy 378.239722 -180.540261)
			(xy 378.204092 -180.584267) (xy 378.162347 -180.622521) (xy 378.115406 -180.654184) (xy 378.064299 -180.678558)
			(xy 378.01015 -180.695108) (xy 377.954149 -180.70347) (xy 377.925838 -180.703982) (xy 377.907819 -180.703764)
			(xy 377.871944 -180.700328) (xy 377.85421 -180.697124) (xy 377.844558 -180.695346) (xy 377.825508 -180.698902)
			(xy 377.750578 -180.746908) (xy 377.739148 -180.762656) (xy 377.736862 -180.772054) (xy 377.72949 -180.799106)
			(xy 377.707858 -180.850833) (xy 377.67889 -180.898839) (xy 377.643212 -180.942091) (xy 377.601589 -180.979658)
			(xy 377.554918 -181.010731) (xy 377.504204 -181.034642) (xy 377.450537 -181.050876) (xy 377.395072 -181.059085)
			(xy 377.367038 -181.059582) (xy 377.339785 -181.059109) (xy 377.285833 -181.051357) (xy 377.233534 -181.036004)
			(xy 377.183952 -181.013364) (xy 377.138097 -180.983898) (xy 377.096904 -180.948205) (xy 377.061209 -180.907012)
			(xy 377.031741 -180.861159) (xy 377.0091 -180.811578) (xy 376.993746 -180.759279) (xy 376.985992 -180.705327)
			(xy 376.98553 -180.678074) (xy 376.305287 -180.678074) (xy 376.308937 -180.68568) (xy 376.323385 -180.699837)
			(xy 376.342187 -180.707297) (xy 376.352308 -180.707538) (xy 376.35815 -180.707538) (xy 376.385404 -180.708002)
			(xy 376.439357 -180.715753) (xy 376.491658 -180.731105) (xy 376.541241 -180.753745) (xy 376.587096 -180.783212)
			(xy 376.628291 -180.818906) (xy 376.663985 -180.8601) (xy 376.693453 -180.905956) (xy 376.716093 -180.955539)
			(xy 376.731446 -181.007839) (xy 376.739198 -181.061792) (xy 376.739658 -181.089046) (xy 376.739181 -181.116957)
			(xy 376.731041 -181.172183) (xy 376.714941 -181.225634) (xy 376.691225 -181.276168) (xy 376.660399 -181.322708)
			(xy 376.642122 -181.343808) (xy 376.636225 -181.350985) (xy 376.629573 -181.36831) (xy 376.629168 -181.37759)
			(xy 376.629168 -181.455314) (xy 376.635772 -181.472586) (xy 376.642122 -181.479698) (xy 376.660377 -181.500817)
			(xy 376.691207 -181.54735) (xy 376.714926 -181.59788) (xy 376.731028 -181.651327) (xy 376.739169 -181.70655)
			(xy 376.739658 -181.73446) (xy 376.739172 -181.761711) (xy 376.731416 -181.815659) (xy 376.716061 -181.867954)
			(xy 376.693419 -181.917531) (xy 376.663953 -181.963381) (xy 376.628262 -182.004572) (xy 376.587071 -182.040263)
			(xy 376.541221 -182.069729) (xy 376.491644 -182.092371) (xy 376.439349 -182.107726) (xy 376.385401 -182.115482)
			(xy 376.330899 -182.115482) (xy 376.276951 -182.107726) (xy 376.224656 -182.092371) (xy 376.175079 -182.069729)
			(xy 376.129229 -182.040263) (xy 376.088038 -182.004572) (xy 376.052347 -181.963381) (xy 376.022881 -181.917531)
			(xy 376.000239 -181.867954) (xy 375.984884 -181.815659) (xy 375.977128 -181.761711) (xy 375.976642 -181.73446)
			(xy 375.977123 -181.706549) (xy 375.985262 -181.651323) (xy 376.001361 -181.597873) (xy 376.025076 -181.547338)
			(xy 376.055901 -181.500798) (xy 376.074178 -181.479698) (xy 376.080073 -181.472519) (xy 376.086726 -181.455195)
			(xy 376.087132 -181.445916) (xy 376.087132 -181.368192) (xy 376.080528 -181.35092) (xy 376.074178 -181.343808)
			(xy 376.055879 -181.322726) (xy 376.025055 -181.276182) (xy 376.001344 -181.225643) (xy 375.985253 -181.172188)
			(xy 375.977124 -181.116958) (xy 375.976642 -181.089046) (xy 375.976642 -181.083204) (xy 375.976359 -181.073087)
			(xy 375.968904 -181.05429) (xy 375.954786 -181.039813) (xy 375.945654 -181.035452) (xy 375.85904 -180.998876)
			(xy 375.849609 -180.995338) (xy 375.829487 -180.995158) (xy 375.810852 -181.002754) (xy 375.803414 -181.009544)
			(xy 375.581418 -181.231286) (xy 375.574594 -181.238699) (xy 375.566864 -181.257288) (xy 375.566432 -181.267354)
			(xy 375.566432 -182.230776) (xy 378.653548 -182.230776) (xy 378.654049 -182.203203) (xy 378.661992 -182.148631)
			(xy 378.677709 -182.095771) (xy 378.700872 -182.045724) (xy 378.730999 -181.999534) (xy 378.767463 -181.958162)
			(xy 378.788168 -181.939946) (xy 378.796234 -181.932383) (xy 378.805591 -181.912377) (xy 378.806202 -181.901338)
			(xy 378.806202 -181.823614) (xy 378.805625 -181.812566) (xy 378.796266 -181.792545) (xy 378.788168 -181.785006)
			(xy 378.76745 -181.766802) (xy 378.730982 -181.725431) (xy 378.700851 -181.679239) (xy 378.677687 -181.62919)
			(xy 378.661972 -181.576327) (xy 378.654033 -181.521751) (xy 378.653548 -181.494176) (xy 378.654063 -181.465222)
			(xy 378.662824 -181.40798) (xy 378.680128 -181.352717) (xy 378.705578 -181.3007) (xy 378.738589 -181.253122)
			(xy 378.778405 -181.211074) (xy 378.824113 -181.175519) (xy 378.849128 -181.160928) (xy 378.858802 -181.154767)
			(xy 378.871996 -181.136046) (xy 378.874528 -181.12486) (xy 378.889514 -181.034944) (xy 378.883164 -181.0131)
			(xy 378.87529 -181.004464) (xy 378.857463 -180.983825) (xy 378.827355 -180.938354) (xy 378.804192 -180.888983)
			(xy 378.788467 -180.836764) (xy 378.780517 -180.782811) (xy 378.78004 -180.755544) (xy 378.780575 -180.728929)
			(xy 378.788144 -180.676241) (xy 378.803135 -180.625165) (xy 378.825241 -180.576743) (xy 378.854014 -180.531961)
			(xy 378.888867 -180.491728) (xy 378.929092 -180.456866) (xy 378.973868 -180.428083) (xy 379.022285 -180.405965)
			(xy 379.073356 -180.390962) (xy 379.126043 -180.383381) (xy 379.152658 -180.382926) (xy 379.17908 -180.383368)
			(xy 379.231396 -180.390824) (xy 379.282134 -180.405594) (xy 379.330278 -180.427381) (xy 379.374862 -180.455748)
			(xy 379.395228 -180.472588) (xy 379.402086 -180.47843) (xy 379.419104 -180.48478) (xy 379.503432 -180.48478)
			(xy 379.52045 -180.47843) (xy 379.527308 -180.472588) (xy 379.547674 -180.455749) (xy 379.59226 -180.427384)
			(xy 379.640404 -180.405597) (xy 379.691141 -180.390826) (xy 379.743456 -180.383366) (xy 379.7963 -180.383366)
			(xy 379.848615 -180.390826) (xy 379.899352 -180.405597) (xy 379.947496 -180.427384) (xy 379.992082 -180.455749)
			(xy 380.012448 -180.472588) (xy 380.019306 -180.47843) (xy 380.036324 -180.48478) (xy 380.120652 -180.48478)
			(xy 380.13767 -180.47843) (xy 380.144528 -180.472588) (xy 380.164882 -180.455735) (xy 380.209475 -180.427383)
			(xy 380.257623 -180.405606) (xy 380.308362 -180.390842) (xy 380.360676 -180.383385) (xy 380.387098 -180.382926)
			(xy 380.414988 -180.383333) (xy 380.470145 -180.391646) (xy 380.523448 -180.408088) (xy 380.573704 -180.43229)
			(xy 380.619792 -180.463712) (xy 380.660682 -180.501652) (xy 380.695461 -180.545262) (xy 380.723351 -180.59357)
			(xy 380.74373 -180.645494) (xy 380.756142 -180.699876) (xy 380.760311 -180.7555) (xy 380.756142 -180.811124)
			(xy 380.74373 -180.865506) (xy 380.723351 -180.91743) (xy 380.695461 -180.965738) (xy 380.660682 -181.009348)
			(xy 380.619792 -181.047288) (xy 380.573704 -181.07871) (xy 380.523448 -181.102912) (xy 380.470145 -181.119354)
			(xy 380.414988 -181.127667) (xy 380.387098 -181.128162) (xy 380.360677 -181.127691) (xy 380.308363 -181.120242)
			(xy 380.257625 -181.105479) (xy 380.20948 -181.083699) (xy 380.164894 -181.055337) (xy 380.144528 -181.0385)
			(xy 380.13767 -181.032658) (xy 380.120652 -181.026308) (xy 380.036324 -181.026308) (xy 380.019306 -181.032658)
			(xy 380.012448 -181.0385) (xy 379.992082 -181.055339) (xy 379.947496 -181.083704) (xy 379.899352 -181.105491)
			(xy 379.848615 -181.120262) (xy 379.7963 -181.127722) (xy 379.743456 -181.127722) (xy 379.691141 -181.120262)
			(xy 379.640404 -181.105491) (xy 379.59226 -181.083704) (xy 379.547674 -181.055339) (xy 379.527308 -181.0385)
			(xy 379.52045 -181.032658) (xy 379.503432 -181.026308) (xy 379.419104 -181.026308) (xy 379.402086 -181.032658)
			(xy 379.395228 -181.0385) (xy 379.382014 -181.04952) (xy 379.353903 -181.069365) (xy 379.339094 -181.078124)
			(xy 379.33884 -181.078378) (xy 379.329331 -181.084683) (xy 379.316532 -181.103532) (xy 379.314202 -181.1147)
			(xy 379.300486 -181.20487) (xy 379.307344 -181.226714) (xy 379.315218 -181.235096) (xy 379.334155 -181.256385)
			(xy 379.366166 -181.303519) (xy 379.390819 -181.354885) (xy 379.407566 -181.409345) (xy 379.416035 -181.465688)
			(xy 379.416564 -181.494176) (xy 379.416094 -181.521751) (xy 379.408144 -181.576324) (xy 379.392421 -181.629184)
			(xy 379.369252 -181.67923) (xy 379.339119 -181.72542) (xy 379.302651 -181.766791) (xy 379.281944 -181.785006)
			(xy 379.273857 -181.79255) (xy 379.264512 -181.81257) (xy 379.26391 -181.823614) (xy 379.26391 -181.901338)
			(xy 379.26451 -181.912383) (xy 379.273852 -181.932405) (xy 379.281944 -181.939946) (xy 379.302641 -181.958172)
			(xy 379.339111 -181.999539) (xy 379.369243 -182.045726) (xy 379.392411 -182.095771) (xy 379.408131 -182.14863)
			(xy 379.416076 -182.203202) (xy 379.416564 -182.230776) (xy 379.416078 -182.258027) (xy 379.408322 -182.311975)
			(xy 379.392967 -182.36427) (xy 379.370325 -182.413847) (xy 379.340859 -182.459697) (xy 379.305168 -182.500888)
			(xy 379.263977 -182.536579) (xy 379.218127 -182.566045) (xy 379.16855 -182.588687) (xy 379.116255 -182.604042)
			(xy 379.062307 -182.611798) (xy 379.007805 -182.611798) (xy 378.953857 -182.604042) (xy 378.901562 -182.588687)
			(xy 378.851985 -182.566045) (xy 378.806135 -182.536579) (xy 378.764944 -182.500888) (xy 378.729253 -182.459697)
			(xy 378.699787 -182.413847) (xy 378.677145 -182.36427) (xy 378.66179 -182.311975) (xy 378.654034 -182.258027)
			(xy 378.653548 -182.230776) (xy 375.566432 -182.230776) (xy 375.566432 -194.637406) (xy 375.567702 -194.64274)
			(xy 375.571733 -194.66269) (xy 375.576063 -194.703161) (xy 375.576338 -194.723512) (xy 375.575846 -194.751423)
			(xy 375.56771 -194.806648) (xy 375.551614 -194.860099) (xy 375.527901 -194.910634) (xy 375.497078 -194.957174)
			(xy 375.478802 -194.978274) (xy 375.472762 -194.98559) (xy 375.466094 -195.003335) (xy 375.465848 -195.012818)
			(xy 375.46661 -195.081398) (xy 375.467083 -195.090821) (xy 375.474141 -195.108307) (xy 375.480326 -195.115434)
			(xy 375.499512 -195.136741) (xy 375.531918 -195.184041) (xy 375.556883 -195.235657) (xy 375.573846 -195.290426)
			(xy 375.582426 -195.347116) (xy 375.582942 -195.375784) (xy 375.582481 -195.403155) (xy 375.574664 -195.457334)
			(xy 375.559174 -195.509838) (xy 375.536331 -195.559585) (xy 375.506605 -195.605551) (xy 375.488962 -195.626482)
			(xy 375.488708 -195.626736) (xy 375.483143 -195.633837) (xy 375.476883 -195.650743) (xy 375.476516 -195.659756)
			(xy 375.476516 -195.726812) (xy 375.476864 -195.73583) (xy 375.483117 -195.752747) (xy 375.488708 -195.759832)
			(xy 375.488962 -195.759832) (xy 375.488962 -195.760086) (xy 375.506587 -195.781031) (xy 375.536314 -195.826997)
			(xy 375.559161 -195.876741) (xy 375.574659 -195.929241) (xy 375.582489 -195.983418) (xy 375.582491 -196.038158)
			(xy 375.574664 -196.092335) (xy 375.559169 -196.144837) (xy 375.536325 -196.194582) (xy 375.506602 -196.24055)
			(xy 375.488962 -196.261482) (xy 375.488708 -196.261736) (xy 375.483143 -196.268837) (xy 375.476883 -196.285743)
			(xy 375.476516 -196.294756) (xy 375.476516 -196.361812) (xy 375.476864 -196.37083) (xy 375.483117 -196.387747)
			(xy 375.488708 -196.394832) (xy 375.488962 -196.394832) (xy 375.488962 -196.395086) (xy 375.506587 -196.416031)
			(xy 375.536314 -196.461997) (xy 375.559161 -196.511741) (xy 375.574659 -196.564241) (xy 375.582489 -196.618418)
			(xy 375.582491 -196.673158) (xy 375.574664 -196.727335) (xy 375.559169 -196.779837) (xy 375.536325 -196.829582)
			(xy 375.506602 -196.87555) (xy 375.488962 -196.896482) (xy 375.488708 -196.896736) (xy 375.483143 -196.903837)
			(xy 375.476883 -196.920743) (xy 375.476516 -196.929756) (xy 375.476516 -196.996812) (xy 375.476864 -197.00583)
			(xy 375.483117 -197.022747) (xy 375.488708 -197.029832) (xy 375.488962 -197.029832) (xy 375.488962 -197.030086)
			(xy 375.506587 -197.051031) (xy 375.536314 -197.096997) (xy 375.559161 -197.146741) (xy 375.574659 -197.199241)
			(xy 375.582489 -197.253418) (xy 375.58249 -197.284594) (xy 377.93041 -197.284594) (xy 377.93041 -197.28434)
			(xy 377.930897 -197.25697) (xy 377.938709 -197.202792) (xy 377.954193 -197.150289) (xy 377.977031 -197.100542)
			(xy 378.006751 -197.054574) (xy 378.02439 -197.033642) (xy 378.024644 -197.033388) (xy 378.030247 -197.026313)
			(xy 378.036483 -197.009387) (xy 378.036836 -197.000368) (xy 378.036836 -196.933312) (xy 378.036465 -196.924297)
			(xy 378.030226 -196.90738) (xy 378.024644 -196.900292) (xy 378.02439 -196.900292) (xy 378.02439 -196.900038)
			(xy 378.00679 -196.879073) (xy 377.977066 -196.83311) (xy 377.954221 -196.783369) (xy 377.938723 -196.730872)
			(xy 377.930892 -196.676698) (xy 377.930887 -196.621962) (xy 377.93871 -196.567787) (xy 377.9542 -196.515288)
			(xy 377.977037 -196.465543) (xy 378.006754 -196.419575) (xy 378.02439 -196.398642) (xy 378.024644 -196.398388)
			(xy 378.030247 -196.391313) (xy 378.036483 -196.374387) (xy 378.036836 -196.365368) (xy 378.036836 -196.298312)
			(xy 378.036465 -196.289297) (xy 378.030226 -196.27238) (xy 378.024644 -196.265292) (xy 378.02439 -196.265292)
			(xy 378.02439 -196.265038) (xy 378.00679 -196.244073) (xy 377.977066 -196.19811) (xy 377.954221 -196.148369)
			(xy 377.938723 -196.095872) (xy 377.930892 -196.041698) (xy 377.930887 -195.986962) (xy 377.93871 -195.932787)
			(xy 377.9542 -195.880288) (xy 377.977037 -195.830543) (xy 378.006754 -195.784575) (xy 378.02439 -195.763642)
			(xy 378.024644 -195.763388) (xy 378.030247 -195.756313) (xy 378.036483 -195.739387) (xy 378.036836 -195.730368)
			(xy 378.036836 -195.663312) (xy 378.036465 -195.654297) (xy 378.030226 -195.63738) (xy 378.024644 -195.630292)
			(xy 378.02439 -195.630292) (xy 378.02439 -195.630038) (xy 378.006754 -195.609104) (xy 377.977042 -195.563131)
			(xy 377.954205 -195.513384) (xy 377.938714 -195.460884) (xy 377.930885 -195.406709) (xy 377.93041 -195.37934)
			(xy 377.930926 -195.350851) (xy 377.93939 -195.294504) (xy 377.956136 -195.240042) (xy 377.980792 -195.188675)
			(xy 378.01281 -195.141543) (xy 378.031756 -195.12026) (xy 378.03836 -195.113148) (xy 378.045218 -195.095622)
			(xy 378.045218 -195.00723) (xy 378.03836 -194.989704) (xy 378.031756 -194.982592) (xy 378.012809 -194.961311)
			(xy 377.9808 -194.914175) (xy 377.95615 -194.862806) (xy 377.939405 -194.808345) (xy 377.930938 -194.752001)
			(xy 377.93041 -194.723512) (xy 377.930867 -194.696259) (xy 377.938622 -194.642307) (xy 377.953978 -194.590007)
			(xy 377.97662 -194.540426) (xy 378.006089 -194.494572) (xy 378.041783 -194.453379) (xy 378.082977 -194.417685)
			(xy 378.128831 -194.388217) (xy 378.178413 -194.365576) (xy 378.230712 -194.350221) (xy 378.284665 -194.342466)
			(xy 378.311918 -194.342004) (xy 378.339289 -194.342459) (xy 378.393468 -194.350279) (xy 378.445972 -194.365771)
			(xy 378.495718 -194.388615) (xy 378.541685 -194.418342) (xy 378.562616 -194.435984) (xy 378.56287 -194.436238)
			(xy 378.569958 -194.441822) (xy 378.586874 -194.448069) (xy 378.59589 -194.44843) (xy 378.662946 -194.44843)
			(xy 378.671959 -194.448041) (xy 378.688876 -194.441815) (xy 378.695966 -194.436238) (xy 378.695966 -194.435984)
			(xy 378.69622 -194.435984) (xy 378.717153 -194.418343) (xy 378.763121 -194.388619) (xy 378.812867 -194.365773)
			(xy 378.865369 -194.350277) (xy 378.919547 -194.342448) (xy 378.974289 -194.342448) (xy 379.028467 -194.350277)
			(xy 379.080969 -194.365773) (xy 379.130715 -194.388619) (xy 379.176683 -194.418343) (xy 379.197616 -194.435984)
			(xy 379.19787 -194.436238) (xy 379.204958 -194.441822) (xy 379.221874 -194.448069) (xy 379.23089 -194.44843)
			(xy 379.297946 -194.44843) (xy 379.306959 -194.448041) (xy 379.323876 -194.441815) (xy 379.330966 -194.436238)
			(xy 379.330966 -194.435984) (xy 379.33122 -194.435984) (xy 379.352169 -194.418366) (xy 379.398138 -194.388652)
			(xy 379.447881 -194.365812) (xy 379.500378 -194.350316) (xy 379.55455 -194.342482) (xy 379.581918 -194.342004)
			(xy 379.60917 -194.342461) (xy 379.66312 -194.35022) (xy 379.715416 -194.365578) (xy 379.764994 -194.388222)
			(xy 379.810845 -194.417692) (xy 379.852035 -194.453386) (xy 379.887726 -194.494579) (xy 379.917192 -194.540433)
			(xy 379.939832 -194.590013) (xy 379.955186 -194.64231) (xy 379.962941 -194.69626) (xy 379.963426 -194.723512)
			(xy 381.94615 -194.723512) (xy 381.946689 -194.696263) (xy 381.954443 -194.642319) (xy 381.969795 -194.590028)
			(xy 381.992431 -194.540454) (xy 382.021892 -194.494606) (xy 382.057578 -194.453416) (xy 382.098762 -194.417725)
			(xy 382.144607 -194.388257) (xy 382.194178 -194.365613) (xy 382.246467 -194.350255) (xy 382.300409 -194.342493)
			(xy 382.327658 -194.342004) (xy 382.355027 -194.342494) (xy 382.409205 -194.350306) (xy 382.461708 -194.365789)
			(xy 382.511456 -194.388626) (xy 382.557424 -194.418345) (xy 382.578356 -194.435984) (xy 382.57861 -194.436238)
			(xy 382.585686 -194.441839) (xy 382.602611 -194.448076) (xy 382.61163 -194.44843) (xy 382.678686 -194.44843)
			(xy 382.687701 -194.44806) (xy 382.704618 -194.441821) (xy 382.711706 -194.436238) (xy 382.711706 -194.435984)
			(xy 382.71196 -194.435984) (xy 382.732893 -194.418343) (xy 382.778861 -194.388619) (xy 382.828607 -194.365773)
			(xy 382.881109 -194.350277) (xy 382.935287 -194.342448) (xy 382.990029 -194.342448) (xy 383.044207 -194.350277)
			(xy 383.096709 -194.365773) (xy 383.146455 -194.388619) (xy 383.192423 -194.418343) (xy 383.213356 -194.435984)
			(xy 383.21361 -194.436238) (xy 383.220686 -194.441839) (xy 383.237611 -194.448076) (xy 383.24663 -194.44843)
			(xy 383.313686 -194.44843) (xy 383.322701 -194.44806) (xy 383.339618 -194.441821) (xy 383.346706 -194.436238)
			(xy 383.34696 -194.435984) (xy 383.370452 -194.416362) (xy 383.422432 -194.384049) (xy 383.478893 -194.360424)
			(xy 383.508504 -194.352672) (xy 383.509012 -194.352672) (xy 383.515563 -194.350718) (xy 383.527406 -194.343899)
			(xy 383.53238 -194.33921) (xy 383.590038 -194.281552) (xy 383.596795 -194.274094) (xy 383.604518 -194.255534)
			(xy 383.605024 -194.245484) (xy 383.605024 -188.936884) (xy 383.604627 -188.926811) (xy 383.596888 -188.908213)
			(xy 383.590038 -188.900816) (xy 383.388108 -188.698886) (xy 383.370808 -188.6809) (xy 383.341485 -188.640521)
			(xy 383.318839 -188.596054) (xy 383.303427 -188.548591) (xy 383.295629 -188.499301) (xy 383.295144 -188.47435)
			(xy 383.295144 -181.153054) (xy 383.295631 -181.128105) (xy 383.303448 -181.078822) (xy 383.318868 -181.031365)
			(xy 383.341512 -180.986899) (xy 383.370823 -180.946517) (xy 383.388108 -180.928518) (xy 383.905252 -180.411374)
			(xy 383.912144 -180.403718) (xy 383.919828 -180.384632) (xy 383.91944 -180.36406) (xy 383.915666 -180.354478)
			(xy 383.869946 -180.253386) (xy 383.842768 -180.23713) (xy 383.82702 -180.238146) (xy 383.802636 -180.238908)
			(xy 383.77538 -180.238484) (xy 383.721422 -180.230731) (xy 383.669117 -180.215378) (xy 383.619529 -180.192737)
			(xy 383.573668 -180.163269) (xy 383.532468 -180.127575) (xy 383.496767 -180.08638) (xy 383.467292 -180.040524)
			(xy 383.444643 -179.990939) (xy 383.429282 -179.938637) (xy 383.421521 -179.88468) (xy 383.421517 -179.830168)
			(xy 383.429272 -179.77621) (xy 383.444627 -179.723906) (xy 383.467269 -179.674319) (xy 383.496738 -179.628459)
			(xy 383.532434 -179.587259) (xy 383.57363 -179.55156) (xy 383.619487 -179.522086) (xy 383.669072 -179.499439)
			(xy 383.721375 -179.48408) (xy 383.775332 -179.47632) (xy 383.829844 -179.476318) (xy 383.883801 -179.484074)
			(xy 383.936106 -179.499431) (xy 383.985692 -179.522075) (xy 384.031551 -179.551545) (xy 384.072749 -179.587242)
			(xy 384.108447 -179.628439) (xy 384.137919 -179.674297) (xy 384.160565 -179.723883) (xy 384.175923 -179.776187)
			(xy 384.183681 -179.830144) (xy 384.184144 -179.8574) (xy 384.184144 -179.857654) (xy 384.183523 -179.888743)
			(xy 384.173438 -179.950097) (xy 384.153513 -180.008996) (xy 384.13944 -180.036724) (xy 384.131566 -180.05171)
			(xy 384.136392 -180.08473) (xy 384.14833 -180.096668) (xy 384.155742 -180.103352) (xy 384.174175 -180.110949)
			(xy 384.194113 -180.110949) (xy 384.212546 -180.103352) (xy 384.219958 -180.096668) (xy 384.283966 -180.03266)
			(xy 384.290811 -180.025264) (xy 384.298529 -180.006662) (xy 384.298952 -179.996592) (xy 384.298952 -179.356512)
			(xy 384.279648 -179.330096) (xy 384.2639 -179.325016) (xy 384.238698 -179.316326) (xy 384.190786 -179.292959)
			(xy 384.146592 -179.263151) (xy 384.106978 -179.227481) (xy 384.072714 -179.186644) (xy 384.044468 -179.141436)
			(xy 384.02279 -179.092736) (xy 384.008101 -179.041493) (xy 384.000688 -178.988704) (xy 384.000248 -178.96205)
			(xy 384.000802 -178.9348) (xy 384.008551 -178.880855) (xy 384.023898 -178.828561) (xy 384.046532 -178.778984)
			(xy 384.07599 -178.733133) (xy 384.111675 -178.691941) (xy 384.152858 -178.656247) (xy 384.198702 -178.626777)
			(xy 384.248273 -178.604131) (xy 384.300563 -178.588771) (xy 384.354506 -178.581008) (xy 384.381756 -178.580542)
			(xy 384.41006 -178.581111) (xy 384.466051 -178.589449) (xy 384.520192 -178.605978) (xy 384.571293 -178.630334)
			(xy 384.618228 -178.661981) (xy 384.659966 -178.700223) (xy 384.695587 -178.744218) (xy 384.724309 -178.792999)
			(xy 384.745498 -178.845492) (xy 384.752596 -178.872896) (xy 384.752596 -178.873404) (xy 384.754539 -178.879959)
			(xy 384.761365 -178.8918) (xy 384.766058 -178.896772) (xy 384.84175 -178.972464) (xy 384.859064 -178.990481)
			(xy 384.888434 -179.030903) (xy 384.91113 -179.075416) (xy 384.926597 -179.122928) (xy 384.934453 -179.172272)
			(xy 384.934968 -179.197254) (xy 384.934968 -180.149246) (xy 384.93449 -180.174234) (xy 384.92667 -180.223595)
			(xy 384.911215 -180.271121) (xy 384.888506 -180.31564) (xy 384.859105 -180.356052) (xy 384.84175 -180.374036)
			(xy 384.681476 -180.53431) (xy 384.674715 -180.541766) (xy 384.667139 -180.560398) (xy 384.66728 -180.580509)
			(xy 384.670808 -180.589936) (xy 384.707384 -180.67655) (xy 384.708111 -180.678074) (xy 385.31673 -180.678074)
			(xy 385.317236 -180.650501) (xy 385.325179 -180.595929) (xy 385.340895 -180.54307) (xy 385.364058 -180.493023)
			(xy 385.394184 -180.446833) (xy 385.430645 -180.40546) (xy 385.45135 -180.387244) (xy 385.459414 -180.379679)
			(xy 385.468772 -180.359675) (xy 385.469384 -180.348636) (xy 385.469384 -180.270912) (xy 385.468814 -180.259863)
			(xy 385.459451 -180.239842) (xy 385.45135 -180.232304) (xy 385.430628 -180.214105) (xy 385.39416 -180.172733)
			(xy 385.364031 -180.12654) (xy 385.340867 -180.07649) (xy 385.325153 -180.023625) (xy 385.317215 -179.969049)
			(xy 385.31673 -179.941474) (xy 385.317236 -179.913901) (xy 385.325179 -179.859329) (xy 385.340895 -179.80647)
			(xy 385.364058 -179.756423) (xy 385.394184 -179.710233) (xy 385.430645 -179.66886) (xy 385.45135 -179.650644)
			(xy 385.459414 -179.643079) (xy 385.468772 -179.623075) (xy 385.469384 -179.612036) (xy 385.469384 -179.534312)
			(xy 385.468814 -179.523263) (xy 385.459451 -179.503242) (xy 385.45135 -179.495704) (xy 385.430628 -179.477505)
			(xy 385.39416 -179.436133) (xy 385.364031 -179.38994) (xy 385.340867 -179.33989) (xy 385.325153 -179.287025)
			(xy 385.317215 -179.232449) (xy 385.31673 -179.204874) (xy 385.317131 -179.177619) (xy 385.324892 -179.123664)
			(xy 385.340254 -179.071362) (xy 385.362902 -179.021779) (xy 385.392376 -178.975924) (xy 385.428076 -178.934731)
			(xy 385.469276 -178.899038) (xy 385.515136 -178.869571) (xy 385.564722 -178.846931) (xy 385.617026 -178.831579)
			(xy 385.670983 -178.823826) (xy 385.698238 -178.823366) (xy 385.726093 -178.82388) (xy 385.781208 -178.832008)
			(xy 385.834557 -178.848057) (xy 385.885009 -178.871686) (xy 385.931492 -178.902394) (xy 385.973021 -178.93953)
			(xy 386.008714 -178.982305) (xy 386.037815 -179.029811) (xy 386.059705 -179.081041) (xy 386.0673 -179.107846)
			(xy 386.069586 -179.116736) (xy 386.080254 -179.131976) (xy 386.152136 -179.179728) (xy 386.17017 -179.183792)
			(xy 386.179314 -179.182522) (xy 386.192331 -179.180854) (xy 386.218515 -179.179073) (xy 386.231638 -179.178966)
			(xy 386.245787 -179.179056) (xy 386.27401 -179.181093) (xy 386.288026 -179.18303) (xy 386.297932 -179.184554)
			(xy 386.317744 -179.179728) (xy 386.392166 -179.123848) (xy 386.402326 -179.106322) (xy 386.403596 -179.096162)
			(xy 386.407677 -179.069007) (xy 386.42265 -179.016176) (xy 386.445041 -178.966037) (xy 386.474389 -178.919625)
			(xy 386.510088 -178.877901) (xy 386.551398 -178.841724) (xy 386.597468 -178.811843) (xy 386.647346 -178.788875)
			(xy 386.700001 -178.773295) (xy 386.754346 -178.765423) (xy 386.781802 -178.764946) (xy 386.809051 -178.765476)
			(xy 386.862995 -178.773231) (xy 386.915286 -178.788584) (xy 386.96486 -178.811222) (xy 387.010708 -178.840685)
			(xy 387.051897 -178.876371) (xy 387.087589 -178.917556) (xy 387.117056 -178.963401) (xy 387.1397 -179.012973)
			(xy 387.155059 -179.065262) (xy 387.162821 -179.119205) (xy 387.16331 -179.146454) (xy 387.162809 -179.174027)
			(xy 387.154863 -179.228598) (xy 387.139145 -179.281457) (xy 387.115982 -179.331503) (xy 387.085855 -179.377694)
			(xy 387.049394 -179.419067) (xy 387.02869 -179.437284) (xy 387.02062 -179.444844) (xy 387.011263 -179.464852)
			(xy 387.010656 -179.475892) (xy 387.010656 -179.553616) (xy 387.011253 -179.564662) (xy 387.020596 -179.584685)
			(xy 387.02869 -179.592224) (xy 387.049414 -179.610421) (xy 387.085884 -179.651793) (xy 387.116014 -179.697985)
			(xy 387.139178 -179.748036) (xy 387.154892 -179.800901) (xy 387.162827 -179.855478) (xy 387.162861 -179.8574)
			(xy 391.751818 -179.8574) (xy 391.755889 -179.801778) (xy 391.768015 -179.747341) (xy 391.787938 -179.69525)
			(xy 391.815234 -179.646615) (xy 391.84932 -179.602472) (xy 391.889469 -179.563763) (xy 391.934827 -179.531312)
			(xy 391.984427 -179.505811) (xy 392.037211 -179.487804) (xy 392.092054 -179.477674) (xy 392.147788 -179.475637)
			(xy 392.203225 -179.481737) (xy 392.257182 -179.495843) (xy 392.308511 -179.517655) (xy 392.356117 -179.546709)
			(xy 392.398985 -179.582384) (xy 392.436202 -179.623921) (xy 392.466975 -179.670434) (xy 392.490647 -179.720931)
			(xy 392.506715 -179.774338) (xy 392.514835 -179.829514) (xy 392.515344 -179.8574) (xy 392.514835 -179.885286)
			(xy 392.506715 -179.940462) (xy 392.490647 -179.993869) (xy 392.466975 -180.044366) (xy 392.436202 -180.090879)
			(xy 392.398985 -180.132416) (xy 392.356117 -180.168091) (xy 392.308511 -180.197145) (xy 392.257182 -180.218957)
			(xy 392.203225 -180.233063) (xy 392.147788 -180.239163) (xy 392.092054 -180.237126) (xy 392.037211 -180.226996)
			(xy 391.984427 -180.208989) (xy 391.934827 -180.183488) (xy 391.889469 -180.151037) (xy 391.84932 -180.112328)
			(xy 391.815234 -180.068185) (xy 391.787938 -180.01955) (xy 391.768015 -179.967459) (xy 391.755889 -179.913022)
			(xy 391.751818 -179.8574) (xy 387.162861 -179.8574) (xy 387.16331 -179.883054) (xy 387.162802 -179.910306)
			(xy 387.155051 -179.964255) (xy 387.139701 -180.016552) (xy 387.117064 -180.066132) (xy 387.087601 -180.111985)
			(xy 387.051912 -180.153178) (xy 387.010723 -180.188872) (xy 386.964874 -180.218341) (xy 386.915297 -180.240984)
			(xy 386.863002 -180.256341) (xy 386.809054 -180.264098) (xy 386.781802 -180.264562) (xy 386.781294 -180.264562)
			(xy 386.747512 -180.263038) (xy 386.737352 -180.262022) (xy 386.718048 -180.268118) (xy 386.655056 -180.32095)
			(xy 386.64776 -180.327668) (xy 386.638483 -180.345176) (xy 386.637022 -180.354986) (xy 386.637022 -180.355748)
			(xy 386.634064 -180.383908) (xy 386.620856 -180.438968) (xy 386.599654 -180.49147) (xy 386.570922 -180.540261)
			(xy 386.535292 -180.584267) (xy 386.493547 -180.622521) (xy 386.446606 -180.654184) (xy 386.395499 -180.678558)
			(xy 386.34135 -180.695108) (xy 386.285349 -180.70347) (xy 386.257038 -180.703982) (xy 386.239019 -180.703764)
			(xy 386.203144 -180.700328) (xy 386.18541 -180.697124) (xy 386.175758 -180.695346) (xy 386.156708 -180.698902)
			(xy 386.081778 -180.746908) (xy 386.070348 -180.762656) (xy 386.068062 -180.772054) (xy 386.06069 -180.799106)
			(xy 386.039058 -180.850833) (xy 386.01009 -180.898839) (xy 385.974412 -180.942091) (xy 385.932789 -180.979658)
			(xy 385.886118 -181.010731) (xy 385.835404 -181.034642) (xy 385.781737 -181.050876) (xy 385.726272 -181.059085)
			(xy 385.698238 -181.059582) (xy 385.670985 -181.059109) (xy 385.617033 -181.051357) (xy 385.564734 -181.036004)
			(xy 385.515152 -181.013364) (xy 385.469297 -180.983898) (xy 385.428104 -180.948205) (xy 385.392409 -180.907012)
			(xy 385.362941 -180.861159) (xy 385.3403 -180.811578) (xy 385.324946 -180.759279) (xy 385.317192 -180.705327)
			(xy 385.31673 -180.678074) (xy 384.708111 -180.678074) (xy 384.711744 -180.685691) (xy 384.726201 -180.699849)
			(xy 384.745012 -180.707302) (xy 384.755136 -180.707538) (xy 384.760978 -180.707538) (xy 384.788232 -180.707976)
			(xy 384.842187 -180.715731) (xy 384.894488 -180.731087) (xy 384.944071 -180.75373) (xy 384.989926 -180.7832)
			(xy 385.03112 -180.818897) (xy 385.066814 -180.860093) (xy 385.096282 -180.90595) (xy 385.118922 -180.955535)
			(xy 385.134274 -181.007837) (xy 385.142026 -181.061792) (xy 385.142486 -181.089046) (xy 385.142002 -181.116957)
			(xy 385.133862 -181.172182) (xy 385.117764 -181.225632) (xy 385.09405 -181.276167) (xy 385.063226 -181.322707)
			(xy 385.04495 -181.343808) (xy 385.039044 -181.350978) (xy 385.0324 -181.368309) (xy 385.031996 -181.37759)
			(xy 385.031996 -181.455314) (xy 385.0386 -181.472586) (xy 385.04495 -181.479698) (xy 385.063209 -181.500813)
			(xy 385.094038 -181.547348) (xy 385.117756 -181.597879) (xy 385.133857 -181.651326) (xy 385.141997 -181.70655)
			(xy 385.142486 -181.73446) (xy 385.142 -181.761711) (xy 385.134244 -181.815659) (xy 385.118889 -181.867954)
			(xy 385.096247 -181.917531) (xy 385.066781 -181.963381) (xy 385.03109 -182.004572) (xy 384.989899 -182.040263)
			(xy 384.944049 -182.069729) (xy 384.894472 -182.092371) (xy 384.842177 -182.107726) (xy 384.788229 -182.115482)
			(xy 384.733727 -182.115482) (xy 384.679779 -182.107726) (xy 384.627484 -182.092371) (xy 384.577907 -182.069729)
			(xy 384.532057 -182.040263) (xy 384.490866 -182.004572) (xy 384.455175 -181.963381) (xy 384.425709 -181.917531)
			(xy 384.403067 -181.867954) (xy 384.387712 -181.815659) (xy 384.379956 -181.761711) (xy 384.37947 -181.73446)
			(xy 384.379944 -181.706549) (xy 384.388084 -181.651322) (xy 384.404184 -181.597871) (xy 384.427901 -181.547337)
			(xy 384.458728 -181.500798) (xy 384.477006 -181.479698) (xy 384.482905 -181.472522) (xy 384.489555 -181.455196)
			(xy 384.48996 -181.445916) (xy 384.48996 -181.368192) (xy 384.483356 -181.35092) (xy 384.477006 -181.343808)
			(xy 384.458711 -181.322722) (xy 384.427886 -181.27618) (xy 384.404174 -181.225642) (xy 384.388081 -181.172188)
			(xy 384.379952 -181.116958) (xy 384.37947 -181.089046) (xy 384.37947 -181.083204) (xy 384.379228 -181.073082)
			(xy 384.371762 -181.054278) (xy 384.357624 -181.039805) (xy 384.348482 -181.035452) (xy 384.261868 -180.998876)
			(xy 384.252457 -180.995275) (xy 384.232319 -180.995119) (xy 384.213678 -181.002741) (xy 384.206242 -181.009544)
			(xy 383.945638 -181.269894) (xy 383.938813 -181.277307) (xy 383.931084 -181.295896) (xy 383.930652 -181.305962)
			(xy 383.930652 -182.230776) (xy 386.984748 -182.230776) (xy 386.985249 -182.203203) (xy 386.993192 -182.148631)
			(xy 387.008909 -182.095771) (xy 387.032072 -182.045724) (xy 387.062199 -181.999534) (xy 387.098663 -181.958162)
			(xy 387.119368 -181.939946) (xy 387.127434 -181.932383) (xy 387.136791 -181.912377) (xy 387.137402 -181.901338)
			(xy 387.137402 -181.823614) (xy 387.136825 -181.812566) (xy 387.127466 -181.792545) (xy 387.119368 -181.785006)
			(xy 387.09865 -181.766802) (xy 387.062182 -181.725431) (xy 387.032051 -181.679239) (xy 387.008887 -181.62919)
			(xy 386.993172 -181.576327) (xy 386.985233 -181.521751) (xy 386.984748 -181.494176) (xy 386.985263 -181.465222)
			(xy 386.994024 -181.40798) (xy 387.011328 -181.352717) (xy 387.036778 -181.3007) (xy 387.069789 -181.253122)
			(xy 387.109605 -181.211074) (xy 387.155313 -181.175519) (xy 387.180328 -181.160928) (xy 387.190002 -181.154767)
			(xy 387.203196 -181.136046) (xy 387.205728 -181.12486) (xy 387.220714 -181.034944) (xy 387.214364 -181.0131)
			(xy 387.20649 -181.004464) (xy 387.188663 -180.983825) (xy 387.158555 -180.938354) (xy 387.135392 -180.888983)
			(xy 387.119667 -180.836764) (xy 387.111717 -180.782811) (xy 387.11124 -180.755544) (xy 387.111775 -180.728929)
			(xy 387.119344 -180.676241) (xy 387.134335 -180.625165) (xy 387.156441 -180.576743) (xy 387.185214 -180.531961)
			(xy 387.220067 -180.491728) (xy 387.260292 -180.456866) (xy 387.305068 -180.428083) (xy 387.353485 -180.405965)
			(xy 387.404556 -180.390962) (xy 387.457243 -180.383381) (xy 387.483858 -180.382926) (xy 387.51028 -180.383368)
			(xy 387.562596 -180.390824) (xy 387.613334 -180.405594) (xy 387.661478 -180.427381) (xy 387.706062 -180.455748)
			(xy 387.726428 -180.472588) (xy 387.733286 -180.47843) (xy 387.750304 -180.48478) (xy 387.834632 -180.48478)
			(xy 387.85165 -180.47843) (xy 387.858508 -180.472588) (xy 387.878874 -180.455749) (xy 387.92346 -180.427384)
			(xy 387.971604 -180.405597) (xy 388.022341 -180.390826) (xy 388.074656 -180.383366) (xy 388.1275 -180.383366)
			(xy 388.179815 -180.390826) (xy 388.230552 -180.405597) (xy 388.278696 -180.427384) (xy 388.323282 -180.455749)
			(xy 388.343648 -180.472588) (xy 388.350506 -180.47843) (xy 388.367524 -180.48478) (xy 388.451852 -180.48478)
			(xy 388.46887 -180.47843) (xy 388.475728 -180.472588) (xy 388.496082 -180.455735) (xy 388.540675 -180.427383)
			(xy 388.588823 -180.405606) (xy 388.639562 -180.390842) (xy 388.691876 -180.383385) (xy 388.718298 -180.382926)
			(xy 388.746188 -180.383333) (xy 388.801345 -180.391646) (xy 388.854648 -180.408088) (xy 388.904904 -180.43229)
			(xy 388.950992 -180.463712) (xy 388.991882 -180.501652) (xy 389.026661 -180.545262) (xy 389.054551 -180.59357)
			(xy 389.07493 -180.645494) (xy 389.087342 -180.699876) (xy 389.091511 -180.7555) (xy 389.087342 -180.811124)
			(xy 389.07493 -180.865506) (xy 389.054551 -180.91743) (xy 389.026661 -180.965738) (xy 388.991882 -181.009348)
			(xy 388.950992 -181.047288) (xy 388.904904 -181.07871) (xy 388.854648 -181.102912) (xy 388.801345 -181.119354)
			(xy 388.746188 -181.127667) (xy 388.718298 -181.128162) (xy 388.691877 -181.127691) (xy 388.639563 -181.120242)
			(xy 388.588825 -181.105479) (xy 388.54068 -181.083699) (xy 388.496094 -181.055337) (xy 388.475728 -181.0385)
			(xy 388.46887 -181.032658) (xy 388.451852 -181.026308) (xy 388.367524 -181.026308) (xy 388.350506 -181.032658)
			(xy 388.343648 -181.0385) (xy 388.323282 -181.055339) (xy 388.278696 -181.083704) (xy 388.230552 -181.105491)
			(xy 388.179815 -181.120262) (xy 388.1275 -181.127722) (xy 388.074656 -181.127722) (xy 388.022341 -181.120262)
			(xy 387.971604 -181.105491) (xy 387.92346 -181.083704) (xy 387.878874 -181.055339) (xy 387.858508 -181.0385)
			(xy 387.85165 -181.032658) (xy 387.834632 -181.026308) (xy 387.750304 -181.026308) (xy 387.733286 -181.032658)
			(xy 387.726428 -181.0385) (xy 387.713214 -181.04952) (xy 387.685103 -181.069365) (xy 387.670294 -181.078124)
			(xy 387.67004 -181.078378) (xy 387.660531 -181.084683) (xy 387.647732 -181.103532) (xy 387.645402 -181.1147)
			(xy 387.631686 -181.20487) (xy 387.638544 -181.226714) (xy 387.646418 -181.235096) (xy 387.665355 -181.256385)
			(xy 387.697366 -181.303519) (xy 387.722019 -181.354885) (xy 387.738766 -181.409345) (xy 387.747235 -181.465688)
			(xy 387.747764 -181.494176) (xy 387.747294 -181.521751) (xy 387.739344 -181.576324) (xy 387.723621 -181.629184)
			(xy 387.700452 -181.67923) (xy 387.670319 -181.72542) (xy 387.633851 -181.766791) (xy 387.613144 -181.785006)
			(xy 387.605057 -181.79255) (xy 387.595712 -181.81257) (xy 387.59511 -181.823614) (xy 387.59511 -181.901338)
			(xy 387.59571 -181.912383) (xy 387.605052 -181.932405) (xy 387.613144 -181.939946) (xy 387.633841 -181.958172)
			(xy 387.670311 -181.999539) (xy 387.700443 -182.045726) (xy 387.723611 -182.095771) (xy 387.739331 -182.14863)
			(xy 387.747276 -182.203202) (xy 387.747764 -182.230776) (xy 387.747278 -182.258027) (xy 387.739522 -182.311975)
			(xy 387.724167 -182.36427) (xy 387.701525 -182.413847) (xy 387.672059 -182.459697) (xy 387.636368 -182.500888)
			(xy 387.595177 -182.536579) (xy 387.549327 -182.566045) (xy 387.49975 -182.588687) (xy 387.447455 -182.604042)
			(xy 387.393507 -182.611798) (xy 387.339005 -182.611798) (xy 387.285057 -182.604042) (xy 387.232762 -182.588687)
			(xy 387.183185 -182.566045) (xy 387.137335 -182.536579) (xy 387.096144 -182.500888) (xy 387.060453 -182.459697)
			(xy 387.030987 -182.413847) (xy 387.008345 -182.36427) (xy 386.99299 -182.311975) (xy 386.985234 -182.258027)
			(xy 386.984748 -182.230776) (xy 383.930652 -182.230776) (xy 383.930652 -188.321442) (xy 383.931042 -188.331516)
			(xy 383.938786 -188.350114) (xy 383.945638 -188.35751) (xy 384.147822 -188.55944) (xy 384.16512 -188.577472)
			(xy 384.194493 -188.61789) (xy 384.217193 -188.662399) (xy 384.232663 -188.709907) (xy 384.240524 -188.759249)
			(xy 384.24104 -188.78423) (xy 384.24104 -194.398138) (xy 384.240536 -194.423125) (xy 384.232719 -194.472483)
			(xy 384.217269 -194.520008) (xy 384.194567 -194.564527) (xy 384.165173 -194.604942) (xy 384.147822 -194.622928)
			(xy 383.98196 -194.78879) (xy 383.977256 -194.793756) (xy 383.97042 -194.805595) (xy 383.968498 -194.812158)
			(xy 383.968498 -194.81292) (xy 383.960677 -194.842882) (xy 383.936646 -194.89995) (xy 383.903703 -194.952381)
			(xy 383.883662 -194.975988) (xy 383.877623 -194.98336) (xy 383.871106 -195.001256) (xy 383.870962 -195.010786)
			(xy 383.87274 -195.089526) (xy 383.880106 -195.107052) (xy 383.886964 -195.11391) (xy 383.90698 -195.135409)
			(xy 383.940892 -195.183366) (xy 383.967056 -195.235954) (xy 383.984852 -195.29193) (xy 383.993861 -195.349972)
			(xy 383.994406 -195.37934) (xy 383.993903 -195.406709) (xy 383.986094 -195.460886) (xy 383.970613 -195.513389)
			(xy 383.94778 -195.563136) (xy 383.918063 -195.609105) (xy 383.900426 -195.630038) (xy 383.900172 -195.630292)
			(xy 383.89458 -195.637374) (xy 383.888337 -195.654294) (xy 383.88798 -195.663312) (xy 383.88798 -195.730368)
			(xy 383.888357 -195.739383) (xy 383.894591 -195.7563) (xy 383.900172 -195.763388) (xy 383.900426 -195.763388)
			(xy 383.900426 -195.763642) (xy 383.918108 -195.784542) (xy 383.947835 -195.830514) (xy 383.97068 -195.880266)
			(xy 383.986176 -195.932773) (xy 383.994002 -195.986957) (xy 383.993997 -196.041703) (xy 383.986163 -196.095886)
			(xy 383.970659 -196.148391) (xy 383.947806 -196.198139) (xy 383.918071 -196.244106) (xy 383.900426 -196.265038)
			(xy 383.900172 -196.265292) (xy 383.89458 -196.272374) (xy 383.888337 -196.289294) (xy 383.88798 -196.298312)
			(xy 383.88798 -196.365368) (xy 383.888357 -196.374383) (xy 383.894591 -196.3913) (xy 383.900172 -196.398388)
			(xy 383.900426 -196.398388) (xy 383.900426 -196.398642) (xy 383.918108 -196.419542) (xy 383.947835 -196.465514)
			(xy 383.97068 -196.515266) (xy 383.986176 -196.567773) (xy 383.994002 -196.621957) (xy 383.993997 -196.676703)
			(xy 383.986163 -196.730886) (xy 383.970659 -196.783391) (xy 383.947806 -196.833139) (xy 383.918071 -196.879106)
			(xy 383.900426 -196.900038) (xy 383.900172 -196.900292) (xy 383.89458 -196.907374) (xy 383.888337 -196.924294)
			(xy 383.88798 -196.933312) (xy 383.88798 -197.000368) (xy 383.888357 -197.009383) (xy 383.894591 -197.0263)
			(xy 383.900172 -197.033388) (xy 383.900426 -197.033388) (xy 383.900426 -197.033642) (xy 383.918108 -197.054542)
			(xy 383.947835 -197.100514) (xy 383.97068 -197.150266) (xy 383.986176 -197.202773) (xy 383.994002 -197.256957)
			(xy 383.993997 -197.311703) (xy 383.986163 -197.365886) (xy 383.970659 -197.418391) (xy 383.947806 -197.468139)
			(xy 383.918071 -197.514106) (xy 383.900426 -197.535038) (xy 383.900172 -197.535292) (xy 383.89458 -197.542374)
			(xy 383.888337 -197.559294) (xy 383.88798 -197.568312) (xy 383.88798 -197.635368) (xy 383.888357 -197.644383)
			(xy 383.894591 -197.6613) (xy 383.900172 -197.668388) (xy 383.900426 -197.668388) (xy 383.900426 -197.668642)
			(xy 383.918108 -197.689542) (xy 383.947835 -197.735514) (xy 383.97068 -197.785266) (xy 383.986176 -197.837773)
			(xy 383.994002 -197.891957) (xy 383.993997 -197.946703) (xy 383.986163 -198.000886) (xy 383.970659 -198.053391)
			(xy 383.947806 -198.103139) (xy 383.918071 -198.149106) (xy 383.900426 -198.170038) (xy 383.900172 -198.170292)
			(xy 383.89458 -198.177374) (xy 383.888337 -198.194294) (xy 383.88798 -198.203312) (xy 383.88798 -198.270368)
			(xy 383.888357 -198.279383) (xy 383.894591 -198.2963) (xy 383.900172 -198.303388) (xy 383.900426 -198.303388)
			(xy 383.900426 -198.303642) (xy 383.918108 -198.324542) (xy 383.947835 -198.370514) (xy 383.97068 -198.420266)
			(xy 383.986176 -198.472773) (xy 383.994002 -198.526957) (xy 383.993997 -198.581703) (xy 383.986163 -198.635886)
			(xy 383.970659 -198.688391) (xy 383.947806 -198.738139) (xy 383.918071 -198.784106) (xy 383.900426 -198.805038)
			(xy 383.900172 -198.805292) (xy 383.89458 -198.812374) (xy 383.888337 -198.829294) (xy 383.88798 -198.838312)
			(xy 383.88798 -198.905368) (xy 383.888357 -198.914383) (xy 383.894591 -198.9313) (xy 383.900172 -198.938388)
			(xy 383.900426 -198.938388) (xy 383.900426 -198.938642) (xy 383.918108 -198.959542) (xy 383.947835 -199.005514)
			(xy 383.97068 -199.055266) (xy 383.986176 -199.107773) (xy 383.994002 -199.161957) (xy 383.993997 -199.216703)
			(xy 383.986163 -199.270886) (xy 383.970659 -199.323391) (xy 383.947806 -199.373139) (xy 383.918071 -199.419106)
			(xy 383.900426 -199.440038) (xy 383.900172 -199.440292) (xy 383.89458 -199.447374) (xy 383.888337 -199.464294)
			(xy 383.88798 -199.473312) (xy 383.88798 -199.540368) (xy 383.888357 -199.549383) (xy 383.894591 -199.5663)
			(xy 383.900172 -199.573388) (xy 383.900426 -199.573388) (xy 383.900426 -199.573642) (xy 383.918055 -199.594582)
			(xy 383.947768 -199.640553) (xy 383.970605 -199.690298) (xy 383.986099 -199.742797) (xy 383.99393 -199.796971)
			(xy 383.994406 -199.82434) (xy 386.26161 -199.82434) (xy 386.262097 -199.79697) (xy 386.269909 -199.742792)
			(xy 386.285393 -199.690289) (xy 386.308231 -199.640542) (xy 386.337951 -199.594574) (xy 386.35559 -199.573642)
			(xy 386.355844 -199.573388) (xy 386.361447 -199.566313) (xy 386.367683 -199.549387) (xy 386.368036 -199.540368)
			(xy 386.368036 -199.473312) (xy 386.367665 -199.464297) (xy 386.361426 -199.44738) (xy 386.355844 -199.440292)
			(xy 386.35559 -199.440292) (xy 386.35559 -199.440038) (xy 386.33799 -199.419073) (xy 386.308266 -199.37311)
			(xy 386.285421 -199.323369) (xy 386.269923 -199.270872) (xy 386.262092 -199.216698) (xy 386.262087 -199.161962)
			(xy 386.26991 -199.107787) (xy 386.2854 -199.055288) (xy 386.308237 -199.005543) (xy 386.337954 -198.959575)
			(xy 386.35559 -198.938642) (xy 386.355844 -198.938388) (xy 386.361447 -198.931313) (xy 386.367683 -198.914387)
			(xy 386.368036 -198.905368) (xy 386.368036 -198.838312) (xy 386.367665 -198.829297) (xy 386.361426 -198.81238)
			(xy 386.355844 -198.805292) (xy 386.35559 -198.805292) (xy 386.35559 -198.805038) (xy 386.33799 -198.784073)
			(xy 386.308266 -198.73811) (xy 386.285421 -198.688369) (xy 386.269923 -198.635872) (xy 386.262092 -198.581698)
			(xy 386.262087 -198.526962) (xy 386.26991 -198.472787) (xy 386.2854 -198.420288) (xy 386.308237 -198.370543)
			(xy 386.337954 -198.324575) (xy 386.35559 -198.303642) (xy 386.355844 -198.303388) (xy 386.361447 -198.296313)
			(xy 386.367683 -198.279387) (xy 386.368036 -198.270368) (xy 386.368036 -198.203312) (xy 386.367665 -198.194297)
			(xy 386.361426 -198.17738) (xy 386.355844 -198.170292) (xy 386.35559 -198.170292) (xy 386.35559 -198.170038)
			(xy 386.33799 -198.149073) (xy 386.308266 -198.10311) (xy 386.285421 -198.053369) (xy 386.269923 -198.000872)
			(xy 386.262092 -197.946698) (xy 386.262087 -197.891962) (xy 386.26991 -197.837787) (xy 386.2854 -197.785288)
			(xy 386.308237 -197.735543) (xy 386.337954 -197.689575) (xy 386.35559 -197.668642) (xy 386.355844 -197.668388)
			(xy 386.361447 -197.661313) (xy 386.367683 -197.644387) (xy 386.368036 -197.635368) (xy 386.368036 -197.568312)
			(xy 386.367665 -197.559297) (xy 386.361426 -197.54238) (xy 386.355844 -197.535292) (xy 386.35559 -197.535292)
			(xy 386.35559 -197.535038) (xy 386.33799 -197.514073) (xy 386.308266 -197.46811) (xy 386.285421 -197.418369)
			(xy 386.269923 -197.365872) (xy 386.262092 -197.311698) (xy 386.262087 -197.256962) (xy 386.26991 -197.202787)
			(xy 386.2854 -197.150288) (xy 386.308237 -197.100543) (xy 386.337954 -197.054575) (xy 386.35559 -197.033642)
			(xy 386.355844 -197.033388) (xy 386.361447 -197.026313) (xy 386.367683 -197.009387) (xy 386.368036 -197.000368)
			(xy 386.368036 -196.933312) (xy 386.367665 -196.924297) (xy 386.361426 -196.90738) (xy 386.355844 -196.900292)
			(xy 386.35559 -196.900292) (xy 386.35559 -196.900038) (xy 386.33799 -196.879073) (xy 386.308266 -196.83311)
			(xy 386.285421 -196.783369) (xy 386.269923 -196.730872) (xy 386.262092 -196.676698) (xy 386.262087 -196.621962)
			(xy 386.26991 -196.567787) (xy 386.2854 -196.515288) (xy 386.308237 -196.465543) (xy 386.337954 -196.419575)
			(xy 386.35559 -196.398642) (xy 386.355844 -196.398388) (xy 386.361447 -196.391313) (xy 386.367683 -196.374387)
			(xy 386.368036 -196.365368) (xy 386.368036 -196.298312) (xy 386.367665 -196.289297) (xy 386.361426 -196.27238)
			(xy 386.355844 -196.265292) (xy 386.35559 -196.265292) (xy 386.35559 -196.265038) (xy 386.33799 -196.244073)
			(xy 386.308266 -196.19811) (xy 386.285421 -196.148369) (xy 386.269923 -196.095872) (xy 386.262092 -196.041698)
			(xy 386.262087 -195.986962) (xy 386.26991 -195.932787) (xy 386.2854 -195.880288) (xy 386.308237 -195.830543)
			(xy 386.337954 -195.784575) (xy 386.35559 -195.763642) (xy 386.355844 -195.763388) (xy 386.361447 -195.756313)
			(xy 386.367683 -195.739387) (xy 386.368036 -195.730368) (xy 386.368036 -195.663312) (xy 386.367665 -195.654297)
			(xy 386.361426 -195.63738) (xy 386.355844 -195.630292) (xy 386.35559 -195.630292) (xy 386.35559 -195.630038)
			(xy 386.337954 -195.609104) (xy 386.308242 -195.563131) (xy 386.285405 -195.513384) (xy 386.269914 -195.460884)
			(xy 386.262085 -195.406709) (xy 386.26161 -195.37934) (xy 386.262126 -195.350851) (xy 386.27059 -195.294504)
			(xy 386.287336 -195.240042) (xy 386.311992 -195.188675) (xy 386.34401 -195.141543) (xy 386.362956 -195.12026)
			(xy 386.36956 -195.113148) (xy 386.376418 -195.095622) (xy 386.376418 -195.00723) (xy 386.36956 -194.989704)
			(xy 386.362956 -194.982592) (xy 386.344009 -194.961311) (xy 386.312 -194.914175) (xy 386.28735 -194.862806)
			(xy 386.270605 -194.808345) (xy 386.262138 -194.752001) (xy 386.26161 -194.723512) (xy 386.262067 -194.696259)
			(xy 386.269822 -194.642307) (xy 386.285178 -194.590007) (xy 386.30782 -194.540426) (xy 386.337289 -194.494572)
			(xy 386.372983 -194.453379) (xy 386.414177 -194.417685) (xy 386.460031 -194.388217) (xy 386.509613 -194.365576)
			(xy 386.561912 -194.350221) (xy 386.615865 -194.342466) (xy 386.643118 -194.342004) (xy 386.670489 -194.342459)
			(xy 386.724668 -194.350279) (xy 386.777172 -194.365771) (xy 386.826918 -194.388615) (xy 386.872885 -194.418342)
			(xy 386.893816 -194.435984) (xy 386.89407 -194.436238) (xy 386.901158 -194.441822) (xy 386.918074 -194.448069)
			(xy 386.92709 -194.44843) (xy 386.994146 -194.44843) (xy 387.003159 -194.448041) (xy 387.020076 -194.441815)
			(xy 387.027166 -194.436238) (xy 387.027166 -194.435984) (xy 387.02742 -194.435984) (xy 387.048353 -194.418343)
			(xy 387.094321 -194.388619) (xy 387.144067 -194.365773) (xy 387.196569 -194.350277) (xy 387.250747 -194.342448)
			(xy 387.305489 -194.342448) (xy 387.359667 -194.350277) (xy 387.412169 -194.365773) (xy 387.461915 -194.388619)
			(xy 387.507883 -194.418343) (xy 387.528816 -194.435984) (xy 387.52907 -194.436238) (xy 387.536158 -194.441822)
			(xy 387.553074 -194.448069) (xy 387.56209 -194.44843) (xy 387.629146 -194.44843) (xy 387.638159 -194.448041)
			(xy 387.655076 -194.441815) (xy 387.662166 -194.436238) (xy 387.662166 -194.435984) (xy 387.66242 -194.435984)
			(xy 387.683369 -194.418366) (xy 387.729338 -194.388652) (xy 387.779081 -194.365812) (xy 387.831578 -194.350316)
			(xy 387.88575 -194.342482) (xy 387.913118 -194.342004) (xy 387.94037 -194.342461) (xy 387.99432 -194.35022)
			(xy 388.046616 -194.365578) (xy 388.096194 -194.388222) (xy 388.142045 -194.417692) (xy 388.183235 -194.453386)
			(xy 388.218926 -194.494579) (xy 388.248392 -194.540433) (xy 388.271032 -194.590013) (xy 388.286386 -194.64231)
			(xy 388.294141 -194.69626) (xy 388.294626 -194.723512) (xy 388.294178 -194.750483) (xy 388.286569 -194.803884)
			(xy 388.271505 -194.855679) (xy 388.249287 -194.904832) (xy 388.22036 -194.950361) (xy 388.203186 -194.971162)
			(xy 388.197653 -194.978339) (xy 388.191531 -194.99538) (xy 388.191248 -195.004436) (xy 388.19201 -195.08089)
			(xy 388.19836 -195.097654) (xy 388.20471 -195.104766) (xy 388.222802 -195.125838) (xy 388.253307 -195.172247)
			(xy 388.276767 -195.222585) (xy 388.292688 -195.275792) (xy 388.300732 -195.330743) (xy 388.30123 -195.358512)
			(xy 388.300788 -195.385883) (xy 388.292967 -195.440064) (xy 388.277473 -195.492568) (xy 388.254626 -195.542315)
			(xy 388.224895 -195.58828) (xy 388.20725 -195.60921) (xy 388.206996 -195.609464) (xy 388.201418 -195.616556)
			(xy 388.195166 -195.633469) (xy 388.194804 -195.642484) (xy 388.194804 -195.70954) (xy 388.195141 -195.718559)
			(xy 388.201403 -195.735476) (xy 388.206996 -195.74256) (xy 388.20725 -195.74256) (xy 388.20725 -195.742814)
			(xy 388.224903 -195.763737) (xy 388.254629 -195.809706) (xy 388.277476 -195.859453) (xy 388.292972 -195.911957)
			(xy 388.3008 -195.966138) (xy 388.300799 -196.02088) (xy 388.292968 -196.07506) (xy 388.277469 -196.127563)
			(xy 388.254621 -196.17731) (xy 388.224892 -196.223278) (xy 388.20725 -196.24421) (xy 388.206996 -196.244464)
			(xy 388.201418 -196.251556) (xy 388.195166 -196.268469) (xy 388.194804 -196.277484) (xy 388.194804 -196.34454)
			(xy 388.195141 -196.353559) (xy 388.201403 -196.370476) (xy 388.206996 -196.37756) (xy 388.20725 -196.37756)
			(xy 388.20725 -196.377814) (xy 388.224903 -196.398737) (xy 388.254629 -196.444706) (xy 388.277476 -196.494453)
			(xy 388.292972 -196.546957) (xy 388.3008 -196.601138) (xy 388.300799 -196.65588) (xy 388.292968 -196.71006)
			(xy 388.277469 -196.762563) (xy 388.254621 -196.81231) (xy 388.224892 -196.858278) (xy 388.20725 -196.87921)
			(xy 388.206996 -196.879464) (xy 388.201418 -196.886556) (xy 388.195166 -196.903469) (xy 388.194804 -196.912484)
			(xy 388.194804 -196.97954) (xy 388.195141 -196.988559) (xy 388.201403 -197.005476) (xy 388.206996 -197.01256)
			(xy 388.20725 -197.01256) (xy 388.20725 -197.012814) (xy 388.224854 -197.033774) (xy 388.254573 -197.079738)
			(xy 388.277417 -197.129479) (xy 388.292916 -197.181973) (xy 388.300752 -197.236145) (xy 388.30123 -197.263512)
			(xy 388.30123 -197.263766) (xy 388.300704 -197.292611) (xy 388.291999 -197.34964) (xy 388.274811 -197.40471)
			(xy 388.249533 -197.456567) (xy 388.21674 -197.50403) (xy 388.197344 -197.525386) (xy 388.19074 -197.532498)
			(xy 388.183628 -197.550024) (xy 388.182612 -197.638416) (xy 388.18947 -197.656196) (xy 388.19582 -197.663308)
			(xy 388.214294 -197.684467) (xy 388.245486 -197.731179) (xy 388.269503 -197.781955) (xy 388.285826 -197.8357)
			(xy 388.294103 -197.891256) (xy 388.294626 -197.91934) (xy 388.294143 -197.94671) (xy 388.286332 -198.000889)
			(xy 388.270848 -198.053393) (xy 388.248009 -198.10314) (xy 388.218287 -198.149107) (xy 388.200646 -198.170038)
			(xy 388.200392 -198.170292) (xy 388.194802 -198.177376) (xy 388.188558 -198.194295) (xy 388.1882 -198.203312)
			(xy 388.1882 -198.270368) (xy 388.188572 -198.279383) (xy 388.194809 -198.2963) (xy 388.200392 -198.303388)
			(xy 388.200646 -198.303388) (xy 388.200646 -198.303642) (xy 388.218327 -198.324542) (xy 388.248052 -198.370515)
			(xy 388.270897 -198.420267) (xy 388.286391 -198.472774) (xy 388.294217 -198.526957) (xy 388.294212 -198.581703)
			(xy 388.286378 -198.635885) (xy 388.270876 -198.68839) (xy 388.248023 -198.738138) (xy 388.218291 -198.784106)
			(xy 388.200646 -198.805038) (xy 388.200392 -198.805292) (xy 388.194802 -198.812376) (xy 388.188558 -198.829295)
			(xy 388.1882 -198.838312) (xy 388.1882 -198.905368) (xy 388.188572 -198.914383) (xy 388.194809 -198.9313)
			(xy 388.200392 -198.938388) (xy 388.200646 -198.938388) (xy 388.200646 -198.938642) (xy 388.218327 -198.959542)
			(xy 388.248052 -199.005515) (xy 388.270897 -199.055267) (xy 388.286391 -199.107774) (xy 388.294217 -199.161957)
			(xy 388.294212 -199.216703) (xy 388.286378 -199.270885) (xy 388.272957 -199.31634) (xy 390.27735 -199.31634)
			(xy 390.277878 -199.287423) (xy 390.286602 -199.230252) (xy 390.303857 -199.175052) (xy 390.329247 -199.12309)
			(xy 390.36219 -199.075556) (xy 390.40193 -199.03354) (xy 390.424416 -199.01535) (xy 390.433193 -199.007714)
			(xy 390.443393 -198.986835) (xy 390.443974 -198.975218) (xy 390.443974 -198.895462) (xy 390.443451 -198.883828)
			(xy 390.433252 -198.862918) (xy 390.424416 -198.85533) (xy 390.40195 -198.837118) (xy 390.362213 -198.795103)
			(xy 390.329272 -198.747573) (xy 390.30388 -198.695615) (xy 390.28662 -198.640421) (xy 390.277887 -198.583255)
			(xy 390.27735 -198.55434) (xy 390.277827 -198.52697) (xy 390.285641 -198.472791) (xy 390.301126 -198.420287)
			(xy 390.323966 -198.37054) (xy 390.353689 -198.324574) (xy 390.37133 -198.303642) (xy 390.371584 -198.303388)
			(xy 390.37718 -198.296308) (xy 390.383422 -198.279386) (xy 390.383776 -198.270368) (xy 390.383776 -198.203312)
			(xy 390.383419 -198.194295) (xy 390.377172 -198.177378) (xy 390.371584 -198.170292) (xy 390.37133 -198.170292)
			(xy 390.37133 -198.170038) (xy 390.3537 -198.149099) (xy 390.323986 -198.103128) (xy 390.301148 -198.053383)
			(xy 390.285654 -198.000883) (xy 390.277825 -197.946709) (xy 390.27735 -197.91934) (xy 390.27787 -197.890636)
			(xy 390.286467 -197.833876) (xy 390.303472 -197.779046) (xy 390.328502 -197.727382) (xy 390.360991 -197.680053)
			(xy 390.38022 -197.658736) (xy 390.386824 -197.651878) (xy 390.393936 -197.633844) (xy 390.394444 -197.545452)
			(xy 390.387586 -197.527672) (xy 390.381236 -197.520814) (xy 390.362555 -197.499613) (xy 390.331021 -197.452725)
			(xy 390.306745 -197.4017) (xy 390.29026 -197.347652) (xy 390.281926 -197.291765) (xy 390.281414 -197.263512)
			(xy 390.281884 -197.236142) (xy 390.2897 -197.181963) (xy 390.305188 -197.12946) (xy 390.328029 -197.079713)
			(xy 390.357753 -197.033746) (xy 390.375394 -197.012814) (xy 390.375648 -197.01256) (xy 390.381221 -197.005465)
			(xy 390.387475 -196.988554) (xy 390.38784 -196.97954) (xy 390.38784 -196.912484) (xy 390.387503 -196.903465)
			(xy 390.381243 -196.886547) (xy 390.375648 -196.879464) (xy 390.375394 -196.879464) (xy 390.375394 -196.87921)
			(xy 390.357766 -196.858267) (xy 390.328044 -196.8123) (xy 390.3052 -196.762555) (xy 390.289704 -196.710055)
			(xy 390.281875 -196.655879) (xy 390.281874 -196.601139) (xy 390.2897 -196.546962) (xy 390.305193 -196.494461)
			(xy 390.328035 -196.444716) (xy 390.357756 -196.398747) (xy 390.375394 -196.377814) (xy 390.375648 -196.37756)
			(xy 390.381221 -196.370465) (xy 390.387475 -196.353554) (xy 390.38784 -196.34454) (xy 390.38784 -196.277484)
			(xy 390.387503 -196.268465) (xy 390.381243 -196.251547) (xy 390.375648 -196.244464) (xy 390.375394 -196.244464)
			(xy 390.375394 -196.24421) (xy 390.357766 -196.223267) (xy 390.328044 -196.1773) (xy 390.3052 -196.127555)
			(xy 390.289704 -196.075055) (xy 390.281875 -196.020879) (xy 390.281874 -195.966139) (xy 390.2897 -195.911962)
			(xy 390.305193 -195.859461) (xy 390.328035 -195.809716) (xy 390.357756 -195.763747) (xy 390.375394 -195.742814)
			(xy 390.375648 -195.74256) (xy 390.381221 -195.735465) (xy 390.387475 -195.718554) (xy 390.38784 -195.70954)
			(xy 390.38784 -195.642484) (xy 390.387503 -195.633465) (xy 390.381243 -195.616547) (xy 390.375648 -195.609464)
			(xy 390.375394 -195.609464) (xy 390.375394 -195.60921) (xy 390.357745 -195.588286) (xy 390.328035 -195.542311)
			(xy 390.305201 -195.492561) (xy 390.289712 -195.440059) (xy 390.281887 -195.385882) (xy 390.281414 -195.358512)
			(xy 390.281869 -195.331377) (xy 390.289564 -195.277656) (xy 390.304799 -195.22557) (xy 390.327268 -195.17617)
			(xy 390.356515 -195.130456) (xy 390.37387 -195.109592) (xy 390.379529 -195.1024) (xy 390.385775 -195.085212)
			(xy 390.386062 -195.076064) (xy 390.385808 -195.009262) (xy 390.385317 -195.000207) (xy 390.378812 -194.983291)
			(xy 390.373108 -194.976242) (xy 390.372854 -194.975988) (xy 390.354961 -194.954963) (xy 390.324767 -194.908745)
			(xy 390.301552 -194.858657) (xy 390.2858 -194.805745) (xy 390.27784 -194.751115) (xy 390.27735 -194.723512)
			(xy 390.277889 -194.696263) (xy 390.285643 -194.642319) (xy 390.300995 -194.590028) (xy 390.323631 -194.540454)
			(xy 390.353092 -194.494606) (xy 390.388778 -194.453416) (xy 390.429962 -194.417725) (xy 390.475807 -194.388257)
			(xy 390.525378 -194.365613) (xy 390.577667 -194.350255) (xy 390.631609 -194.342493) (xy 390.658858 -194.342004)
			(xy 390.688278 -194.342547) (xy 390.746418 -194.351594) (xy 390.802475 -194.369478) (xy 390.829038 -194.382136)
			(xy 390.829292 -194.382136) (xy 390.837127 -194.385612) (xy 390.854123 -194.387725) (xy 390.870854 -194.384068)
			(xy 390.878314 -194.37985) (xy 390.951974 -194.334384) (xy 390.959207 -194.329568) (xy 390.970094 -194.316036)
			(xy 390.97581 -194.299636) (xy 390.976104 -194.29095) (xy 390.976104 -188.826902) (xy 390.976604 -188.801953)
			(xy 390.984415 -188.75267) (xy 390.999831 -188.705212) (xy 391.022472 -188.660746) (xy 391.051783 -188.620364)
			(xy 391.069068 -188.602366) (xy 391.629138 -188.04255) (xy 391.635896 -188.035092) (xy 391.643618 -188.016532)
			(xy 391.644124 -188.006482) (xy 391.644124 -181.177946) (xy 391.644612 -181.152997) (xy 391.65243 -181.103714)
			(xy 391.66785 -181.056257) (xy 391.690493 -181.011792) (xy 391.719804 -180.971409) (xy 391.737088 -180.95341)
			(xy 392.671554 -180.019198) (xy 392.678381 -180.011787) (xy 392.68611 -179.993196) (xy 392.68654 -179.98313)
			(xy 392.68654 -179.406042) (xy 392.686109 -179.395973) (xy 392.678394 -179.377374) (xy 392.671554 -179.369974)
			(xy 392.647678 -179.346352) (xy 392.64269 -179.341723) (xy 392.63085 -179.335023) (xy 392.62431 -179.333144)
			(xy 392.624056 -179.33289) (xy 392.623548 -179.33289) (xy 392.596151 -179.325808) (xy 392.543702 -179.30457)
			(xy 392.494965 -179.275817) (xy 392.45101 -179.240179) (xy 392.412803 -179.198439) (xy 392.381182 -179.151512)
			(xy 392.356839 -179.100429) (xy 392.340311 -179.04631) (xy 392.331959 -178.990343) (xy 392.331448 -178.96205)
			(xy 392.332002 -178.9348) (xy 392.339751 -178.880855) (xy 392.355098 -178.828561) (xy 392.377732 -178.778984)
			(xy 392.40719 -178.733133) (xy 392.442875 -178.691941) (xy 392.484058 -178.656247) (xy 392.529902 -178.626777)
			(xy 392.579473 -178.604131) (xy 392.631763 -178.588771) (xy 392.685706 -178.581008) (xy 392.712956 -178.580542)
			(xy 392.74126 -178.581111) (xy 392.797251 -178.589449) (xy 392.851392 -178.605978) (xy 392.902493 -178.630334)
			(xy 392.949428 -178.661981) (xy 392.991166 -178.700223) (xy 393.026787 -178.744218) (xy 393.055509 -178.792999)
			(xy 393.076698 -178.845492) (xy 393.083796 -178.872896) (xy 393.083796 -178.873404) (xy 393.085739 -178.879959)
			(xy 393.092565 -178.8918) (xy 393.097258 -178.896772) (xy 393.229084 -179.028598) (xy 393.246375 -179.046593)
			(xy 393.275699 -179.086968) (xy 393.298347 -179.131434) (xy 393.313761 -179.178895) (xy 393.321561 -179.228183)
			(xy 393.322048 -179.253134) (xy 393.322048 -180.136038) (xy 393.321558 -180.160987) (xy 393.313742 -180.21027)
			(xy 393.298323 -180.257727) (xy 393.27568 -180.302193) (xy 393.246369 -180.342576) (xy 393.229084 -180.360574)
			(xy 393.054332 -180.535326) (xy 393.047791 -180.542499) (xy 393.040118 -180.560305) (xy 393.039652 -180.579689)
			(xy 393.042648 -180.58892) (xy 393.074906 -180.675534) (xy 393.07876 -180.684449) (xy 393.091797 -180.698818)
			(xy 393.109211 -180.707371) (xy 393.118848 -180.708554) (xy 393.119102 -180.708554) (xy 393.147625 -180.711081)
			(xy 393.203501 -180.723599) (xy 393.256877 -180.744329) (xy 393.306555 -180.772806) (xy 393.351416 -180.80839)
			(xy 393.390455 -180.85028) (xy 393.422792 -180.897535) (xy 393.447701 -180.949094) (xy 393.464622 -181.003797)
			(xy 393.473176 -181.060416) (xy 393.473686 -181.089046) (xy 393.473202 -181.116957) (xy 393.465062 -181.172182)
			(xy 393.448964 -181.225632) (xy 393.42525 -181.276167) (xy 393.394426 -181.322707) (xy 393.37615 -181.343808)
			(xy 393.370244 -181.350978) (xy 393.3636 -181.368309) (xy 393.363196 -181.37759) (xy 393.363196 -181.455314)
			(xy 393.3698 -181.472586) (xy 393.37615 -181.479698) (xy 393.394409 -181.500813) (xy 393.425238 -181.547348)
			(xy 393.448956 -181.597879) (xy 393.465057 -181.651326) (xy 393.473197 -181.70655) (xy 393.473686 -181.73446)
			(xy 393.4732 -181.761711) (xy 393.465444 -181.815659) (xy 393.450089 -181.867954) (xy 393.427447 -181.917531)
			(xy 393.397981 -181.963381) (xy 393.36229 -182.004572) (xy 393.321099 -182.040263) (xy 393.275249 -182.069729)
			(xy 393.225672 -182.092371) (xy 393.173377 -182.107726) (xy 393.119429 -182.115482) (xy 393.064927 -182.115482)
			(xy 393.010979 -182.107726) (xy 392.958684 -182.092371) (xy 392.909107 -182.069729) (xy 392.863257 -182.040263)
			(xy 392.822066 -182.004572) (xy 392.786375 -181.963381) (xy 392.756909 -181.917531) (xy 392.734267 -181.867954)
			(xy 392.718912 -181.815659) (xy 392.711156 -181.761711) (xy 392.71067 -181.73446) (xy 392.711144 -181.706549)
			(xy 392.719284 -181.651322) (xy 392.735384 -181.597871) (xy 392.759101 -181.547337) (xy 392.789928 -181.500798)
			(xy 392.808206 -181.479698) (xy 392.814105 -181.472522) (xy 392.820755 -181.455196) (xy 392.82116 -181.445916)
			(xy 392.82116 -181.368192) (xy 392.814556 -181.35092) (xy 392.808206 -181.343808) (xy 392.791696 -181.324755)
			(xy 392.763284 -181.283107) (xy 392.740599 -181.238084) (xy 392.724033 -181.190468) (xy 392.713876 -181.141086)
			(xy 392.711686 -181.11597) (xy 392.711686 -181.115716) (xy 392.710629 -181.106035) (xy 392.702121 -181.088534)
			(xy 392.68766 -181.075512) (xy 392.678666 -181.071774) (xy 392.592052 -181.039516) (xy 392.582822 -181.036526)
			(xy 392.563439 -181.037014) (xy 392.545618 -181.044651) (xy 392.538458 -181.0512) (xy 392.294618 -181.294786)
			(xy 392.287794 -181.302199) (xy 392.280064 -181.320788) (xy 392.279632 -181.330854) (xy 392.279632 -188.15939)
			(xy 392.279117 -188.184338) (xy 392.271307 -188.23362) (xy 392.255895 -188.281077) (xy 392.233257 -188.325543)
			(xy 392.203951 -188.365927) (xy 392.186668 -188.383926) (xy 391.626598 -188.943742) (xy 391.619747 -188.951133)
			(xy 391.612034 -188.969739) (xy 391.611612 -188.97981) (xy 391.611612 -194.497706) (xy 391.611917 -194.504672)
			(xy 391.615778 -194.518065) (xy 391.619232 -194.524122) (xy 391.632542 -194.546732) (xy 391.653555 -194.594805)
			(xy 391.667779 -194.645306) (xy 391.674944 -194.697279) (xy 391.675366 -194.723512) (xy 391.674872 -194.750645)
			(xy 391.667187 -194.804365) (xy 391.651961 -194.856451) (xy 391.629501 -194.905851) (xy 391.600261 -194.951567)
			(xy 391.58291 -194.972432) (xy 391.57728 -194.979644) (xy 391.571017 -194.996817) (xy 391.570718 -195.00596)
			(xy 391.570972 -195.072762) (xy 391.571434 -195.081821) (xy 391.577957 -195.098737) (xy 391.583672 -195.105782)
			(xy 391.583926 -195.106036) (xy 391.601827 -195.127054) (xy 391.63202 -195.173274) (xy 391.655234 -195.223364)
			(xy 391.670985 -195.276277) (xy 391.678942 -195.330908) (xy 391.67943 -195.358512) (xy 391.678988 -195.385883)
			(xy 391.671167 -195.440064) (xy 391.655673 -195.492568) (xy 391.632826 -195.542315) (xy 391.603095 -195.58828)
			(xy 391.58545 -195.60921) (xy 391.585196 -195.609464) (xy 391.579618 -195.616556) (xy 391.573366 -195.633469)
			(xy 391.573004 -195.642484) (xy 391.573004 -195.70954) (xy 391.573341 -195.718559) (xy 391.579603 -195.735476)
			(xy 391.585196 -195.74256) (xy 391.58545 -195.74256) (xy 391.58545 -195.742814) (xy 391.603103 -195.763737)
			(xy 391.632829 -195.809706) (xy 391.655676 -195.859453) (xy 391.671172 -195.911957) (xy 391.679 -195.966138)
			(xy 391.678999 -196.02088) (xy 391.671168 -196.07506) (xy 391.655669 -196.127563) (xy 391.632821 -196.17731)
			(xy 391.603092 -196.223278) (xy 391.58545 -196.24421) (xy 391.585196 -196.244464) (xy 391.579618 -196.251556)
			(xy 391.573366 -196.268469) (xy 391.573004 -196.277484) (xy 391.573004 -196.34454) (xy 391.573341 -196.353559)
			(xy 391.579603 -196.370476) (xy 391.585196 -196.37756) (xy 391.58545 -196.37756) (xy 391.58545 -196.377814)
			(xy 391.603103 -196.398737) (xy 391.632829 -196.444706) (xy 391.655676 -196.494453) (xy 391.671172 -196.546957)
			(xy 391.679 -196.601138) (xy 391.678999 -196.65588) (xy 391.671168 -196.71006) (xy 391.655669 -196.762563)
			(xy 391.632821 -196.81231) (xy 391.603092 -196.858278) (xy 391.58545 -196.87921) (xy 391.585196 -196.879464)
			(xy 391.579618 -196.886556) (xy 391.573366 -196.903469) (xy 391.573004 -196.912484) (xy 391.573004 -196.97954)
			(xy 391.573341 -196.988559) (xy 391.579603 -197.005476) (xy 391.585196 -197.01256) (xy 391.58545 -197.01256)
			(xy 391.58545 -197.012814) (xy 391.603054 -197.033774) (xy 391.632773 -197.079738) (xy 391.655617 -197.129479)
			(xy 391.671116 -197.181973) (xy 391.678952 -197.236145) (xy 391.67943 -197.263512) (xy 391.678947 -197.292217)
			(xy 391.670342 -197.348979) (xy 391.653328 -197.40381) (xy 391.62829 -197.455473) (xy 391.595793 -197.5028)
			(xy 391.57656 -197.524116) (xy 391.569956 -197.530974) (xy 391.562844 -197.549008) (xy 391.562336 -197.6374)
			(xy 391.569194 -197.65518) (xy 391.575544 -197.662038) (xy 391.594246 -197.683221) (xy 391.625778 -197.730114)
			(xy 391.65005 -197.781144) (xy 391.66653 -197.835195) (xy 391.674858 -197.891086) (xy 391.675366 -197.91934)
			(xy 391.674873 -197.946709) (xy 391.667063 -198.000888) (xy 391.651581 -198.053391) (xy 391.628745 -198.103138)
			(xy 391.599025 -198.149106) (xy 391.581386 -198.170038) (xy 391.581132 -198.170292) (xy 391.575535 -198.177371)
			(xy 391.569296 -198.194294) (xy 391.56894 -198.203312) (xy 391.56894 -198.270368) (xy 391.569304 -198.279384)
			(xy 391.575546 -198.296302) (xy 391.581132 -198.303388) (xy 391.581386 -198.303388) (xy 391.581386 -198.303642)
			(xy 391.599009 -198.324587) (xy 391.628724 -198.370556) (xy 391.651563 -198.4203) (xy 391.667058 -198.472798)
			(xy 391.67489 -198.526972) (xy 391.675366 -198.55434) (xy 391.674982 -198.581596) (xy 391.667219 -198.635552)
			(xy 391.651855 -198.687854) (xy 391.629205 -198.737437) (xy 391.599729 -198.783292) (xy 391.564027 -198.824485)
			(xy 391.522826 -198.860178) (xy 391.476965 -198.889645) (xy 391.427377 -198.912284) (xy 391.375072 -198.927636)
			(xy 391.321114 -198.935388) (xy 391.293858 -198.935848) (xy 391.266488 -198.935361) (xy 391.21231 -198.92755)
			(xy 391.159806 -198.912066) (xy 391.110059 -198.889229) (xy 391.064092 -198.859508) (xy 391.04316 -198.841868)
			(xy 391.042906 -198.841614) (xy 391.035821 -198.836025) (xy 391.018903 -198.829779) (xy 391.009886 -198.829422)
			(xy 390.94283 -198.829422) (xy 390.933814 -198.829789) (xy 390.916897 -198.836029) (xy 390.90981 -198.841614)
			(xy 390.90981 -198.841868) (xy 390.909302 -198.841868) (xy 390.8933 -198.85533) (xy 390.884489 -198.862934)
			(xy 390.874307 -198.883837) (xy 390.873742 -198.895462) (xy 390.873742 -198.975218) (xy 390.874271 -198.986852)
			(xy 390.884465 -199.007762) (xy 390.8933 -199.01535) (xy 390.91576 -199.033569) (xy 390.955496 -199.075583)
			(xy 390.988438 -199.123112) (xy 391.013831 -199.175068) (xy 391.031092 -199.23026) (xy 391.039827 -199.287426)
			(xy 391.040366 -199.31634) (xy 391.03988 -199.343591) (xy 391.032124 -199.397539) (xy 391.016769 -199.449834)
			(xy 390.994127 -199.499411) (xy 390.964661 -199.545261) (xy 390.92897 -199.586452) (xy 390.887779 -199.622143)
			(xy 390.841929 -199.651609) (xy 390.792352 -199.674251) (xy 390.740057 -199.689606) (xy 390.686109 -199.697362)
			(xy 390.631607 -199.697362) (xy 390.577659 -199.689606) (xy 390.525364 -199.674251) (xy 390.475787 -199.651609)
			(xy 390.429937 -199.622143) (xy 390.388746 -199.586452) (xy 390.353055 -199.545261) (xy 390.323589 -199.499411)
			(xy 390.300947 -199.449834) (xy 390.285592 -199.397539) (xy 390.277836 -199.343591) (xy 390.27735 -199.31634)
			(xy 388.272957 -199.31634) (xy 388.270876 -199.32339) (xy 388.248023 -199.373138) (xy 388.218291 -199.419106)
			(xy 388.200646 -199.440038) (xy 388.200392 -199.440292) (xy 388.194802 -199.447376) (xy 388.188558 -199.464295)
			(xy 388.1882 -199.473312) (xy 388.1882 -199.540368) (xy 388.188572 -199.549383) (xy 388.194809 -199.5663)
			(xy 388.200392 -199.573388) (xy 388.200646 -199.573388) (xy 388.200646 -199.573642) (xy 388.218263 -199.594592)
			(xy 388.24798 -199.640559) (xy 388.270821 -199.690302) (xy 388.286317 -199.742799) (xy 388.29415 -199.796972)
			(xy 388.294626 -199.82434) (xy 388.294159 -199.851591) (xy 388.286398 -199.905539) (xy 388.271039 -199.957833)
			(xy 388.248394 -200.007409) (xy 388.218925 -200.053258) (xy 388.183232 -200.094448) (xy 388.142041 -200.130139)
			(xy 388.09619 -200.159605) (xy 388.046612 -200.182246) (xy 387.994317 -200.197603) (xy 387.940369 -200.205361)
			(xy 387.913118 -200.205848) (xy 387.885748 -200.205384) (xy 387.831568 -200.197568) (xy 387.779064 -200.182079)
			(xy 387.729317 -200.159236) (xy 387.683351 -200.12951) (xy 387.66242 -200.111868) (xy 387.662166 -200.111614)
			(xy 387.655064 -200.10605) (xy 387.638159 -200.099789) (xy 387.629146 -200.099422) (xy 387.56209 -200.099422)
			(xy 387.553072 -200.099769) (xy 387.536155 -200.106023) (xy 387.52907 -200.111614) (xy 387.528816 -200.111868)
			(xy 387.507883 -200.129509) (xy 387.461915 -200.159233) (xy 387.412169 -200.182079) (xy 387.359667 -200.197575)
			(xy 387.305489 -200.205404) (xy 387.250747 -200.205404) (xy 387.196569 -200.197575) (xy 387.144067 -200.182079)
			(xy 387.094321 -200.159233) (xy 387.048353 -200.129509) (xy 387.02742 -200.111868) (xy 387.027166 -200.111614)
			(xy 387.020064 -200.10605) (xy 387.003159 -200.099789) (xy 386.994146 -200.099422) (xy 386.92709 -200.099422)
			(xy 386.918072 -200.099769) (xy 386.901155 -200.106023) (xy 386.89407 -200.111614) (xy 386.89407 -200.111868)
			(xy 386.893816 -200.111868) (xy 386.872885 -200.129508) (xy 386.826912 -200.159221) (xy 386.777165 -200.182057)
			(xy 386.724663 -200.197548) (xy 386.670487 -200.205375) (xy 386.643118 -200.205848) (xy 386.615869 -200.205305)
			(xy 386.561925 -200.197552) (xy 386.509634 -200.182201) (xy 386.46006 -200.159565) (xy 386.414211 -200.130105)
			(xy 386.373022 -200.094419) (xy 386.33733 -200.053235) (xy 386.307863 -200.007391) (xy 386.285219 -199.95782)
			(xy 386.26986 -199.905531) (xy 386.262099 -199.851589) (xy 386.26161 -199.82434) (xy 383.994406 -199.82434)
			(xy 383.993959 -199.851592) (xy 383.986197 -199.905542) (xy 383.970837 -199.957837) (xy 383.948191 -200.007415)
			(xy 383.91872 -200.053265) (xy 383.883025 -200.094455) (xy 383.841831 -200.130146) (xy 383.795978 -200.159611)
			(xy 383.746398 -200.182252) (xy 383.6941 -200.197606) (xy 383.64015 -200.205362) (xy 383.612898 -200.205848)
			(xy 383.585527 -200.205396) (xy 383.531347 -200.197577) (xy 383.478843 -200.182085) (xy 383.429096 -200.15924)
			(xy 383.383131 -200.129511) (xy 383.3622 -200.111868) (xy 383.361946 -200.111614) (xy 383.354849 -200.106042)
			(xy 383.33794 -200.099786) (xy 383.328926 -200.099422) (xy 383.26187 -200.099422) (xy 383.252851 -200.09976)
			(xy 383.235934 -200.10602) (xy 383.22885 -200.111614) (xy 383.22885 -200.111868) (xy 383.228596 -200.111868)
			(xy 383.207663 -200.129509) (xy 383.161695 -200.159233) (xy 383.111949 -200.182079) (xy 383.059447 -200.197575)
			(xy 383.005269 -200.205404) (xy 382.950527 -200.205404) (xy 382.896349 -200.197575) (xy 382.843847 -200.182079)
			(xy 382.794101 -200.159233) (xy 382.748133 -200.129509) (xy 382.7272 -200.111868) (xy 382.726946 -200.111614)
			(xy 382.719849 -200.106042) (xy 382.70294 -200.099786) (xy 382.693926 -200.099422) (xy 382.62687 -200.099422)
			(xy 382.617851 -200.09976) (xy 382.600934 -200.10602) (xy 382.59385 -200.111614) (xy 382.59385 -200.111868)
			(xy 382.593596 -200.111868) (xy 382.572672 -200.129517) (xy 382.526698 -200.159229) (xy 382.476948 -200.182063)
			(xy 382.424445 -200.197552) (xy 382.370268 -200.205376) (xy 382.342898 -200.205848) (xy 382.315649 -200.205324)
			(xy 382.261704 -200.197568) (xy 382.209413 -200.182215) (xy 382.159838 -200.159577) (xy 382.11399 -200.130114)
			(xy 382.0728 -200.094426) (xy 382.037109 -200.053241) (xy 382.007642 -200.007395) (xy 381.984998 -199.957823)
			(xy 381.96964 -199.905533) (xy 381.961879 -199.851589) (xy 381.96139 -199.82434) (xy 381.961882 -199.796971)
			(xy 381.969694 -199.742793) (xy 381.985177 -199.69029) (xy 382.008013 -199.640543) (xy 382.037732 -199.594575)
			(xy 382.05537 -199.573642) (xy 382.055624 -199.573388) (xy 382.061224 -199.566311) (xy 382.067462 -199.549387)
			(xy 382.067816 -199.540368) (xy 382.067816 -199.473312) (xy 382.06745 -199.464296) (xy 382.061208 -199.447379)
			(xy 382.055624 -199.440292) (xy 382.05537 -199.440292) (xy 382.05537 -199.440038) (xy 382.037767 -199.419074)
			(xy 382.008037 -199.373113) (xy 381.985187 -199.323372) (xy 381.969685 -199.270874) (xy 381.961852 -199.216699)
			(xy 381.961848 -199.161961) (xy 381.969673 -199.107785) (xy 381.985165 -199.055284) (xy 382.008008 -199.00554)
			(xy 382.03773 -198.959574) (xy 382.05537 -198.938642) (xy 382.055624 -198.938388) (xy 382.061224 -198.931311)
			(xy 382.067462 -198.914387) (xy 382.067816 -198.905368) (xy 382.067816 -198.838312) (xy 382.06745 -198.829296)
			(xy 382.061208 -198.812379) (xy 382.055624 -198.805292) (xy 382.05537 -198.805292) (xy 382.05537 -198.805038)
			(xy 382.037767 -198.784074) (xy 382.008037 -198.738113) (xy 381.985187 -198.688372) (xy 381.969685 -198.635874)
			(xy 381.961852 -198.581699) (xy 381.961848 -198.526961) (xy 381.969673 -198.472785) (xy 381.985165 -198.420284)
			(xy 382.008008 -198.37054) (xy 382.03773 -198.324574) (xy 382.05537 -198.303642) (xy 382.055624 -198.303388)
			(xy 382.061224 -198.296311) (xy 382.067462 -198.279387) (xy 382.067816 -198.270368) (xy 382.067816 -198.203312)
			(xy 382.06745 -198.194296) (xy 382.061208 -198.177379) (xy 382.055624 -198.170292) (xy 382.05537 -198.170292)
			(xy 382.05537 -198.170038) (xy 382.037731 -198.149106) (xy 382.00802 -198.103133) (xy 381.985184 -198.053385)
			(xy 381.969693 -198.000885) (xy 381.961865 -197.946709) (xy 381.96139 -197.91934) (xy 381.961892 -197.891502)
			(xy 381.969997 -197.83642) (xy 381.986012 -197.783097) (xy 382.009598 -197.732663) (xy 382.040254 -197.686188)
			(xy 382.058418 -197.665086) (xy 382.064768 -197.657974) (xy 382.071372 -197.640194) (xy 382.070102 -197.561454)
			(xy 382.069532 -197.552014) (xy 382.062368 -197.534527) (xy 382.056132 -197.527418) (xy 382.056132 -197.527164)
			(xy 382.036377 -197.505752) (xy 382.002977 -197.45802) (xy 381.977212 -197.405771) (xy 381.959679 -197.350214)
			(xy 381.950786 -197.29264) (xy 381.950214 -197.263512) (xy 381.950684 -197.236142) (xy 381.9585 -197.181963)
			(xy 381.973988 -197.12946) (xy 381.996829 -197.079713) (xy 382.026553 -197.033746) (xy 382.044194 -197.012814)
			(xy 382.044448 -197.01256) (xy 382.050021 -197.005465) (xy 382.056275 -196.988554) (xy 382.05664 -196.97954)
			(xy 382.05664 -196.912484) (xy 382.056303 -196.903465) (xy 382.050043 -196.886547) (xy 382.044448 -196.879464)
			(xy 382.044194 -196.879464) (xy 382.044194 -196.87921) (xy 382.026566 -196.858267) (xy 381.996844 -196.8123)
			(xy 381.974 -196.762555) (xy 381.958504 -196.710055) (xy 381.950675 -196.655879) (xy 381.950674 -196.601139)
			(xy 381.9585 -196.546962) (xy 381.973993 -196.494461) (xy 381.996835 -196.444716) (xy 382.026556 -196.398747)
			(xy 382.044194 -196.377814) (xy 382.044448 -196.37756) (xy 382.050021 -196.370465) (xy 382.056275 -196.353554)
			(xy 382.05664 -196.34454) (xy 382.05664 -196.277484) (xy 382.056303 -196.268465) (xy 382.050043 -196.251547)
			(xy 382.044448 -196.244464) (xy 382.044194 -196.244464) (xy 382.044194 -196.24421) (xy 382.026566 -196.223267)
			(xy 381.996844 -196.1773) (xy 381.974 -196.127555) (xy 381.958504 -196.075055) (xy 381.950675 -196.020879)
			(xy 381.950674 -195.966139) (xy 381.9585 -195.911962) (xy 381.973993 -195.859461) (xy 381.996835 -195.809716)
			(xy 382.026556 -195.763747) (xy 382.044194 -195.742814) (xy 382.044448 -195.74256) (xy 382.050021 -195.735465)
			(xy 382.056275 -195.718554) (xy 382.05664 -195.70954) (xy 382.05664 -195.642484) (xy 382.056303 -195.633465)
			(xy 382.050043 -195.616547) (xy 382.044448 -195.609464) (xy 382.044194 -195.609464) (xy 382.044194 -195.60921)
			(xy 382.026545 -195.588286) (xy 381.996835 -195.542311) (xy 381.974001 -195.492561) (xy 381.958512 -195.440059)
			(xy 381.950687 -195.385882) (xy 381.950214 -195.358512) (xy 381.950669 -195.331377) (xy 381.958364 -195.277656)
			(xy 381.973599 -195.22557) (xy 381.996068 -195.17617) (xy 382.025315 -195.130456) (xy 382.04267 -195.109592)
			(xy 382.048329 -195.1024) (xy 382.054575 -195.085212) (xy 382.054862 -195.076064) (xy 382.054608 -195.009262)
			(xy 382.054117 -195.000207) (xy 382.047612 -194.983291) (xy 382.041908 -194.976242) (xy 382.041654 -194.975988)
			(xy 382.023761 -194.954963) (xy 381.993567 -194.908745) (xy 381.970352 -194.858657) (xy 381.9546 -194.805745)
			(xy 381.94664 -194.751115) (xy 381.94615 -194.723512) (xy 379.963426 -194.723512) (xy 379.962978 -194.750483)
			(xy 379.955369 -194.803884) (xy 379.940305 -194.855679) (xy 379.918087 -194.904832) (xy 379.88916 -194.950361)
			(xy 379.871986 -194.971162) (xy 379.866453 -194.978339) (xy 379.860331 -194.99538) (xy 379.860048 -195.004436)
			(xy 379.86081 -195.08089) (xy 379.86716 -195.097654) (xy 379.87351 -195.104766) (xy 379.891602 -195.125838)
			(xy 379.922107 -195.172247) (xy 379.945567 -195.222585) (xy 379.961488 -195.275792) (xy 379.969532 -195.330743)
			(xy 379.97003 -195.358512) (xy 379.969588 -195.385883) (xy 379.961767 -195.440064) (xy 379.946273 -195.492568)
			(xy 379.923426 -195.542315) (xy 379.893695 -195.58828) (xy 379.87605 -195.60921) (xy 379.875796 -195.609464)
			(xy 379.870218 -195.616556) (xy 379.863966 -195.633469) (xy 379.863604 -195.642484) (xy 379.863604 -195.70954)
			(xy 379.863941 -195.718559) (xy 379.870203 -195.735476) (xy 379.875796 -195.74256) (xy 379.87605 -195.74256)
			(xy 379.87605 -195.742814) (xy 379.893703 -195.763737) (xy 379.923429 -195.809706) (xy 379.946276 -195.859453)
			(xy 379.961772 -195.911957) (xy 379.9696 -195.966138) (xy 379.969599 -196.02088) (xy 379.961768 -196.07506)
			(xy 379.946269 -196.127563) (xy 379.923421 -196.17731) (xy 379.893692 -196.223278) (xy 379.87605 -196.24421)
			(xy 379.875796 -196.244464) (xy 379.870218 -196.251556) (xy 379.863966 -196.268469) (xy 379.863604 -196.277484)
			(xy 379.863604 -196.34454) (xy 379.863941 -196.353559) (xy 379.870203 -196.370476) (xy 379.875796 -196.37756)
			(xy 379.87605 -196.37756) (xy 379.87605 -196.377814) (xy 379.893703 -196.398737) (xy 379.923429 -196.444706)
			(xy 379.946276 -196.494453) (xy 379.961772 -196.546957) (xy 379.9696 -196.601138) (xy 379.969599 -196.65588)
			(xy 379.961768 -196.71006) (xy 379.946269 -196.762563) (xy 379.923421 -196.81231) (xy 379.893692 -196.858278)
			(xy 379.87605 -196.87921) (xy 379.875796 -196.879464) (xy 379.870218 -196.886556) (xy 379.863966 -196.903469)
			(xy 379.863604 -196.912484) (xy 379.863604 -196.97954) (xy 379.863941 -196.988559) (xy 379.870203 -197.005476)
			(xy 379.875796 -197.01256) (xy 379.87605 -197.01256) (xy 379.87605 -197.012814) (xy 379.893654 -197.033774)
			(xy 379.923373 -197.079738) (xy 379.946217 -197.129479) (xy 379.961716 -197.181973) (xy 379.969552 -197.236145)
			(xy 379.97003 -197.263512) (xy 379.969519 -197.29135) (xy 379.961419 -197.346433) (xy 379.945408 -197.399756)
			(xy 379.921823 -197.45019) (xy 379.891166 -197.496665) (xy 379.873002 -197.517766) (xy 379.866652 -197.524878)
			(xy 379.860048 -197.542658) (xy 379.861318 -197.621398) (xy 379.861857 -197.630842) (xy 379.869042 -197.648329)
			(xy 379.875288 -197.655434) (xy 379.875288 -197.655688) (xy 379.895007 -197.677132) (xy 379.928415 -197.724854)
			(xy 379.954188 -197.777095) (xy 379.971729 -197.832645) (xy 379.98063 -197.890214) (xy 379.981206 -197.91934)
			(xy 379.980703 -197.946709) (xy 379.972894 -198.000886) (xy 379.957413 -198.053389) (xy 379.93458 -198.103136)
			(xy 379.904863 -198.149105) (xy 379.887226 -198.170038) (xy 379.886972 -198.170292) (xy 379.88138 -198.177374)
			(xy 379.875137 -198.194294) (xy 379.87478 -198.203312) (xy 379.87478 -198.270368) (xy 379.875157 -198.279383)
			(xy 379.881391 -198.2963) (xy 379.886972 -198.303388) (xy 379.887226 -198.303388) (xy 379.887226 -198.303642)
			(xy 379.904908 -198.324542) (xy 379.934635 -198.370514) (xy 379.95748 -198.420266) (xy 379.972976 -198.472773)
			(xy 379.980802 -198.526957) (xy 379.980797 -198.581703) (xy 379.972963 -198.635886) (xy 379.957459 -198.688391)
			(xy 379.934606 -198.738139) (xy 379.904871 -198.784106) (xy 379.887226 -198.805038) (xy 379.886972 -198.805292)
			(xy 379.88138 -198.812374) (xy 379.875137 -198.829294) (xy 379.87478 -198.838312) (xy 379.87478 -198.905368)
			(xy 379.875157 -198.914383) (xy 379.881391 -198.9313) (xy 379.886972 -198.938388) (xy 379.887226 -198.938388)
			(xy 379.887226 -198.938642) (xy 379.904908 -198.959542) (xy 379.934635 -199.005514) (xy 379.95748 -199.055266)
			(xy 379.972976 -199.107773) (xy 379.980802 -199.161957) (xy 379.980797 -199.216703) (xy 379.972963 -199.270886)
			(xy 379.957459 -199.323391) (xy 379.934606 -199.373139) (xy 379.904871 -199.419106) (xy 379.887226 -199.440038)
			(xy 379.886972 -199.440292) (xy 379.88138 -199.447374) (xy 379.875137 -199.464294) (xy 379.87478 -199.473312)
			(xy 379.87478 -199.540368) (xy 379.875157 -199.549383) (xy 379.881391 -199.5663) (xy 379.886972 -199.573388)
			(xy 379.887226 -199.573388) (xy 379.887226 -199.573642) (xy 379.904855 -199.594582) (xy 379.934568 -199.640553)
			(xy 379.957405 -199.690298) (xy 379.972899 -199.742797) (xy 379.98073 -199.796971) (xy 379.981206 -199.82434)
			(xy 379.980759 -199.851592) (xy 379.972997 -199.905542) (xy 379.957637 -199.957837) (xy 379.934991 -200.007415)
			(xy 379.90552 -200.053265) (xy 379.869825 -200.094455) (xy 379.828631 -200.130146) (xy 379.782778 -200.159611)
			(xy 379.733198 -200.182252) (xy 379.6809 -200.197606) (xy 379.62695 -200.205362) (xy 379.599698 -200.205848)
			(xy 379.572327 -200.205396) (xy 379.518147 -200.197577) (xy 379.465643 -200.182085) (xy 379.415896 -200.15924)
			(xy 379.369931 -200.129511) (xy 379.349 -200.111868) (xy 379.348746 -200.111614) (xy 379.341649 -200.106042)
			(xy 379.32474 -200.099786) (xy 379.315726 -200.099422) (xy 379.24867 -200.099422) (xy 379.239651 -200.09976)
			(xy 379.222734 -200.10602) (xy 379.21565 -200.111614) (xy 379.215396 -200.111868) (xy 379.194463 -200.129509)
			(xy 379.148495 -200.159233) (xy 379.098749 -200.182079) (xy 379.046247 -200.197575) (xy 378.992069 -200.205404)
			(xy 378.937327 -200.205404) (xy 378.883149 -200.197575) (xy 378.830647 -200.182079) (xy 378.780901 -200.159233)
			(xy 378.734933 -200.129509) (xy 378.714 -200.111868) (xy 378.713746 -200.111614) (xy 378.706649 -200.106042)
			(xy 378.68974 -200.099786) (xy 378.680726 -200.099422) (xy 378.61367 -200.099422) (xy 378.604651 -200.09976)
			(xy 378.587734 -200.10602) (xy 378.58065 -200.111614) (xy 378.58065 -200.111868) (xy 378.580396 -200.111868)
			(xy 378.559472 -200.129517) (xy 378.513498 -200.159229) (xy 378.463748 -200.182063) (xy 378.411245 -200.197552)
			(xy 378.357068 -200.205376) (xy 378.329698 -200.205848) (xy 378.302449 -200.205324) (xy 378.248504 -200.197568)
			(xy 378.196213 -200.182215) (xy 378.146638 -200.159577) (xy 378.10079 -200.130114) (xy 378.0596 -200.094426)
			(xy 378.023909 -200.053241) (xy 377.994442 -200.007395) (xy 377.971798 -199.957823) (xy 377.95644 -199.905533)
			(xy 377.948679 -199.851589) (xy 377.94819 -199.82434) (xy 377.948682 -199.796971) (xy 377.956494 -199.742793)
			(xy 377.971977 -199.69029) (xy 377.994813 -199.640543) (xy 378.024532 -199.594575) (xy 378.04217 -199.573642)
			(xy 378.042424 -199.573388) (xy 378.048024 -199.566311) (xy 378.054262 -199.549387) (xy 378.054616 -199.540368)
			(xy 378.054616 -199.473312) (xy 378.05425 -199.464296) (xy 378.048008 -199.447379) (xy 378.042424 -199.440292)
			(xy 378.04217 -199.440292) (xy 378.04217 -199.440038) (xy 378.024567 -199.419074) (xy 377.994837 -199.373113)
			(xy 377.971987 -199.323372) (xy 377.956485 -199.270874) (xy 377.948652 -199.216699) (xy 377.948648 -199.161961)
			(xy 377.956473 -199.107785) (xy 377.971965 -199.055284) (xy 377.994808 -199.00554) (xy 378.02453 -198.959574)
			(xy 378.04217 -198.938642) (xy 378.042424 -198.938388) (xy 378.048024 -198.931311) (xy 378.054262 -198.914387)
			(xy 378.054616 -198.905368) (xy 378.054616 -198.838312) (xy 378.05425 -198.829296) (xy 378.048008 -198.812379)
			(xy 378.042424 -198.805292) (xy 378.04217 -198.805292) (xy 378.04217 -198.805038) (xy 378.024567 -198.784074)
			(xy 377.994837 -198.738113) (xy 377.971987 -198.688372) (xy 377.956485 -198.635874) (xy 377.948652 -198.581699)
			(xy 377.948648 -198.526961) (xy 377.956473 -198.472785) (xy 377.971965 -198.420284) (xy 377.994808 -198.37054)
			(xy 378.02453 -198.324574) (xy 378.04217 -198.303642) (xy 378.042424 -198.303388) (xy 378.048024 -198.296311)
			(xy 378.054262 -198.279387) (xy 378.054616 -198.270368) (xy 378.054616 -198.203312) (xy 378.05425 -198.194296)
			(xy 378.048008 -198.177379) (xy 378.042424 -198.170292) (xy 378.04217 -198.170292) (xy 378.04217 -198.170038)
			(xy 378.024531 -198.149106) (xy 377.99482 -198.103133) (xy 377.971984 -198.053385) (xy 377.956493 -198.000885)
			(xy 377.948665 -197.946709) (xy 377.94819 -197.91934) (xy 377.948668 -197.893038) (xy 377.955894 -197.840933)
			(xy 377.970215 -197.790316) (xy 377.991358 -197.742149) (xy 378.018922 -197.697345) (xy 378.035312 -197.67677)
			(xy 378.041408 -197.669404) (xy 378.04725 -197.652386) (xy 378.04471 -197.566788) (xy 378.037852 -197.550024)
			(xy 378.031502 -197.543166) (xy 378.012635 -197.521898) (xy 377.980733 -197.47484) (xy 377.956154 -197.423575)
			(xy 377.93944 -197.369236) (xy 377.93096 -197.313019) (xy 377.93041 -197.284594) (xy 375.58249 -197.284594)
			(xy 375.582491 -197.308158) (xy 375.574664 -197.362335) (xy 375.559169 -197.414837) (xy 375.536325 -197.464582)
			(xy 375.506602 -197.51055) (xy 375.488962 -197.531482) (xy 375.488708 -197.531736) (xy 375.483143 -197.538837)
			(xy 375.476883 -197.555743) (xy 375.476516 -197.564756) (xy 375.476516 -197.631812) (xy 375.476864 -197.64083)
			(xy 375.483117 -197.657747) (xy 375.488708 -197.664832) (xy 375.488962 -197.664832) (xy 375.488962 -197.665086)
			(xy 375.506587 -197.686031) (xy 375.536314 -197.731997) (xy 375.559161 -197.781741) (xy 375.574659 -197.834241)
			(xy 375.582489 -197.888418) (xy 375.582491 -197.943158) (xy 375.574664 -197.997335) (xy 375.559169 -198.049837)
			(xy 375.536325 -198.099582) (xy 375.506602 -198.14555) (xy 375.488962 -198.166482) (xy 375.488708 -198.166736)
			(xy 375.483143 -198.173837) (xy 375.476883 -198.190743) (xy 375.476516 -198.199756) (xy 375.476516 -198.266812)
			(xy 375.476864 -198.27583) (xy 375.483117 -198.292747) (xy 375.488708 -198.299832) (xy 375.488962 -198.299832)
			(xy 375.488962 -198.300086) (xy 375.506587 -198.321031) (xy 375.536314 -198.366997) (xy 375.559161 -198.416741)
			(xy 375.574659 -198.469241) (xy 375.582489 -198.523418) (xy 375.582491 -198.578158) (xy 375.574664 -198.632335)
			(xy 375.559169 -198.684837) (xy 375.536325 -198.734582) (xy 375.506602 -198.78055) (xy 375.488962 -198.801482)
			(xy 375.488708 -198.801736) (xy 375.483143 -198.808837) (xy 375.476883 -198.825743) (xy 375.476516 -198.834756)
			(xy 375.476516 -198.901812) (xy 375.476864 -198.91083) (xy 375.483117 -198.927747) (xy 375.488708 -198.934832)
			(xy 375.488962 -198.934832) (xy 375.488962 -198.935086) (xy 375.506587 -198.956031) (xy 375.536314 -199.001997)
			(xy 375.559161 -199.051741) (xy 375.574659 -199.104241) (xy 375.582489 -199.158418) (xy 375.582491 -199.213158)
			(xy 375.574664 -199.267335) (xy 375.559169 -199.319837) (xy 375.536325 -199.369582) (xy 375.506602 -199.41555)
			(xy 375.488962 -199.436482) (xy 375.488708 -199.436736) (xy 375.483143 -199.443837) (xy 375.476883 -199.460743)
			(xy 375.476516 -199.469756) (xy 375.476516 -199.536812) (xy 375.476864 -199.54583) (xy 375.483117 -199.562747)
			(xy 375.488708 -199.569832) (xy 375.488962 -199.569832) (xy 375.488962 -199.570086) (xy 375.506587 -199.591031)
			(xy 375.536314 -199.636997) (xy 375.559161 -199.686741) (xy 375.574659 -199.739241) (xy 375.582489 -199.793418)
			(xy 375.582491 -199.848158) (xy 375.574664 -199.902335) (xy 375.559169 -199.954837) (xy 375.536325 -200.004582)
			(xy 375.506602 -200.05055) (xy 375.488962 -200.071482) (xy 375.488708 -200.071736) (xy 375.483143 -200.078837)
			(xy 375.476883 -200.095743) (xy 375.476516 -200.104756) (xy 375.476516 -200.171812) (xy 375.476864 -200.18083)
			(xy 375.483117 -200.197747) (xy 375.488708 -200.204832) (xy 375.488962 -200.204832) (xy 375.488962 -200.205086)
			(xy 375.506587 -200.226031) (xy 375.536314 -200.271997) (xy 375.559161 -200.321741) (xy 375.574659 -200.374241)
			(xy 375.582489 -200.428418) (xy 375.582491 -200.483158) (xy 375.574664 -200.537335) (xy 375.559169 -200.589837)
			(xy 375.536325 -200.639582) (xy 375.506602 -200.68555) (xy 375.488962 -200.706482) (xy 375.488708 -200.706736)
			(xy 375.483143 -200.713837) (xy 375.476883 -200.730743) (xy 375.476516 -200.739756) (xy 375.476516 -200.806812)
			(xy 375.476864 -200.81583) (xy 375.483117 -200.832747) (xy 375.488708 -200.839832) (xy 375.488962 -200.839832)
			(xy 375.488962 -200.840086) (xy 375.506602 -200.861017) (xy 375.536315 -200.90699) (xy 375.559151 -200.956737)
			(xy 375.574642 -201.009238) (xy 375.582469 -201.063415) (xy 375.582942 -201.090784) (xy 375.582407 -201.118033)
			(xy 375.574654 -201.171977) (xy 375.559302 -201.224269) (xy 375.536665 -201.273844) (xy 375.507204 -201.319693)
			(xy 375.471518 -201.360882) (xy 375.430333 -201.396574) (xy 375.384488 -201.426041) (xy 375.334916 -201.448685)
			(xy 375.282626 -201.464043) (xy 375.228683 -201.471803) (xy 375.201434 -201.472292) (xy 375.174064 -201.471808)
			(xy 375.119886 -201.463995) (xy 375.067383 -201.44851) (xy 375.017636 -201.425672) (xy 374.971668 -201.395951)
			(xy 374.950736 -201.378312) (xy 374.950482 -201.378058) (xy 374.943408 -201.372453) (xy 374.926482 -201.366218)
			(xy 374.917462 -201.365866) (xy 374.850406 -201.365866) (xy 374.84139 -201.366233) (xy 374.824474 -201.372475)
			(xy 374.817386 -201.378058) (xy 374.817386 -201.378312) (xy 374.817132 -201.378312) (xy 374.796199 -201.395953)
			(xy 374.750231 -201.425677) (xy 374.700485 -201.448523) (xy 374.647983 -201.464019) (xy 374.593805 -201.471848)
			(xy 374.539063 -201.471848) (xy 374.484885 -201.464019) (xy 374.432383 -201.448523) (xy 374.382637 -201.425677)
			(xy 374.336669 -201.395953) (xy 374.315736 -201.378312) (xy 374.315482 -201.378058) (xy 374.308408 -201.372453)
			(xy 374.291482 -201.366218) (xy 374.282462 -201.365866) (xy 374.215406 -201.365866) (xy 374.20639 -201.366233)
			(xy 374.189474 -201.372475) (xy 374.182386 -201.378058) (xy 374.182386 -201.378312) (xy 374.182132 -201.378312)
			(xy 374.1612 -201.395951) (xy 374.115227 -201.425663) (xy 374.06548 -201.448498) (xy 374.012979 -201.46399)
			(xy 373.958803 -201.471818) (xy 373.931434 -201.472292) (xy 373.904181 -201.471813) (xy 373.85023 -201.46406)
			(xy 373.797932 -201.448708) (xy 373.74835 -201.426068) (xy 373.702496 -201.396602) (xy 373.661303 -201.36091)
			(xy 373.625609 -201.319718) (xy 373.596141 -201.273865) (xy 373.573499 -201.224285) (xy 373.558144 -201.171988)
			(xy 373.550388 -201.118037) (xy 373.549926 -201.090784) (xy 373.550376 -201.063413) (xy 373.558197 -201.009233)
			(xy 373.573689 -200.95673) (xy 373.596535 -200.906983) (xy 373.626263 -200.861017) (xy 373.643906 -200.840086)
			(xy 373.64416 -200.839832) (xy 373.649746 -200.832746) (xy 373.655992 -200.815828) (xy 373.656352 -200.806812)
			(xy 373.656352 -200.739756) (xy 373.655979 -200.730741) (xy 373.649744 -200.713823) (xy 373.64416 -200.706736)
			(xy 373.643906 -200.706736) (xy 373.643906 -200.706482) (xy 373.626251 -200.685562) (xy 373.596528 -200.639591)
			(xy 373.573685 -200.589843) (xy 373.558191 -200.537339) (xy 373.550364 -200.483159) (xy 373.550366 -200.428417)
			(xy 373.558196 -200.374237) (xy 373.573693 -200.321735) (xy 373.59654 -200.271988) (xy 373.626265 -200.226019)
			(xy 373.643906 -200.205086) (xy 373.64416 -200.204832) (xy 373.649746 -200.197746) (xy 373.655992 -200.180828)
			(xy 373.656352 -200.171812) (xy 373.656352 -200.104756) (xy 373.655979 -200.095741) (xy 373.649744 -200.078823)
			(xy 373.64416 -200.071736) (xy 373.643906 -200.071736) (xy 373.643906 -200.071482) (xy 373.626251 -200.050562)
			(xy 373.596528 -200.004591) (xy 373.573685 -199.954843) (xy 373.558191 -199.902339) (xy 373.550364 -199.848159)
			(xy 373.550366 -199.793417) (xy 373.558196 -199.739237) (xy 373.573693 -199.686735) (xy 373.59654 -199.636988)
			(xy 373.626265 -199.591019) (xy 373.643906 -199.570086) (xy 373.64416 -199.569832) (xy 373.649746 -199.562746)
			(xy 373.655992 -199.545828) (xy 373.656352 -199.536812) (xy 373.656352 -199.469756) (xy 373.655979 -199.460741)
			(xy 373.649744 -199.443823) (xy 373.64416 -199.436736) (xy 373.643906 -199.436736) (xy 373.643906 -199.436482)
			(xy 373.626251 -199.415562) (xy 373.596528 -199.369591) (xy 373.573685 -199.319843) (xy 373.558191 -199.267339)
			(xy 373.550364 -199.213159) (xy 373.550366 -199.158417) (xy 373.558196 -199.104237) (xy 373.573693 -199.051735)
			(xy 373.59654 -199.001988) (xy 373.626265 -198.956019) (xy 373.643906 -198.935086) (xy 373.64416 -198.934832)
			(xy 373.649746 -198.927746) (xy 373.655992 -198.910828) (xy 373.656352 -198.901812) (xy 373.656352 -198.834756)
			(xy 373.655979 -198.825741) (xy 373.649744 -198.808823) (xy 373.64416 -198.801736) (xy 373.643906 -198.801736)
			(xy 373.643906 -198.801482) (xy 373.626251 -198.780562) (xy 373.596528 -198.734591) (xy 373.573685 -198.684843)
			(xy 373.558191 -198.632339) (xy 373.550364 -198.578159) (xy 373.550366 -198.523417) (xy 373.558196 -198.469237)
			(xy 373.573693 -198.416735) (xy 373.59654 -198.366988) (xy 373.626265 -198.321019) (xy 373.643906 -198.300086)
			(xy 373.64416 -198.299832) (xy 373.649746 -198.292746) (xy 373.655992 -198.275828) (xy 373.656352 -198.266812)
			(xy 373.656352 -198.199756) (xy 373.655979 -198.190741) (xy 373.649744 -198.173823) (xy 373.64416 -198.166736)
			(xy 373.643906 -198.166736) (xy 373.643906 -198.166482) (xy 373.626293 -198.145529) (xy 373.596577 -198.099562)
			(xy 373.573736 -198.04982) (xy 373.558239 -197.997324) (xy 373.550404 -197.943152) (xy 373.549926 -197.915784)
			(xy 373.550459 -197.887639) (xy 373.558725 -197.83196) (xy 373.575076 -197.778097) (xy 373.599158 -197.727219)
			(xy 373.630447 -197.680427) (xy 373.648986 -197.659244) (xy 373.655336 -197.652386) (xy 373.662194 -197.634606)
			(xy 373.66194 -197.546722) (xy 373.655082 -197.529196) (xy 373.648478 -197.522084) (xy 373.62959 -197.500829)
			(xy 373.597656 -197.453785) (xy 373.573064 -197.402519) (xy 373.556359 -197.348169) (xy 373.547912 -197.291941)
			(xy 373.547386 -197.263512) (xy 373.547863 -197.236142) (xy 373.555678 -197.181964) (xy 373.571165 -197.129461)
			(xy 373.594004 -197.079714) (xy 373.623726 -197.033746) (xy 373.641366 -197.012814) (xy 373.64162 -197.01256)
			(xy 373.64719 -197.005462) (xy 373.653446 -196.988554) (xy 373.653812 -196.97954) (xy 373.653812 -196.912484)
			(xy 373.65346 -196.903467) (xy 373.647209 -196.88655) (xy 373.64162 -196.879464) (xy 373.641366 -196.879464)
			(xy 373.641366 -196.87921) (xy 373.623735 -196.858269) (xy 373.594007 -196.812303) (xy 373.571159 -196.762559)
			(xy 373.55566 -196.710058) (xy 373.547829 -196.65588) (xy 373.547828 -196.601139) (xy 373.555656 -196.54696)
			(xy 373.571152 -196.494458) (xy 373.593998 -196.444713) (xy 373.623725 -196.398746) (xy 373.641366 -196.377814)
			(xy 373.64162 -196.37756) (xy 373.64719 -196.370462) (xy 373.653446 -196.353554) (xy 373.653812 -196.34454)
			(xy 373.653812 -196.277484) (xy 373.65346 -196.268467) (xy 373.647209 -196.25155) (xy 373.64162 -196.244464)
			(xy 373.641366 -196.244464) (xy 373.641366 -196.24421) (xy 373.623735 -196.223269) (xy 373.594007 -196.177303)
			(xy 373.571159 -196.127559) (xy 373.55566 -196.075058) (xy 373.547829 -196.02088) (xy 373.547828 -195.966139)
			(xy 373.555656 -195.91196) (xy 373.571152 -195.859458) (xy 373.593998 -195.809713) (xy 373.623725 -195.763746)
			(xy 373.641366 -195.742814) (xy 373.64162 -195.74256) (xy 373.64719 -195.735462) (xy 373.653446 -195.718554)
			(xy 373.653812 -195.70954) (xy 373.653812 -195.642484) (xy 373.65346 -195.633467) (xy 373.647209 -195.61655)
			(xy 373.64162 -195.609464) (xy 373.641366 -195.609464) (xy 373.641366 -195.60921) (xy 373.623713 -195.588289)
			(xy 373.594004 -195.542313) (xy 373.571172 -195.492562) (xy 373.555684 -195.440059) (xy 373.547859 -195.385882)
			(xy 373.547386 -195.358512) (xy 373.547824 -195.331377) (xy 373.55552 -195.277654) (xy 373.570759 -195.225567)
			(xy 373.593232 -195.176167) (xy 373.622484 -195.130455) (xy 373.639842 -195.109592) (xy 373.64551 -195.102406)
			(xy 373.651749 -195.085213) (xy 373.652034 -195.076064) (xy 373.65178 -195.009262) (xy 373.651295 -195.000206)
			(xy 373.644787 -194.98329) (xy 373.63908 -194.976242) (xy 373.638826 -194.975988) (xy 373.620929 -194.954967)
			(xy 373.590737 -194.908747) (xy 373.567523 -194.858658) (xy 373.551771 -194.805746) (xy 373.543812 -194.751116)
			(xy 373.543322 -194.723512) (xy 371.560598 -194.723512) (xy 371.560133 -194.750482) (xy 371.552525 -194.803882)
			(xy 371.537465 -194.855676) (xy 371.515251 -194.90483) (xy 371.486329 -194.95036) (xy 371.469158 -194.971162)
			(xy 371.463622 -194.978336) (xy 371.457502 -194.995379) (xy 371.45722 -195.004436) (xy 371.457982 -195.08089)
			(xy 371.464332 -195.097654) (xy 371.470682 -195.104766) (xy 371.488769 -195.125842) (xy 371.519276 -195.172249)
			(xy 371.542738 -195.222587) (xy 371.558659 -195.275793) (xy 371.566704 -195.330744) (xy 371.567202 -195.358512)
			(xy 371.566742 -195.385882) (xy 371.558923 -195.440062) (xy 371.543432 -195.492565) (xy 371.520589 -195.542312)
			(xy 371.490864 -195.588278) (xy 371.473222 -195.60921) (xy 371.472968 -195.609464) (xy 371.467387 -195.616554)
			(xy 371.461138 -195.633468) (xy 371.460776 -195.642484) (xy 371.460776 -195.70954) (xy 371.461119 -195.718558)
			(xy 371.467377 -195.735475) (xy 371.472968 -195.74256) (xy 371.473222 -195.74256) (xy 371.473222 -195.742814)
			(xy 371.490872 -195.763738) (xy 371.520593 -195.809709) (xy 371.543435 -195.859457) (xy 371.558928 -195.91196)
			(xy 371.566754 -195.966138) (xy 371.566753 -196.02088) (xy 371.558924 -196.075058) (xy 371.543428 -196.12756)
			(xy 371.520584 -196.177307) (xy 371.490861 -196.223276) (xy 371.473222 -196.24421) (xy 371.472968 -196.244464)
			(xy 371.467387 -196.251554) (xy 371.461138 -196.268468) (xy 371.460776 -196.277484) (xy 371.460776 -196.34454)
			(xy 371.461119 -196.353558) (xy 371.467377 -196.370475) (xy 371.472968 -196.37756) (xy 371.473222 -196.37756)
			(xy 371.473222 -196.377814) (xy 371.490872 -196.398738) (xy 371.520593 -196.444709) (xy 371.543435 -196.494457)
			(xy 371.558928 -196.54696) (xy 371.566754 -196.601138) (xy 371.566753 -196.65588) (xy 371.558924 -196.710058)
			(xy 371.543428 -196.76256) (xy 371.520584 -196.812307) (xy 371.490861 -196.858276) (xy 371.473222 -196.87921)
			(xy 371.472968 -196.879464) (xy 371.467387 -196.886554) (xy 371.461138 -196.903468) (xy 371.460776 -196.912484)
			(xy 371.460776 -196.97954) (xy 371.461119 -196.988558) (xy 371.467377 -197.005475) (xy 371.472968 -197.01256)
			(xy 371.473222 -197.01256) (xy 371.473222 -197.012814) (xy 371.490838 -197.033765) (xy 371.520552 -197.079733)
			(xy 371.543392 -197.129476) (xy 371.558889 -197.181972) (xy 371.566724 -197.236144) (xy 371.567202 -197.263512)
			(xy 371.566685 -197.291658) (xy 371.558418 -197.347339) (xy 371.542064 -197.401202) (xy 371.517979 -197.45208)
			(xy 371.486683 -197.498871) (xy 371.468142 -197.520052) (xy 371.461792 -197.52691) (xy 371.454934 -197.54469)
			(xy 371.455188 -197.632574) (xy 371.462046 -197.6501) (xy 371.46865 -197.657212) (xy 371.48754 -197.678465)
			(xy 371.519473 -197.72551) (xy 371.544064 -197.776776) (xy 371.560768 -197.831126) (xy 371.569215 -197.887354)
			(xy 371.569742 -197.915784) (xy 371.569281 -197.943155) (xy 371.561464 -197.997334) (xy 371.545974 -198.049838)
			(xy 371.523131 -198.099585) (xy 371.493405 -198.145551) (xy 371.475762 -198.166482) (xy 371.475508 -198.166736)
			(xy 371.469943 -198.173837) (xy 371.463683 -198.190743) (xy 371.463316 -198.199756) (xy 371.463316 -198.266812)
			(xy 371.463664 -198.27583) (xy 371.469917 -198.292747) (xy 371.475508 -198.299832) (xy 371.475762 -198.299832)
			(xy 371.475762 -198.300086) (xy 371.493387 -198.321031) (xy 371.523114 -198.366997) (xy 371.545961 -198.416741)
			(xy 371.561459 -198.469241) (xy 371.569289 -198.523418) (xy 371.569291 -198.578158) (xy 371.561464 -198.632335)
			(xy 371.545969 -198.684837) (xy 371.523125 -198.734582) (xy 371.493402 -198.78055) (xy 371.475762 -198.801482)
			(xy 371.475508 -198.801736) (xy 371.469943 -198.808837) (xy 371.463683 -198.825743) (xy 371.463316 -198.834756)
			(xy 371.463316 -198.901812) (xy 371.463664 -198.91083) (xy 371.469917 -198.927747) (xy 371.475508 -198.934832)
			(xy 371.475762 -198.934832) (xy 371.475762 -198.935086) (xy 371.493387 -198.956031) (xy 371.523114 -199.001997)
			(xy 371.545961 -199.051741) (xy 371.561459 -199.104241) (xy 371.569289 -199.158418) (xy 371.569291 -199.213158)
			(xy 371.561464 -199.267335) (xy 371.545969 -199.319837) (xy 371.523125 -199.369582) (xy 371.493402 -199.41555)
			(xy 371.475762 -199.436482) (xy 371.475508 -199.436736) (xy 371.469943 -199.443837) (xy 371.463683 -199.460743)
			(xy 371.463316 -199.469756) (xy 371.463316 -199.536812) (xy 371.463664 -199.54583) (xy 371.469917 -199.562747)
			(xy 371.475508 -199.569832) (xy 371.475762 -199.569832) (xy 371.475762 -199.570086) (xy 371.493387 -199.591031)
			(xy 371.523114 -199.636997) (xy 371.545961 -199.686741) (xy 371.561459 -199.739241) (xy 371.569289 -199.793418)
			(xy 371.569291 -199.848158) (xy 371.561464 -199.902335) (xy 371.545969 -199.954837) (xy 371.523125 -200.004582)
			(xy 371.493402 -200.05055) (xy 371.475762 -200.071482) (xy 371.475508 -200.071736) (xy 371.469943 -200.078837)
			(xy 371.463683 -200.095743) (xy 371.463316 -200.104756) (xy 371.463316 -200.171812) (xy 371.463664 -200.18083)
			(xy 371.469917 -200.197747) (xy 371.475508 -200.204832) (xy 371.475762 -200.204832) (xy 371.475762 -200.205086)
			(xy 371.493387 -200.226031) (xy 371.523114 -200.271997) (xy 371.545961 -200.321741) (xy 371.561459 -200.374241)
			(xy 371.569289 -200.428418) (xy 371.569291 -200.483158) (xy 371.561464 -200.537335) (xy 371.545969 -200.589837)
			(xy 371.523125 -200.639582) (xy 371.493402 -200.68555) (xy 371.475762 -200.706482) (xy 371.475508 -200.706736)
			(xy 371.469943 -200.713837) (xy 371.463683 -200.730743) (xy 371.463316 -200.739756) (xy 371.463316 -200.806812)
			(xy 371.463664 -200.81583) (xy 371.469917 -200.832747) (xy 371.475508 -200.839832) (xy 371.475762 -200.839832)
			(xy 371.475762 -200.840086) (xy 371.493402 -200.861017) (xy 371.523115 -200.90699) (xy 371.545951 -200.956737)
			(xy 371.561442 -201.009238) (xy 371.569269 -201.063415) (xy 371.569742 -201.090784) (xy 371.569256 -201.118035)
			(xy 371.5615 -201.171983) (xy 371.546145 -201.224278) (xy 371.523503 -201.273855) (xy 371.494037 -201.319705)
			(xy 371.458346 -201.360896) (xy 371.417155 -201.396587) (xy 371.371305 -201.426053) (xy 371.321728 -201.448695)
			(xy 371.269433 -201.46405) (xy 371.215485 -201.471806) (xy 371.160983 -201.471806) (xy 371.107035 -201.46405)
			(xy 371.05474 -201.448695) (xy 371.005163 -201.426053) (xy 370.959313 -201.396587) (xy 370.918122 -201.360896)
			(xy 370.882431 -201.319705) (xy 370.852965 -201.273855) (xy 370.830323 -201.224278) (xy 370.814968 -201.171983)
			(xy 370.807212 -201.118035) (xy 370.806726 -201.090784) (xy 370.807176 -201.063413) (xy 370.814997 -201.009233)
			(xy 370.830489 -200.95673) (xy 370.853335 -200.906983) (xy 370.883063 -200.861017) (xy 370.900706 -200.840086)
			(xy 370.90096 -200.839832) (xy 370.906546 -200.832746) (xy 370.912792 -200.815828) (xy 370.913152 -200.806812)
			(xy 370.913152 -200.739756) (xy 370.912779 -200.730741) (xy 370.906544 -200.713823) (xy 370.90096 -200.706736)
			(xy 370.900706 -200.706736) (xy 370.900706 -200.706482) (xy 370.883093 -200.685529) (xy 370.853377 -200.639562)
			(xy 370.830536 -200.58982) (xy 370.815039 -200.537324) (xy 370.807204 -200.483152) (xy 370.806726 -200.455784)
			(xy 370.807249 -200.426306) (xy 370.816321 -200.368051) (xy 370.834247 -200.311886) (xy 370.860601 -200.259147)
			(xy 370.894753 -200.21109) (xy 370.91493 -200.189592) (xy 370.921465 -200.182258) (xy 370.928909 -200.164097)
			(xy 370.929408 -200.154286) (xy 370.929408 -200.100946) (xy 370.922042 -200.094088) (xy 370.914689 -200.087577)
			(xy 370.896543 -200.080118) (xy 370.886736 -200.07961) (xy 370.854732 -200.07961) (xy 370.844914 -200.080068)
			(xy 370.82675 -200.087532) (xy 370.819426 -200.094088) (xy 370.797921 -200.114255) (xy 370.749862 -200.1484)
			(xy 370.697124 -200.174746) (xy 370.640961 -200.192669) (xy 370.582711 -200.201741) (xy 370.553234 -200.202292)
			(xy 370.525981 -200.201813) (xy 370.47203 -200.19406) (xy 370.419732 -200.178708) (xy 370.37015 -200.156068)
			(xy 370.324296 -200.126602) (xy 370.283103 -200.09091) (xy 370.247409 -200.049718) (xy 370.217941 -200.003865)
			(xy 370.195299 -199.954285) (xy 370.179944 -199.901988) (xy 370.172188 -199.848037) (xy 370.171726 -199.820784)
			(xy 370.172249 -199.791306) (xy 370.181321 -199.733051) (xy 370.199247 -199.676886) (xy 370.225601 -199.624147)
			(xy 370.259753 -199.57609) (xy 370.27993 -199.554592) (xy 370.286465 -199.547258) (xy 370.293909 -199.529097)
			(xy 370.294408 -199.519286) (xy 370.294408 -199.465946) (xy 370.288566 -199.460612) (xy 370.281195 -199.45416)
			(xy 370.263045 -199.446838) (xy 370.25326 -199.446388) (xy 370.22151 -199.446642) (xy 370.211631 -199.447093)
			(xy 370.193332 -199.45454) (xy 370.18595 -199.46112) (xy 370.16443 -199.481586) (xy 370.116174 -199.516201)
			(xy 370.063136 -199.542919) (xy 370.006599 -199.561094) (xy 369.947928 -199.570287) (xy 369.918234 -199.570848)
			(xy 369.890985 -199.57029) (xy 369.837042 -199.562539) (xy 369.784751 -199.547191) (xy 369.735177 -199.524556)
			(xy 369.689329 -199.495097) (xy 369.648139 -199.459413) (xy 369.612447 -199.418231) (xy 369.582979 -199.372388)
			(xy 369.560335 -199.322818) (xy 369.544976 -199.27053) (xy 369.537215 -199.216588) (xy 369.536726 -199.18934)
			(xy 369.537209 -199.16197) (xy 369.545022 -199.107792) (xy 369.560507 -199.055289) (xy 369.583345 -199.005541)
			(xy 369.613066 -198.959574) (xy 369.630706 -198.938642) (xy 369.63096 -198.938388) (xy 369.636565 -198.931314)
			(xy 369.642799 -198.914387) (xy 369.643152 -198.905368) (xy 369.643152 -198.838312) (xy 369.6428 -198.829294)
			(xy 369.63655 -198.812377) (xy 369.63096 -198.805292) (xy 369.630706 -198.805292) (xy 369.630706 -198.805038)
			(xy 369.613105 -198.784073) (xy 369.583381 -198.73811) (xy 369.560534 -198.688369) (xy 369.545036 -198.635872)
			(xy 369.537204 -198.581699) (xy 369.537199 -198.526962) (xy 369.545023 -198.472787) (xy 369.560513 -198.420287)
			(xy 369.583352 -198.370543) (xy 369.613069 -198.324575) (xy 369.630706 -198.303642) (xy 369.63096 -198.303388)
			(xy 369.636565 -198.296314) (xy 369.642799 -198.279387) (xy 369.643152 -198.270368) (xy 369.643152 -198.203312)
			(xy 369.6428 -198.194294) (xy 369.63655 -198.177377) (xy 369.63096 -198.170292) (xy 369.630706 -198.170292)
			(xy 369.630706 -198.170038) (xy 369.613072 -198.149102) (xy 369.583359 -198.10313) (xy 369.560522 -198.053384)
			(xy 369.54503 -198.000884) (xy 369.537201 -197.946709) (xy 369.536726 -197.91934) (xy 369.537161 -197.892509)
			(xy 369.544677 -197.839377) (xy 369.559567 -197.787823) (xy 369.581536 -197.738865) (xy 369.610151 -197.693469)
			(xy 369.62715 -197.672706) (xy 369.633246 -197.665594) (xy 369.639088 -197.648576) (xy 369.638072 -197.572376)
			(xy 369.637568 -197.563234) (xy 369.630923 -197.546184) (xy 369.625118 -197.539102) (xy 369.60687 -197.517978)
			(xy 369.576037 -197.471447) (xy 369.552316 -197.420918) (xy 369.536213 -197.367472) (xy 369.528071 -197.31225)
			(xy 369.527582 -197.28434) (xy 360.128807 -197.28434) (xy 366.496346 -201.61885) (xy 366.502798 -201.62296)
			(xy 366.517402 -201.627493) (xy 366.525048 -201.62774)
		)
		(stroke
			(width 0)
			(type solid)
		)
		(fill yes)
		(layer "In2.Cu")
		(net "GND")
	)
	(gr_poly
		(pts
			(xy 368.431064 -251.185172) (xy 368.440901 -251.184636) (xy 368.459061 -251.177048) (xy 368.46637 -251.17044)
			(xy 369.305586 -250.331224) (xy 369.312821 -250.324503) (xy 369.331026 -250.316894) (xy 369.340892 -250.316492)
			(xy 370.123974 -250.316492) (xy 370.134995 -250.315956) (xy 370.155017 -250.306743) (xy 370.162582 -250.298712)
			(xy 370.218716 -250.232926) (xy 370.224812 -250.212098) (xy 370.223034 -250.200922) (xy 370.221357 -250.189311)
			(xy 370.219577 -250.165917) (xy 370.219478 -250.154186) (xy 370.22 -250.128931) (xy 370.228313 -250.079109)
			(xy 370.244714 -250.031335) (xy 370.268755 -249.986912) (xy 370.299779 -249.947052) (xy 370.336941 -249.912842)
			(xy 370.379227 -249.885216) (xy 370.425483 -249.864926) (xy 370.474448 -249.852526) (xy 370.524786 -249.848355)
			(xy 370.575124 -249.852526) (xy 370.624089 -249.864926) (xy 370.670345 -249.885216) (xy 370.712631 -249.912842)
			(xy 370.749793 -249.947052) (xy 370.780817 -249.986912) (xy 370.804858 -250.031335) (xy 370.821259 -250.079109)
			(xy 370.829572 -250.128931) (xy 370.830094 -250.154186) (xy 372.09909 -250.154186) (xy 372.10305 -250.105132)
			(xy 372.114827 -250.057348) (xy 372.134118 -250.012072) (xy 372.160421 -249.970476) (xy 372.193056 -249.933639)
			(xy 372.231177 -249.902514) (xy 372.273798 -249.877907) (xy 372.319814 -249.860455) (xy 372.368033 -249.850611)
			(xy 372.417208 -249.84863) (xy 372.466063 -249.854562) (xy 372.513334 -249.868254) (xy 372.557796 -249.889352)
			(xy 372.598299 -249.917308) (xy 372.633792 -249.9514) (xy 372.663357 -249.990744) (xy 372.686228 -250.034321)
			(xy 372.701812 -250.081002) (xy 372.709707 -250.129579) (xy 372.710202 -250.154186) (xy 372.709707 -250.178793)
			(xy 372.701812 -250.22737) (xy 372.686228 -250.274051) (xy 372.663357 -250.317628) (xy 372.633792 -250.356972)
			(xy 372.598299 -250.391064) (xy 372.557796 -250.41902) (xy 372.513334 -250.440118) (xy 372.466063 -250.45381)
			(xy 372.417208 -250.459742) (xy 372.368033 -250.457761) (xy 372.319814 -250.447917) (xy 372.273798 -250.430465)
			(xy 372.231177 -250.405858) (xy 372.193056 -250.374733) (xy 372.160421 -250.337896) (xy 372.134118 -250.2963)
			(xy 372.114827 -250.251024) (xy 372.10305 -250.20324) (xy 372.09909 -250.154186) (xy 370.830094 -250.154186)
			(xy 370.829575 -250.180127) (xy 370.8208 -250.231261) (xy 370.803502 -250.280173) (xy 370.778179 -250.325455)
			(xy 370.762276 -250.345956) (xy 370.756434 -250.353322) (xy 370.750592 -250.370848) (xy 370.754402 -250.446794)
			(xy 370.755285 -250.456093) (xy 370.76285 -250.473155) (xy 370.769134 -250.480068) (xy 370.933726 -250.64466)
			(xy 370.941124 -250.651507) (xy 370.959722 -250.659238) (xy 370.969794 -250.659646) (xy 370.97462 -250.659646)
			(xy 370.99494 -250.658884) (xy 370.995194 -250.658884) (xy 371.019135 -250.659389) (xy 371.066418 -250.666941)
			(xy 371.111944 -250.681781) (xy 371.154594 -250.703546) (xy 371.193324 -250.731702) (xy 371.227183 -250.765559)
			(xy 371.255342 -250.804287) (xy 371.277111 -250.846936) (xy 371.291954 -250.89246) (xy 371.299509 -250.939743)
			(xy 371.299994 -250.963684) (xy 371.299994 -250.964192) (xy 371.299232 -250.985528) (xy 371.29847 -250.996704)
			(xy 371.30609 -251.017024) (xy 371.459252 -251.170186) (xy 371.466653 -251.177026) (xy 371.485251 -251.184744)
			(xy 371.49532 -251.185172) (xy 372.258844 -251.185172) (xy 372.268683 -251.18464) (xy 372.286848 -251.177057)
			(xy 372.29415 -251.17044) (xy 372.575328 -250.889262) (xy 372.581424 -250.879102) (xy 372.583456 -250.873006)
			(xy 372.591254 -250.849732) (xy 372.613221 -250.805841) (xy 372.641927 -250.766031) (xy 372.676632 -250.731325)
			(xy 372.716444 -250.70262) (xy 372.760335 -250.680653) (xy 372.783608 -250.672854) (xy 372.789704 -250.670822)
			(xy 372.799864 -250.664726) (xy 372.996206 -250.468384) (xy 373.003444 -250.461671) (xy 373.021649 -250.454075)
			(xy 373.031512 -250.453652) (xy 373.597424 -250.453652) (xy 373.607266 -250.453125) (xy 373.625444 -250.445556)
			(xy 373.63273 -250.43892) (xy 373.982488 -250.089162) (xy 373.989092 -250.077986) (xy 373.99087 -250.071636)
			(xy 373.998423 -250.046708) (xy 374.020818 -249.999684) (xy 374.050868 -249.957143) (xy 374.087701 -249.920318)
			(xy 374.13025 -249.890279) (xy 374.177279 -249.867896) (xy 374.202198 -249.860308) (xy 374.208548 -249.85853)
			(xy 374.219724 -249.851926) (xy 374.485916 -249.585734) (xy 374.492761 -249.578336) (xy 374.500485 -249.559737)
			(xy 374.500902 -249.549666) (xy 374.500902 -249.521218) (xy 374.497346 -249.50801) (xy 374.493536 -249.502168)
			(xy 374.479741 -249.478149) (xy 374.460129 -249.426353) (xy 374.450162 -249.371872) (xy 374.449594 -249.34418)
			(xy 374.450066 -249.32019) (xy 374.457575 -249.272801) (xy 374.472404 -249.227169) (xy 374.494189 -249.18442)
			(xy 374.522392 -249.145604) (xy 374.556321 -249.111678) (xy 374.595139 -249.083477) (xy 374.63789 -249.061695)
			(xy 374.683522 -249.04687) (xy 374.730912 -249.039364) (xy 374.754902 -249.038872) (xy 374.778667 -249.039339)
			(xy 374.82562 -249.046731) (xy 374.848374 -249.053604) (xy 374.860058 -249.057414) (xy 374.883934 -249.053604)
			(xy 374.95861 -248.998994) (xy 374.967951 -248.991372) (xy 374.978809 -248.969887) (xy 374.979438 -248.957846)
			(xy 374.979438 -248.739152) (xy 374.979359 -248.735409) (xy 374.978212 -248.728011) (xy 374.977152 -248.72442)
			(xy 374.97131 -248.704354) (xy 374.9675 -248.698512) (xy 374.954558 -248.677346) (xy 374.93497 -248.631769)
			(xy 374.923008 -248.583624) (xy 374.918987 -248.534178) (xy 374.923015 -248.484733) (xy 374.934984 -248.43659)
			(xy 374.954579 -248.391015) (xy 374.9675 -248.369836) (xy 374.97131 -248.363994) (xy 374.977152 -248.343928)
			(xy 374.978187 -248.340332) (xy 374.979331 -248.332937) (xy 374.979438 -248.329196) (xy 374.979438 -248.110502)
			(xy 374.978775 -248.098472) (xy 374.967922 -248.076996) (xy 374.95861 -248.069354) (xy 374.883934 -248.014744)
			(xy 374.860058 -248.010934) (xy 374.848374 -248.014744) (xy 374.825616 -248.021605) (xy 374.778667 -248.029008)
			(xy 374.754902 -248.029476) (xy 374.729647 -248.028984) (xy 374.679825 -248.02067) (xy 374.632052 -248.00427)
			(xy 374.587629 -247.98023) (xy 374.547769 -247.949206) (xy 374.513559 -247.912044) (xy 374.485933 -247.869759)
			(xy 374.465643 -247.823503) (xy 374.453243 -247.774538) (xy 374.449072 -247.7242) (xy 374.453243 -247.673862)
			(xy 374.465643 -247.624897) (xy 374.485933 -247.578641) (xy 374.513559 -247.536356) (xy 374.547769 -247.499194)
			(xy 374.587629 -247.46817) (xy 374.632052 -247.44413) (xy 374.679825 -247.42773) (xy 374.729647 -247.419416)
			(xy 374.754902 -247.41886) (xy 374.778667 -247.419327) (xy 374.82562 -247.426719) (xy 374.848374 -247.433592)
			(xy 374.860058 -247.437402) (xy 374.883934 -247.433592) (xy 374.95861 -247.378982) (xy 374.967948 -247.371359)
			(xy 374.978802 -247.349874) (xy 374.979438 -247.337834) (xy 374.979438 -247.11914) (xy 374.979358 -247.115397)
			(xy 374.97821 -247.107999) (xy 374.977152 -247.104408) (xy 374.97131 -247.084342) (xy 374.9675 -247.0785)
			(xy 374.954559 -247.057334) (xy 374.934972 -247.011757) (xy 374.923012 -246.963613) (xy 374.918994 -246.914168)
			(xy 374.923023 -246.864724) (xy 374.934993 -246.816582) (xy 374.954589 -246.771009) (xy 374.9675 -246.749824)
			(xy 374.97131 -246.743982) (xy 374.977152 -246.723916) (xy 374.978186 -246.72032) (xy 374.979329 -246.712925)
			(xy 374.979438 -246.709184) (xy 374.979438 -246.49049) (xy 374.978772 -246.478461) (xy 374.967917 -246.456989)
			(xy 374.95861 -246.449342) (xy 374.883934 -246.394732) (xy 374.860058 -246.390922) (xy 374.848374 -246.394732)
			(xy 374.825616 -246.401593) (xy 374.778667 -246.408996) (xy 374.754902 -246.409464) (xy 374.729648 -246.408972)
			(xy 374.679828 -246.400659) (xy 374.632056 -246.384259) (xy 374.587636 -246.36022) (xy 374.547777 -246.329197)
			(xy 374.513569 -246.292037) (xy 374.485943 -246.249753) (xy 374.465654 -246.203499) (xy 374.453255 -246.154536)
			(xy 374.449084 -246.1042) (xy 374.453255 -246.053864) (xy 374.465654 -246.004901) (xy 374.485943 -245.958647)
			(xy 374.513569 -245.916363) (xy 374.547777 -245.879203) (xy 374.587636 -245.84818) (xy 374.632056 -245.824141)
			(xy 374.679828 -245.807741) (xy 374.729648 -245.799428) (xy 374.754902 -245.798848) (xy 374.778667 -245.799316)
			(xy 374.825619 -245.806709) (xy 374.848374 -245.81358) (xy 374.860058 -245.81739) (xy 374.883934 -245.81358)
			(xy 374.95861 -245.75897) (xy 374.967963 -245.751353) (xy 374.978854 -245.729869) (xy 374.979438 -245.717822)
			(xy 374.979438 -245.499128) (xy 374.979357 -245.495385) (xy 374.978207 -245.487988) (xy 374.977152 -245.484396)
			(xy 374.97131 -245.46433) (xy 374.9675 -245.458488) (xy 374.954552 -245.437322) (xy 374.934951 -245.391742)
			(xy 374.922978 -245.343594) (xy 374.918947 -245.294142) (xy 374.922964 -245.24469) (xy 374.934924 -245.196538)
			(xy 374.954513 -245.150953) (xy 374.9675 -245.129812) (xy 374.97131 -245.12397) (xy 374.977152 -245.103904)
			(xy 374.978185 -245.100308) (xy 374.979326 -245.092912) (xy 374.979438 -245.089172) (xy 374.979438 -244.870478)
			(xy 374.97877 -244.858451) (xy 374.967911 -244.836983) (xy 374.95861 -244.82933) (xy 374.883934 -244.77472)
			(xy 374.860058 -244.77091) (xy 374.848374 -244.77472) (xy 374.825617 -244.781581) (xy 374.778667 -244.788985)
			(xy 374.754902 -244.789452) (xy 374.729641 -244.788959) (xy 374.679807 -244.780644) (xy 374.632021 -244.764239)
			(xy 374.587587 -244.740193) (xy 374.547718 -244.709162) (xy 374.513499 -244.671991) (xy 374.485866 -244.629695)
			(xy 374.465571 -244.583427) (xy 374.453168 -244.53445) (xy 374.448996 -244.4841) (xy 374.453168 -244.43375)
			(xy 374.465571 -244.384773) (xy 374.485866 -244.338505) (xy 374.513499 -244.296209) (xy 374.547718 -244.259038)
			(xy 374.587587 -244.228007) (xy 374.632021 -244.203961) (xy 374.679807 -244.187556) (xy 374.729641 -244.179241)
			(xy 374.754902 -244.178836) (xy 374.778667 -244.179304) (xy 374.825619 -244.186697) (xy 374.848374 -244.193568)
			(xy 374.860058 -244.197378) (xy 374.883934 -244.193568) (xy 374.95861 -244.138958) (xy 374.967961 -244.13134)
			(xy 374.978847 -244.109856) (xy 374.979438 -244.09781) (xy 374.979438 -243.879116) (xy 374.979356 -243.875373)
			(xy 374.978205 -243.867977) (xy 374.977152 -243.864384) (xy 374.97131 -243.844318) (xy 374.9675 -243.838476)
			(xy 374.954553 -243.81731) (xy 374.934954 -243.771731) (xy 374.922982 -243.723582) (xy 374.918953 -243.674132)
			(xy 374.922972 -243.624681) (xy 374.934934 -243.57653) (xy 374.954523 -243.530947) (xy 374.9675 -243.5098)
			(xy 374.97131 -243.503958) (xy 374.977152 -243.483892) (xy 374.978191 -243.480296) (xy 374.979345 -243.472901)
			(xy 374.979438 -243.46916) (xy 374.979438 -243.250466) (xy 374.978767 -243.23844) (xy 374.967906 -243.216976)
			(xy 374.95861 -243.209318) (xy 374.883934 -243.154708) (xy 374.860058 -243.150898) (xy 374.848374 -243.154708)
			(xy 374.825617 -243.16157) (xy 374.778667 -243.168974) (xy 374.754902 -243.16944) (xy 374.729642 -243.168947)
			(xy 374.67981 -243.160632) (xy 374.632026 -243.144228) (xy 374.587594 -243.120183) (xy 374.547726 -243.089153)
			(xy 374.513509 -243.051983) (xy 374.485876 -243.009689) (xy 374.465582 -242.963423) (xy 374.45318 -242.914448)
			(xy 374.449008 -242.8641) (xy 374.45318 -242.813752) (xy 374.465582 -242.764777) (xy 374.485876 -242.718511)
			(xy 374.513509 -242.676217) (xy 374.547726 -242.639047) (xy 374.587594 -242.608017) (xy 374.632026 -242.583972)
			(xy 374.67981 -242.567568) (xy 374.729642 -242.559253) (xy 374.754902 -242.558824) (xy 374.778667 -242.559292)
			(xy 374.825619 -242.566685) (xy 374.848374 -242.573556) (xy 374.860058 -242.577366) (xy 374.883934 -242.573556)
			(xy 374.95861 -242.518946) (xy 374.967959 -242.511327) (xy 374.97884 -242.489843) (xy 374.979438 -242.477798)
			(xy 374.979438 -242.259104) (xy 374.979355 -242.255362) (xy 374.978202 -242.247965) (xy 374.977152 -242.244372)
			(xy 374.97131 -242.224306) (xy 374.9675 -242.218464) (xy 374.954554 -242.197298) (xy 374.934957 -242.151719)
			(xy 374.922987 -242.103571) (xy 374.918959 -242.054122) (xy 374.92298 -242.004672) (xy 374.934943 -241.956523)
			(xy 374.954534 -241.910941) (xy 374.9675 -241.889788) (xy 374.97131 -241.883946) (xy 374.977152 -241.86388)
			(xy 374.97819 -241.860284) (xy 374.979342 -241.852889) (xy 374.979438 -241.849148) (xy 374.979438 -241.630454)
			(xy 374.978765 -241.618429) (xy 374.9679 -241.59697) (xy 374.95861 -241.589306) (xy 374.883934 -241.534696)
			(xy 374.860058 -241.530886) (xy 374.848374 -241.534696) (xy 374.825617 -241.541558) (xy 374.778667 -241.548962)
			(xy 374.754902 -241.549428) (xy 374.729643 -241.548935) (xy 374.679813 -241.540621) (xy 374.632031 -241.524217)
			(xy 374.587601 -241.500173) (xy 374.547734 -241.469144) (xy 374.513518 -241.431976) (xy 374.485887 -241.389683)
			(xy 374.465594 -241.343419) (xy 374.453192 -241.294446) (xy 374.44902 -241.2441) (xy 374.453192 -241.193754)
			(xy 374.465594 -241.144781) (xy 374.485887 -241.098517) (xy 374.513518 -241.056224) (xy 374.547734 -241.019056)
			(xy 374.587601 -240.988027) (xy 374.632031 -240.963983) (xy 374.679813 -240.947579) (xy 374.729643 -240.939265)
			(xy 374.754902 -240.938812) (xy 374.778667 -240.93928) (xy 374.82562 -240.946672) (xy 374.848374 -240.953544)
			(xy 374.860058 -240.957354) (xy 374.883934 -240.953544) (xy 374.95861 -240.898934) (xy 374.967957 -240.891315)
			(xy 374.978833 -240.86983) (xy 374.979438 -240.857786) (xy 374.979438 -240.639092) (xy 374.979354 -240.63535)
			(xy 374.978199 -240.627954) (xy 374.977152 -240.62436) (xy 374.97131 -240.604294) (xy 374.9675 -240.598452)
			(xy 374.954555 -240.577286) (xy 374.93496 -240.531707) (xy 374.922992 -240.48356) (xy 374.918966 -240.434112)
			(xy 374.922988 -240.384663) (xy 374.934952 -240.336515) (xy 374.954544 -240.290935) (xy 374.9675 -240.269776)
			(xy 374.97131 -240.263934) (xy 374.977152 -240.243868) (xy 374.978189 -240.240272) (xy 374.97934 -240.232877)
			(xy 374.979438 -240.229136) (xy 374.979438 -240.010442) (xy 374.978762 -239.998419) (xy 374.967895 -239.976963)
			(xy 374.95861 -239.969294) (xy 374.883934 -239.914684) (xy 374.860058 -239.910874) (xy 374.848374 -239.914684)
			(xy 374.825617 -239.921546) (xy 374.778667 -239.928951) (xy 374.754902 -239.929416) (xy 374.729644 -239.928923)
			(xy 374.679815 -239.920609) (xy 374.632036 -239.904206) (xy 374.587607 -239.880163) (xy 374.547742 -239.849135)
			(xy 374.513528 -239.811969) (xy 374.485897 -239.769678) (xy 374.465605 -239.723416) (xy 374.453204 -239.674444)
			(xy 374.449032 -239.6241) (xy 374.453204 -239.573756) (xy 374.465605 -239.524784) (xy 374.485897 -239.478522)
			(xy 374.513528 -239.436231) (xy 374.547742 -239.399065) (xy 374.587607 -239.368037) (xy 374.632036 -239.343994)
			(xy 374.679815 -239.327591) (xy 374.729644 -239.319277) (xy 374.754902 -239.3188) (xy 374.778667 -239.319268)
			(xy 374.82562 -239.32666) (xy 374.848374 -239.333532) (xy 374.860058 -239.337342) (xy 374.883934 -239.333532)
			(xy 374.95861 -239.278922) (xy 374.967955 -239.271302) (xy 374.978825 -239.249817) (xy 374.979438 -239.237774)
			(xy 374.979438 -239.01908) (xy 374.979361 -239.015337) (xy 374.978218 -239.007937) (xy 374.977152 -239.004348)
			(xy 374.97131 -238.984282) (xy 374.9675 -238.97844) (xy 374.954556 -238.957274) (xy 374.934963 -238.911696)
			(xy 374.922997 -238.863549) (xy 374.918972 -238.814102) (xy 374.922996 -238.764654) (xy 374.934962 -238.716507)
			(xy 374.954554 -238.670929) (xy 374.9675 -238.649764) (xy 374.97131 -238.643922) (xy 374.977152 -238.623856)
			(xy 374.978189 -238.62026) (xy 374.979337 -238.612865) (xy 374.979438 -238.609124) (xy 374.979438 -238.39043)
			(xy 374.978781 -238.378397) (xy 374.967935 -238.356911) (xy 374.95861 -238.349282) (xy 374.883934 -238.294672)
			(xy 374.860058 -238.290862) (xy 374.848374 -238.294672) (xy 374.825616 -238.301532) (xy 374.778666 -238.308935)
			(xy 374.754902 -238.309404) (xy 374.729645 -238.308912) (xy 374.679818 -238.300597) (xy 374.63204 -238.284195)
			(xy 374.587614 -238.260153) (xy 374.54775 -238.229126) (xy 374.513537 -238.191961) (xy 374.485908 -238.149672)
			(xy 374.465616 -238.103412) (xy 374.453216 -238.054442) (xy 374.449044 -238.0041) (xy 374.453216 -237.953758)
			(xy 374.465616 -237.904788) (xy 374.485908 -237.858528) (xy 374.513537 -237.816239) (xy 374.54775 -237.779074)
			(xy 374.587614 -237.748047) (xy 374.63204 -237.724005) (xy 374.679818 -237.707603) (xy 374.729645 -237.699288)
			(xy 374.754902 -237.698788) (xy 374.778667 -237.699256) (xy 374.82562 -237.706648) (xy 374.848374 -237.71352)
			(xy 374.860058 -237.71733) (xy 374.883934 -237.71352) (xy 374.95861 -237.65891) (xy 374.967953 -237.651289)
			(xy 374.978818 -237.629804) (xy 374.979438 -237.617762) (xy 374.979438 -237.399068) (xy 374.97936 -237.395325)
			(xy 374.978216 -237.387926) (xy 374.977152 -237.384336) (xy 374.97131 -237.36427) (xy 374.9675 -237.358428)
			(xy 374.954557 -237.337262) (xy 374.934966 -237.291684) (xy 374.923001 -237.243538) (xy 374.918979 -237.194092)
			(xy 374.923004 -237.144645) (xy 374.934971 -237.0965) (xy 374.954565 -237.050923) (xy 374.9675 -237.029752)
			(xy 374.97131 -237.02391) (xy 374.977152 -237.003844) (xy 374.978188 -237.000248) (xy 374.979335 -236.992853)
			(xy 374.979438 -236.989112) (xy 374.979438 -236.770418) (xy 374.978778 -236.758386) (xy 374.96793 -236.736905)
			(xy 374.95861 -236.72927) (xy 374.883934 -236.67466) (xy 374.860058 -236.67085) (xy 374.848374 -236.67466)
			(xy 374.825616 -236.681521) (xy 374.778666 -236.688923) (xy 374.754902 -236.689392) (xy 374.729645 -236.6889)
			(xy 374.679821 -236.680586) (xy 374.632045 -236.664184) (xy 374.58762 -236.640143) (xy 374.547758 -236.609117)
			(xy 374.513547 -236.571954) (xy 374.485919 -236.529666) (xy 374.465628 -236.483408) (xy 374.453227 -236.43444)
			(xy 374.449056 -236.3841) (xy 374.453227 -236.33376) (xy 374.465628 -236.284792) (xy 374.485919 -236.238534)
			(xy 374.513547 -236.196246) (xy 374.547758 -236.159083) (xy 374.58762 -236.128057) (xy 374.632045 -236.104016)
			(xy 374.679821 -236.087614) (xy 374.729645 -236.0793) (xy 374.754902 -236.078776) (xy 374.778667 -236.079243)
			(xy 374.82562 -236.086635) (xy 374.848374 -236.093508) (xy 374.860058 -236.097318) (xy 374.883934 -236.093508)
			(xy 374.95861 -236.038898) (xy 374.967951 -236.031276) (xy 374.978811 -236.009791) (xy 374.979438 -235.99775)
			(xy 374.979438 -235.779056) (xy 374.979359 -235.775313) (xy 374.978213 -235.767914) (xy 374.977152 -235.764324)
			(xy 374.97131 -235.744258) (xy 374.9675 -235.738416) (xy 374.954558 -235.71725) (xy 374.934969 -235.671672)
			(xy 374.923006 -235.623527) (xy 374.918985 -235.574081) (xy 374.923012 -235.524636) (xy 374.93498 -235.476492)
			(xy 374.954575 -235.430917) (xy 374.9675 -235.40974) (xy 374.97131 -235.403898) (xy 374.977152 -235.383832)
			(xy 374.978187 -235.380236) (xy 374.979332 -235.372841) (xy 374.979438 -235.3691) (xy 374.979438 -235.150406)
			(xy 374.978776 -235.138376) (xy 374.967924 -235.116898) (xy 374.95861 -235.109258) (xy 374.883934 -235.054648)
			(xy 374.860058 -235.050838) (xy 374.848374 -235.054648) (xy 374.825616 -235.061509) (xy 374.778667 -235.068912)
			(xy 374.754902 -235.06938) (xy 374.729646 -235.068888) (xy 374.679824 -235.060574) (xy 374.63205 -235.044173)
			(xy 374.587627 -235.020133) (xy 374.547766 -234.989109) (xy 374.513556 -234.951947) (xy 374.485929 -234.90966)
			(xy 374.465639 -234.863404) (xy 374.453239 -234.814439) (xy 374.449068 -234.7641) (xy 374.453239 -234.713761)
			(xy 374.465639 -234.664796) (xy 374.485929 -234.61854) (xy 374.513556 -234.576253) (xy 374.547766 -234.539091)
			(xy 374.587627 -234.508067) (xy 374.63205 -234.484027) (xy 374.679824 -234.467626) (xy 374.729646 -234.459312)
			(xy 374.754902 -234.458764) (xy 374.778667 -234.459231) (xy 374.82562 -234.466623) (xy 374.848374 -234.473496)
			(xy 374.860058 -234.477306) (xy 374.883934 -234.473496) (xy 374.95861 -234.418886) (xy 374.967949 -234.411263)
			(xy 374.978804 -234.389779) (xy 374.979438 -234.377738) (xy 374.979438 -234.159044) (xy 374.979358 -234.155301)
			(xy 374.978211 -234.147903) (xy 374.977152 -234.144312) (xy 374.97131 -234.124246) (xy 374.9675 -234.118404)
			(xy 374.954559 -234.097238) (xy 374.934971 -234.051661) (xy 374.923011 -234.003516) (xy 374.918992 -233.954071)
			(xy 374.92302 -233.904627) (xy 374.93499 -233.856485) (xy 374.954586 -233.810911) (xy 374.9675 -233.789728)
			(xy 374.97131 -233.783886) (xy 374.977152 -233.76382) (xy 374.978186 -233.760224) (xy 374.97933 -233.752829)
			(xy 374.979438 -233.749088) (xy 374.979438 -233.530394) (xy 374.978773 -233.518365) (xy 374.967919 -233.496892)
			(xy 374.95861 -233.489246) (xy 374.883934 -233.434636) (xy 374.860058 -233.430826) (xy 374.848374 -233.434636)
			(xy 374.825616 -233.441497) (xy 374.778667 -233.4489) (xy 374.754902 -233.449368) (xy 374.729647 -233.448876)
			(xy 374.679827 -233.440562) (xy 374.632055 -233.424162) (xy 374.587633 -233.400123) (xy 374.547775 -233.3691)
			(xy 374.513566 -233.331939) (xy 374.48594 -233.289655) (xy 374.46565 -233.2434) (xy 374.453251 -233.194437)
			(xy 374.44908 -233.1441) (xy 374.453251 -233.093763) (xy 374.46565 -233.0448) (xy 374.48594 -232.998545)
			(xy 374.513566 -232.956261) (xy 374.547775 -232.9191) (xy 374.587633 -232.888077) (xy 374.632055 -232.864038)
			(xy 374.679827 -232.847638) (xy 374.729647 -232.839324) (xy 374.754902 -232.838752) (xy 374.778667 -232.83922)
			(xy 374.825619 -232.846613) (xy 374.848374 -232.853484) (xy 374.860058 -232.857294) (xy 374.883934 -232.853484)
			(xy 374.95861 -232.798874) (xy 374.967947 -232.791251) (xy 374.978797 -232.769766) (xy 374.979438 -232.757726)
			(xy 374.979438 -232.539032) (xy 374.979357 -232.535289) (xy 374.978208 -232.527892) (xy 374.977152 -232.5243)
			(xy 374.97131 -232.504234) (xy 374.9675 -232.498392) (xy 374.95456 -232.477226) (xy 374.934974 -232.431649)
			(xy 374.923016 -232.383505) (xy 374.918998 -232.334061) (xy 374.923028 -232.284618) (xy 374.934999 -232.236477)
			(xy 374.954596 -232.190905) (xy 374.9675 -232.169716) (xy 374.97131 -232.163874) (xy 374.977152 -232.143808)
			(xy 374.978185 -232.140212) (xy 374.979327 -232.132816) (xy 374.979438 -232.129076) (xy 374.979438 -231.834944)
			(xy 374.979027 -231.824914) (xy 374.971366 -231.806375) (xy 374.957194 -231.79218) (xy 374.938667 -231.784489)
			(xy 374.928638 -231.784144) (xy 374.91543 -231.784144) (xy 374.903746 -231.790494) (xy 374.885966 -231.799892)
			(xy 374.885712 -231.799892) (xy 374.870218 -231.80675) (xy 374.860312 -231.810814) (xy 374.830086 -231.84231)
			(xy 374.82653 -231.853232) (xy 374.81228 -231.895534) (xy 374.777638 -231.977808) (xy 374.73623 -232.056894)
			(xy 374.688349 -232.132237) (xy 374.634329 -232.203308) (xy 374.604788 -232.236772) (xy 374.598692 -232.24363)
			(xy 374.58523 -232.278174) (xy 374.587008 -232.291128) (xy 374.588439 -232.301802) (xy 374.589963 -232.323285)
			(xy 374.590056 -232.334054) (xy 374.589589 -232.358049) (xy 374.582089 -232.405449) (xy 374.567266 -232.451092)
			(xy 374.545486 -232.493855) (xy 374.517284 -232.532684) (xy 374.483355 -232.566623) (xy 374.444535 -232.594836)
			(xy 374.401779 -232.61663) (xy 374.356141 -232.631467) (xy 374.308743 -232.638981) (xy 374.284748 -232.639362)
			(xy 374.259748 -232.638888) (xy 374.210411 -232.630789) (xy 374.163055 -232.61475) (xy 374.11895 -232.591202)
			(xy 374.09882 -232.57637) (xy 374.09247 -232.57129) (xy 374.066308 -232.562146) (xy 374.052084 -232.56113)
			(xy 374.045226 -232.562908) (xy 374.007401 -232.57092) (xy 373.930888 -232.582103) (xy 373.853765 -232.587709)
			(xy 373.815102 -232.588054) (xy 373.535194 -232.588054) (xy 373.521732 -232.589832) (xy 373.503444 -232.594912)
			(xy 373.497602 -232.598214) (xy 373.474213 -232.611139) (xy 373.424026 -232.629481) (xy 373.371411 -232.638794)
			(xy 373.344694 -232.639362) (xy 373.317982 -232.638754) (xy 373.265376 -232.629425) (xy 373.215189 -232.611105)
			(xy 373.191786 -232.598214) (xy 373.185944 -232.594912) (xy 373.167656 -232.589832) (xy 373.154194 -232.588054)
			(xy 372.87454 -232.588054) (xy 372.835876 -232.587717) (xy 372.758753 -232.58212) (xy 372.68224 -232.570929)
			(xy 372.644416 -232.562908) (xy 372.637558 -232.56113) (xy 372.623334 -232.562146) (xy 372.597172 -232.57129)
			(xy 372.590822 -232.57637) (xy 372.570675 -232.591175) (xy 372.526569 -232.614711) (xy 372.47922 -232.630754)
			(xy 372.429891 -232.638875) (xy 372.404894 -232.639362) (xy 372.380902 -232.638915) (xy 372.33351 -232.631408)
			(xy 372.287876 -232.616578) (xy 372.245125 -232.594792) (xy 372.206307 -232.566585) (xy 372.172381 -232.532653)
			(xy 372.144181 -232.493831) (xy 372.122402 -232.451075) (xy 372.10758 -232.405439) (xy 372.100081 -232.358046)
			(xy 372.099586 -232.334054) (xy 372.099692 -232.323286) (xy 372.101215 -232.301803) (xy 372.102634 -232.291128)
			(xy 372.104412 -232.278174) (xy 372.09095 -232.24363) (xy 372.084854 -232.236772) (xy 372.055289 -232.203327)
			(xy 372.001251 -232.132267) (xy 371.953364 -232.056923) (xy 371.911967 -231.977828) (xy 371.877351 -231.895539)
			(xy 371.863112 -231.853232) (xy 371.859556 -231.84231) (xy 371.82933 -231.810814) (xy 371.819424 -231.80675)
			(xy 371.797272 -231.797227) (xy 371.756039 -231.772233) (xy 371.719246 -231.74107) (xy 371.687809 -231.704512)
			(xy 371.662508 -231.663467) (xy 371.643972 -231.618956) (xy 371.632661 -231.572084) (xy 371.628858 -231.524018)
			(xy 371.632655 -231.475951) (xy 371.64396 -231.429079) (xy 371.662491 -231.384566) (xy 371.687788 -231.343518)
			(xy 371.719221 -231.306956) (xy 371.756009 -231.275788) (xy 371.797239 -231.250789) (xy 371.819424 -231.241346)
			(xy 371.82933 -231.237282) (xy 371.859556 -231.205786) (xy 371.863112 -231.194864) (xy 371.877361 -231.152562)
			(xy 371.912003 -231.070286) (xy 371.953408 -230.991199) (xy 372.001288 -230.915855) (xy 372.055306 -230.844782)
			(xy 372.084854 -230.811324) (xy 372.09095 -230.804466) (xy 372.104412 -230.769922) (xy 372.102634 -230.756968)
			(xy 372.101223 -230.746356) (xy 372.099696 -230.725001) (xy 372.099586 -230.714296) (xy 372.099586 -230.713788)
			(xy 372.099683 -230.703083) (xy 372.101206 -230.681726) (xy 372.102634 -230.671116) (xy 372.104412 -230.658162)
			(xy 372.09095 -230.623618) (xy 372.0846 -230.61676) (xy 372.066446 -230.596335) (xy 372.032015 -230.553894)
			(xy 372.015766 -230.531924) (xy 372.0084 -230.522018) (xy 371.987064 -230.511096) (xy 371.882416 -230.511096)
			(xy 371.86108 -230.522018) (xy 371.853714 -230.531924) (xy 371.842034 -230.547876) (xy 371.817645 -230.579001)
			(xy 371.804946 -230.594154) (xy 371.799104 -230.600758) (xy 371.788944 -230.62819) (xy 371.787674 -230.642414)
			(xy 371.789198 -230.649272) (xy 371.792193 -230.66536) (xy 371.795369 -230.697932) (xy 371.795548 -230.714296)
			(xy 371.795039 -230.740285) (xy 371.786909 -230.791622) (xy 371.770849 -230.841055) (xy 371.747254 -230.887368)
			(xy 371.716705 -230.92942) (xy 371.679954 -230.966176) (xy 371.637906 -230.996731) (xy 371.591596 -231.020332)
			(xy 371.542165 -231.036399) (xy 371.490828 -231.044535) (xy 371.46484 -231.045004) (xy 371.441408 -231.044599)
			(xy 371.395012 -231.037989) (xy 371.350013 -231.024894) (xy 371.307315 -231.005578) (xy 371.26777 -230.980428)
			(xy 371.249702 -230.965502) (xy 371.243098 -230.959914) (xy 371.215158 -230.948992) (xy 371.201188 -230.947722)
			(xy 371.194076 -230.949246) (xy 371.144701 -230.958065) (xy 371.044839 -230.967484) (xy 370.994686 -230.968042)
			(xy 370.762784 -230.968042) (xy 370.758648 -230.968077) (xy 370.750478 -230.969356) (xy 370.746528 -230.970582)
			(xy 370.72443 -230.978202) (xy 370.718334 -230.98252) (xy 370.697073 -230.997246) (xy 370.650938 -231.020611)
			(xy 370.601728 -231.036512) (xy 370.550643 -231.044561) (xy 370.498929 -231.044561) (xy 370.447844 -231.036512)
			(xy 370.398634 -231.020611) (xy 370.352499 -230.997246) (xy 370.331238 -230.98252) (xy 370.325142 -230.978202)
			(xy 370.303044 -230.970582) (xy 370.299087 -230.969388) (xy 370.290921 -230.968119) (xy 370.286788 -230.968042)
			(xy 370.054632 -230.968042) (xy 370.015969 -230.967705) (xy 369.938845 -230.962107) (xy 369.862332 -230.950917)
			(xy 369.824508 -230.942896) (xy 369.81765 -230.941118) (xy 369.803426 -230.942134) (xy 369.777264 -230.951278)
			(xy 369.770914 -230.956358) (xy 369.750754 -230.971218) (xy 369.7066 -230.994849) (xy 369.659183 -231.010959)
			(xy 369.609772 -231.019119) (xy 369.584732 -231.019604) (xy 369.560737 -231.01916) (xy 369.513338 -231.011657)
			(xy 369.467696 -230.996832) (xy 369.424936 -230.975048) (xy 369.38611 -230.946843) (xy 369.352175 -230.912911)
			(xy 369.323967 -230.874088) (xy 369.302179 -230.831329) (xy 369.287349 -230.785689) (xy 369.279842 -230.738291)
			(xy 369.279424 -230.714296) (xy 369.2795 -230.7034) (xy 369.281027 -230.681662) (xy 369.282472 -230.670862)
			(xy 369.28425 -230.657908) (xy 369.270788 -230.623364) (xy 369.264692 -230.616506) (xy 369.246541 -230.596145)
			(xy 369.212106 -230.553834) (xy 369.195858 -230.531924) (xy 369.188492 -230.522018) (xy 369.167156 -230.511096)
			(xy 369.062508 -230.511096) (xy 369.041172 -230.522018) (xy 369.033806 -230.531924) (xy 369.022064 -230.547941)
			(xy 368.997547 -230.579192) (xy 368.984784 -230.594408) (xy 368.978942 -230.601012) (xy 368.968782 -230.628444)
			(xy 368.967512 -230.642414) (xy 368.969036 -230.649526) (xy 368.972025 -230.665551) (xy 368.975208 -230.697996)
			(xy 368.975386 -230.714296) (xy 368.974903 -230.740285) (xy 368.966772 -230.791623) (xy 368.95071 -230.841056)
			(xy 368.927112 -230.887368) (xy 368.89656 -230.929419) (xy 368.859805 -230.966171) (xy 368.817753 -230.996722)
			(xy 368.77144 -231.020317) (xy 368.722005 -231.036376) (xy 368.670667 -231.044505) (xy 368.644678 -231.045004)
			(xy 368.631928 -231.044912) (xy 368.606499 -231.043005) (xy 368.593878 -231.041194) (xy 368.571259 -231.037301)
			(xy 368.527307 -231.024081) (xy 368.48561 -231.004902) (xy 368.446969 -230.980134) (xy 368.429286 -230.965502)
			(xy 368.422682 -230.95966) (xy 368.394996 -230.948992) (xy 368.381026 -230.947722) (xy 368.373914 -230.949246)
			(xy 368.324602 -230.958053) (xy 368.224867 -230.967466) (xy 368.174778 -230.968042) (xy 367.942876 -230.968042)
			(xy 367.93874 -230.968077) (xy 367.93057 -230.969357) (xy 367.92662 -230.970582) (xy 367.904522 -230.978202)
			(xy 367.898426 -230.98252) (xy 367.877165 -230.997246) (xy 367.83103 -231.020611) (xy 367.78182 -231.036512)
			(xy 367.730735 -231.044561) (xy 367.679021 -231.044561) (xy 367.627936 -231.036512) (xy 367.578726 -231.020611)
			(xy 367.532591 -230.997246) (xy 367.51133 -230.98252) (xy 367.505234 -230.978202) (xy 367.483136 -230.970582)
			(xy 367.47918 -230.969381) (xy 367.471014 -230.968098) (xy 367.46688 -230.968042) (xy 367.234724 -230.968042)
			(xy 367.196061 -230.967705) (xy 367.118937 -230.962107) (xy 367.042424 -230.950916) (xy 367.0046 -230.942896)
			(xy 366.997742 -230.941118) (xy 366.983518 -230.942134) (xy 366.957356 -230.951278) (xy 366.951006 -230.956358)
			(xy 366.930846 -230.971217) (xy 366.886692 -230.994847) (xy 366.839274 -231.010957) (xy 366.789864 -231.019114)
			(xy 366.764824 -231.019604) (xy 366.74083 -231.01916) (xy 366.693432 -231.011656) (xy 366.647791 -230.996829)
			(xy 366.605032 -230.975045) (xy 366.566207 -230.94684) (xy 366.532273 -230.912908) (xy 366.504065 -230.874085)
			(xy 366.482278 -230.831328) (xy 366.467449 -230.785688) (xy 366.459942 -230.73829) (xy 366.459516 -230.714296)
			(xy 366.459516 -230.713788) (xy 366.459613 -230.703083) (xy 366.461137 -230.681726) (xy 366.462564 -230.671116)
			(xy 366.464342 -230.658162) (xy 366.45088 -230.623618) (xy 366.444784 -230.61676) (xy 366.426629 -230.596336)
			(xy 366.392196 -230.553897) (xy 366.37595 -230.531924) (xy 366.368584 -230.522018) (xy 366.347248 -230.511096)
			(xy 366.242346 -230.511096) (xy 366.22101 -230.522018) (xy 366.213644 -230.531924) (xy 366.201961 -230.547874)
			(xy 366.177571 -230.578998) (xy 366.164876 -230.594154) (xy 366.159034 -230.600758) (xy 366.148874 -230.62819)
			(xy 366.147604 -230.642414) (xy 366.149128 -230.649272) (xy 366.152122 -230.66536) (xy 366.155299 -230.697932)
			(xy 366.155478 -230.714296) (xy 366.154995 -230.740285) (xy 366.146864 -230.791622) (xy 366.130802 -230.841055)
			(xy 366.107204 -230.887367) (xy 366.076651 -230.929416) (xy 366.039896 -230.966168) (xy 365.997844 -230.996718)
			(xy 365.951531 -231.020312) (xy 365.902097 -231.03637) (xy 365.850759 -231.044497) (xy 365.82477 -231.045004)
			(xy 365.81202 -231.044912) (xy 365.786591 -231.043004) (xy 365.77397 -231.041194) (xy 365.751351 -231.0373)
			(xy 365.7074 -231.024079) (xy 365.665703 -231.0049) (xy 365.627063 -230.980131) (xy 365.609378 -230.965502)
			(xy 365.602774 -230.95966) (xy 365.575088 -230.948992) (xy 365.561118 -230.947722) (xy 365.554006 -230.949246)
			(xy 365.504695 -230.958059) (xy 365.404959 -230.967475) (xy 365.35487 -230.968042) (xy 365.122714 -230.968042)
			(xy 365.118578 -230.968074) (xy 365.110406 -230.969348) (xy 365.106458 -230.970582) (xy 365.08436 -230.978202)
			(xy 365.078264 -230.98252) (xy 365.057003 -230.997246) (xy 365.010868 -231.020611) (xy 364.961658 -231.036512)
			(xy 364.910573 -231.044561) (xy 364.858859 -231.044561) (xy 364.807774 -231.036512) (xy 364.758564 -231.020611)
			(xy 364.712429 -230.997246) (xy 364.691168 -230.98252) (xy 364.685072 -230.978202) (xy 364.662974 -230.970582)
			(xy 364.659018 -230.969385) (xy 364.650851 -230.968113) (xy 364.646718 -230.968042) (xy 364.414816 -230.968042)
			(xy 364.376153 -230.967705) (xy 364.299029 -230.962106) (xy 364.222516 -230.950914) (xy 364.184692 -230.942896)
			(xy 364.177834 -230.941118) (xy 364.16361 -230.942134) (xy 364.137448 -230.951278) (xy 364.131098 -230.956358)
			(xy 364.120831 -230.964072) (xy 364.099213 -230.977935) (xy 364.087918 -230.984044) (xy 364.060232 -230.996998)
			(xy 364.050326 -231.001062) (xy 364.0201 -231.032558) (xy 364.016544 -231.04348) (xy 364.002296 -231.085783)
			(xy 363.967657 -231.16806) (xy 363.926253 -231.247149) (xy 363.878375 -231.322495) (xy 363.824358 -231.393569)
			(xy 363.794802 -231.42702) (xy 363.788706 -231.433878) (xy 363.775244 -231.468422) (xy 363.777022 -231.481376)
			(xy 363.778432 -231.491988) (xy 363.779955 -231.513343) (xy 363.780069 -231.524) (xy 364.108988 -231.524)
			(xy 364.113159 -231.473663) (xy 364.125559 -231.4247) (xy 364.145849 -231.378445) (xy 364.173476 -231.336161)
			(xy 364.207685 -231.299001) (xy 364.247545 -231.267979) (xy 364.291968 -231.243941) (xy 364.339741 -231.227542)
			(xy 364.389561 -231.219231) (xy 364.414816 -231.21874) (xy 365.35487 -231.21874) (xy 365.380133 -231.219134)
			(xy 365.429971 -231.227446) (xy 365.477762 -231.243849) (xy 365.5222 -231.267894) (xy 365.562074 -231.298925)
			(xy 365.596297 -231.336097) (xy 365.623934 -231.378396) (xy 365.644231 -231.424666) (xy 365.656635 -231.473646)
			(xy 365.660808 -231.524) (xy 365.660804 -231.524048) (xy 365.98912 -231.524048) (xy 365.99308 -231.474994)
			(xy 366.004857 -231.42721) (xy 366.024148 -231.381934) (xy 366.050451 -231.340338) (xy 366.083086 -231.303501)
			(xy 366.121207 -231.272376) (xy 366.163828 -231.247769) (xy 366.209844 -231.230317) (xy 366.258063 -231.220473)
			(xy 366.307238 -231.218492) (xy 366.356093 -231.224424) (xy 366.403364 -231.238116) (xy 366.447826 -231.259214)
			(xy 366.488329 -231.28717) (xy 366.523822 -231.321262) (xy 366.553387 -231.360606) (xy 366.576258 -231.404183)
			(xy 366.591842 -231.450864) (xy 366.599737 -231.499441) (xy 366.600231 -231.524) (xy 366.928888 -231.524)
			(xy 366.933059 -231.473662) (xy 366.945459 -231.424698) (xy 366.96575 -231.378443) (xy 366.993378 -231.336158)
			(xy 367.027588 -231.298998) (xy 367.067449 -231.267976) (xy 367.111873 -231.243938) (xy 367.159647 -231.227541)
			(xy 367.209469 -231.219231) (xy 367.234724 -231.21874) (xy 368.174778 -231.21874) (xy 368.200041 -231.219135)
			(xy 368.249878 -231.227448) (xy 368.297667 -231.243851) (xy 368.342104 -231.267896) (xy 368.381977 -231.298928)
			(xy 368.416199 -231.3361) (xy 368.443835 -231.378398) (xy 368.464132 -231.424667) (xy 368.476535 -231.473647)
			(xy 368.480708 -231.524) (xy 368.480704 -231.524048) (xy 368.809028 -231.524048) (xy 368.812988 -231.474994)
			(xy 368.824765 -231.42721) (xy 368.844056 -231.381934) (xy 368.870359 -231.340338) (xy 368.902994 -231.303501)
			(xy 368.941115 -231.272376) (xy 368.983736 -231.247769) (xy 369.029752 -231.230317) (xy 369.077971 -231.220473)
			(xy 369.127146 -231.218492) (xy 369.176001 -231.224424) (xy 369.223272 -231.238116) (xy 369.267734 -231.259214)
			(xy 369.308237 -231.28717) (xy 369.34373 -231.321262) (xy 369.373295 -231.360606) (xy 369.396166 -231.404183)
			(xy 369.41175 -231.450864) (xy 369.419645 -231.499441) (xy 369.420139 -231.524) (xy 369.749117 -231.524)
			(xy 369.753287 -231.473671) (xy 369.765684 -231.424715) (xy 369.78597 -231.378467) (xy 369.813591 -231.336189)
			(xy 369.847793 -231.299033) (xy 369.887645 -231.268014) (xy 369.932059 -231.243976) (xy 369.979823 -231.227577)
			(xy 370.029635 -231.219263) (xy 370.054886 -231.21874) (xy 370.99494 -231.21874) (xy 371.020197 -231.219168)
			(xy 371.070022 -231.227489) (xy 371.117797 -231.243896) (xy 371.162221 -231.267942) (xy 371.202082 -231.298971)
			(xy 371.236292 -231.336138) (xy 371.263919 -231.378429) (xy 371.284209 -231.424689) (xy 371.296608 -231.473658)
			(xy 371.30078 -231.524) (xy 371.296608 -231.574342) (xy 371.284209 -231.623311) (xy 371.263919 -231.669571)
			(xy 371.236292 -231.711862) (xy 371.202082 -231.749029) (xy 371.162221 -231.780058) (xy 371.117797 -231.804104)
			(xy 371.070022 -231.820511) (xy 371.020197 -231.828832) (xy 370.99494 -231.829356) (xy 370.054886 -231.829356)
			(xy 370.029635 -231.828737) (xy 369.979823 -231.820423) (xy 369.932059 -231.804024) (xy 369.887645 -231.779986)
			(xy 369.847793 -231.748967) (xy 369.813591 -231.711811) (xy 369.78597 -231.669533) (xy 369.765684 -231.623285)
			(xy 369.753287 -231.574329) (xy 369.749117 -231.524) (xy 369.420139 -231.524) (xy 369.42014 -231.524048)
			(xy 369.419645 -231.548655) (xy 369.41175 -231.597232) (xy 369.396166 -231.643913) (xy 369.373295 -231.68749)
			(xy 369.34373 -231.726834) (xy 369.308237 -231.760926) (xy 369.267734 -231.788882) (xy 369.223272 -231.80998)
			(xy 369.176001 -231.823672) (xy 369.127146 -231.829604) (xy 369.077971 -231.827623) (xy 369.029752 -231.817779)
			(xy 368.983736 -231.800327) (xy 368.941115 -231.77572) (xy 368.902994 -231.744595) (xy 368.870359 -231.707758)
			(xy 368.844056 -231.666162) (xy 368.824765 -231.620886) (xy 368.812988 -231.573102) (xy 368.809028 -231.524048)
			(xy 368.480704 -231.524048) (xy 368.476535 -231.574353) (xy 368.464132 -231.623333) (xy 368.443835 -231.669602)
			(xy 368.416199 -231.7119) (xy 368.381977 -231.749072) (xy 368.342104 -231.780104) (xy 368.297667 -231.804149)
			(xy 368.249878 -231.820552) (xy 368.200041 -231.828865) (xy 368.174778 -231.829356) (xy 367.234724 -231.829356)
			(xy 367.209469 -231.828769) (xy 367.159647 -231.820459) (xy 367.111873 -231.804062) (xy 367.067449 -231.780024)
			(xy 367.027588 -231.749002) (xy 366.993378 -231.711842) (xy 366.96575 -231.669557) (xy 366.945459 -231.623302)
			(xy 366.933059 -231.574337) (xy 366.928888 -231.524) (xy 366.600231 -231.524) (xy 366.600232 -231.524048)
			(xy 366.599737 -231.548655) (xy 366.591842 -231.597232) (xy 366.576258 -231.643913) (xy 366.553387 -231.68749)
			(xy 366.523822 -231.726834) (xy 366.488329 -231.760926) (xy 366.447826 -231.788882) (xy 366.403364 -231.80998)
			(xy 366.356093 -231.823672) (xy 366.307238 -231.829604) (xy 366.258063 -231.827623) (xy 366.209844 -231.817779)
			(xy 366.163828 -231.800327) (xy 366.121207 -231.77572) (xy 366.083086 -231.744595) (xy 366.050451 -231.707758)
			(xy 366.024148 -231.666162) (xy 366.004857 -231.620886) (xy 365.99308 -231.573102) (xy 365.98912 -231.524048)
			(xy 365.660804 -231.524048) (xy 365.656635 -231.574354) (xy 365.644231 -231.623334) (xy 365.623934 -231.669604)
			(xy 365.596297 -231.711903) (xy 365.562074 -231.749075) (xy 365.5222 -231.780106) (xy 365.477762 -231.804151)
			(xy 365.429971 -231.820554) (xy 365.380133 -231.828866) (xy 365.35487 -231.829356) (xy 364.414816 -231.829356)
			(xy 364.389561 -231.828769) (xy 364.339741 -231.820458) (xy 364.291968 -231.804059) (xy 364.247545 -231.780021)
			(xy 364.207685 -231.748999) (xy 364.173476 -231.711839) (xy 364.145849 -231.669555) (xy 364.125559 -231.6233)
			(xy 364.113159 -231.574337) (xy 364.108988 -231.524) (xy 363.780069 -231.524) (xy 363.78007 -231.524048)
			(xy 363.779596 -231.548036) (xy 363.772083 -231.595419) (xy 363.757251 -231.641044) (xy 363.735465 -231.683788)
			(xy 363.70726 -231.722597) (xy 363.673331 -231.756516) (xy 363.634514 -231.78471) (xy 363.591765 -231.806484)
			(xy 363.546136 -231.821304) (xy 363.49875 -231.828803) (xy 363.474762 -231.829356) (xy 363.44984 -231.82886)
			(xy 363.400657 -231.820761) (xy 363.353442 -231.804784) (xy 363.309448 -231.781353) (xy 363.289342 -231.766618)
			(xy 363.282992 -231.761792) (xy 363.256576 -231.752394) (xy 363.242606 -231.751632) (xy 363.235494 -231.753156)
			(xy 363.19771 -231.761159) (xy 363.121282 -231.772333) (xy 363.044244 -231.777942) (xy 363.005624 -231.778302)
			(xy 362.771944 -231.778302) (xy 362.767799 -231.778399) (xy 362.759629 -231.779806) (xy 362.755688 -231.781096)
			(xy 362.733844 -231.788462) (xy 362.727748 -231.79278) (xy 362.706521 -231.807409) (xy 362.660486 -231.830612)
			(xy 362.611412 -231.846399) (xy 362.560484 -231.854389) (xy 362.508932 -231.854389) (xy 362.458004 -231.846399)
			(xy 362.40893 -231.830612) (xy 362.362895 -231.807409) (xy 362.341668 -231.79278) (xy 362.335572 -231.788462)
			(xy 362.313728 -231.781096) (xy 362.309781 -231.779834) (xy 362.301614 -231.778432) (xy 362.297472 -231.778302)
			(xy 362.064554 -231.778302) (xy 362.014401 -231.777736) (xy 361.914538 -231.768325) (xy 361.865164 -231.759506)
			(xy 361.858052 -231.757982) (xy 361.844082 -231.759252) (xy 361.816142 -231.770174) (xy 361.809538 -231.775762)
			(xy 361.791494 -231.790609) (xy 361.752017 -231.815609) (xy 361.709415 -231.834805) (xy 361.664535 -231.847813)
			(xy 361.618272 -231.854377) (xy 361.594908 -231.854756) (xy 361.568919 -231.854247) (xy 361.517581 -231.846118)
			(xy 361.468146 -231.830058) (xy 361.421832 -231.806463) (xy 361.379779 -231.775915) (xy 361.343022 -231.739164)
			(xy 361.312466 -231.697116) (xy 361.288863 -231.650806) (xy 361.272795 -231.601374) (xy 361.264657 -231.550037)
			(xy 361.2642 -231.524048) (xy 361.2642 -231.523286) (xy 361.264429 -231.507241) (xy 361.267613 -231.475308)
			(xy 361.27055 -231.459532) (xy 361.27182 -231.45242) (xy 361.270804 -231.438704) (xy 361.26039 -231.411018)
			(xy 361.254548 -231.404414) (xy 361.227913 -231.372452) (xy 361.179145 -231.305037) (xy 361.13579 -231.234018)
			(xy 361.098114 -231.159831) (xy 361.066346 -231.082929) (xy 361.053126 -231.04348) (xy 361.04957 -231.032558)
			(xy 361.019344 -231.001062) (xy 361.009438 -230.996998) (xy 360.987329 -230.987488) (xy 360.946174 -230.962539)
			(xy 360.909442 -230.931443) (xy 360.878044 -230.894969) (xy 360.852756 -230.854021) (xy 360.834205 -230.809613)
			(xy 360.822851 -230.762845) (xy 360.818974 -230.714874) (xy 360.82267 -230.66689) (xy 360.833849 -230.620079)
			(xy 360.852233 -230.575602) (xy 360.877367 -230.534559) (xy 360.892598 -230.515922) (xy 360.898948 -230.508556)
			(xy 360.905298 -230.490522) (xy 360.90225 -230.412036) (xy 360.901479 -230.402499) (xy 360.893793 -230.384992)
			(xy 360.887264 -230.378) (xy 358.741726 -228.232462) (xy 358.734883 -228.225063) (xy 358.727158 -228.206464)
			(xy 358.72674 -228.196394) (xy 358.72674 -222.636842) (xy 358.726305 -222.626778) (xy 358.718569 -222.608194)
			(xy 358.711754 -222.600774) (xy 358.702864 -222.591884) (xy 358.695452 -222.5852) (xy 358.677019 -222.577603)
			(xy 358.657081 -222.577603) (xy 358.638648 -222.5852) (xy 358.631236 -222.591884) (xy 358.624124 -222.598742)
			(xy 358.616758 -222.616268) (xy 358.61625 -222.62592) (xy 358.614727 -222.651891) (xy 358.603953 -222.702784)
			(xy 358.584713 -222.751117) (xy 358.557563 -222.795491) (xy 358.523287 -222.834624) (xy 358.482878 -222.867385)
			(xy 358.437503 -222.892826) (xy 358.388473 -222.910213) (xy 358.337206 -222.919042) (xy 358.311196 -222.919544)
			(xy 358.287204 -222.919073) (xy 358.239811 -222.911567) (xy 358.194175 -222.896739) (xy 358.15142 -222.874956)
			(xy 358.112599 -222.846753) (xy 358.078667 -222.812825) (xy 358.050461 -222.774007) (xy 358.028673 -222.731255)
			(xy 358.013841 -222.685621) (xy 358.006329 -222.638228) (xy 358.005888 -222.614236) (xy 358.006359 -222.5899)
			(xy 358.014075 -222.541843) (xy 358.029318 -222.495619) (xy 358.051702 -222.452398) (xy 358.08066 -222.413277)
			(xy 358.115457 -222.379245) (xy 358.155213 -222.351166) (xy 358.198921 -222.329749) (xy 358.222042 -222.322136)
			(xy 358.234996 -222.318326) (xy 358.253284 -222.299022) (xy 358.277668 -222.201486) (xy 358.279411 -222.192901)
			(xy 358.277647 -222.175484) (xy 358.270144 -222.159667) (xy 358.264206 -222.153226) (xy 356.907846 -220.796866)
			(xy 356.900448 -220.790021) (xy 356.881849 -220.782296) (xy 356.871778 -220.78188) (xy 341.059516 -220.78188)
			(xy 341.05032 -220.78226) (xy 341.033117 -220.788761) (xy 341.025988 -220.79458) (xy 341.002729 -220.814375)
			(xy 340.952314 -220.848855) (xy 340.898133 -220.877051) (xy 340.840965 -220.898556) (xy 340.781634 -220.913061)
			(xy 340.720993 -220.920357) (xy 340.690454 -220.920818) (xy 340.65717 -220.920317) (xy 340.591168 -220.911653)
			(xy 340.558882 -220.903546) (xy 340.54542 -220.89999) (xy 340.519512 -220.906848) (xy 340.319106 -221.107254)
			(xy 340.312267 -221.114655) (xy 340.304552 -221.133253) (xy 340.30412 -221.143322) (xy 340.30412 -221.80423)
			(xy 345.315298 -221.80423) (xy 345.319258 -221.755176) (xy 345.331035 -221.707392) (xy 345.350326 -221.662116)
			(xy 345.376629 -221.62052) (xy 345.409264 -221.583683) (xy 345.447385 -221.552558) (xy 345.490006 -221.527951)
			(xy 345.536022 -221.510499) (xy 345.584241 -221.500655) (xy 345.633416 -221.498674) (xy 345.682271 -221.504606)
			(xy 345.729542 -221.518298) (xy 345.774004 -221.539396) (xy 345.814507 -221.567352) (xy 345.85 -221.601444)
			(xy 345.879565 -221.640788) (xy 345.902436 -221.684365) (xy 345.91802 -221.731046) (xy 345.925915 -221.779623)
			(xy 345.92641 -221.80423) (xy 349.07526 -221.80423) (xy 349.07922 -221.755176) (xy 349.090997 -221.707392)
			(xy 349.110288 -221.662116) (xy 349.136591 -221.62052) (xy 349.169226 -221.583683) (xy 349.207347 -221.552558)
			(xy 349.249968 -221.527951) (xy 349.295984 -221.510499) (xy 349.344203 -221.500655) (xy 349.393378 -221.498674)
			(xy 349.442233 -221.504606) (xy 349.489504 -221.518298) (xy 349.533966 -221.539396) (xy 349.574469 -221.567352)
			(xy 349.609962 -221.601444) (xy 349.639527 -221.640788) (xy 349.662398 -221.684365) (xy 349.677982 -221.731046)
			(xy 349.685877 -221.779623) (xy 349.686372 -221.80423) (xy 350.955368 -221.80423) (xy 350.959328 -221.755176)
			(xy 350.971105 -221.707392) (xy 350.990396 -221.662116) (xy 351.016699 -221.62052) (xy 351.049334 -221.583683)
			(xy 351.087455 -221.552558) (xy 351.130076 -221.527951) (xy 351.176092 -221.510499) (xy 351.224311 -221.500655)
			(xy 351.273486 -221.498674) (xy 351.322341 -221.504606) (xy 351.369612 -221.518298) (xy 351.414074 -221.539396)
			(xy 351.454577 -221.567352) (xy 351.49007 -221.601444) (xy 351.519635 -221.640788) (xy 351.542506 -221.684365)
			(xy 351.55809 -221.731046) (xy 351.565985 -221.779623) (xy 351.56648 -221.80423) (xy 353.775276 -221.80423)
			(xy 353.779236 -221.755176) (xy 353.791013 -221.707392) (xy 353.810304 -221.662116) (xy 353.836607 -221.62052)
			(xy 353.869242 -221.583683) (xy 353.907363 -221.552558) (xy 353.949984 -221.527951) (xy 353.996 -221.510499)
			(xy 354.044219 -221.500655) (xy 354.093394 -221.498674) (xy 354.142249 -221.504606) (xy 354.18952 -221.518298)
			(xy 354.233982 -221.539396) (xy 354.274485 -221.567352) (xy 354.309978 -221.601444) (xy 354.339543 -221.640788)
			(xy 354.362414 -221.684365) (xy 354.377998 -221.731046) (xy 354.385893 -221.779623) (xy 354.386388 -221.80423)
			(xy 354.71533 -221.80423) (xy 354.71929 -221.755176) (xy 354.731067 -221.707392) (xy 354.750358 -221.662116)
			(xy 354.776661 -221.62052) (xy 354.809296 -221.583683) (xy 354.847417 -221.552558) (xy 354.890038 -221.527951)
			(xy 354.936054 -221.510499) (xy 354.984273 -221.500655) (xy 355.033448 -221.498674) (xy 355.082303 -221.504606)
			(xy 355.129574 -221.518298) (xy 355.174036 -221.539396) (xy 355.214539 -221.567352) (xy 355.250032 -221.601444)
			(xy 355.279597 -221.640788) (xy 355.302468 -221.684365) (xy 355.318052 -221.731046) (xy 355.325947 -221.779623)
			(xy 355.326442 -221.80423) (xy 355.325947 -221.828837) (xy 355.318052 -221.877414) (xy 355.302468 -221.924095)
			(xy 355.279597 -221.967672) (xy 355.250032 -222.007016) (xy 355.214539 -222.041108) (xy 355.174036 -222.069064)
			(xy 355.129574 -222.090162) (xy 355.082303 -222.103854) (xy 355.033448 -222.109786) (xy 354.984273 -222.107805)
			(xy 354.936054 -222.097961) (xy 354.890038 -222.080509) (xy 354.847417 -222.055902) (xy 354.809296 -222.024777)
			(xy 354.776661 -221.98794) (xy 354.750358 -221.946344) (xy 354.731067 -221.901068) (xy 354.71929 -221.853284)
			(xy 354.71533 -221.80423) (xy 354.386388 -221.80423) (xy 354.385893 -221.828837) (xy 354.377998 -221.877414)
			(xy 354.362414 -221.924095) (xy 354.339543 -221.967672) (xy 354.309978 -222.007016) (xy 354.274485 -222.041108)
			(xy 354.233982 -222.069064) (xy 354.18952 -222.090162) (xy 354.142249 -222.103854) (xy 354.093394 -222.109786)
			(xy 354.044219 -222.107805) (xy 353.996 -222.097961) (xy 353.949984 -222.080509) (xy 353.907363 -222.055902)
			(xy 353.869242 -222.024777) (xy 353.836607 -221.98794) (xy 353.810304 -221.946344) (xy 353.791013 -221.901068)
			(xy 353.779236 -221.853284) (xy 353.775276 -221.80423) (xy 351.56648 -221.80423) (xy 351.565985 -221.828837)
			(xy 351.55809 -221.877414) (xy 351.542506 -221.924095) (xy 351.519635 -221.967672) (xy 351.49007 -222.007016)
			(xy 351.454577 -222.041108) (xy 351.414074 -222.069064) (xy 351.369612 -222.090162) (xy 351.322341 -222.103854)
			(xy 351.273486 -222.109786) (xy 351.224311 -222.107805) (xy 351.176092 -222.097961) (xy 351.130076 -222.080509)
			(xy 351.087455 -222.055902) (xy 351.049334 -222.024777) (xy 351.016699 -221.98794) (xy 350.990396 -221.946344)
			(xy 350.971105 -221.901068) (xy 350.959328 -221.853284) (xy 350.955368 -221.80423) (xy 349.686372 -221.80423)
			(xy 349.685877 -221.828837) (xy 349.677982 -221.877414) (xy 349.662398 -221.924095) (xy 349.639527 -221.967672)
			(xy 349.609962 -222.007016) (xy 349.574469 -222.041108) (xy 349.533966 -222.069064) (xy 349.489504 -222.090162)
			(xy 349.442233 -222.103854) (xy 349.393378 -222.109786) (xy 349.344203 -222.107805) (xy 349.295984 -222.097961)
			(xy 349.249968 -222.080509) (xy 349.207347 -222.055902) (xy 349.169226 -222.024777) (xy 349.136591 -221.98794)
			(xy 349.110288 -221.946344) (xy 349.090997 -221.901068) (xy 349.07922 -221.853284) (xy 349.07526 -221.80423)
			(xy 345.92641 -221.80423) (xy 345.925915 -221.828837) (xy 345.91802 -221.877414) (xy 345.902436 -221.924095)
			(xy 345.879565 -221.967672) (xy 345.85 -222.007016) (xy 345.814507 -222.041108) (xy 345.774004 -222.069064)
			(xy 345.729542 -222.090162) (xy 345.682271 -222.103854) (xy 345.633416 -222.109786) (xy 345.584241 -222.107805)
			(xy 345.536022 -222.097961) (xy 345.490006 -222.080509) (xy 345.447385 -222.055902) (xy 345.409264 -222.024777)
			(xy 345.376629 -221.98794) (xy 345.350326 -221.946344) (xy 345.331035 -221.901068) (xy 345.319258 -221.853284)
			(xy 345.315298 -221.80423) (xy 340.30412 -221.80423) (xy 340.30412 -222.209868) (xy 340.304589 -222.220621)
			(xy 340.313396 -222.240238) (xy 340.321138 -222.247714) (xy 340.385654 -222.305626) (xy 340.405974 -222.311976)
			(xy 340.41715 -222.31096) (xy 340.451186 -222.308928) (xy 340.476442 -222.309419) (xy 340.526264 -222.317731)
			(xy 340.574039 -222.33413) (xy 340.618462 -222.35817) (xy 340.658324 -222.389193) (xy 340.692534 -222.426354)
			(xy 340.720162 -222.46864) (xy 340.740453 -222.514896) (xy 340.752853 -222.563862) (xy 340.757024 -222.6142)
			(xy 340.757021 -222.614236) (xy 342.96529 -222.614236) (xy 342.96925 -222.565182) (xy 342.981027 -222.517398)
			(xy 343.000318 -222.472122) (xy 343.026621 -222.430526) (xy 343.059256 -222.393689) (xy 343.097377 -222.362564)
			(xy 343.139998 -222.337957) (xy 343.186014 -222.320505) (xy 343.234233 -222.310661) (xy 343.283408 -222.30868)
			(xy 343.332263 -222.314612) (xy 343.379534 -222.328304) (xy 343.423996 -222.349402) (xy 343.464499 -222.377358)
			(xy 343.499992 -222.41145) (xy 343.529557 -222.450794) (xy 343.552428 -222.494371) (xy 343.568012 -222.541052)
			(xy 343.575907 -222.589629) (xy 343.576402 -222.614236) (xy 345.785198 -222.614236) (xy 345.789158 -222.565182)
			(xy 345.800935 -222.517398) (xy 345.820226 -222.472122) (xy 345.846529 -222.430526) (xy 345.879164 -222.393689)
			(xy 345.917285 -222.362564) (xy 345.959906 -222.337957) (xy 346.005922 -222.320505) (xy 346.054141 -222.310661)
			(xy 346.103316 -222.30868) (xy 346.152171 -222.314612) (xy 346.199442 -222.328304) (xy 346.243904 -222.349402)
			(xy 346.284407 -222.377358) (xy 346.3199 -222.41145) (xy 346.349465 -222.450794) (xy 346.372336 -222.494371)
			(xy 346.38792 -222.541052) (xy 346.395815 -222.589629) (xy 346.39631 -222.614236) (xy 348.60536 -222.614236)
			(xy 348.60932 -222.565182) (xy 348.621097 -222.517398) (xy 348.640388 -222.472122) (xy 348.666691 -222.430526)
			(xy 348.699326 -222.393689) (xy 348.737447 -222.362564) (xy 348.780068 -222.337957) (xy 348.826084 -222.320505)
			(xy 348.874303 -222.310661) (xy 348.923478 -222.30868) (xy 348.972333 -222.314612) (xy 349.019604 -222.328304)
			(xy 349.064066 -222.349402) (xy 349.104569 -222.377358) (xy 349.140062 -222.41145) (xy 349.169627 -222.450794)
			(xy 349.192498 -222.494371) (xy 349.208082 -222.541052) (xy 349.215977 -222.589629) (xy 349.216472 -222.614236)
			(xy 351.425268 -222.614236) (xy 351.429228 -222.565182) (xy 351.441005 -222.517398) (xy 351.460296 -222.472122)
			(xy 351.486599 -222.430526) (xy 351.519234 -222.393689) (xy 351.557355 -222.362564) (xy 351.599976 -222.337957)
			(xy 351.645992 -222.320505) (xy 351.694211 -222.310661) (xy 351.743386 -222.30868) (xy 351.792241 -222.314612)
			(xy 351.839512 -222.328304) (xy 351.883974 -222.349402) (xy 351.924477 -222.377358) (xy 351.95997 -222.41145)
			(xy 351.989535 -222.450794) (xy 352.012406 -222.494371) (xy 352.02799 -222.541052) (xy 352.035885 -222.589629)
			(xy 352.03638 -222.614236) (xy 354.24543 -222.614236) (xy 354.24939 -222.565182) (xy 354.261167 -222.517398)
			(xy 354.280458 -222.472122) (xy 354.306761 -222.430526) (xy 354.339396 -222.393689) (xy 354.377517 -222.362564)
			(xy 354.420138 -222.337957) (xy 354.466154 -222.320505) (xy 354.514373 -222.310661) (xy 354.563548 -222.30868)
			(xy 354.612403 -222.314612) (xy 354.659674 -222.328304) (xy 354.704136 -222.349402) (xy 354.744639 -222.377358)
			(xy 354.780132 -222.41145) (xy 354.809697 -222.450794) (xy 354.832568 -222.494371) (xy 354.848152 -222.541052)
			(xy 354.856047 -222.589629) (xy 354.856542 -222.614236) (xy 354.856047 -222.638843) (xy 354.848152 -222.68742)
			(xy 354.832568 -222.734101) (xy 354.809697 -222.777678) (xy 354.780132 -222.817022) (xy 354.744639 -222.851114)
			(xy 354.704136 -222.87907) (xy 354.659674 -222.900168) (xy 354.612403 -222.91386) (xy 354.563548 -222.919792)
			(xy 354.514373 -222.917811) (xy 354.466154 -222.907967) (xy 354.420138 -222.890515) (xy 354.377517 -222.865908)
			(xy 354.339396 -222.834783) (xy 354.306761 -222.797946) (xy 354.280458 -222.75635) (xy 354.261167 -222.711074)
			(xy 354.24939 -222.66329) (xy 354.24543 -222.614236) (xy 352.03638 -222.614236) (xy 352.035885 -222.638843)
			(xy 352.02799 -222.68742) (xy 352.012406 -222.734101) (xy 351.989535 -222.777678) (xy 351.95997 -222.817022)
			(xy 351.924477 -222.851114) (xy 351.883974 -222.87907) (xy 351.839512 -222.900168) (xy 351.792241 -222.91386)
			(xy 351.743386 -222.919792) (xy 351.694211 -222.917811) (xy 351.645992 -222.907967) (xy 351.599976 -222.890515)
			(xy 351.557355 -222.865908) (xy 351.519234 -222.834783) (xy 351.486599 -222.797946) (xy 351.460296 -222.75635)
			(xy 351.441005 -222.711074) (xy 351.429228 -222.66329) (xy 351.425268 -222.614236) (xy 349.216472 -222.614236)
			(xy 349.215977 -222.638843) (xy 349.208082 -222.68742) (xy 349.192498 -222.734101) (xy 349.169627 -222.777678)
			(xy 349.140062 -222.817022) (xy 349.104569 -222.851114) (xy 349.064066 -222.87907) (xy 349.019604 -222.900168)
			(xy 348.972333 -222.91386) (xy 348.923478 -222.919792) (xy 348.874303 -222.917811) (xy 348.826084 -222.907967)
			(xy 348.780068 -222.890515) (xy 348.737447 -222.865908) (xy 348.699326 -222.834783) (xy 348.666691 -222.797946)
			(xy 348.640388 -222.75635) (xy 348.621097 -222.711074) (xy 348.60932 -222.66329) (xy 348.60536 -222.614236)
			(xy 346.39631 -222.614236) (xy 346.395815 -222.638843) (xy 346.38792 -222.68742) (xy 346.372336 -222.734101)
			(xy 346.349465 -222.777678) (xy 346.3199 -222.817022) (xy 346.284407 -222.851114) (xy 346.243904 -222.87907)
			(xy 346.199442 -222.900168) (xy 346.152171 -222.91386) (xy 346.103316 -222.919792) (xy 346.054141 -222.917811)
			(xy 346.005922 -222.907967) (xy 345.959906 -222.890515) (xy 345.917285 -222.865908) (xy 345.879164 -222.834783)
			(xy 345.846529 -222.797946) (xy 345.820226 -222.75635) (xy 345.800935 -222.711074) (xy 345.789158 -222.66329)
			(xy 345.785198 -222.614236) (xy 343.576402 -222.614236) (xy 343.575907 -222.638843) (xy 343.568012 -222.68742)
			(xy 343.552428 -222.734101) (xy 343.529557 -222.777678) (xy 343.499992 -222.817022) (xy 343.464499 -222.851114)
			(xy 343.423996 -222.87907) (xy 343.379534 -222.900168) (xy 343.332263 -222.91386) (xy 343.283408 -222.919792)
			(xy 343.234233 -222.917811) (xy 343.186014 -222.907967) (xy 343.139998 -222.890515) (xy 343.097377 -222.865908)
			(xy 343.059256 -222.834783) (xy 343.026621 -222.797946) (xy 343.000318 -222.75635) (xy 342.981027 -222.711074)
			(xy 342.96925 -222.66329) (xy 342.96529 -222.614236) (xy 340.757021 -222.614236) (xy 340.752853 -222.664538)
			(xy 340.740453 -222.713504) (xy 340.720162 -222.75976) (xy 340.692534 -222.802046) (xy 340.658324 -222.839207)
			(xy 340.618462 -222.87023) (xy 340.574039 -222.89427) (xy 340.526264 -222.910669) (xy 340.476442 -222.918981)
			(xy 340.451186 -222.919544) (xy 340.41715 -222.917512) (xy 340.405974 -222.916496) (xy 340.385654 -222.922846)
			(xy 340.321138 -222.980758) (xy 340.31352 -222.988324) (xy 340.304734 -223.007884) (xy 340.30412 -223.018604)
			(xy 340.30412 -223.424242) (xy 341.555336 -223.424242) (xy 341.559296 -223.375188) (xy 341.571073 -223.327404)
			(xy 341.590364 -223.282128) (xy 341.616667 -223.240532) (xy 341.649302 -223.203695) (xy 341.687423 -223.17257)
			(xy 341.730044 -223.147963) (xy 341.77606 -223.130511) (xy 341.824279 -223.120667) (xy 341.873454 -223.118686)
			(xy 341.922309 -223.124618) (xy 341.96958 -223.13831) (xy 342.014042 -223.159408) (xy 342.054545 -223.187364)
			(xy 342.090038 -223.221456) (xy 342.119603 -223.2608) (xy 342.142474 -223.304377) (xy 342.158058 -223.351058)
			(xy 342.165953 -223.399635) (xy 342.166448 -223.424242) (xy 342.49539 -223.424242) (xy 342.49935 -223.375188)
			(xy 342.511127 -223.327404) (xy 342.530418 -223.282128) (xy 342.556721 -223.240532) (xy 342.589356 -223.203695)
			(xy 342.627477 -223.17257) (xy 342.670098 -223.147963) (xy 342.716114 -223.130511) (xy 342.764333 -223.120667)
			(xy 342.813508 -223.118686) (xy 342.862363 -223.124618) (xy 342.909634 -223.13831) (xy 342.954096 -223.159408)
			(xy 342.994599 -223.187364) (xy 343.030092 -223.221456) (xy 343.059657 -223.2608) (xy 343.082528 -223.304377)
			(xy 343.098112 -223.351058) (xy 343.106007 -223.399635) (xy 343.106502 -223.424242) (xy 343.43519 -223.424242)
			(xy 343.43915 -223.375188) (xy 343.450927 -223.327404) (xy 343.470218 -223.282128) (xy 343.496521 -223.240532)
			(xy 343.529156 -223.203695) (xy 343.567277 -223.17257) (xy 343.609898 -223.147963) (xy 343.655914 -223.130511)
			(xy 343.704133 -223.120667) (xy 343.753308 -223.118686) (xy 343.802163 -223.124618) (xy 343.849434 -223.13831)
			(xy 343.893896 -223.159408) (xy 343.934399 -223.187364) (xy 343.969892 -223.221456) (xy 343.999457 -223.2608)
			(xy 344.022328 -223.304377) (xy 344.037912 -223.351058) (xy 344.045807 -223.399635) (xy 344.046302 -223.424242)
			(xy 346.255352 -223.424242) (xy 346.259312 -223.375188) (xy 346.271089 -223.327404) (xy 346.29038 -223.282128)
			(xy 346.316683 -223.240532) (xy 346.349318 -223.203695) (xy 346.387439 -223.17257) (xy 346.43006 -223.147963)
			(xy 346.476076 -223.130511) (xy 346.524295 -223.120667) (xy 346.57347 -223.118686) (xy 346.622325 -223.124618)
			(xy 346.669596 -223.13831) (xy 346.714058 -223.159408) (xy 346.754561 -223.187364) (xy 346.790054 -223.221456)
			(xy 346.819619 -223.2608) (xy 346.84249 -223.304377) (xy 346.858074 -223.351058) (xy 346.865969 -223.399635)
			(xy 346.866464 -223.424242) (xy 347.195406 -223.424242) (xy 347.199366 -223.375188) (xy 347.211143 -223.327404)
			(xy 347.230434 -223.282128) (xy 347.256737 -223.240532) (xy 347.289372 -223.203695) (xy 347.327493 -223.17257)
			(xy 347.370114 -223.147963) (xy 347.41613 -223.130511) (xy 347.464349 -223.120667) (xy 347.513524 -223.118686)
			(xy 347.562379 -223.124618) (xy 347.60965 -223.13831) (xy 347.654112 -223.159408) (xy 347.694615 -223.187364)
			(xy 347.730108 -223.221456) (xy 347.759673 -223.2608) (xy 347.782544 -223.304377) (xy 347.798128 -223.351058)
			(xy 347.806023 -223.399635) (xy 347.806518 -223.424242) (xy 348.135206 -223.424242) (xy 348.139166 -223.375188)
			(xy 348.150943 -223.327404) (xy 348.170234 -223.282128) (xy 348.196537 -223.240532) (xy 348.229172 -223.203695)
			(xy 348.267293 -223.17257) (xy 348.309914 -223.147963) (xy 348.35593 -223.130511) (xy 348.404149 -223.120667)
			(xy 348.453324 -223.118686) (xy 348.502179 -223.124618) (xy 348.54945 -223.13831) (xy 348.593912 -223.159408)
			(xy 348.634415 -223.187364) (xy 348.669908 -223.221456) (xy 348.699473 -223.2608) (xy 348.722344 -223.304377)
			(xy 348.737928 -223.351058) (xy 348.745823 -223.399635) (xy 348.746318 -223.424242) (xy 349.07526 -223.424242)
			(xy 349.07922 -223.375188) (xy 349.090997 -223.327404) (xy 349.110288 -223.282128) (xy 349.136591 -223.240532)
			(xy 349.169226 -223.203695) (xy 349.207347 -223.17257) (xy 349.249968 -223.147963) (xy 349.295984 -223.130511)
			(xy 349.344203 -223.120667) (xy 349.393378 -223.118686) (xy 349.442233 -223.124618) (xy 349.489504 -223.13831)
			(xy 349.533966 -223.159408) (xy 349.574469 -223.187364) (xy 349.609962 -223.221456) (xy 349.639527 -223.2608)
			(xy 349.662398 -223.304377) (xy 349.677982 -223.351058) (xy 349.685877 -223.399635) (xy 349.686372 -223.424242)
			(xy 351.895422 -223.424242) (xy 351.899382 -223.375188) (xy 351.911159 -223.327404) (xy 351.93045 -223.282128)
			(xy 351.956753 -223.240532) (xy 351.989388 -223.203695) (xy 352.027509 -223.17257) (xy 352.07013 -223.147963)
			(xy 352.116146 -223.130511) (xy 352.164365 -223.120667) (xy 352.21354 -223.118686) (xy 352.262395 -223.124618)
			(xy 352.309666 -223.13831) (xy 352.354128 -223.159408) (xy 352.394631 -223.187364) (xy 352.430124 -223.221456)
			(xy 352.459689 -223.2608) (xy 352.48256 -223.304377) (xy 352.498144 -223.351058) (xy 352.506039 -223.399635)
			(xy 352.506534 -223.424242) (xy 352.835476 -223.424242) (xy 352.839436 -223.375188) (xy 352.851213 -223.327404)
			(xy 352.870504 -223.282128) (xy 352.896807 -223.240532) (xy 352.929442 -223.203695) (xy 352.967563 -223.17257)
			(xy 353.010184 -223.147963) (xy 353.0562 -223.130511) (xy 353.104419 -223.120667) (xy 353.153594 -223.118686)
			(xy 353.202449 -223.124618) (xy 353.24972 -223.13831) (xy 353.294182 -223.159408) (xy 353.334685 -223.187364)
			(xy 353.370178 -223.221456) (xy 353.399743 -223.2608) (xy 353.422614 -223.304377) (xy 353.438198 -223.351058)
			(xy 353.446093 -223.399635) (xy 353.446588 -223.424242) (xy 353.77553 -223.424242) (xy 353.77949 -223.375188)
			(xy 353.791267 -223.327404) (xy 353.810558 -223.282128) (xy 353.836861 -223.240532) (xy 353.869496 -223.203695)
			(xy 353.907617 -223.17257) (xy 353.950238 -223.147963) (xy 353.996254 -223.130511) (xy 354.044473 -223.120667)
			(xy 354.093648 -223.118686) (xy 354.142503 -223.124618) (xy 354.189774 -223.13831) (xy 354.234236 -223.159408)
			(xy 354.274739 -223.187364) (xy 354.310232 -223.221456) (xy 354.339797 -223.2608) (xy 354.362668 -223.304377)
			(xy 354.378252 -223.351058) (xy 354.386147 -223.399635) (xy 354.386642 -223.424242) (xy 354.71533 -223.424242)
			(xy 354.71929 -223.375188) (xy 354.731067 -223.327404) (xy 354.750358 -223.282128) (xy 354.776661 -223.240532)
			(xy 354.809296 -223.203695) (xy 354.847417 -223.17257) (xy 354.890038 -223.147963) (xy 354.936054 -223.130511)
			(xy 354.984273 -223.120667) (xy 355.033448 -223.118686) (xy 355.082303 -223.124618) (xy 355.129574 -223.13831)
			(xy 355.174036 -223.159408) (xy 355.214539 -223.187364) (xy 355.250032 -223.221456) (xy 355.279597 -223.2608)
			(xy 355.302468 -223.304377) (xy 355.318052 -223.351058) (xy 355.325947 -223.399635) (xy 355.326442 -223.424242)
			(xy 355.655638 -223.424242) (xy 355.659598 -223.375188) (xy 355.671375 -223.327404) (xy 355.690666 -223.282128)
			(xy 355.716969 -223.240532) (xy 355.749604 -223.203695) (xy 355.787725 -223.17257) (xy 355.830346 -223.147963)
			(xy 355.876362 -223.130511) (xy 355.924581 -223.120667) (xy 355.973756 -223.118686) (xy 356.022611 -223.124618)
			(xy 356.069882 -223.13831) (xy 356.114344 -223.159408) (xy 356.154847 -223.187364) (xy 356.19034 -223.221456)
			(xy 356.219905 -223.2608) (xy 356.242776 -223.304377) (xy 356.25836 -223.351058) (xy 356.266255 -223.399635)
			(xy 356.26675 -223.424242) (xy 356.595438 -223.424242) (xy 356.599398 -223.375188) (xy 356.611175 -223.327404)
			(xy 356.630466 -223.282128) (xy 356.656769 -223.240532) (xy 356.689404 -223.203695) (xy 356.727525 -223.17257)
			(xy 356.770146 -223.147963) (xy 356.816162 -223.130511) (xy 356.864381 -223.120667) (xy 356.913556 -223.118686)
			(xy 356.962411 -223.124618) (xy 357.009682 -223.13831) (xy 357.054144 -223.159408) (xy 357.094647 -223.187364)
			(xy 357.13014 -223.221456) (xy 357.159705 -223.2608) (xy 357.182576 -223.304377) (xy 357.19816 -223.351058)
			(xy 357.206055 -223.399635) (xy 357.20655 -223.424242) (xy 357.535238 -223.424242) (xy 357.539198 -223.375188)
			(xy 357.550975 -223.327404) (xy 357.570266 -223.282128) (xy 357.596569 -223.240532) (xy 357.629204 -223.203695)
			(xy 357.667325 -223.17257) (xy 357.709946 -223.147963) (xy 357.755962 -223.130511) (xy 357.804181 -223.120667)
			(xy 357.853356 -223.118686) (xy 357.902211 -223.124618) (xy 357.949482 -223.13831) (xy 357.993944 -223.159408)
			(xy 358.034447 -223.187364) (xy 358.06994 -223.221456) (xy 358.099505 -223.2608) (xy 358.122376 -223.304377)
			(xy 358.13796 -223.351058) (xy 358.145855 -223.399635) (xy 358.14635 -223.424242) (xy 358.145855 -223.448849)
			(xy 358.13796 -223.497426) (xy 358.122376 -223.544107) (xy 358.099505 -223.587684) (xy 358.06994 -223.627028)
			(xy 358.034447 -223.66112) (xy 357.993944 -223.689076) (xy 357.949482 -223.710174) (xy 357.902211 -223.723866)
			(xy 357.853356 -223.729798) (xy 357.804181 -223.727817) (xy 357.755962 -223.717973) (xy 357.709946 -223.700521)
			(xy 357.667325 -223.675914) (xy 357.629204 -223.644789) (xy 357.596569 -223.607952) (xy 357.570266 -223.566356)
			(xy 357.550975 -223.52108) (xy 357.539198 -223.473296) (xy 357.535238 -223.424242) (xy 357.20655 -223.424242)
			(xy 357.206055 -223.448849) (xy 357.19816 -223.497426) (xy 357.182576 -223.544107) (xy 357.159705 -223.587684)
			(xy 357.13014 -223.627028) (xy 357.094647 -223.66112) (xy 357.054144 -223.689076) (xy 357.009682 -223.710174)
			(xy 356.962411 -223.723866) (xy 356.913556 -223.729798) (xy 356.864381 -223.727817) (xy 356.816162 -223.717973)
			(xy 356.770146 -223.700521) (xy 356.727525 -223.675914) (xy 356.689404 -223.644789) (xy 356.656769 -223.607952)
			(xy 356.630466 -223.566356) (xy 356.611175 -223.52108) (xy 356.599398 -223.473296) (xy 356.595438 -223.424242)
			(xy 356.26675 -223.424242) (xy 356.266255 -223.448849) (xy 356.25836 -223.497426) (xy 356.242776 -223.544107)
			(xy 356.219905 -223.587684) (xy 356.19034 -223.627028) (xy 356.154847 -223.66112) (xy 356.114344 -223.689076)
			(xy 356.069882 -223.710174) (xy 356.022611 -223.723866) (xy 355.973756 -223.729798) (xy 355.924581 -223.727817)
			(xy 355.876362 -223.717973) (xy 355.830346 -223.700521) (xy 355.787725 -223.675914) (xy 355.749604 -223.644789)
			(xy 355.716969 -223.607952) (xy 355.690666 -223.566356) (xy 355.671375 -223.52108) (xy 355.659598 -223.473296)
			(xy 355.655638 -223.424242) (xy 355.326442 -223.424242) (xy 355.325947 -223.448849) (xy 355.318052 -223.497426)
			(xy 355.302468 -223.544107) (xy 355.279597 -223.587684) (xy 355.250032 -223.627028) (xy 355.214539 -223.66112)
			(xy 355.174036 -223.689076) (xy 355.129574 -223.710174) (xy 355.082303 -223.723866) (xy 355.033448 -223.729798)
			(xy 354.984273 -223.727817) (xy 354.936054 -223.717973) (xy 354.890038 -223.700521) (xy 354.847417 -223.675914)
			(xy 354.809296 -223.644789) (xy 354.776661 -223.607952) (xy 354.750358 -223.566356) (xy 354.731067 -223.52108)
			(xy 354.71929 -223.473296) (xy 354.71533 -223.424242) (xy 354.386642 -223.424242) (xy 354.386147 -223.448849)
			(xy 354.378252 -223.497426) (xy 354.362668 -223.544107) (xy 354.339797 -223.587684) (xy 354.310232 -223.627028)
			(xy 354.274739 -223.66112) (xy 354.234236 -223.689076) (xy 354.189774 -223.710174) (xy 354.142503 -223.723866)
			(xy 354.093648 -223.729798) (xy 354.044473 -223.727817) (xy 353.996254 -223.717973) (xy 353.950238 -223.700521)
			(xy 353.907617 -223.675914) (xy 353.869496 -223.644789) (xy 353.836861 -223.607952) (xy 353.810558 -223.566356)
			(xy 353.791267 -223.52108) (xy 353.77949 -223.473296) (xy 353.77553 -223.424242) (xy 353.446588 -223.424242)
			(xy 353.446093 -223.448849) (xy 353.438198 -223.497426) (xy 353.422614 -223.544107) (xy 353.399743 -223.587684)
			(xy 353.370178 -223.627028) (xy 353.334685 -223.66112) (xy 353.294182 -223.689076) (xy 353.24972 -223.710174)
			(xy 353.202449 -223.723866) (xy 353.153594 -223.729798) (xy 353.104419 -223.727817) (xy 353.0562 -223.717973)
			(xy 353.010184 -223.700521) (xy 352.967563 -223.675914) (xy 352.929442 -223.644789) (xy 352.896807 -223.607952)
			(xy 352.870504 -223.566356) (xy 352.851213 -223.52108) (xy 352.839436 -223.473296) (xy 352.835476 -223.424242)
			(xy 352.506534 -223.424242) (xy 352.506039 -223.448849) (xy 352.498144 -223.497426) (xy 352.48256 -223.544107)
			(xy 352.459689 -223.587684) (xy 352.430124 -223.627028) (xy 352.394631 -223.66112) (xy 352.354128 -223.689076)
			(xy 352.309666 -223.710174) (xy 352.262395 -223.723866) (xy 352.21354 -223.729798) (xy 352.164365 -223.727817)
			(xy 352.116146 -223.717973) (xy 352.07013 -223.700521) (xy 352.027509 -223.675914) (xy 351.989388 -223.644789)
			(xy 351.956753 -223.607952) (xy 351.93045 -223.566356) (xy 351.911159 -223.52108) (xy 351.899382 -223.473296)
			(xy 351.895422 -223.424242) (xy 349.686372 -223.424242) (xy 349.685877 -223.448849) (xy 349.677982 -223.497426)
			(xy 349.662398 -223.544107) (xy 349.639527 -223.587684) (xy 349.609962 -223.627028) (xy 349.574469 -223.66112)
			(xy 349.533966 -223.689076) (xy 349.489504 -223.710174) (xy 349.442233 -223.723866) (xy 349.393378 -223.729798)
			(xy 349.344203 -223.727817) (xy 349.295984 -223.717973) (xy 349.249968 -223.700521) (xy 349.207347 -223.675914)
			(xy 349.169226 -223.644789) (xy 349.136591 -223.607952) (xy 349.110288 -223.566356) (xy 349.090997 -223.52108)
			(xy 349.07922 -223.473296) (xy 349.07526 -223.424242) (xy 348.746318 -223.424242) (xy 348.745823 -223.448849)
			(xy 348.737928 -223.497426) (xy 348.722344 -223.544107) (xy 348.699473 -223.587684) (xy 348.669908 -223.627028)
			(xy 348.634415 -223.66112) (xy 348.593912 -223.689076) (xy 348.54945 -223.710174) (xy 348.502179 -223.723866)
			(xy 348.453324 -223.729798) (xy 348.404149 -223.727817) (xy 348.35593 -223.717973) (xy 348.309914 -223.700521)
			(xy 348.267293 -223.675914) (xy 348.229172 -223.644789) (xy 348.196537 -223.607952) (xy 348.170234 -223.566356)
			(xy 348.150943 -223.52108) (xy 348.139166 -223.473296) (xy 348.135206 -223.424242) (xy 347.806518 -223.424242)
			(xy 347.806023 -223.448849) (xy 347.798128 -223.497426) (xy 347.782544 -223.544107) (xy 347.759673 -223.587684)
			(xy 347.730108 -223.627028) (xy 347.694615 -223.66112) (xy 347.654112 -223.689076) (xy 347.60965 -223.710174)
			(xy 347.562379 -223.723866) (xy 347.513524 -223.729798) (xy 347.464349 -223.727817) (xy 347.41613 -223.717973)
			(xy 347.370114 -223.700521) (xy 347.327493 -223.675914) (xy 347.289372 -223.644789) (xy 347.256737 -223.607952)
			(xy 347.230434 -223.566356) (xy 347.211143 -223.52108) (xy 347.199366 -223.473296) (xy 347.195406 -223.424242)
			(xy 346.866464 -223.424242) (xy 346.865969 -223.448849) (xy 346.858074 -223.497426) (xy 346.84249 -223.544107)
			(xy 346.819619 -223.587684) (xy 346.790054 -223.627028) (xy 346.754561 -223.66112) (xy 346.714058 -223.689076)
			(xy 346.669596 -223.710174) (xy 346.622325 -223.723866) (xy 346.57347 -223.729798) (xy 346.524295 -223.727817)
			(xy 346.476076 -223.717973) (xy 346.43006 -223.700521) (xy 346.387439 -223.675914) (xy 346.349318 -223.644789)
			(xy 346.316683 -223.607952) (xy 346.29038 -223.566356) (xy 346.271089 -223.52108) (xy 346.259312 -223.473296)
			(xy 346.255352 -223.424242) (xy 344.046302 -223.424242) (xy 344.045807 -223.448849) (xy 344.037912 -223.497426)
			(xy 344.022328 -223.544107) (xy 343.999457 -223.587684) (xy 343.969892 -223.627028) (xy 343.934399 -223.66112)
			(xy 343.893896 -223.689076) (xy 343.849434 -223.710174) (xy 343.802163 -223.723866) (xy 343.753308 -223.729798)
			(xy 343.704133 -223.727817) (xy 343.655914 -223.717973) (xy 343.609898 -223.700521) (xy 343.567277 -223.675914)
			(xy 343.529156 -223.644789) (xy 343.496521 -223.607952) (xy 343.470218 -223.566356) (xy 343.450927 -223.52108)
			(xy 343.43915 -223.473296) (xy 343.43519 -223.424242) (xy 343.106502 -223.424242) (xy 343.106007 -223.448849)
			(xy 343.098112 -223.497426) (xy 343.082528 -223.544107) (xy 343.059657 -223.587684) (xy 343.030092 -223.627028)
			(xy 342.994599 -223.66112) (xy 342.954096 -223.689076) (xy 342.909634 -223.710174) (xy 342.862363 -223.723866)
			(xy 342.813508 -223.729798) (xy 342.764333 -223.727817) (xy 342.716114 -223.717973) (xy 342.670098 -223.700521)
			(xy 342.627477 -223.675914) (xy 342.589356 -223.644789) (xy 342.556721 -223.607952) (xy 342.530418 -223.566356)
			(xy 342.511127 -223.52108) (xy 342.49935 -223.473296) (xy 342.49539 -223.424242) (xy 342.166448 -223.424242)
			(xy 342.165953 -223.448849) (xy 342.158058 -223.497426) (xy 342.142474 -223.544107) (xy 342.119603 -223.587684)
			(xy 342.090038 -223.627028) (xy 342.054545 -223.66112) (xy 342.014042 -223.689076) (xy 341.96958 -223.710174)
			(xy 341.922309 -223.723866) (xy 341.873454 -223.729798) (xy 341.824279 -223.727817) (xy 341.77606 -223.717973)
			(xy 341.730044 -223.700521) (xy 341.687423 -223.675914) (xy 341.649302 -223.644789) (xy 341.616667 -223.607952)
			(xy 341.590364 -223.566356) (xy 341.571073 -223.52108) (xy 341.559296 -223.473296) (xy 341.555336 -223.424242)
			(xy 340.30412 -223.424242) (xy 340.30412 -223.445578) (xy 340.304558 -223.455641) (xy 340.312294 -223.474223)
			(xy 340.319106 -223.481646) (xy 340.957408 -224.119948) (xy 340.966369 -224.127926) (xy 340.989155 -224.135344)
			(xy 341.001096 -224.134172) (xy 341.094314 -224.119694) (xy 341.113872 -224.10547) (xy 341.11946 -224.094548)
			(xy 341.130806 -224.073496) (xy 341.159037 -224.034896) (xy 341.192942 -224.001172) (xy 341.231692 -223.973149)
			(xy 341.274338 -223.951512) (xy 341.319837 -223.936791) (xy 341.367075 -223.929346) (xy 341.390986 -223.92894)
			(xy 341.414978 -223.929385) (xy 341.462373 -223.93689) (xy 341.508009 -223.951718) (xy 341.550764 -223.973504)
			(xy 341.589584 -224.00171) (xy 341.623512 -224.035642) (xy 341.651714 -224.074465) (xy 341.673495 -224.117222)
			(xy 341.688317 -224.16286) (xy 341.695817 -224.210255) (xy 341.696294 -224.234248) (xy 343.905344 -224.234248)
			(xy 343.909304 -224.185194) (xy 343.921081 -224.13741) (xy 343.940372 -224.092134) (xy 343.966675 -224.050538)
			(xy 343.99931 -224.013701) (xy 344.037431 -223.982576) (xy 344.080052 -223.957969) (xy 344.126068 -223.940517)
			(xy 344.174287 -223.930673) (xy 344.223462 -223.928692) (xy 344.272317 -223.934624) (xy 344.319588 -223.948316)
			(xy 344.36405 -223.969414) (xy 344.404553 -223.99737) (xy 344.440046 -224.031462) (xy 344.469611 -224.070806)
			(xy 344.492482 -224.114383) (xy 344.508066 -224.161064) (xy 344.515961 -224.209641) (xy 344.516456 -224.234248)
			(xy 344.845398 -224.234248) (xy 344.849358 -224.185194) (xy 344.861135 -224.13741) (xy 344.880426 -224.092134)
			(xy 344.906729 -224.050538) (xy 344.939364 -224.013701) (xy 344.977485 -223.982576) (xy 345.020106 -223.957969)
			(xy 345.066122 -223.940517) (xy 345.114341 -223.930673) (xy 345.163516 -223.928692) (xy 345.212371 -223.934624)
			(xy 345.259642 -223.948316) (xy 345.304104 -223.969414) (xy 345.344607 -223.99737) (xy 345.3801 -224.031462)
			(xy 345.409665 -224.070806) (xy 345.432536 -224.114383) (xy 345.44812 -224.161064) (xy 345.456015 -224.209641)
			(xy 345.45651 -224.234248) (xy 345.785198 -224.234248) (xy 345.789158 -224.185194) (xy 345.800935 -224.13741)
			(xy 345.820226 -224.092134) (xy 345.846529 -224.050538) (xy 345.879164 -224.013701) (xy 345.917285 -223.982576)
			(xy 345.959906 -223.957969) (xy 346.005922 -223.940517) (xy 346.054141 -223.930673) (xy 346.103316 -223.928692)
			(xy 346.152171 -223.934624) (xy 346.199442 -223.948316) (xy 346.243904 -223.969414) (xy 346.284407 -223.99737)
			(xy 346.3199 -224.031462) (xy 346.349465 -224.070806) (xy 346.372336 -224.114383) (xy 346.38792 -224.161064)
			(xy 346.395815 -224.209641) (xy 346.39631 -224.234248) (xy 346.725252 -224.234248) (xy 346.729212 -224.185194)
			(xy 346.740989 -224.13741) (xy 346.76028 -224.092134) (xy 346.786583 -224.050538) (xy 346.819218 -224.013701)
			(xy 346.857339 -223.982576) (xy 346.89996 -223.957969) (xy 346.945976 -223.940517) (xy 346.994195 -223.930673)
			(xy 347.04337 -223.928692) (xy 347.092225 -223.934624) (xy 347.139496 -223.948316) (xy 347.183958 -223.969414)
			(xy 347.224461 -223.99737) (xy 347.259954 -224.031462) (xy 347.289519 -224.070806) (xy 347.31239 -224.114383)
			(xy 347.327974 -224.161064) (xy 347.335869 -224.209641) (xy 347.336364 -224.234248) (xy 347.665306 -224.234248)
			(xy 347.669266 -224.185194) (xy 347.681043 -224.13741) (xy 347.700334 -224.092134) (xy 347.726637 -224.050538)
			(xy 347.759272 -224.013701) (xy 347.797393 -223.982576) (xy 347.840014 -223.957969) (xy 347.88603 -223.940517)
			(xy 347.934249 -223.930673) (xy 347.983424 -223.928692) (xy 348.032279 -223.934624) (xy 348.07955 -223.948316)
			(xy 348.124012 -223.969414) (xy 348.164515 -223.99737) (xy 348.200008 -224.031462) (xy 348.229573 -224.070806)
			(xy 348.252444 -224.114383) (xy 348.268028 -224.161064) (xy 348.275923 -224.209641) (xy 348.276418 -224.234248)
			(xy 348.60536 -224.234248) (xy 348.60932 -224.185194) (xy 348.621097 -224.13741) (xy 348.640388 -224.092134)
			(xy 348.666691 -224.050538) (xy 348.699326 -224.013701) (xy 348.737447 -223.982576) (xy 348.780068 -223.957969)
			(xy 348.826084 -223.940517) (xy 348.874303 -223.930673) (xy 348.923478 -223.928692) (xy 348.972333 -223.934624)
			(xy 349.019604 -223.948316) (xy 349.064066 -223.969414) (xy 349.104569 -223.99737) (xy 349.140062 -224.031462)
			(xy 349.169627 -224.070806) (xy 349.192498 -224.114383) (xy 349.208082 -224.161064) (xy 349.215977 -224.209641)
			(xy 349.216472 -224.234248) (xy 349.545414 -224.234248) (xy 349.549374 -224.185194) (xy 349.561151 -224.13741)
			(xy 349.580442 -224.092134) (xy 349.606745 -224.050538) (xy 349.63938 -224.013701) (xy 349.677501 -223.982576)
			(xy 349.720122 -223.957969) (xy 349.766138 -223.940517) (xy 349.814357 -223.930673) (xy 349.863532 -223.928692)
			(xy 349.912387 -223.934624) (xy 349.959658 -223.948316) (xy 350.00412 -223.969414) (xy 350.044623 -223.99737)
			(xy 350.080116 -224.031462) (xy 350.109681 -224.070806) (xy 350.132552 -224.114383) (xy 350.148136 -224.161064)
			(xy 350.156031 -224.209641) (xy 350.156526 -224.234248) (xy 350.485214 -224.234248) (xy 350.489174 -224.185194)
			(xy 350.500951 -224.13741) (xy 350.520242 -224.092134) (xy 350.546545 -224.050538) (xy 350.57918 -224.013701)
			(xy 350.617301 -223.982576) (xy 350.659922 -223.957969) (xy 350.705938 -223.940517) (xy 350.754157 -223.930673)
			(xy 350.803332 -223.928692) (xy 350.852187 -223.934624) (xy 350.899458 -223.948316) (xy 350.94392 -223.969414)
			(xy 350.984423 -223.99737) (xy 351.019916 -224.031462) (xy 351.049481 -224.070806) (xy 351.072352 -224.114383)
			(xy 351.087936 -224.161064) (xy 351.095831 -224.209641) (xy 351.096326 -224.234248) (xy 351.425268 -224.234248)
			(xy 351.429228 -224.185194) (xy 351.441005 -224.13741) (xy 351.460296 -224.092134) (xy 351.486599 -224.050538)
			(xy 351.519234 -224.013701) (xy 351.557355 -223.982576) (xy 351.599976 -223.957969) (xy 351.645992 -223.940517)
			(xy 351.694211 -223.930673) (xy 351.743386 -223.928692) (xy 351.792241 -223.934624) (xy 351.839512 -223.948316)
			(xy 351.883974 -223.969414) (xy 351.924477 -223.99737) (xy 351.95997 -224.031462) (xy 351.989535 -224.070806)
			(xy 352.012406 -224.114383) (xy 352.02799 -224.161064) (xy 352.035885 -224.209641) (xy 352.03638 -224.234248)
			(xy 352.365322 -224.234248) (xy 352.369282 -224.185194) (xy 352.381059 -224.13741) (xy 352.40035 -224.092134)
			(xy 352.426653 -224.050538) (xy 352.459288 -224.013701) (xy 352.497409 -223.982576) (xy 352.54003 -223.957969)
			(xy 352.586046 -223.940517) (xy 352.634265 -223.930673) (xy 352.68344 -223.928692) (xy 352.732295 -223.934624)
			(xy 352.779566 -223.948316) (xy 352.824028 -223.969414) (xy 352.864531 -223.99737) (xy 352.900024 -224.031462)
			(xy 352.929589 -224.070806) (xy 352.95246 -224.114383) (xy 352.968044 -224.161064) (xy 352.975939 -224.209641)
			(xy 352.976434 -224.234248) (xy 353.305376 -224.234248) (xy 353.309336 -224.185194) (xy 353.321113 -224.13741)
			(xy 353.340404 -224.092134) (xy 353.366707 -224.050538) (xy 353.399342 -224.013701) (xy 353.437463 -223.982576)
			(xy 353.480084 -223.957969) (xy 353.5261 -223.940517) (xy 353.574319 -223.930673) (xy 353.623494 -223.928692)
			(xy 353.672349 -223.934624) (xy 353.71962 -223.948316) (xy 353.764082 -223.969414) (xy 353.804585 -223.99737)
			(xy 353.840078 -224.031462) (xy 353.869643 -224.070806) (xy 353.892514 -224.114383) (xy 353.908098 -224.161064)
			(xy 353.915993 -224.209641) (xy 353.916488 -224.234248) (xy 354.24543 -224.234248) (xy 354.24939 -224.185194)
			(xy 354.261167 -224.13741) (xy 354.280458 -224.092134) (xy 354.306761 -224.050538) (xy 354.339396 -224.013701)
			(xy 354.377517 -223.982576) (xy 354.420138 -223.957969) (xy 354.466154 -223.940517) (xy 354.514373 -223.930673)
			(xy 354.563548 -223.928692) (xy 354.612403 -223.934624) (xy 354.659674 -223.948316) (xy 354.704136 -223.969414)
			(xy 354.744639 -223.99737) (xy 354.780132 -224.031462) (xy 354.809697 -224.070806) (xy 354.832568 -224.114383)
			(xy 354.848152 -224.161064) (xy 354.856047 -224.209641) (xy 354.856542 -224.234248) (xy 355.18523 -224.234248)
			(xy 355.18919 -224.185194) (xy 355.200967 -224.13741) (xy 355.220258 -224.092134) (xy 355.246561 -224.050538)
			(xy 355.279196 -224.013701) (xy 355.317317 -223.982576) (xy 355.359938 -223.957969) (xy 355.405954 -223.940517)
			(xy 355.454173 -223.930673) (xy 355.503348 -223.928692) (xy 355.552203 -223.934624) (xy 355.599474 -223.948316)
			(xy 355.643936 -223.969414) (xy 355.684439 -223.99737) (xy 355.719932 -224.031462) (xy 355.749497 -224.070806)
			(xy 355.772368 -224.114383) (xy 355.787952 -224.161064) (xy 355.795847 -224.209641) (xy 355.796342 -224.234248)
			(xy 356.125284 -224.234248) (xy 356.129244 -224.185194) (xy 356.141021 -224.13741) (xy 356.160312 -224.092134)
			(xy 356.186615 -224.050538) (xy 356.21925 -224.013701) (xy 356.257371 -223.982576) (xy 356.299992 -223.957969)
			(xy 356.346008 -223.940517) (xy 356.394227 -223.930673) (xy 356.443402 -223.928692) (xy 356.492257 -223.934624)
			(xy 356.539528 -223.948316) (xy 356.58399 -223.969414) (xy 356.624493 -223.99737) (xy 356.659986 -224.031462)
			(xy 356.689551 -224.070806) (xy 356.712422 -224.114383) (xy 356.728006 -224.161064) (xy 356.735901 -224.209641)
			(xy 356.736396 -224.234248) (xy 357.065338 -224.234248) (xy 357.069298 -224.185194) (xy 357.081075 -224.13741)
			(xy 357.100366 -224.092134) (xy 357.126669 -224.050538) (xy 357.159304 -224.013701) (xy 357.197425 -223.982576)
			(xy 357.240046 -223.957969) (xy 357.286062 -223.940517) (xy 357.334281 -223.930673) (xy 357.383456 -223.928692)
			(xy 357.432311 -223.934624) (xy 357.479582 -223.948316) (xy 357.524044 -223.969414) (xy 357.564547 -223.99737)
			(xy 357.60004 -224.031462) (xy 357.629605 -224.070806) (xy 357.652476 -224.114383) (xy 357.66806 -224.161064)
			(xy 357.675955 -224.209641) (xy 357.67645 -224.234248) (xy 358.005392 -224.234248) (xy 358.009352 -224.185194)
			(xy 358.021129 -224.13741) (xy 358.04042 -224.092134) (xy 358.066723 -224.050538) (xy 358.099358 -224.013701)
			(xy 358.137479 -223.982576) (xy 358.1801 -223.957969) (xy 358.226116 -223.940517) (xy 358.274335 -223.930673)
			(xy 358.32351 -223.928692) (xy 358.372365 -223.934624) (xy 358.419636 -223.948316) (xy 358.464098 -223.969414)
			(xy 358.504601 -223.99737) (xy 358.540094 -224.031462) (xy 358.569659 -224.070806) (xy 358.59253 -224.114383)
			(xy 358.608114 -224.161064) (xy 358.616009 -224.209641) (xy 358.616504 -224.234248) (xy 358.616009 -224.258855)
			(xy 358.608114 -224.307432) (xy 358.59253 -224.354113) (xy 358.569659 -224.39769) (xy 358.540094 -224.437034)
			(xy 358.504601 -224.471126) (xy 358.464098 -224.499082) (xy 358.419636 -224.52018) (xy 358.372365 -224.533872)
			(xy 358.32351 -224.539804) (xy 358.274335 -224.537823) (xy 358.226116 -224.527979) (xy 358.1801 -224.510527)
			(xy 358.137479 -224.48592) (xy 358.099358 -224.454795) (xy 358.066723 -224.417958) (xy 358.04042 -224.376362)
			(xy 358.021129 -224.331086) (xy 358.009352 -224.283302) (xy 358.005392 -224.234248) (xy 357.67645 -224.234248)
			(xy 357.675955 -224.258855) (xy 357.66806 -224.307432) (xy 357.652476 -224.354113) (xy 357.629605 -224.39769)
			(xy 357.60004 -224.437034) (xy 357.564547 -224.471126) (xy 357.524044 -224.499082) (xy 357.479582 -224.52018)
			(xy 357.432311 -224.533872) (xy 357.383456 -224.539804) (xy 357.334281 -224.537823) (xy 357.286062 -224.527979)
			(xy 357.240046 -224.510527) (xy 357.197425 -224.48592) (xy 357.159304 -224.454795) (xy 357.126669 -224.417958)
			(xy 357.100366 -224.376362) (xy 357.081075 -224.331086) (xy 357.069298 -224.283302) (xy 357.065338 -224.234248)
			(xy 356.736396 -224.234248) (xy 356.735901 -224.258855) (xy 356.728006 -224.307432) (xy 356.712422 -224.354113)
			(xy 356.689551 -224.39769) (xy 356.659986 -224.437034) (xy 356.624493 -224.471126) (xy 356.58399 -224.499082)
			(xy 356.539528 -224.52018) (xy 356.492257 -224.533872) (xy 356.443402 -224.539804) (xy 356.394227 -224.537823)
			(xy 356.346008 -224.527979) (xy 356.299992 -224.510527) (xy 356.257371 -224.48592) (xy 356.21925 -224.454795)
			(xy 356.186615 -224.417958) (xy 356.160312 -224.376362) (xy 356.141021 -224.331086) (xy 356.129244 -224.283302)
			(xy 356.125284 -224.234248) (xy 355.796342 -224.234248) (xy 355.795847 -224.258855) (xy 355.787952 -224.307432)
			(xy 355.772368 -224.354113) (xy 355.749497 -224.39769) (xy 355.719932 -224.437034) (xy 355.684439 -224.471126)
			(xy 355.643936 -224.499082) (xy 355.599474 -224.52018) (xy 355.552203 -224.533872) (xy 355.503348 -224.539804)
			(xy 355.454173 -224.537823) (xy 355.405954 -224.527979) (xy 355.359938 -224.510527) (xy 355.317317 -224.48592)
			(xy 355.279196 -224.454795) (xy 355.246561 -224.417958) (xy 355.220258 -224.376362) (xy 355.200967 -224.331086)
			(xy 355.18919 -224.283302) (xy 355.18523 -224.234248) (xy 354.856542 -224.234248) (xy 354.856047 -224.258855)
			(xy 354.848152 -224.307432) (xy 354.832568 -224.354113) (xy 354.809697 -224.39769) (xy 354.780132 -224.437034)
			(xy 354.744639 -224.471126) (xy 354.704136 -224.499082) (xy 354.659674 -224.52018) (xy 354.612403 -224.533872)
			(xy 354.563548 -224.539804) (xy 354.514373 -224.537823) (xy 354.466154 -224.527979) (xy 354.420138 -224.510527)
			(xy 354.377517 -224.48592) (xy 354.339396 -224.454795) (xy 354.306761 -224.417958) (xy 354.280458 -224.376362)
			(xy 354.261167 -224.331086) (xy 354.24939 -224.283302) (xy 354.24543 -224.234248) (xy 353.916488 -224.234248)
			(xy 353.915993 -224.258855) (xy 353.908098 -224.307432) (xy 353.892514 -224.354113) (xy 353.869643 -224.39769)
			(xy 353.840078 -224.437034) (xy 353.804585 -224.471126) (xy 353.764082 -224.499082) (xy 353.71962 -224.52018)
			(xy 353.672349 -224.533872) (xy 353.623494 -224.539804) (xy 353.574319 -224.537823) (xy 353.5261 -224.527979)
			(xy 353.480084 -224.510527) (xy 353.437463 -224.48592) (xy 353.399342 -224.454795) (xy 353.366707 -224.417958)
			(xy 353.340404 -224.376362) (xy 353.321113 -224.331086) (xy 353.309336 -224.283302) (xy 353.305376 -224.234248)
			(xy 352.976434 -224.234248) (xy 352.975939 -224.258855) (xy 352.968044 -224.307432) (xy 352.95246 -224.354113)
			(xy 352.929589 -224.39769) (xy 352.900024 -224.437034) (xy 352.864531 -224.471126) (xy 352.824028 -224.499082)
			(xy 352.779566 -224.52018) (xy 352.732295 -224.533872) (xy 352.68344 -224.539804) (xy 352.634265 -224.537823)
			(xy 352.586046 -224.527979) (xy 352.54003 -224.510527) (xy 352.497409 -224.48592) (xy 352.459288 -224.454795)
			(xy 352.426653 -224.417958) (xy 352.40035 -224.376362) (xy 352.381059 -224.331086) (xy 352.369282 -224.283302)
			(xy 352.365322 -224.234248) (xy 352.03638 -224.234248) (xy 352.035885 -224.258855) (xy 352.02799 -224.307432)
			(xy 352.012406 -224.354113) (xy 351.989535 -224.39769) (xy 351.95997 -224.437034) (xy 351.924477 -224.471126)
			(xy 351.883974 -224.499082) (xy 351.839512 -224.52018) (xy 351.792241 -224.533872) (xy 351.743386 -224.539804)
			(xy 351.694211 -224.537823) (xy 351.645992 -224.527979) (xy 351.599976 -224.510527) (xy 351.557355 -224.48592)
			(xy 351.519234 -224.454795) (xy 351.486599 -224.417958) (xy 351.460296 -224.376362) (xy 351.441005 -224.331086)
			(xy 351.429228 -224.283302) (xy 351.425268 -224.234248) (xy 351.096326 -224.234248) (xy 351.095831 -224.258855)
			(xy 351.087936 -224.307432) (xy 351.072352 -224.354113) (xy 351.049481 -224.39769) (xy 351.019916 -224.437034)
			(xy 350.984423 -224.471126) (xy 350.94392 -224.499082) (xy 350.899458 -224.52018) (xy 350.852187 -224.533872)
			(xy 350.803332 -224.539804) (xy 350.754157 -224.537823) (xy 350.705938 -224.527979) (xy 350.659922 -224.510527)
			(xy 350.617301 -224.48592) (xy 350.57918 -224.454795) (xy 350.546545 -224.417958) (xy 350.520242 -224.376362)
			(xy 350.500951 -224.331086) (xy 350.489174 -224.283302) (xy 350.485214 -224.234248) (xy 350.156526 -224.234248)
			(xy 350.156031 -224.258855) (xy 350.148136 -224.307432) (xy 350.132552 -224.354113) (xy 350.109681 -224.39769)
			(xy 350.080116 -224.437034) (xy 350.044623 -224.471126) (xy 350.00412 -224.499082) (xy 349.959658 -224.52018)
			(xy 349.912387 -224.533872) (xy 349.863532 -224.539804) (xy 349.814357 -224.537823) (xy 349.766138 -224.527979)
			(xy 349.720122 -224.510527) (xy 349.677501 -224.48592) (xy 349.63938 -224.454795) (xy 349.606745 -224.417958)
			(xy 349.580442 -224.376362) (xy 349.561151 -224.331086) (xy 349.549374 -224.283302) (xy 349.545414 -224.234248)
			(xy 349.216472 -224.234248) (xy 349.215977 -224.258855) (xy 349.208082 -224.307432) (xy 349.192498 -224.354113)
			(xy 349.169627 -224.39769) (xy 349.140062 -224.437034) (xy 349.104569 -224.471126) (xy 349.064066 -224.499082)
			(xy 349.019604 -224.52018) (xy 348.972333 -224.533872) (xy 348.923478 -224.539804) (xy 348.874303 -224.537823)
			(xy 348.826084 -224.527979) (xy 348.780068 -224.510527) (xy 348.737447 -224.48592) (xy 348.699326 -224.454795)
			(xy 348.666691 -224.417958) (xy 348.640388 -224.376362) (xy 348.621097 -224.331086) (xy 348.60932 -224.283302)
			(xy 348.60536 -224.234248) (xy 348.276418 -224.234248) (xy 348.275923 -224.258855) (xy 348.268028 -224.307432)
			(xy 348.252444 -224.354113) (xy 348.229573 -224.39769) (xy 348.200008 -224.437034) (xy 348.164515 -224.471126)
			(xy 348.124012 -224.499082) (xy 348.07955 -224.52018) (xy 348.032279 -224.533872) (xy 347.983424 -224.539804)
			(xy 347.934249 -224.537823) (xy 347.88603 -224.527979) (xy 347.840014 -224.510527) (xy 347.797393 -224.48592)
			(xy 347.759272 -224.454795) (xy 347.726637 -224.417958) (xy 347.700334 -224.376362) (xy 347.681043 -224.331086)
			(xy 347.669266 -224.283302) (xy 347.665306 -224.234248) (xy 347.336364 -224.234248) (xy 347.335869 -224.258855)
			(xy 347.327974 -224.307432) (xy 347.31239 -224.354113) (xy 347.289519 -224.39769) (xy 347.259954 -224.437034)
			(xy 347.224461 -224.471126) (xy 347.183958 -224.499082) (xy 347.139496 -224.52018) (xy 347.092225 -224.533872)
			(xy 347.04337 -224.539804) (xy 346.994195 -224.537823) (xy 346.945976 -224.527979) (xy 346.89996 -224.510527)
			(xy 346.857339 -224.48592) (xy 346.819218 -224.454795) (xy 346.786583 -224.417958) (xy 346.76028 -224.376362)
			(xy 346.740989 -224.331086) (xy 346.729212 -224.283302) (xy 346.725252 -224.234248) (xy 346.39631 -224.234248)
			(xy 346.395815 -224.258855) (xy 346.38792 -224.307432) (xy 346.372336 -224.354113) (xy 346.349465 -224.39769)
			(xy 346.3199 -224.437034) (xy 346.284407 -224.471126) (xy 346.243904 -224.499082) (xy 346.199442 -224.52018)
			(xy 346.152171 -224.533872) (xy 346.103316 -224.539804) (xy 346.054141 -224.537823) (xy 346.005922 -224.527979)
			(xy 345.959906 -224.510527) (xy 345.917285 -224.48592) (xy 345.879164 -224.454795) (xy 345.846529 -224.417958)
			(xy 345.820226 -224.376362) (xy 345.800935 -224.331086) (xy 345.789158 -224.283302) (xy 345.785198 -224.234248)
			(xy 345.45651 -224.234248) (xy 345.456015 -224.258855) (xy 345.44812 -224.307432) (xy 345.432536 -224.354113)
			(xy 345.409665 -224.39769) (xy 345.3801 -224.437034) (xy 345.344607 -224.471126) (xy 345.304104 -224.499082)
			(xy 345.259642 -224.52018) (xy 345.212371 -224.533872) (xy 345.163516 -224.539804) (xy 345.114341 -224.537823)
			(xy 345.066122 -224.527979) (xy 345.020106 -224.510527) (xy 344.977485 -224.48592) (xy 344.939364 -224.454795)
			(xy 344.906729 -224.417958) (xy 344.880426 -224.376362) (xy 344.861135 -224.331086) (xy 344.849358 -224.283302)
			(xy 344.845398 -224.234248) (xy 344.516456 -224.234248) (xy 344.515961 -224.258855) (xy 344.508066 -224.307432)
			(xy 344.492482 -224.354113) (xy 344.469611 -224.39769) (xy 344.440046 -224.437034) (xy 344.404553 -224.471126)
			(xy 344.36405 -224.499082) (xy 344.319588 -224.52018) (xy 344.272317 -224.533872) (xy 344.223462 -224.539804)
			(xy 344.174287 -224.537823) (xy 344.126068 -224.527979) (xy 344.080052 -224.510527) (xy 344.037431 -224.48592)
			(xy 343.99931 -224.454795) (xy 343.966675 -224.417958) (xy 343.940372 -224.376362) (xy 343.921081 -224.331086)
			(xy 343.909304 -224.283302) (xy 343.905344 -224.234248) (xy 341.696294 -224.234248) (xy 341.695917 -224.255883)
			(xy 341.689795 -224.298716) (xy 341.684102 -224.319592) (xy 341.6808 -224.331276) (xy 341.684864 -224.354644)
			(xy 341.740998 -224.42932) (xy 341.748607 -224.438413) (xy 341.769797 -224.448984) (xy 341.781638 -224.44964)
			(xy 343.110058 -224.44964) (xy 343.120123 -224.450075) (xy 343.138708 -224.457809) (xy 343.146126 -224.464626)
			(xy 343.4969 -224.8154) (xy 343.535508 -224.817686) (xy 343.550748 -224.805494) (xy 343.57117 -224.789898)
			(xy 343.616148 -224.765054) (xy 343.664648 -224.748085) (xy 343.715303 -224.73947) (xy 343.740994 -224.738946)
			(xy 343.764987 -224.739416) (xy 343.812382 -224.746921) (xy 343.85802 -224.761747) (xy 343.900777 -224.78353)
			(xy 343.9396 -224.811732) (xy 343.973534 -224.845661) (xy 344.001743 -224.884479) (xy 344.023533 -224.927232)
			(xy 344.038367 -224.972867) (xy 344.04588 -225.020261) (xy 344.046302 -225.044254) (xy 345.315298 -225.044254)
			(xy 345.319258 -224.9952) (xy 345.331035 -224.947416) (xy 345.350326 -224.90214) (xy 345.376629 -224.860544)
			(xy 345.409264 -224.823707) (xy 345.447385 -224.792582) (xy 345.490006 -224.767975) (xy 345.536022 -224.750523)
			(xy 345.584241 -224.740679) (xy 345.633416 -224.738698) (xy 345.682271 -224.74463) (xy 345.729542 -224.758322)
			(xy 345.774004 -224.77942) (xy 345.814507 -224.807376) (xy 345.85 -224.841468) (xy 345.879565 -224.880812)
			(xy 345.902436 -224.924389) (xy 345.91802 -224.97107) (xy 345.925915 -225.019647) (xy 345.92641 -225.044254)
			(xy 346.255352 -225.044254) (xy 346.259312 -224.9952) (xy 346.271089 -224.947416) (xy 346.29038 -224.90214)
			(xy 346.316683 -224.860544) (xy 346.349318 -224.823707) (xy 346.387439 -224.792582) (xy 346.43006 -224.767975)
			(xy 346.476076 -224.750523) (xy 346.524295 -224.740679) (xy 346.57347 -224.738698) (xy 346.622325 -224.74463)
			(xy 346.669596 -224.758322) (xy 346.714058 -224.77942) (xy 346.754561 -224.807376) (xy 346.790054 -224.841468)
			(xy 346.819619 -224.880812) (xy 346.84249 -224.924389) (xy 346.858074 -224.97107) (xy 346.865969 -225.019647)
			(xy 346.866464 -225.044254) (xy 348.135206 -225.044254) (xy 348.139166 -224.9952) (xy 348.150943 -224.947416)
			(xy 348.170234 -224.90214) (xy 348.196537 -224.860544) (xy 348.229172 -224.823707) (xy 348.267293 -224.792582)
			(xy 348.309914 -224.767975) (xy 348.35593 -224.750523) (xy 348.404149 -224.740679) (xy 348.453324 -224.738698)
			(xy 348.502179 -224.74463) (xy 348.54945 -224.758322) (xy 348.593912 -224.77942) (xy 348.634415 -224.807376)
			(xy 348.669908 -224.841468) (xy 348.699473 -224.880812) (xy 348.722344 -224.924389) (xy 348.737928 -224.97107)
			(xy 348.745823 -225.019647) (xy 348.746318 -225.044254) (xy 349.07526 -225.044254) (xy 349.07922 -224.9952)
			(xy 349.090997 -224.947416) (xy 349.110288 -224.90214) (xy 349.136591 -224.860544) (xy 349.169226 -224.823707)
			(xy 349.207347 -224.792582) (xy 349.249968 -224.767975) (xy 349.295984 -224.750523) (xy 349.344203 -224.740679)
			(xy 349.393378 -224.738698) (xy 349.442233 -224.74463) (xy 349.489504 -224.758322) (xy 349.533966 -224.77942)
			(xy 349.574469 -224.807376) (xy 349.609962 -224.841468) (xy 349.639527 -224.880812) (xy 349.662398 -224.924389)
			(xy 349.677982 -224.97107) (xy 349.685877 -225.019647) (xy 349.686372 -225.044254) (xy 353.77553 -225.044254)
			(xy 353.77949 -224.9952) (xy 353.791267 -224.947416) (xy 353.810558 -224.90214) (xy 353.836861 -224.860544)
			(xy 353.869496 -224.823707) (xy 353.907617 -224.792582) (xy 353.950238 -224.767975) (xy 353.996254 -224.750523)
			(xy 354.044473 -224.740679) (xy 354.093648 -224.738698) (xy 354.142503 -224.74463) (xy 354.189774 -224.758322)
			(xy 354.234236 -224.77942) (xy 354.274739 -224.807376) (xy 354.310232 -224.841468) (xy 354.339797 -224.880812)
			(xy 354.362668 -224.924389) (xy 354.378252 -224.97107) (xy 354.386147 -225.019647) (xy 354.386642 -225.044254)
			(xy 354.715584 -225.044254) (xy 354.719544 -224.9952) (xy 354.731321 -224.947416) (xy 354.750612 -224.90214)
			(xy 354.776915 -224.860544) (xy 354.80955 -224.823707) (xy 354.847671 -224.792582) (xy 354.890292 -224.767975)
			(xy 354.936308 -224.750523) (xy 354.984527 -224.740679) (xy 355.033702 -224.738698) (xy 355.082557 -224.74463)
			(xy 355.129828 -224.758322) (xy 355.17429 -224.77942) (xy 355.214793 -224.807376) (xy 355.250286 -224.841468)
			(xy 355.279851 -224.880812) (xy 355.302722 -224.924389) (xy 355.318306 -224.97107) (xy 355.326201 -225.019647)
			(xy 355.326696 -225.044254) (xy 356.595438 -225.044254) (xy 356.599398 -224.9952) (xy 356.611175 -224.947416)
			(xy 356.630466 -224.90214) (xy 356.656769 -224.860544) (xy 356.689404 -224.823707) (xy 356.727525 -224.792582)
			(xy 356.770146 -224.767975) (xy 356.816162 -224.750523) (xy 356.864381 -224.740679) (xy 356.913556 -224.738698)
			(xy 356.962411 -224.74463) (xy 357.009682 -224.758322) (xy 357.054144 -224.77942) (xy 357.094647 -224.807376)
			(xy 357.13014 -224.841468) (xy 357.159705 -224.880812) (xy 357.182576 -224.924389) (xy 357.19816 -224.97107)
			(xy 357.206055 -225.019647) (xy 357.20655 -225.044254) (xy 357.535492 -225.044254) (xy 357.539452 -224.9952)
			(xy 357.551229 -224.947416) (xy 357.57052 -224.90214) (xy 357.596823 -224.860544) (xy 357.629458 -224.823707)
			(xy 357.667579 -224.792582) (xy 357.7102 -224.767975) (xy 357.756216 -224.750523) (xy 357.804435 -224.740679)
			(xy 357.85361 -224.738698) (xy 357.902465 -224.74463) (xy 357.949736 -224.758322) (xy 357.994198 -224.77942)
			(xy 358.034701 -224.807376) (xy 358.070194 -224.841468) (xy 358.099759 -224.880812) (xy 358.12263 -224.924389)
			(xy 358.138214 -224.97107) (xy 358.146109 -225.019647) (xy 358.146604 -225.044254) (xy 358.146109 -225.068861)
			(xy 358.138214 -225.117438) (xy 358.12263 -225.164119) (xy 358.099759 -225.207696) (xy 358.070194 -225.24704)
			(xy 358.034701 -225.281132) (xy 357.994198 -225.309088) (xy 357.949736 -225.330186) (xy 357.902465 -225.343878)
			(xy 357.85361 -225.34981) (xy 357.804435 -225.347829) (xy 357.756216 -225.337985) (xy 357.7102 -225.320533)
			(xy 357.667579 -225.295926) (xy 357.629458 -225.264801) (xy 357.596823 -225.227964) (xy 357.57052 -225.186368)
			(xy 357.551229 -225.141092) (xy 357.539452 -225.093308) (xy 357.535492 -225.044254) (xy 357.20655 -225.044254)
			(xy 357.206055 -225.068861) (xy 357.19816 -225.117438) (xy 357.182576 -225.164119) (xy 357.159705 -225.207696)
			(xy 357.13014 -225.24704) (xy 357.094647 -225.281132) (xy 357.054144 -225.309088) (xy 357.009682 -225.330186)
			(xy 356.962411 -225.343878) (xy 356.913556 -225.34981) (xy 356.864381 -225.347829) (xy 356.816162 -225.337985)
			(xy 356.770146 -225.320533) (xy 356.727525 -225.295926) (xy 356.689404 -225.264801) (xy 356.656769 -225.227964)
			(xy 356.630466 -225.186368) (xy 356.611175 -225.141092) (xy 356.599398 -225.093308) (xy 356.595438 -225.044254)
			(xy 355.326696 -225.044254) (xy 355.326201 -225.068861) (xy 355.318306 -225.117438) (xy 355.302722 -225.164119)
			(xy 355.279851 -225.207696) (xy 355.250286 -225.24704) (xy 355.214793 -225.281132) (xy 355.17429 -225.309088)
			(xy 355.129828 -225.330186) (xy 355.082557 -225.343878) (xy 355.033702 -225.34981) (xy 354.984527 -225.347829)
			(xy 354.936308 -225.337985) (xy 354.890292 -225.320533) (xy 354.847671 -225.295926) (xy 354.80955 -225.264801)
			(xy 354.776915 -225.227964) (xy 354.750612 -225.186368) (xy 354.731321 -225.141092) (xy 354.719544 -225.093308)
			(xy 354.715584 -225.044254) (xy 354.386642 -225.044254) (xy 354.386147 -225.068861) (xy 354.378252 -225.117438)
			(xy 354.362668 -225.164119) (xy 354.339797 -225.207696) (xy 354.310232 -225.24704) (xy 354.274739 -225.281132)
			(xy 354.234236 -225.309088) (xy 354.189774 -225.330186) (xy 354.142503 -225.343878) (xy 354.093648 -225.34981)
			(xy 354.044473 -225.347829) (xy 353.996254 -225.337985) (xy 353.950238 -225.320533) (xy 353.907617 -225.295926)
			(xy 353.869496 -225.264801) (xy 353.836861 -225.227964) (xy 353.810558 -225.186368) (xy 353.791267 -225.141092)
			(xy 353.77949 -225.093308) (xy 353.77553 -225.044254) (xy 349.686372 -225.044254) (xy 349.685877 -225.068861)
			(xy 349.677982 -225.117438) (xy 349.662398 -225.164119) (xy 349.639527 -225.207696) (xy 349.609962 -225.24704)
			(xy 349.574469 -225.281132) (xy 349.533966 -225.309088) (xy 349.489504 -225.330186) (xy 349.442233 -225.343878)
			(xy 349.393378 -225.34981) (xy 349.344203 -225.347829) (xy 349.295984 -225.337985) (xy 349.249968 -225.320533)
			(xy 349.207347 -225.295926) (xy 349.169226 -225.264801) (xy 349.136591 -225.227964) (xy 349.110288 -225.186368)
			(xy 349.090997 -225.141092) (xy 349.07922 -225.093308) (xy 349.07526 -225.044254) (xy 348.746318 -225.044254)
			(xy 348.745823 -225.068861) (xy 348.737928 -225.117438) (xy 348.722344 -225.164119) (xy 348.699473 -225.207696)
			(xy 348.669908 -225.24704) (xy 348.634415 -225.281132) (xy 348.593912 -225.309088) (xy 348.54945 -225.330186)
			(xy 348.502179 -225.343878) (xy 348.453324 -225.34981) (xy 348.404149 -225.347829) (xy 348.35593 -225.337985)
			(xy 348.309914 -225.320533) (xy 348.267293 -225.295926) (xy 348.229172 -225.264801) (xy 348.196537 -225.227964)
			(xy 348.170234 -225.186368) (xy 348.150943 -225.141092) (xy 348.139166 -225.093308) (xy 348.135206 -225.044254)
			(xy 346.866464 -225.044254) (xy 346.865969 -225.068861) (xy 346.858074 -225.117438) (xy 346.84249 -225.164119)
			(xy 346.819619 -225.207696) (xy 346.790054 -225.24704) (xy 346.754561 -225.281132) (xy 346.714058 -225.309088)
			(xy 346.669596 -225.330186) (xy 346.622325 -225.343878) (xy 346.57347 -225.34981) (xy 346.524295 -225.347829)
			(xy 346.476076 -225.337985) (xy 346.43006 -225.320533) (xy 346.387439 -225.295926) (xy 346.349318 -225.264801)
			(xy 346.316683 -225.227964) (xy 346.29038 -225.186368) (xy 346.271089 -225.141092) (xy 346.259312 -225.093308)
			(xy 346.255352 -225.044254) (xy 345.92641 -225.044254) (xy 345.925915 -225.068861) (xy 345.91802 -225.117438)
			(xy 345.902436 -225.164119) (xy 345.879565 -225.207696) (xy 345.85 -225.24704) (xy 345.814507 -225.281132)
			(xy 345.774004 -225.309088) (xy 345.729542 -225.330186) (xy 345.682271 -225.343878) (xy 345.633416 -225.34981)
			(xy 345.584241 -225.347829) (xy 345.536022 -225.337985) (xy 345.490006 -225.320533) (xy 345.447385 -225.295926)
			(xy 345.409264 -225.264801) (xy 345.376629 -225.227964) (xy 345.350326 -225.186368) (xy 345.331035 -225.141092)
			(xy 345.319258 -225.093308) (xy 345.315298 -225.044254) (xy 344.046302 -225.044254) (xy 344.045708 -225.071399)
			(xy 344.036105 -225.124834) (xy 344.01721 -225.175731) (xy 343.989619 -225.222488) (xy 343.9542 -225.263633)
			(xy 343.933526 -225.281236) (xy 343.925132 -225.288855) (xy 343.915383 -225.309288) (xy 343.91473 -225.320606)
			(xy 343.91473 -225.84029) (xy 343.915152 -225.85036) (xy 343.916769 -225.85426) (xy 344.845398 -225.85426)
			(xy 344.849358 -225.805206) (xy 344.861135 -225.757422) (xy 344.880426 -225.712146) (xy 344.906729 -225.67055)
			(xy 344.939364 -225.633713) (xy 344.977485 -225.602588) (xy 345.020106 -225.577981) (xy 345.066122 -225.560529)
			(xy 345.114341 -225.550685) (xy 345.163516 -225.548704) (xy 345.212371 -225.554636) (xy 345.259642 -225.568328)
			(xy 345.304104 -225.589426) (xy 345.344607 -225.617382) (xy 345.3801 -225.651474) (xy 345.409665 -225.690818)
			(xy 345.432536 -225.734395) (xy 345.44812 -225.781076) (xy 345.456015 -225.829653) (xy 345.45651 -225.85426)
			(xy 345.785198 -225.85426) (xy 345.789158 -225.805206) (xy 345.800935 -225.757422) (xy 345.820226 -225.712146)
			(xy 345.846529 -225.67055) (xy 345.879164 -225.633713) (xy 345.917285 -225.602588) (xy 345.959906 -225.577981)
			(xy 346.005922 -225.560529) (xy 346.054141 -225.550685) (xy 346.103316 -225.548704) (xy 346.152171 -225.554636)
			(xy 346.199442 -225.568328) (xy 346.243904 -225.589426) (xy 346.284407 -225.617382) (xy 346.3199 -225.651474)
			(xy 346.349465 -225.690818) (xy 346.372336 -225.734395) (xy 346.38792 -225.781076) (xy 346.395815 -225.829653)
			(xy 346.39631 -225.85426) (xy 347.665306 -225.85426) (xy 347.669266 -225.805206) (xy 347.681043 -225.757422)
			(xy 347.700334 -225.712146) (xy 347.726637 -225.67055) (xy 347.759272 -225.633713) (xy 347.797393 -225.602588)
			(xy 347.840014 -225.577981) (xy 347.88603 -225.560529) (xy 347.934249 -225.550685) (xy 347.983424 -225.548704)
			(xy 348.032279 -225.554636) (xy 348.07955 -225.568328) (xy 348.124012 -225.589426) (xy 348.164515 -225.617382)
			(xy 348.200008 -225.651474) (xy 348.229573 -225.690818) (xy 348.252444 -225.734395) (xy 348.268028 -225.781076)
			(xy 348.275923 -225.829653) (xy 348.276418 -225.85426) (xy 348.60536 -225.85426) (xy 348.60932 -225.805206)
			(xy 348.621097 -225.757422) (xy 348.640388 -225.712146) (xy 348.666691 -225.67055) (xy 348.699326 -225.633713)
			(xy 348.737447 -225.602588) (xy 348.780068 -225.577981) (xy 348.826084 -225.560529) (xy 348.874303 -225.550685)
			(xy 348.923478 -225.548704) (xy 348.972333 -225.554636) (xy 349.019604 -225.568328) (xy 349.064066 -225.589426)
			(xy 349.104569 -225.617382) (xy 349.140062 -225.651474) (xy 349.169627 -225.690818) (xy 349.192498 -225.734395)
			(xy 349.208082 -225.781076) (xy 349.215977 -225.829653) (xy 349.216472 -225.85426) (xy 350.485214 -225.85426)
			(xy 350.489174 -225.805206) (xy 350.500951 -225.757422) (xy 350.520242 -225.712146) (xy 350.546545 -225.67055)
			(xy 350.57918 -225.633713) (xy 350.617301 -225.602588) (xy 350.659922 -225.577981) (xy 350.705938 -225.560529)
			(xy 350.754157 -225.550685) (xy 350.803332 -225.548704) (xy 350.852187 -225.554636) (xy 350.899458 -225.568328)
			(xy 350.94392 -225.589426) (xy 350.984423 -225.617382) (xy 351.019916 -225.651474) (xy 351.049481 -225.690818)
			(xy 351.072352 -225.734395) (xy 351.087936 -225.781076) (xy 351.095831 -225.829653) (xy 351.096326 -225.85426)
			(xy 351.425268 -225.85426) (xy 351.429228 -225.805206) (xy 351.441005 -225.757422) (xy 351.460296 -225.712146)
			(xy 351.486599 -225.67055) (xy 351.519234 -225.633713) (xy 351.557355 -225.602588) (xy 351.599976 -225.577981)
			(xy 351.645992 -225.560529) (xy 351.694211 -225.550685) (xy 351.743386 -225.548704) (xy 351.792241 -225.554636)
			(xy 351.839512 -225.568328) (xy 351.883974 -225.589426) (xy 351.924477 -225.617382) (xy 351.95997 -225.651474)
			(xy 351.989535 -225.690818) (xy 352.012406 -225.734395) (xy 352.02799 -225.781076) (xy 352.035885 -225.829653)
			(xy 352.03638 -225.85426) (xy 353.305376 -225.85426) (xy 353.309336 -225.805206) (xy 353.321113 -225.757422)
			(xy 353.340404 -225.712146) (xy 353.366707 -225.67055) (xy 353.399342 -225.633713) (xy 353.437463 -225.602588)
			(xy 353.480084 -225.577981) (xy 353.5261 -225.560529) (xy 353.574319 -225.550685) (xy 353.623494 -225.548704)
			(xy 353.672349 -225.554636) (xy 353.71962 -225.568328) (xy 353.764082 -225.589426) (xy 353.804585 -225.617382)
			(xy 353.840078 -225.651474) (xy 353.869643 -225.690818) (xy 353.892514 -225.734395) (xy 353.908098 -225.781076)
			(xy 353.915993 -225.829653) (xy 353.916488 -225.85426) (xy 354.24543 -225.85426) (xy 354.24939 -225.805206)
			(xy 354.261167 -225.757422) (xy 354.280458 -225.712146) (xy 354.306761 -225.67055) (xy 354.339396 -225.633713)
			(xy 354.377517 -225.602588) (xy 354.420138 -225.577981) (xy 354.466154 -225.560529) (xy 354.514373 -225.550685)
			(xy 354.563548 -225.548704) (xy 354.612403 -225.554636) (xy 354.659674 -225.568328) (xy 354.704136 -225.589426)
			(xy 354.744639 -225.617382) (xy 354.780132 -225.651474) (xy 354.809697 -225.690818) (xy 354.832568 -225.734395)
			(xy 354.848152 -225.781076) (xy 354.856047 -225.829653) (xy 354.856542 -225.85426) (xy 356.125284 -225.85426)
			(xy 356.129244 -225.805206) (xy 356.141021 -225.757422) (xy 356.160312 -225.712146) (xy 356.186615 -225.67055)
			(xy 356.21925 -225.633713) (xy 356.257371 -225.602588) (xy 356.299992 -225.577981) (xy 356.346008 -225.560529)
			(xy 356.394227 -225.550685) (xy 356.443402 -225.548704) (xy 356.492257 -225.554636) (xy 356.539528 -225.568328)
			(xy 356.58399 -225.589426) (xy 356.624493 -225.617382) (xy 356.659986 -225.651474) (xy 356.689551 -225.690818)
			(xy 356.712422 -225.734395) (xy 356.728006 -225.781076) (xy 356.735901 -225.829653) (xy 356.736396 -225.85426)
			(xy 357.065338 -225.85426) (xy 357.069298 -225.805206) (xy 357.081075 -225.757422) (xy 357.100366 -225.712146)
			(xy 357.126669 -225.67055) (xy 357.159304 -225.633713) (xy 357.197425 -225.602588) (xy 357.240046 -225.577981)
			(xy 357.286062 -225.560529) (xy 357.334281 -225.550685) (xy 357.383456 -225.548704) (xy 357.432311 -225.554636)
			(xy 357.479582 -225.568328) (xy 357.524044 -225.589426) (xy 357.564547 -225.617382) (xy 357.60004 -225.651474)
			(xy 357.629605 -225.690818) (xy 357.652476 -225.734395) (xy 357.66806 -225.781076) (xy 357.675955 -225.829653)
			(xy 357.67645 -225.85426) (xy 358.005392 -225.85426) (xy 358.009352 -225.805206) (xy 358.021129 -225.757422)
			(xy 358.04042 -225.712146) (xy 358.066723 -225.67055) (xy 358.099358 -225.633713) (xy 358.137479 -225.602588)
			(xy 358.1801 -225.577981) (xy 358.226116 -225.560529) (xy 358.274335 -225.550685) (xy 358.32351 -225.548704)
			(xy 358.372365 -225.554636) (xy 358.419636 -225.568328) (xy 358.464098 -225.589426) (xy 358.504601 -225.617382)
			(xy 358.540094 -225.651474) (xy 358.569659 -225.690818) (xy 358.59253 -225.734395) (xy 358.608114 -225.781076)
			(xy 358.616009 -225.829653) (xy 358.616504 -225.85426) (xy 358.616009 -225.878867) (xy 358.608114 -225.927444)
			(xy 358.59253 -225.974125) (xy 358.569659 -226.017702) (xy 358.540094 -226.057046) (xy 358.504601 -226.091138)
			(xy 358.464098 -226.119094) (xy 358.419636 -226.140192) (xy 358.372365 -226.153884) (xy 358.32351 -226.159816)
			(xy 358.274335 -226.157835) (xy 358.226116 -226.147991) (xy 358.1801 -226.130539) (xy 358.137479 -226.105932)
			(xy 358.099358 -226.074807) (xy 358.066723 -226.03797) (xy 358.04042 -225.996374) (xy 358.021129 -225.951098)
			(xy 358.009352 -225.903314) (xy 358.005392 -225.85426) (xy 357.67645 -225.85426) (xy 357.675955 -225.878867)
			(xy 357.66806 -225.927444) (xy 357.652476 -225.974125) (xy 357.629605 -226.017702) (xy 357.60004 -226.057046)
			(xy 357.564547 -226.091138) (xy 357.524044 -226.119094) (xy 357.479582 -226.140192) (xy 357.432311 -226.153884)
			(xy 357.383456 -226.159816) (xy 357.334281 -226.157835) (xy 357.286062 -226.147991) (xy 357.240046 -226.130539)
			(xy 357.197425 -226.105932) (xy 357.159304 -226.074807) (xy 357.126669 -226.03797) (xy 357.100366 -225.996374)
			(xy 357.081075 -225.951098) (xy 357.069298 -225.903314) (xy 357.065338 -225.85426) (xy 356.736396 -225.85426)
			(xy 356.735901 -225.878867) (xy 356.728006 -225.927444) (xy 356.712422 -225.974125) (xy 356.689551 -226.017702)
			(xy 356.659986 -226.057046) (xy 356.624493 -226.091138) (xy 356.58399 -226.119094) (xy 356.539528 -226.140192)
			(xy 356.492257 -226.153884) (xy 356.443402 -226.159816) (xy 356.394227 -226.157835) (xy 356.346008 -226.147991)
			(xy 356.299992 -226.130539) (xy 356.257371 -226.105932) (xy 356.21925 -226.074807) (xy 356.186615 -226.03797)
			(xy 356.160312 -225.996374) (xy 356.141021 -225.951098) (xy 356.129244 -225.903314) (xy 356.125284 -225.85426)
			(xy 354.856542 -225.85426) (xy 354.856047 -225.878867) (xy 354.848152 -225.927444) (xy 354.832568 -225.974125)
			(xy 354.809697 -226.017702) (xy 354.780132 -226.057046) (xy 354.744639 -226.091138) (xy 354.704136 -226.119094)
			(xy 354.659674 -226.140192) (xy 354.612403 -226.153884) (xy 354.563548 -226.159816) (xy 354.514373 -226.157835)
			(xy 354.466154 -226.147991) (xy 354.420138 -226.130539) (xy 354.377517 -226.105932) (xy 354.339396 -226.074807)
			(xy 354.306761 -226.03797) (xy 354.280458 -225.996374) (xy 354.261167 -225.951098) (xy 354.24939 -225.903314)
			(xy 354.24543 -225.85426) (xy 353.916488 -225.85426) (xy 353.915993 -225.878867) (xy 353.908098 -225.927444)
			(xy 353.892514 -225.974125) (xy 353.869643 -226.017702) (xy 353.840078 -226.057046) (xy 353.804585 -226.091138)
			(xy 353.764082 -226.119094) (xy 353.71962 -226.140192) (xy 353.672349 -226.153884) (xy 353.623494 -226.159816)
			(xy 353.574319 -226.157835) (xy 353.5261 -226.147991) (xy 353.480084 -226.130539) (xy 353.437463 -226.105932)
			(xy 353.399342 -226.074807) (xy 353.366707 -226.03797) (xy 353.340404 -225.996374) (xy 353.321113 -225.951098)
			(xy 353.309336 -225.903314) (xy 353.305376 -225.85426) (xy 352.03638 -225.85426) (xy 352.035885 -225.878867)
			(xy 352.02799 -225.927444) (xy 352.012406 -225.974125) (xy 351.989535 -226.017702) (xy 351.95997 -226.057046)
			(xy 351.924477 -226.091138) (xy 351.883974 -226.119094) (xy 351.839512 -226.140192) (xy 351.792241 -226.153884)
			(xy 351.743386 -226.159816) (xy 351.694211 -226.157835) (xy 351.645992 -226.147991) (xy 351.599976 -226.130539)
			(xy 351.557355 -226.105932) (xy 351.519234 -226.074807) (xy 351.486599 -226.03797) (xy 351.460296 -225.996374)
			(xy 351.441005 -225.951098) (xy 351.429228 -225.903314) (xy 351.425268 -225.85426) (xy 351.096326 -225.85426)
			(xy 351.095831 -225.878867) (xy 351.087936 -225.927444) (xy 351.072352 -225.974125) (xy 351.049481 -226.017702)
			(xy 351.019916 -226.057046) (xy 350.984423 -226.091138) (xy 350.94392 -226.119094) (xy 350.899458 -226.140192)
			(xy 350.852187 -226.153884) (xy 350.803332 -226.159816) (xy 350.754157 -226.157835) (xy 350.705938 -226.147991)
			(xy 350.659922 -226.130539) (xy 350.617301 -226.105932) (xy 350.57918 -226.074807) (xy 350.546545 -226.03797)
			(xy 350.520242 -225.996374) (xy 350.500951 -225.951098) (xy 350.489174 -225.903314) (xy 350.485214 -225.85426)
			(xy 349.216472 -225.85426) (xy 349.215977 -225.878867) (xy 349.208082 -225.927444) (xy 349.192498 -225.974125)
			(xy 349.169627 -226.017702) (xy 349.140062 -226.057046) (xy 349.104569 -226.091138) (xy 349.064066 -226.119094)
			(xy 349.019604 -226.140192) (xy 348.972333 -226.153884) (xy 348.923478 -226.159816) (xy 348.874303 -226.157835)
			(xy 348.826084 -226.147991) (xy 348.780068 -226.130539) (xy 348.737447 -226.105932) (xy 348.699326 -226.074807)
			(xy 348.666691 -226.03797) (xy 348.640388 -225.996374) (xy 348.621097 -225.951098) (xy 348.60932 -225.903314)
			(xy 348.60536 -225.85426) (xy 348.276418 -225.85426) (xy 348.275923 -225.878867) (xy 348.268028 -225.927444)
			(xy 348.252444 -225.974125) (xy 348.229573 -226.017702) (xy 348.200008 -226.057046) (xy 348.164515 -226.091138)
			(xy 348.124012 -226.119094) (xy 348.07955 -226.140192) (xy 348.032279 -226.153884) (xy 347.983424 -226.159816)
			(xy 347.934249 -226.157835) (xy 347.88603 -226.147991) (xy 347.840014 -226.130539) (xy 347.797393 -226.105932)
			(xy 347.759272 -226.074807) (xy 347.726637 -226.03797) (xy 347.700334 -225.996374) (xy 347.681043 -225.951098)
			(xy 347.669266 -225.903314) (xy 347.665306 -225.85426) (xy 346.39631 -225.85426) (xy 346.395815 -225.878867)
			(xy 346.38792 -225.927444) (xy 346.372336 -225.974125) (xy 346.349465 -226.017702) (xy 346.3199 -226.057046)
			(xy 346.284407 -226.091138) (xy 346.243904 -226.119094) (xy 346.199442 -226.140192) (xy 346.152171 -226.153884)
			(xy 346.103316 -226.159816) (xy 346.054141 -226.157835) (xy 346.005922 -226.147991) (xy 345.959906 -226.130539)
			(xy 345.917285 -226.105932) (xy 345.879164 -226.074807) (xy 345.846529 -226.03797) (xy 345.820226 -225.996374)
			(xy 345.800935 -225.951098) (xy 345.789158 -225.903314) (xy 345.785198 -225.85426) (xy 345.45651 -225.85426)
			(xy 345.456015 -225.878867) (xy 345.44812 -225.927444) (xy 345.432536 -225.974125) (xy 345.409665 -226.017702)
			(xy 345.3801 -226.057046) (xy 345.344607 -226.091138) (xy 345.304104 -226.119094) (xy 345.259642 -226.140192)
			(xy 345.212371 -226.153884) (xy 345.163516 -226.159816) (xy 345.114341 -226.157835) (xy 345.066122 -226.147991)
			(xy 345.020106 -226.130539) (xy 344.977485 -226.105932) (xy 344.939364 -226.074807) (xy 344.906729 -226.03797)
			(xy 344.880426 -225.996374) (xy 344.861135 -225.951098) (xy 344.849358 -225.903314) (xy 344.845398 -225.85426)
			(xy 343.916769 -225.85426) (xy 343.922867 -225.868965) (xy 343.929716 -225.876358) (xy 344.453464 -226.400106)
			(xy 344.462082 -226.407741) (xy 344.483819 -226.415239) (xy 344.506657 -226.412578) (xy 344.51671 -226.406964)
			(xy 344.535204 -226.395602) (xy 344.574721 -226.377651) (xy 344.616381 -226.365476) (xy 344.659346 -226.359323)
			(xy 344.681048 -226.358958) (xy 344.705038 -226.359432) (xy 344.752426 -226.366944) (xy 344.798055 -226.381775)
			(xy 344.840804 -226.403561) (xy 344.879619 -226.431764) (xy 344.913545 -226.465692) (xy 344.941747 -226.504508)
			(xy 344.96353 -226.547258) (xy 344.978359 -226.592888) (xy 344.985869 -226.640276) (xy 344.986356 -226.664266)
			(xy 345.315298 -226.664266) (xy 345.319258 -226.615212) (xy 345.331035 -226.567428) (xy 345.350326 -226.522152)
			(xy 345.376629 -226.480556) (xy 345.409264 -226.443719) (xy 345.447385 -226.412594) (xy 345.490006 -226.387987)
			(xy 345.536022 -226.370535) (xy 345.584241 -226.360691) (xy 345.633416 -226.35871) (xy 345.682271 -226.364642)
			(xy 345.729542 -226.378334) (xy 345.774004 -226.399432) (xy 345.814507 -226.427388) (xy 345.85 -226.46148)
			(xy 345.879565 -226.500824) (xy 345.902436 -226.544401) (xy 345.91802 -226.591082) (xy 345.925915 -226.639659)
			(xy 345.92641 -226.664266) (xy 346.255352 -226.664266) (xy 346.259312 -226.615212) (xy 346.271089 -226.567428)
			(xy 346.29038 -226.522152) (xy 346.316683 -226.480556) (xy 346.349318 -226.443719) (xy 346.387439 -226.412594)
			(xy 346.43006 -226.387987) (xy 346.476076 -226.370535) (xy 346.524295 -226.360691) (xy 346.57347 -226.35871)
			(xy 346.622325 -226.364642) (xy 346.669596 -226.378334) (xy 346.714058 -226.399432) (xy 346.754561 -226.427388)
			(xy 346.790054 -226.46148) (xy 346.819619 -226.500824) (xy 346.84249 -226.544401) (xy 346.858074 -226.591082)
			(xy 346.865969 -226.639659) (xy 346.866464 -226.664266) (xy 347.195406 -226.664266) (xy 347.199366 -226.615212)
			(xy 347.211143 -226.567428) (xy 347.230434 -226.522152) (xy 347.256737 -226.480556) (xy 347.289372 -226.443719)
			(xy 347.327493 -226.412594) (xy 347.370114 -226.387987) (xy 347.41613 -226.370535) (xy 347.464349 -226.360691)
			(xy 347.513524 -226.35871) (xy 347.562379 -226.364642) (xy 347.60965 -226.378334) (xy 347.654112 -226.399432)
			(xy 347.694615 -226.427388) (xy 347.730108 -226.46148) (xy 347.759673 -226.500824) (xy 347.782544 -226.544401)
			(xy 347.798128 -226.591082) (xy 347.806023 -226.639659) (xy 347.806518 -226.664266) (xy 348.135206 -226.664266)
			(xy 348.139166 -226.615212) (xy 348.150943 -226.567428) (xy 348.170234 -226.522152) (xy 348.196537 -226.480556)
			(xy 348.229172 -226.443719) (xy 348.267293 -226.412594) (xy 348.309914 -226.387987) (xy 348.35593 -226.370535)
			(xy 348.404149 -226.360691) (xy 348.453324 -226.35871) (xy 348.502179 -226.364642) (xy 348.54945 -226.378334)
			(xy 348.593912 -226.399432) (xy 348.634415 -226.427388) (xy 348.669908 -226.46148) (xy 348.699473 -226.500824)
			(xy 348.722344 -226.544401) (xy 348.737928 -226.591082) (xy 348.745823 -226.639659) (xy 348.746318 -226.664266)
			(xy 349.07526 -226.664266) (xy 349.07922 -226.615212) (xy 349.090997 -226.567428) (xy 349.110288 -226.522152)
			(xy 349.136591 -226.480556) (xy 349.169226 -226.443719) (xy 349.207347 -226.412594) (xy 349.249968 -226.387987)
			(xy 349.295984 -226.370535) (xy 349.344203 -226.360691) (xy 349.393378 -226.35871) (xy 349.442233 -226.364642)
			(xy 349.489504 -226.378334) (xy 349.533966 -226.399432) (xy 349.574469 -226.427388) (xy 349.609962 -226.46148)
			(xy 349.639527 -226.500824) (xy 349.662398 -226.544401) (xy 349.677982 -226.591082) (xy 349.685877 -226.639659)
			(xy 349.686372 -226.664266) (xy 350.015314 -226.664266) (xy 350.019274 -226.615212) (xy 350.031051 -226.567428)
			(xy 350.050342 -226.522152) (xy 350.076645 -226.480556) (xy 350.10928 -226.443719) (xy 350.147401 -226.412594)
			(xy 350.190022 -226.387987) (xy 350.236038 -226.370535) (xy 350.284257 -226.360691) (xy 350.333432 -226.35871)
			(xy 350.382287 -226.364642) (xy 350.429558 -226.378334) (xy 350.47402 -226.399432) (xy 350.514523 -226.427388)
			(xy 350.550016 -226.46148) (xy 350.579581 -226.500824) (xy 350.602452 -226.544401) (xy 350.618036 -226.591082)
			(xy 350.625931 -226.639659) (xy 350.626426 -226.664266) (xy 350.955368 -226.664266) (xy 350.959328 -226.615212)
			(xy 350.971105 -226.567428) (xy 350.990396 -226.522152) (xy 351.016699 -226.480556) (xy 351.049334 -226.443719)
			(xy 351.087455 -226.412594) (xy 351.130076 -226.387987) (xy 351.176092 -226.370535) (xy 351.224311 -226.360691)
			(xy 351.273486 -226.35871) (xy 351.322341 -226.364642) (xy 351.369612 -226.378334) (xy 351.414074 -226.399432)
			(xy 351.454577 -226.427388) (xy 351.49007 -226.46148) (xy 351.519635 -226.500824) (xy 351.542506 -226.544401)
			(xy 351.55809 -226.591082) (xy 351.565985 -226.639659) (xy 351.56648 -226.664266) (xy 351.895422 -226.664266)
			(xy 351.899382 -226.615212) (xy 351.911159 -226.567428) (xy 351.93045 -226.522152) (xy 351.956753 -226.480556)
			(xy 351.989388 -226.443719) (xy 352.027509 -226.412594) (xy 352.07013 -226.387987) (xy 352.116146 -226.370535)
			(xy 352.164365 -226.360691) (xy 352.21354 -226.35871) (xy 352.262395 -226.364642) (xy 352.309666 -226.378334)
			(xy 352.354128 -226.399432) (xy 352.394631 -226.427388) (xy 352.430124 -226.46148) (xy 352.459689 -226.500824)
			(xy 352.48256 -226.544401) (xy 352.498144 -226.591082) (xy 352.506039 -226.639659) (xy 352.506534 -226.664266)
			(xy 352.835222 -226.664266) (xy 352.839182 -226.615212) (xy 352.850959 -226.567428) (xy 352.87025 -226.522152)
			(xy 352.896553 -226.480556) (xy 352.929188 -226.443719) (xy 352.967309 -226.412594) (xy 353.00993 -226.387987)
			(xy 353.055946 -226.370535) (xy 353.104165 -226.360691) (xy 353.15334 -226.35871) (xy 353.202195 -226.364642)
			(xy 353.249466 -226.378334) (xy 353.293928 -226.399432) (xy 353.334431 -226.427388) (xy 353.369924 -226.46148)
			(xy 353.399489 -226.500824) (xy 353.42236 -226.544401) (xy 353.437944 -226.591082) (xy 353.445839 -226.639659)
			(xy 353.446334 -226.664266) (xy 353.775276 -226.664266) (xy 353.779236 -226.615212) (xy 353.791013 -226.567428)
			(xy 353.810304 -226.522152) (xy 353.836607 -226.480556) (xy 353.869242 -226.443719) (xy 353.907363 -226.412594)
			(xy 353.949984 -226.387987) (xy 353.996 -226.370535) (xy 354.044219 -226.360691) (xy 354.093394 -226.35871)
			(xy 354.142249 -226.364642) (xy 354.18952 -226.378334) (xy 354.233982 -226.399432) (xy 354.274485 -226.427388)
			(xy 354.309978 -226.46148) (xy 354.339543 -226.500824) (xy 354.362414 -226.544401) (xy 354.377998 -226.591082)
			(xy 354.385893 -226.639659) (xy 354.386388 -226.664266) (xy 354.71533 -226.664266) (xy 354.71929 -226.615212)
			(xy 354.731067 -226.567428) (xy 354.750358 -226.522152) (xy 354.776661 -226.480556) (xy 354.809296 -226.443719)
			(xy 354.847417 -226.412594) (xy 354.890038 -226.387987) (xy 354.936054 -226.370535) (xy 354.984273 -226.360691)
			(xy 355.033448 -226.35871) (xy 355.082303 -226.364642) (xy 355.129574 -226.378334) (xy 355.174036 -226.399432)
			(xy 355.214539 -226.427388) (xy 355.250032 -226.46148) (xy 355.279597 -226.500824) (xy 355.302468 -226.544401)
			(xy 355.318052 -226.591082) (xy 355.325947 -226.639659) (xy 355.326442 -226.664266) (xy 355.655384 -226.664266)
			(xy 355.659344 -226.615212) (xy 355.671121 -226.567428) (xy 355.690412 -226.522152) (xy 355.716715 -226.480556)
			(xy 355.74935 -226.443719) (xy 355.787471 -226.412594) (xy 355.830092 -226.387987) (xy 355.876108 -226.370535)
			(xy 355.924327 -226.360691) (xy 355.973502 -226.35871) (xy 356.022357 -226.364642) (xy 356.069628 -226.378334)
			(xy 356.11409 -226.399432) (xy 356.154593 -226.427388) (xy 356.190086 -226.46148) (xy 356.219651 -226.500824)
			(xy 356.242522 -226.544401) (xy 356.258106 -226.591082) (xy 356.266001 -226.639659) (xy 356.266496 -226.664266)
			(xy 356.266001 -226.688873) (xy 356.258106 -226.73745) (xy 356.242522 -226.784131) (xy 356.219651 -226.827708)
			(xy 356.190086 -226.867052) (xy 356.154593 -226.901144) (xy 356.11409 -226.9291) (xy 356.069628 -226.950198)
			(xy 356.022357 -226.96389) (xy 355.973502 -226.969822) (xy 355.924327 -226.967841) (xy 355.876108 -226.957997)
			(xy 355.830092 -226.940545) (xy 355.787471 -226.915938) (xy 355.74935 -226.884813) (xy 355.716715 -226.847976)
			(xy 355.690412 -226.80638) (xy 355.671121 -226.761104) (xy 355.659344 -226.71332) (xy 355.655384 -226.664266)
			(xy 355.326442 -226.664266) (xy 355.325947 -226.688873) (xy 355.318052 -226.73745) (xy 355.302468 -226.784131)
			(xy 355.279597 -226.827708) (xy 355.250032 -226.867052) (xy 355.214539 -226.901144) (xy 355.174036 -226.9291)
			(xy 355.129574 -226.950198) (xy 355.082303 -226.96389) (xy 355.033448 -226.969822) (xy 354.984273 -226.967841)
			(xy 354.936054 -226.957997) (xy 354.890038 -226.940545) (xy 354.847417 -226.915938) (xy 354.809296 -226.884813)
			(xy 354.776661 -226.847976) (xy 354.750358 -226.80638) (xy 354.731067 -226.761104) (xy 354.71929 -226.71332)
			(xy 354.71533 -226.664266) (xy 354.386388 -226.664266) (xy 354.385893 -226.688873) (xy 354.377998 -226.73745)
			(xy 354.362414 -226.784131) (xy 354.339543 -226.827708) (xy 354.309978 -226.867052) (xy 354.274485 -226.901144)
			(xy 354.233982 -226.9291) (xy 354.18952 -226.950198) (xy 354.142249 -226.96389) (xy 354.093394 -226.969822)
			(xy 354.044219 -226.967841) (xy 353.996 -226.957997) (xy 353.949984 -226.940545) (xy 353.907363 -226.915938)
			(xy 353.869242 -226.884813) (xy 353.836607 -226.847976) (xy 353.810304 -226.80638) (xy 353.791013 -226.761104)
			(xy 353.779236 -226.71332) (xy 353.775276 -226.664266) (xy 353.446334 -226.664266) (xy 353.445839 -226.688873)
			(xy 353.437944 -226.73745) (xy 353.42236 -226.784131) (xy 353.399489 -226.827708) (xy 353.369924 -226.867052)
			(xy 353.334431 -226.901144) (xy 353.293928 -226.9291) (xy 353.249466 -226.950198) (xy 353.202195 -226.96389)
			(xy 353.15334 -226.969822) (xy 353.104165 -226.967841) (xy 353.055946 -226.957997) (xy 353.00993 -226.940545)
			(xy 352.967309 -226.915938) (xy 352.929188 -226.884813) (xy 352.896553 -226.847976) (xy 352.87025 -226.80638)
			(xy 352.850959 -226.761104) (xy 352.839182 -226.71332) (xy 352.835222 -226.664266) (xy 352.506534 -226.664266)
			(xy 352.506039 -226.688873) (xy 352.498144 -226.73745) (xy 352.48256 -226.784131) (xy 352.459689 -226.827708)
			(xy 352.430124 -226.867052) (xy 352.394631 -226.901144) (xy 352.354128 -226.9291) (xy 352.309666 -226.950198)
			(xy 352.262395 -226.96389) (xy 352.21354 -226.969822) (xy 352.164365 -226.967841) (xy 352.116146 -226.957997)
			(xy 352.07013 -226.940545) (xy 352.027509 -226.915938) (xy 351.989388 -226.884813) (xy 351.956753 -226.847976)
			(xy 351.93045 -226.80638) (xy 351.911159 -226.761104) (xy 351.899382 -226.71332) (xy 351.895422 -226.664266)
			(xy 351.56648 -226.664266) (xy 351.565985 -226.688873) (xy 351.55809 -226.73745) (xy 351.542506 -226.784131)
			(xy 351.519635 -226.827708) (xy 351.49007 -226.867052) (xy 351.454577 -226.901144) (xy 351.414074 -226.9291)
			(xy 351.369612 -226.950198) (xy 351.322341 -226.96389) (xy 351.273486 -226.969822) (xy 351.224311 -226.967841)
			(xy 351.176092 -226.957997) (xy 351.130076 -226.940545) (xy 351.087455 -226.915938) (xy 351.049334 -226.884813)
			(xy 351.016699 -226.847976) (xy 350.990396 -226.80638) (xy 350.971105 -226.761104) (xy 350.959328 -226.71332)
			(xy 350.955368 -226.664266) (xy 350.626426 -226.664266) (xy 350.625931 -226.688873) (xy 350.618036 -226.73745)
			(xy 350.602452 -226.784131) (xy 350.579581 -226.827708) (xy 350.550016 -226.867052) (xy 350.514523 -226.901144)
			(xy 350.47402 -226.9291) (xy 350.429558 -226.950198) (xy 350.382287 -226.96389) (xy 350.333432 -226.969822)
			(xy 350.284257 -226.967841) (xy 350.236038 -226.957997) (xy 350.190022 -226.940545) (xy 350.147401 -226.915938)
			(xy 350.10928 -226.884813) (xy 350.076645 -226.847976) (xy 350.050342 -226.80638) (xy 350.031051 -226.761104)
			(xy 350.019274 -226.71332) (xy 350.015314 -226.664266) (xy 349.686372 -226.664266) (xy 349.685877 -226.688873)
			(xy 349.677982 -226.73745) (xy 349.662398 -226.784131) (xy 349.639527 -226.827708) (xy 349.609962 -226.867052)
			(xy 349.574469 -226.901144) (xy 349.533966 -226.9291) (xy 349.489504 -226.950198) (xy 349.442233 -226.96389)
			(xy 349.393378 -226.969822) (xy 349.344203 -226.967841) (xy 349.295984 -226.957997) (xy 349.249968 -226.940545)
			(xy 349.207347 -226.915938) (xy 349.169226 -226.884813) (xy 349.136591 -226.847976) (xy 349.110288 -226.80638)
			(xy 349.090997 -226.761104) (xy 349.07922 -226.71332) (xy 349.07526 -226.664266) (xy 348.746318 -226.664266)
			(xy 348.745823 -226.688873) (xy 348.737928 -226.73745) (xy 348.722344 -226.784131) (xy 348.699473 -226.827708)
			(xy 348.669908 -226.867052) (xy 348.634415 -226.901144) (xy 348.593912 -226.9291) (xy 348.54945 -226.950198)
			(xy 348.502179 -226.96389) (xy 348.453324 -226.969822) (xy 348.404149 -226.967841) (xy 348.35593 -226.957997)
			(xy 348.309914 -226.940545) (xy 348.267293 -226.915938) (xy 348.229172 -226.884813) (xy 348.196537 -226.847976)
			(xy 348.170234 -226.80638) (xy 348.150943 -226.761104) (xy 348.139166 -226.71332) (xy 348.135206 -226.664266)
			(xy 347.806518 -226.664266) (xy 347.806023 -226.688873) (xy 347.798128 -226.73745) (xy 347.782544 -226.784131)
			(xy 347.759673 -226.827708) (xy 347.730108 -226.867052) (xy 347.694615 -226.901144) (xy 347.654112 -226.9291)
			(xy 347.60965 -226.950198) (xy 347.562379 -226.96389) (xy 347.513524 -226.969822) (xy 347.464349 -226.967841)
			(xy 347.41613 -226.957997) (xy 347.370114 -226.940545) (xy 347.327493 -226.915938) (xy 347.289372 -226.884813)
			(xy 347.256737 -226.847976) (xy 347.230434 -226.80638) (xy 347.211143 -226.761104) (xy 347.199366 -226.71332)
			(xy 347.195406 -226.664266) (xy 346.866464 -226.664266) (xy 346.865969 -226.688873) (xy 346.858074 -226.73745)
			(xy 346.84249 -226.784131) (xy 346.819619 -226.827708) (xy 346.790054 -226.867052) (xy 346.754561 -226.901144)
			(xy 346.714058 -226.9291) (xy 346.669596 -226.950198) (xy 346.622325 -226.96389) (xy 346.57347 -226.969822)
			(xy 346.524295 -226.967841) (xy 346.476076 -226.957997) (xy 346.43006 -226.940545) (xy 346.387439 -226.915938)
			(xy 346.349318 -226.884813) (xy 346.316683 -226.847976) (xy 346.29038 -226.80638) (xy 346.271089 -226.761104)
			(xy 346.259312 -226.71332) (xy 346.255352 -226.664266) (xy 345.92641 -226.664266) (xy 345.925915 -226.688873)
			(xy 345.91802 -226.73745) (xy 345.902436 -226.784131) (xy 345.879565 -226.827708) (xy 345.85 -226.867052)
			(xy 345.814507 -226.901144) (xy 345.774004 -226.9291) (xy 345.729542 -226.950198) (xy 345.682271 -226.96389)
			(xy 345.633416 -226.969822) (xy 345.584241 -226.967841) (xy 345.536022 -226.957997) (xy 345.490006 -226.940545)
			(xy 345.447385 -226.915938) (xy 345.409264 -226.884813) (xy 345.376629 -226.847976) (xy 345.350326 -226.80638)
			(xy 345.331035 -226.761104) (xy 345.319258 -226.71332) (xy 345.315298 -226.664266) (xy 344.986356 -226.664266)
			(xy 344.98582 -226.690058) (xy 344.97715 -226.740908) (xy 344.960051 -226.789576) (xy 344.93501 -226.834674)
			(xy 344.90274 -226.874919) (xy 344.864162 -226.909162) (xy 344.820373 -226.93643) (xy 344.772623 -226.955944)
			(xy 344.72227 -226.967149) (xy 344.696542 -226.969066) (xy 344.687239 -226.969942) (xy 344.670166 -226.977495)
			(xy 344.663268 -226.983798) (xy 344.641424 -227.005388) (xy 344.634573 -227.012785) (xy 344.626831 -227.031383)
			(xy 344.626438 -227.041456) (xy 344.626438 -227.474272) (xy 346.725252 -227.474272) (xy 346.729212 -227.425218)
			(xy 346.740989 -227.377434) (xy 346.76028 -227.332158) (xy 346.786583 -227.290562) (xy 346.819218 -227.253725)
			(xy 346.857339 -227.2226) (xy 346.89996 -227.197993) (xy 346.945976 -227.180541) (xy 346.994195 -227.170697)
			(xy 347.04337 -227.168716) (xy 347.092225 -227.174648) (xy 347.139496 -227.18834) (xy 347.183958 -227.209438)
			(xy 347.224461 -227.237394) (xy 347.259954 -227.271486) (xy 347.289519 -227.31083) (xy 347.31239 -227.354407)
			(xy 347.327974 -227.401088) (xy 347.335869 -227.449665) (xy 347.336364 -227.474272) (xy 349.545414 -227.474272)
			(xy 349.549374 -227.425218) (xy 349.561151 -227.377434) (xy 349.580442 -227.332158) (xy 349.606745 -227.290562)
			(xy 349.63938 -227.253725) (xy 349.677501 -227.2226) (xy 349.720122 -227.197993) (xy 349.766138 -227.180541)
			(xy 349.814357 -227.170697) (xy 349.863532 -227.168716) (xy 349.912387 -227.174648) (xy 349.959658 -227.18834)
			(xy 350.00412 -227.209438) (xy 350.044623 -227.237394) (xy 350.080116 -227.271486) (xy 350.109681 -227.31083)
			(xy 350.132552 -227.354407) (xy 350.148136 -227.401088) (xy 350.156031 -227.449665) (xy 350.156526 -227.474272)
			(xy 352.365322 -227.474272) (xy 352.369282 -227.425218) (xy 352.381059 -227.377434) (xy 352.40035 -227.332158)
			(xy 352.426653 -227.290562) (xy 352.459288 -227.253725) (xy 352.497409 -227.2226) (xy 352.54003 -227.197993)
			(xy 352.586046 -227.180541) (xy 352.634265 -227.170697) (xy 352.68344 -227.168716) (xy 352.732295 -227.174648)
			(xy 352.779566 -227.18834) (xy 352.824028 -227.209438) (xy 352.864531 -227.237394) (xy 352.900024 -227.271486)
			(xy 352.929589 -227.31083) (xy 352.95246 -227.354407) (xy 352.968044 -227.401088) (xy 352.975939 -227.449665)
			(xy 352.976434 -227.474272) (xy 355.18523 -227.474272) (xy 355.18919 -227.425218) (xy 355.200967 -227.377434)
			(xy 355.220258 -227.332158) (xy 355.246561 -227.290562) (xy 355.279196 -227.253725) (xy 355.317317 -227.2226)
			(xy 355.359938 -227.197993) (xy 355.405954 -227.180541) (xy 355.454173 -227.170697) (xy 355.503348 -227.168716)
			(xy 355.552203 -227.174648) (xy 355.599474 -227.18834) (xy 355.643936 -227.209438) (xy 355.684439 -227.237394)
			(xy 355.719932 -227.271486) (xy 355.749497 -227.31083) (xy 355.772368 -227.354407) (xy 355.787952 -227.401088)
			(xy 355.795847 -227.449665) (xy 355.796342 -227.474272) (xy 356.125284 -227.474272) (xy 356.129244 -227.425218)
			(xy 356.141021 -227.377434) (xy 356.160312 -227.332158) (xy 356.186615 -227.290562) (xy 356.21925 -227.253725)
			(xy 356.257371 -227.2226) (xy 356.299992 -227.197993) (xy 356.346008 -227.180541) (xy 356.394227 -227.170697)
			(xy 356.443402 -227.168716) (xy 356.492257 -227.174648) (xy 356.539528 -227.18834) (xy 356.58399 -227.209438)
			(xy 356.624493 -227.237394) (xy 356.659986 -227.271486) (xy 356.689551 -227.31083) (xy 356.712422 -227.354407)
			(xy 356.728006 -227.401088) (xy 356.735901 -227.449665) (xy 356.736396 -227.474272) (xy 357.065338 -227.474272)
			(xy 357.069298 -227.425218) (xy 357.081075 -227.377434) (xy 357.100366 -227.332158) (xy 357.126669 -227.290562)
			(xy 357.159304 -227.253725) (xy 357.197425 -227.2226) (xy 357.240046 -227.197993) (xy 357.286062 -227.180541)
			(xy 357.334281 -227.170697) (xy 357.383456 -227.168716) (xy 357.432311 -227.174648) (xy 357.479582 -227.18834)
			(xy 357.524044 -227.209438) (xy 357.564547 -227.237394) (xy 357.60004 -227.271486) (xy 357.629605 -227.31083)
			(xy 357.652476 -227.354407) (xy 357.66806 -227.401088) (xy 357.675955 -227.449665) (xy 357.67645 -227.474272)
			(xy 358.005392 -227.474272) (xy 358.009352 -227.425218) (xy 358.021129 -227.377434) (xy 358.04042 -227.332158)
			(xy 358.066723 -227.290562) (xy 358.099358 -227.253725) (xy 358.137479 -227.2226) (xy 358.1801 -227.197993)
			(xy 358.226116 -227.180541) (xy 358.274335 -227.170697) (xy 358.32351 -227.168716) (xy 358.372365 -227.174648)
			(xy 358.419636 -227.18834) (xy 358.464098 -227.209438) (xy 358.504601 -227.237394) (xy 358.540094 -227.271486)
			(xy 358.569659 -227.31083) (xy 358.59253 -227.354407) (xy 358.608114 -227.401088) (xy 358.616009 -227.449665)
			(xy 358.616504 -227.474272) (xy 358.616009 -227.498879) (xy 358.608114 -227.547456) (xy 358.59253 -227.594137)
			(xy 358.569659 -227.637714) (xy 358.540094 -227.677058) (xy 358.504601 -227.71115) (xy 358.464098 -227.739106)
			(xy 358.419636 -227.760204) (xy 358.372365 -227.773896) (xy 358.32351 -227.779828) (xy 358.274335 -227.777847)
			(xy 358.226116 -227.768003) (xy 358.1801 -227.750551) (xy 358.137479 -227.725944) (xy 358.099358 -227.694819)
			(xy 358.066723 -227.657982) (xy 358.04042 -227.616386) (xy 358.021129 -227.57111) (xy 358.009352 -227.523326)
			(xy 358.005392 -227.474272) (xy 357.67645 -227.474272) (xy 357.675955 -227.498879) (xy 357.66806 -227.547456)
			(xy 357.652476 -227.594137) (xy 357.629605 -227.637714) (xy 357.60004 -227.677058) (xy 357.564547 -227.71115)
			(xy 357.524044 -227.739106) (xy 357.479582 -227.760204) (xy 357.432311 -227.773896) (xy 357.383456 -227.779828)
			(xy 357.334281 -227.777847) (xy 357.286062 -227.768003) (xy 357.240046 -227.750551) (xy 357.197425 -227.725944)
			(xy 357.159304 -227.694819) (xy 357.126669 -227.657982) (xy 357.100366 -227.616386) (xy 357.081075 -227.57111)
			(xy 357.069298 -227.523326) (xy 357.065338 -227.474272) (xy 356.736396 -227.474272) (xy 356.735901 -227.498879)
			(xy 356.728006 -227.547456) (xy 356.712422 -227.594137) (xy 356.689551 -227.637714) (xy 356.659986 -227.677058)
			(xy 356.624493 -227.71115) (xy 356.58399 -227.739106) (xy 356.539528 -227.760204) (xy 356.492257 -227.773896)
			(xy 356.443402 -227.779828) (xy 356.394227 -227.777847) (xy 356.346008 -227.768003) (xy 356.299992 -227.750551)
			(xy 356.257371 -227.725944) (xy 356.21925 -227.694819) (xy 356.186615 -227.657982) (xy 356.160312 -227.616386)
			(xy 356.141021 -227.57111) (xy 356.129244 -227.523326) (xy 356.125284 -227.474272) (xy 355.796342 -227.474272)
			(xy 355.795847 -227.498879) (xy 355.787952 -227.547456) (xy 355.772368 -227.594137) (xy 355.749497 -227.637714)
			(xy 355.719932 -227.677058) (xy 355.684439 -227.71115) (xy 355.643936 -227.739106) (xy 355.599474 -227.760204)
			(xy 355.552203 -227.773896) (xy 355.503348 -227.779828) (xy 355.454173 -227.777847) (xy 355.405954 -227.768003)
			(xy 355.359938 -227.750551) (xy 355.317317 -227.725944) (xy 355.279196 -227.694819) (xy 355.246561 -227.657982)
			(xy 355.220258 -227.616386) (xy 355.200967 -227.57111) (xy 355.18919 -227.523326) (xy 355.18523 -227.474272)
			(xy 352.976434 -227.474272) (xy 352.975939 -227.498879) (xy 352.968044 -227.547456) (xy 352.95246 -227.594137)
			(xy 352.929589 -227.637714) (xy 352.900024 -227.677058) (xy 352.864531 -227.71115) (xy 352.824028 -227.739106)
			(xy 352.779566 -227.760204) (xy 352.732295 -227.773896) (xy 352.68344 -227.779828) (xy 352.634265 -227.777847)
			(xy 352.586046 -227.768003) (xy 352.54003 -227.750551) (xy 352.497409 -227.725944) (xy 352.459288 -227.694819)
			(xy 352.426653 -227.657982) (xy 352.40035 -227.616386) (xy 352.381059 -227.57111) (xy 352.369282 -227.523326)
			(xy 352.365322 -227.474272) (xy 350.156526 -227.474272) (xy 350.156031 -227.498879) (xy 350.148136 -227.547456)
			(xy 350.132552 -227.594137) (xy 350.109681 -227.637714) (xy 350.080116 -227.677058) (xy 350.044623 -227.71115)
			(xy 350.00412 -227.739106) (xy 349.959658 -227.760204) (xy 349.912387 -227.773896) (xy 349.863532 -227.779828)
			(xy 349.814357 -227.777847) (xy 349.766138 -227.768003) (xy 349.720122 -227.750551) (xy 349.677501 -227.725944)
			(xy 349.63938 -227.694819) (xy 349.606745 -227.657982) (xy 349.580442 -227.616386) (xy 349.561151 -227.57111)
			(xy 349.549374 -227.523326) (xy 349.545414 -227.474272) (xy 347.336364 -227.474272) (xy 347.335869 -227.498879)
			(xy 347.327974 -227.547456) (xy 347.31239 -227.594137) (xy 347.289519 -227.637714) (xy 347.259954 -227.677058)
			(xy 347.224461 -227.71115) (xy 347.183958 -227.739106) (xy 347.139496 -227.760204) (xy 347.092225 -227.773896)
			(xy 347.04337 -227.779828) (xy 346.994195 -227.777847) (xy 346.945976 -227.768003) (xy 346.89996 -227.750551)
			(xy 346.857339 -227.725944) (xy 346.819218 -227.694819) (xy 346.786583 -227.657982) (xy 346.76028 -227.616386)
			(xy 346.740989 -227.57111) (xy 346.729212 -227.523326) (xy 346.725252 -227.474272) (xy 344.626438 -227.474272)
			(xy 344.626438 -227.907088) (xy 344.62686 -227.917158) (xy 344.634575 -227.935763) (xy 344.641424 -227.943156)
			(xy 344.663268 -227.964746) (xy 344.670183 -227.971023) (xy 344.687247 -227.978573) (xy 344.696542 -227.979478)
			(xy 344.720914 -227.981202) (xy 344.768689 -227.991431) (xy 344.814224 -228.009141) (xy 344.856356 -228.033877)
			(xy 344.89401 -228.06501) (xy 344.926223 -228.101743) (xy 344.952173 -228.143139) (xy 344.971198 -228.188141)
			(xy 344.98281 -228.235598) (xy 344.986712 -228.284278) (xy 345.315298 -228.284278) (xy 345.319258 -228.235224)
			(xy 345.331035 -228.18744) (xy 345.350326 -228.142164) (xy 345.376629 -228.100568) (xy 345.409264 -228.063731)
			(xy 345.447385 -228.032606) (xy 345.490006 -228.007999) (xy 345.536022 -227.990547) (xy 345.584241 -227.980703)
			(xy 345.633416 -227.978722) (xy 345.682271 -227.984654) (xy 345.729542 -227.998346) (xy 345.774004 -228.019444)
			(xy 345.814507 -228.0474) (xy 345.85 -228.081492) (xy 345.879565 -228.120836) (xy 345.902436 -228.164413)
			(xy 345.91802 -228.211094) (xy 345.925915 -228.259671) (xy 345.92641 -228.284278) (xy 346.255352 -228.284278)
			(xy 346.259312 -228.235224) (xy 346.271089 -228.18744) (xy 346.29038 -228.142164) (xy 346.316683 -228.100568)
			(xy 346.349318 -228.063731) (xy 346.387439 -228.032606) (xy 346.43006 -228.007999) (xy 346.476076 -227.990547)
			(xy 346.524295 -227.980703) (xy 346.57347 -227.978722) (xy 346.622325 -227.984654) (xy 346.669596 -227.998346)
			(xy 346.714058 -228.019444) (xy 346.754561 -228.0474) (xy 346.790054 -228.081492) (xy 346.819619 -228.120836)
			(xy 346.84249 -228.164413) (xy 346.858074 -228.211094) (xy 346.865969 -228.259671) (xy 346.866464 -228.284278)
			(xy 347.195406 -228.284278) (xy 347.199366 -228.235224) (xy 347.211143 -228.18744) (xy 347.230434 -228.142164)
			(xy 347.256737 -228.100568) (xy 347.289372 -228.063731) (xy 347.327493 -228.032606) (xy 347.370114 -228.007999)
			(xy 347.41613 -227.990547) (xy 347.464349 -227.980703) (xy 347.513524 -227.978722) (xy 347.562379 -227.984654)
			(xy 347.60965 -227.998346) (xy 347.654112 -228.019444) (xy 347.694615 -228.0474) (xy 347.730108 -228.081492)
			(xy 347.759673 -228.120836) (xy 347.782544 -228.164413) (xy 347.798128 -228.211094) (xy 347.806023 -228.259671)
			(xy 347.806518 -228.284278) (xy 348.135206 -228.284278) (xy 348.139166 -228.235224) (xy 348.150943 -228.18744)
			(xy 348.170234 -228.142164) (xy 348.196537 -228.100568) (xy 348.229172 -228.063731) (xy 348.267293 -228.032606)
			(xy 348.309914 -228.007999) (xy 348.35593 -227.990547) (xy 348.404149 -227.980703) (xy 348.453324 -227.978722)
			(xy 348.502179 -227.984654) (xy 348.54945 -227.998346) (xy 348.593912 -228.019444) (xy 348.634415 -228.0474)
			(xy 348.669908 -228.081492) (xy 348.699473 -228.120836) (xy 348.722344 -228.164413) (xy 348.737928 -228.211094)
			(xy 348.745823 -228.259671) (xy 348.746318 -228.284278) (xy 349.07526 -228.284278) (xy 349.07922 -228.235224)
			(xy 349.090997 -228.18744) (xy 349.110288 -228.142164) (xy 349.136591 -228.100568) (xy 349.169226 -228.063731)
			(xy 349.207347 -228.032606) (xy 349.249968 -228.007999) (xy 349.295984 -227.990547) (xy 349.344203 -227.980703)
			(xy 349.393378 -227.978722) (xy 349.442233 -227.984654) (xy 349.489504 -227.998346) (xy 349.533966 -228.019444)
			(xy 349.574469 -228.0474) (xy 349.609962 -228.081492) (xy 349.639527 -228.120836) (xy 349.662398 -228.164413)
			(xy 349.677982 -228.211094) (xy 349.685877 -228.259671) (xy 349.686372 -228.284278) (xy 350.015314 -228.284278)
			(xy 350.019274 -228.235224) (xy 350.031051 -228.18744) (xy 350.050342 -228.142164) (xy 350.076645 -228.100568)
			(xy 350.10928 -228.063731) (xy 350.147401 -228.032606) (xy 350.190022 -228.007999) (xy 350.236038 -227.990547)
			(xy 350.284257 -227.980703) (xy 350.333432 -227.978722) (xy 350.382287 -227.984654) (xy 350.429558 -227.998346)
			(xy 350.47402 -228.019444) (xy 350.514523 -228.0474) (xy 350.550016 -228.081492) (xy 350.579581 -228.120836)
			(xy 350.602452 -228.164413) (xy 350.618036 -228.211094) (xy 350.625931 -228.259671) (xy 350.626426 -228.284278)
			(xy 350.955368 -228.284278) (xy 350.959328 -228.235224) (xy 350.971105 -228.18744) (xy 350.990396 -228.142164)
			(xy 351.016699 -228.100568) (xy 351.049334 -228.063731) (xy 351.087455 -228.032606) (xy 351.130076 -228.007999)
			(xy 351.176092 -227.990547) (xy 351.224311 -227.980703) (xy 351.273486 -227.978722) (xy 351.322341 -227.984654)
			(xy 351.369612 -227.998346) (xy 351.414074 -228.019444) (xy 351.454577 -228.0474) (xy 351.49007 -228.081492)
			(xy 351.519635 -228.120836) (xy 351.542506 -228.164413) (xy 351.55809 -228.211094) (xy 351.565985 -228.259671)
			(xy 351.56648 -228.284278) (xy 351.895422 -228.284278) (xy 351.899382 -228.235224) (xy 351.911159 -228.18744)
			(xy 351.93045 -228.142164) (xy 351.956753 -228.100568) (xy 351.989388 -228.063731) (xy 352.027509 -228.032606)
			(xy 352.07013 -228.007999) (xy 352.116146 -227.990547) (xy 352.164365 -227.980703) (xy 352.21354 -227.978722)
			(xy 352.262395 -227.984654) (xy 352.309666 -227.998346) (xy 352.354128 -228.019444) (xy 352.394631 -228.0474)
			(xy 352.430124 -228.081492) (xy 352.459689 -228.120836) (xy 352.48256 -228.164413) (xy 352.498144 -228.211094)
			(xy 352.506039 -228.259671) (xy 352.506534 -228.284278) (xy 352.835222 -228.284278) (xy 352.839182 -228.235224)
			(xy 352.850959 -228.18744) (xy 352.87025 -228.142164) (xy 352.896553 -228.100568) (xy 352.929188 -228.063731)
			(xy 352.967309 -228.032606) (xy 353.00993 -228.007999) (xy 353.055946 -227.990547) (xy 353.104165 -227.980703)
			(xy 353.15334 -227.978722) (xy 353.202195 -227.984654) (xy 353.249466 -227.998346) (xy 353.293928 -228.019444)
			(xy 353.334431 -228.0474) (xy 353.369924 -228.081492) (xy 353.399489 -228.120836) (xy 353.42236 -228.164413)
			(xy 353.437944 -228.211094) (xy 353.445839 -228.259671) (xy 353.446334 -228.284278) (xy 353.775276 -228.284278)
			(xy 353.779236 -228.235224) (xy 353.791013 -228.18744) (xy 353.810304 -228.142164) (xy 353.836607 -228.100568)
			(xy 353.869242 -228.063731) (xy 353.907363 -228.032606) (xy 353.949984 -228.007999) (xy 353.996 -227.990547)
			(xy 354.044219 -227.980703) (xy 354.093394 -227.978722) (xy 354.142249 -227.984654) (xy 354.18952 -227.998346)
			(xy 354.233982 -228.019444) (xy 354.274485 -228.0474) (xy 354.309978 -228.081492) (xy 354.339543 -228.120836)
			(xy 354.362414 -228.164413) (xy 354.377998 -228.211094) (xy 354.385893 -228.259671) (xy 354.386388 -228.284278)
			(xy 354.71533 -228.284278) (xy 354.71929 -228.235224) (xy 354.731067 -228.18744) (xy 354.750358 -228.142164)
			(xy 354.776661 -228.100568) (xy 354.809296 -228.063731) (xy 354.847417 -228.032606) (xy 354.890038 -228.007999)
			(xy 354.936054 -227.990547) (xy 354.984273 -227.980703) (xy 355.033448 -227.978722) (xy 355.082303 -227.984654)
			(xy 355.129574 -227.998346) (xy 355.174036 -228.019444) (xy 355.214539 -228.0474) (xy 355.250032 -228.081492)
			(xy 355.279597 -228.120836) (xy 355.302468 -228.164413) (xy 355.318052 -228.211094) (xy 355.325947 -228.259671)
			(xy 355.326442 -228.284278) (xy 355.655384 -228.284278) (xy 355.659344 -228.235224) (xy 355.671121 -228.18744)
			(xy 355.690412 -228.142164) (xy 355.716715 -228.100568) (xy 355.74935 -228.063731) (xy 355.787471 -228.032606)
			(xy 355.830092 -228.007999) (xy 355.876108 -227.990547) (xy 355.924327 -227.980703) (xy 355.973502 -227.978722)
			(xy 356.022357 -227.984654) (xy 356.069628 -227.998346) (xy 356.11409 -228.019444) (xy 356.154593 -228.0474)
			(xy 356.190086 -228.081492) (xy 356.219651 -228.120836) (xy 356.242522 -228.164413) (xy 356.258106 -228.211094)
			(xy 356.266001 -228.259671) (xy 356.266496 -228.284278) (xy 356.266001 -228.308885) (xy 356.258106 -228.357462)
			(xy 356.242522 -228.404143) (xy 356.219651 -228.44772) (xy 356.190086 -228.487064) (xy 356.154593 -228.521156)
			(xy 356.11409 -228.549112) (xy 356.069628 -228.57021) (xy 356.022357 -228.583902) (xy 355.973502 -228.589834)
			(xy 355.924327 -228.587853) (xy 355.876108 -228.578009) (xy 355.830092 -228.560557) (xy 355.787471 -228.53595)
			(xy 355.74935 -228.504825) (xy 355.716715 -228.467988) (xy 355.690412 -228.426392) (xy 355.671121 -228.381116)
			(xy 355.659344 -228.333332) (xy 355.655384 -228.284278) (xy 355.326442 -228.284278) (xy 355.325947 -228.308885)
			(xy 355.318052 -228.357462) (xy 355.302468 -228.404143) (xy 355.279597 -228.44772) (xy 355.250032 -228.487064)
			(xy 355.214539 -228.521156) (xy 355.174036 -228.549112) (xy 355.129574 -228.57021) (xy 355.082303 -228.583902)
			(xy 355.033448 -228.589834) (xy 354.984273 -228.587853) (xy 354.936054 -228.578009) (xy 354.890038 -228.560557)
			(xy 354.847417 -228.53595) (xy 354.809296 -228.504825) (xy 354.776661 -228.467988) (xy 354.750358 -228.426392)
			(xy 354.731067 -228.381116) (xy 354.71929 -228.333332) (xy 354.71533 -228.284278) (xy 354.386388 -228.284278)
			(xy 354.385893 -228.308885) (xy 354.377998 -228.357462) (xy 354.362414 -228.404143) (xy 354.339543 -228.44772)
			(xy 354.309978 -228.487064) (xy 354.274485 -228.521156) (xy 354.233982 -228.549112) (xy 354.18952 -228.57021)
			(xy 354.142249 -228.583902) (xy 354.093394 -228.589834) (xy 354.044219 -228.587853) (xy 353.996 -228.578009)
			(xy 353.949984 -228.560557) (xy 353.907363 -228.53595) (xy 353.869242 -228.504825) (xy 353.836607 -228.467988)
			(xy 353.810304 -228.426392) (xy 353.791013 -228.381116) (xy 353.779236 -228.333332) (xy 353.775276 -228.284278)
			(xy 353.446334 -228.284278) (xy 353.445839 -228.308885) (xy 353.437944 -228.357462) (xy 353.42236 -228.404143)
			(xy 353.399489 -228.44772) (xy 353.369924 -228.487064) (xy 353.334431 -228.521156) (xy 353.293928 -228.549112)
			(xy 353.249466 -228.57021) (xy 353.202195 -228.583902) (xy 353.15334 -228.589834) (xy 353.104165 -228.587853)
			(xy 353.055946 -228.578009) (xy 353.00993 -228.560557) (xy 352.967309 -228.53595) (xy 352.929188 -228.504825)
			(xy 352.896553 -228.467988) (xy 352.87025 -228.426392) (xy 352.850959 -228.381116) (xy 352.839182 -228.333332)
			(xy 352.835222 -228.284278) (xy 352.506534 -228.284278) (xy 352.506039 -228.308885) (xy 352.498144 -228.357462)
			(xy 352.48256 -228.404143) (xy 352.459689 -228.44772) (xy 352.430124 -228.487064) (xy 352.394631 -228.521156)
			(xy 352.354128 -228.549112) (xy 352.309666 -228.57021) (xy 352.262395 -228.583902) (xy 352.21354 -228.589834)
			(xy 352.164365 -228.587853) (xy 352.116146 -228.578009) (xy 352.07013 -228.560557) (xy 352.027509 -228.53595)
			(xy 351.989388 -228.504825) (xy 351.956753 -228.467988) (xy 351.93045 -228.426392) (xy 351.911159 -228.381116)
			(xy 351.899382 -228.333332) (xy 351.895422 -228.284278) (xy 351.56648 -228.284278) (xy 351.565985 -228.308885)
			(xy 351.55809 -228.357462) (xy 351.542506 -228.404143) (xy 351.519635 -228.44772) (xy 351.49007 -228.487064)
			(xy 351.454577 -228.521156) (xy 351.414074 -228.549112) (xy 351.369612 -228.57021) (xy 351.322341 -228.583902)
			(xy 351.273486 -228.589834) (xy 351.224311 -228.587853) (xy 351.176092 -228.578009) (xy 351.130076 -228.560557)
			(xy 351.087455 -228.53595) (xy 351.049334 -228.504825) (xy 351.016699 -228.467988) (xy 350.990396 -228.426392)
			(xy 350.971105 -228.381116) (xy 350.959328 -228.333332) (xy 350.955368 -228.284278) (xy 350.626426 -228.284278)
			(xy 350.625931 -228.308885) (xy 350.618036 -228.357462) (xy 350.602452 -228.404143) (xy 350.579581 -228.44772)
			(xy 350.550016 -228.487064) (xy 350.514523 -228.521156) (xy 350.47402 -228.549112) (xy 350.429558 -228.57021)
			(xy 350.382287 -228.583902) (xy 350.333432 -228.589834) (xy 350.284257 -228.587853) (xy 350.236038 -228.578009)
			(xy 350.190022 -228.560557) (xy 350.147401 -228.53595) (xy 350.10928 -228.504825) (xy 350.076645 -228.467988)
			(xy 350.050342 -228.426392) (xy 350.031051 -228.381116) (xy 350.019274 -228.333332) (xy 350.015314 -228.284278)
			(xy 349.686372 -228.284278) (xy 349.685877 -228.308885) (xy 349.677982 -228.357462) (xy 349.662398 -228.404143)
			(xy 349.639527 -228.44772) (xy 349.609962 -228.487064) (xy 349.574469 -228.521156) (xy 349.533966 -228.549112)
			(xy 349.489504 -228.57021) (xy 349.442233 -228.583902) (xy 349.393378 -228.589834) (xy 349.344203 -228.587853)
			(xy 349.295984 -228.578009) (xy 349.249968 -228.560557) (xy 349.207347 -228.53595) (xy 349.169226 -228.504825)
			(xy 349.136591 -228.467988) (xy 349.110288 -228.426392) (xy 349.090997 -228.381116) (xy 349.07922 -228.333332)
			(xy 349.07526 -228.284278) (xy 348.746318 -228.284278) (xy 348.745823 -228.308885) (xy 348.737928 -228.357462)
			(xy 348.722344 -228.404143) (xy 348.699473 -228.44772) (xy 348.669908 -228.487064) (xy 348.634415 -228.521156)
			(xy 348.593912 -228.549112) (xy 348.54945 -228.57021) (xy 348.502179 -228.583902) (xy 348.453324 -228.589834)
			(xy 348.404149 -228.587853) (xy 348.35593 -228.578009) (xy 348.309914 -228.560557) (xy 348.267293 -228.53595)
			(xy 348.229172 -228.504825) (xy 348.196537 -228.467988) (xy 348.170234 -228.426392) (xy 348.150943 -228.381116)
			(xy 348.139166 -228.333332) (xy 348.135206 -228.284278) (xy 347.806518 -228.284278) (xy 347.806023 -228.308885)
			(xy 347.798128 -228.357462) (xy 347.782544 -228.404143) (xy 347.759673 -228.44772) (xy 347.730108 -228.487064)
			(xy 347.694615 -228.521156) (xy 347.654112 -228.549112) (xy 347.60965 -228.57021) (xy 347.562379 -228.583902)
			(xy 347.513524 -228.589834) (xy 347.464349 -228.587853) (xy 347.41613 -228.578009) (xy 347.370114 -228.560557)
			(xy 347.327493 -228.53595) (xy 347.289372 -228.504825) (xy 347.256737 -228.467988) (xy 347.230434 -228.426392)
			(xy 347.211143 -228.381116) (xy 347.199366 -228.333332) (xy 347.195406 -228.284278) (xy 346.866464 -228.284278)
			(xy 346.865969 -228.308885) (xy 346.858074 -228.357462) (xy 346.84249 -228.404143) (xy 346.819619 -228.44772)
			(xy 346.790054 -228.487064) (xy 346.754561 -228.521156) (xy 346.714058 -228.549112) (xy 346.669596 -228.57021)
			(xy 346.622325 -228.583902) (xy 346.57347 -228.589834) (xy 346.524295 -228.587853) (xy 346.476076 -228.578009)
			(xy 346.43006 -228.560557) (xy 346.387439 -228.53595) (xy 346.349318 -228.504825) (xy 346.316683 -228.467988)
			(xy 346.29038 -228.426392) (xy 346.271089 -228.381116) (xy 346.259312 -228.333332) (xy 346.255352 -228.284278)
			(xy 345.92641 -228.284278) (xy 345.925915 -228.308885) (xy 345.91802 -228.357462) (xy 345.902436 -228.404143)
			(xy 345.879565 -228.44772) (xy 345.85 -228.487064) (xy 345.814507 -228.521156) (xy 345.774004 -228.549112)
			(xy 345.729542 -228.57021) (xy 345.682271 -228.583902) (xy 345.633416 -228.589834) (xy 345.584241 -228.587853)
			(xy 345.536022 -228.578009) (xy 345.490006 -228.560557) (xy 345.447385 -228.53595) (xy 345.409264 -228.504825)
			(xy 345.376629 -228.467988) (xy 345.350326 -228.426392) (xy 345.331035 -228.381116) (xy 345.319258 -228.333332)
			(xy 345.315298 -228.284278) (xy 344.986712 -228.284278) (xy 344.986714 -228.284299) (xy 344.982811 -228.333)
			(xy 344.971198 -228.380457) (xy 344.952174 -228.425459) (xy 344.926225 -228.466855) (xy 344.894011 -228.503588)
			(xy 344.856358 -228.534721) (xy 344.814226 -228.559458) (xy 344.768691 -228.577168) (xy 344.720917 -228.587397)
			(xy 344.696542 -228.589078) (xy 344.687239 -228.589954) (xy 344.670167 -228.597509) (xy 344.663268 -228.60381)
			(xy 344.641424 -228.6254) (xy 344.634575 -228.632797) (xy 344.626837 -228.651396) (xy 344.626438 -228.661468)
			(xy 344.626438 -229.094284) (xy 344.845398 -229.094284) (xy 344.849358 -229.04523) (xy 344.861135 -228.997446)
			(xy 344.880426 -228.95217) (xy 344.906729 -228.910574) (xy 344.939364 -228.873737) (xy 344.977485 -228.842612)
			(xy 345.020106 -228.818005) (xy 345.066122 -228.800553) (xy 345.114341 -228.790709) (xy 345.163516 -228.788728)
			(xy 345.212371 -228.79466) (xy 345.259642 -228.808352) (xy 345.304104 -228.82945) (xy 345.344607 -228.857406)
			(xy 345.3801 -228.891498) (xy 345.409665 -228.930842) (xy 345.432536 -228.974419) (xy 345.44812 -229.0211)
			(xy 345.456015 -229.069677) (xy 345.45651 -229.094284) (xy 345.785198 -229.094284) (xy 345.789158 -229.04523)
			(xy 345.800935 -228.997446) (xy 345.820226 -228.95217) (xy 345.846529 -228.910574) (xy 345.879164 -228.873737)
			(xy 345.917285 -228.842612) (xy 345.959906 -228.818005) (xy 346.005922 -228.800553) (xy 346.054141 -228.790709)
			(xy 346.103316 -228.788728) (xy 346.152171 -228.79466) (xy 346.199442 -228.808352) (xy 346.243904 -228.82945)
			(xy 346.284407 -228.857406) (xy 346.3199 -228.891498) (xy 346.349465 -228.930842) (xy 346.372336 -228.974419)
			(xy 346.38792 -229.0211) (xy 346.395815 -229.069677) (xy 346.39631 -229.094284) (xy 346.725252 -229.094284)
			(xy 346.729212 -229.04523) (xy 346.740989 -228.997446) (xy 346.76028 -228.95217) (xy 346.786583 -228.910574)
			(xy 346.819218 -228.873737) (xy 346.857339 -228.842612) (xy 346.89996 -228.818005) (xy 346.945976 -228.800553)
			(xy 346.994195 -228.790709) (xy 347.04337 -228.788728) (xy 347.092225 -228.79466) (xy 347.139496 -228.808352)
			(xy 347.183958 -228.82945) (xy 347.224461 -228.857406) (xy 347.259954 -228.891498) (xy 347.289519 -228.930842)
			(xy 347.31239 -228.974419) (xy 347.327974 -229.0211) (xy 347.335869 -229.069677) (xy 347.336364 -229.094284)
			(xy 347.665306 -229.094284) (xy 347.669266 -229.04523) (xy 347.681043 -228.997446) (xy 347.700334 -228.95217)
			(xy 347.726637 -228.910574) (xy 347.759272 -228.873737) (xy 347.797393 -228.842612) (xy 347.840014 -228.818005)
			(xy 347.88603 -228.800553) (xy 347.934249 -228.790709) (xy 347.983424 -228.788728) (xy 348.032279 -228.79466)
			(xy 348.07955 -228.808352) (xy 348.124012 -228.82945) (xy 348.164515 -228.857406) (xy 348.200008 -228.891498)
			(xy 348.229573 -228.930842) (xy 348.252444 -228.974419) (xy 348.268028 -229.0211) (xy 348.275923 -229.069677)
			(xy 348.276418 -229.094284) (xy 348.60536 -229.094284) (xy 348.60932 -229.04523) (xy 348.621097 -228.997446)
			(xy 348.640388 -228.95217) (xy 348.666691 -228.910574) (xy 348.699326 -228.873737) (xy 348.737447 -228.842612)
			(xy 348.780068 -228.818005) (xy 348.826084 -228.800553) (xy 348.874303 -228.790709) (xy 348.923478 -228.788728)
			(xy 348.972333 -228.79466) (xy 349.019604 -228.808352) (xy 349.064066 -228.82945) (xy 349.104569 -228.857406)
			(xy 349.140062 -228.891498) (xy 349.169627 -228.930842) (xy 349.192498 -228.974419) (xy 349.208082 -229.0211)
			(xy 349.215977 -229.069677) (xy 349.216472 -229.094284) (xy 349.545414 -229.094284) (xy 349.549374 -229.04523)
			(xy 349.561151 -228.997446) (xy 349.580442 -228.95217) (xy 349.606745 -228.910574) (xy 349.63938 -228.873737)
			(xy 349.677501 -228.842612) (xy 349.720122 -228.818005) (xy 349.766138 -228.800553) (xy 349.814357 -228.790709)
			(xy 349.863532 -228.788728) (xy 349.912387 -228.79466) (xy 349.959658 -228.808352) (xy 350.00412 -228.82945)
			(xy 350.044623 -228.857406) (xy 350.080116 -228.891498) (xy 350.109681 -228.930842) (xy 350.132552 -228.974419)
			(xy 350.148136 -229.0211) (xy 350.156031 -229.069677) (xy 350.156526 -229.094284) (xy 350.485214 -229.094284)
			(xy 350.489174 -229.04523) (xy 350.500951 -228.997446) (xy 350.520242 -228.95217) (xy 350.546545 -228.910574)
			(xy 350.57918 -228.873737) (xy 350.617301 -228.842612) (xy 350.659922 -228.818005) (xy 350.705938 -228.800553)
			(xy 350.754157 -228.790709) (xy 350.803332 -228.788728) (xy 350.852187 -228.79466) (xy 350.899458 -228.808352)
			(xy 350.94392 -228.82945) (xy 350.984423 -228.857406) (xy 351.019916 -228.891498) (xy 351.049481 -228.930842)
			(xy 351.072352 -228.974419) (xy 351.087936 -229.0211) (xy 351.095831 -229.069677) (xy 351.096326 -229.094284)
			(xy 351.425268 -229.094284) (xy 351.429228 -229.04523) (xy 351.441005 -228.997446) (xy 351.460296 -228.95217)
			(xy 351.486599 -228.910574) (xy 351.519234 -228.873737) (xy 351.557355 -228.842612) (xy 351.599976 -228.818005)
			(xy 351.645992 -228.800553) (xy 351.694211 -228.790709) (xy 351.743386 -228.788728) (xy 351.792241 -228.79466)
			(xy 351.839512 -228.808352) (xy 351.883974 -228.82945) (xy 351.924477 -228.857406) (xy 351.95997 -228.891498)
			(xy 351.989535 -228.930842) (xy 352.012406 -228.974419) (xy 352.02799 -229.0211) (xy 352.035885 -229.069677)
			(xy 352.03638 -229.094284) (xy 352.365322 -229.094284) (xy 352.369282 -229.04523) (xy 352.381059 -228.997446)
			(xy 352.40035 -228.95217) (xy 352.426653 -228.910574) (xy 352.459288 -228.873737) (xy 352.497409 -228.842612)
			(xy 352.54003 -228.818005) (xy 352.586046 -228.800553) (xy 352.634265 -228.790709) (xy 352.68344 -228.788728)
			(xy 352.732295 -228.79466) (xy 352.779566 -228.808352) (xy 352.824028 -228.82945) (xy 352.864531 -228.857406)
			(xy 352.900024 -228.891498) (xy 352.929589 -228.930842) (xy 352.95246 -228.974419) (xy 352.968044 -229.0211)
			(xy 352.975939 -229.069677) (xy 352.976434 -229.094284) (xy 353.305376 -229.094284) (xy 353.309336 -229.04523)
			(xy 353.321113 -228.997446) (xy 353.340404 -228.95217) (xy 353.366707 -228.910574) (xy 353.399342 -228.873737)
			(xy 353.437463 -228.842612) (xy 353.480084 -228.818005) (xy 353.5261 -228.800553) (xy 353.574319 -228.790709)
			(xy 353.623494 -228.788728) (xy 353.672349 -228.79466) (xy 353.71962 -228.808352) (xy 353.764082 -228.82945)
			(xy 353.804585 -228.857406) (xy 353.840078 -228.891498) (xy 353.869643 -228.930842) (xy 353.892514 -228.974419)
			(xy 353.908098 -229.0211) (xy 353.915993 -229.069677) (xy 353.916488 -229.094284) (xy 354.24543 -229.094284)
			(xy 354.24939 -229.04523) (xy 354.261167 -228.997446) (xy 354.280458 -228.95217) (xy 354.306761 -228.910574)
			(xy 354.339396 -228.873737) (xy 354.377517 -228.842612) (xy 354.420138 -228.818005) (xy 354.466154 -228.800553)
			(xy 354.514373 -228.790709) (xy 354.563548 -228.788728) (xy 354.612403 -228.79466) (xy 354.659674 -228.808352)
			(xy 354.704136 -228.82945) (xy 354.744639 -228.857406) (xy 354.780132 -228.891498) (xy 354.809697 -228.930842)
			(xy 354.832568 -228.974419) (xy 354.848152 -229.0211) (xy 354.856047 -229.069677) (xy 354.856542 -229.094284)
			(xy 355.18523 -229.094284) (xy 355.18919 -229.04523) (xy 355.200967 -228.997446) (xy 355.220258 -228.95217)
			(xy 355.246561 -228.910574) (xy 355.279196 -228.873737) (xy 355.317317 -228.842612) (xy 355.359938 -228.818005)
			(xy 355.405954 -228.800553) (xy 355.454173 -228.790709) (xy 355.503348 -228.788728) (xy 355.552203 -228.79466)
			(xy 355.599474 -228.808352) (xy 355.643936 -228.82945) (xy 355.684439 -228.857406) (xy 355.719932 -228.891498)
			(xy 355.749497 -228.930842) (xy 355.772368 -228.974419) (xy 355.787952 -229.0211) (xy 355.795847 -229.069677)
			(xy 355.796342 -229.094284) (xy 356.125284 -229.094284) (xy 356.129244 -229.04523) (xy 356.141021 -228.997446)
			(xy 356.160312 -228.95217) (xy 356.186615 -228.910574) (xy 356.21925 -228.873737) (xy 356.257371 -228.842612)
			(xy 356.299992 -228.818005) (xy 356.346008 -228.800553) (xy 356.394227 -228.790709) (xy 356.443402 -228.788728)
			(xy 356.492257 -228.79466) (xy 356.539528 -228.808352) (xy 356.58399 -228.82945) (xy 356.624493 -228.857406)
			(xy 356.659986 -228.891498) (xy 356.689551 -228.930842) (xy 356.712422 -228.974419) (xy 356.728006 -229.0211)
			(xy 356.735901 -229.069677) (xy 356.736396 -229.094284) (xy 357.065338 -229.094284) (xy 357.069298 -229.04523)
			(xy 357.081075 -228.997446) (xy 357.100366 -228.95217) (xy 357.126669 -228.910574) (xy 357.159304 -228.873737)
			(xy 357.197425 -228.842612) (xy 357.240046 -228.818005) (xy 357.286062 -228.800553) (xy 357.334281 -228.790709)
			(xy 357.383456 -228.788728) (xy 357.432311 -228.79466) (xy 357.479582 -228.808352) (xy 357.524044 -228.82945)
			(xy 357.564547 -228.857406) (xy 357.60004 -228.891498) (xy 357.629605 -228.930842) (xy 357.652476 -228.974419)
			(xy 357.66806 -229.0211) (xy 357.675955 -229.069677) (xy 357.67645 -229.094284) (xy 358.005392 -229.094284)
			(xy 358.009352 -229.04523) (xy 358.021129 -228.997446) (xy 358.04042 -228.95217) (xy 358.066723 -228.910574)
			(xy 358.099358 -228.873737) (xy 358.137479 -228.842612) (xy 358.1801 -228.818005) (xy 358.226116 -228.800553)
			(xy 358.274335 -228.790709) (xy 358.32351 -228.788728) (xy 358.372365 -228.79466) (xy 358.419636 -228.808352)
			(xy 358.464098 -228.82945) (xy 358.504601 -228.857406) (xy 358.540094 -228.891498) (xy 358.569659 -228.930842)
			(xy 358.59253 -228.974419) (xy 358.608114 -229.0211) (xy 358.616009 -229.069677) (xy 358.616504 -229.094284)
			(xy 358.616009 -229.118891) (xy 358.608114 -229.167468) (xy 358.59253 -229.214149) (xy 358.569659 -229.257726)
			(xy 358.540094 -229.29707) (xy 358.504601 -229.331162) (xy 358.464098 -229.359118) (xy 358.419636 -229.380216)
			(xy 358.372365 -229.393908) (xy 358.32351 -229.39984) (xy 358.274335 -229.397859) (xy 358.226116 -229.388015)
			(xy 358.1801 -229.370563) (xy 358.137479 -229.345956) (xy 358.099358 -229.314831) (xy 358.066723 -229.277994)
			(xy 358.04042 -229.236398) (xy 358.021129 -229.191122) (xy 358.009352 -229.143338) (xy 358.005392 -229.094284)
			(xy 357.67645 -229.094284) (xy 357.675955 -229.118891) (xy 357.66806 -229.167468) (xy 357.652476 -229.214149)
			(xy 357.629605 -229.257726) (xy 357.60004 -229.29707) (xy 357.564547 -229.331162) (xy 357.524044 -229.359118)
			(xy 357.479582 -229.380216) (xy 357.432311 -229.393908) (xy 357.383456 -229.39984) (xy 357.334281 -229.397859)
			(xy 357.286062 -229.388015) (xy 357.240046 -229.370563) (xy 357.197425 -229.345956) (xy 357.159304 -229.314831)
			(xy 357.126669 -229.277994) (xy 357.100366 -229.236398) (xy 357.081075 -229.191122) (xy 357.069298 -229.143338)
			(xy 357.065338 -229.094284) (xy 356.736396 -229.094284) (xy 356.735901 -229.118891) (xy 356.728006 -229.167468)
			(xy 356.712422 -229.214149) (xy 356.689551 -229.257726) (xy 356.659986 -229.29707) (xy 356.624493 -229.331162)
			(xy 356.58399 -229.359118) (xy 356.539528 -229.380216) (xy 356.492257 -229.393908) (xy 356.443402 -229.39984)
			(xy 356.394227 -229.397859) (xy 356.346008 -229.388015) (xy 356.299992 -229.370563) (xy 356.257371 -229.345956)
			(xy 356.21925 -229.314831) (xy 356.186615 -229.277994) (xy 356.160312 -229.236398) (xy 356.141021 -229.191122)
			(xy 356.129244 -229.143338) (xy 356.125284 -229.094284) (xy 355.796342 -229.094284) (xy 355.795847 -229.118891)
			(xy 355.787952 -229.167468) (xy 355.772368 -229.214149) (xy 355.749497 -229.257726) (xy 355.719932 -229.29707)
			(xy 355.684439 -229.331162) (xy 355.643936 -229.359118) (xy 355.599474 -229.380216) (xy 355.552203 -229.393908)
			(xy 355.503348 -229.39984) (xy 355.454173 -229.397859) (xy 355.405954 -229.388015) (xy 355.359938 -229.370563)
			(xy 355.317317 -229.345956) (xy 355.279196 -229.314831) (xy 355.246561 -229.277994) (xy 355.220258 -229.236398)
			(xy 355.200967 -229.191122) (xy 355.18919 -229.143338) (xy 355.18523 -229.094284) (xy 354.856542 -229.094284)
			(xy 354.856047 -229.118891) (xy 354.848152 -229.167468) (xy 354.832568 -229.214149) (xy 354.809697 -229.257726)
			(xy 354.780132 -229.29707) (xy 354.744639 -229.331162) (xy 354.704136 -229.359118) (xy 354.659674 -229.380216)
			(xy 354.612403 -229.393908) (xy 354.563548 -229.39984) (xy 354.514373 -229.397859) (xy 354.466154 -229.388015)
			(xy 354.420138 -229.370563) (xy 354.377517 -229.345956) (xy 354.339396 -229.314831) (xy 354.306761 -229.277994)
			(xy 354.280458 -229.236398) (xy 354.261167 -229.191122) (xy 354.24939 -229.143338) (xy 354.24543 -229.094284)
			(xy 353.916488 -229.094284) (xy 353.915993 -229.118891) (xy 353.908098 -229.167468) (xy 353.892514 -229.214149)
			(xy 353.869643 -229.257726) (xy 353.840078 -229.29707) (xy 353.804585 -229.331162) (xy 353.764082 -229.359118)
			(xy 353.71962 -229.380216) (xy 353.672349 -229.393908) (xy 353.623494 -229.39984) (xy 353.574319 -229.397859)
			(xy 353.5261 -229.388015) (xy 353.480084 -229.370563) (xy 353.437463 -229.345956) (xy 353.399342 -229.314831)
			(xy 353.366707 -229.277994) (xy 353.340404 -229.236398) (xy 353.321113 -229.191122) (xy 353.309336 -229.143338)
			(xy 353.305376 -229.094284) (xy 352.976434 -229.094284) (xy 352.975939 -229.118891) (xy 352.968044 -229.167468)
			(xy 352.95246 -229.214149) (xy 352.929589 -229.257726) (xy 352.900024 -229.29707) (xy 352.864531 -229.331162)
			(xy 352.824028 -229.359118) (xy 352.779566 -229.380216) (xy 352.732295 -229.393908) (xy 352.68344 -229.39984)
			(xy 352.634265 -229.397859) (xy 352.586046 -229.388015) (xy 352.54003 -229.370563) (xy 352.497409 -229.345956)
			(xy 352.459288 -229.314831) (xy 352.426653 -229.277994) (xy 352.40035 -229.236398) (xy 352.381059 -229.191122)
			(xy 352.369282 -229.143338) (xy 352.365322 -229.094284) (xy 352.03638 -229.094284) (xy 352.035885 -229.118891)
			(xy 352.02799 -229.167468) (xy 352.012406 -229.214149) (xy 351.989535 -229.257726) (xy 351.95997 -229.29707)
			(xy 351.924477 -229.331162) (xy 351.883974 -229.359118) (xy 351.839512 -229.380216) (xy 351.792241 -229.393908)
			(xy 351.743386 -229.39984) (xy 351.694211 -229.397859) (xy 351.645992 -229.388015) (xy 351.599976 -229.370563)
			(xy 351.557355 -229.345956) (xy 351.519234 -229.314831) (xy 351.486599 -229.277994) (xy 351.460296 -229.236398)
			(xy 351.441005 -229.191122) (xy 351.429228 -229.143338) (xy 351.425268 -229.094284) (xy 351.096326 -229.094284)
			(xy 351.095831 -229.118891) (xy 351.087936 -229.167468) (xy 351.072352 -229.214149) (xy 351.049481 -229.257726)
			(xy 351.019916 -229.29707) (xy 350.984423 -229.331162) (xy 350.94392 -229.359118) (xy 350.899458 -229.380216)
			(xy 350.852187 -229.393908) (xy 350.803332 -229.39984) (xy 350.754157 -229.397859) (xy 350.705938 -229.388015)
			(xy 350.659922 -229.370563) (xy 350.617301 -229.345956) (xy 350.57918 -229.314831) (xy 350.546545 -229.277994)
			(xy 350.520242 -229.236398) (xy 350.500951 -229.191122) (xy 350.489174 -229.143338) (xy 350.485214 -229.094284)
			(xy 350.156526 -229.094284) (xy 350.156031 -229.118891) (xy 350.148136 -229.167468) (xy 350.132552 -229.214149)
			(xy 350.109681 -229.257726) (xy 350.080116 -229.29707) (xy 350.044623 -229.331162) (xy 350.00412 -229.359118)
			(xy 349.959658 -229.380216) (xy 349.912387 -229.393908) (xy 349.863532 -229.39984) (xy 349.814357 -229.397859)
			(xy 349.766138 -229.388015) (xy 349.720122 -229.370563) (xy 349.677501 -229.345956) (xy 349.63938 -229.314831)
			(xy 349.606745 -229.277994) (xy 349.580442 -229.236398) (xy 349.561151 -229.191122) (xy 349.549374 -229.143338)
			(xy 349.545414 -229.094284) (xy 349.216472 -229.094284) (xy 349.215977 -229.118891) (xy 349.208082 -229.167468)
			(xy 349.192498 -229.214149) (xy 349.169627 -229.257726) (xy 349.140062 -229.29707) (xy 349.104569 -229.331162)
			(xy 349.064066 -229.359118) (xy 349.019604 -229.380216) (xy 348.972333 -229.393908) (xy 348.923478 -229.39984)
			(xy 348.874303 -229.397859) (xy 348.826084 -229.388015) (xy 348.780068 -229.370563) (xy 348.737447 -229.345956)
			(xy 348.699326 -229.314831) (xy 348.666691 -229.277994) (xy 348.640388 -229.236398) (xy 348.621097 -229.191122)
			(xy 348.60932 -229.143338) (xy 348.60536 -229.094284) (xy 348.276418 -229.094284) (xy 348.275923 -229.118891)
			(xy 348.268028 -229.167468) (xy 348.252444 -229.214149) (xy 348.229573 -229.257726) (xy 348.200008 -229.29707)
			(xy 348.164515 -229.331162) (xy 348.124012 -229.359118) (xy 348.07955 -229.380216) (xy 348.032279 -229.393908)
			(xy 347.983424 -229.39984) (xy 347.934249 -229.397859) (xy 347.88603 -229.388015) (xy 347.840014 -229.370563)
			(xy 347.797393 -229.345956) (xy 347.759272 -229.314831) (xy 347.726637 -229.277994) (xy 347.700334 -229.236398)
			(xy 347.681043 -229.191122) (xy 347.669266 -229.143338) (xy 347.665306 -229.094284) (xy 347.336364 -229.094284)
			(xy 347.335869 -229.118891) (xy 347.327974 -229.167468) (xy 347.31239 -229.214149) (xy 347.289519 -229.257726)
			(xy 347.259954 -229.29707) (xy 347.224461 -229.331162) (xy 347.183958 -229.359118) (xy 347.139496 -229.380216)
			(xy 347.092225 -229.393908) (xy 347.04337 -229.39984) (xy 346.994195 -229.397859) (xy 346.945976 -229.388015)
			(xy 346.89996 -229.370563) (xy 346.857339 -229.345956) (xy 346.819218 -229.314831) (xy 346.786583 -229.277994)
			(xy 346.76028 -229.236398) (xy 346.740989 -229.191122) (xy 346.729212 -229.143338) (xy 346.725252 -229.094284)
			(xy 346.39631 -229.094284) (xy 346.395815 -229.118891) (xy 346.38792 -229.167468) (xy 346.372336 -229.214149)
			(xy 346.349465 -229.257726) (xy 346.3199 -229.29707) (xy 346.284407 -229.331162) (xy 346.243904 -229.359118)
			(xy 346.199442 -229.380216) (xy 346.152171 -229.393908) (xy 346.103316 -229.39984) (xy 346.054141 -229.397859)
			(xy 346.005922 -229.388015) (xy 345.959906 -229.370563) (xy 345.917285 -229.345956) (xy 345.879164 -229.314831)
			(xy 345.846529 -229.277994) (xy 345.820226 -229.236398) (xy 345.800935 -229.191122) (xy 345.789158 -229.143338)
			(xy 345.785198 -229.094284) (xy 345.45651 -229.094284) (xy 345.456015 -229.118891) (xy 345.44812 -229.167468)
			(xy 345.432536 -229.214149) (xy 345.409665 -229.257726) (xy 345.3801 -229.29707) (xy 345.344607 -229.331162)
			(xy 345.304104 -229.359118) (xy 345.259642 -229.380216) (xy 345.212371 -229.393908) (xy 345.163516 -229.39984)
			(xy 345.114341 -229.397859) (xy 345.066122 -229.388015) (xy 345.020106 -229.370563) (xy 344.977485 -229.345956)
			(xy 344.939364 -229.314831) (xy 344.906729 -229.277994) (xy 344.880426 -229.236398) (xy 344.861135 -229.191122)
			(xy 344.849358 -229.143338) (xy 344.845398 -229.094284) (xy 344.626438 -229.094284) (xy 344.626438 -229.526846)
			(xy 344.62687 -229.536912) (xy 344.634601 -229.555501) (xy 344.641424 -229.562914) (xy 344.663268 -229.584504)
			(xy 344.670185 -229.590775) (xy 344.687249 -229.598317) (xy 344.696542 -229.599236) (xy 344.72091 -229.60096)
			(xy 344.768675 -229.611188) (xy 344.814201 -229.628894) (xy 344.856325 -229.653626) (xy 344.893972 -229.684754)
			(xy 344.926178 -229.72148) (xy 344.952123 -229.762869) (xy 344.971144 -229.807862) (xy 344.982754 -229.85531)
			(xy 344.986657 -229.904002) (xy 344.986654 -229.904036) (xy 345.315298 -229.904036) (xy 345.319258 -229.854982)
			(xy 345.331035 -229.807198) (xy 345.350326 -229.761922) (xy 345.376629 -229.720326) (xy 345.409264 -229.683489)
			(xy 345.447385 -229.652364) (xy 345.490006 -229.627757) (xy 345.536022 -229.610305) (xy 345.584241 -229.600461)
			(xy 345.633416 -229.59848) (xy 345.682271 -229.604412) (xy 345.729542 -229.618104) (xy 345.774004 -229.639202)
			(xy 345.814507 -229.667158) (xy 345.85 -229.70125) (xy 345.879565 -229.740594) (xy 345.902436 -229.784171)
			(xy 345.91802 -229.830852) (xy 345.925915 -229.879429) (xy 345.92641 -229.904036) (xy 346.255352 -229.904036)
			(xy 346.259312 -229.854982) (xy 346.271089 -229.807198) (xy 346.29038 -229.761922) (xy 346.316683 -229.720326)
			(xy 346.349318 -229.683489) (xy 346.387439 -229.652364) (xy 346.43006 -229.627757) (xy 346.476076 -229.610305)
			(xy 346.524295 -229.600461) (xy 346.57347 -229.59848) (xy 346.622325 -229.604412) (xy 346.669596 -229.618104)
			(xy 346.714058 -229.639202) (xy 346.754561 -229.667158) (xy 346.790054 -229.70125) (xy 346.819619 -229.740594)
			(xy 346.84249 -229.784171) (xy 346.858074 -229.830852) (xy 346.865969 -229.879429) (xy 346.866464 -229.904036)
			(xy 347.195406 -229.904036) (xy 347.199366 -229.854982) (xy 347.211143 -229.807198) (xy 347.230434 -229.761922)
			(xy 347.256737 -229.720326) (xy 347.289372 -229.683489) (xy 347.327493 -229.652364) (xy 347.370114 -229.627757)
			(xy 347.41613 -229.610305) (xy 347.464349 -229.600461) (xy 347.513524 -229.59848) (xy 347.562379 -229.604412)
			(xy 347.60965 -229.618104) (xy 347.654112 -229.639202) (xy 347.694615 -229.667158) (xy 347.730108 -229.70125)
			(xy 347.759673 -229.740594) (xy 347.782544 -229.784171) (xy 347.798128 -229.830852) (xy 347.806023 -229.879429)
			(xy 347.806518 -229.904036) (xy 348.135206 -229.904036) (xy 348.139166 -229.854982) (xy 348.150943 -229.807198)
			(xy 348.170234 -229.761922) (xy 348.196537 -229.720326) (xy 348.229172 -229.683489) (xy 348.267293 -229.652364)
			(xy 348.309914 -229.627757) (xy 348.35593 -229.610305) (xy 348.404149 -229.600461) (xy 348.453324 -229.59848)
			(xy 348.502179 -229.604412) (xy 348.54945 -229.618104) (xy 348.593912 -229.639202) (xy 348.634415 -229.667158)
			(xy 348.669908 -229.70125) (xy 348.699473 -229.740594) (xy 348.722344 -229.784171) (xy 348.737928 -229.830852)
			(xy 348.745823 -229.879429) (xy 348.746318 -229.904036) (xy 349.07526 -229.904036) (xy 349.07922 -229.854982)
			(xy 349.090997 -229.807198) (xy 349.110288 -229.761922) (xy 349.136591 -229.720326) (xy 349.169226 -229.683489)
			(xy 349.207347 -229.652364) (xy 349.249968 -229.627757) (xy 349.295984 -229.610305) (xy 349.344203 -229.600461)
			(xy 349.393378 -229.59848) (xy 349.442233 -229.604412) (xy 349.489504 -229.618104) (xy 349.533966 -229.639202)
			(xy 349.574469 -229.667158) (xy 349.609962 -229.70125) (xy 349.639527 -229.740594) (xy 349.662398 -229.784171)
			(xy 349.677982 -229.830852) (xy 349.685877 -229.879429) (xy 349.686372 -229.904036) (xy 350.015314 -229.904036)
			(xy 350.019274 -229.854982) (xy 350.031051 -229.807198) (xy 350.050342 -229.761922) (xy 350.076645 -229.720326)
			(xy 350.10928 -229.683489) (xy 350.147401 -229.652364) (xy 350.190022 -229.627757) (xy 350.236038 -229.610305)
			(xy 350.284257 -229.600461) (xy 350.333432 -229.59848) (xy 350.382287 -229.604412) (xy 350.429558 -229.618104)
			(xy 350.47402 -229.639202) (xy 350.514523 -229.667158) (xy 350.550016 -229.70125) (xy 350.579581 -229.740594)
			(xy 350.602452 -229.784171) (xy 350.618036 -229.830852) (xy 350.625931 -229.879429) (xy 350.626426 -229.904036)
			(xy 350.955368 -229.904036) (xy 350.959328 -229.854982) (xy 350.971105 -229.807198) (xy 350.990396 -229.761922)
			(xy 351.016699 -229.720326) (xy 351.049334 -229.683489) (xy 351.087455 -229.652364) (xy 351.130076 -229.627757)
			(xy 351.176092 -229.610305) (xy 351.224311 -229.600461) (xy 351.273486 -229.59848) (xy 351.322341 -229.604412)
			(xy 351.369612 -229.618104) (xy 351.414074 -229.639202) (xy 351.454577 -229.667158) (xy 351.49007 -229.70125)
			(xy 351.519635 -229.740594) (xy 351.542506 -229.784171) (xy 351.55809 -229.830852) (xy 351.565985 -229.879429)
			(xy 351.56648 -229.904036) (xy 351.895422 -229.904036) (xy 351.899382 -229.854982) (xy 351.911159 -229.807198)
			(xy 351.93045 -229.761922) (xy 351.956753 -229.720326) (xy 351.989388 -229.683489) (xy 352.027509 -229.652364)
			(xy 352.07013 -229.627757) (xy 352.116146 -229.610305) (xy 352.164365 -229.600461) (xy 352.21354 -229.59848)
			(xy 352.262395 -229.604412) (xy 352.309666 -229.618104) (xy 352.354128 -229.639202) (xy 352.394631 -229.667158)
			(xy 352.430124 -229.70125) (xy 352.459689 -229.740594) (xy 352.48256 -229.784171) (xy 352.498144 -229.830852)
			(xy 352.506039 -229.879429) (xy 352.506534 -229.904036) (xy 352.835222 -229.904036) (xy 352.839182 -229.854982)
			(xy 352.850959 -229.807198) (xy 352.87025 -229.761922) (xy 352.896553 -229.720326) (xy 352.929188 -229.683489)
			(xy 352.967309 -229.652364) (xy 353.00993 -229.627757) (xy 353.055946 -229.610305) (xy 353.104165 -229.600461)
			(xy 353.15334 -229.59848) (xy 353.202195 -229.604412) (xy 353.249466 -229.618104) (xy 353.293928 -229.639202)
			(xy 353.334431 -229.667158) (xy 353.369924 -229.70125) (xy 353.399489 -229.740594) (xy 353.42236 -229.784171)
			(xy 353.437944 -229.830852) (xy 353.445839 -229.879429) (xy 353.446334 -229.904036) (xy 353.775276 -229.904036)
			(xy 353.779236 -229.854982) (xy 353.791013 -229.807198) (xy 353.810304 -229.761922) (xy 353.836607 -229.720326)
			(xy 353.869242 -229.683489) (xy 353.907363 -229.652364) (xy 353.949984 -229.627757) (xy 353.996 -229.610305)
			(xy 354.044219 -229.600461) (xy 354.093394 -229.59848) (xy 354.142249 -229.604412) (xy 354.18952 -229.618104)
			(xy 354.233982 -229.639202) (xy 354.274485 -229.667158) (xy 354.309978 -229.70125) (xy 354.339543 -229.740594)
			(xy 354.362414 -229.784171) (xy 354.377998 -229.830852) (xy 354.385893 -229.879429) (xy 354.386388 -229.904036)
			(xy 354.71533 -229.904036) (xy 354.71929 -229.854982) (xy 354.731067 -229.807198) (xy 354.750358 -229.761922)
			(xy 354.776661 -229.720326) (xy 354.809296 -229.683489) (xy 354.847417 -229.652364) (xy 354.890038 -229.627757)
			(xy 354.936054 -229.610305) (xy 354.984273 -229.600461) (xy 355.033448 -229.59848) (xy 355.082303 -229.604412)
			(xy 355.129574 -229.618104) (xy 355.174036 -229.639202) (xy 355.214539 -229.667158) (xy 355.250032 -229.70125)
			(xy 355.279597 -229.740594) (xy 355.302468 -229.784171) (xy 355.318052 -229.830852) (xy 355.325947 -229.879429)
			(xy 355.326442 -229.904036) (xy 355.655384 -229.904036) (xy 355.659344 -229.854982) (xy 355.671121 -229.807198)
			(xy 355.690412 -229.761922) (xy 355.716715 -229.720326) (xy 355.74935 -229.683489) (xy 355.787471 -229.652364)
			(xy 355.830092 -229.627757) (xy 355.876108 -229.610305) (xy 355.924327 -229.600461) (xy 355.973502 -229.59848)
			(xy 356.022357 -229.604412) (xy 356.069628 -229.618104) (xy 356.11409 -229.639202) (xy 356.154593 -229.667158)
			(xy 356.190086 -229.70125) (xy 356.219651 -229.740594) (xy 356.242522 -229.784171) (xy 356.258106 -229.830852)
			(xy 356.266001 -229.879429) (xy 356.266496 -229.904036) (xy 356.595438 -229.904036) (xy 356.599398 -229.854982)
			(xy 356.611175 -229.807198) (xy 356.630466 -229.761922) (xy 356.656769 -229.720326) (xy 356.689404 -229.683489)
			(xy 356.727525 -229.652364) (xy 356.770146 -229.627757) (xy 356.816162 -229.610305) (xy 356.864381 -229.600461)
			(xy 356.913556 -229.59848) (xy 356.962411 -229.604412) (xy 357.009682 -229.618104) (xy 357.054144 -229.639202)
			(xy 357.094647 -229.667158) (xy 357.13014 -229.70125) (xy 357.159705 -229.740594) (xy 357.182576 -229.784171)
			(xy 357.19816 -229.830852) (xy 357.206055 -229.879429) (xy 357.20655 -229.904036) (xy 357.535238 -229.904036)
			(xy 357.539198 -229.854982) (xy 357.550975 -229.807198) (xy 357.570266 -229.761922) (xy 357.596569 -229.720326)
			(xy 357.629204 -229.683489) (xy 357.667325 -229.652364) (xy 357.709946 -229.627757) (xy 357.755962 -229.610305)
			(xy 357.804181 -229.600461) (xy 357.853356 -229.59848) (xy 357.902211 -229.604412) (xy 357.949482 -229.618104)
			(xy 357.993944 -229.639202) (xy 358.034447 -229.667158) (xy 358.06994 -229.70125) (xy 358.099505 -229.740594)
			(xy 358.122376 -229.784171) (xy 358.13796 -229.830852) (xy 358.145855 -229.879429) (xy 358.14635 -229.904036)
			(xy 358.145855 -229.928643) (xy 358.13796 -229.97722) (xy 358.122376 -230.023901) (xy 358.099505 -230.067478)
			(xy 358.06994 -230.106822) (xy 358.034447 -230.140914) (xy 357.993944 -230.16887) (xy 357.949482 -230.189968)
			(xy 357.902211 -230.20366) (xy 357.853356 -230.209592) (xy 357.804181 -230.207611) (xy 357.755962 -230.197767)
			(xy 357.709946 -230.180315) (xy 357.667325 -230.155708) (xy 357.629204 -230.124583) (xy 357.596569 -230.087746)
			(xy 357.570266 -230.04615) (xy 357.550975 -230.000874) (xy 357.539198 -229.95309) (xy 357.535238 -229.904036)
			(xy 357.20655 -229.904036) (xy 357.206055 -229.928643) (xy 357.19816 -229.97722) (xy 357.182576 -230.023901)
			(xy 357.159705 -230.067478) (xy 357.13014 -230.106822) (xy 357.094647 -230.140914) (xy 357.054144 -230.16887)
			(xy 357.009682 -230.189968) (xy 356.962411 -230.20366) (xy 356.913556 -230.209592) (xy 356.864381 -230.207611)
			(xy 356.816162 -230.197767) (xy 356.770146 -230.180315) (xy 356.727525 -230.155708) (xy 356.689404 -230.124583)
			(xy 356.656769 -230.087746) (xy 356.630466 -230.04615) (xy 356.611175 -230.000874) (xy 356.599398 -229.95309)
			(xy 356.595438 -229.904036) (xy 356.266496 -229.904036) (xy 356.266001 -229.928643) (xy 356.258106 -229.97722)
			(xy 356.242522 -230.023901) (xy 356.219651 -230.067478) (xy 356.190086 -230.106822) (xy 356.154593 -230.140914)
			(xy 356.11409 -230.16887) (xy 356.069628 -230.189968) (xy 356.022357 -230.20366) (xy 355.973502 -230.209592)
			(xy 355.924327 -230.207611) (xy 355.876108 -230.197767) (xy 355.830092 -230.180315) (xy 355.787471 -230.155708)
			(xy 355.74935 -230.124583) (xy 355.716715 -230.087746) (xy 355.690412 -230.04615) (xy 355.671121 -230.000874)
			(xy 355.659344 -229.95309) (xy 355.655384 -229.904036) (xy 355.326442 -229.904036) (xy 355.325947 -229.928643)
			(xy 355.318052 -229.97722) (xy 355.302468 -230.023901) (xy 355.279597 -230.067478) (xy 355.250032 -230.106822)
			(xy 355.214539 -230.140914) (xy 355.174036 -230.16887) (xy 355.129574 -230.189968) (xy 355.082303 -230.20366)
			(xy 355.033448 -230.209592) (xy 354.984273 -230.207611) (xy 354.936054 -230.197767) (xy 354.890038 -230.180315)
			(xy 354.847417 -230.155708) (xy 354.809296 -230.124583) (xy 354.776661 -230.087746) (xy 354.750358 -230.04615)
			(xy 354.731067 -230.000874) (xy 354.71929 -229.95309) (xy 354.71533 -229.904036) (xy 354.386388 -229.904036)
			(xy 354.385893 -229.928643) (xy 354.377998 -229.97722) (xy 354.362414 -230.023901) (xy 354.339543 -230.067478)
			(xy 354.309978 -230.106822) (xy 354.274485 -230.140914) (xy 354.233982 -230.16887) (xy 354.18952 -230.189968)
			(xy 354.142249 -230.20366) (xy 354.093394 -230.209592) (xy 354.044219 -230.207611) (xy 353.996 -230.197767)
			(xy 353.949984 -230.180315) (xy 353.907363 -230.155708) (xy 353.869242 -230.124583) (xy 353.836607 -230.087746)
			(xy 353.810304 -230.04615) (xy 353.791013 -230.000874) (xy 353.779236 -229.95309) (xy 353.775276 -229.904036)
			(xy 353.446334 -229.904036) (xy 353.445839 -229.928643) (xy 353.437944 -229.97722) (xy 353.42236 -230.023901)
			(xy 353.399489 -230.067478) (xy 353.369924 -230.106822) (xy 353.334431 -230.140914) (xy 353.293928 -230.16887)
			(xy 353.249466 -230.189968) (xy 353.202195 -230.20366) (xy 353.15334 -230.209592) (xy 353.104165 -230.207611)
			(xy 353.055946 -230.197767) (xy 353.00993 -230.180315) (xy 352.967309 -230.155708) (xy 352.929188 -230.124583)
			(xy 352.896553 -230.087746) (xy 352.87025 -230.04615) (xy 352.850959 -230.000874) (xy 352.839182 -229.95309)
			(xy 352.835222 -229.904036) (xy 352.506534 -229.904036) (xy 352.506039 -229.928643) (xy 352.498144 -229.97722)
			(xy 352.48256 -230.023901) (xy 352.459689 -230.067478) (xy 352.430124 -230.106822) (xy 352.394631 -230.140914)
			(xy 352.354128 -230.16887) (xy 352.309666 -230.189968) (xy 352.262395 -230.20366) (xy 352.21354 -230.209592)
			(xy 352.164365 -230.207611) (xy 352.116146 -230.197767) (xy 352.07013 -230.180315) (xy 352.027509 -230.155708)
			(xy 351.989388 -230.124583) (xy 351.956753 -230.087746) (xy 351.93045 -230.04615) (xy 351.911159 -230.000874)
			(xy 351.899382 -229.95309) (xy 351.895422 -229.904036) (xy 351.56648 -229.904036) (xy 351.565985 -229.928643)
			(xy 351.55809 -229.97722) (xy 351.542506 -230.023901) (xy 351.519635 -230.067478) (xy 351.49007 -230.106822)
			(xy 351.454577 -230.140914) (xy 351.414074 -230.16887) (xy 351.369612 -230.189968) (xy 351.322341 -230.20366)
			(xy 351.273486 -230.209592) (xy 351.224311 -230.207611) (xy 351.176092 -230.197767) (xy 351.130076 -230.180315)
			(xy 351.087455 -230.155708) (xy 351.049334 -230.124583) (xy 351.016699 -230.087746) (xy 350.990396 -230.04615)
			(xy 350.971105 -230.000874) (xy 350.959328 -229.95309) (xy 350.955368 -229.904036) (xy 350.626426 -229.904036)
			(xy 350.625931 -229.928643) (xy 350.618036 -229.97722) (xy 350.602452 -230.023901) (xy 350.579581 -230.067478)
			(xy 350.550016 -230.106822) (xy 350.514523 -230.140914) (xy 350.47402 -230.16887) (xy 350.429558 -230.189968)
			(xy 350.382287 -230.20366) (xy 350.333432 -230.209592) (xy 350.284257 -230.207611) (xy 350.236038 -230.197767)
			(xy 350.190022 -230.180315) (xy 350.147401 -230.155708) (xy 350.10928 -230.124583) (xy 350.076645 -230.087746)
			(xy 350.050342 -230.04615) (xy 350.031051 -230.000874) (xy 350.019274 -229.95309) (xy 350.015314 -229.904036)
			(xy 349.686372 -229.904036) (xy 349.685877 -229.928643) (xy 349.677982 -229.97722) (xy 349.662398 -230.023901)
			(xy 349.639527 -230.067478) (xy 349.609962 -230.106822) (xy 349.574469 -230.140914) (xy 349.533966 -230.16887)
			(xy 349.489504 -230.189968) (xy 349.442233 -230.20366) (xy 349.393378 -230.209592) (xy 349.344203 -230.207611)
			(xy 349.295984 -230.197767) (xy 349.249968 -230.180315) (xy 349.207347 -230.155708) (xy 349.169226 -230.124583)
			(xy 349.136591 -230.087746) (xy 349.110288 -230.04615) (xy 349.090997 -230.000874) (xy 349.07922 -229.95309)
			(xy 349.07526 -229.904036) (xy 348.746318 -229.904036) (xy 348.745823 -229.928643) (xy 348.737928 -229.97722)
			(xy 348.722344 -230.023901) (xy 348.699473 -230.067478) (xy 348.669908 -230.106822) (xy 348.634415 -230.140914)
			(xy 348.593912 -230.16887) (xy 348.54945 -230.189968) (xy 348.502179 -230.20366) (xy 348.453324 -230.209592)
			(xy 348.404149 -230.207611) (xy 348.35593 -230.197767) (xy 348.309914 -230.180315) (xy 348.267293 -230.155708)
			(xy 348.229172 -230.124583) (xy 348.196537 -230.087746) (xy 348.170234 -230.04615) (xy 348.150943 -230.000874)
			(xy 348.139166 -229.95309) (xy 348.135206 -229.904036) (xy 347.806518 -229.904036) (xy 347.806023 -229.928643)
			(xy 347.798128 -229.97722) (xy 347.782544 -230.023901) (xy 347.759673 -230.067478) (xy 347.730108 -230.106822)
			(xy 347.694615 -230.140914) (xy 347.654112 -230.16887) (xy 347.60965 -230.189968) (xy 347.562379 -230.20366)
			(xy 347.513524 -230.209592) (xy 347.464349 -230.207611) (xy 347.41613 -230.197767) (xy 347.370114 -230.180315)
			(xy 347.327493 -230.155708) (xy 347.289372 -230.124583) (xy 347.256737 -230.087746) (xy 347.230434 -230.04615)
			(xy 347.211143 -230.000874) (xy 347.199366 -229.95309) (xy 347.195406 -229.904036) (xy 346.866464 -229.904036)
			(xy 346.865969 -229.928643) (xy 346.858074 -229.97722) (xy 346.84249 -230.023901) (xy 346.819619 -230.067478)
			(xy 346.790054 -230.106822) (xy 346.754561 -230.140914) (xy 346.714058 -230.16887) (xy 346.669596 -230.189968)
			(xy 346.622325 -230.20366) (xy 346.57347 -230.209592) (xy 346.524295 -230.207611) (xy 346.476076 -230.197767)
			(xy 346.43006 -230.180315) (xy 346.387439 -230.155708) (xy 346.349318 -230.124583) (xy 346.316683 -230.087746)
			(xy 346.29038 -230.04615) (xy 346.271089 -230.000874) (xy 346.259312 -229.95309) (xy 346.255352 -229.904036)
			(xy 345.92641 -229.904036) (xy 345.925915 -229.928643) (xy 345.91802 -229.97722) (xy 345.902436 -230.023901)
			(xy 345.879565 -230.067478) (xy 345.85 -230.106822) (xy 345.814507 -230.140914) (xy 345.774004 -230.16887)
			(xy 345.729542 -230.189968) (xy 345.682271 -230.20366) (xy 345.633416 -230.209592) (xy 345.584241 -230.207611)
			(xy 345.536022 -230.197767) (xy 345.490006 -230.180315) (xy 345.447385 -230.155708) (xy 345.409264 -230.124583)
			(xy 345.376629 -230.087746) (xy 345.350326 -230.04615) (xy 345.331035 -230.000874) (xy 345.319258 -229.95309)
			(xy 345.315298 -229.904036) (xy 344.986654 -229.904036) (xy 344.982753 -229.952694) (xy 344.971142 -230.000142)
			(xy 344.952122 -230.045135) (xy 344.926176 -230.086523) (xy 344.893969 -230.123249) (xy 344.856322 -230.154376)
			(xy 344.814198 -230.179108) (xy 344.768672 -230.196813) (xy 344.720906 -230.20704) (xy 344.696542 -230.208836)
			(xy 344.687238 -230.209711) (xy 344.670162 -230.217261) (xy 344.663268 -230.223568) (xy 344.641424 -230.245158)
			(xy 344.634584 -230.252559) (xy 344.626867 -230.271157) (xy 344.626438 -230.281226) (xy 344.626438 -230.714296)
			(xy 346.725252 -230.714296) (xy 346.729212 -230.665242) (xy 346.740989 -230.617458) (xy 346.76028 -230.572182)
			(xy 346.786583 -230.530586) (xy 346.819218 -230.493749) (xy 346.857339 -230.462624) (xy 346.89996 -230.438017)
			(xy 346.945976 -230.420565) (xy 346.994195 -230.410721) (xy 347.04337 -230.40874) (xy 347.092225 -230.414672)
			(xy 347.139496 -230.428364) (xy 347.183958 -230.449462) (xy 347.224461 -230.477418) (xy 347.259954 -230.51151)
			(xy 347.289519 -230.550854) (xy 347.31239 -230.594431) (xy 347.327974 -230.641112) (xy 347.335869 -230.689689)
			(xy 347.336364 -230.714296) (xy 349.545414 -230.714296) (xy 349.549374 -230.665242) (xy 349.561151 -230.617458)
			(xy 349.580442 -230.572182) (xy 349.606745 -230.530586) (xy 349.63938 -230.493749) (xy 349.677501 -230.462624)
			(xy 349.720122 -230.438017) (xy 349.766138 -230.420565) (xy 349.814357 -230.410721) (xy 349.863532 -230.40874)
			(xy 349.912387 -230.414672) (xy 349.959658 -230.428364) (xy 350.00412 -230.449462) (xy 350.044623 -230.477418)
			(xy 350.080116 -230.51151) (xy 350.109681 -230.550854) (xy 350.132552 -230.594431) (xy 350.148136 -230.641112)
			(xy 350.156031 -230.689689) (xy 350.156526 -230.714296) (xy 352.365322 -230.714296) (xy 352.369282 -230.665242)
			(xy 352.381059 -230.617458) (xy 352.40035 -230.572182) (xy 352.426653 -230.530586) (xy 352.459288 -230.493749)
			(xy 352.497409 -230.462624) (xy 352.54003 -230.438017) (xy 352.586046 -230.420565) (xy 352.634265 -230.410721)
			(xy 352.68344 -230.40874) (xy 352.732295 -230.414672) (xy 352.779566 -230.428364) (xy 352.824028 -230.449462)
			(xy 352.864531 -230.477418) (xy 352.900024 -230.51151) (xy 352.929589 -230.550854) (xy 352.95246 -230.594431)
			(xy 352.968044 -230.641112) (xy 352.975939 -230.689689) (xy 352.976434 -230.714296) (xy 355.18523 -230.714296)
			(xy 355.18919 -230.665242) (xy 355.200967 -230.617458) (xy 355.220258 -230.572182) (xy 355.246561 -230.530586)
			(xy 355.279196 -230.493749) (xy 355.317317 -230.462624) (xy 355.359938 -230.438017) (xy 355.405954 -230.420565)
			(xy 355.454173 -230.410721) (xy 355.503348 -230.40874) (xy 355.552203 -230.414672) (xy 355.599474 -230.428364)
			(xy 355.643936 -230.449462) (xy 355.684439 -230.477418) (xy 355.719932 -230.51151) (xy 355.749497 -230.550854)
			(xy 355.772368 -230.594431) (xy 355.787952 -230.641112) (xy 355.795847 -230.689689) (xy 355.796342 -230.714296)
			(xy 356.125284 -230.714296) (xy 356.129244 -230.665242) (xy 356.141021 -230.617458) (xy 356.160312 -230.572182)
			(xy 356.186615 -230.530586) (xy 356.21925 -230.493749) (xy 356.257371 -230.462624) (xy 356.299992 -230.438017)
			(xy 356.346008 -230.420565) (xy 356.394227 -230.410721) (xy 356.443402 -230.40874) (xy 356.492257 -230.414672)
			(xy 356.539528 -230.428364) (xy 356.58399 -230.449462) (xy 356.624493 -230.477418) (xy 356.659986 -230.51151)
			(xy 356.689551 -230.550854) (xy 356.712422 -230.594431) (xy 356.728006 -230.641112) (xy 356.735901 -230.689689)
			(xy 356.736396 -230.714296) (xy 357.065338 -230.714296) (xy 357.069298 -230.665242) (xy 357.081075 -230.617458)
			(xy 357.100366 -230.572182) (xy 357.126669 -230.530586) (xy 357.159304 -230.493749) (xy 357.197425 -230.462624)
			(xy 357.240046 -230.438017) (xy 357.286062 -230.420565) (xy 357.334281 -230.410721) (xy 357.383456 -230.40874)
			(xy 357.432311 -230.414672) (xy 357.479582 -230.428364) (xy 357.524044 -230.449462) (xy 357.564547 -230.477418)
			(xy 357.60004 -230.51151) (xy 357.629605 -230.550854) (xy 357.652476 -230.594431) (xy 357.66806 -230.641112)
			(xy 357.675955 -230.689689) (xy 357.67645 -230.714296) (xy 358.005392 -230.714296) (xy 358.009352 -230.665242)
			(xy 358.021129 -230.617458) (xy 358.04042 -230.572182) (xy 358.066723 -230.530586) (xy 358.099358 -230.493749)
			(xy 358.137479 -230.462624) (xy 358.1801 -230.438017) (xy 358.226116 -230.420565) (xy 358.274335 -230.410721)
			(xy 358.32351 -230.40874) (xy 358.372365 -230.414672) (xy 358.419636 -230.428364) (xy 358.464098 -230.449462)
			(xy 358.504601 -230.477418) (xy 358.540094 -230.51151) (xy 358.569659 -230.550854) (xy 358.59253 -230.594431)
			(xy 358.608114 -230.641112) (xy 358.616009 -230.689689) (xy 358.616504 -230.714296) (xy 358.616009 -230.738903)
			(xy 358.608114 -230.78748) (xy 358.59253 -230.834161) (xy 358.569659 -230.877738) (xy 358.540094 -230.917082)
			(xy 358.504601 -230.951174) (xy 358.464098 -230.97913) (xy 358.419636 -231.000228) (xy 358.372365 -231.01392)
			(xy 358.32351 -231.019852) (xy 358.274335 -231.017871) (xy 358.226116 -231.008027) (xy 358.1801 -230.990575)
			(xy 358.137479 -230.965968) (xy 358.099358 -230.934843) (xy 358.066723 -230.898006) (xy 358.04042 -230.85641)
			(xy 358.021129 -230.811134) (xy 358.009352 -230.76335) (xy 358.005392 -230.714296) (xy 357.67645 -230.714296)
			(xy 357.675955 -230.738903) (xy 357.66806 -230.78748) (xy 357.652476 -230.834161) (xy 357.629605 -230.877738)
			(xy 357.60004 -230.917082) (xy 357.564547 -230.951174) (xy 357.524044 -230.97913) (xy 357.479582 -231.000228)
			(xy 357.432311 -231.01392) (xy 357.383456 -231.019852) (xy 357.334281 -231.017871) (xy 357.286062 -231.008027)
			(xy 357.240046 -230.990575) (xy 357.197425 -230.965968) (xy 357.159304 -230.934843) (xy 357.126669 -230.898006)
			(xy 357.100366 -230.85641) (xy 357.081075 -230.811134) (xy 357.069298 -230.76335) (xy 357.065338 -230.714296)
			(xy 356.736396 -230.714296) (xy 356.735901 -230.738903) (xy 356.728006 -230.78748) (xy 356.712422 -230.834161)
			(xy 356.689551 -230.877738) (xy 356.659986 -230.917082) (xy 356.624493 -230.951174) (xy 356.58399 -230.97913)
			(xy 356.539528 -231.000228) (xy 356.492257 -231.01392) (xy 356.443402 -231.019852) (xy 356.394227 -231.017871)
			(xy 356.346008 -231.008027) (xy 356.299992 -230.990575) (xy 356.257371 -230.965968) (xy 356.21925 -230.934843)
			(xy 356.186615 -230.898006) (xy 356.160312 -230.85641) (xy 356.141021 -230.811134) (xy 356.129244 -230.76335)
			(xy 356.125284 -230.714296) (xy 355.796342 -230.714296) (xy 355.795847 -230.738903) (xy 355.787952 -230.78748)
			(xy 355.772368 -230.834161) (xy 355.749497 -230.877738) (xy 355.719932 -230.917082) (xy 355.684439 -230.951174)
			(xy 355.643936 -230.97913) (xy 355.599474 -231.000228) (xy 355.552203 -231.01392) (xy 355.503348 -231.019852)
			(xy 355.454173 -231.017871) (xy 355.405954 -231.008027) (xy 355.359938 -230.990575) (xy 355.317317 -230.965968)
			(xy 355.279196 -230.934843) (xy 355.246561 -230.898006) (xy 355.220258 -230.85641) (xy 355.200967 -230.811134)
			(xy 355.18919 -230.76335) (xy 355.18523 -230.714296) (xy 352.976434 -230.714296) (xy 352.975939 -230.738903)
			(xy 352.968044 -230.78748) (xy 352.95246 -230.834161) (xy 352.929589 -230.877738) (xy 352.900024 -230.917082)
			(xy 352.864531 -230.951174) (xy 352.824028 -230.97913) (xy 352.779566 -231.000228) (xy 352.732295 -231.01392)
			(xy 352.68344 -231.019852) (xy 352.634265 -231.017871) (xy 352.586046 -231.008027) (xy 352.54003 -230.990575)
			(xy 352.497409 -230.965968) (xy 352.459288 -230.934843) (xy 352.426653 -230.898006) (xy 352.40035 -230.85641)
			(xy 352.381059 -230.811134) (xy 352.369282 -230.76335) (xy 352.365322 -230.714296) (xy 350.156526 -230.714296)
			(xy 350.156031 -230.738903) (xy 350.148136 -230.78748) (xy 350.132552 -230.834161) (xy 350.109681 -230.877738)
			(xy 350.080116 -230.917082) (xy 350.044623 -230.951174) (xy 350.00412 -230.97913) (xy 349.959658 -231.000228)
			(xy 349.912387 -231.01392) (xy 349.863532 -231.019852) (xy 349.814357 -231.017871) (xy 349.766138 -231.008027)
			(xy 349.720122 -230.990575) (xy 349.677501 -230.965968) (xy 349.63938 -230.934843) (xy 349.606745 -230.898006)
			(xy 349.580442 -230.85641) (xy 349.561151 -230.811134) (xy 349.549374 -230.76335) (xy 349.545414 -230.714296)
			(xy 347.336364 -230.714296) (xy 347.335869 -230.738903) (xy 347.327974 -230.78748) (xy 347.31239 -230.834161)
			(xy 347.289519 -230.877738) (xy 347.259954 -230.917082) (xy 347.224461 -230.951174) (xy 347.183958 -230.97913)
			(xy 347.139496 -231.000228) (xy 347.092225 -231.01392) (xy 347.04337 -231.019852) (xy 346.994195 -231.017871)
			(xy 346.945976 -231.008027) (xy 346.89996 -230.990575) (xy 346.857339 -230.965968) (xy 346.819218 -230.934843)
			(xy 346.786583 -230.898006) (xy 346.76028 -230.85641) (xy 346.740989 -230.811134) (xy 346.729212 -230.76335)
			(xy 346.725252 -230.714296) (xy 344.626438 -230.714296) (xy 344.626438 -231.146858) (xy 344.626872 -231.156923)
			(xy 344.634606 -231.175508) (xy 344.641424 -231.182926) (xy 344.663268 -231.204516) (xy 344.670186 -231.210786)
			(xy 344.68725 -231.218325) (xy 344.696542 -231.219248) (xy 344.720909 -231.220972) (xy 344.768672 -231.231199)
			(xy 344.814197 -231.248905) (xy 344.856319 -231.273637) (xy 344.893964 -231.304763) (xy 344.926169 -231.341488)
			(xy 344.952113 -231.382875) (xy 344.971132 -231.427866) (xy 344.982742 -231.475312) (xy 344.986645 -231.524002)
			(xy 344.986641 -231.524048) (xy 345.315298 -231.524048) (xy 345.319258 -231.474994) (xy 345.331035 -231.42721)
			(xy 345.350326 -231.381934) (xy 345.376629 -231.340338) (xy 345.409264 -231.303501) (xy 345.447385 -231.272376)
			(xy 345.490006 -231.247769) (xy 345.536022 -231.230317) (xy 345.584241 -231.220473) (xy 345.633416 -231.218492)
			(xy 345.682271 -231.224424) (xy 345.729542 -231.238116) (xy 345.774004 -231.259214) (xy 345.814507 -231.28717)
			(xy 345.85 -231.321262) (xy 345.879565 -231.360606) (xy 345.902436 -231.404183) (xy 345.91802 -231.450864)
			(xy 345.925915 -231.499441) (xy 345.92641 -231.524048) (xy 346.255352 -231.524048) (xy 346.259312 -231.474994)
			(xy 346.271089 -231.42721) (xy 346.29038 -231.381934) (xy 346.316683 -231.340338) (xy 346.349318 -231.303501)
			(xy 346.387439 -231.272376) (xy 346.43006 -231.247769) (xy 346.476076 -231.230317) (xy 346.524295 -231.220473)
			(xy 346.57347 -231.218492) (xy 346.622325 -231.224424) (xy 346.669596 -231.238116) (xy 346.714058 -231.259214)
			(xy 346.754561 -231.28717) (xy 346.790054 -231.321262) (xy 346.819619 -231.360606) (xy 346.84249 -231.404183)
			(xy 346.858074 -231.450864) (xy 346.865969 -231.499441) (xy 346.866464 -231.524048) (xy 347.195406 -231.524048)
			(xy 347.199366 -231.474994) (xy 347.211143 -231.42721) (xy 347.230434 -231.381934) (xy 347.256737 -231.340338)
			(xy 347.289372 -231.303501) (xy 347.327493 -231.272376) (xy 347.370114 -231.247769) (xy 347.41613 -231.230317)
			(xy 347.464349 -231.220473) (xy 347.513524 -231.218492) (xy 347.562379 -231.224424) (xy 347.60965 -231.238116)
			(xy 347.654112 -231.259214) (xy 347.694615 -231.28717) (xy 347.730108 -231.321262) (xy 347.759673 -231.360606)
			(xy 347.782544 -231.404183) (xy 347.798128 -231.450864) (xy 347.806023 -231.499441) (xy 347.806518 -231.524048)
			(xy 348.135206 -231.524048) (xy 348.139166 -231.474994) (xy 348.150943 -231.42721) (xy 348.170234 -231.381934)
			(xy 348.196537 -231.340338) (xy 348.229172 -231.303501) (xy 348.267293 -231.272376) (xy 348.309914 -231.247769)
			(xy 348.35593 -231.230317) (xy 348.404149 -231.220473) (xy 348.453324 -231.218492) (xy 348.502179 -231.224424)
			(xy 348.54945 -231.238116) (xy 348.593912 -231.259214) (xy 348.634415 -231.28717) (xy 348.669908 -231.321262)
			(xy 348.699473 -231.360606) (xy 348.722344 -231.404183) (xy 348.737928 -231.450864) (xy 348.745823 -231.499441)
			(xy 348.746318 -231.524048) (xy 349.07526 -231.524048) (xy 349.07922 -231.474994) (xy 349.090997 -231.42721)
			(xy 349.110288 -231.381934) (xy 349.136591 -231.340338) (xy 349.169226 -231.303501) (xy 349.207347 -231.272376)
			(xy 349.249968 -231.247769) (xy 349.295984 -231.230317) (xy 349.344203 -231.220473) (xy 349.393378 -231.218492)
			(xy 349.442233 -231.224424) (xy 349.489504 -231.238116) (xy 349.533966 -231.259214) (xy 349.574469 -231.28717)
			(xy 349.609962 -231.321262) (xy 349.639527 -231.360606) (xy 349.662398 -231.404183) (xy 349.677982 -231.450864)
			(xy 349.685877 -231.499441) (xy 349.686372 -231.524048) (xy 350.015314 -231.524048) (xy 350.019274 -231.474994)
			(xy 350.031051 -231.42721) (xy 350.050342 -231.381934) (xy 350.076645 -231.340338) (xy 350.10928 -231.303501)
			(xy 350.147401 -231.272376) (xy 350.190022 -231.247769) (xy 350.236038 -231.230317) (xy 350.284257 -231.220473)
			(xy 350.333432 -231.218492) (xy 350.382287 -231.224424) (xy 350.429558 -231.238116) (xy 350.47402 -231.259214)
			(xy 350.514523 -231.28717) (xy 350.550016 -231.321262) (xy 350.579581 -231.360606) (xy 350.602452 -231.404183)
			(xy 350.618036 -231.450864) (xy 350.625931 -231.499441) (xy 350.626426 -231.524048) (xy 350.955368 -231.524048)
			(xy 350.959328 -231.474994) (xy 350.971105 -231.42721) (xy 350.990396 -231.381934) (xy 351.016699 -231.340338)
			(xy 351.049334 -231.303501) (xy 351.087455 -231.272376) (xy 351.130076 -231.247769) (xy 351.176092 -231.230317)
			(xy 351.224311 -231.220473) (xy 351.273486 -231.218492) (xy 351.322341 -231.224424) (xy 351.369612 -231.238116)
			(xy 351.414074 -231.259214) (xy 351.454577 -231.28717) (xy 351.49007 -231.321262) (xy 351.519635 -231.360606)
			(xy 351.542506 -231.404183) (xy 351.55809 -231.450864) (xy 351.565985 -231.499441) (xy 351.56648 -231.524048)
			(xy 351.895422 -231.524048) (xy 351.899382 -231.474994) (xy 351.911159 -231.42721) (xy 351.93045 -231.381934)
			(xy 351.956753 -231.340338) (xy 351.989388 -231.303501) (xy 352.027509 -231.272376) (xy 352.07013 -231.247769)
			(xy 352.116146 -231.230317) (xy 352.164365 -231.220473) (xy 352.21354 -231.218492) (xy 352.262395 -231.224424)
			(xy 352.309666 -231.238116) (xy 352.354128 -231.259214) (xy 352.394631 -231.28717) (xy 352.430124 -231.321262)
			(xy 352.459689 -231.360606) (xy 352.48256 -231.404183) (xy 352.498144 -231.450864) (xy 352.506039 -231.499441)
			(xy 352.506534 -231.524048) (xy 352.835222 -231.524048) (xy 352.839182 -231.474994) (xy 352.850959 -231.42721)
			(xy 352.87025 -231.381934) (xy 352.896553 -231.340338) (xy 352.929188 -231.303501) (xy 352.967309 -231.272376)
			(xy 353.00993 -231.247769) (xy 353.055946 -231.230317) (xy 353.104165 -231.220473) (xy 353.15334 -231.218492)
			(xy 353.202195 -231.224424) (xy 353.249466 -231.238116) (xy 353.293928 -231.259214) (xy 353.334431 -231.28717)
			(xy 353.369924 -231.321262) (xy 353.399489 -231.360606) (xy 353.42236 -231.404183) (xy 353.437944 -231.450864)
			(xy 353.445839 -231.499441) (xy 353.446334 -231.524048) (xy 353.775276 -231.524048) (xy 353.779236 -231.474994)
			(xy 353.791013 -231.42721) (xy 353.810304 -231.381934) (xy 353.836607 -231.340338) (xy 353.869242 -231.303501)
			(xy 353.907363 -231.272376) (xy 353.949984 -231.247769) (xy 353.996 -231.230317) (xy 354.044219 -231.220473)
			(xy 354.093394 -231.218492) (xy 354.142249 -231.224424) (xy 354.18952 -231.238116) (xy 354.233982 -231.259214)
			(xy 354.274485 -231.28717) (xy 354.309978 -231.321262) (xy 354.339543 -231.360606) (xy 354.362414 -231.404183)
			(xy 354.377998 -231.450864) (xy 354.385893 -231.499441) (xy 354.386388 -231.524048) (xy 354.71533 -231.524048)
			(xy 354.71929 -231.474994) (xy 354.731067 -231.42721) (xy 354.750358 -231.381934) (xy 354.776661 -231.340338)
			(xy 354.809296 -231.303501) (xy 354.847417 -231.272376) (xy 354.890038 -231.247769) (xy 354.936054 -231.230317)
			(xy 354.984273 -231.220473) (xy 355.033448 -231.218492) (xy 355.082303 -231.224424) (xy 355.129574 -231.238116)
			(xy 355.174036 -231.259214) (xy 355.214539 -231.28717) (xy 355.250032 -231.321262) (xy 355.279597 -231.360606)
			(xy 355.302468 -231.404183) (xy 355.318052 -231.450864) (xy 355.325947 -231.499441) (xy 355.326442 -231.524048)
			(xy 355.655384 -231.524048) (xy 355.659344 -231.474994) (xy 355.671121 -231.42721) (xy 355.690412 -231.381934)
			(xy 355.716715 -231.340338) (xy 355.74935 -231.303501) (xy 355.787471 -231.272376) (xy 355.830092 -231.247769)
			(xy 355.876108 -231.230317) (xy 355.924327 -231.220473) (xy 355.973502 -231.218492) (xy 356.022357 -231.224424)
			(xy 356.069628 -231.238116) (xy 356.11409 -231.259214) (xy 356.154593 -231.28717) (xy 356.190086 -231.321262)
			(xy 356.219651 -231.360606) (xy 356.242522 -231.404183) (xy 356.258106 -231.450864) (xy 356.266001 -231.499441)
			(xy 356.266496 -231.524048) (xy 356.266001 -231.548655) (xy 356.258106 -231.597232) (xy 356.242522 -231.643913)
			(xy 356.219651 -231.68749) (xy 356.190086 -231.726834) (xy 356.154593 -231.760926) (xy 356.11409 -231.788882)
			(xy 356.069628 -231.80998) (xy 356.022357 -231.823672) (xy 355.973502 -231.829604) (xy 355.924327 -231.827623)
			(xy 355.876108 -231.817779) (xy 355.830092 -231.800327) (xy 355.787471 -231.77572) (xy 355.74935 -231.744595)
			(xy 355.716715 -231.707758) (xy 355.690412 -231.666162) (xy 355.671121 -231.620886) (xy 355.659344 -231.573102)
			(xy 355.655384 -231.524048) (xy 355.326442 -231.524048) (xy 355.325947 -231.548655) (xy 355.318052 -231.597232)
			(xy 355.302468 -231.643913) (xy 355.279597 -231.68749) (xy 355.250032 -231.726834) (xy 355.214539 -231.760926)
			(xy 355.174036 -231.788882) (xy 355.129574 -231.80998) (xy 355.082303 -231.823672) (xy 355.033448 -231.829604)
			(xy 354.984273 -231.827623) (xy 354.936054 -231.817779) (xy 354.890038 -231.800327) (xy 354.847417 -231.77572)
			(xy 354.809296 -231.744595) (xy 354.776661 -231.707758) (xy 354.750358 -231.666162) (xy 354.731067 -231.620886)
			(xy 354.71929 -231.573102) (xy 354.71533 -231.524048) (xy 354.386388 -231.524048) (xy 354.385893 -231.548655)
			(xy 354.377998 -231.597232) (xy 354.362414 -231.643913) (xy 354.339543 -231.68749) (xy 354.309978 -231.726834)
			(xy 354.274485 -231.760926) (xy 354.233982 -231.788882) (xy 354.18952 -231.80998) (xy 354.142249 -231.823672)
			(xy 354.093394 -231.829604) (xy 354.044219 -231.827623) (xy 353.996 -231.817779) (xy 353.949984 -231.800327)
			(xy 353.907363 -231.77572) (xy 353.869242 -231.744595) (xy 353.836607 -231.707758) (xy 353.810304 -231.666162)
			(xy 353.791013 -231.620886) (xy 353.779236 -231.573102) (xy 353.775276 -231.524048) (xy 353.446334 -231.524048)
			(xy 353.445839 -231.548655) (xy 353.437944 -231.597232) (xy 353.42236 -231.643913) (xy 353.399489 -231.68749)
			(xy 353.369924 -231.726834) (xy 353.334431 -231.760926) (xy 353.293928 -231.788882) (xy 353.249466 -231.80998)
			(xy 353.202195 -231.823672) (xy 353.15334 -231.829604) (xy 353.104165 -231.827623) (xy 353.055946 -231.817779)
			(xy 353.00993 -231.800327) (xy 352.967309 -231.77572) (xy 352.929188 -231.744595) (xy 352.896553 -231.707758)
			(xy 352.87025 -231.666162) (xy 352.850959 -231.620886) (xy 352.839182 -231.573102) (xy 352.835222 -231.524048)
			(xy 352.506534 -231.524048) (xy 352.506039 -231.548655) (xy 352.498144 -231.597232) (xy 352.48256 -231.643913)
			(xy 352.459689 -231.68749) (xy 352.430124 -231.726834) (xy 352.394631 -231.760926) (xy 352.354128 -231.788882)
			(xy 352.309666 -231.80998) (xy 352.262395 -231.823672) (xy 352.21354 -231.829604) (xy 352.164365 -231.827623)
			(xy 352.116146 -231.817779) (xy 352.07013 -231.800327) (xy 352.027509 -231.77572) (xy 351.989388 -231.744595)
			(xy 351.956753 -231.707758) (xy 351.93045 -231.666162) (xy 351.911159 -231.620886) (xy 351.899382 -231.573102)
			(xy 351.895422 -231.524048) (xy 351.56648 -231.524048) (xy 351.565985 -231.548655) (xy 351.55809 -231.597232)
			(xy 351.542506 -231.643913) (xy 351.519635 -231.68749) (xy 351.49007 -231.726834) (xy 351.454577 -231.760926)
			(xy 351.414074 -231.788882) (xy 351.369612 -231.80998) (xy 351.322341 -231.823672) (xy 351.273486 -231.829604)
			(xy 351.224311 -231.827623) (xy 351.176092 -231.817779) (xy 351.130076 -231.800327) (xy 351.087455 -231.77572)
			(xy 351.049334 -231.744595) (xy 351.016699 -231.707758) (xy 350.990396 -231.666162) (xy 350.971105 -231.620886)
			(xy 350.959328 -231.573102) (xy 350.955368 -231.524048) (xy 350.626426 -231.524048) (xy 350.625931 -231.548655)
			(xy 350.618036 -231.597232) (xy 350.602452 -231.643913) (xy 350.579581 -231.68749) (xy 350.550016 -231.726834)
			(xy 350.514523 -231.760926) (xy 350.47402 -231.788882) (xy 350.429558 -231.80998) (xy 350.382287 -231.823672)
			(xy 350.333432 -231.829604) (xy 350.284257 -231.827623) (xy 350.236038 -231.817779) (xy 350.190022 -231.800327)
			(xy 350.147401 -231.77572) (xy 350.10928 -231.744595) (xy 350.076645 -231.707758) (xy 350.050342 -231.666162)
			(xy 350.031051 -231.620886) (xy 350.019274 -231.573102) (xy 350.015314 -231.524048) (xy 349.686372 -231.524048)
			(xy 349.685877 -231.548655) (xy 349.677982 -231.597232) (xy 349.662398 -231.643913) (xy 349.639527 -231.68749)
			(xy 349.609962 -231.726834) (xy 349.574469 -231.760926) (xy 349.533966 -231.788882) (xy 349.489504 -231.80998)
			(xy 349.442233 -231.823672) (xy 349.393378 -231.829604) (xy 349.344203 -231.827623) (xy 349.295984 -231.817779)
			(xy 349.249968 -231.800327) (xy 349.207347 -231.77572) (xy 349.169226 -231.744595) (xy 349.136591 -231.707758)
			(xy 349.110288 -231.666162) (xy 349.090997 -231.620886) (xy 349.07922 -231.573102) (xy 349.07526 -231.524048)
			(xy 348.746318 -231.524048) (xy 348.745823 -231.548655) (xy 348.737928 -231.597232) (xy 348.722344 -231.643913)
			(xy 348.699473 -231.68749) (xy 348.669908 -231.726834) (xy 348.634415 -231.760926) (xy 348.593912 -231.788882)
			(xy 348.54945 -231.80998) (xy 348.502179 -231.823672) (xy 348.453324 -231.829604) (xy 348.404149 -231.827623)
			(xy 348.35593 -231.817779) (xy 348.309914 -231.800327) (xy 348.267293 -231.77572) (xy 348.229172 -231.744595)
			(xy 348.196537 -231.707758) (xy 348.170234 -231.666162) (xy 348.150943 -231.620886) (xy 348.139166 -231.573102)
			(xy 348.135206 -231.524048) (xy 347.806518 -231.524048) (xy 347.806023 -231.548655) (xy 347.798128 -231.597232)
			(xy 347.782544 -231.643913) (xy 347.759673 -231.68749) (xy 347.730108 -231.726834) (xy 347.694615 -231.760926)
			(xy 347.654112 -231.788882) (xy 347.60965 -231.80998) (xy 347.562379 -231.823672) (xy 347.513524 -231.829604)
			(xy 347.464349 -231.827623) (xy 347.41613 -231.817779) (xy 347.370114 -231.800327) (xy 347.327493 -231.77572)
			(xy 347.289372 -231.744595) (xy 347.256737 -231.707758) (xy 347.230434 -231.666162) (xy 347.211143 -231.620886)
			(xy 347.199366 -231.573102) (xy 347.195406 -231.524048) (xy 346.866464 -231.524048) (xy 346.865969 -231.548655)
			(xy 346.858074 -231.597232) (xy 346.84249 -231.643913) (xy 346.819619 -231.68749) (xy 346.790054 -231.726834)
			(xy 346.754561 -231.760926) (xy 346.714058 -231.788882) (xy 346.669596 -231.80998) (xy 346.622325 -231.823672)
			(xy 346.57347 -231.829604) (xy 346.524295 -231.827623) (xy 346.476076 -231.817779) (xy 346.43006 -231.800327)
			(xy 346.387439 -231.77572) (xy 346.349318 -231.744595) (xy 346.316683 -231.707758) (xy 346.29038 -231.666162)
			(xy 346.271089 -231.620886) (xy 346.259312 -231.573102) (xy 346.255352 -231.524048) (xy 345.92641 -231.524048)
			(xy 345.925915 -231.548655) (xy 345.91802 -231.597232) (xy 345.902436 -231.643913) (xy 345.879565 -231.68749)
			(xy 345.85 -231.726834) (xy 345.814507 -231.760926) (xy 345.774004 -231.788882) (xy 345.729542 -231.80998)
			(xy 345.682271 -231.823672) (xy 345.633416 -231.829604) (xy 345.584241 -231.827623) (xy 345.536022 -231.817779)
			(xy 345.490006 -231.800327) (xy 345.447385 -231.77572) (xy 345.409264 -231.744595) (xy 345.376629 -231.707758)
			(xy 345.350326 -231.666162) (xy 345.331035 -231.620886) (xy 345.319258 -231.573102) (xy 345.315298 -231.524048)
			(xy 344.986641 -231.524048) (xy 344.982741 -231.572692) (xy 344.971131 -231.620139) (xy 344.952111 -231.66513)
			(xy 344.926166 -231.706516) (xy 344.89396 -231.743241) (xy 344.856315 -231.774366) (xy 344.814192 -231.799097)
			(xy 344.768668 -231.816802) (xy 344.720904 -231.827028) (xy 344.696542 -231.828848) (xy 344.687238 -231.829723)
			(xy 344.670163 -231.837274) (xy 344.663268 -231.84358) (xy 344.641424 -231.86517) (xy 344.634586 -231.872571)
			(xy 344.626873 -231.89117) (xy 344.626438 -231.901238) (xy 344.626438 -232.334054) (xy 344.845398 -232.334054)
			(xy 344.849358 -232.285) (xy 344.861135 -232.237216) (xy 344.880426 -232.19194) (xy 344.906729 -232.150344)
			(xy 344.939364 -232.113507) (xy 344.977485 -232.082382) (xy 345.020106 -232.057775) (xy 345.066122 -232.040323)
			(xy 345.114341 -232.030479) (xy 345.163516 -232.028498) (xy 345.212371 -232.03443) (xy 345.259642 -232.048122)
			(xy 345.304104 -232.06922) (xy 345.344607 -232.097176) (xy 345.3801 -232.131268) (xy 345.409665 -232.170612)
			(xy 345.432536 -232.214189) (xy 345.44812 -232.26087) (xy 345.456015 -232.309447) (xy 345.45651 -232.334054)
			(xy 345.785198 -232.334054) (xy 345.789158 -232.285) (xy 345.800935 -232.237216) (xy 345.820226 -232.19194)
			(xy 345.846529 -232.150344) (xy 345.879164 -232.113507) (xy 345.917285 -232.082382) (xy 345.959906 -232.057775)
			(xy 346.005922 -232.040323) (xy 346.054141 -232.030479) (xy 346.103316 -232.028498) (xy 346.152171 -232.03443)
			(xy 346.199442 -232.048122) (xy 346.243904 -232.06922) (xy 346.284407 -232.097176) (xy 346.3199 -232.131268)
			(xy 346.349465 -232.170612) (xy 346.372336 -232.214189) (xy 346.38792 -232.26087) (xy 346.395815 -232.309447)
			(xy 346.39631 -232.334054) (xy 346.725252 -232.334054) (xy 346.729212 -232.285) (xy 346.740989 -232.237216)
			(xy 346.76028 -232.19194) (xy 346.786583 -232.150344) (xy 346.819218 -232.113507) (xy 346.857339 -232.082382)
			(xy 346.89996 -232.057775) (xy 346.945976 -232.040323) (xy 346.994195 -232.030479) (xy 347.04337 -232.028498)
			(xy 347.092225 -232.03443) (xy 347.139496 -232.048122) (xy 347.183958 -232.06922) (xy 347.224461 -232.097176)
			(xy 347.259954 -232.131268) (xy 347.289519 -232.170612) (xy 347.31239 -232.214189) (xy 347.327974 -232.26087)
			(xy 347.335869 -232.309447) (xy 347.336364 -232.334054) (xy 347.665306 -232.334054) (xy 347.669266 -232.285)
			(xy 347.681043 -232.237216) (xy 347.700334 -232.19194) (xy 347.726637 -232.150344) (xy 347.759272 -232.113507)
			(xy 347.797393 -232.082382) (xy 347.840014 -232.057775) (xy 347.88603 -232.040323) (xy 347.934249 -232.030479)
			(xy 347.983424 -232.028498) (xy 348.032279 -232.03443) (xy 348.07955 -232.048122) (xy 348.124012 -232.06922)
			(xy 348.164515 -232.097176) (xy 348.200008 -232.131268) (xy 348.229573 -232.170612) (xy 348.252444 -232.214189)
			(xy 348.268028 -232.26087) (xy 348.275923 -232.309447) (xy 348.276418 -232.334054) (xy 348.60536 -232.334054)
			(xy 348.60932 -232.285) (xy 348.621097 -232.237216) (xy 348.640388 -232.19194) (xy 348.666691 -232.150344)
			(xy 348.699326 -232.113507) (xy 348.737447 -232.082382) (xy 348.780068 -232.057775) (xy 348.826084 -232.040323)
			(xy 348.874303 -232.030479) (xy 348.923478 -232.028498) (xy 348.972333 -232.03443) (xy 349.019604 -232.048122)
			(xy 349.064066 -232.06922) (xy 349.104569 -232.097176) (xy 349.140062 -232.131268) (xy 349.169627 -232.170612)
			(xy 349.192498 -232.214189) (xy 349.208082 -232.26087) (xy 349.215977 -232.309447) (xy 349.216472 -232.334054)
			(xy 349.545414 -232.334054) (xy 349.549374 -232.285) (xy 349.561151 -232.237216) (xy 349.580442 -232.19194)
			(xy 349.606745 -232.150344) (xy 349.63938 -232.113507) (xy 349.677501 -232.082382) (xy 349.720122 -232.057775)
			(xy 349.766138 -232.040323) (xy 349.814357 -232.030479) (xy 349.863532 -232.028498) (xy 349.912387 -232.03443)
			(xy 349.959658 -232.048122) (xy 350.00412 -232.06922) (xy 350.044623 -232.097176) (xy 350.080116 -232.131268)
			(xy 350.109681 -232.170612) (xy 350.132552 -232.214189) (xy 350.148136 -232.26087) (xy 350.156031 -232.309447)
			(xy 350.156526 -232.334054) (xy 350.485214 -232.334054) (xy 350.489174 -232.285) (xy 350.500951 -232.237216)
			(xy 350.520242 -232.19194) (xy 350.546545 -232.150344) (xy 350.57918 -232.113507) (xy 350.617301 -232.082382)
			(xy 350.659922 -232.057775) (xy 350.705938 -232.040323) (xy 350.754157 -232.030479) (xy 350.803332 -232.028498)
			(xy 350.852187 -232.03443) (xy 350.899458 -232.048122) (xy 350.94392 -232.06922) (xy 350.984423 -232.097176)
			(xy 351.019916 -232.131268) (xy 351.049481 -232.170612) (xy 351.072352 -232.214189) (xy 351.087936 -232.26087)
			(xy 351.095831 -232.309447) (xy 351.096326 -232.334054) (xy 351.425268 -232.334054) (xy 351.429228 -232.285)
			(xy 351.441005 -232.237216) (xy 351.460296 -232.19194) (xy 351.486599 -232.150344) (xy 351.519234 -232.113507)
			(xy 351.557355 -232.082382) (xy 351.599976 -232.057775) (xy 351.645992 -232.040323) (xy 351.694211 -232.030479)
			(xy 351.743386 -232.028498) (xy 351.792241 -232.03443) (xy 351.839512 -232.048122) (xy 351.883974 -232.06922)
			(xy 351.924477 -232.097176) (xy 351.95997 -232.131268) (xy 351.989535 -232.170612) (xy 352.012406 -232.214189)
			(xy 352.02799 -232.26087) (xy 352.035885 -232.309447) (xy 352.03638 -232.334054) (xy 352.365322 -232.334054)
			(xy 352.369282 -232.285) (xy 352.381059 -232.237216) (xy 352.40035 -232.19194) (xy 352.426653 -232.150344)
			(xy 352.459288 -232.113507) (xy 352.497409 -232.082382) (xy 352.54003 -232.057775) (xy 352.586046 -232.040323)
			(xy 352.634265 -232.030479) (xy 352.68344 -232.028498) (xy 352.732295 -232.03443) (xy 352.779566 -232.048122)
			(xy 352.824028 -232.06922) (xy 352.864531 -232.097176) (xy 352.900024 -232.131268) (xy 352.929589 -232.170612)
			(xy 352.95246 -232.214189) (xy 352.968044 -232.26087) (xy 352.975939 -232.309447) (xy 352.976434 -232.334054)
			(xy 353.305376 -232.334054) (xy 353.309336 -232.285) (xy 353.321113 -232.237216) (xy 353.340404 -232.19194)
			(xy 353.366707 -232.150344) (xy 353.399342 -232.113507) (xy 353.437463 -232.082382) (xy 353.480084 -232.057775)
			(xy 353.5261 -232.040323) (xy 353.574319 -232.030479) (xy 353.623494 -232.028498) (xy 353.672349 -232.03443)
			(xy 353.71962 -232.048122) (xy 353.764082 -232.06922) (xy 353.804585 -232.097176) (xy 353.840078 -232.131268)
			(xy 353.869643 -232.170612) (xy 353.892514 -232.214189) (xy 353.908098 -232.26087) (xy 353.915993 -232.309447)
			(xy 353.916488 -232.334054) (xy 354.24543 -232.334054) (xy 354.24939 -232.285) (xy 354.261167 -232.237216)
			(xy 354.280458 -232.19194) (xy 354.306761 -232.150344) (xy 354.339396 -232.113507) (xy 354.377517 -232.082382)
			(xy 354.420138 -232.057775) (xy 354.466154 -232.040323) (xy 354.514373 -232.030479) (xy 354.563548 -232.028498)
			(xy 354.612403 -232.03443) (xy 354.659674 -232.048122) (xy 354.704136 -232.06922) (xy 354.744639 -232.097176)
			(xy 354.780132 -232.131268) (xy 354.809697 -232.170612) (xy 354.832568 -232.214189) (xy 354.848152 -232.26087)
			(xy 354.856047 -232.309447) (xy 354.856542 -232.334054) (xy 355.18523 -232.334054) (xy 355.18919 -232.285)
			(xy 355.200967 -232.237216) (xy 355.220258 -232.19194) (xy 355.246561 -232.150344) (xy 355.279196 -232.113507)
			(xy 355.317317 -232.082382) (xy 355.359938 -232.057775) (xy 355.405954 -232.040323) (xy 355.454173 -232.030479)
			(xy 355.503348 -232.028498) (xy 355.552203 -232.03443) (xy 355.599474 -232.048122) (xy 355.643936 -232.06922)
			(xy 355.684439 -232.097176) (xy 355.719932 -232.131268) (xy 355.749497 -232.170612) (xy 355.772368 -232.214189)
			(xy 355.787952 -232.26087) (xy 355.795847 -232.309447) (xy 355.796342 -232.334054) (xy 356.125284 -232.334054)
			(xy 356.129244 -232.285) (xy 356.141021 -232.237216) (xy 356.160312 -232.19194) (xy 356.186615 -232.150344)
			(xy 356.21925 -232.113507) (xy 356.257371 -232.082382) (xy 356.299992 -232.057775) (xy 356.346008 -232.040323)
			(xy 356.394227 -232.030479) (xy 356.443402 -232.028498) (xy 356.492257 -232.03443) (xy 356.539528 -232.048122)
			(xy 356.58399 -232.06922) (xy 356.624493 -232.097176) (xy 356.659986 -232.131268) (xy 356.689551 -232.170612)
			(xy 356.712422 -232.214189) (xy 356.728006 -232.26087) (xy 356.735901 -232.309447) (xy 356.736396 -232.334054)
			(xy 357.065338 -232.334054) (xy 357.069298 -232.285) (xy 357.081075 -232.237216) (xy 357.100366 -232.19194)
			(xy 357.126669 -232.150344) (xy 357.159304 -232.113507) (xy 357.197425 -232.082382) (xy 357.240046 -232.057775)
			(xy 357.286062 -232.040323) (xy 357.334281 -232.030479) (xy 357.383456 -232.028498) (xy 357.432311 -232.03443)
			(xy 357.479582 -232.048122) (xy 357.524044 -232.06922) (xy 357.564547 -232.097176) (xy 357.60004 -232.131268)
			(xy 357.629605 -232.170612) (xy 357.652476 -232.214189) (xy 357.66806 -232.26087) (xy 357.675955 -232.309447)
			(xy 357.67645 -232.334054) (xy 358.005392 -232.334054) (xy 358.009352 -232.285) (xy 358.021129 -232.237216)
			(xy 358.04042 -232.19194) (xy 358.066723 -232.150344) (xy 358.099358 -232.113507) (xy 358.137479 -232.082382)
			(xy 358.1801 -232.057775) (xy 358.226116 -232.040323) (xy 358.274335 -232.030479) (xy 358.32351 -232.028498)
			(xy 358.372365 -232.03443) (xy 358.419636 -232.048122) (xy 358.464098 -232.06922) (xy 358.504601 -232.097176)
			(xy 358.540094 -232.131268) (xy 358.569659 -232.170612) (xy 358.59253 -232.214189) (xy 358.608114 -232.26087)
			(xy 358.616009 -232.309447) (xy 358.616504 -232.334054) (xy 360.81895 -232.334054) (xy 360.82291 -232.285)
			(xy 360.834687 -232.237216) (xy 360.853978 -232.19194) (xy 360.880281 -232.150344) (xy 360.912916 -232.113507)
			(xy 360.951037 -232.082382) (xy 360.993658 -232.057775) (xy 361.039674 -232.040323) (xy 361.087893 -232.030479)
			(xy 361.137068 -232.028498) (xy 361.185923 -232.03443) (xy 361.233194 -232.048122) (xy 361.277656 -232.06922)
			(xy 361.318159 -232.097176) (xy 361.353652 -232.131268) (xy 361.383217 -232.170612) (xy 361.406088 -232.214189)
			(xy 361.421672 -232.26087) (xy 361.429567 -232.309447) (xy 361.430062 -232.334054) (xy 361.430061 -232.3341)
			(xy 361.758639 -232.3341) (xy 361.762815 -232.283707) (xy 361.775229 -232.234688) (xy 361.795541 -232.188381)
			(xy 361.823198 -232.14605) (xy 361.857446 -232.108848) (xy 361.89735 -232.07779) (xy 361.941822 -232.053724)
			(xy 361.989649 -232.037306) (xy 362.039525 -232.028985) (xy 362.064808 -232.028492) (xy 363.004862 -232.028492)
			(xy 363.030139 -232.029074) (xy 363.080004 -232.037389) (xy 363.127821 -232.053799) (xy 363.172283 -232.077857)
			(xy 363.21218 -232.108905) (xy 363.246421 -232.146096) (xy 363.274073 -232.188417) (xy 363.294382 -232.234712)
			(xy 363.306793 -232.283719) (xy 363.310965 -232.334054) (xy 363.639112 -232.334054) (xy 363.643072 -232.285)
			(xy 363.654849 -232.237216) (xy 363.67414 -232.19194) (xy 363.700443 -232.150344) (xy 363.733078 -232.113507)
			(xy 363.771199 -232.082382) (xy 363.81382 -232.057775) (xy 363.859836 -232.040323) (xy 363.908055 -232.030479)
			(xy 363.95723 -232.028498) (xy 364.006085 -232.03443) (xy 364.053356 -232.048122) (xy 364.097818 -232.06922)
			(xy 364.138321 -232.097176) (xy 364.173814 -232.131268) (xy 364.203379 -232.170612) (xy 364.22625 -232.214189)
			(xy 364.241834 -232.26087) (xy 364.249729 -232.309447) (xy 364.250224 -232.334054) (xy 364.578912 -232.334054)
			(xy 364.582872 -232.285) (xy 364.594649 -232.237216) (xy 364.61394 -232.19194) (xy 364.640243 -232.150344)
			(xy 364.672878 -232.113507) (xy 364.710999 -232.082382) (xy 364.75362 -232.057775) (xy 364.799636 -232.040323)
			(xy 364.847855 -232.030479) (xy 364.89703 -232.028498) (xy 364.945885 -232.03443) (xy 364.993156 -232.048122)
			(xy 365.037618 -232.06922) (xy 365.078121 -232.097176) (xy 365.113614 -232.131268) (xy 365.143179 -232.170612)
			(xy 365.16605 -232.214189) (xy 365.181634 -232.26087) (xy 365.189529 -232.309447) (xy 365.190024 -232.334054)
			(xy 365.518966 -232.334054) (xy 365.522926 -232.285) (xy 365.534703 -232.237216) (xy 365.553994 -232.19194)
			(xy 365.580297 -232.150344) (xy 365.612932 -232.113507) (xy 365.651053 -232.082382) (xy 365.693674 -232.057775)
			(xy 365.73969 -232.040323) (xy 365.787909 -232.030479) (xy 365.837084 -232.028498) (xy 365.885939 -232.03443)
			(xy 365.93321 -232.048122) (xy 365.977672 -232.06922) (xy 366.018175 -232.097176) (xy 366.053668 -232.131268)
			(xy 366.083233 -232.170612) (xy 366.106104 -232.214189) (xy 366.121688 -232.26087) (xy 366.129583 -232.309447)
			(xy 366.130078 -232.334054) (xy 366.45902 -232.334054) (xy 366.46298 -232.285) (xy 366.474757 -232.237216)
			(xy 366.494048 -232.19194) (xy 366.520351 -232.150344) (xy 366.552986 -232.113507) (xy 366.591107 -232.082382)
			(xy 366.633728 -232.057775) (xy 366.679744 -232.040323) (xy 366.727963 -232.030479) (xy 366.777138 -232.028498)
			(xy 366.825993 -232.03443) (xy 366.873264 -232.048122) (xy 366.917726 -232.06922) (xy 366.958229 -232.097176)
			(xy 366.993722 -232.131268) (xy 367.023287 -232.170612) (xy 367.046158 -232.214189) (xy 367.061742 -232.26087)
			(xy 367.069637 -232.309447) (xy 367.070132 -232.334054) (xy 367.399074 -232.334054) (xy 367.403034 -232.285)
			(xy 367.414811 -232.237216) (xy 367.434102 -232.19194) (xy 367.460405 -232.150344) (xy 367.49304 -232.113507)
			(xy 367.531161 -232.082382) (xy 367.573782 -232.057775) (xy 367.619798 -232.040323) (xy 367.668017 -232.030479)
			(xy 367.717192 -232.028498) (xy 367.766047 -232.03443) (xy 367.813318 -232.048122) (xy 367.85778 -232.06922)
			(xy 367.898283 -232.097176) (xy 367.933776 -232.131268) (xy 367.963341 -232.170612) (xy 367.986212 -232.214189)
			(xy 368.001796 -232.26087) (xy 368.009691 -232.309447) (xy 368.010186 -232.334054) (xy 368.338874 -232.334054)
			(xy 368.342834 -232.285) (xy 368.354611 -232.237216) (xy 368.373902 -232.19194) (xy 368.400205 -232.150344)
			(xy 368.43284 -232.113507) (xy 368.470961 -232.082382) (xy 368.513582 -232.057775) (xy 368.559598 -232.040323)
			(xy 368.607817 -232.030479) (xy 368.656992 -232.028498) (xy 368.705847 -232.03443) (xy 368.753118 -232.048122)
			(xy 368.79758 -232.06922) (xy 368.838083 -232.097176) (xy 368.873576 -232.131268) (xy 368.903141 -232.170612)
			(xy 368.926012 -232.214189) (xy 368.941596 -232.26087) (xy 368.949491 -232.309447) (xy 368.949986 -232.334054)
			(xy 369.278928 -232.334054) (xy 369.282888 -232.285) (xy 369.294665 -232.237216) (xy 369.313956 -232.19194)
			(xy 369.340259 -232.150344) (xy 369.372894 -232.113507) (xy 369.411015 -232.082382) (xy 369.453636 -232.057775)
			(xy 369.499652 -232.040323) (xy 369.547871 -232.030479) (xy 369.597046 -232.028498) (xy 369.645901 -232.03443)
			(xy 369.693172 -232.048122) (xy 369.737634 -232.06922) (xy 369.778137 -232.097176) (xy 369.81363 -232.131268)
			(xy 369.843195 -232.170612) (xy 369.866066 -232.214189) (xy 369.88165 -232.26087) (xy 369.889545 -232.309447)
			(xy 369.89004 -232.334054) (xy 370.218982 -232.334054) (xy 370.222942 -232.285) (xy 370.234719 -232.237216)
			(xy 370.25401 -232.19194) (xy 370.280313 -232.150344) (xy 370.312948 -232.113507) (xy 370.351069 -232.082382)
			(xy 370.39369 -232.057775) (xy 370.439706 -232.040323) (xy 370.487925 -232.030479) (xy 370.5371 -232.028498)
			(xy 370.585955 -232.03443) (xy 370.633226 -232.048122) (xy 370.677688 -232.06922) (xy 370.718191 -232.097176)
			(xy 370.753684 -232.131268) (xy 370.783249 -232.170612) (xy 370.80612 -232.214189) (xy 370.821704 -232.26087)
			(xy 370.829599 -232.309447) (xy 370.830094 -232.334054) (xy 371.159036 -232.334054) (xy 371.162996 -232.285)
			(xy 371.174773 -232.237216) (xy 371.194064 -232.19194) (xy 371.220367 -232.150344) (xy 371.253002 -232.113507)
			(xy 371.291123 -232.082382) (xy 371.333744 -232.057775) (xy 371.37976 -232.040323) (xy 371.427979 -232.030479)
			(xy 371.477154 -232.028498) (xy 371.526009 -232.03443) (xy 371.57328 -232.048122) (xy 371.617742 -232.06922)
			(xy 371.658245 -232.097176) (xy 371.693738 -232.131268) (xy 371.723303 -232.170612) (xy 371.746174 -232.214189)
			(xy 371.761758 -232.26087) (xy 371.769653 -232.309447) (xy 371.770148 -232.334054) (xy 371.769653 -232.358661)
			(xy 371.761758 -232.407238) (xy 371.746174 -232.453919) (xy 371.723303 -232.497496) (xy 371.693738 -232.53684)
			(xy 371.658245 -232.570932) (xy 371.617742 -232.598888) (xy 371.57328 -232.619986) (xy 371.526009 -232.633678)
			(xy 371.477154 -232.63961) (xy 371.427979 -232.637629) (xy 371.37976 -232.627785) (xy 371.333744 -232.610333)
			(xy 371.291123 -232.585726) (xy 371.253002 -232.554601) (xy 371.220367 -232.517764) (xy 371.194064 -232.476168)
			(xy 371.174773 -232.430892) (xy 371.162996 -232.383108) (xy 371.159036 -232.334054) (xy 370.830094 -232.334054)
			(xy 370.829599 -232.358661) (xy 370.821704 -232.407238) (xy 370.80612 -232.453919) (xy 370.783249 -232.497496)
			(xy 370.753684 -232.53684) (xy 370.718191 -232.570932) (xy 370.677688 -232.598888) (xy 370.633226 -232.619986)
			(xy 370.585955 -232.633678) (xy 370.5371 -232.63961) (xy 370.487925 -232.637629) (xy 370.439706 -232.627785)
			(xy 370.39369 -232.610333) (xy 370.351069 -232.585726) (xy 370.312948 -232.554601) (xy 370.280313 -232.517764)
			(xy 370.25401 -232.476168) (xy 370.234719 -232.430892) (xy 370.222942 -232.383108) (xy 370.218982 -232.334054)
			(xy 369.89004 -232.334054) (xy 369.889545 -232.358661) (xy 369.88165 -232.407238) (xy 369.866066 -232.453919)
			(xy 369.843195 -232.497496) (xy 369.81363 -232.53684) (xy 369.778137 -232.570932) (xy 369.737634 -232.598888)
			(xy 369.693172 -232.619986) (xy 369.645901 -232.633678) (xy 369.597046 -232.63961) (xy 369.547871 -232.637629)
			(xy 369.499652 -232.627785) (xy 369.453636 -232.610333) (xy 369.411015 -232.585726) (xy 369.372894 -232.554601)
			(xy 369.340259 -232.517764) (xy 369.313956 -232.476168) (xy 369.294665 -232.430892) (xy 369.282888 -232.383108)
			(xy 369.278928 -232.334054) (xy 368.949986 -232.334054) (xy 368.949491 -232.358661) (xy 368.941596 -232.407238)
			(xy 368.926012 -232.453919) (xy 368.903141 -232.497496) (xy 368.873576 -232.53684) (xy 368.838083 -232.570932)
			(xy 368.79758 -232.598888) (xy 368.753118 -232.619986) (xy 368.705847 -232.633678) (xy 368.656992 -232.63961)
			(xy 368.607817 -232.637629) (xy 368.559598 -232.627785) (xy 368.513582 -232.610333) (xy 368.470961 -232.585726)
			(xy 368.43284 -232.554601) (xy 368.400205 -232.517764) (xy 368.373902 -232.476168) (xy 368.354611 -232.430892)
			(xy 368.342834 -232.383108) (xy 368.338874 -232.334054) (xy 368.010186 -232.334054) (xy 368.009691 -232.358661)
			(xy 368.001796 -232.407238) (xy 367.986212 -232.453919) (xy 367.963341 -232.497496) (xy 367.933776 -232.53684)
			(xy 367.898283 -232.570932) (xy 367.85778 -232.598888) (xy 367.813318 -232.619986) (xy 367.766047 -232.633678)
			(xy 367.717192 -232.63961) (xy 367.668017 -232.637629) (xy 367.619798 -232.627785) (xy 367.573782 -232.610333)
			(xy 367.531161 -232.585726) (xy 367.49304 -232.554601) (xy 367.460405 -232.517764) (xy 367.434102 -232.476168)
			(xy 367.414811 -232.430892) (xy 367.403034 -232.383108) (xy 367.399074 -232.334054) (xy 367.070132 -232.334054)
			(xy 367.069637 -232.358661) (xy 367.061742 -232.407238) (xy 367.046158 -232.453919) (xy 367.023287 -232.497496)
			(xy 366.993722 -232.53684) (xy 366.958229 -232.570932) (xy 366.917726 -232.598888) (xy 366.873264 -232.619986)
			(xy 366.825993 -232.633678) (xy 366.777138 -232.63961) (xy 366.727963 -232.637629) (xy 366.679744 -232.627785)
			(xy 366.633728 -232.610333) (xy 366.591107 -232.585726) (xy 366.552986 -232.554601) (xy 366.520351 -232.517764)
			(xy 366.494048 -232.476168) (xy 366.474757 -232.430892) (xy 366.46298 -232.383108) (xy 366.45902 -232.334054)
			(xy 366.130078 -232.334054) (xy 366.129583 -232.358661) (xy 366.121688 -232.407238) (xy 366.106104 -232.453919)
			(xy 366.083233 -232.497496) (xy 366.053668 -232.53684) (xy 366.018175 -232.570932) (xy 365.977672 -232.598888)
			(xy 365.93321 -232.619986) (xy 365.885939 -232.633678) (xy 365.837084 -232.63961) (xy 365.787909 -232.637629)
			(xy 365.73969 -232.627785) (xy 365.693674 -232.610333) (xy 365.651053 -232.585726) (xy 365.612932 -232.554601)
			(xy 365.580297 -232.517764) (xy 365.553994 -232.476168) (xy 365.534703 -232.430892) (xy 365.522926 -232.383108)
			(xy 365.518966 -232.334054) (xy 365.190024 -232.334054) (xy 365.189529 -232.358661) (xy 365.181634 -232.407238)
			(xy 365.16605 -232.453919) (xy 365.143179 -232.497496) (xy 365.113614 -232.53684) (xy 365.078121 -232.570932)
			(xy 365.037618 -232.598888) (xy 364.993156 -232.619986) (xy 364.945885 -232.633678) (xy 364.89703 -232.63961)
			(xy 364.847855 -232.637629) (xy 364.799636 -232.627785) (xy 364.75362 -232.610333) (xy 364.710999 -232.585726)
			(xy 364.672878 -232.554601) (xy 364.640243 -232.517764) (xy 364.61394 -232.476168) (xy 364.594649 -232.430892)
			(xy 364.582872 -232.383108) (xy 364.578912 -232.334054) (xy 364.250224 -232.334054) (xy 364.249729 -232.358661)
			(xy 364.241834 -232.407238) (xy 364.22625 -232.453919) (xy 364.203379 -232.497496) (xy 364.173814 -232.53684)
			(xy 364.138321 -232.570932) (xy 364.097818 -232.598888) (xy 364.053356 -232.619986) (xy 364.006085 -232.633678)
			(xy 363.95723 -232.63961) (xy 363.908055 -232.637629) (xy 363.859836 -232.627785) (xy 363.81382 -232.610333)
			(xy 363.771199 -232.585726) (xy 363.733078 -232.554601) (xy 363.700443 -232.517764) (xy 363.67414 -232.476168)
			(xy 363.654849 -232.430892) (xy 363.643072 -232.383108) (xy 363.639112 -232.334054) (xy 363.310965 -232.334054)
			(xy 363.310969 -232.3341) (xy 363.306793 -232.384481) (xy 363.294382 -232.433488) (xy 363.274073 -232.479783)
			(xy 363.246421 -232.522104) (xy 363.21218 -232.559295) (xy 363.172283 -232.590343) (xy 363.127821 -232.614401)
			(xy 363.080004 -232.630811) (xy 363.030139 -232.639126) (xy 363.004862 -232.639616) (xy 362.064808 -232.639616)
			(xy 362.039525 -232.639215) (xy 361.989649 -232.630894) (xy 361.941822 -232.614476) (xy 361.89735 -232.59041)
			(xy 361.857446 -232.559352) (xy 361.823198 -232.52215) (xy 361.795541 -232.479819) (xy 361.775229 -232.433512)
			(xy 361.762815 -232.384493) (xy 361.758639 -232.3341) (xy 361.430061 -232.3341) (xy 361.429567 -232.358661)
			(xy 361.421672 -232.407238) (xy 361.406088 -232.453919) (xy 361.383217 -232.497496) (xy 361.353652 -232.53684)
			(xy 361.318159 -232.570932) (xy 361.277656 -232.598888) (xy 361.233194 -232.619986) (xy 361.185923 -232.633678)
			(xy 361.137068 -232.63961) (xy 361.087893 -232.637629) (xy 361.039674 -232.627785) (xy 360.993658 -232.610333)
			(xy 360.951037 -232.585726) (xy 360.912916 -232.554601) (xy 360.880281 -232.517764) (xy 360.853978 -232.476168)
			(xy 360.834687 -232.430892) (xy 360.82291 -232.383108) (xy 360.81895 -232.334054) (xy 358.616504 -232.334054)
			(xy 358.616009 -232.358661) (xy 358.608114 -232.407238) (xy 358.59253 -232.453919) (xy 358.569659 -232.497496)
			(xy 358.540094 -232.53684) (xy 358.504601 -232.570932) (xy 358.464098 -232.598888) (xy 358.419636 -232.619986)
			(xy 358.372365 -232.633678) (xy 358.32351 -232.63961) (xy 358.274335 -232.637629) (xy 358.226116 -232.627785)
			(xy 358.1801 -232.610333) (xy 358.137479 -232.585726) (xy 358.099358 -232.554601) (xy 358.066723 -232.517764)
			(xy 358.04042 -232.476168) (xy 358.021129 -232.430892) (xy 358.009352 -232.383108) (xy 358.005392 -232.334054)
			(xy 357.67645 -232.334054) (xy 357.675955 -232.358661) (xy 357.66806 -232.407238) (xy 357.652476 -232.453919)
			(xy 357.629605 -232.497496) (xy 357.60004 -232.53684) (xy 357.564547 -232.570932) (xy 357.524044 -232.598888)
			(xy 357.479582 -232.619986) (xy 357.432311 -232.633678) (xy 357.383456 -232.63961) (xy 357.334281 -232.637629)
			(xy 357.286062 -232.627785) (xy 357.240046 -232.610333) (xy 357.197425 -232.585726) (xy 357.159304 -232.554601)
			(xy 357.126669 -232.517764) (xy 357.100366 -232.476168) (xy 357.081075 -232.430892) (xy 357.069298 -232.383108)
			(xy 357.065338 -232.334054) (xy 356.736396 -232.334054) (xy 356.735901 -232.358661) (xy 356.728006 -232.407238)
			(xy 356.712422 -232.453919) (xy 356.689551 -232.497496) (xy 356.659986 -232.53684) (xy 356.624493 -232.570932)
			(xy 356.58399 -232.598888) (xy 356.539528 -232.619986) (xy 356.492257 -232.633678) (xy 356.443402 -232.63961)
			(xy 356.394227 -232.637629) (xy 356.346008 -232.627785) (xy 356.299992 -232.610333) (xy 356.257371 -232.585726)
			(xy 356.21925 -232.554601) (xy 356.186615 -232.517764) (xy 356.160312 -232.476168) (xy 356.141021 -232.430892)
			(xy 356.129244 -232.383108) (xy 356.125284 -232.334054) (xy 355.796342 -232.334054) (xy 355.795847 -232.358661)
			(xy 355.787952 -232.407238) (xy 355.772368 -232.453919) (xy 355.749497 -232.497496) (xy 355.719932 -232.53684)
			(xy 355.684439 -232.570932) (xy 355.643936 -232.598888) (xy 355.599474 -232.619986) (xy 355.552203 -232.633678)
			(xy 355.503348 -232.63961) (xy 355.454173 -232.637629) (xy 355.405954 -232.627785) (xy 355.359938 -232.610333)
			(xy 355.317317 -232.585726) (xy 355.279196 -232.554601) (xy 355.246561 -232.517764) (xy 355.220258 -232.476168)
			(xy 355.200967 -232.430892) (xy 355.18919 -232.383108) (xy 355.18523 -232.334054) (xy 354.856542 -232.334054)
			(xy 354.856047 -232.358661) (xy 354.848152 -232.407238) (xy 354.832568 -232.453919) (xy 354.809697 -232.497496)
			(xy 354.780132 -232.53684) (xy 354.744639 -232.570932) (xy 354.704136 -232.598888) (xy 354.659674 -232.619986)
			(xy 354.612403 -232.633678) (xy 354.563548 -232.63961) (xy 354.514373 -232.637629) (xy 354.466154 -232.627785)
			(xy 354.420138 -232.610333) (xy 354.377517 -232.585726) (xy 354.339396 -232.554601) (xy 354.306761 -232.517764)
			(xy 354.280458 -232.476168) (xy 354.261167 -232.430892) (xy 354.24939 -232.383108) (xy 354.24543 -232.334054)
			(xy 353.916488 -232.334054) (xy 353.915993 -232.358661) (xy 353.908098 -232.407238) (xy 353.892514 -232.453919)
			(xy 353.869643 -232.497496) (xy 353.840078 -232.53684) (xy 353.804585 -232.570932) (xy 353.764082 -232.598888)
			(xy 353.71962 -232.619986) (xy 353.672349 -232.633678) (xy 353.623494 -232.63961) (xy 353.574319 -232.637629)
			(xy 353.5261 -232.627785) (xy 353.480084 -232.610333) (xy 353.437463 -232.585726) (xy 353.399342 -232.554601)
			(xy 353.366707 -232.517764) (xy 353.340404 -232.476168) (xy 353.321113 -232.430892) (xy 353.309336 -232.383108)
			(xy 353.305376 -232.334054) (xy 352.976434 -232.334054) (xy 352.975939 -232.358661) (xy 352.968044 -232.407238)
			(xy 352.95246 -232.453919) (xy 352.929589 -232.497496) (xy 352.900024 -232.53684) (xy 352.864531 -232.570932)
			(xy 352.824028 -232.598888) (xy 352.779566 -232.619986) (xy 352.732295 -232.633678) (xy 352.68344 -232.63961)
			(xy 352.634265 -232.637629) (xy 352.586046 -232.627785) (xy 352.54003 -232.610333) (xy 352.497409 -232.585726)
			(xy 352.459288 -232.554601) (xy 352.426653 -232.517764) (xy 352.40035 -232.476168) (xy 352.381059 -232.430892)
			(xy 352.369282 -232.383108) (xy 352.365322 -232.334054) (xy 352.03638 -232.334054) (xy 352.035885 -232.358661)
			(xy 352.02799 -232.407238) (xy 352.012406 -232.453919) (xy 351.989535 -232.497496) (xy 351.95997 -232.53684)
			(xy 351.924477 -232.570932) (xy 351.883974 -232.598888) (xy 351.839512 -232.619986) (xy 351.792241 -232.633678)
			(xy 351.743386 -232.63961) (xy 351.694211 -232.637629) (xy 351.645992 -232.627785) (xy 351.599976 -232.610333)
			(xy 351.557355 -232.585726) (xy 351.519234 -232.554601) (xy 351.486599 -232.517764) (xy 351.460296 -232.476168)
			(xy 351.441005 -232.430892) (xy 351.429228 -232.383108) (xy 351.425268 -232.334054) (xy 351.096326 -232.334054)
			(xy 351.095831 -232.358661) (xy 351.087936 -232.407238) (xy 351.072352 -232.453919) (xy 351.049481 -232.497496)
			(xy 351.019916 -232.53684) (xy 350.984423 -232.570932) (xy 350.94392 -232.598888) (xy 350.899458 -232.619986)
			(xy 350.852187 -232.633678) (xy 350.803332 -232.63961) (xy 350.754157 -232.637629) (xy 350.705938 -232.627785)
			(xy 350.659922 -232.610333) (xy 350.617301 -232.585726) (xy 350.57918 -232.554601) (xy 350.546545 -232.517764)
			(xy 350.520242 -232.476168) (xy 350.500951 -232.430892) (xy 350.489174 -232.383108) (xy 350.485214 -232.334054)
			(xy 350.156526 -232.334054) (xy 350.156031 -232.358661) (xy 350.148136 -232.407238) (xy 350.132552 -232.453919)
			(xy 350.109681 -232.497496) (xy 350.080116 -232.53684) (xy 350.044623 -232.570932) (xy 350.00412 -232.598888)
			(xy 349.959658 -232.619986) (xy 349.912387 -232.633678) (xy 349.863532 -232.63961) (xy 349.814357 -232.637629)
			(xy 349.766138 -232.627785) (xy 349.720122 -232.610333) (xy 349.677501 -232.585726) (xy 349.63938 -232.554601)
			(xy 349.606745 -232.517764) (xy 349.580442 -232.476168) (xy 349.561151 -232.430892) (xy 349.549374 -232.383108)
			(xy 349.545414 -232.334054) (xy 349.216472 -232.334054) (xy 349.215977 -232.358661) (xy 349.208082 -232.407238)
			(xy 349.192498 -232.453919) (xy 349.169627 -232.497496) (xy 349.140062 -232.53684) (xy 349.104569 -232.570932)
			(xy 349.064066 -232.598888) (xy 349.019604 -232.619986) (xy 348.972333 -232.633678) (xy 348.923478 -232.63961)
			(xy 348.874303 -232.637629) (xy 348.826084 -232.627785) (xy 348.780068 -232.610333) (xy 348.737447 -232.585726)
			(xy 348.699326 -232.554601) (xy 348.666691 -232.517764) (xy 348.640388 -232.476168) (xy 348.621097 -232.430892)
			(xy 348.60932 -232.383108) (xy 348.60536 -232.334054) (xy 348.276418 -232.334054) (xy 348.275923 -232.358661)
			(xy 348.268028 -232.407238) (xy 348.252444 -232.453919) (xy 348.229573 -232.497496) (xy 348.200008 -232.53684)
			(xy 348.164515 -232.570932) (xy 348.124012 -232.598888) (xy 348.07955 -232.619986) (xy 348.032279 -232.633678)
			(xy 347.983424 -232.63961) (xy 347.934249 -232.637629) (xy 347.88603 -232.627785) (xy 347.840014 -232.610333)
			(xy 347.797393 -232.585726) (xy 347.759272 -232.554601) (xy 347.726637 -232.517764) (xy 347.700334 -232.476168)
			(xy 347.681043 -232.430892) (xy 347.669266 -232.383108) (xy 347.665306 -232.334054) (xy 347.336364 -232.334054)
			(xy 347.335869 -232.358661) (xy 347.327974 -232.407238) (xy 347.31239 -232.453919) (xy 347.289519 -232.497496)
			(xy 347.259954 -232.53684) (xy 347.224461 -232.570932) (xy 347.183958 -232.598888) (xy 347.139496 -232.619986)
			(xy 347.092225 -232.633678) (xy 347.04337 -232.63961) (xy 346.994195 -232.637629) (xy 346.945976 -232.627785)
			(xy 346.89996 -232.610333) (xy 346.857339 -232.585726) (xy 346.819218 -232.554601) (xy 346.786583 -232.517764)
			(xy 346.76028 -232.476168) (xy 346.740989 -232.430892) (xy 346.729212 -232.383108) (xy 346.725252 -232.334054)
			(xy 346.39631 -232.334054) (xy 346.395815 -232.358661) (xy 346.38792 -232.407238) (xy 346.372336 -232.453919)
			(xy 346.349465 -232.497496) (xy 346.3199 -232.53684) (xy 346.284407 -232.570932) (xy 346.243904 -232.598888)
			(xy 346.199442 -232.619986) (xy 346.152171 -232.633678) (xy 346.103316 -232.63961) (xy 346.054141 -232.637629)
			(xy 346.005922 -232.627785) (xy 345.959906 -232.610333) (xy 345.917285 -232.585726) (xy 345.879164 -232.554601)
			(xy 345.846529 -232.517764) (xy 345.820226 -232.476168) (xy 345.800935 -232.430892) (xy 345.789158 -232.383108)
			(xy 345.785198 -232.334054) (xy 345.45651 -232.334054) (xy 345.456015 -232.358661) (xy 345.44812 -232.407238)
			(xy 345.432536 -232.453919) (xy 345.409665 -232.497496) (xy 345.3801 -232.53684) (xy 345.344607 -232.570932)
			(xy 345.304104 -232.598888) (xy 345.259642 -232.619986) (xy 345.212371 -232.633678) (xy 345.163516 -232.63961)
			(xy 345.114341 -232.637629) (xy 345.066122 -232.627785) (xy 345.020106 -232.610333) (xy 344.977485 -232.585726)
			(xy 344.939364 -232.554601) (xy 344.906729 -232.517764) (xy 344.880426 -232.476168) (xy 344.861135 -232.430892)
			(xy 344.849358 -232.383108) (xy 344.845398 -232.334054) (xy 344.626438 -232.334054) (xy 344.626438 -232.767378)
			(xy 344.626894 -232.77753) (xy 344.634767 -232.796247) (xy 344.641678 -232.8037) (xy 344.669618 -232.831132)
			(xy 344.686636 -232.838752) (xy 344.696034 -232.839006) (xy 344.720456 -232.840694) (xy 344.768338 -232.850869)
			(xy 344.813985 -232.868551) (xy 344.856227 -232.893286) (xy 344.893984 -232.924441) (xy 344.926289 -232.961219)
			(xy 344.952316 -233.002679) (xy 344.971397 -233.047758) (xy 344.983045 -233.095303) (xy 344.986958 -233.14406)
			(xy 345.315298 -233.14406) (xy 345.319258 -233.095006) (xy 345.331035 -233.047222) (xy 345.350326 -233.001946)
			(xy 345.376629 -232.96035) (xy 345.409264 -232.923513) (xy 345.447385 -232.892388) (xy 345.490006 -232.867781)
			(xy 345.536022 -232.850329) (xy 345.584241 -232.840485) (xy 345.633416 -232.838504) (xy 345.682271 -232.844436)
			(xy 345.729542 -232.858128) (xy 345.774004 -232.879226) (xy 345.814507 -232.907182) (xy 345.85 -232.941274)
			(xy 345.879565 -232.980618) (xy 345.902436 -233.024195) (xy 345.91802 -233.070876) (xy 345.925915 -233.119453)
			(xy 345.92641 -233.14406) (xy 346.255352 -233.14406) (xy 346.259312 -233.095006) (xy 346.271089 -233.047222)
			(xy 346.29038 -233.001946) (xy 346.316683 -232.96035) (xy 346.349318 -232.923513) (xy 346.387439 -232.892388)
			(xy 346.43006 -232.867781) (xy 346.476076 -232.850329) (xy 346.524295 -232.840485) (xy 346.57347 -232.838504)
			(xy 346.622325 -232.844436) (xy 346.669596 -232.858128) (xy 346.714058 -232.879226) (xy 346.754561 -232.907182)
			(xy 346.790054 -232.941274) (xy 346.819619 -232.980618) (xy 346.84249 -233.024195) (xy 346.858074 -233.070876)
			(xy 346.865969 -233.119453) (xy 346.866464 -233.14406) (xy 347.195406 -233.14406) (xy 347.199366 -233.095006)
			(xy 347.211143 -233.047222) (xy 347.230434 -233.001946) (xy 347.256737 -232.96035) (xy 347.289372 -232.923513)
			(xy 347.327493 -232.892388) (xy 347.370114 -232.867781) (xy 347.41613 -232.850329) (xy 347.464349 -232.840485)
			(xy 347.513524 -232.838504) (xy 347.562379 -232.844436) (xy 347.60965 -232.858128) (xy 347.654112 -232.879226)
			(xy 347.694615 -232.907182) (xy 347.730108 -232.941274) (xy 347.759673 -232.980618) (xy 347.782544 -233.024195)
			(xy 347.798128 -233.070876) (xy 347.806023 -233.119453) (xy 347.806518 -233.14406) (xy 348.135206 -233.14406)
			(xy 348.139166 -233.095006) (xy 348.150943 -233.047222) (xy 348.170234 -233.001946) (xy 348.196537 -232.96035)
			(xy 348.229172 -232.923513) (xy 348.267293 -232.892388) (xy 348.309914 -232.867781) (xy 348.35593 -232.850329)
			(xy 348.404149 -232.840485) (xy 348.453324 -232.838504) (xy 348.502179 -232.844436) (xy 348.54945 -232.858128)
			(xy 348.593912 -232.879226) (xy 348.634415 -232.907182) (xy 348.669908 -232.941274) (xy 348.699473 -232.980618)
			(xy 348.722344 -233.024195) (xy 348.737928 -233.070876) (xy 348.745823 -233.119453) (xy 348.746318 -233.14406)
			(xy 349.07526 -233.14406) (xy 349.07922 -233.095006) (xy 349.090997 -233.047222) (xy 349.110288 -233.001946)
			(xy 349.136591 -232.96035) (xy 349.169226 -232.923513) (xy 349.207347 -232.892388) (xy 349.249968 -232.867781)
			(xy 349.295984 -232.850329) (xy 349.344203 -232.840485) (xy 349.393378 -232.838504) (xy 349.442233 -232.844436)
			(xy 349.489504 -232.858128) (xy 349.533966 -232.879226) (xy 349.574469 -232.907182) (xy 349.609962 -232.941274)
			(xy 349.639527 -232.980618) (xy 349.662398 -233.024195) (xy 349.677982 -233.070876) (xy 349.685877 -233.119453)
			(xy 349.686372 -233.14406) (xy 350.015314 -233.14406) (xy 350.019274 -233.095006) (xy 350.031051 -233.047222)
			(xy 350.050342 -233.001946) (xy 350.076645 -232.96035) (xy 350.10928 -232.923513) (xy 350.147401 -232.892388)
			(xy 350.190022 -232.867781) (xy 350.236038 -232.850329) (xy 350.284257 -232.840485) (xy 350.333432 -232.838504)
			(xy 350.382287 -232.844436) (xy 350.429558 -232.858128) (xy 350.47402 -232.879226) (xy 350.514523 -232.907182)
			(xy 350.550016 -232.941274) (xy 350.579581 -232.980618) (xy 350.602452 -233.024195) (xy 350.618036 -233.070876)
			(xy 350.625931 -233.119453) (xy 350.626426 -233.14406) (xy 350.955368 -233.14406) (xy 350.959328 -233.095006)
			(xy 350.971105 -233.047222) (xy 350.990396 -233.001946) (xy 351.016699 -232.96035) (xy 351.049334 -232.923513)
			(xy 351.087455 -232.892388) (xy 351.130076 -232.867781) (xy 351.176092 -232.850329) (xy 351.224311 -232.840485)
			(xy 351.273486 -232.838504) (xy 351.322341 -232.844436) (xy 351.369612 -232.858128) (xy 351.414074 -232.879226)
			(xy 351.454577 -232.907182) (xy 351.49007 -232.941274) (xy 351.519635 -232.980618) (xy 351.542506 -233.024195)
			(xy 351.55809 -233.070876) (xy 351.565985 -233.119453) (xy 351.56648 -233.14406) (xy 351.895422 -233.14406)
			(xy 351.899382 -233.095006) (xy 351.911159 -233.047222) (xy 351.93045 -233.001946) (xy 351.956753 -232.96035)
			(xy 351.989388 -232.923513) (xy 352.027509 -232.892388) (xy 352.07013 -232.867781) (xy 352.116146 -232.850329)
			(xy 352.164365 -232.840485) (xy 352.21354 -232.838504) (xy 352.262395 -232.844436) (xy 352.309666 -232.858128)
			(xy 352.354128 -232.879226) (xy 352.394631 -232.907182) (xy 352.430124 -232.941274) (xy 352.459689 -232.980618)
			(xy 352.48256 -233.024195) (xy 352.498144 -233.070876) (xy 352.506039 -233.119453) (xy 352.506534 -233.14406)
			(xy 352.835222 -233.14406) (xy 352.839182 -233.095006) (xy 352.850959 -233.047222) (xy 352.87025 -233.001946)
			(xy 352.896553 -232.96035) (xy 352.929188 -232.923513) (xy 352.967309 -232.892388) (xy 353.00993 -232.867781)
			(xy 353.055946 -232.850329) (xy 353.104165 -232.840485) (xy 353.15334 -232.838504) (xy 353.202195 -232.844436)
			(xy 353.249466 -232.858128) (xy 353.293928 -232.879226) (xy 353.334431 -232.907182) (xy 353.369924 -232.941274)
			(xy 353.399489 -232.980618) (xy 353.42236 -233.024195) (xy 353.437944 -233.070876) (xy 353.445839 -233.119453)
			(xy 353.446334 -233.14406) (xy 353.775276 -233.14406) (xy 353.779236 -233.095006) (xy 353.791013 -233.047222)
			(xy 353.810304 -233.001946) (xy 353.836607 -232.96035) (xy 353.869242 -232.923513) (xy 353.907363 -232.892388)
			(xy 353.949984 -232.867781) (xy 353.996 -232.850329) (xy 354.044219 -232.840485) (xy 354.093394 -232.838504)
			(xy 354.142249 -232.844436) (xy 354.18952 -232.858128) (xy 354.233982 -232.879226) (xy 354.274485 -232.907182)
			(xy 354.309978 -232.941274) (xy 354.339543 -232.980618) (xy 354.362414 -233.024195) (xy 354.377998 -233.070876)
			(xy 354.385893 -233.119453) (xy 354.386388 -233.14406) (xy 354.71533 -233.14406) (xy 354.71929 -233.095006)
			(xy 354.731067 -233.047222) (xy 354.750358 -233.001946) (xy 354.776661 -232.96035) (xy 354.809296 -232.923513)
			(xy 354.847417 -232.892388) (xy 354.890038 -232.867781) (xy 354.936054 -232.850329) (xy 354.984273 -232.840485)
			(xy 355.033448 -232.838504) (xy 355.082303 -232.844436) (xy 355.129574 -232.858128) (xy 355.174036 -232.879226)
			(xy 355.214539 -232.907182) (xy 355.250032 -232.941274) (xy 355.279597 -232.980618) (xy 355.302468 -233.024195)
			(xy 355.318052 -233.070876) (xy 355.325947 -233.119453) (xy 355.326442 -233.14406) (xy 355.655384 -233.14406)
			(xy 355.659344 -233.095006) (xy 355.671121 -233.047222) (xy 355.690412 -233.001946) (xy 355.716715 -232.96035)
			(xy 355.74935 -232.923513) (xy 355.787471 -232.892388) (xy 355.830092 -232.867781) (xy 355.876108 -232.850329)
			(xy 355.924327 -232.840485) (xy 355.973502 -232.838504) (xy 356.022357 -232.844436) (xy 356.069628 -232.858128)
			(xy 356.11409 -232.879226) (xy 356.154593 -232.907182) (xy 356.190086 -232.941274) (xy 356.219651 -232.980618)
			(xy 356.242522 -233.024195) (xy 356.258106 -233.070876) (xy 356.266001 -233.119453) (xy 356.266496 -233.14406)
			(xy 356.595438 -233.14406) (xy 356.599398 -233.095006) (xy 356.611175 -233.047222) (xy 356.630466 -233.001946)
			(xy 356.656769 -232.96035) (xy 356.689404 -232.923513) (xy 356.727525 -232.892388) (xy 356.770146 -232.867781)
			(xy 356.816162 -232.850329) (xy 356.864381 -232.840485) (xy 356.913556 -232.838504) (xy 356.962411 -232.844436)
			(xy 357.009682 -232.858128) (xy 357.054144 -232.879226) (xy 357.094647 -232.907182) (xy 357.13014 -232.941274)
			(xy 357.159705 -232.980618) (xy 357.182576 -233.024195) (xy 357.19816 -233.070876) (xy 357.206055 -233.119453)
			(xy 357.20655 -233.14406) (xy 357.535238 -233.14406) (xy 357.539198 -233.095006) (xy 357.550975 -233.047222)
			(xy 357.570266 -233.001946) (xy 357.596569 -232.96035) (xy 357.629204 -232.923513) (xy 357.667325 -232.892388)
			(xy 357.709946 -232.867781) (xy 357.755962 -232.850329) (xy 357.804181 -232.840485) (xy 357.853356 -232.838504)
			(xy 357.902211 -232.844436) (xy 357.949482 -232.858128) (xy 357.993944 -232.879226) (xy 358.034447 -232.907182)
			(xy 358.06994 -232.941274) (xy 358.099505 -232.980618) (xy 358.122376 -233.024195) (xy 358.13796 -233.070876)
			(xy 358.145855 -233.119453) (xy 358.14635 -233.14406) (xy 361.289104 -233.14406) (xy 361.293064 -233.095006)
			(xy 361.304841 -233.047222) (xy 361.324132 -233.001946) (xy 361.350435 -232.96035) (xy 361.38307 -232.923513)
			(xy 361.421191 -232.892388) (xy 361.463812 -232.867781) (xy 361.509828 -232.850329) (xy 361.558047 -232.840485)
			(xy 361.607222 -232.838504) (xy 361.656077 -232.844436) (xy 361.703348 -232.858128) (xy 361.74781 -232.879226)
			(xy 361.788313 -232.907182) (xy 361.823806 -232.941274) (xy 361.853371 -232.980618) (xy 361.876242 -233.024195)
			(xy 361.891826 -233.070876) (xy 361.899721 -233.119453) (xy 361.900216 -233.14406) (xy 362.228904 -233.14406)
			(xy 362.232864 -233.095006) (xy 362.244641 -233.047222) (xy 362.263932 -233.001946) (xy 362.290235 -232.96035)
			(xy 362.32287 -232.923513) (xy 362.360991 -232.892388) (xy 362.403612 -232.867781) (xy 362.449628 -232.850329)
			(xy 362.497847 -232.840485) (xy 362.547022 -232.838504) (xy 362.595877 -232.844436) (xy 362.643148 -232.858128)
			(xy 362.68761 -232.879226) (xy 362.728113 -232.907182) (xy 362.763606 -232.941274) (xy 362.793171 -232.980618)
			(xy 362.816042 -233.024195) (xy 362.831626 -233.070876) (xy 362.839521 -233.119453) (xy 362.840016 -233.14406)
			(xy 363.168958 -233.14406) (xy 363.172918 -233.095006) (xy 363.184695 -233.047222) (xy 363.203986 -233.001946)
			(xy 363.230289 -232.96035) (xy 363.262924 -232.923513) (xy 363.301045 -232.892388) (xy 363.343666 -232.867781)
			(xy 363.389682 -232.850329) (xy 363.437901 -232.840485) (xy 363.487076 -232.838504) (xy 363.535931 -232.844436)
			(xy 363.583202 -232.858128) (xy 363.627664 -232.879226) (xy 363.668167 -232.907182) (xy 363.70366 -232.941274)
			(xy 363.733225 -232.980618) (xy 363.756096 -233.024195) (xy 363.77168 -233.070876) (xy 363.779575 -233.119453)
			(xy 363.78007 -233.14406) (xy 363.780069 -233.1441) (xy 364.1089 -233.1441) (xy 364.113072 -233.093749)
			(xy 364.125476 -233.044771) (xy 364.145771 -232.998503) (xy 364.173406 -232.956207) (xy 364.207626 -232.919036)
			(xy 364.247497 -232.888005) (xy 364.291932 -232.86396) (xy 364.339719 -232.847557) (xy 364.389554 -232.839244)
			(xy 364.414816 -232.838752) (xy 365.35487 -232.838752) (xy 365.380126 -232.839322) (xy 365.42995 -232.847632)
			(xy 365.477726 -232.864029) (xy 365.522152 -232.888067) (xy 365.562015 -232.91909) (xy 365.596227 -232.956251)
			(xy 365.623856 -232.998537) (xy 365.644148 -233.044794) (xy 365.656548 -233.093761) (xy 365.660717 -233.14406)
			(xy 365.98912 -233.14406) (xy 365.99308 -233.095006) (xy 366.004857 -233.047222) (xy 366.024148 -233.001946)
			(xy 366.050451 -232.96035) (xy 366.083086 -232.923513) (xy 366.121207 -232.892388) (xy 366.163828 -232.867781)
			(xy 366.209844 -232.850329) (xy 366.258063 -232.840485) (xy 366.307238 -232.838504) (xy 366.356093 -232.844436)
			(xy 366.403364 -232.858128) (xy 366.447826 -232.879226) (xy 366.488329 -232.907182) (xy 366.523822 -232.941274)
			(xy 366.553387 -232.980618) (xy 366.576258 -233.024195) (xy 366.591842 -233.070876) (xy 366.599737 -233.119453)
			(xy 366.600232 -233.14406) (xy 366.600231 -233.1441) (xy 366.9288 -233.1441) (xy 366.932972 -233.093748)
			(xy 366.945376 -233.04477) (xy 366.965673 -232.998501) (xy 366.993308 -232.956204) (xy 367.027529 -232.919033)
			(xy 367.067401 -232.888002) (xy 367.111838 -232.863958) (xy 367.159626 -232.847555) (xy 367.209462 -232.839243)
			(xy 367.234724 -232.838752) (xy 368.174778 -232.838752) (xy 368.200034 -232.839323) (xy 368.249856 -232.847633)
			(xy 368.297632 -232.864032) (xy 368.342056 -232.88807) (xy 368.381918 -232.919093) (xy 368.416129 -232.956254)
			(xy 368.443757 -232.99854) (xy 368.464048 -233.044796) (xy 368.476449 -233.093761) (xy 368.480617 -233.14406)
			(xy 368.809028 -233.14406) (xy 368.812988 -233.095006) (xy 368.824765 -233.047222) (xy 368.844056 -233.001946)
			(xy 368.870359 -232.96035) (xy 368.902994 -232.923513) (xy 368.941115 -232.892388) (xy 368.983736 -232.867781)
			(xy 369.029752 -232.850329) (xy 369.077971 -232.840485) (xy 369.127146 -232.838504) (xy 369.176001 -232.844436)
			(xy 369.223272 -232.858128) (xy 369.267734 -232.879226) (xy 369.308237 -232.907182) (xy 369.34373 -232.941274)
			(xy 369.373295 -232.980618) (xy 369.396166 -233.024195) (xy 369.41175 -233.070876) (xy 369.419645 -233.119453)
			(xy 369.42014 -233.14406) (xy 369.420139 -233.1441) (xy 369.749029 -233.1441) (xy 369.7532 -233.093757)
			(xy 369.765601 -233.044787) (xy 369.785892 -232.998525) (xy 369.813521 -232.956235) (xy 369.847734 -232.919068)
			(xy 369.887597 -232.88804) (xy 369.932024 -232.863996) (xy 369.979802 -232.847591) (xy 370.029628 -232.839275)
			(xy 370.054886 -232.838752) (xy 370.99494 -232.838752) (xy 371.02019 -232.839357) (xy 371.07 -232.847674)
			(xy 371.117762 -232.864077) (xy 371.162173 -232.888116) (xy 371.202022 -232.919137) (xy 371.236222 -232.956293)
			(xy 371.263841 -232.998571) (xy 371.284125 -233.044818) (xy 371.296521 -233.093773) (xy 371.300688 -233.14406)
			(xy 371.628936 -233.14406) (xy 371.632896 -233.095006) (xy 371.644673 -233.047222) (xy 371.663964 -233.001946)
			(xy 371.690267 -232.96035) (xy 371.722902 -232.923513) (xy 371.761023 -232.892388) (xy 371.803644 -232.867781)
			(xy 371.84966 -232.850329) (xy 371.897879 -232.840485) (xy 371.947054 -232.838504) (xy 371.995909 -232.844436)
			(xy 372.04318 -232.858128) (xy 372.087642 -232.879226) (xy 372.128145 -232.907182) (xy 372.163638 -232.941274)
			(xy 372.193203 -232.980618) (xy 372.216074 -233.024195) (xy 372.231658 -233.070876) (xy 372.239553 -233.119453)
			(xy 372.240048 -233.14406) (xy 372.240047 -233.1441) (xy 372.568929 -233.1441) (xy 372.573101 -233.093756)
			(xy 372.585502 -233.044785) (xy 372.605794 -232.998523) (xy 372.633423 -232.956232) (xy 372.667637 -232.919066)
			(xy 372.707501 -232.888037) (xy 372.751929 -232.863993) (xy 372.799708 -232.84759) (xy 372.849536 -232.839274)
			(xy 372.874794 -232.838752) (xy 373.814848 -232.838752) (xy 373.840097 -232.839357) (xy 373.889906 -232.847676)
			(xy 373.937667 -232.864079) (xy 373.982077 -232.888119) (xy 374.021925 -232.919139) (xy 374.056124 -232.956295)
			(xy 374.083742 -232.998573) (xy 374.104026 -233.044819) (xy 374.116421 -233.093773) (xy 374.120591 -233.1441)
			(xy 374.116421 -233.194427) (xy 374.104026 -233.243381) (xy 374.083742 -233.289627) (xy 374.056125 -233.331905)
			(xy 374.021925 -233.369061) (xy 373.982077 -233.400081) (xy 373.937667 -233.424121) (xy 373.889907 -233.440524)
			(xy 373.840097 -233.448843) (xy 373.814848 -233.449368) (xy 372.874794 -233.449368) (xy 372.849536 -233.448926)
			(xy 372.799708 -233.44061) (xy 372.751929 -233.424207) (xy 372.707501 -233.400163) (xy 372.667637 -233.369134)
			(xy 372.633423 -233.331968) (xy 372.605794 -233.289677) (xy 372.585502 -233.243415) (xy 372.573101 -233.194444)
			(xy 372.568929 -233.1441) (xy 372.240047 -233.1441) (xy 372.239553 -233.168667) (xy 372.231658 -233.217244)
			(xy 372.216074 -233.263925) (xy 372.193203 -233.307502) (xy 372.163638 -233.346846) (xy 372.128145 -233.380938)
			(xy 372.087642 -233.408894) (xy 372.04318 -233.429992) (xy 371.995909 -233.443684) (xy 371.947054 -233.449616)
			(xy 371.897879 -233.447635) (xy 371.84966 -233.437791) (xy 371.803644 -233.420339) (xy 371.761023 -233.395732)
			(xy 371.722902 -233.364607) (xy 371.690267 -233.32777) (xy 371.663964 -233.286174) (xy 371.644673 -233.240898)
			(xy 371.632896 -233.193114) (xy 371.628936 -233.14406) (xy 371.300688 -233.14406) (xy 371.300691 -233.1441)
			(xy 371.296521 -233.194427) (xy 371.284125 -233.243382) (xy 371.263841 -233.289629) (xy 371.236222 -233.331907)
			(xy 371.202022 -233.369063) (xy 371.162173 -233.400084) (xy 371.117762 -233.424123) (xy 371.07 -233.440526)
			(xy 371.02019 -233.448843) (xy 370.99494 -233.449368) (xy 370.054886 -233.449368) (xy 370.029628 -233.448925)
			(xy 369.979802 -233.440609) (xy 369.932024 -233.424204) (xy 369.887597 -233.40016) (xy 369.847734 -233.369132)
			(xy 369.813521 -233.331965) (xy 369.785892 -233.289675) (xy 369.765601 -233.243413) (xy 369.7532 -233.194443)
			(xy 369.749029 -233.1441) (xy 369.420139 -233.1441) (xy 369.419645 -233.168667) (xy 369.41175 -233.217244)
			(xy 369.396166 -233.263925) (xy 369.373295 -233.307502) (xy 369.34373 -233.346846) (xy 369.308237 -233.380938)
			(xy 369.267734 -233.408894) (xy 369.223272 -233.429992) (xy 369.176001 -233.443684) (xy 369.127146 -233.449616)
			(xy 369.077971 -233.447635) (xy 369.029752 -233.437791) (xy 368.983736 -233.420339) (xy 368.941115 -233.395732)
			(xy 368.902994 -233.364607) (xy 368.870359 -233.32777) (xy 368.844056 -233.286174) (xy 368.824765 -233.240898)
			(xy 368.812988 -233.193114) (xy 368.809028 -233.14406) (xy 368.480617 -233.14406) (xy 368.48062 -233.1441)
			(xy 368.476449 -233.194439) (xy 368.464048 -233.243404) (xy 368.443757 -233.28966) (xy 368.416129 -233.331946)
			(xy 368.381918 -233.369107) (xy 368.342056 -233.40013) (xy 368.297632 -233.424168) (xy 368.249856 -233.440567)
			(xy 368.200034 -233.448877) (xy 368.174778 -233.449368) (xy 367.234724 -233.449368) (xy 367.209462 -233.448957)
			(xy 367.159626 -233.440645) (xy 367.111838 -233.424242) (xy 367.067401 -233.400198) (xy 367.027529 -233.369167)
			(xy 366.993308 -233.331996) (xy 366.965673 -233.289699) (xy 366.945376 -233.24343) (xy 366.932972 -233.194452)
			(xy 366.9288 -233.1441) (xy 366.600231 -233.1441) (xy 366.599737 -233.168667) (xy 366.591842 -233.217244)
			(xy 366.576258 -233.263925) (xy 366.553387 -233.307502) (xy 366.523822 -233.346846) (xy 366.488329 -233.380938)
			(xy 366.447826 -233.408894) (xy 366.403364 -233.429992) (xy 366.356093 -233.443684) (xy 366.307238 -233.449616)
			(xy 366.258063 -233.447635) (xy 366.209844 -233.437791) (xy 366.163828 -233.420339) (xy 366.121207 -233.395732)
			(xy 366.083086 -233.364607) (xy 366.050451 -233.32777) (xy 366.024148 -233.286174) (xy 366.004857 -233.240898)
			(xy 365.99308 -233.193114) (xy 365.98912 -233.14406) (xy 365.660717 -233.14406) (xy 365.66072 -233.1441)
			(xy 365.656548 -233.194439) (xy 365.644148 -233.243406) (xy 365.623856 -233.289663) (xy 365.596227 -233.331949)
			(xy 365.562015 -233.36911) (xy 365.522152 -233.400133) (xy 365.477726 -233.424171) (xy 365.42995 -233.440568)
			(xy 365.380126 -233.448878) (xy 365.35487 -233.449368) (xy 364.414816 -233.449368) (xy 364.389554 -233.448956)
			(xy 364.339719 -233.440643) (xy 364.291932 -233.42424) (xy 364.247497 -233.400195) (xy 364.207626 -233.369164)
			(xy 364.173406 -233.331993) (xy 364.145771 -233.289697) (xy 364.125476 -233.243429) (xy 364.113072 -233.194451)
			(xy 364.1089 -233.1441) (xy 363.780069 -233.1441) (xy 363.779575 -233.168667) (xy 363.77168 -233.217244)
			(xy 363.756096 -233.263925) (xy 363.733225 -233.307502) (xy 363.70366 -233.346846) (xy 363.668167 -233.380938)
			(xy 363.627664 -233.408894) (xy 363.583202 -233.429992) (xy 363.535931 -233.443684) (xy 363.487076 -233.449616)
			(xy 363.437901 -233.447635) (xy 363.389682 -233.437791) (xy 363.343666 -233.420339) (xy 363.301045 -233.395732)
			(xy 363.262924 -233.364607) (xy 363.230289 -233.32777) (xy 363.203986 -233.286174) (xy 363.184695 -233.240898)
			(xy 363.172918 -233.193114) (xy 363.168958 -233.14406) (xy 362.840016 -233.14406) (xy 362.839521 -233.168667)
			(xy 362.831626 -233.217244) (xy 362.816042 -233.263925) (xy 362.793171 -233.307502) (xy 362.763606 -233.346846)
			(xy 362.728113 -233.380938) (xy 362.68761 -233.408894) (xy 362.643148 -233.429992) (xy 362.595877 -233.443684)
			(xy 362.547022 -233.449616) (xy 362.497847 -233.447635) (xy 362.449628 -233.437791) (xy 362.403612 -233.420339)
			(xy 362.360991 -233.395732) (xy 362.32287 -233.364607) (xy 362.290235 -233.32777) (xy 362.263932 -233.286174)
			(xy 362.244641 -233.240898) (xy 362.232864 -233.193114) (xy 362.228904 -233.14406) (xy 361.900216 -233.14406)
			(xy 361.899721 -233.168667) (xy 361.891826 -233.217244) (xy 361.876242 -233.263925) (xy 361.853371 -233.307502)
			(xy 361.823806 -233.346846) (xy 361.788313 -233.380938) (xy 361.74781 -233.408894) (xy 361.703348 -233.429992)
			(xy 361.656077 -233.443684) (xy 361.607222 -233.449616) (xy 361.558047 -233.447635) (xy 361.509828 -233.437791)
			(xy 361.463812 -233.420339) (xy 361.421191 -233.395732) (xy 361.38307 -233.364607) (xy 361.350435 -233.32777)
			(xy 361.324132 -233.286174) (xy 361.304841 -233.240898) (xy 361.293064 -233.193114) (xy 361.289104 -233.14406)
			(xy 358.14635 -233.14406) (xy 358.145855 -233.168667) (xy 358.13796 -233.217244) (xy 358.122376 -233.263925)
			(xy 358.099505 -233.307502) (xy 358.06994 -233.346846) (xy 358.034447 -233.380938) (xy 357.993944 -233.408894)
			(xy 357.949482 -233.429992) (xy 357.902211 -233.443684) (xy 357.853356 -233.449616) (xy 357.804181 -233.447635)
			(xy 357.755962 -233.437791) (xy 357.709946 -233.420339) (xy 357.667325 -233.395732) (xy 357.629204 -233.364607)
			(xy 357.596569 -233.32777) (xy 357.570266 -233.286174) (xy 357.550975 -233.240898) (xy 357.539198 -233.193114)
			(xy 357.535238 -233.14406) (xy 357.20655 -233.14406) (xy 357.206055 -233.168667) (xy 357.19816 -233.217244)
			(xy 357.182576 -233.263925) (xy 357.159705 -233.307502) (xy 357.13014 -233.346846) (xy 357.094647 -233.380938)
			(xy 357.054144 -233.408894) (xy 357.009682 -233.429992) (xy 356.962411 -233.443684) (xy 356.913556 -233.449616)
			(xy 356.864381 -233.447635) (xy 356.816162 -233.437791) (xy 356.770146 -233.420339) (xy 356.727525 -233.395732)
			(xy 356.689404 -233.364607) (xy 356.656769 -233.32777) (xy 356.630466 -233.286174) (xy 356.611175 -233.240898)
			(xy 356.599398 -233.193114) (xy 356.595438 -233.14406) (xy 356.266496 -233.14406) (xy 356.266001 -233.168667)
			(xy 356.258106 -233.217244) (xy 356.242522 -233.263925) (xy 356.219651 -233.307502) (xy 356.190086 -233.346846)
			(xy 356.154593 -233.380938) (xy 356.11409 -233.408894) (xy 356.069628 -233.429992) (xy 356.022357 -233.443684)
			(xy 355.973502 -233.449616) (xy 355.924327 -233.447635) (xy 355.876108 -233.437791) (xy 355.830092 -233.420339)
			(xy 355.787471 -233.395732) (xy 355.74935 -233.364607) (xy 355.716715 -233.32777) (xy 355.690412 -233.286174)
			(xy 355.671121 -233.240898) (xy 355.659344 -233.193114) (xy 355.655384 -233.14406) (xy 355.326442 -233.14406)
			(xy 355.325947 -233.168667) (xy 355.318052 -233.217244) (xy 355.302468 -233.263925) (xy 355.279597 -233.307502)
			(xy 355.250032 -233.346846) (xy 355.214539 -233.380938) (xy 355.174036 -233.408894) (xy 355.129574 -233.429992)
			(xy 355.082303 -233.443684) (xy 355.033448 -233.449616) (xy 354.984273 -233.447635) (xy 354.936054 -233.437791)
			(xy 354.890038 -233.420339) (xy 354.847417 -233.395732) (xy 354.809296 -233.364607) (xy 354.776661 -233.32777)
			(xy 354.750358 -233.286174) (xy 354.731067 -233.240898) (xy 354.71929 -233.193114) (xy 354.71533 -233.14406)
			(xy 354.386388 -233.14406) (xy 354.385893 -233.168667) (xy 354.377998 -233.217244) (xy 354.362414 -233.263925)
			(xy 354.339543 -233.307502) (xy 354.309978 -233.346846) (xy 354.274485 -233.380938) (xy 354.233982 -233.408894)
			(xy 354.18952 -233.429992) (xy 354.142249 -233.443684) (xy 354.093394 -233.449616) (xy 354.044219 -233.447635)
			(xy 353.996 -233.437791) (xy 353.949984 -233.420339) (xy 353.907363 -233.395732) (xy 353.869242 -233.364607)
			(xy 353.836607 -233.32777) (xy 353.810304 -233.286174) (xy 353.791013 -233.240898) (xy 353.779236 -233.193114)
			(xy 353.775276 -233.14406) (xy 353.446334 -233.14406) (xy 353.445839 -233.168667) (xy 353.437944 -233.217244)
			(xy 353.42236 -233.263925) (xy 353.399489 -233.307502) (xy 353.369924 -233.346846) (xy 353.334431 -233.380938)
			(xy 353.293928 -233.408894) (xy 353.249466 -233.429992) (xy 353.202195 -233.443684) (xy 353.15334 -233.449616)
			(xy 353.104165 -233.447635) (xy 353.055946 -233.437791) (xy 353.00993 -233.420339) (xy 352.967309 -233.395732)
			(xy 352.929188 -233.364607) (xy 352.896553 -233.32777) (xy 352.87025 -233.286174) (xy 352.850959 -233.240898)
			(xy 352.839182 -233.193114) (xy 352.835222 -233.14406) (xy 352.506534 -233.14406) (xy 352.506039 -233.168667)
			(xy 352.498144 -233.217244) (xy 352.48256 -233.263925) (xy 352.459689 -233.307502) (xy 352.430124 -233.346846)
			(xy 352.394631 -233.380938) (xy 352.354128 -233.408894) (xy 352.309666 -233.429992) (xy 352.262395 -233.443684)
			(xy 352.21354 -233.449616) (xy 352.164365 -233.447635) (xy 352.116146 -233.437791) (xy 352.07013 -233.420339)
			(xy 352.027509 -233.395732) (xy 351.989388 -233.364607) (xy 351.956753 -233.32777) (xy 351.93045 -233.286174)
			(xy 351.911159 -233.240898) (xy 351.899382 -233.193114) (xy 351.895422 -233.14406) (xy 351.56648 -233.14406)
			(xy 351.565985 -233.168667) (xy 351.55809 -233.217244) (xy 351.542506 -233.263925) (xy 351.519635 -233.307502)
			(xy 351.49007 -233.346846) (xy 351.454577 -233.380938) (xy 351.414074 -233.408894) (xy 351.369612 -233.429992)
			(xy 351.322341 -233.443684) (xy 351.273486 -233.449616) (xy 351.224311 -233.447635) (xy 351.176092 -233.437791)
			(xy 351.130076 -233.420339) (xy 351.087455 -233.395732) (xy 351.049334 -233.364607) (xy 351.016699 -233.32777)
			(xy 350.990396 -233.286174) (xy 350.971105 -233.240898) (xy 350.959328 -233.193114) (xy 350.955368 -233.14406)
			(xy 350.626426 -233.14406) (xy 350.625931 -233.168667) (xy 350.618036 -233.217244) (xy 350.602452 -233.263925)
			(xy 350.579581 -233.307502) (xy 350.550016 -233.346846) (xy 350.514523 -233.380938) (xy 350.47402 -233.408894)
			(xy 350.429558 -233.429992) (xy 350.382287 -233.443684) (xy 350.333432 -233.449616) (xy 350.284257 -233.447635)
			(xy 350.236038 -233.437791) (xy 350.190022 -233.420339) (xy 350.147401 -233.395732) (xy 350.10928 -233.364607)
			(xy 350.076645 -233.32777) (xy 350.050342 -233.286174) (xy 350.031051 -233.240898) (xy 350.019274 -233.193114)
			(xy 350.015314 -233.14406) (xy 349.686372 -233.14406) (xy 349.685877 -233.168667) (xy 349.677982 -233.217244)
			(xy 349.662398 -233.263925) (xy 349.639527 -233.307502) (xy 349.609962 -233.346846) (xy 349.574469 -233.380938)
			(xy 349.533966 -233.408894) (xy 349.489504 -233.429992) (xy 349.442233 -233.443684) (xy 349.393378 -233.449616)
			(xy 349.344203 -233.447635) (xy 349.295984 -233.437791) (xy 349.249968 -233.420339) (xy 349.207347 -233.395732)
			(xy 349.169226 -233.364607) (xy 349.136591 -233.32777) (xy 349.110288 -233.286174) (xy 349.090997 -233.240898)
			(xy 349.07922 -233.193114) (xy 349.07526 -233.14406) (xy 348.746318 -233.14406) (xy 348.745823 -233.168667)
			(xy 348.737928 -233.217244) (xy 348.722344 -233.263925) (xy 348.699473 -233.307502) (xy 348.669908 -233.346846)
			(xy 348.634415 -233.380938) (xy 348.593912 -233.408894) (xy 348.54945 -233.429992) (xy 348.502179 -233.443684)
			(xy 348.453324 -233.449616) (xy 348.404149 -233.447635) (xy 348.35593 -233.437791) (xy 348.309914 -233.420339)
			(xy 348.267293 -233.395732) (xy 348.229172 -233.364607) (xy 348.196537 -233.32777) (xy 348.170234 -233.286174)
			(xy 348.150943 -233.240898) (xy 348.139166 -233.193114) (xy 348.135206 -233.14406) (xy 347.806518 -233.14406)
			(xy 347.806023 -233.168667) (xy 347.798128 -233.217244) (xy 347.782544 -233.263925) (xy 347.759673 -233.307502)
			(xy 347.730108 -233.346846) (xy 347.694615 -233.380938) (xy 347.654112 -233.408894) (xy 347.60965 -233.429992)
			(xy 347.562379 -233.443684) (xy 347.513524 -233.449616) (xy 347.464349 -233.447635) (xy 347.41613 -233.437791)
			(xy 347.370114 -233.420339) (xy 347.327493 -233.395732) (xy 347.289372 -233.364607) (xy 347.256737 -233.32777)
			(xy 347.230434 -233.286174) (xy 347.211143 -233.240898) (xy 347.199366 -233.193114) (xy 347.195406 -233.14406)
			(xy 346.866464 -233.14406) (xy 346.865969 -233.168667) (xy 346.858074 -233.217244) (xy 346.84249 -233.263925)
			(xy 346.819619 -233.307502) (xy 346.790054 -233.346846) (xy 346.754561 -233.380938) (xy 346.714058 -233.408894)
			(xy 346.669596 -233.429992) (xy 346.622325 -233.443684) (xy 346.57347 -233.449616) (xy 346.524295 -233.447635)
			(xy 346.476076 -233.437791) (xy 346.43006 -233.420339) (xy 346.387439 -233.395732) (xy 346.349318 -233.364607)
			(xy 346.316683 -233.32777) (xy 346.29038 -233.286174) (xy 346.271089 -233.240898) (xy 346.259312 -233.193114)
			(xy 346.255352 -233.14406) (xy 345.92641 -233.14406) (xy 345.925915 -233.168667) (xy 345.91802 -233.217244)
			(xy 345.902436 -233.263925) (xy 345.879565 -233.307502) (xy 345.85 -233.346846) (xy 345.814507 -233.380938)
			(xy 345.774004 -233.408894) (xy 345.729542 -233.429992) (xy 345.682271 -233.443684) (xy 345.633416 -233.449616)
			(xy 345.584241 -233.447635) (xy 345.536022 -233.437791) (xy 345.490006 -233.420339) (xy 345.447385 -233.395732)
			(xy 345.409264 -233.364607) (xy 345.376629 -233.32777) (xy 345.350326 -233.286174) (xy 345.331035 -233.240898)
			(xy 345.319258 -233.193114) (xy 345.315298 -233.14406) (xy 344.986958 -233.14406) (xy 344.986961 -233.144098)
			(xy 344.983046 -233.192893) (xy 344.971398 -233.240438) (xy 344.952318 -233.285518) (xy 344.926292 -233.326977)
			(xy 344.893987 -233.363756) (xy 344.856231 -233.394912) (xy 344.813988 -233.419647) (xy 344.768342 -233.43733)
			(xy 344.72046 -233.447506) (xy 344.696034 -233.449114) (xy 344.686636 -233.449368) (xy 344.669618 -233.456988)
			(xy 344.641424 -233.484674) (xy 344.634612 -233.49194) (xy 344.626891 -233.510283) (xy 344.626438 -233.520234)
			(xy 344.626438 -233.954066) (xy 346.725252 -233.954066) (xy 346.729212 -233.905012) (xy 346.740989 -233.857228)
			(xy 346.76028 -233.811952) (xy 346.786583 -233.770356) (xy 346.819218 -233.733519) (xy 346.857339 -233.702394)
			(xy 346.89996 -233.677787) (xy 346.945976 -233.660335) (xy 346.994195 -233.650491) (xy 347.04337 -233.64851)
			(xy 347.092225 -233.654442) (xy 347.139496 -233.668134) (xy 347.183958 -233.689232) (xy 347.224461 -233.717188)
			(xy 347.259954 -233.75128) (xy 347.289519 -233.790624) (xy 347.31239 -233.834201) (xy 347.327974 -233.880882)
			(xy 347.335869 -233.929459) (xy 347.336364 -233.954066) (xy 349.545414 -233.954066) (xy 349.549374 -233.905012)
			(xy 349.561151 -233.857228) (xy 349.580442 -233.811952) (xy 349.606745 -233.770356) (xy 349.63938 -233.733519)
			(xy 349.677501 -233.702394) (xy 349.720122 -233.677787) (xy 349.766138 -233.660335) (xy 349.814357 -233.650491)
			(xy 349.863532 -233.64851) (xy 349.912387 -233.654442) (xy 349.959658 -233.668134) (xy 350.00412 -233.689232)
			(xy 350.044623 -233.717188) (xy 350.080116 -233.75128) (xy 350.109681 -233.790624) (xy 350.132552 -233.834201)
			(xy 350.148136 -233.880882) (xy 350.156031 -233.929459) (xy 350.156526 -233.954066) (xy 352.365322 -233.954066)
			(xy 352.369282 -233.905012) (xy 352.381059 -233.857228) (xy 352.40035 -233.811952) (xy 352.426653 -233.770356)
			(xy 352.459288 -233.733519) (xy 352.497409 -233.702394) (xy 352.54003 -233.677787) (xy 352.586046 -233.660335)
			(xy 352.634265 -233.650491) (xy 352.68344 -233.64851) (xy 352.732295 -233.654442) (xy 352.779566 -233.668134)
			(xy 352.824028 -233.689232) (xy 352.864531 -233.717188) (xy 352.900024 -233.75128) (xy 352.929589 -233.790624)
			(xy 352.95246 -233.834201) (xy 352.968044 -233.880882) (xy 352.975939 -233.929459) (xy 352.976434 -233.954066)
			(xy 355.18523 -233.954066) (xy 355.18919 -233.905012) (xy 355.200967 -233.857228) (xy 355.220258 -233.811952)
			(xy 355.246561 -233.770356) (xy 355.279196 -233.733519) (xy 355.317317 -233.702394) (xy 355.359938 -233.677787)
			(xy 355.405954 -233.660335) (xy 355.454173 -233.650491) (xy 355.503348 -233.64851) (xy 355.552203 -233.654442)
			(xy 355.599474 -233.668134) (xy 355.643936 -233.689232) (xy 355.684439 -233.717188) (xy 355.719932 -233.75128)
			(xy 355.749497 -233.790624) (xy 355.772368 -233.834201) (xy 355.787952 -233.880882) (xy 355.795847 -233.929459)
			(xy 355.796342 -233.954066) (xy 356.125284 -233.954066) (xy 356.129244 -233.905012) (xy 356.141021 -233.857228)
			(xy 356.160312 -233.811952) (xy 356.186615 -233.770356) (xy 356.21925 -233.733519) (xy 356.257371 -233.702394)
			(xy 356.299992 -233.677787) (xy 356.346008 -233.660335) (xy 356.394227 -233.650491) (xy 356.443402 -233.64851)
			(xy 356.492257 -233.654442) (xy 356.539528 -233.668134) (xy 356.58399 -233.689232) (xy 356.624493 -233.717188)
			(xy 356.659986 -233.75128) (xy 356.689551 -233.790624) (xy 356.712422 -233.834201) (xy 356.728006 -233.880882)
			(xy 356.735901 -233.929459) (xy 356.736396 -233.954066) (xy 357.065338 -233.954066) (xy 357.069298 -233.905012)
			(xy 357.081075 -233.857228) (xy 357.100366 -233.811952) (xy 357.126669 -233.770356) (xy 357.159304 -233.733519)
			(xy 357.197425 -233.702394) (xy 357.240046 -233.677787) (xy 357.286062 -233.660335) (xy 357.334281 -233.650491)
			(xy 357.383456 -233.64851) (xy 357.432311 -233.654442) (xy 357.479582 -233.668134) (xy 357.524044 -233.689232)
			(xy 357.564547 -233.717188) (xy 357.60004 -233.75128) (xy 357.629605 -233.790624) (xy 357.652476 -233.834201)
			(xy 357.66806 -233.880882) (xy 357.675955 -233.929459) (xy 357.67645 -233.954066) (xy 358.005392 -233.954066)
			(xy 358.009352 -233.905012) (xy 358.021129 -233.857228) (xy 358.04042 -233.811952) (xy 358.066723 -233.770356)
			(xy 358.099358 -233.733519) (xy 358.137479 -233.702394) (xy 358.1801 -233.677787) (xy 358.226116 -233.660335)
			(xy 358.274335 -233.650491) (xy 358.32351 -233.64851) (xy 358.372365 -233.654442) (xy 358.419636 -233.668134)
			(xy 358.464098 -233.689232) (xy 358.504601 -233.717188) (xy 358.540094 -233.75128) (xy 358.569659 -233.790624)
			(xy 358.59253 -233.834201) (xy 358.608114 -233.880882) (xy 358.616009 -233.929459) (xy 358.616504 -233.954066)
			(xy 360.81895 -233.954066) (xy 360.82291 -233.905012) (xy 360.834687 -233.857228) (xy 360.853978 -233.811952)
			(xy 360.880281 -233.770356) (xy 360.912916 -233.733519) (xy 360.951037 -233.702394) (xy 360.993658 -233.677787)
			(xy 361.039674 -233.660335) (xy 361.087893 -233.650491) (xy 361.137068 -233.64851) (xy 361.185923 -233.654442)
			(xy 361.233194 -233.668134) (xy 361.277656 -233.689232) (xy 361.318159 -233.717188) (xy 361.353652 -233.75128)
			(xy 361.383217 -233.790624) (xy 361.406088 -233.834201) (xy 361.421672 -233.880882) (xy 361.429567 -233.929459)
			(xy 361.430062 -233.954066) (xy 361.430061 -233.9541) (xy 361.758651 -233.9541) (xy 361.762827 -233.903709)
			(xy 361.77524 -233.854692) (xy 361.795552 -233.808387) (xy 361.823208 -233.766057) (xy 361.857454 -233.728856)
			(xy 361.897357 -233.6978) (xy 361.941827 -233.673735) (xy 361.989652 -233.657318) (xy 362.039526 -233.648997)
			(xy 362.064808 -233.648504) (xy 363.004862 -233.648504) (xy 363.03014 -233.649062) (xy 363.080007 -233.657378)
			(xy 363.127825 -233.673788) (xy 363.17229 -233.697847) (xy 363.212188 -233.728896) (xy 363.246431 -233.766089)
			(xy 363.274084 -233.808411) (xy 363.294394 -233.854708) (xy 363.306805 -233.903717) (xy 363.310978 -233.954066)
			(xy 363.639112 -233.954066) (xy 363.643072 -233.905012) (xy 363.654849 -233.857228) (xy 363.67414 -233.811952)
			(xy 363.700443 -233.770356) (xy 363.733078 -233.733519) (xy 363.771199 -233.702394) (xy 363.81382 -233.677787)
			(xy 363.859836 -233.660335) (xy 363.908055 -233.650491) (xy 363.95723 -233.64851) (xy 364.006085 -233.654442)
			(xy 364.053356 -233.668134) (xy 364.097818 -233.689232) (xy 364.138321 -233.717188) (xy 364.173814 -233.75128)
			(xy 364.203379 -233.790624) (xy 364.22625 -233.834201) (xy 364.241834 -233.880882) (xy 364.249729 -233.929459)
			(xy 364.250224 -233.954066) (xy 366.45902 -233.954066) (xy 366.46298 -233.905012) (xy 366.474757 -233.857228)
			(xy 366.494048 -233.811952) (xy 366.520351 -233.770356) (xy 366.552986 -233.733519) (xy 366.591107 -233.702394)
			(xy 366.633728 -233.677787) (xy 366.679744 -233.660335) (xy 366.727963 -233.650491) (xy 366.777138 -233.64851)
			(xy 366.825993 -233.654442) (xy 366.873264 -233.668134) (xy 366.917726 -233.689232) (xy 366.958229 -233.717188)
			(xy 366.993722 -233.75128) (xy 367.023287 -233.790624) (xy 367.046158 -233.834201) (xy 367.061742 -233.880882)
			(xy 367.069637 -233.929459) (xy 367.070132 -233.954066) (xy 369.278928 -233.954066) (xy 369.282888 -233.905012)
			(xy 369.294665 -233.857228) (xy 369.313956 -233.811952) (xy 369.340259 -233.770356) (xy 369.372894 -233.733519)
			(xy 369.411015 -233.702394) (xy 369.453636 -233.677787) (xy 369.499652 -233.660335) (xy 369.547871 -233.650491)
			(xy 369.597046 -233.64851) (xy 369.645901 -233.654442) (xy 369.693172 -233.668134) (xy 369.737634 -233.689232)
			(xy 369.778137 -233.717188) (xy 369.81363 -233.75128) (xy 369.843195 -233.790624) (xy 369.866066 -233.834201)
			(xy 369.88165 -233.880882) (xy 369.889545 -233.929459) (xy 369.89004 -233.954066) (xy 372.09909 -233.954066)
			(xy 372.10305 -233.905012) (xy 372.114827 -233.857228) (xy 372.134118 -233.811952) (xy 372.160421 -233.770356)
			(xy 372.193056 -233.733519) (xy 372.231177 -233.702394) (xy 372.273798 -233.677787) (xy 372.319814 -233.660335)
			(xy 372.368033 -233.650491) (xy 372.417208 -233.64851) (xy 372.466063 -233.654442) (xy 372.513334 -233.668134)
			(xy 372.557796 -233.689232) (xy 372.598299 -233.717188) (xy 372.633792 -233.75128) (xy 372.663357 -233.790624)
			(xy 372.686228 -233.834201) (xy 372.701812 -233.880882) (xy 372.709707 -233.929459) (xy 372.710202 -233.954066)
			(xy 372.709707 -233.978673) (xy 372.701812 -234.02725) (xy 372.686228 -234.073931) (xy 372.663357 -234.117508)
			(xy 372.633792 -234.156852) (xy 372.598299 -234.190944) (xy 372.557796 -234.2189) (xy 372.513334 -234.239998)
			(xy 372.466063 -234.25369) (xy 372.417208 -234.259622) (xy 372.368033 -234.257641) (xy 372.319814 -234.247797)
			(xy 372.273798 -234.230345) (xy 372.231177 -234.205738) (xy 372.193056 -234.174613) (xy 372.160421 -234.137776)
			(xy 372.134118 -234.09618) (xy 372.114827 -234.050904) (xy 372.10305 -234.00312) (xy 372.09909 -233.954066)
			(xy 369.89004 -233.954066) (xy 369.889545 -233.978673) (xy 369.88165 -234.02725) (xy 369.866066 -234.073931)
			(xy 369.843195 -234.117508) (xy 369.81363 -234.156852) (xy 369.778137 -234.190944) (xy 369.737634 -234.2189)
			(xy 369.693172 -234.239998) (xy 369.645901 -234.25369) (xy 369.597046 -234.259622) (xy 369.547871 -234.257641)
			(xy 369.499652 -234.247797) (xy 369.453636 -234.230345) (xy 369.411015 -234.205738) (xy 369.372894 -234.174613)
			(xy 369.340259 -234.137776) (xy 369.313956 -234.09618) (xy 369.294665 -234.050904) (xy 369.282888 -234.00312)
			(xy 369.278928 -233.954066) (xy 367.070132 -233.954066) (xy 367.069637 -233.978673) (xy 367.061742 -234.02725)
			(xy 367.046158 -234.073931) (xy 367.023287 -234.117508) (xy 366.993722 -234.156852) (xy 366.958229 -234.190944)
			(xy 366.917726 -234.2189) (xy 366.873264 -234.239998) (xy 366.825993 -234.25369) (xy 366.777138 -234.259622)
			(xy 366.727963 -234.257641) (xy 366.679744 -234.247797) (xy 366.633728 -234.230345) (xy 366.591107 -234.205738)
			(xy 366.552986 -234.174613) (xy 366.520351 -234.137776) (xy 366.494048 -234.09618) (xy 366.474757 -234.050904)
			(xy 366.46298 -234.00312) (xy 366.45902 -233.954066) (xy 364.250224 -233.954066) (xy 364.249729 -233.978673)
			(xy 364.241834 -234.02725) (xy 364.22625 -234.073931) (xy 364.203379 -234.117508) (xy 364.173814 -234.156852)
			(xy 364.138321 -234.190944) (xy 364.097818 -234.2189) (xy 364.053356 -234.239998) (xy 364.006085 -234.25369)
			(xy 363.95723 -234.259622) (xy 363.908055 -234.257641) (xy 363.859836 -234.247797) (xy 363.81382 -234.230345)
			(xy 363.771199 -234.205738) (xy 363.733078 -234.174613) (xy 363.700443 -234.137776) (xy 363.67414 -234.09618)
			(xy 363.654849 -234.050904) (xy 363.643072 -234.00312) (xy 363.639112 -233.954066) (xy 363.310978 -233.954066)
			(xy 363.310981 -233.9541) (xy 363.306805 -234.004483) (xy 363.294394 -234.053492) (xy 363.274084 -234.099789)
			(xy 363.246431 -234.142111) (xy 363.212188 -234.179304) (xy 363.17229 -234.210353) (xy 363.127825 -234.234412)
			(xy 363.080007 -234.250822) (xy 363.03014 -234.259138) (xy 363.004862 -234.259628) (xy 362.064808 -234.259628)
			(xy 362.039526 -234.259203) (xy 361.989652 -234.250882) (xy 361.941827 -234.234465) (xy 361.897357 -234.2104)
			(xy 361.857454 -234.179344) (xy 361.823208 -234.142143) (xy 361.795552 -234.099813) (xy 361.77524 -234.053508)
			(xy 361.762827 -234.004491) (xy 361.758651 -233.9541) (xy 361.430061 -233.9541) (xy 361.429567 -233.978673)
			(xy 361.421672 -234.02725) (xy 361.406088 -234.073931) (xy 361.383217 -234.117508) (xy 361.353652 -234.156852)
			(xy 361.318159 -234.190944) (xy 361.277656 -234.2189) (xy 361.233194 -234.239998) (xy 361.185923 -234.25369)
			(xy 361.137068 -234.259622) (xy 361.087893 -234.257641) (xy 361.039674 -234.247797) (xy 360.993658 -234.230345)
			(xy 360.951037 -234.205738) (xy 360.912916 -234.174613) (xy 360.880281 -234.137776) (xy 360.853978 -234.09618)
			(xy 360.834687 -234.050904) (xy 360.82291 -234.00312) (xy 360.81895 -233.954066) (xy 358.616504 -233.954066)
			(xy 358.616009 -233.978673) (xy 358.608114 -234.02725) (xy 358.59253 -234.073931) (xy 358.569659 -234.117508)
			(xy 358.540094 -234.156852) (xy 358.504601 -234.190944) (xy 358.464098 -234.2189) (xy 358.419636 -234.239998)
			(xy 358.372365 -234.25369) (xy 358.32351 -234.259622) (xy 358.274335 -234.257641) (xy 358.226116 -234.247797)
			(xy 358.1801 -234.230345) (xy 358.137479 -234.205738) (xy 358.099358 -234.174613) (xy 358.066723 -234.137776)
			(xy 358.04042 -234.09618) (xy 358.021129 -234.050904) (xy 358.009352 -234.00312) (xy 358.005392 -233.954066)
			(xy 357.67645 -233.954066) (xy 357.675955 -233.978673) (xy 357.66806 -234.02725) (xy 357.652476 -234.073931)
			(xy 357.629605 -234.117508) (xy 357.60004 -234.156852) (xy 357.564547 -234.190944) (xy 357.524044 -234.2189)
			(xy 357.479582 -234.239998) (xy 357.432311 -234.25369) (xy 357.383456 -234.259622) (xy 357.334281 -234.257641)
			(xy 357.286062 -234.247797) (xy 357.240046 -234.230345) (xy 357.197425 -234.205738) (xy 357.159304 -234.174613)
			(xy 357.126669 -234.137776) (xy 357.100366 -234.09618) (xy 357.081075 -234.050904) (xy 357.069298 -234.00312)
			(xy 357.065338 -233.954066) (xy 356.736396 -233.954066) (xy 356.735901 -233.978673) (xy 356.728006 -234.02725)
			(xy 356.712422 -234.073931) (xy 356.689551 -234.117508) (xy 356.659986 -234.156852) (xy 356.624493 -234.190944)
			(xy 356.58399 -234.2189) (xy 356.539528 -234.239998) (xy 356.492257 -234.25369) (xy 356.443402 -234.259622)
			(xy 356.394227 -234.257641) (xy 356.346008 -234.247797) (xy 356.299992 -234.230345) (xy 356.257371 -234.205738)
			(xy 356.21925 -234.174613) (xy 356.186615 -234.137776) (xy 356.160312 -234.09618) (xy 356.141021 -234.050904)
			(xy 356.129244 -234.00312) (xy 356.125284 -233.954066) (xy 355.796342 -233.954066) (xy 355.795847 -233.978673)
			(xy 355.787952 -234.02725) (xy 355.772368 -234.073931) (xy 355.749497 -234.117508) (xy 355.719932 -234.156852)
			(xy 355.684439 -234.190944) (xy 355.643936 -234.2189) (xy 355.599474 -234.239998) (xy 355.552203 -234.25369)
			(xy 355.503348 -234.259622) (xy 355.454173 -234.257641) (xy 355.405954 -234.247797) (xy 355.359938 -234.230345)
			(xy 355.317317 -234.205738) (xy 355.279196 -234.174613) (xy 355.246561 -234.137776) (xy 355.220258 -234.09618)
			(xy 355.200967 -234.050904) (xy 355.18919 -234.00312) (xy 355.18523 -233.954066) (xy 352.976434 -233.954066)
			(xy 352.975939 -233.978673) (xy 352.968044 -234.02725) (xy 352.95246 -234.073931) (xy 352.929589 -234.117508)
			(xy 352.900024 -234.156852) (xy 352.864531 -234.190944) (xy 352.824028 -234.2189) (xy 352.779566 -234.239998)
			(xy 352.732295 -234.25369) (xy 352.68344 -234.259622) (xy 352.634265 -234.257641) (xy 352.586046 -234.247797)
			(xy 352.54003 -234.230345) (xy 352.497409 -234.205738) (xy 352.459288 -234.174613) (xy 352.426653 -234.137776)
			(xy 352.40035 -234.09618) (xy 352.381059 -234.050904) (xy 352.369282 -234.00312) (xy 352.365322 -233.954066)
			(xy 350.156526 -233.954066) (xy 350.156031 -233.978673) (xy 350.148136 -234.02725) (xy 350.132552 -234.073931)
			(xy 350.109681 -234.117508) (xy 350.080116 -234.156852) (xy 350.044623 -234.190944) (xy 350.00412 -234.2189)
			(xy 349.959658 -234.239998) (xy 349.912387 -234.25369) (xy 349.863532 -234.259622) (xy 349.814357 -234.257641)
			(xy 349.766138 -234.247797) (xy 349.720122 -234.230345) (xy 349.677501 -234.205738) (xy 349.63938 -234.174613)
			(xy 349.606745 -234.137776) (xy 349.580442 -234.09618) (xy 349.561151 -234.050904) (xy 349.549374 -234.00312)
			(xy 349.545414 -233.954066) (xy 347.336364 -233.954066) (xy 347.335869 -233.978673) (xy 347.327974 -234.02725)
			(xy 347.31239 -234.073931) (xy 347.289519 -234.117508) (xy 347.259954 -234.156852) (xy 347.224461 -234.190944)
			(xy 347.183958 -234.2189) (xy 347.139496 -234.239998) (xy 347.092225 -234.25369) (xy 347.04337 -234.259622)
			(xy 346.994195 -234.257641) (xy 346.945976 -234.247797) (xy 346.89996 -234.230345) (xy 346.857339 -234.205738)
			(xy 346.819218 -234.174613) (xy 346.786583 -234.137776) (xy 346.76028 -234.09618) (xy 346.740989 -234.050904)
			(xy 346.729212 -234.00312) (xy 346.725252 -233.954066) (xy 344.626438 -233.954066) (xy 344.626438 -234.38739)
			(xy 344.626896 -234.397541) (xy 344.634772 -234.416255) (xy 344.641678 -234.423712) (xy 344.669618 -234.451144)
			(xy 344.686636 -234.458764) (xy 344.696034 -234.459018) (xy 344.720455 -234.460706) (xy 344.768336 -234.470881)
			(xy 344.81398 -234.488562) (xy 344.856221 -234.513296) (xy 344.893976 -234.54445) (xy 344.92628 -234.581227)
			(xy 344.952305 -234.622685) (xy 344.971386 -234.667762) (xy 344.983033 -234.715306) (xy 344.986947 -234.764072)
			(xy 345.315298 -234.764072) (xy 345.319258 -234.715018) (xy 345.331035 -234.667234) (xy 345.350326 -234.621958)
			(xy 345.376629 -234.580362) (xy 345.409264 -234.543525) (xy 345.447385 -234.5124) (xy 345.490006 -234.487793)
			(xy 345.536022 -234.470341) (xy 345.584241 -234.460497) (xy 345.633416 -234.458516) (xy 345.682271 -234.464448)
			(xy 345.729542 -234.47814) (xy 345.774004 -234.499238) (xy 345.814507 -234.527194) (xy 345.85 -234.561286)
			(xy 345.879565 -234.60063) (xy 345.902436 -234.644207) (xy 345.91802 -234.690888) (xy 345.925915 -234.739465)
			(xy 345.92641 -234.764072) (xy 346.255352 -234.764072) (xy 346.259312 -234.715018) (xy 346.271089 -234.667234)
			(xy 346.29038 -234.621958) (xy 346.316683 -234.580362) (xy 346.349318 -234.543525) (xy 346.387439 -234.5124)
			(xy 346.43006 -234.487793) (xy 346.476076 -234.470341) (xy 346.524295 -234.460497) (xy 346.57347 -234.458516)
			(xy 346.622325 -234.464448) (xy 346.669596 -234.47814) (xy 346.714058 -234.499238) (xy 346.754561 -234.527194)
			(xy 346.790054 -234.561286) (xy 346.819619 -234.60063) (xy 346.84249 -234.644207) (xy 346.858074 -234.690888)
			(xy 346.865969 -234.739465) (xy 346.866464 -234.764072) (xy 347.195406 -234.764072) (xy 347.199366 -234.715018)
			(xy 347.211143 -234.667234) (xy 347.230434 -234.621958) (xy 347.256737 -234.580362) (xy 347.289372 -234.543525)
			(xy 347.327493 -234.5124) (xy 347.370114 -234.487793) (xy 347.41613 -234.470341) (xy 347.464349 -234.460497)
			(xy 347.513524 -234.458516) (xy 347.562379 -234.464448) (xy 347.60965 -234.47814) (xy 347.654112 -234.499238)
			(xy 347.694615 -234.527194) (xy 347.730108 -234.561286) (xy 347.759673 -234.60063) (xy 347.782544 -234.644207)
			(xy 347.798128 -234.690888) (xy 347.806023 -234.739465) (xy 347.806518 -234.764072) (xy 348.135206 -234.764072)
			(xy 348.139166 -234.715018) (xy 348.150943 -234.667234) (xy 348.170234 -234.621958) (xy 348.196537 -234.580362)
			(xy 348.229172 -234.543525) (xy 348.267293 -234.5124) (xy 348.309914 -234.487793) (xy 348.35593 -234.470341)
			(xy 348.404149 -234.460497) (xy 348.453324 -234.458516) (xy 348.502179 -234.464448) (xy 348.54945 -234.47814)
			(xy 348.593912 -234.499238) (xy 348.634415 -234.527194) (xy 348.669908 -234.561286) (xy 348.699473 -234.60063)
			(xy 348.722344 -234.644207) (xy 348.737928 -234.690888) (xy 348.745823 -234.739465) (xy 348.746318 -234.764072)
			(xy 349.07526 -234.764072) (xy 349.07922 -234.715018) (xy 349.090997 -234.667234) (xy 349.110288 -234.621958)
			(xy 349.136591 -234.580362) (xy 349.169226 -234.543525) (xy 349.207347 -234.5124) (xy 349.249968 -234.487793)
			(xy 349.295984 -234.470341) (xy 349.344203 -234.460497) (xy 349.393378 -234.458516) (xy 349.442233 -234.464448)
			(xy 349.489504 -234.47814) (xy 349.533966 -234.499238) (xy 349.574469 -234.527194) (xy 349.609962 -234.561286)
			(xy 349.639527 -234.60063) (xy 349.662398 -234.644207) (xy 349.677982 -234.690888) (xy 349.685877 -234.739465)
			(xy 349.686372 -234.764072) (xy 350.015314 -234.764072) (xy 350.019274 -234.715018) (xy 350.031051 -234.667234)
			(xy 350.050342 -234.621958) (xy 350.076645 -234.580362) (xy 350.10928 -234.543525) (xy 350.147401 -234.5124)
			(xy 350.190022 -234.487793) (xy 350.236038 -234.470341) (xy 350.284257 -234.460497) (xy 350.333432 -234.458516)
			(xy 350.382287 -234.464448) (xy 350.429558 -234.47814) (xy 350.47402 -234.499238) (xy 350.514523 -234.527194)
			(xy 350.550016 -234.561286) (xy 350.579581 -234.60063) (xy 350.602452 -234.644207) (xy 350.618036 -234.690888)
			(xy 350.625931 -234.739465) (xy 350.626426 -234.764072) (xy 350.955368 -234.764072) (xy 350.959328 -234.715018)
			(xy 350.971105 -234.667234) (xy 350.990396 -234.621958) (xy 351.016699 -234.580362) (xy 351.049334 -234.543525)
			(xy 351.087455 -234.5124) (xy 351.130076 -234.487793) (xy 351.176092 -234.470341) (xy 351.224311 -234.460497)
			(xy 351.273486 -234.458516) (xy 351.322341 -234.464448) (xy 351.369612 -234.47814) (xy 351.414074 -234.499238)
			(xy 351.454577 -234.527194) (xy 351.49007 -234.561286) (xy 351.519635 -234.60063) (xy 351.542506 -234.644207)
			(xy 351.55809 -234.690888) (xy 351.565985 -234.739465) (xy 351.56648 -234.764072) (xy 351.895422 -234.764072)
			(xy 351.899382 -234.715018) (xy 351.911159 -234.667234) (xy 351.93045 -234.621958) (xy 351.956753 -234.580362)
			(xy 351.989388 -234.543525) (xy 352.027509 -234.5124) (xy 352.07013 -234.487793) (xy 352.116146 -234.470341)
			(xy 352.164365 -234.460497) (xy 352.21354 -234.458516) (xy 352.262395 -234.464448) (xy 352.309666 -234.47814)
			(xy 352.354128 -234.499238) (xy 352.394631 -234.527194) (xy 352.430124 -234.561286) (xy 352.459689 -234.60063)
			(xy 352.48256 -234.644207) (xy 352.498144 -234.690888) (xy 352.506039 -234.739465) (xy 352.506534 -234.764072)
			(xy 352.835222 -234.764072) (xy 352.839182 -234.715018) (xy 352.850959 -234.667234) (xy 352.87025 -234.621958)
			(xy 352.896553 -234.580362) (xy 352.929188 -234.543525) (xy 352.967309 -234.5124) (xy 353.00993 -234.487793)
			(xy 353.055946 -234.470341) (xy 353.104165 -234.460497) (xy 353.15334 -234.458516) (xy 353.202195 -234.464448)
			(xy 353.249466 -234.47814) (xy 353.293928 -234.499238) (xy 353.334431 -234.527194) (xy 353.369924 -234.561286)
			(xy 353.399489 -234.60063) (xy 353.42236 -234.644207) (xy 353.437944 -234.690888) (xy 353.445839 -234.739465)
			(xy 353.446334 -234.764072) (xy 353.775276 -234.764072) (xy 353.779236 -234.715018) (xy 353.791013 -234.667234)
			(xy 353.810304 -234.621958) (xy 353.836607 -234.580362) (xy 353.869242 -234.543525) (xy 353.907363 -234.5124)
			(xy 353.949984 -234.487793) (xy 353.996 -234.470341) (xy 354.044219 -234.460497) (xy 354.093394 -234.458516)
			(xy 354.142249 -234.464448) (xy 354.18952 -234.47814) (xy 354.233982 -234.499238) (xy 354.274485 -234.527194)
			(xy 354.309978 -234.561286) (xy 354.339543 -234.60063) (xy 354.362414 -234.644207) (xy 354.377998 -234.690888)
			(xy 354.385893 -234.739465) (xy 354.386388 -234.764072) (xy 354.71533 -234.764072) (xy 354.71929 -234.715018)
			(xy 354.731067 -234.667234) (xy 354.750358 -234.621958) (xy 354.776661 -234.580362) (xy 354.809296 -234.543525)
			(xy 354.847417 -234.5124) (xy 354.890038 -234.487793) (xy 354.936054 -234.470341) (xy 354.984273 -234.460497)
			(xy 355.033448 -234.458516) (xy 355.082303 -234.464448) (xy 355.129574 -234.47814) (xy 355.174036 -234.499238)
			(xy 355.214539 -234.527194) (xy 355.250032 -234.561286) (xy 355.279597 -234.60063) (xy 355.302468 -234.644207)
			(xy 355.318052 -234.690888) (xy 355.325947 -234.739465) (xy 355.326442 -234.764072) (xy 355.655384 -234.764072)
			(xy 355.659344 -234.715018) (xy 355.671121 -234.667234) (xy 355.690412 -234.621958) (xy 355.716715 -234.580362)
			(xy 355.74935 -234.543525) (xy 355.787471 -234.5124) (xy 355.830092 -234.487793) (xy 355.876108 -234.470341)
			(xy 355.924327 -234.460497) (xy 355.973502 -234.458516) (xy 356.022357 -234.464448) (xy 356.069628 -234.47814)
			(xy 356.11409 -234.499238) (xy 356.154593 -234.527194) (xy 356.190086 -234.561286) (xy 356.219651 -234.60063)
			(xy 356.242522 -234.644207) (xy 356.258106 -234.690888) (xy 356.266001 -234.739465) (xy 356.266496 -234.764072)
			(xy 363.168958 -234.764072) (xy 363.172918 -234.715018) (xy 363.184695 -234.667234) (xy 363.203986 -234.621958)
			(xy 363.230289 -234.580362) (xy 363.262924 -234.543525) (xy 363.301045 -234.5124) (xy 363.343666 -234.487793)
			(xy 363.389682 -234.470341) (xy 363.437901 -234.460497) (xy 363.487076 -234.458516) (xy 363.535931 -234.464448)
			(xy 363.583202 -234.47814) (xy 363.627664 -234.499238) (xy 363.668167 -234.527194) (xy 363.70366 -234.561286)
			(xy 363.733225 -234.60063) (xy 363.756096 -234.644207) (xy 363.77168 -234.690888) (xy 363.779575 -234.739465)
			(xy 363.78007 -234.764072) (xy 363.780069 -234.7641) (xy 364.108912 -234.7641) (xy 364.113084 -234.713751)
			(xy 364.125487 -234.664775) (xy 364.145782 -234.618509) (xy 364.173416 -234.576214) (xy 364.207634 -234.539045)
			(xy 364.247504 -234.508015) (xy 364.291937 -234.483971) (xy 364.339722 -234.467569) (xy 364.389555 -234.459256)
			(xy 364.414816 -234.458764) (xy 365.35487 -234.458764) (xy 365.380127 -234.45931) (xy 365.429953 -234.46762)
			(xy 365.477731 -234.484018) (xy 365.522158 -234.508057) (xy 365.562023 -234.539081) (xy 365.596237 -234.576244)
			(xy 365.623867 -234.618532) (xy 365.644159 -234.664791) (xy 365.65656 -234.713759) (xy 365.66073 -234.764072)
			(xy 365.98912 -234.764072) (xy 365.99308 -234.715018) (xy 366.004857 -234.667234) (xy 366.024148 -234.621958)
			(xy 366.050451 -234.580362) (xy 366.083086 -234.543525) (xy 366.121207 -234.5124) (xy 366.163828 -234.487793)
			(xy 366.209844 -234.470341) (xy 366.258063 -234.460497) (xy 366.307238 -234.458516) (xy 366.356093 -234.464448)
			(xy 366.403364 -234.47814) (xy 366.447826 -234.499238) (xy 366.488329 -234.527194) (xy 366.523822 -234.561286)
			(xy 366.553387 -234.60063) (xy 366.576258 -234.644207) (xy 366.591842 -234.690888) (xy 366.599737 -234.739465)
			(xy 366.600232 -234.764072) (xy 366.600231 -234.7641) (xy 366.928812 -234.7641) (xy 366.932984 -234.71375)
			(xy 366.945387 -234.664774) (xy 366.965683 -234.618507) (xy 366.993318 -234.576212) (xy 367.027537 -234.539042)
			(xy 367.067408 -234.508013) (xy 367.111842 -234.483969) (xy 367.159629 -234.467567) (xy 367.209463 -234.459255)
			(xy 367.234724 -234.458764) (xy 368.174778 -234.458764) (xy 368.200035 -234.459311) (xy 368.249859 -234.467622)
			(xy 368.297636 -234.484021) (xy 368.342063 -234.50806) (xy 368.381926 -234.539084) (xy 368.416139 -234.576247)
			(xy 368.443768 -234.618534) (xy 368.46406 -234.664792) (xy 368.47646 -234.713759) (xy 368.48063 -234.764072)
			(xy 368.809028 -234.764072) (xy 368.812988 -234.715018) (xy 368.824765 -234.667234) (xy 368.844056 -234.621958)
			(xy 368.870359 -234.580362) (xy 368.902994 -234.543525) (xy 368.941115 -234.5124) (xy 368.983736 -234.487793)
			(xy 369.029752 -234.470341) (xy 369.077971 -234.460497) (xy 369.127146 -234.458516) (xy 369.176001 -234.464448)
			(xy 369.223272 -234.47814) (xy 369.267734 -234.499238) (xy 369.308237 -234.527194) (xy 369.34373 -234.561286)
			(xy 369.373295 -234.60063) (xy 369.396166 -234.644207) (xy 369.41175 -234.690888) (xy 369.419645 -234.739465)
			(xy 369.42014 -234.764072) (xy 369.420139 -234.7641) (xy 369.749041 -234.7641) (xy 369.753212 -234.713759)
			(xy 369.765612 -234.664791) (xy 369.785903 -234.618531) (xy 369.813531 -234.576242) (xy 369.847742 -234.539077)
			(xy 369.887604 -234.50805) (xy 369.932028 -234.484007) (xy 369.979805 -234.467603) (xy 370.029629 -234.459287)
			(xy 370.054886 -234.458764) (xy 370.99494 -234.458764) (xy 371.020191 -234.459345) (xy 371.070003 -234.467663)
			(xy 371.117767 -234.484066) (xy 371.16218 -234.508106) (xy 371.20203 -234.539128) (xy 371.236232 -234.576285)
			(xy 371.263852 -234.618565) (xy 371.284136 -234.664814) (xy 371.296533 -234.713771) (xy 371.300701 -234.764072)
			(xy 371.628936 -234.764072) (xy 371.632896 -234.715018) (xy 371.644673 -234.667234) (xy 371.663964 -234.621958)
			(xy 371.690267 -234.580362) (xy 371.722902 -234.543525) (xy 371.761023 -234.5124) (xy 371.803644 -234.487793)
			(xy 371.84966 -234.470341) (xy 371.897879 -234.460497) (xy 371.947054 -234.458516) (xy 371.995909 -234.464448)
			(xy 372.04318 -234.47814) (xy 372.087642 -234.499238) (xy 372.128145 -234.527194) (xy 372.163638 -234.561286)
			(xy 372.193203 -234.60063) (xy 372.216074 -234.644207) (xy 372.231658 -234.690888) (xy 372.239553 -234.739465)
			(xy 372.240048 -234.764072) (xy 372.240047 -234.7641) (xy 372.568941 -234.7641) (xy 372.573112 -234.713758)
			(xy 372.585513 -234.664789) (xy 372.605804 -234.618529) (xy 372.633433 -234.57624) (xy 372.667645 -234.539074)
			(xy 372.707508 -234.508047) (xy 372.751934 -234.484004) (xy 372.799711 -234.467601) (xy 372.849537 -234.459286)
			(xy 372.874794 -234.458764) (xy 373.814848 -234.458764) (xy 373.840098 -234.459345) (xy 373.889909 -234.467664)
			(xy 373.937672 -234.484068) (xy 373.982084 -234.508109) (xy 374.021933 -234.539131) (xy 374.056134 -234.576288)
			(xy 374.083753 -234.618567) (xy 374.104037 -234.664815) (xy 374.116433 -234.713771) (xy 374.120603 -234.7641)
			(xy 374.116433 -234.814429) (xy 374.104037 -234.863384) (xy 374.083753 -234.909633) (xy 374.056134 -234.951912)
			(xy 374.021933 -234.989069) (xy 373.982084 -235.020091) (xy 373.937672 -235.044132) (xy 373.889909 -235.060536)
			(xy 373.840098 -235.068855) (xy 373.814848 -235.06938) (xy 372.874794 -235.06938) (xy 372.849537 -235.068914)
			(xy 372.799711 -235.060599) (xy 372.751934 -235.044196) (xy 372.707508 -235.020153) (xy 372.667645 -234.989126)
			(xy 372.633433 -234.95196) (xy 372.605804 -234.909671) (xy 372.585513 -234.863411) (xy 372.573112 -234.814442)
			(xy 372.568941 -234.7641) (xy 372.240047 -234.7641) (xy 372.239553 -234.788679) (xy 372.231658 -234.837256)
			(xy 372.216074 -234.883937) (xy 372.193203 -234.927514) (xy 372.163638 -234.966858) (xy 372.128145 -235.00095)
			(xy 372.087642 -235.028906) (xy 372.04318 -235.050004) (xy 371.995909 -235.063696) (xy 371.947054 -235.069628)
			(xy 371.897879 -235.067647) (xy 371.84966 -235.057803) (xy 371.803644 -235.040351) (xy 371.761023 -235.015744)
			(xy 371.722902 -234.984619) (xy 371.690267 -234.947782) (xy 371.663964 -234.906186) (xy 371.644673 -234.86091)
			(xy 371.632896 -234.813126) (xy 371.628936 -234.764072) (xy 371.300701 -234.764072) (xy 371.300703 -234.7641)
			(xy 371.296533 -234.814429) (xy 371.284136 -234.863386) (xy 371.263852 -234.909635) (xy 371.236232 -234.951915)
			(xy 371.20203 -234.989072) (xy 371.16218 -235.020094) (xy 371.117767 -235.044134) (xy 371.070003 -235.060537)
			(xy 371.020191 -235.068855) (xy 370.99494 -235.06938) (xy 370.054886 -235.06938) (xy 370.029629 -235.068913)
			(xy 369.979805 -235.060597) (xy 369.932028 -235.044193) (xy 369.887604 -235.02015) (xy 369.847742 -234.989123)
			(xy 369.813531 -234.951958) (xy 369.785903 -234.909669) (xy 369.765612 -234.863409) (xy 369.753212 -234.814441)
			(xy 369.749041 -234.7641) (xy 369.420139 -234.7641) (xy 369.419645 -234.788679) (xy 369.41175 -234.837256)
			(xy 369.396166 -234.883937) (xy 369.373295 -234.927514) (xy 369.34373 -234.966858) (xy 369.308237 -235.00095)
			(xy 369.267734 -235.028906) (xy 369.223272 -235.050004) (xy 369.176001 -235.063696) (xy 369.127146 -235.069628)
			(xy 369.077971 -235.067647) (xy 369.029752 -235.057803) (xy 368.983736 -235.040351) (xy 368.941115 -235.015744)
			(xy 368.902994 -234.984619) (xy 368.870359 -234.947782) (xy 368.844056 -234.906186) (xy 368.824765 -234.86091)
			(xy 368.812988 -234.813126) (xy 368.809028 -234.764072) (xy 368.48063 -234.764072) (xy 368.480632 -234.7641)
			(xy 368.47646 -234.814441) (xy 368.46406 -234.863408) (xy 368.443768 -234.909666) (xy 368.416139 -234.951953)
			(xy 368.381926 -234.989116) (xy 368.342063 -235.02014) (xy 368.297636 -235.044179) (xy 368.249859 -235.060578)
			(xy 368.200035 -235.068889) (xy 368.174778 -235.06938) (xy 367.234724 -235.06938) (xy 367.209463 -235.068945)
			(xy 367.159629 -235.060633) (xy 367.111842 -235.044231) (xy 367.067408 -235.020187) (xy 367.027537 -234.989158)
			(xy 366.993318 -234.951988) (xy 366.965683 -234.909693) (xy 366.945387 -234.863426) (xy 366.932984 -234.81445)
			(xy 366.928812 -234.7641) (xy 366.600231 -234.7641) (xy 366.599737 -234.788679) (xy 366.591842 -234.837256)
			(xy 366.576258 -234.883937) (xy 366.553387 -234.927514) (xy 366.523822 -234.966858) (xy 366.488329 -235.00095)
			(xy 366.447826 -235.028906) (xy 366.403364 -235.050004) (xy 366.356093 -235.063696) (xy 366.307238 -235.069628)
			(xy 366.258063 -235.067647) (xy 366.209844 -235.057803) (xy 366.163828 -235.040351) (xy 366.121207 -235.015744)
			(xy 366.083086 -234.984619) (xy 366.050451 -234.947782) (xy 366.024148 -234.906186) (xy 366.004857 -234.86091)
			(xy 365.99308 -234.813126) (xy 365.98912 -234.764072) (xy 365.66073 -234.764072) (xy 365.660732 -234.7641)
			(xy 365.65656 -234.814441) (xy 365.644159 -234.863409) (xy 365.623867 -234.909668) (xy 365.596237 -234.951956)
			(xy 365.562023 -234.989119) (xy 365.522158 -235.020143) (xy 365.477731 -235.044182) (xy 365.429953 -235.06058)
			(xy 365.380127 -235.06889) (xy 365.35487 -235.06938) (xy 364.414816 -235.06938) (xy 364.389555 -235.068944)
			(xy 364.339722 -235.060631) (xy 364.291937 -235.044229) (xy 364.247504 -235.020185) (xy 364.207634 -234.989155)
			(xy 364.173416 -234.951986) (xy 364.145782 -234.909691) (xy 364.125487 -234.863425) (xy 364.113084 -234.814449)
			(xy 364.108912 -234.7641) (xy 363.780069 -234.7641) (xy 363.779575 -234.788679) (xy 363.77168 -234.837256)
			(xy 363.756096 -234.883937) (xy 363.733225 -234.927514) (xy 363.70366 -234.966858) (xy 363.668167 -235.00095)
			(xy 363.627664 -235.028906) (xy 363.583202 -235.050004) (xy 363.535931 -235.063696) (xy 363.487076 -235.069628)
			(xy 363.437901 -235.067647) (xy 363.389682 -235.057803) (xy 363.343666 -235.040351) (xy 363.301045 -235.015744)
			(xy 363.262924 -234.984619) (xy 363.230289 -234.947782) (xy 363.203986 -234.906186) (xy 363.184695 -234.86091)
			(xy 363.172918 -234.813126) (xy 363.168958 -234.764072) (xy 356.266496 -234.764072) (xy 356.266001 -234.788679)
			(xy 356.258106 -234.837256) (xy 356.242522 -234.883937) (xy 356.219651 -234.927514) (xy 356.190086 -234.966858)
			(xy 356.154593 -235.00095) (xy 356.11409 -235.028906) (xy 356.069628 -235.050004) (xy 356.022357 -235.063696)
			(xy 355.973502 -235.069628) (xy 355.924327 -235.067647) (xy 355.876108 -235.057803) (xy 355.830092 -235.040351)
			(xy 355.787471 -235.015744) (xy 355.74935 -234.984619) (xy 355.716715 -234.947782) (xy 355.690412 -234.906186)
			(xy 355.671121 -234.86091) (xy 355.659344 -234.813126) (xy 355.655384 -234.764072) (xy 355.326442 -234.764072)
			(xy 355.325947 -234.788679) (xy 355.318052 -234.837256) (xy 355.302468 -234.883937) (xy 355.279597 -234.927514)
			(xy 355.250032 -234.966858) (xy 355.214539 -235.00095) (xy 355.174036 -235.028906) (xy 355.129574 -235.050004)
			(xy 355.082303 -235.063696) (xy 355.033448 -235.069628) (xy 354.984273 -235.067647) (xy 354.936054 -235.057803)
			(xy 354.890038 -235.040351) (xy 354.847417 -235.015744) (xy 354.809296 -234.984619) (xy 354.776661 -234.947782)
			(xy 354.750358 -234.906186) (xy 354.731067 -234.86091) (xy 354.71929 -234.813126) (xy 354.71533 -234.764072)
			(xy 354.386388 -234.764072) (xy 354.385893 -234.788679) (xy 354.377998 -234.837256) (xy 354.362414 -234.883937)
			(xy 354.339543 -234.927514) (xy 354.309978 -234.966858) (xy 354.274485 -235.00095) (xy 354.233982 -235.028906)
			(xy 354.18952 -235.050004) (xy 354.142249 -235.063696) (xy 354.093394 -235.069628) (xy 354.044219 -235.067647)
			(xy 353.996 -235.057803) (xy 353.949984 -235.040351) (xy 353.907363 -235.015744) (xy 353.869242 -234.984619)
			(xy 353.836607 -234.947782) (xy 353.810304 -234.906186) (xy 353.791013 -234.86091) (xy 353.779236 -234.813126)
			(xy 353.775276 -234.764072) (xy 353.446334 -234.764072) (xy 353.445839 -234.788679) (xy 353.437944 -234.837256)
			(xy 353.42236 -234.883937) (xy 353.399489 -234.927514) (xy 353.369924 -234.966858) (xy 353.334431 -235.00095)
			(xy 353.293928 -235.028906) (xy 353.249466 -235.050004) (xy 353.202195 -235.063696) (xy 353.15334 -235.069628)
			(xy 353.104165 -235.067647) (xy 353.055946 -235.057803) (xy 353.00993 -235.040351) (xy 352.967309 -235.015744)
			(xy 352.929188 -234.984619) (xy 352.896553 -234.947782) (xy 352.87025 -234.906186) (xy 352.850959 -234.86091)
			(xy 352.839182 -234.813126) (xy 352.835222 -234.764072) (xy 352.506534 -234.764072) (xy 352.506039 -234.788679)
			(xy 352.498144 -234.837256) (xy 352.48256 -234.883937) (xy 352.459689 -234.927514) (xy 352.430124 -234.966858)
			(xy 352.394631 -235.00095) (xy 352.354128 -235.028906) (xy 352.309666 -235.050004) (xy 352.262395 -235.063696)
			(xy 352.21354 -235.069628) (xy 352.164365 -235.067647) (xy 352.116146 -235.057803) (xy 352.07013 -235.040351)
			(xy 352.027509 -235.015744) (xy 351.989388 -234.984619) (xy 351.956753 -234.947782) (xy 351.93045 -234.906186)
			(xy 351.911159 -234.86091) (xy 351.899382 -234.813126) (xy 351.895422 -234.764072) (xy 351.56648 -234.764072)
			(xy 351.565985 -234.788679) (xy 351.55809 -234.837256) (xy 351.542506 -234.883937) (xy 351.519635 -234.927514)
			(xy 351.49007 -234.966858) (xy 351.454577 -235.00095) (xy 351.414074 -235.028906) (xy 351.369612 -235.050004)
			(xy 351.322341 -235.063696) (xy 351.273486 -235.069628) (xy 351.224311 -235.067647) (xy 351.176092 -235.057803)
			(xy 351.130076 -235.040351) (xy 351.087455 -235.015744) (xy 351.049334 -234.984619) (xy 351.016699 -234.947782)
			(xy 350.990396 -234.906186) (xy 350.971105 -234.86091) (xy 350.959328 -234.813126) (xy 350.955368 -234.764072)
			(xy 350.626426 -234.764072) (xy 350.625931 -234.788679) (xy 350.618036 -234.837256) (xy 350.602452 -234.883937)
			(xy 350.579581 -234.927514) (xy 350.550016 -234.966858) (xy 350.514523 -235.00095) (xy 350.47402 -235.028906)
			(xy 350.429558 -235.050004) (xy 350.382287 -235.063696) (xy 350.333432 -235.069628) (xy 350.284257 -235.067647)
			(xy 350.236038 -235.057803) (xy 350.190022 -235.040351) (xy 350.147401 -235.015744) (xy 350.10928 -234.984619)
			(xy 350.076645 -234.947782) (xy 350.050342 -234.906186) (xy 350.031051 -234.86091) (xy 350.019274 -234.813126)
			(xy 350.015314 -234.764072) (xy 349.686372 -234.764072) (xy 349.685877 -234.788679) (xy 349.677982 -234.837256)
			(xy 349.662398 -234.883937) (xy 349.639527 -234.927514) (xy 349.609962 -234.966858) (xy 349.574469 -235.00095)
			(xy 349.533966 -235.028906) (xy 349.489504 -235.050004) (xy 349.442233 -235.063696) (xy 349.393378 -235.069628)
			(xy 349.344203 -235.067647) (xy 349.295984 -235.057803) (xy 349.249968 -235.040351) (xy 349.207347 -235.015744)
			(xy 349.169226 -234.984619) (xy 349.136591 -234.947782) (xy 349.110288 -234.906186) (xy 349.090997 -234.86091)
			(xy 349.07922 -234.813126) (xy 349.07526 -234.764072) (xy 348.746318 -234.764072) (xy 348.745823 -234.788679)
			(xy 348.737928 -234.837256) (xy 348.722344 -234.883937) (xy 348.699473 -234.927514) (xy 348.669908 -234.966858)
			(xy 348.634415 -235.00095) (xy 348.593912 -235.028906) (xy 348.54945 -235.050004) (xy 348.502179 -235.063696)
			(xy 348.453324 -235.069628) (xy 348.404149 -235.067647) (xy 348.35593 -235.057803) (xy 348.309914 -235.040351)
			(xy 348.267293 -235.015744) (xy 348.229172 -234.984619) (xy 348.196537 -234.947782) (xy 348.170234 -234.906186)
			(xy 348.150943 -234.86091) (xy 348.139166 -234.813126) (xy 348.135206 -234.764072) (xy 347.806518 -234.764072)
			(xy 347.806023 -234.788679) (xy 347.798128 -234.837256) (xy 347.782544 -234.883937) (xy 347.759673 -234.927514)
			(xy 347.730108 -234.966858) (xy 347.694615 -235.00095) (xy 347.654112 -235.028906) (xy 347.60965 -235.050004)
			(xy 347.562379 -235.063696) (xy 347.513524 -235.069628) (xy 347.464349 -235.067647) (xy 347.41613 -235.057803)
			(xy 347.370114 -235.040351) (xy 347.327493 -235.015744) (xy 347.289372 -234.984619) (xy 347.256737 -234.947782)
			(xy 347.230434 -234.906186) (xy 347.211143 -234.86091) (xy 347.199366 -234.813126) (xy 347.195406 -234.764072)
			(xy 346.866464 -234.764072) (xy 346.865969 -234.788679) (xy 346.858074 -234.837256) (xy 346.84249 -234.883937)
			(xy 346.819619 -234.927514) (xy 346.790054 -234.966858) (xy 346.754561 -235.00095) (xy 346.714058 -235.028906)
			(xy 346.669596 -235.050004) (xy 346.622325 -235.063696) (xy 346.57347 -235.069628) (xy 346.524295 -235.067647)
			(xy 346.476076 -235.057803) (xy 346.43006 -235.040351) (xy 346.387439 -235.015744) (xy 346.349318 -234.984619)
			(xy 346.316683 -234.947782) (xy 346.29038 -234.906186) (xy 346.271089 -234.86091) (xy 346.259312 -234.813126)
			(xy 346.255352 -234.764072) (xy 345.92641 -234.764072) (xy 345.925915 -234.788679) (xy 345.91802 -234.837256)
			(xy 345.902436 -234.883937) (xy 345.879565 -234.927514) (xy 345.85 -234.966858) (xy 345.814507 -235.00095)
			(xy 345.774004 -235.028906) (xy 345.729542 -235.050004) (xy 345.682271 -235.063696) (xy 345.633416 -235.069628)
			(xy 345.584241 -235.067647) (xy 345.536022 -235.057803) (xy 345.490006 -235.040351) (xy 345.447385 -235.015744)
			(xy 345.409264 -234.984619) (xy 345.376629 -234.947782) (xy 345.350326 -234.906186) (xy 345.331035 -234.86091)
			(xy 345.319258 -234.813126) (xy 345.315298 -234.764072) (xy 344.986947 -234.764072) (xy 344.986949 -234.764099)
			(xy 344.983034 -234.812891) (xy 344.971387 -234.860435) (xy 344.952307 -234.905513) (xy 344.926282 -234.946971)
			(xy 344.893978 -234.983748) (xy 344.856223 -235.014902) (xy 344.813983 -235.039637) (xy 344.768338 -235.057318)
			(xy 344.720458 -235.067494) (xy 344.696034 -235.069126) (xy 344.686636 -235.06938) (xy 344.669618 -235.077)
			(xy 344.641424 -235.104686) (xy 344.634613 -235.111953) (xy 344.626897 -235.130296) (xy 344.626438 -235.140246)
			(xy 344.626438 -235.574078) (xy 344.845398 -235.574078) (xy 344.849358 -235.525024) (xy 344.861135 -235.47724)
			(xy 344.880426 -235.431964) (xy 344.906729 -235.390368) (xy 344.939364 -235.353531) (xy 344.977485 -235.322406)
			(xy 345.020106 -235.297799) (xy 345.066122 -235.280347) (xy 345.114341 -235.270503) (xy 345.163516 -235.268522)
			(xy 345.212371 -235.274454) (xy 345.259642 -235.288146) (xy 345.304104 -235.309244) (xy 345.344607 -235.3372)
			(xy 345.3801 -235.371292) (xy 345.409665 -235.410636) (xy 345.432536 -235.454213) (xy 345.44812 -235.500894)
			(xy 345.456015 -235.549471) (xy 345.45651 -235.574078) (xy 345.785198 -235.574078) (xy 345.789158 -235.525024)
			(xy 345.800935 -235.47724) (xy 345.820226 -235.431964) (xy 345.846529 -235.390368) (xy 345.879164 -235.353531)
			(xy 345.917285 -235.322406) (xy 345.959906 -235.297799) (xy 346.005922 -235.280347) (xy 346.054141 -235.270503)
			(xy 346.103316 -235.268522) (xy 346.152171 -235.274454) (xy 346.199442 -235.288146) (xy 346.243904 -235.309244)
			(xy 346.284407 -235.3372) (xy 346.3199 -235.371292) (xy 346.349465 -235.410636) (xy 346.372336 -235.454213)
			(xy 346.38792 -235.500894) (xy 346.395815 -235.549471) (xy 346.39631 -235.574078) (xy 346.725252 -235.574078)
			(xy 346.729212 -235.525024) (xy 346.740989 -235.47724) (xy 346.76028 -235.431964) (xy 346.786583 -235.390368)
			(xy 346.819218 -235.353531) (xy 346.857339 -235.322406) (xy 346.89996 -235.297799) (xy 346.945976 -235.280347)
			(xy 346.994195 -235.270503) (xy 347.04337 -235.268522) (xy 347.092225 -235.274454) (xy 347.139496 -235.288146)
			(xy 347.183958 -235.309244) (xy 347.224461 -235.3372) (xy 347.259954 -235.371292) (xy 347.289519 -235.410636)
			(xy 347.31239 -235.454213) (xy 347.327974 -235.500894) (xy 347.335869 -235.549471) (xy 347.336364 -235.574078)
			(xy 347.665306 -235.574078) (xy 347.669266 -235.525024) (xy 347.681043 -235.47724) (xy 347.700334 -235.431964)
			(xy 347.726637 -235.390368) (xy 347.759272 -235.353531) (xy 347.797393 -235.322406) (xy 347.840014 -235.297799)
			(xy 347.88603 -235.280347) (xy 347.934249 -235.270503) (xy 347.983424 -235.268522) (xy 348.032279 -235.274454)
			(xy 348.07955 -235.288146) (xy 348.124012 -235.309244) (xy 348.164515 -235.3372) (xy 348.200008 -235.371292)
			(xy 348.229573 -235.410636) (xy 348.252444 -235.454213) (xy 348.268028 -235.500894) (xy 348.275923 -235.549471)
			(xy 348.276418 -235.574078) (xy 348.60536 -235.574078) (xy 348.60932 -235.525024) (xy 348.621097 -235.47724)
			(xy 348.640388 -235.431964) (xy 348.666691 -235.390368) (xy 348.699326 -235.353531) (xy 348.737447 -235.322406)
			(xy 348.780068 -235.297799) (xy 348.826084 -235.280347) (xy 348.874303 -235.270503) (xy 348.923478 -235.268522)
			(xy 348.972333 -235.274454) (xy 349.019604 -235.288146) (xy 349.064066 -235.309244) (xy 349.104569 -235.3372)
			(xy 349.140062 -235.371292) (xy 349.169627 -235.410636) (xy 349.192498 -235.454213) (xy 349.208082 -235.500894)
			(xy 349.215977 -235.549471) (xy 349.216472 -235.574078) (xy 349.545414 -235.574078) (xy 349.549374 -235.525024)
			(xy 349.561151 -235.47724) (xy 349.580442 -235.431964) (xy 349.606745 -235.390368) (xy 349.63938 -235.353531)
			(xy 349.677501 -235.322406) (xy 349.720122 -235.297799) (xy 349.766138 -235.280347) (xy 349.814357 -235.270503)
			(xy 349.863532 -235.268522) (xy 349.912387 -235.274454) (xy 349.959658 -235.288146) (xy 350.00412 -235.309244)
			(xy 350.044623 -235.3372) (xy 350.080116 -235.371292) (xy 350.109681 -235.410636) (xy 350.132552 -235.454213)
			(xy 350.148136 -235.500894) (xy 350.156031 -235.549471) (xy 350.156526 -235.574078) (xy 350.485214 -235.574078)
			(xy 350.489174 -235.525024) (xy 350.500951 -235.47724) (xy 350.520242 -235.431964) (xy 350.546545 -235.390368)
			(xy 350.57918 -235.353531) (xy 350.617301 -235.322406) (xy 350.659922 -235.297799) (xy 350.705938 -235.280347)
			(xy 350.754157 -235.270503) (xy 350.803332 -235.268522) (xy 350.852187 -235.274454) (xy 350.899458 -235.288146)
			(xy 350.94392 -235.309244) (xy 350.984423 -235.3372) (xy 351.019916 -235.371292) (xy 351.049481 -235.410636)
			(xy 351.072352 -235.454213) (xy 351.087936 -235.500894) (xy 351.095831 -235.549471) (xy 351.096326 -235.574078)
			(xy 351.425268 -235.574078) (xy 351.429228 -235.525024) (xy 351.441005 -235.47724) (xy 351.460296 -235.431964)
			(xy 351.486599 -235.390368) (xy 351.519234 -235.353531) (xy 351.557355 -235.322406) (xy 351.599976 -235.297799)
			(xy 351.645992 -235.280347) (xy 351.694211 -235.270503) (xy 351.743386 -235.268522) (xy 351.792241 -235.274454)
			(xy 351.839512 -235.288146) (xy 351.883974 -235.309244) (xy 351.924477 -235.3372) (xy 351.95997 -235.371292)
			(xy 351.989535 -235.410636) (xy 352.012406 -235.454213) (xy 352.02799 -235.500894) (xy 352.035885 -235.549471)
			(xy 352.03638 -235.574078) (xy 352.365322 -235.574078) (xy 352.369282 -235.525024) (xy 352.381059 -235.47724)
			(xy 352.40035 -235.431964) (xy 352.426653 -235.390368) (xy 352.459288 -235.353531) (xy 352.497409 -235.322406)
			(xy 352.54003 -235.297799) (xy 352.586046 -235.280347) (xy 352.634265 -235.270503) (xy 352.68344 -235.268522)
			(xy 352.732295 -235.274454) (xy 352.779566 -235.288146) (xy 352.824028 -235.309244) (xy 352.864531 -235.3372)
			(xy 352.900024 -235.371292) (xy 352.929589 -235.410636) (xy 352.95246 -235.454213) (xy 352.968044 -235.500894)
			(xy 352.975939 -235.549471) (xy 352.976434 -235.574078) (xy 353.305376 -235.574078) (xy 353.309336 -235.525024)
			(xy 353.321113 -235.47724) (xy 353.340404 -235.431964) (xy 353.366707 -235.390368) (xy 353.399342 -235.353531)
			(xy 353.437463 -235.322406) (xy 353.480084 -235.297799) (xy 353.5261 -235.280347) (xy 353.574319 -235.270503)
			(xy 353.623494 -235.268522) (xy 353.672349 -235.274454) (xy 353.71962 -235.288146) (xy 353.764082 -235.309244)
			(xy 353.804585 -235.3372) (xy 353.840078 -235.371292) (xy 353.869643 -235.410636) (xy 353.892514 -235.454213)
			(xy 353.908098 -235.500894) (xy 353.915993 -235.549471) (xy 353.916488 -235.574078) (xy 354.24543 -235.574078)
			(xy 354.24939 -235.525024) (xy 354.261167 -235.47724) (xy 354.280458 -235.431964) (xy 354.306761 -235.390368)
			(xy 354.339396 -235.353531) (xy 354.377517 -235.322406) (xy 354.420138 -235.297799) (xy 354.466154 -235.280347)
			(xy 354.514373 -235.270503) (xy 354.563548 -235.268522) (xy 354.612403 -235.274454) (xy 354.659674 -235.288146)
			(xy 354.704136 -235.309244) (xy 354.744639 -235.3372) (xy 354.780132 -235.371292) (xy 354.809697 -235.410636)
			(xy 354.832568 -235.454213) (xy 354.848152 -235.500894) (xy 354.856047 -235.549471) (xy 354.856542 -235.574078)
			(xy 355.18523 -235.574078) (xy 355.18919 -235.525024) (xy 355.200967 -235.47724) (xy 355.220258 -235.431964)
			(xy 355.246561 -235.390368) (xy 355.279196 -235.353531) (xy 355.317317 -235.322406) (xy 355.359938 -235.297799)
			(xy 355.405954 -235.280347) (xy 355.454173 -235.270503) (xy 355.503348 -235.268522) (xy 355.552203 -235.274454)
			(xy 355.599474 -235.288146) (xy 355.643936 -235.309244) (xy 355.684439 -235.3372) (xy 355.719932 -235.371292)
			(xy 355.749497 -235.410636) (xy 355.772368 -235.454213) (xy 355.787952 -235.500894) (xy 355.795847 -235.549471)
			(xy 355.796342 -235.574078) (xy 356.125284 -235.574078) (xy 356.129244 -235.525024) (xy 356.141021 -235.47724)
			(xy 356.160312 -235.431964) (xy 356.186615 -235.390368) (xy 356.21925 -235.353531) (xy 356.257371 -235.322406)
			(xy 356.299992 -235.297799) (xy 356.346008 -235.280347) (xy 356.394227 -235.270503) (xy 356.443402 -235.268522)
			(xy 356.492257 -235.274454) (xy 356.539528 -235.288146) (xy 356.58399 -235.309244) (xy 356.624493 -235.3372)
			(xy 356.659986 -235.371292) (xy 356.689551 -235.410636) (xy 356.712422 -235.454213) (xy 356.728006 -235.500894)
			(xy 356.735901 -235.549471) (xy 356.736396 -235.574078) (xy 357.065338 -235.574078) (xy 357.069298 -235.525024)
			(xy 357.081075 -235.47724) (xy 357.100366 -235.431964) (xy 357.126669 -235.390368) (xy 357.159304 -235.353531)
			(xy 357.197425 -235.322406) (xy 357.240046 -235.297799) (xy 357.286062 -235.280347) (xy 357.334281 -235.270503)
			(xy 357.383456 -235.268522) (xy 357.432311 -235.274454) (xy 357.479582 -235.288146) (xy 357.524044 -235.309244)
			(xy 357.564547 -235.3372) (xy 357.60004 -235.371292) (xy 357.629605 -235.410636) (xy 357.652476 -235.454213)
			(xy 357.66806 -235.500894) (xy 357.675955 -235.549471) (xy 357.67645 -235.574078) (xy 358.005392 -235.574078)
			(xy 358.009352 -235.525024) (xy 358.021129 -235.47724) (xy 358.04042 -235.431964) (xy 358.066723 -235.390368)
			(xy 358.099358 -235.353531) (xy 358.137479 -235.322406) (xy 358.1801 -235.297799) (xy 358.226116 -235.280347)
			(xy 358.274335 -235.270503) (xy 358.32351 -235.268522) (xy 358.372365 -235.274454) (xy 358.419636 -235.288146)
			(xy 358.464098 -235.309244) (xy 358.504601 -235.3372) (xy 358.540094 -235.371292) (xy 358.569659 -235.410636)
			(xy 358.59253 -235.454213) (xy 358.608114 -235.500894) (xy 358.616009 -235.549471) (xy 358.616504 -235.574078)
			(xy 360.81895 -235.574078) (xy 360.82291 -235.525024) (xy 360.834687 -235.47724) (xy 360.853978 -235.431964)
			(xy 360.880281 -235.390368) (xy 360.912916 -235.353531) (xy 360.951037 -235.322406) (xy 360.993658 -235.297799)
			(xy 361.039674 -235.280347) (xy 361.087893 -235.270503) (xy 361.137068 -235.268522) (xy 361.185923 -235.274454)
			(xy 361.233194 -235.288146) (xy 361.277656 -235.309244) (xy 361.318159 -235.3372) (xy 361.353652 -235.371292)
			(xy 361.383217 -235.410636) (xy 361.406088 -235.454213) (xy 361.421672 -235.500894) (xy 361.429567 -235.549471)
			(xy 361.430062 -235.574078) (xy 361.430062 -235.5741) (xy 361.758663 -235.5741) (xy 361.762839 -235.523711)
			(xy 361.775251 -235.474696) (xy 361.795562 -235.428393) (xy 361.823217 -235.386064) (xy 361.857462 -235.348865)
			(xy 361.897363 -235.31781) (xy 361.941832 -235.293746) (xy 361.989654 -235.27733) (xy 362.039527 -235.269008)
			(xy 362.064808 -235.268516) (xy 363.004862 -235.268516) (xy 363.030141 -235.26905) (xy 363.08001 -235.277366)
			(xy 363.12783 -235.293777) (xy 363.172297 -235.317836) (xy 363.212196 -235.348887) (xy 363.24644 -235.386081)
			(xy 363.274095 -235.428406) (xy 363.294405 -235.474704) (xy 363.306817 -235.523715) (xy 363.310991 -235.574078)
			(xy 363.639112 -235.574078) (xy 363.643072 -235.525024) (xy 363.654849 -235.47724) (xy 363.67414 -235.431964)
			(xy 363.700443 -235.390368) (xy 363.733078 -235.353531) (xy 363.771199 -235.322406) (xy 363.81382 -235.297799)
			(xy 363.859836 -235.280347) (xy 363.908055 -235.270503) (xy 363.95723 -235.268522) (xy 364.006085 -235.274454)
			(xy 364.053356 -235.288146) (xy 364.097818 -235.309244) (xy 364.138321 -235.3372) (xy 364.173814 -235.371292)
			(xy 364.203379 -235.410636) (xy 364.22625 -235.454213) (xy 364.241834 -235.500894) (xy 364.249729 -235.549471)
			(xy 364.250224 -235.574078) (xy 364.578912 -235.574078) (xy 364.582872 -235.525024) (xy 364.594649 -235.47724)
			(xy 364.61394 -235.431964) (xy 364.640243 -235.390368) (xy 364.672878 -235.353531) (xy 364.710999 -235.322406)
			(xy 364.75362 -235.297799) (xy 364.799636 -235.280347) (xy 364.847855 -235.270503) (xy 364.89703 -235.268522)
			(xy 364.945885 -235.274454) (xy 364.993156 -235.288146) (xy 365.037618 -235.309244) (xy 365.078121 -235.3372)
			(xy 365.113614 -235.371292) (xy 365.143179 -235.410636) (xy 365.16605 -235.454213) (xy 365.181634 -235.500894)
			(xy 365.189529 -235.549471) (xy 365.190024 -235.574078) (xy 365.518966 -235.574078) (xy 365.522926 -235.525024)
			(xy 365.534703 -235.47724) (xy 365.553994 -235.431964) (xy 365.580297 -235.390368) (xy 365.612932 -235.353531)
			(xy 365.651053 -235.322406) (xy 365.693674 -235.297799) (xy 365.73969 -235.280347) (xy 365.787909 -235.270503)
			(xy 365.837084 -235.268522) (xy 365.885939 -235.274454) (xy 365.93321 -235.288146) (xy 365.977672 -235.309244)
			(xy 366.018175 -235.3372) (xy 366.053668 -235.371292) (xy 366.083233 -235.410636) (xy 366.106104 -235.454213)
			(xy 366.121688 -235.500894) (xy 366.129583 -235.549471) (xy 366.130078 -235.574078) (xy 366.45902 -235.574078)
			(xy 366.46298 -235.525024) (xy 366.474757 -235.47724) (xy 366.494048 -235.431964) (xy 366.520351 -235.390368)
			(xy 366.552986 -235.353531) (xy 366.591107 -235.322406) (xy 366.633728 -235.297799) (xy 366.679744 -235.280347)
			(xy 366.727963 -235.270503) (xy 366.777138 -235.268522) (xy 366.825993 -235.274454) (xy 366.873264 -235.288146)
			(xy 366.917726 -235.309244) (xy 366.958229 -235.3372) (xy 366.993722 -235.371292) (xy 367.023287 -235.410636)
			(xy 367.046158 -235.454213) (xy 367.061742 -235.500894) (xy 367.069637 -235.549471) (xy 367.070132 -235.574078)
			(xy 367.399074 -235.574078) (xy 367.403034 -235.525024) (xy 367.414811 -235.47724) (xy 367.434102 -235.431964)
			(xy 367.460405 -235.390368) (xy 367.49304 -235.353531) (xy 367.531161 -235.322406) (xy 367.573782 -235.297799)
			(xy 367.619798 -235.280347) (xy 367.668017 -235.270503) (xy 367.717192 -235.268522) (xy 367.766047 -235.274454)
			(xy 367.813318 -235.288146) (xy 367.85778 -235.309244) (xy 367.898283 -235.3372) (xy 367.933776 -235.371292)
			(xy 367.963341 -235.410636) (xy 367.986212 -235.454213) (xy 368.001796 -235.500894) (xy 368.009691 -235.549471)
			(xy 368.010186 -235.574078) (xy 368.338874 -235.574078) (xy 368.342834 -235.525024) (xy 368.354611 -235.47724)
			(xy 368.373902 -235.431964) (xy 368.400205 -235.390368) (xy 368.43284 -235.353531) (xy 368.470961 -235.322406)
			(xy 368.513582 -235.297799) (xy 368.559598 -235.280347) (xy 368.607817 -235.270503) (xy 368.656992 -235.268522)
			(xy 368.705847 -235.274454) (xy 368.753118 -235.288146) (xy 368.79758 -235.309244) (xy 368.838083 -235.3372)
			(xy 368.873576 -235.371292) (xy 368.903141 -235.410636) (xy 368.926012 -235.454213) (xy 368.941596 -235.500894)
			(xy 368.949491 -235.549471) (xy 368.949986 -235.574078) (xy 369.278928 -235.574078) (xy 369.282888 -235.525024)
			(xy 369.294665 -235.47724) (xy 369.313956 -235.431964) (xy 369.340259 -235.390368) (xy 369.372894 -235.353531)
			(xy 369.411015 -235.322406) (xy 369.453636 -235.297799) (xy 369.499652 -235.280347) (xy 369.547871 -235.270503)
			(xy 369.597046 -235.268522) (xy 369.645901 -235.274454) (xy 369.693172 -235.288146) (xy 369.737634 -235.309244)
			(xy 369.778137 -235.3372) (xy 369.81363 -235.371292) (xy 369.843195 -235.410636) (xy 369.866066 -235.454213)
			(xy 369.88165 -235.500894) (xy 369.889545 -235.549471) (xy 369.89004 -235.574078) (xy 370.218982 -235.574078)
			(xy 370.222942 -235.525024) (xy 370.234719 -235.47724) (xy 370.25401 -235.431964) (xy 370.280313 -235.390368)
			(xy 370.312948 -235.353531) (xy 370.351069 -235.322406) (xy 370.39369 -235.297799) (xy 370.439706 -235.280347)
			(xy 370.487925 -235.270503) (xy 370.5371 -235.268522) (xy 370.585955 -235.274454) (xy 370.633226 -235.288146)
			(xy 370.677688 -235.309244) (xy 370.718191 -235.3372) (xy 370.753684 -235.371292) (xy 370.783249 -235.410636)
			(xy 370.80612 -235.454213) (xy 370.821704 -235.500894) (xy 370.829599 -235.549471) (xy 370.830094 -235.574078)
			(xy 371.159036 -235.574078) (xy 371.162996 -235.525024) (xy 371.174773 -235.47724) (xy 371.194064 -235.431964)
			(xy 371.220367 -235.390368) (xy 371.253002 -235.353531) (xy 371.291123 -235.322406) (xy 371.333744 -235.297799)
			(xy 371.37976 -235.280347) (xy 371.427979 -235.270503) (xy 371.477154 -235.268522) (xy 371.526009 -235.274454)
			(xy 371.57328 -235.288146) (xy 371.617742 -235.309244) (xy 371.658245 -235.3372) (xy 371.693738 -235.371292)
			(xy 371.723303 -235.410636) (xy 371.746174 -235.454213) (xy 371.761758 -235.500894) (xy 371.769653 -235.549471)
			(xy 371.770148 -235.574078) (xy 372.09909 -235.574078) (xy 372.10305 -235.525024) (xy 372.114827 -235.47724)
			(xy 372.134118 -235.431964) (xy 372.160421 -235.390368) (xy 372.193056 -235.353531) (xy 372.231177 -235.322406)
			(xy 372.273798 -235.297799) (xy 372.319814 -235.280347) (xy 372.368033 -235.270503) (xy 372.417208 -235.268522)
			(xy 372.466063 -235.274454) (xy 372.513334 -235.288146) (xy 372.557796 -235.309244) (xy 372.598299 -235.3372)
			(xy 372.633792 -235.371292) (xy 372.663357 -235.410636) (xy 372.686228 -235.454213) (xy 372.701812 -235.500894)
			(xy 372.709707 -235.549471) (xy 372.710202 -235.574078) (xy 373.03889 -235.574078) (xy 373.04285 -235.525024)
			(xy 373.054627 -235.47724) (xy 373.073918 -235.431964) (xy 373.100221 -235.390368) (xy 373.132856 -235.353531)
			(xy 373.170977 -235.322406) (xy 373.213598 -235.297799) (xy 373.259614 -235.280347) (xy 373.307833 -235.270503)
			(xy 373.357008 -235.268522) (xy 373.405863 -235.274454) (xy 373.453134 -235.288146) (xy 373.497596 -235.309244)
			(xy 373.538099 -235.3372) (xy 373.573592 -235.371292) (xy 373.603157 -235.410636) (xy 373.626028 -235.454213)
			(xy 373.641612 -235.500894) (xy 373.649507 -235.549471) (xy 373.650002 -235.574078) (xy 373.978944 -235.574078)
			(xy 373.982904 -235.525024) (xy 373.994681 -235.47724) (xy 374.013972 -235.431964) (xy 374.040275 -235.390368)
			(xy 374.07291 -235.353531) (xy 374.111031 -235.322406) (xy 374.153652 -235.297799) (xy 374.199668 -235.280347)
			(xy 374.247887 -235.270503) (xy 374.297062 -235.268522) (xy 374.345917 -235.274454) (xy 374.393188 -235.288146)
			(xy 374.43765 -235.309244) (xy 374.478153 -235.3372) (xy 374.513646 -235.371292) (xy 374.543211 -235.410636)
			(xy 374.566082 -235.454213) (xy 374.581666 -235.500894) (xy 374.589561 -235.549471) (xy 374.590056 -235.574078)
			(xy 374.589561 -235.598685) (xy 374.581666 -235.647262) (xy 374.566082 -235.693943) (xy 374.543211 -235.73752)
			(xy 374.513646 -235.776864) (xy 374.478153 -235.810956) (xy 374.43765 -235.838912) (xy 374.393188 -235.86001)
			(xy 374.345917 -235.873702) (xy 374.297062 -235.879634) (xy 374.247887 -235.877653) (xy 374.199668 -235.867809)
			(xy 374.153652 -235.850357) (xy 374.111031 -235.82575) (xy 374.07291 -235.794625) (xy 374.040275 -235.757788)
			(xy 374.013972 -235.716192) (xy 373.994681 -235.670916) (xy 373.982904 -235.623132) (xy 373.978944 -235.574078)
			(xy 373.650002 -235.574078) (xy 373.649507 -235.598685) (xy 373.641612 -235.647262) (xy 373.626028 -235.693943)
			(xy 373.603157 -235.73752) (xy 373.573592 -235.776864) (xy 373.538099 -235.810956) (xy 373.497596 -235.838912)
			(xy 373.453134 -235.86001) (xy 373.405863 -235.873702) (xy 373.357008 -235.879634) (xy 373.307833 -235.877653)
			(xy 373.259614 -235.867809) (xy 373.213598 -235.850357) (xy 373.170977 -235.82575) (xy 373.132856 -235.794625)
			(xy 373.100221 -235.757788) (xy 373.073918 -235.716192) (xy 373.054627 -235.670916) (xy 373.04285 -235.623132)
			(xy 373.03889 -235.574078) (xy 372.710202 -235.574078) (xy 372.709707 -235.598685) (xy 372.701812 -235.647262)
			(xy 372.686228 -235.693943) (xy 372.663357 -235.73752) (xy 372.633792 -235.776864) (xy 372.598299 -235.810956)
			(xy 372.557796 -235.838912) (xy 372.513334 -235.86001) (xy 372.466063 -235.873702) (xy 372.417208 -235.879634)
			(xy 372.368033 -235.877653) (xy 372.319814 -235.867809) (xy 372.273798 -235.850357) (xy 372.231177 -235.82575)
			(xy 372.193056 -235.794625) (xy 372.160421 -235.757788) (xy 372.134118 -235.716192) (xy 372.114827 -235.670916)
			(xy 372.10305 -235.623132) (xy 372.09909 -235.574078) (xy 371.770148 -235.574078) (xy 371.769653 -235.598685)
			(xy 371.761758 -235.647262) (xy 371.746174 -235.693943) (xy 371.723303 -235.73752) (xy 371.693738 -235.776864)
			(xy 371.658245 -235.810956) (xy 371.617742 -235.838912) (xy 371.57328 -235.86001) (xy 371.526009 -235.873702)
			(xy 371.477154 -235.879634) (xy 371.427979 -235.877653) (xy 371.37976 -235.867809) (xy 371.333744 -235.850357)
			(xy 371.291123 -235.82575) (xy 371.253002 -235.794625) (xy 371.220367 -235.757788) (xy 371.194064 -235.716192)
			(xy 371.174773 -235.670916) (xy 371.162996 -235.623132) (xy 371.159036 -235.574078) (xy 370.830094 -235.574078)
			(xy 370.829599 -235.598685) (xy 370.821704 -235.647262) (xy 370.80612 -235.693943) (xy 370.783249 -235.73752)
			(xy 370.753684 -235.776864) (xy 370.718191 -235.810956) (xy 370.677688 -235.838912) (xy 370.633226 -235.86001)
			(xy 370.585955 -235.873702) (xy 370.5371 -235.879634) (xy 370.487925 -235.877653) (xy 370.439706 -235.867809)
			(xy 370.39369 -235.850357) (xy 370.351069 -235.82575) (xy 370.312948 -235.794625) (xy 370.280313 -235.757788)
			(xy 370.25401 -235.716192) (xy 370.234719 -235.670916) (xy 370.222942 -235.623132) (xy 370.218982 -235.574078)
			(xy 369.89004 -235.574078) (xy 369.889545 -235.598685) (xy 369.88165 -235.647262) (xy 369.866066 -235.693943)
			(xy 369.843195 -235.73752) (xy 369.81363 -235.776864) (xy 369.778137 -235.810956) (xy 369.737634 -235.838912)
			(xy 369.693172 -235.86001) (xy 369.645901 -235.873702) (xy 369.597046 -235.879634) (xy 369.547871 -235.877653)
			(xy 369.499652 -235.867809) (xy 369.453636 -235.850357) (xy 369.411015 -235.82575) (xy 369.372894 -235.794625)
			(xy 369.340259 -235.757788) (xy 369.313956 -235.716192) (xy 369.294665 -235.670916) (xy 369.282888 -235.623132)
			(xy 369.278928 -235.574078) (xy 368.949986 -235.574078) (xy 368.949491 -235.598685) (xy 368.941596 -235.647262)
			(xy 368.926012 -235.693943) (xy 368.903141 -235.73752) (xy 368.873576 -235.776864) (xy 368.838083 -235.810956)
			(xy 368.79758 -235.838912) (xy 368.753118 -235.86001) (xy 368.705847 -235.873702) (xy 368.656992 -235.879634)
			(xy 368.607817 -235.877653) (xy 368.559598 -235.867809) (xy 368.513582 -235.850357) (xy 368.470961 -235.82575)
			(xy 368.43284 -235.794625) (xy 368.400205 -235.757788) (xy 368.373902 -235.716192) (xy 368.354611 -235.670916)
			(xy 368.342834 -235.623132) (xy 368.338874 -235.574078) (xy 368.010186 -235.574078) (xy 368.009691 -235.598685)
			(xy 368.001796 -235.647262) (xy 367.986212 -235.693943) (xy 367.963341 -235.73752) (xy 367.933776 -235.776864)
			(xy 367.898283 -235.810956) (xy 367.85778 -235.838912) (xy 367.813318 -235.86001) (xy 367.766047 -235.873702)
			(xy 367.717192 -235.879634) (xy 367.668017 -235.877653) (xy 367.619798 -235.867809) (xy 367.573782 -235.850357)
			(xy 367.531161 -235.82575) (xy 367.49304 -235.794625) (xy 367.460405 -235.757788) (xy 367.434102 -235.716192)
			(xy 367.414811 -235.670916) (xy 367.403034 -235.623132) (xy 367.399074 -235.574078) (xy 367.070132 -235.574078)
			(xy 367.069637 -235.598685) (xy 367.061742 -235.647262) (xy 367.046158 -235.693943) (xy 367.023287 -235.73752)
			(xy 366.993722 -235.776864) (xy 366.958229 -235.810956) (xy 366.917726 -235.838912) (xy 366.873264 -235.86001)
			(xy 366.825993 -235.873702) (xy 366.777138 -235.879634) (xy 366.727963 -235.877653) (xy 366.679744 -235.867809)
			(xy 366.633728 -235.850357) (xy 366.591107 -235.82575) (xy 366.552986 -235.794625) (xy 366.520351 -235.757788)
			(xy 366.494048 -235.716192) (xy 366.474757 -235.670916) (xy 366.46298 -235.623132) (xy 366.45902 -235.574078)
			(xy 366.130078 -235.574078) (xy 366.129583 -235.598685) (xy 366.121688 -235.647262) (xy 366.106104 -235.693943)
			(xy 366.083233 -235.73752) (xy 366.053668 -235.776864) (xy 366.018175 -235.810956) (xy 365.977672 -235.838912)
			(xy 365.93321 -235.86001) (xy 365.885939 -235.873702) (xy 365.837084 -235.879634) (xy 365.787909 -235.877653)
			(xy 365.73969 -235.867809) (xy 365.693674 -235.850357) (xy 365.651053 -235.82575) (xy 365.612932 -235.794625)
			(xy 365.580297 -235.757788) (xy 365.553994 -235.716192) (xy 365.534703 -235.670916) (xy 365.522926 -235.623132)
			(xy 365.518966 -235.574078) (xy 365.190024 -235.574078) (xy 365.189529 -235.598685) (xy 365.181634 -235.647262)
			(xy 365.16605 -235.693943) (xy 365.143179 -235.73752) (xy 365.113614 -235.776864) (xy 365.078121 -235.810956)
			(xy 365.037618 -235.838912) (xy 364.993156 -235.86001) (xy 364.945885 -235.873702) (xy 364.89703 -235.879634)
			(xy 364.847855 -235.877653) (xy 364.799636 -235.867809) (xy 364.75362 -235.850357) (xy 364.710999 -235.82575)
			(xy 364.672878 -235.794625) (xy 364.640243 -235.757788) (xy 364.61394 -235.716192) (xy 364.594649 -235.670916)
			(xy 364.582872 -235.623132) (xy 364.578912 -235.574078) (xy 364.250224 -235.574078) (xy 364.249729 -235.598685)
			(xy 364.241834 -235.647262) (xy 364.22625 -235.693943) (xy 364.203379 -235.73752) (xy 364.173814 -235.776864)
			(xy 364.138321 -235.810956) (xy 364.097818 -235.838912) (xy 364.053356 -235.86001) (xy 364.006085 -235.873702)
			(xy 363.95723 -235.879634) (xy 363.908055 -235.877653) (xy 363.859836 -235.867809) (xy 363.81382 -235.850357)
			(xy 363.771199 -235.82575) (xy 363.733078 -235.794625) (xy 363.700443 -235.757788) (xy 363.67414 -235.716192)
			(xy 363.654849 -235.670916) (xy 363.643072 -235.623132) (xy 363.639112 -235.574078) (xy 363.310991 -235.574078)
			(xy 363.310993 -235.5741) (xy 363.306817 -235.624485) (xy 363.294405 -235.673496) (xy 363.274095 -235.719795)
			(xy 363.24644 -235.762119) (xy 363.212196 -235.799313) (xy 363.172297 -235.830364) (xy 363.12783 -235.854423)
			(xy 363.08001 -235.870834) (xy 363.030141 -235.87915) (xy 363.004862 -235.87964) (xy 362.064808 -235.87964)
			(xy 362.039527 -235.879192) (xy 361.989654 -235.87087) (xy 361.941832 -235.854454) (xy 361.897363 -235.83039)
			(xy 361.857462 -235.799335) (xy 361.823217 -235.762136) (xy 361.795562 -235.719807) (xy 361.775251 -235.673504)
			(xy 361.762839 -235.624489) (xy 361.758663 -235.5741) (xy 361.430062 -235.5741) (xy 361.429567 -235.598685)
			(xy 361.421672 -235.647262) (xy 361.406088 -235.693943) (xy 361.383217 -235.73752) (xy 361.353652 -235.776864)
			(xy 361.318159 -235.810956) (xy 361.277656 -235.838912) (xy 361.233194 -235.86001) (xy 361.185923 -235.873702)
			(xy 361.137068 -235.879634) (xy 361.087893 -235.877653) (xy 361.039674 -235.867809) (xy 360.993658 -235.850357)
			(xy 360.951037 -235.82575) (xy 360.912916 -235.794625) (xy 360.880281 -235.757788) (xy 360.853978 -235.716192)
			(xy 360.834687 -235.670916) (xy 360.82291 -235.623132) (xy 360.81895 -235.574078) (xy 358.616504 -235.574078)
			(xy 358.616009 -235.598685) (xy 358.608114 -235.647262) (xy 358.59253 -235.693943) (xy 358.569659 -235.73752)
			(xy 358.540094 -235.776864) (xy 358.504601 -235.810956) (xy 358.464098 -235.838912) (xy 358.419636 -235.86001)
			(xy 358.372365 -235.873702) (xy 358.32351 -235.879634) (xy 358.274335 -235.877653) (xy 358.226116 -235.867809)
			(xy 358.1801 -235.850357) (xy 358.137479 -235.82575) (xy 358.099358 -235.794625) (xy 358.066723 -235.757788)
			(xy 358.04042 -235.716192) (xy 358.021129 -235.670916) (xy 358.009352 -235.623132) (xy 358.005392 -235.574078)
			(xy 357.67645 -235.574078) (xy 357.675955 -235.598685) (xy 357.66806 -235.647262) (xy 357.652476 -235.693943)
			(xy 357.629605 -235.73752) (xy 357.60004 -235.776864) (xy 357.564547 -235.810956) (xy 357.524044 -235.838912)
			(xy 357.479582 -235.86001) (xy 357.432311 -235.873702) (xy 357.383456 -235.879634) (xy 357.334281 -235.877653)
			(xy 357.286062 -235.867809) (xy 357.240046 -235.850357) (xy 357.197425 -235.82575) (xy 357.159304 -235.794625)
			(xy 357.126669 -235.757788) (xy 357.100366 -235.716192) (xy 357.081075 -235.670916) (xy 357.069298 -235.623132)
			(xy 357.065338 -235.574078) (xy 356.736396 -235.574078) (xy 356.735901 -235.598685) (xy 356.728006 -235.647262)
			(xy 356.712422 -235.693943) (xy 356.689551 -235.73752) (xy 356.659986 -235.776864) (xy 356.624493 -235.810956)
			(xy 356.58399 -235.838912) (xy 356.539528 -235.86001) (xy 356.492257 -235.873702) (xy 356.443402 -235.879634)
			(xy 356.394227 -235.877653) (xy 356.346008 -235.867809) (xy 356.299992 -235.850357) (xy 356.257371 -235.82575)
			(xy 356.21925 -235.794625) (xy 356.186615 -235.757788) (xy 356.160312 -235.716192) (xy 356.141021 -235.670916)
			(xy 356.129244 -235.623132) (xy 356.125284 -235.574078) (xy 355.796342 -235.574078) (xy 355.795847 -235.598685)
			(xy 355.787952 -235.647262) (xy 355.772368 -235.693943) (xy 355.749497 -235.73752) (xy 355.719932 -235.776864)
			(xy 355.684439 -235.810956) (xy 355.643936 -235.838912) (xy 355.599474 -235.86001) (xy 355.552203 -235.873702)
			(xy 355.503348 -235.879634) (xy 355.454173 -235.877653) (xy 355.405954 -235.867809) (xy 355.359938 -235.850357)
			(xy 355.317317 -235.82575) (xy 355.279196 -235.794625) (xy 355.246561 -235.757788) (xy 355.220258 -235.716192)
			(xy 355.200967 -235.670916) (xy 355.18919 -235.623132) (xy 355.18523 -235.574078) (xy 354.856542 -235.574078)
			(xy 354.856047 -235.598685) (xy 354.848152 -235.647262) (xy 354.832568 -235.693943) (xy 354.809697 -235.73752)
			(xy 354.780132 -235.776864) (xy 354.744639 -235.810956) (xy 354.704136 -235.838912) (xy 354.659674 -235.86001)
			(xy 354.612403 -235.873702) (xy 354.563548 -235.879634) (xy 354.514373 -235.877653) (xy 354.466154 -235.867809)
			(xy 354.420138 -235.850357) (xy 354.377517 -235.82575) (xy 354.339396 -235.794625) (xy 354.306761 -235.757788)
			(xy 354.280458 -235.716192) (xy 354.261167 -235.670916) (xy 354.24939 -235.623132) (xy 354.24543 -235.574078)
			(xy 353.916488 -235.574078) (xy 353.915993 -235.598685) (xy 353.908098 -235.647262) (xy 353.892514 -235.693943)
			(xy 353.869643 -235.73752) (xy 353.840078 -235.776864) (xy 353.804585 -235.810956) (xy 353.764082 -235.838912)
			(xy 353.71962 -235.86001) (xy 353.672349 -235.873702) (xy 353.623494 -235.879634) (xy 353.574319 -235.877653)
			(xy 353.5261 -235.867809) (xy 353.480084 -235.850357) (xy 353.437463 -235.82575) (xy 353.399342 -235.794625)
			(xy 353.366707 -235.757788) (xy 353.340404 -235.716192) (xy 353.321113 -235.670916) (xy 353.309336 -235.623132)
			(xy 353.305376 -235.574078) (xy 352.976434 -235.574078) (xy 352.975939 -235.598685) (xy 352.968044 -235.647262)
			(xy 352.95246 -235.693943) (xy 352.929589 -235.73752) (xy 352.900024 -235.776864) (xy 352.864531 -235.810956)
			(xy 352.824028 -235.838912) (xy 352.779566 -235.86001) (xy 352.732295 -235.873702) (xy 352.68344 -235.879634)
			(xy 352.634265 -235.877653) (xy 352.586046 -235.867809) (xy 352.54003 -235.850357) (xy 352.497409 -235.82575)
			(xy 352.459288 -235.794625) (xy 352.426653 -235.757788) (xy 352.40035 -235.716192) (xy 352.381059 -235.670916)
			(xy 352.369282 -235.623132) (xy 352.365322 -235.574078) (xy 352.03638 -235.574078) (xy 352.035885 -235.598685)
			(xy 352.02799 -235.647262) (xy 352.012406 -235.693943) (xy 351.989535 -235.73752) (xy 351.95997 -235.776864)
			(xy 351.924477 -235.810956) (xy 351.883974 -235.838912) (xy 351.839512 -235.86001) (xy 351.792241 -235.873702)
			(xy 351.743386 -235.879634) (xy 351.694211 -235.877653) (xy 351.645992 -235.867809) (xy 351.599976 -235.850357)
			(xy 351.557355 -235.82575) (xy 351.519234 -235.794625) (xy 351.486599 -235.757788) (xy 351.460296 -235.716192)
			(xy 351.441005 -235.670916) (xy 351.429228 -235.623132) (xy 351.425268 -235.574078) (xy 351.096326 -235.574078)
			(xy 351.095831 -235.598685) (xy 351.087936 -235.647262) (xy 351.072352 -235.693943) (xy 351.049481 -235.73752)
			(xy 351.019916 -235.776864) (xy 350.984423 -235.810956) (xy 350.94392 -235.838912) (xy 350.899458 -235.86001)
			(xy 350.852187 -235.873702) (xy 350.803332 -235.879634) (xy 350.754157 -235.877653) (xy 350.705938 -235.867809)
			(xy 350.659922 -235.850357) (xy 350.617301 -235.82575) (xy 350.57918 -235.794625) (xy 350.546545 -235.757788)
			(xy 350.520242 -235.716192) (xy 350.500951 -235.670916) (xy 350.489174 -235.623132) (xy 350.485214 -235.574078)
			(xy 350.156526 -235.574078) (xy 350.156031 -235.598685) (xy 350.148136 -235.647262) (xy 350.132552 -235.693943)
			(xy 350.109681 -235.73752) (xy 350.080116 -235.776864) (xy 350.044623 -235.810956) (xy 350.00412 -235.838912)
			(xy 349.959658 -235.86001) (xy 349.912387 -235.873702) (xy 349.863532 -235.879634) (xy 349.814357 -235.877653)
			(xy 349.766138 -235.867809) (xy 349.720122 -235.850357) (xy 349.677501 -235.82575) (xy 349.63938 -235.794625)
			(xy 349.606745 -235.757788) (xy 349.580442 -235.716192) (xy 349.561151 -235.670916) (xy 349.549374 -235.623132)
			(xy 349.545414 -235.574078) (xy 349.216472 -235.574078) (xy 349.215977 -235.598685) (xy 349.208082 -235.647262)
			(xy 349.192498 -235.693943) (xy 349.169627 -235.73752) (xy 349.140062 -235.776864) (xy 349.104569 -235.810956)
			(xy 349.064066 -235.838912) (xy 349.019604 -235.86001) (xy 348.972333 -235.873702) (xy 348.923478 -235.879634)
			(xy 348.874303 -235.877653) (xy 348.826084 -235.867809) (xy 348.780068 -235.850357) (xy 348.737447 -235.82575)
			(xy 348.699326 -235.794625) (xy 348.666691 -235.757788) (xy 348.640388 -235.716192) (xy 348.621097 -235.670916)
			(xy 348.60932 -235.623132) (xy 348.60536 -235.574078) (xy 348.276418 -235.574078) (xy 348.275923 -235.598685)
			(xy 348.268028 -235.647262) (xy 348.252444 -235.693943) (xy 348.229573 -235.73752) (xy 348.200008 -235.776864)
			(xy 348.164515 -235.810956) (xy 348.124012 -235.838912) (xy 348.07955 -235.86001) (xy 348.032279 -235.873702)
			(xy 347.983424 -235.879634) (xy 347.934249 -235.877653) (xy 347.88603 -235.867809) (xy 347.840014 -235.850357)
			(xy 347.797393 -235.82575) (xy 347.759272 -235.794625) (xy 347.726637 -235.757788) (xy 347.700334 -235.716192)
			(xy 347.681043 -235.670916) (xy 347.669266 -235.623132) (xy 347.665306 -235.574078) (xy 347.336364 -235.574078)
			(xy 347.335869 -235.598685) (xy 347.327974 -235.647262) (xy 347.31239 -235.693943) (xy 347.289519 -235.73752)
			(xy 347.259954 -235.776864) (xy 347.224461 -235.810956) (xy 347.183958 -235.838912) (xy 347.139496 -235.86001)
			(xy 347.092225 -235.873702) (xy 347.04337 -235.879634) (xy 346.994195 -235.877653) (xy 346.945976 -235.867809)
			(xy 346.89996 -235.850357) (xy 346.857339 -235.82575) (xy 346.819218 -235.794625) (xy 346.786583 -235.757788)
			(xy 346.76028 -235.716192) (xy 346.740989 -235.670916) (xy 346.729212 -235.623132) (xy 346.725252 -235.574078)
			(xy 346.39631 -235.574078) (xy 346.395815 -235.598685) (xy 346.38792 -235.647262) (xy 346.372336 -235.693943)
			(xy 346.349465 -235.73752) (xy 346.3199 -235.776864) (xy 346.284407 -235.810956) (xy 346.243904 -235.838912)
			(xy 346.199442 -235.86001) (xy 346.152171 -235.873702) (xy 346.103316 -235.879634) (xy 346.054141 -235.877653)
			(xy 346.005922 -235.867809) (xy 345.959906 -235.850357) (xy 345.917285 -235.82575) (xy 345.879164 -235.794625)
			(xy 345.846529 -235.757788) (xy 345.820226 -235.716192) (xy 345.800935 -235.670916) (xy 345.789158 -235.623132)
			(xy 345.785198 -235.574078) (xy 345.45651 -235.574078) (xy 345.456015 -235.598685) (xy 345.44812 -235.647262)
			(xy 345.432536 -235.693943) (xy 345.409665 -235.73752) (xy 345.3801 -235.776864) (xy 345.344607 -235.810956)
			(xy 345.304104 -235.838912) (xy 345.259642 -235.86001) (xy 345.212371 -235.873702) (xy 345.163516 -235.879634)
			(xy 345.114341 -235.877653) (xy 345.066122 -235.867809) (xy 345.020106 -235.850357) (xy 344.977485 -235.82575)
			(xy 344.939364 -235.794625) (xy 344.906729 -235.757788) (xy 344.880426 -235.716192) (xy 344.861135 -235.670916)
			(xy 344.849358 -235.623132) (xy 344.845398 -235.574078) (xy 344.626438 -235.574078) (xy 344.626438 -236.007402)
			(xy 344.62688 -236.01756) (xy 344.634734 -236.036298) (xy 344.641678 -236.043724) (xy 344.669618 -236.071156)
			(xy 344.686636 -236.078776) (xy 344.696034 -236.07903) (xy 344.720454 -236.080718) (xy 344.768333 -236.090893)
			(xy 344.813976 -236.108573) (xy 344.856215 -236.133306) (xy 344.893968 -236.164459) (xy 344.926271 -236.201235)
			(xy 344.952295 -236.242691) (xy 344.971375 -236.287767) (xy 344.983021 -236.335308) (xy 344.986936 -236.384084)
			(xy 345.315298 -236.384084) (xy 345.319258 -236.33503) (xy 345.331035 -236.287246) (xy 345.350326 -236.24197)
			(xy 345.376629 -236.200374) (xy 345.409264 -236.163537) (xy 345.447385 -236.132412) (xy 345.490006 -236.107805)
			(xy 345.536022 -236.090353) (xy 345.584241 -236.080509) (xy 345.633416 -236.078528) (xy 345.682271 -236.08446)
			(xy 345.729542 -236.098152) (xy 345.774004 -236.11925) (xy 345.814507 -236.147206) (xy 345.85 -236.181298)
			(xy 345.879565 -236.220642) (xy 345.902436 -236.264219) (xy 345.91802 -236.3109) (xy 345.925915 -236.359477)
			(xy 345.92641 -236.384084) (xy 346.255352 -236.384084) (xy 346.259312 -236.33503) (xy 346.271089 -236.287246)
			(xy 346.29038 -236.24197) (xy 346.316683 -236.200374) (xy 346.349318 -236.163537) (xy 346.387439 -236.132412)
			(xy 346.43006 -236.107805) (xy 346.476076 -236.090353) (xy 346.524295 -236.080509) (xy 346.57347 -236.078528)
			(xy 346.622325 -236.08446) (xy 346.669596 -236.098152) (xy 346.714058 -236.11925) (xy 346.754561 -236.147206)
			(xy 346.790054 -236.181298) (xy 346.819619 -236.220642) (xy 346.84249 -236.264219) (xy 346.858074 -236.3109)
			(xy 346.865969 -236.359477) (xy 346.866464 -236.384084) (xy 347.195406 -236.384084) (xy 347.199366 -236.33503)
			(xy 347.211143 -236.287246) (xy 347.230434 -236.24197) (xy 347.256737 -236.200374) (xy 347.289372 -236.163537)
			(xy 347.327493 -236.132412) (xy 347.370114 -236.107805) (xy 347.41613 -236.090353) (xy 347.464349 -236.080509)
			(xy 347.513524 -236.078528) (xy 347.562379 -236.08446) (xy 347.60965 -236.098152) (xy 347.654112 -236.11925)
			(xy 347.694615 -236.147206) (xy 347.730108 -236.181298) (xy 347.759673 -236.220642) (xy 347.782544 -236.264219)
			(xy 347.798128 -236.3109) (xy 347.806023 -236.359477) (xy 347.806518 -236.384084) (xy 348.135206 -236.384084)
			(xy 348.139166 -236.33503) (xy 348.150943 -236.287246) (xy 348.170234 -236.24197) (xy 348.196537 -236.200374)
			(xy 348.229172 -236.163537) (xy 348.267293 -236.132412) (xy 348.309914 -236.107805) (xy 348.35593 -236.090353)
			(xy 348.404149 -236.080509) (xy 348.453324 -236.078528) (xy 348.502179 -236.08446) (xy 348.54945 -236.098152)
			(xy 348.593912 -236.11925) (xy 348.634415 -236.147206) (xy 348.669908 -236.181298) (xy 348.699473 -236.220642)
			(xy 348.722344 -236.264219) (xy 348.737928 -236.3109) (xy 348.745823 -236.359477) (xy 348.746318 -236.384084)
			(xy 349.07526 -236.384084) (xy 349.07922 -236.33503) (xy 349.090997 -236.287246) (xy 349.110288 -236.24197)
			(xy 349.136591 -236.200374) (xy 349.169226 -236.163537) (xy 349.207347 -236.132412) (xy 349.249968 -236.107805)
			(xy 349.295984 -236.090353) (xy 349.344203 -236.080509) (xy 349.393378 -236.078528) (xy 349.442233 -236.08446)
			(xy 349.489504 -236.098152) (xy 349.533966 -236.11925) (xy 349.574469 -236.147206) (xy 349.609962 -236.181298)
			(xy 349.639527 -236.220642) (xy 349.662398 -236.264219) (xy 349.677982 -236.3109) (xy 349.685877 -236.359477)
			(xy 349.686372 -236.384084) (xy 350.015314 -236.384084) (xy 350.019274 -236.33503) (xy 350.031051 -236.287246)
			(xy 350.050342 -236.24197) (xy 350.076645 -236.200374) (xy 350.10928 -236.163537) (xy 350.147401 -236.132412)
			(xy 350.190022 -236.107805) (xy 350.236038 -236.090353) (xy 350.284257 -236.080509) (xy 350.333432 -236.078528)
			(xy 350.382287 -236.08446) (xy 350.429558 -236.098152) (xy 350.47402 -236.11925) (xy 350.514523 -236.147206)
			(xy 350.550016 -236.181298) (xy 350.579581 -236.220642) (xy 350.602452 -236.264219) (xy 350.618036 -236.3109)
			(xy 350.625931 -236.359477) (xy 350.626426 -236.384084) (xy 352.835222 -236.384084) (xy 352.839182 -236.33503)
			(xy 352.850959 -236.287246) (xy 352.87025 -236.24197) (xy 352.896553 -236.200374) (xy 352.929188 -236.163537)
			(xy 352.967309 -236.132412) (xy 353.00993 -236.107805) (xy 353.055946 -236.090353) (xy 353.104165 -236.080509)
			(xy 353.15334 -236.078528) (xy 353.202195 -236.08446) (xy 353.249466 -236.098152) (xy 353.293928 -236.11925)
			(xy 353.334431 -236.147206) (xy 353.369924 -236.181298) (xy 353.399489 -236.220642) (xy 353.42236 -236.264219)
			(xy 353.437944 -236.3109) (xy 353.445839 -236.359477) (xy 353.446334 -236.384084) (xy 355.655384 -236.384084)
			(xy 355.659344 -236.33503) (xy 355.671121 -236.287246) (xy 355.690412 -236.24197) (xy 355.716715 -236.200374)
			(xy 355.74935 -236.163537) (xy 355.787471 -236.132412) (xy 355.830092 -236.107805) (xy 355.876108 -236.090353)
			(xy 355.924327 -236.080509) (xy 355.973502 -236.078528) (xy 356.022357 -236.08446) (xy 356.069628 -236.098152)
			(xy 356.11409 -236.11925) (xy 356.154593 -236.147206) (xy 356.190086 -236.181298) (xy 356.219651 -236.220642)
			(xy 356.242522 -236.264219) (xy 356.258106 -236.3109) (xy 356.266001 -236.359477) (xy 356.266496 -236.384084)
			(xy 356.595438 -236.384084) (xy 356.599398 -236.33503) (xy 356.611175 -236.287246) (xy 356.630466 -236.24197)
			(xy 356.656769 -236.200374) (xy 356.689404 -236.163537) (xy 356.727525 -236.132412) (xy 356.770146 -236.107805)
			(xy 356.816162 -236.090353) (xy 356.864381 -236.080509) (xy 356.913556 -236.078528) (xy 356.962411 -236.08446)
			(xy 357.009682 -236.098152) (xy 357.054144 -236.11925) (xy 357.094647 -236.147206) (xy 357.13014 -236.181298)
			(xy 357.159705 -236.220642) (xy 357.182576 -236.264219) (xy 357.19816 -236.3109) (xy 357.206055 -236.359477)
			(xy 357.20655 -236.384084) (xy 357.535238 -236.384084) (xy 357.539198 -236.33503) (xy 357.550975 -236.287246)
			(xy 357.570266 -236.24197) (xy 357.596569 -236.200374) (xy 357.629204 -236.163537) (xy 357.667325 -236.132412)
			(xy 357.709946 -236.107805) (xy 357.755962 -236.090353) (xy 357.804181 -236.080509) (xy 357.853356 -236.078528)
			(xy 357.902211 -236.08446) (xy 357.949482 -236.098152) (xy 357.993944 -236.11925) (xy 358.034447 -236.147206)
			(xy 358.06994 -236.181298) (xy 358.099505 -236.220642) (xy 358.122376 -236.264219) (xy 358.13796 -236.3109)
			(xy 358.145855 -236.359477) (xy 358.14635 -236.384084) (xy 361.289104 -236.384084) (xy 361.293064 -236.33503)
			(xy 361.304841 -236.287246) (xy 361.324132 -236.24197) (xy 361.350435 -236.200374) (xy 361.38307 -236.163537)
			(xy 361.421191 -236.132412) (xy 361.463812 -236.107805) (xy 361.509828 -236.090353) (xy 361.558047 -236.080509)
			(xy 361.607222 -236.078528) (xy 361.656077 -236.08446) (xy 361.703348 -236.098152) (xy 361.74781 -236.11925)
			(xy 361.788313 -236.147206) (xy 361.823806 -236.181298) (xy 361.853371 -236.220642) (xy 361.876242 -236.264219)
			(xy 361.891826 -236.3109) (xy 361.899721 -236.359477) (xy 361.900216 -236.384084) (xy 362.228904 -236.384084)
			(xy 362.232864 -236.33503) (xy 362.244641 -236.287246) (xy 362.263932 -236.24197) (xy 362.290235 -236.200374)
			(xy 362.32287 -236.163537) (xy 362.360991 -236.132412) (xy 362.403612 -236.107805) (xy 362.449628 -236.090353)
			(xy 362.497847 -236.080509) (xy 362.547022 -236.078528) (xy 362.595877 -236.08446) (xy 362.643148 -236.098152)
			(xy 362.68761 -236.11925) (xy 362.728113 -236.147206) (xy 362.763606 -236.181298) (xy 362.793171 -236.220642)
			(xy 362.816042 -236.264219) (xy 362.831626 -236.3109) (xy 362.839521 -236.359477) (xy 362.840016 -236.384084)
			(xy 363.168958 -236.384084) (xy 363.172918 -236.33503) (xy 363.184695 -236.287246) (xy 363.203986 -236.24197)
			(xy 363.230289 -236.200374) (xy 363.262924 -236.163537) (xy 363.301045 -236.132412) (xy 363.343666 -236.107805)
			(xy 363.389682 -236.090353) (xy 363.437901 -236.080509) (xy 363.487076 -236.078528) (xy 363.535931 -236.08446)
			(xy 363.583202 -236.098152) (xy 363.627664 -236.11925) (xy 363.668167 -236.147206) (xy 363.70366 -236.181298)
			(xy 363.733225 -236.220642) (xy 363.756096 -236.264219) (xy 363.77168 -236.3109) (xy 363.779575 -236.359477)
			(xy 363.78007 -236.384084) (xy 365.98912 -236.384084) (xy 365.99308 -236.33503) (xy 366.004857 -236.287246)
			(xy 366.024148 -236.24197) (xy 366.050451 -236.200374) (xy 366.083086 -236.163537) (xy 366.121207 -236.132412)
			(xy 366.163828 -236.107805) (xy 366.209844 -236.090353) (xy 366.258063 -236.080509) (xy 366.307238 -236.078528)
			(xy 366.356093 -236.08446) (xy 366.403364 -236.098152) (xy 366.447826 -236.11925) (xy 366.488329 -236.147206)
			(xy 366.523822 -236.181298) (xy 366.553387 -236.220642) (xy 366.576258 -236.264219) (xy 366.591842 -236.3109)
			(xy 366.599737 -236.359477) (xy 366.600232 -236.384084) (xy 368.809028 -236.384084) (xy 368.812988 -236.33503)
			(xy 368.824765 -236.287246) (xy 368.844056 -236.24197) (xy 368.870359 -236.200374) (xy 368.902994 -236.163537)
			(xy 368.941115 -236.132412) (xy 368.983736 -236.107805) (xy 369.029752 -236.090353) (xy 369.077971 -236.080509)
			(xy 369.127146 -236.078528) (xy 369.176001 -236.08446) (xy 369.223272 -236.098152) (xy 369.267734 -236.11925)
			(xy 369.308237 -236.147206) (xy 369.34373 -236.181298) (xy 369.373295 -236.220642) (xy 369.396166 -236.264219)
			(xy 369.41175 -236.3109) (xy 369.419645 -236.359477) (xy 369.42014 -236.384084) (xy 369.42014 -236.3841)
			(xy 369.749053 -236.3841) (xy 369.753224 -236.333761) (xy 369.765624 -236.284794) (xy 369.785913 -236.238537)
			(xy 369.81354 -236.19625) (xy 369.84775 -236.159086) (xy 369.88761 -236.12806) (xy 369.932033 -236.104018)
			(xy 369.979808 -236.087615) (xy 370.02963 -236.079299) (xy 370.054886 -236.078776) (xy 370.99494 -236.078776)
			(xy 371.020192 -236.079333) (xy 371.070006 -236.087651) (xy 371.117772 -236.104055) (xy 371.162186 -236.128096)
			(xy 371.202038 -236.159119) (xy 371.236241 -236.196278) (xy 371.263862 -236.238559) (xy 371.284148 -236.28481)
			(xy 371.296545 -236.333769) (xy 371.300714 -236.384084) (xy 371.628936 -236.384084) (xy 371.632896 -236.33503)
			(xy 371.644673 -236.287246) (xy 371.663964 -236.24197) (xy 371.690267 -236.200374) (xy 371.722902 -236.163537)
			(xy 371.761023 -236.132412) (xy 371.803644 -236.107805) (xy 371.84966 -236.090353) (xy 371.897879 -236.080509)
			(xy 371.947054 -236.078528) (xy 371.995909 -236.08446) (xy 372.04318 -236.098152) (xy 372.087642 -236.11925)
			(xy 372.128145 -236.147206) (xy 372.163638 -236.181298) (xy 372.193203 -236.220642) (xy 372.216074 -236.264219)
			(xy 372.231658 -236.3109) (xy 372.239553 -236.359477) (xy 372.240048 -236.384084) (xy 372.240048 -236.3841)
			(xy 372.568953 -236.3841) (xy 372.573124 -236.33376) (xy 372.585524 -236.284793) (xy 372.605815 -236.238535)
			(xy 372.633442 -236.196247) (xy 372.667653 -236.159083) (xy 372.707514 -236.128057) (xy 372.751939 -236.104015)
			(xy 372.799714 -236.087613) (xy 372.849538 -236.079298) (xy 372.874794 -236.078776) (xy 373.814848 -236.078776)
			(xy 373.840099 -236.079333) (xy 373.889912 -236.087653) (xy 373.937677 -236.104057) (xy 373.98209 -236.128099)
			(xy 374.021941 -236.159122) (xy 374.056143 -236.196281) (xy 374.083763 -236.238561) (xy 374.104048 -236.284812)
			(xy 374.116445 -236.333769) (xy 374.120615 -236.3841) (xy 374.116445 -236.434431) (xy 374.104048 -236.483388)
			(xy 374.083763 -236.529638) (xy 374.056143 -236.571919) (xy 374.021941 -236.609078) (xy 373.98209 -236.640101)
			(xy 373.937677 -236.664143) (xy 373.889912 -236.680547) (xy 373.840099 -236.688867) (xy 373.814848 -236.689392)
			(xy 372.874794 -236.689392) (xy 372.849538 -236.688902) (xy 372.799714 -236.680587) (xy 372.751939 -236.664185)
			(xy 372.707514 -236.640143) (xy 372.667653 -236.609117) (xy 372.633442 -236.571953) (xy 372.605815 -236.529665)
			(xy 372.585524 -236.483407) (xy 372.573124 -236.43444) (xy 372.568953 -236.3841) (xy 372.240048 -236.3841)
			(xy 372.239553 -236.408691) (xy 372.231658 -236.457268) (xy 372.216074 -236.503949) (xy 372.193203 -236.547526)
			(xy 372.163638 -236.58687) (xy 372.128145 -236.620962) (xy 372.087642 -236.648918) (xy 372.04318 -236.670016)
			(xy 371.995909 -236.683708) (xy 371.947054 -236.68964) (xy 371.897879 -236.687659) (xy 371.84966 -236.677815)
			(xy 371.803644 -236.660363) (xy 371.761023 -236.635756) (xy 371.722902 -236.604631) (xy 371.690267 -236.567794)
			(xy 371.663964 -236.526198) (xy 371.644673 -236.480922) (xy 371.632896 -236.433138) (xy 371.628936 -236.384084)
			(xy 371.300714 -236.384084) (xy 371.300715 -236.3841) (xy 371.296545 -236.434431) (xy 371.284148 -236.48339)
			(xy 371.263862 -236.529641) (xy 371.236241 -236.571922) (xy 371.202038 -236.609081) (xy 371.162186 -236.640104)
			(xy 371.117772 -236.664145) (xy 371.070006 -236.680549) (xy 371.020192 -236.688867) (xy 370.99494 -236.689392)
			(xy 370.054886 -236.689392) (xy 370.02963 -236.688901) (xy 369.979808 -236.680585) (xy 369.932033 -236.664182)
			(xy 369.88761 -236.64014) (xy 369.84775 -236.609114) (xy 369.81354 -236.57195) (xy 369.785913 -236.529663)
			(xy 369.765624 -236.483406) (xy 369.753224 -236.434439) (xy 369.749053 -236.3841) (xy 369.42014 -236.3841)
			(xy 369.419645 -236.408691) (xy 369.41175 -236.457268) (xy 369.396166 -236.503949) (xy 369.373295 -236.547526)
			(xy 369.34373 -236.58687) (xy 369.308237 -236.620962) (xy 369.267734 -236.648918) (xy 369.223272 -236.670016)
			(xy 369.176001 -236.683708) (xy 369.127146 -236.68964) (xy 369.077971 -236.687659) (xy 369.029752 -236.677815)
			(xy 368.983736 -236.660363) (xy 368.941115 -236.635756) (xy 368.902994 -236.604631) (xy 368.870359 -236.567794)
			(xy 368.844056 -236.526198) (xy 368.824765 -236.480922) (xy 368.812988 -236.433138) (xy 368.809028 -236.384084)
			(xy 366.600232 -236.384084) (xy 366.599737 -236.408691) (xy 366.591842 -236.457268) (xy 366.576258 -236.503949)
			(xy 366.553387 -236.547526) (xy 366.523822 -236.58687) (xy 366.488329 -236.620962) (xy 366.447826 -236.648918)
			(xy 366.403364 -236.670016) (xy 366.356093 -236.683708) (xy 366.307238 -236.68964) (xy 366.258063 -236.687659)
			(xy 366.209844 -236.677815) (xy 366.163828 -236.660363) (xy 366.121207 -236.635756) (xy 366.083086 -236.604631)
			(xy 366.050451 -236.567794) (xy 366.024148 -236.526198) (xy 366.004857 -236.480922) (xy 365.99308 -236.433138)
			(xy 365.98912 -236.384084) (xy 363.78007 -236.384084) (xy 363.779575 -236.408691) (xy 363.77168 -236.457268)
			(xy 363.756096 -236.503949) (xy 363.733225 -236.547526) (xy 363.70366 -236.58687) (xy 363.668167 -236.620962)
			(xy 363.627664 -236.648918) (xy 363.583202 -236.670016) (xy 363.535931 -236.683708) (xy 363.487076 -236.68964)
			(xy 363.437901 -236.687659) (xy 363.389682 -236.677815) (xy 363.343666 -236.660363) (xy 363.301045 -236.635756)
			(xy 363.262924 -236.604631) (xy 363.230289 -236.567794) (xy 363.203986 -236.526198) (xy 363.184695 -236.480922)
			(xy 363.172918 -236.433138) (xy 363.168958 -236.384084) (xy 362.840016 -236.384084) (xy 362.839521 -236.408691)
			(xy 362.831626 -236.457268) (xy 362.816042 -236.503949) (xy 362.793171 -236.547526) (xy 362.763606 -236.58687)
			(xy 362.728113 -236.620962) (xy 362.68761 -236.648918) (xy 362.643148 -236.670016) (xy 362.595877 -236.683708)
			(xy 362.547022 -236.68964) (xy 362.497847 -236.687659) (xy 362.449628 -236.677815) (xy 362.403612 -236.660363)
			(xy 362.360991 -236.635756) (xy 362.32287 -236.604631) (xy 362.290235 -236.567794) (xy 362.263932 -236.526198)
			(xy 362.244641 -236.480922) (xy 362.232864 -236.433138) (xy 362.228904 -236.384084) (xy 361.900216 -236.384084)
			(xy 361.899721 -236.408691) (xy 361.891826 -236.457268) (xy 361.876242 -236.503949) (xy 361.853371 -236.547526)
			(xy 361.823806 -236.58687) (xy 361.788313 -236.620962) (xy 361.74781 -236.648918) (xy 361.703348 -236.670016)
			(xy 361.656077 -236.683708) (xy 361.607222 -236.68964) (xy 361.558047 -236.687659) (xy 361.509828 -236.677815)
			(xy 361.463812 -236.660363) (xy 361.421191 -236.635756) (xy 361.38307 -236.604631) (xy 361.350435 -236.567794)
			(xy 361.324132 -236.526198) (xy 361.304841 -236.480922) (xy 361.293064 -236.433138) (xy 361.289104 -236.384084)
			(xy 358.14635 -236.384084) (xy 358.145855 -236.408691) (xy 358.13796 -236.457268) (xy 358.122376 -236.503949)
			(xy 358.099505 -236.547526) (xy 358.06994 -236.58687) (xy 358.034447 -236.620962) (xy 357.993944 -236.648918)
			(xy 357.949482 -236.670016) (xy 357.902211 -236.683708) (xy 357.853356 -236.68964) (xy 357.804181 -236.687659)
			(xy 357.755962 -236.677815) (xy 357.709946 -236.660363) (xy 357.667325 -236.635756) (xy 357.629204 -236.604631)
			(xy 357.596569 -236.567794) (xy 357.570266 -236.526198) (xy 357.550975 -236.480922) (xy 357.539198 -236.433138)
			(xy 357.535238 -236.384084) (xy 357.20655 -236.384084) (xy 357.206055 -236.408691) (xy 357.19816 -236.457268)
			(xy 357.182576 -236.503949) (xy 357.159705 -236.547526) (xy 357.13014 -236.58687) (xy 357.094647 -236.620962)
			(xy 357.054144 -236.648918) (xy 357.009682 -236.670016) (xy 356.962411 -236.683708) (xy 356.913556 -236.68964)
			(xy 356.864381 -236.687659) (xy 356.816162 -236.677815) (xy 356.770146 -236.660363) (xy 356.727525 -236.635756)
			(xy 356.689404 -236.604631) (xy 356.656769 -236.567794) (xy 356.630466 -236.526198) (xy 356.611175 -236.480922)
			(xy 356.599398 -236.433138) (xy 356.595438 -236.384084) (xy 356.266496 -236.384084) (xy 356.266001 -236.408691)
			(xy 356.258106 -236.457268) (xy 356.242522 -236.503949) (xy 356.219651 -236.547526) (xy 356.190086 -236.58687)
			(xy 356.154593 -236.620962) (xy 356.11409 -236.648918) (xy 356.069628 -236.670016) (xy 356.022357 -236.683708)
			(xy 355.973502 -236.68964) (xy 355.924327 -236.687659) (xy 355.876108 -236.677815) (xy 355.830092 -236.660363)
			(xy 355.787471 -236.635756) (xy 355.74935 -236.604631) (xy 355.716715 -236.567794) (xy 355.690412 -236.526198)
			(xy 355.671121 -236.480922) (xy 355.659344 -236.433138) (xy 355.655384 -236.384084) (xy 353.446334 -236.384084)
			(xy 353.445839 -236.408691) (xy 353.437944 -236.457268) (xy 353.42236 -236.503949) (xy 353.399489 -236.547526)
			(xy 353.369924 -236.58687) (xy 353.334431 -236.620962) (xy 353.293928 -236.648918) (xy 353.249466 -236.670016)
			(xy 353.202195 -236.683708) (xy 353.15334 -236.68964) (xy 353.104165 -236.687659) (xy 353.055946 -236.677815)
			(xy 353.00993 -236.660363) (xy 352.967309 -236.635756) (xy 352.929188 -236.604631) (xy 352.896553 -236.567794)
			(xy 352.87025 -236.526198) (xy 352.850959 -236.480922) (xy 352.839182 -236.433138) (xy 352.835222 -236.384084)
			(xy 350.626426 -236.384084) (xy 350.625931 -236.408691) (xy 350.618036 -236.457268) (xy 350.602452 -236.503949)
			(xy 350.579581 -236.547526) (xy 350.550016 -236.58687) (xy 350.514523 -236.620962) (xy 350.47402 -236.648918)
			(xy 350.429558 -236.670016) (xy 350.382287 -236.683708) (xy 350.333432 -236.68964) (xy 350.284257 -236.687659)
			(xy 350.236038 -236.677815) (xy 350.190022 -236.660363) (xy 350.147401 -236.635756) (xy 350.10928 -236.604631)
			(xy 350.076645 -236.567794) (xy 350.050342 -236.526198) (xy 350.031051 -236.480922) (xy 350.019274 -236.433138)
			(xy 350.015314 -236.384084) (xy 349.686372 -236.384084) (xy 349.685877 -236.408691) (xy 349.677982 -236.457268)
			(xy 349.662398 -236.503949) (xy 349.639527 -236.547526) (xy 349.609962 -236.58687) (xy 349.574469 -236.620962)
			(xy 349.533966 -236.648918) (xy 349.489504 -236.670016) (xy 349.442233 -236.683708) (xy 349.393378 -236.68964)
			(xy 349.344203 -236.687659) (xy 349.295984 -236.677815) (xy 349.249968 -236.660363) (xy 349.207347 -236.635756)
			(xy 349.169226 -236.604631) (xy 349.136591 -236.567794) (xy 349.110288 -236.526198) (xy 349.090997 -236.480922)
			(xy 349.07922 -236.433138) (xy 349.07526 -236.384084) (xy 348.746318 -236.384084) (xy 348.745823 -236.408691)
			(xy 348.737928 -236.457268) (xy 348.722344 -236.503949) (xy 348.699473 -236.547526) (xy 348.669908 -236.58687)
			(xy 348.634415 -236.620962) (xy 348.593912 -236.648918) (xy 348.54945 -236.670016) (xy 348.502179 -236.683708)
			(xy 348.453324 -236.68964) (xy 348.404149 -236.687659) (xy 348.35593 -236.677815) (xy 348.309914 -236.660363)
			(xy 348.267293 -236.635756) (xy 348.229172 -236.604631) (xy 348.196537 -236.567794) (xy 348.170234 -236.526198)
			(xy 348.150943 -236.480922) (xy 348.139166 -236.433138) (xy 348.135206 -236.384084) (xy 347.806518 -236.384084)
			(xy 347.806023 -236.408691) (xy 347.798128 -236.457268) (xy 347.782544 -236.503949) (xy 347.759673 -236.547526)
			(xy 347.730108 -236.58687) (xy 347.694615 -236.620962) (xy 347.654112 -236.648918) (xy 347.60965 -236.670016)
			(xy 347.562379 -236.683708) (xy 347.513524 -236.68964) (xy 347.464349 -236.687659) (xy 347.41613 -236.677815)
			(xy 347.370114 -236.660363) (xy 347.327493 -236.635756) (xy 347.289372 -236.604631) (xy 347.256737 -236.567794)
			(xy 347.230434 -236.526198) (xy 347.211143 -236.480922) (xy 347.199366 -236.433138) (xy 347.195406 -236.384084)
			(xy 346.866464 -236.384084) (xy 346.865969 -236.408691) (xy 346.858074 -236.457268) (xy 346.84249 -236.503949)
			(xy 346.819619 -236.547526) (xy 346.790054 -236.58687) (xy 346.754561 -236.620962) (xy 346.714058 -236.648918)
			(xy 346.669596 -236.670016) (xy 346.622325 -236.683708) (xy 346.57347 -236.68964) (xy 346.524295 -236.687659)
			(xy 346.476076 -236.677815) (xy 346.43006 -236.660363) (xy 346.387439 -236.635756) (xy 346.349318 -236.604631)
			(xy 346.316683 -236.567794) (xy 346.29038 -236.526198) (xy 346.271089 -236.480922) (xy 346.259312 -236.433138)
			(xy 346.255352 -236.384084) (xy 345.92641 -236.384084) (xy 345.925915 -236.408691) (xy 345.91802 -236.457268)
			(xy 345.902436 -236.503949) (xy 345.879565 -236.547526) (xy 345.85 -236.58687) (xy 345.814507 -236.620962)
			(xy 345.774004 -236.648918) (xy 345.729542 -236.670016) (xy 345.682271 -236.683708) (xy 345.633416 -236.68964)
			(xy 345.584241 -236.687659) (xy 345.536022 -236.677815) (xy 345.490006 -236.660363) (xy 345.447385 -236.635756)
			(xy 345.409264 -236.604631) (xy 345.376629 -236.567794) (xy 345.350326 -236.526198) (xy 345.331035 -236.480922)
			(xy 345.319258 -236.433138) (xy 345.315298 -236.384084) (xy 344.986936 -236.384084) (xy 344.986937 -236.384099)
			(xy 344.983022 -236.43289) (xy 344.971375 -236.480432) (xy 344.952296 -236.525508) (xy 344.926272 -236.566964)
			(xy 344.89397 -236.60374) (xy 344.856216 -236.634893) (xy 344.813977 -236.659626) (xy 344.768334 -236.677307)
			(xy 344.720456 -236.687482) (xy 344.696034 -236.689138) (xy 344.686636 -236.689392) (xy 344.669618 -236.697012)
			(xy 344.641424 -236.724698) (xy 344.634615 -236.731966) (xy 344.626903 -236.750308) (xy 344.626438 -236.760258)
			(xy 344.626438 -237.19409) (xy 344.845398 -237.19409) (xy 344.849358 -237.145036) (xy 344.861135 -237.097252)
			(xy 344.880426 -237.051976) (xy 344.906729 -237.01038) (xy 344.939364 -236.973543) (xy 344.977485 -236.942418)
			(xy 345.020106 -236.917811) (xy 345.066122 -236.900359) (xy 345.114341 -236.890515) (xy 345.163516 -236.888534)
			(xy 345.212371 -236.894466) (xy 345.259642 -236.908158) (xy 345.304104 -236.929256) (xy 345.344607 -236.957212)
			(xy 345.3801 -236.991304) (xy 345.409665 -237.030648) (xy 345.432536 -237.074225) (xy 345.44812 -237.120906)
			(xy 345.456015 -237.169483) (xy 345.45651 -237.19409) (xy 345.785198 -237.19409) (xy 345.789158 -237.145036)
			(xy 345.800935 -237.097252) (xy 345.820226 -237.051976) (xy 345.846529 -237.01038) (xy 345.879164 -236.973543)
			(xy 345.917285 -236.942418) (xy 345.959906 -236.917811) (xy 346.005922 -236.900359) (xy 346.054141 -236.890515)
			(xy 346.103316 -236.888534) (xy 346.152171 -236.894466) (xy 346.199442 -236.908158) (xy 346.243904 -236.929256)
			(xy 346.284407 -236.957212) (xy 346.3199 -236.991304) (xy 346.349465 -237.030648) (xy 346.372336 -237.074225)
			(xy 346.38792 -237.120906) (xy 346.395815 -237.169483) (xy 346.39631 -237.19409) (xy 346.725252 -237.19409)
			(xy 346.729212 -237.145036) (xy 346.740989 -237.097252) (xy 346.76028 -237.051976) (xy 346.786583 -237.01038)
			(xy 346.819218 -236.973543) (xy 346.857339 -236.942418) (xy 346.89996 -236.917811) (xy 346.945976 -236.900359)
			(xy 346.994195 -236.890515) (xy 347.04337 -236.888534) (xy 347.092225 -236.894466) (xy 347.139496 -236.908158)
			(xy 347.183958 -236.929256) (xy 347.224461 -236.957212) (xy 347.259954 -236.991304) (xy 347.289519 -237.030648)
			(xy 347.31239 -237.074225) (xy 347.327974 -237.120906) (xy 347.335869 -237.169483) (xy 347.336364 -237.19409)
			(xy 347.665306 -237.19409) (xy 347.669266 -237.145036) (xy 347.681043 -237.097252) (xy 347.700334 -237.051976)
			(xy 347.726637 -237.01038) (xy 347.759272 -236.973543) (xy 347.797393 -236.942418) (xy 347.840014 -236.917811)
			(xy 347.88603 -236.900359) (xy 347.934249 -236.890515) (xy 347.983424 -236.888534) (xy 348.032279 -236.894466)
			(xy 348.07955 -236.908158) (xy 348.124012 -236.929256) (xy 348.164515 -236.957212) (xy 348.200008 -236.991304)
			(xy 348.229573 -237.030648) (xy 348.252444 -237.074225) (xy 348.268028 -237.120906) (xy 348.275923 -237.169483)
			(xy 348.276418 -237.19409) (xy 348.60536 -237.19409) (xy 348.60932 -237.145036) (xy 348.621097 -237.097252)
			(xy 348.640388 -237.051976) (xy 348.666691 -237.01038) (xy 348.699326 -236.973543) (xy 348.737447 -236.942418)
			(xy 348.780068 -236.917811) (xy 348.826084 -236.900359) (xy 348.874303 -236.890515) (xy 348.923478 -236.888534)
			(xy 348.972333 -236.894466) (xy 349.019604 -236.908158) (xy 349.064066 -236.929256) (xy 349.104569 -236.957212)
			(xy 349.140062 -236.991304) (xy 349.169627 -237.030648) (xy 349.192498 -237.074225) (xy 349.208082 -237.120906)
			(xy 349.215977 -237.169483) (xy 349.216472 -237.19409) (xy 349.545414 -237.19409) (xy 349.549374 -237.145036)
			(xy 349.561151 -237.097252) (xy 349.580442 -237.051976) (xy 349.606745 -237.01038) (xy 349.63938 -236.973543)
			(xy 349.677501 -236.942418) (xy 349.720122 -236.917811) (xy 349.766138 -236.900359) (xy 349.814357 -236.890515)
			(xy 349.863532 -236.888534) (xy 349.912387 -236.894466) (xy 349.959658 -236.908158) (xy 350.00412 -236.929256)
			(xy 350.044623 -236.957212) (xy 350.080116 -236.991304) (xy 350.109681 -237.030648) (xy 350.132552 -237.074225)
			(xy 350.148136 -237.120906) (xy 350.156031 -237.169483) (xy 350.156526 -237.19409) (xy 350.485214 -237.19409)
			(xy 350.489174 -237.145036) (xy 350.500951 -237.097252) (xy 350.520242 -237.051976) (xy 350.546545 -237.01038)
			(xy 350.57918 -236.973543) (xy 350.617301 -236.942418) (xy 350.659922 -236.917811) (xy 350.705938 -236.900359)
			(xy 350.754157 -236.890515) (xy 350.803332 -236.888534) (xy 350.852187 -236.894466) (xy 350.899458 -236.908158)
			(xy 350.94392 -236.929256) (xy 350.984423 -236.957212) (xy 351.019916 -236.991304) (xy 351.049481 -237.030648)
			(xy 351.072352 -237.074225) (xy 351.087936 -237.120906) (xy 351.095831 -237.169483) (xy 351.096326 -237.19409)
			(xy 351.425268 -237.19409) (xy 351.429228 -237.145036) (xy 351.441005 -237.097252) (xy 351.460296 -237.051976)
			(xy 351.486599 -237.01038) (xy 351.519234 -236.973543) (xy 351.557355 -236.942418) (xy 351.599976 -236.917811)
			(xy 351.645992 -236.900359) (xy 351.694211 -236.890515) (xy 351.743386 -236.888534) (xy 351.792241 -236.894466)
			(xy 351.839512 -236.908158) (xy 351.883974 -236.929256) (xy 351.924477 -236.957212) (xy 351.95997 -236.991304)
			(xy 351.989535 -237.030648) (xy 352.012406 -237.074225) (xy 352.02799 -237.120906) (xy 352.035885 -237.169483)
			(xy 352.03638 -237.19409) (xy 352.365322 -237.19409) (xy 352.369282 -237.145036) (xy 352.381059 -237.097252)
			(xy 352.40035 -237.051976) (xy 352.426653 -237.01038) (xy 352.459288 -236.973543) (xy 352.497409 -236.942418)
			(xy 352.54003 -236.917811) (xy 352.586046 -236.900359) (xy 352.634265 -236.890515) (xy 352.68344 -236.888534)
			(xy 352.732295 -236.894466) (xy 352.779566 -236.908158) (xy 352.824028 -236.929256) (xy 352.864531 -236.957212)
			(xy 352.900024 -236.991304) (xy 352.929589 -237.030648) (xy 352.95246 -237.074225) (xy 352.968044 -237.120906)
			(xy 352.975939 -237.169483) (xy 352.976434 -237.19409) (xy 353.305376 -237.19409) (xy 353.309336 -237.145036)
			(xy 353.321113 -237.097252) (xy 353.340404 -237.051976) (xy 353.366707 -237.01038) (xy 353.399342 -236.973543)
			(xy 353.437463 -236.942418) (xy 353.480084 -236.917811) (xy 353.5261 -236.900359) (xy 353.574319 -236.890515)
			(xy 353.623494 -236.888534) (xy 353.672349 -236.894466) (xy 353.71962 -236.908158) (xy 353.764082 -236.929256)
			(xy 353.804585 -236.957212) (xy 353.840078 -236.991304) (xy 353.869643 -237.030648) (xy 353.892514 -237.074225)
			(xy 353.908098 -237.120906) (xy 353.915993 -237.169483) (xy 353.916488 -237.19409) (xy 354.24543 -237.19409)
			(xy 354.24939 -237.145036) (xy 354.261167 -237.097252) (xy 354.280458 -237.051976) (xy 354.306761 -237.01038)
			(xy 354.339396 -236.973543) (xy 354.377517 -236.942418) (xy 354.420138 -236.917811) (xy 354.466154 -236.900359)
			(xy 354.514373 -236.890515) (xy 354.563548 -236.888534) (xy 354.612403 -236.894466) (xy 354.659674 -236.908158)
			(xy 354.704136 -236.929256) (xy 354.744639 -236.957212) (xy 354.780132 -236.991304) (xy 354.809697 -237.030648)
			(xy 354.832568 -237.074225) (xy 354.848152 -237.120906) (xy 354.856047 -237.169483) (xy 354.856542 -237.19409)
			(xy 355.18523 -237.19409) (xy 355.18919 -237.145036) (xy 355.200967 -237.097252) (xy 355.220258 -237.051976)
			(xy 355.246561 -237.01038) (xy 355.279196 -236.973543) (xy 355.317317 -236.942418) (xy 355.359938 -236.917811)
			(xy 355.405954 -236.900359) (xy 355.454173 -236.890515) (xy 355.503348 -236.888534) (xy 355.552203 -236.894466)
			(xy 355.599474 -236.908158) (xy 355.643936 -236.929256) (xy 355.684439 -236.957212) (xy 355.719932 -236.991304)
			(xy 355.749497 -237.030648) (xy 355.772368 -237.074225) (xy 355.787952 -237.120906) (xy 355.795847 -237.169483)
			(xy 355.796342 -237.19409) (xy 358.005392 -237.19409) (xy 358.009352 -237.145036) (xy 358.021129 -237.097252)
			(xy 358.04042 -237.051976) (xy 358.066723 -237.01038) (xy 358.099358 -236.973543) (xy 358.137479 -236.942418)
			(xy 358.1801 -236.917811) (xy 358.226116 -236.900359) (xy 358.274335 -236.890515) (xy 358.32351 -236.888534)
			(xy 358.372365 -236.894466) (xy 358.419636 -236.908158) (xy 358.464098 -236.929256) (xy 358.504601 -236.957212)
			(xy 358.540094 -236.991304) (xy 358.569659 -237.030648) (xy 358.59253 -237.074225) (xy 358.608114 -237.120906)
			(xy 358.616009 -237.169483) (xy 358.616504 -237.19409) (xy 360.81895 -237.19409) (xy 360.82291 -237.145036)
			(xy 360.834687 -237.097252) (xy 360.853978 -237.051976) (xy 360.880281 -237.01038) (xy 360.912916 -236.973543)
			(xy 360.951037 -236.942418) (xy 360.993658 -236.917811) (xy 361.039674 -236.900359) (xy 361.087893 -236.890515)
			(xy 361.137068 -236.888534) (xy 361.185923 -236.894466) (xy 361.233194 -236.908158) (xy 361.277656 -236.929256)
			(xy 361.318159 -236.957212) (xy 361.353652 -236.991304) (xy 361.383217 -237.030648) (xy 361.406088 -237.074225)
			(xy 361.421672 -237.120906) (xy 361.429567 -237.169483) (xy 361.430062 -237.19409) (xy 363.639112 -237.19409)
			(xy 363.643072 -237.145036) (xy 363.654849 -237.097252) (xy 363.67414 -237.051976) (xy 363.700443 -237.01038)
			(xy 363.733078 -236.973543) (xy 363.771199 -236.942418) (xy 363.81382 -236.917811) (xy 363.859836 -236.900359)
			(xy 363.908055 -236.890515) (xy 363.95723 -236.888534) (xy 364.006085 -236.894466) (xy 364.053356 -236.908158)
			(xy 364.097818 -236.929256) (xy 364.138321 -236.957212) (xy 364.173814 -236.991304) (xy 364.203379 -237.030648)
			(xy 364.22625 -237.074225) (xy 364.241834 -237.120906) (xy 364.249729 -237.169483) (xy 364.250224 -237.19409)
			(xy 364.578912 -237.19409) (xy 364.582872 -237.145036) (xy 364.594649 -237.097252) (xy 364.61394 -237.051976)
			(xy 364.640243 -237.01038) (xy 364.672878 -236.973543) (xy 364.710999 -236.942418) (xy 364.75362 -236.917811)
			(xy 364.799636 -236.900359) (xy 364.847855 -236.890515) (xy 364.89703 -236.888534) (xy 364.945885 -236.894466)
			(xy 364.993156 -236.908158) (xy 365.037618 -236.929256) (xy 365.078121 -236.957212) (xy 365.113614 -236.991304)
			(xy 365.143179 -237.030648) (xy 365.16605 -237.074225) (xy 365.181634 -237.120906) (xy 365.189529 -237.169483)
			(xy 365.190024 -237.19409) (xy 365.518966 -237.19409) (xy 365.522926 -237.145036) (xy 365.534703 -237.097252)
			(xy 365.553994 -237.051976) (xy 365.580297 -237.01038) (xy 365.612932 -236.973543) (xy 365.651053 -236.942418)
			(xy 365.693674 -236.917811) (xy 365.73969 -236.900359) (xy 365.787909 -236.890515) (xy 365.837084 -236.888534)
			(xy 365.885939 -236.894466) (xy 365.93321 -236.908158) (xy 365.977672 -236.929256) (xy 366.018175 -236.957212)
			(xy 366.053668 -236.991304) (xy 366.083233 -237.030648) (xy 366.106104 -237.074225) (xy 366.121688 -237.120906)
			(xy 366.129583 -237.169483) (xy 366.130078 -237.19409) (xy 366.45902 -237.19409) (xy 366.46298 -237.145036)
			(xy 366.474757 -237.097252) (xy 366.494048 -237.051976) (xy 366.520351 -237.01038) (xy 366.552986 -236.973543)
			(xy 366.591107 -236.942418) (xy 366.633728 -236.917811) (xy 366.679744 -236.900359) (xy 366.727963 -236.890515)
			(xy 366.777138 -236.888534) (xy 366.825993 -236.894466) (xy 366.873264 -236.908158) (xy 366.917726 -236.929256)
			(xy 366.958229 -236.957212) (xy 366.993722 -236.991304) (xy 367.023287 -237.030648) (xy 367.046158 -237.074225)
			(xy 367.061742 -237.120906) (xy 367.069637 -237.169483) (xy 367.070132 -237.19409) (xy 367.399074 -237.19409)
			(xy 367.403034 -237.145036) (xy 367.414811 -237.097252) (xy 367.434102 -237.051976) (xy 367.460405 -237.01038)
			(xy 367.49304 -236.973543) (xy 367.531161 -236.942418) (xy 367.573782 -236.917811) (xy 367.619798 -236.900359)
			(xy 367.668017 -236.890515) (xy 367.717192 -236.888534) (xy 367.766047 -236.894466) (xy 367.813318 -236.908158)
			(xy 367.85778 -236.929256) (xy 367.898283 -236.957212) (xy 367.933776 -236.991304) (xy 367.963341 -237.030648)
			(xy 367.986212 -237.074225) (xy 368.001796 -237.120906) (xy 368.009691 -237.169483) (xy 368.010186 -237.19409)
			(xy 368.338874 -237.19409) (xy 368.342834 -237.145036) (xy 368.354611 -237.097252) (xy 368.373902 -237.051976)
			(xy 368.400205 -237.01038) (xy 368.43284 -236.973543) (xy 368.470961 -236.942418) (xy 368.513582 -236.917811)
			(xy 368.559598 -236.900359) (xy 368.607817 -236.890515) (xy 368.656992 -236.888534) (xy 368.705847 -236.894466)
			(xy 368.753118 -236.908158) (xy 368.79758 -236.929256) (xy 368.838083 -236.957212) (xy 368.873576 -236.991304)
			(xy 368.903141 -237.030648) (xy 368.926012 -237.074225) (xy 368.941596 -237.120906) (xy 368.949491 -237.169483)
			(xy 368.949986 -237.19409) (xy 369.278928 -237.19409) (xy 369.282888 -237.145036) (xy 369.294665 -237.097252)
			(xy 369.313956 -237.051976) (xy 369.340259 -237.01038) (xy 369.372894 -236.973543) (xy 369.411015 -236.942418)
			(xy 369.453636 -236.917811) (xy 369.499652 -236.900359) (xy 369.547871 -236.890515) (xy 369.597046 -236.888534)
			(xy 369.645901 -236.894466) (xy 369.693172 -236.908158) (xy 369.737634 -236.929256) (xy 369.778137 -236.957212)
			(xy 369.81363 -236.991304) (xy 369.843195 -237.030648) (xy 369.866066 -237.074225) (xy 369.88165 -237.120906)
			(xy 369.889545 -237.169483) (xy 369.89004 -237.19409) (xy 370.218982 -237.19409) (xy 370.222942 -237.145036)
			(xy 370.234719 -237.097252) (xy 370.25401 -237.051976) (xy 370.280313 -237.01038) (xy 370.312948 -236.973543)
			(xy 370.351069 -236.942418) (xy 370.39369 -236.917811) (xy 370.439706 -236.900359) (xy 370.487925 -236.890515)
			(xy 370.5371 -236.888534) (xy 370.585955 -236.894466) (xy 370.633226 -236.908158) (xy 370.677688 -236.929256)
			(xy 370.718191 -236.957212) (xy 370.753684 -236.991304) (xy 370.783249 -237.030648) (xy 370.80612 -237.074225)
			(xy 370.821704 -237.120906) (xy 370.829599 -237.169483) (xy 370.830094 -237.19409) (xy 371.159036 -237.19409)
			(xy 371.162996 -237.145036) (xy 371.174773 -237.097252) (xy 371.194064 -237.051976) (xy 371.220367 -237.01038)
			(xy 371.253002 -236.973543) (xy 371.291123 -236.942418) (xy 371.333744 -236.917811) (xy 371.37976 -236.900359)
			(xy 371.427979 -236.890515) (xy 371.477154 -236.888534) (xy 371.526009 -236.894466) (xy 371.57328 -236.908158)
			(xy 371.617742 -236.929256) (xy 371.658245 -236.957212) (xy 371.693738 -236.991304) (xy 371.723303 -237.030648)
			(xy 371.746174 -237.074225) (xy 371.761758 -237.120906) (xy 371.769653 -237.169483) (xy 371.770148 -237.19409)
			(xy 372.09909 -237.19409) (xy 372.10305 -237.145036) (xy 372.114827 -237.097252) (xy 372.134118 -237.051976)
			(xy 372.160421 -237.01038) (xy 372.193056 -236.973543) (xy 372.231177 -236.942418) (xy 372.273798 -236.917811)
			(xy 372.319814 -236.900359) (xy 372.368033 -236.890515) (xy 372.417208 -236.888534) (xy 372.466063 -236.894466)
			(xy 372.513334 -236.908158) (xy 372.557796 -236.929256) (xy 372.598299 -236.957212) (xy 372.633792 -236.991304)
			(xy 372.663357 -237.030648) (xy 372.686228 -237.074225) (xy 372.701812 -237.120906) (xy 372.709707 -237.169483)
			(xy 372.710202 -237.19409) (xy 373.03889 -237.19409) (xy 373.04285 -237.145036) (xy 373.054627 -237.097252)
			(xy 373.073918 -237.051976) (xy 373.100221 -237.01038) (xy 373.132856 -236.973543) (xy 373.170977 -236.942418)
			(xy 373.213598 -236.917811) (xy 373.259614 -236.900359) (xy 373.307833 -236.890515) (xy 373.357008 -236.888534)
			(xy 373.405863 -236.894466) (xy 373.453134 -236.908158) (xy 373.497596 -236.929256) (xy 373.538099 -236.957212)
			(xy 373.573592 -236.991304) (xy 373.603157 -237.030648) (xy 373.626028 -237.074225) (xy 373.641612 -237.120906)
			(xy 373.649507 -237.169483) (xy 373.650002 -237.19409) (xy 373.978944 -237.19409) (xy 373.982904 -237.145036)
			(xy 373.994681 -237.097252) (xy 374.013972 -237.051976) (xy 374.040275 -237.01038) (xy 374.07291 -236.973543)
			(xy 374.111031 -236.942418) (xy 374.153652 -236.917811) (xy 374.199668 -236.900359) (xy 374.247887 -236.890515)
			(xy 374.297062 -236.888534) (xy 374.345917 -236.894466) (xy 374.393188 -236.908158) (xy 374.43765 -236.929256)
			(xy 374.478153 -236.957212) (xy 374.513646 -236.991304) (xy 374.543211 -237.030648) (xy 374.566082 -237.074225)
			(xy 374.581666 -237.120906) (xy 374.589561 -237.169483) (xy 374.590056 -237.19409) (xy 374.589561 -237.218697)
			(xy 374.581666 -237.267274) (xy 374.566082 -237.313955) (xy 374.543211 -237.357532) (xy 374.513646 -237.396876)
			(xy 374.478153 -237.430968) (xy 374.43765 -237.458924) (xy 374.393188 -237.480022) (xy 374.345917 -237.493714)
			(xy 374.297062 -237.499646) (xy 374.247887 -237.497665) (xy 374.199668 -237.487821) (xy 374.153652 -237.470369)
			(xy 374.111031 -237.445762) (xy 374.07291 -237.414637) (xy 374.040275 -237.3778) (xy 374.013972 -237.336204)
			(xy 373.994681 -237.290928) (xy 373.982904 -237.243144) (xy 373.978944 -237.19409) (xy 373.650002 -237.19409)
			(xy 373.649507 -237.218697) (xy 373.641612 -237.267274) (xy 373.626028 -237.313955) (xy 373.603157 -237.357532)
			(xy 373.573592 -237.396876) (xy 373.538099 -237.430968) (xy 373.497596 -237.458924) (xy 373.453134 -237.480022)
			(xy 373.405863 -237.493714) (xy 373.357008 -237.499646) (xy 373.307833 -237.497665) (xy 373.259614 -237.487821)
			(xy 373.213598 -237.470369) (xy 373.170977 -237.445762) (xy 373.132856 -237.414637) (xy 373.100221 -237.3778)
			(xy 373.073918 -237.336204) (xy 373.054627 -237.290928) (xy 373.04285 -237.243144) (xy 373.03889 -237.19409)
			(xy 372.710202 -237.19409) (xy 372.709707 -237.218697) (xy 372.701812 -237.267274) (xy 372.686228 -237.313955)
			(xy 372.663357 -237.357532) (xy 372.633792 -237.396876) (xy 372.598299 -237.430968) (xy 372.557796 -237.458924)
			(xy 372.513334 -237.480022) (xy 372.466063 -237.493714) (xy 372.417208 -237.499646) (xy 372.368033 -237.497665)
			(xy 372.319814 -237.487821) (xy 372.273798 -237.470369) (xy 372.231177 -237.445762) (xy 372.193056 -237.414637)
			(xy 372.160421 -237.3778) (xy 372.134118 -237.336204) (xy 372.114827 -237.290928) (xy 372.10305 -237.243144)
			(xy 372.09909 -237.19409) (xy 371.770148 -237.19409) (xy 371.769653 -237.218697) (xy 371.761758 -237.267274)
			(xy 371.746174 -237.313955) (xy 371.723303 -237.357532) (xy 371.693738 -237.396876) (xy 371.658245 -237.430968)
			(xy 371.617742 -237.458924) (xy 371.57328 -237.480022) (xy 371.526009 -237.493714) (xy 371.477154 -237.499646)
			(xy 371.427979 -237.497665) (xy 371.37976 -237.487821) (xy 371.333744 -237.470369) (xy 371.291123 -237.445762)
			(xy 371.253002 -237.414637) (xy 371.220367 -237.3778) (xy 371.194064 -237.336204) (xy 371.174773 -237.290928)
			(xy 371.162996 -237.243144) (xy 371.159036 -237.19409) (xy 370.830094 -237.19409) (xy 370.829599 -237.218697)
			(xy 370.821704 -237.267274) (xy 370.80612 -237.313955) (xy 370.783249 -237.357532) (xy 370.753684 -237.396876)
			(xy 370.718191 -237.430968) (xy 370.677688 -237.458924) (xy 370.633226 -237.480022) (xy 370.585955 -237.493714)
			(xy 370.5371 -237.499646) (xy 370.487925 -237.497665) (xy 370.439706 -237.487821) (xy 370.39369 -237.470369)
			(xy 370.351069 -237.445762) (xy 370.312948 -237.414637) (xy 370.280313 -237.3778) (xy 370.25401 -237.336204)
			(xy 370.234719 -237.290928) (xy 370.222942 -237.243144) (xy 370.218982 -237.19409) (xy 369.89004 -237.19409)
			(xy 369.889545 -237.218697) (xy 369.88165 -237.267274) (xy 369.866066 -237.313955) (xy 369.843195 -237.357532)
			(xy 369.81363 -237.396876) (xy 369.778137 -237.430968) (xy 369.737634 -237.458924) (xy 369.693172 -237.480022)
			(xy 369.645901 -237.493714) (xy 369.597046 -237.499646) (xy 369.547871 -237.497665) (xy 369.499652 -237.487821)
			(xy 369.453636 -237.470369) (xy 369.411015 -237.445762) (xy 369.372894 -237.414637) (xy 369.340259 -237.3778)
			(xy 369.313956 -237.336204) (xy 369.294665 -237.290928) (xy 369.282888 -237.243144) (xy 369.278928 -237.19409)
			(xy 368.949986 -237.19409) (xy 368.949491 -237.218697) (xy 368.941596 -237.267274) (xy 368.926012 -237.313955)
			(xy 368.903141 -237.357532) (xy 368.873576 -237.396876) (xy 368.838083 -237.430968) (xy 368.79758 -237.458924)
			(xy 368.753118 -237.480022) (xy 368.705847 -237.493714) (xy 368.656992 -237.499646) (xy 368.607817 -237.497665)
			(xy 368.559598 -237.487821) (xy 368.513582 -237.470369) (xy 368.470961 -237.445762) (xy 368.43284 -237.414637)
			(xy 368.400205 -237.3778) (xy 368.373902 -237.336204) (xy 368.354611 -237.290928) (xy 368.342834 -237.243144)
			(xy 368.338874 -237.19409) (xy 368.010186 -237.19409) (xy 368.009691 -237.218697) (xy 368.001796 -237.267274)
			(xy 367.986212 -237.313955) (xy 367.963341 -237.357532) (xy 367.933776 -237.396876) (xy 367.898283 -237.430968)
			(xy 367.85778 -237.458924) (xy 367.813318 -237.480022) (xy 367.766047 -237.493714) (xy 367.717192 -237.499646)
			(xy 367.668017 -237.497665) (xy 367.619798 -237.487821) (xy 367.573782 -237.470369) (xy 367.531161 -237.445762)
			(xy 367.49304 -237.414637) (xy 367.460405 -237.3778) (xy 367.434102 -237.336204) (xy 367.414811 -237.290928)
			(xy 367.403034 -237.243144) (xy 367.399074 -237.19409) (xy 367.070132 -237.19409) (xy 367.069637 -237.218697)
			(xy 367.061742 -237.267274) (xy 367.046158 -237.313955) (xy 367.023287 -237.357532) (xy 366.993722 -237.396876)
			(xy 366.958229 -237.430968) (xy 366.917726 -237.458924) (xy 366.873264 -237.480022) (xy 366.825993 -237.493714)
			(xy 366.777138 -237.499646) (xy 366.727963 -237.497665) (xy 366.679744 -237.487821) (xy 366.633728 -237.470369)
			(xy 366.591107 -237.445762) (xy 366.552986 -237.414637) (xy 366.520351 -237.3778) (xy 366.494048 -237.336204)
			(xy 366.474757 -237.290928) (xy 366.46298 -237.243144) (xy 366.45902 -237.19409) (xy 366.130078 -237.19409)
			(xy 366.129583 -237.218697) (xy 366.121688 -237.267274) (xy 366.106104 -237.313955) (xy 366.083233 -237.357532)
			(xy 366.053668 -237.396876) (xy 366.018175 -237.430968) (xy 365.977672 -237.458924) (xy 365.93321 -237.480022)
			(xy 365.885939 -237.493714) (xy 365.837084 -237.499646) (xy 365.787909 -237.497665) (xy 365.73969 -237.487821)
			(xy 365.693674 -237.470369) (xy 365.651053 -237.445762) (xy 365.612932 -237.414637) (xy 365.580297 -237.3778)
			(xy 365.553994 -237.336204) (xy 365.534703 -237.290928) (xy 365.522926 -237.243144) (xy 365.518966 -237.19409)
			(xy 365.190024 -237.19409) (xy 365.189529 -237.218697) (xy 365.181634 -237.267274) (xy 365.16605 -237.313955)
			(xy 365.143179 -237.357532) (xy 365.113614 -237.396876) (xy 365.078121 -237.430968) (xy 365.037618 -237.458924)
			(xy 364.993156 -237.480022) (xy 364.945885 -237.493714) (xy 364.89703 -237.499646) (xy 364.847855 -237.497665)
			(xy 364.799636 -237.487821) (xy 364.75362 -237.470369) (xy 364.710999 -237.445762) (xy 364.672878 -237.414637)
			(xy 364.640243 -237.3778) (xy 364.61394 -237.336204) (xy 364.594649 -237.290928) (xy 364.582872 -237.243144)
			(xy 364.578912 -237.19409) (xy 364.250224 -237.19409) (xy 364.249729 -237.218697) (xy 364.241834 -237.267274)
			(xy 364.22625 -237.313955) (xy 364.203379 -237.357532) (xy 364.173814 -237.396876) (xy 364.138321 -237.430968)
			(xy 364.097818 -237.458924) (xy 364.053356 -237.480022) (xy 364.006085 -237.493714) (xy 363.95723 -237.499646)
			(xy 363.908055 -237.497665) (xy 363.859836 -237.487821) (xy 363.81382 -237.470369) (xy 363.771199 -237.445762)
			(xy 363.733078 -237.414637) (xy 363.700443 -237.3778) (xy 363.67414 -237.336204) (xy 363.654849 -237.290928)
			(xy 363.643072 -237.243144) (xy 363.639112 -237.19409) (xy 361.430062 -237.19409) (xy 361.429567 -237.218697)
			(xy 361.421672 -237.267274) (xy 361.406088 -237.313955) (xy 361.383217 -237.357532) (xy 361.353652 -237.396876)
			(xy 361.318159 -237.430968) (xy 361.277656 -237.458924) (xy 361.233194 -237.480022) (xy 361.185923 -237.493714)
			(xy 361.137068 -237.499646) (xy 361.087893 -237.497665) (xy 361.039674 -237.487821) (xy 360.993658 -237.470369)
			(xy 360.951037 -237.445762) (xy 360.912916 -237.414637) (xy 360.880281 -237.3778) (xy 360.853978 -237.336204)
			(xy 360.834687 -237.290928) (xy 360.82291 -237.243144) (xy 360.81895 -237.19409) (xy 358.616504 -237.19409)
			(xy 358.616009 -237.218697) (xy 358.608114 -237.267274) (xy 358.59253 -237.313955) (xy 358.569659 -237.357532)
			(xy 358.540094 -237.396876) (xy 358.504601 -237.430968) (xy 358.464098 -237.458924) (xy 358.419636 -237.480022)
			(xy 358.372365 -237.493714) (xy 358.32351 -237.499646) (xy 358.274335 -237.497665) (xy 358.226116 -237.487821)
			(xy 358.1801 -237.470369) (xy 358.137479 -237.445762) (xy 358.099358 -237.414637) (xy 358.066723 -237.3778)
			(xy 358.04042 -237.336204) (xy 358.021129 -237.290928) (xy 358.009352 -237.243144) (xy 358.005392 -237.19409)
			(xy 355.796342 -237.19409) (xy 355.795847 -237.218697) (xy 355.787952 -237.267274) (xy 355.772368 -237.313955)
			(xy 355.749497 -237.357532) (xy 355.719932 -237.396876) (xy 355.684439 -237.430968) (xy 355.643936 -237.458924)
			(xy 355.599474 -237.480022) (xy 355.552203 -237.493714) (xy 355.503348 -237.499646) (xy 355.454173 -237.497665)
			(xy 355.405954 -237.487821) (xy 355.359938 -237.470369) (xy 355.317317 -237.445762) (xy 355.279196 -237.414637)
			(xy 355.246561 -237.3778) (xy 355.220258 -237.336204) (xy 355.200967 -237.290928) (xy 355.18919 -237.243144)
			(xy 355.18523 -237.19409) (xy 354.856542 -237.19409) (xy 354.856047 -237.218697) (xy 354.848152 -237.267274)
			(xy 354.832568 -237.313955) (xy 354.809697 -237.357532) (xy 354.780132 -237.396876) (xy 354.744639 -237.430968)
			(xy 354.704136 -237.458924) (xy 354.659674 -237.480022) (xy 354.612403 -237.493714) (xy 354.563548 -237.499646)
			(xy 354.514373 -237.497665) (xy 354.466154 -237.487821) (xy 354.420138 -237.470369) (xy 354.377517 -237.445762)
			(xy 354.339396 -237.414637) (xy 354.306761 -237.3778) (xy 354.280458 -237.336204) (xy 354.261167 -237.290928)
			(xy 354.24939 -237.243144) (xy 354.24543 -237.19409) (xy 353.916488 -237.19409) (xy 353.915993 -237.218697)
			(xy 353.908098 -237.267274) (xy 353.892514 -237.313955) (xy 353.869643 -237.357532) (xy 353.840078 -237.396876)
			(xy 353.804585 -237.430968) (xy 353.764082 -237.458924) (xy 353.71962 -237.480022) (xy 353.672349 -237.493714)
			(xy 353.623494 -237.499646) (xy 353.574319 -237.497665) (xy 353.5261 -237.487821) (xy 353.480084 -237.470369)
			(xy 353.437463 -237.445762) (xy 353.399342 -237.414637) (xy 353.366707 -237.3778) (xy 353.340404 -237.336204)
			(xy 353.321113 -237.290928) (xy 353.309336 -237.243144) (xy 353.305376 -237.19409) (xy 352.976434 -237.19409)
			(xy 352.975939 -237.218697) (xy 352.968044 -237.267274) (xy 352.95246 -237.313955) (xy 352.929589 -237.357532)
			(xy 352.900024 -237.396876) (xy 352.864531 -237.430968) (xy 352.824028 -237.458924) (xy 352.779566 -237.480022)
			(xy 352.732295 -237.493714) (xy 352.68344 -237.499646) (xy 352.634265 -237.497665) (xy 352.586046 -237.487821)
			(xy 352.54003 -237.470369) (xy 352.497409 -237.445762) (xy 352.459288 -237.414637) (xy 352.426653 -237.3778)
			(xy 352.40035 -237.336204) (xy 352.381059 -237.290928) (xy 352.369282 -237.243144) (xy 352.365322 -237.19409)
			(xy 352.03638 -237.19409) (xy 352.035885 -237.218697) (xy 352.02799 -237.267274) (xy 352.012406 -237.313955)
			(xy 351.989535 -237.357532) (xy 351.95997 -237.396876) (xy 351.924477 -237.430968) (xy 351.883974 -237.458924)
			(xy 351.839512 -237.480022) (xy 351.792241 -237.493714) (xy 351.743386 -237.499646) (xy 351.694211 -237.497665)
			(xy 351.645992 -237.487821) (xy 351.599976 -237.470369) (xy 351.557355 -237.445762) (xy 351.519234 -237.414637)
			(xy 351.486599 -237.3778) (xy 351.460296 -237.336204) (xy 351.441005 -237.290928) (xy 351.429228 -237.243144)
			(xy 351.425268 -237.19409) (xy 351.096326 -237.19409) (xy 351.095831 -237.218697) (xy 351.087936 -237.267274)
			(xy 351.072352 -237.313955) (xy 351.049481 -237.357532) (xy 351.019916 -237.396876) (xy 350.984423 -237.430968)
			(xy 350.94392 -237.458924) (xy 350.899458 -237.480022) (xy 350.852187 -237.493714) (xy 350.803332 -237.499646)
			(xy 350.754157 -237.497665) (xy 350.705938 -237.487821) (xy 350.659922 -237.470369) (xy 350.617301 -237.445762)
			(xy 350.57918 -237.414637) (xy 350.546545 -237.3778) (xy 350.520242 -237.336204) (xy 350.500951 -237.290928)
			(xy 350.489174 -237.243144) (xy 350.485214 -237.19409) (xy 350.156526 -237.19409) (xy 350.156031 -237.218697)
			(xy 350.148136 -237.267274) (xy 350.132552 -237.313955) (xy 350.109681 -237.357532) (xy 350.080116 -237.396876)
			(xy 350.044623 -237.430968) (xy 350.00412 -237.458924) (xy 349.959658 -237.480022) (xy 349.912387 -237.493714)
			(xy 349.863532 -237.499646) (xy 349.814357 -237.497665) (xy 349.766138 -237.487821) (xy 349.720122 -237.470369)
			(xy 349.677501 -237.445762) (xy 349.63938 -237.414637) (xy 349.606745 -237.3778) (xy 349.580442 -237.336204)
			(xy 349.561151 -237.290928) (xy 349.549374 -237.243144) (xy 349.545414 -237.19409) (xy 349.216472 -237.19409)
			(xy 349.215977 -237.218697) (xy 349.208082 -237.267274) (xy 349.192498 -237.313955) (xy 349.169627 -237.357532)
			(xy 349.140062 -237.396876) (xy 349.104569 -237.430968) (xy 349.064066 -237.458924) (xy 349.019604 -237.480022)
			(xy 348.972333 -237.493714) (xy 348.923478 -237.499646) (xy 348.874303 -237.497665) (xy 348.826084 -237.487821)
			(xy 348.780068 -237.470369) (xy 348.737447 -237.445762) (xy 348.699326 -237.414637) (xy 348.666691 -237.3778)
			(xy 348.640388 -237.336204) (xy 348.621097 -237.290928) (xy 348.60932 -237.243144) (xy 348.60536 -237.19409)
			(xy 348.276418 -237.19409) (xy 348.275923 -237.218697) (xy 348.268028 -237.267274) (xy 348.252444 -237.313955)
			(xy 348.229573 -237.357532) (xy 348.200008 -237.396876) (xy 348.164515 -237.430968) (xy 348.124012 -237.458924)
			(xy 348.07955 -237.480022) (xy 348.032279 -237.493714) (xy 347.983424 -237.499646) (xy 347.934249 -237.497665)
			(xy 347.88603 -237.487821) (xy 347.840014 -237.470369) (xy 347.797393 -237.445762) (xy 347.759272 -237.414637)
			(xy 347.726637 -237.3778) (xy 347.700334 -237.336204) (xy 347.681043 -237.290928) (xy 347.669266 -237.243144)
			(xy 347.665306 -237.19409) (xy 347.336364 -237.19409) (xy 347.335869 -237.218697) (xy 347.327974 -237.267274)
			(xy 347.31239 -237.313955) (xy 347.289519 -237.357532) (xy 347.259954 -237.396876) (xy 347.224461 -237.430968)
			(xy 347.183958 -237.458924) (xy 347.139496 -237.480022) (xy 347.092225 -237.493714) (xy 347.04337 -237.499646)
			(xy 346.994195 -237.497665) (xy 346.945976 -237.487821) (xy 346.89996 -237.470369) (xy 346.857339 -237.445762)
			(xy 346.819218 -237.414637) (xy 346.786583 -237.3778) (xy 346.76028 -237.336204) (xy 346.740989 -237.290928)
			(xy 346.729212 -237.243144) (xy 346.725252 -237.19409) (xy 346.39631 -237.19409) (xy 346.395815 -237.218697)
			(xy 346.38792 -237.267274) (xy 346.372336 -237.313955) (xy 346.349465 -237.357532) (xy 346.3199 -237.396876)
			(xy 346.284407 -237.430968) (xy 346.243904 -237.458924) (xy 346.199442 -237.480022) (xy 346.152171 -237.493714)
			(xy 346.103316 -237.499646) (xy 346.054141 -237.497665) (xy 346.005922 -237.487821) (xy 345.959906 -237.470369)
			(xy 345.917285 -237.445762) (xy 345.879164 -237.414637) (xy 345.846529 -237.3778) (xy 345.820226 -237.336204)
			(xy 345.800935 -237.290928) (xy 345.789158 -237.243144) (xy 345.785198 -237.19409) (xy 345.45651 -237.19409)
			(xy 345.456015 -237.218697) (xy 345.44812 -237.267274) (xy 345.432536 -237.313955) (xy 345.409665 -237.357532)
			(xy 345.3801 -237.396876) (xy 345.344607 -237.430968) (xy 345.304104 -237.458924) (xy 345.259642 -237.480022)
			(xy 345.212371 -237.493714) (xy 345.163516 -237.499646) (xy 345.114341 -237.497665) (xy 345.066122 -237.487821)
			(xy 345.020106 -237.470369) (xy 344.977485 -237.445762) (xy 344.939364 -237.414637) (xy 344.906729 -237.3778)
			(xy 344.880426 -237.336204) (xy 344.861135 -237.290928) (xy 344.849358 -237.243144) (xy 344.845398 -237.19409)
			(xy 344.626438 -237.19409) (xy 344.626438 -237.627414) (xy 344.626882 -237.637571) (xy 344.634739 -237.656306)
			(xy 344.641678 -237.663736) (xy 344.669618 -237.691168) (xy 344.686636 -237.698788) (xy 344.696034 -237.699042)
			(xy 344.720453 -237.700729) (xy 344.76833 -237.710904) (xy 344.813971 -237.728584) (xy 344.856208 -237.753317)
			(xy 344.893961 -237.784468) (xy 344.926262 -237.821242) (xy 344.952285 -237.862697) (xy 344.971364 -237.907771)
			(xy 344.98301 -237.955311) (xy 344.986925 -238.004096) (xy 345.315298 -238.004096) (xy 345.319258 -237.955042)
			(xy 345.331035 -237.907258) (xy 345.350326 -237.861982) (xy 345.376629 -237.820386) (xy 345.409264 -237.783549)
			(xy 345.447385 -237.752424) (xy 345.490006 -237.727817) (xy 345.536022 -237.710365) (xy 345.584241 -237.700521)
			(xy 345.633416 -237.69854) (xy 345.682271 -237.704472) (xy 345.729542 -237.718164) (xy 345.774004 -237.739262)
			(xy 345.814507 -237.767218) (xy 345.85 -237.80131) (xy 345.879565 -237.840654) (xy 345.902436 -237.884231)
			(xy 345.91802 -237.930912) (xy 345.925915 -237.979489) (xy 345.92641 -238.004096) (xy 346.255352 -238.004096)
			(xy 346.259312 -237.955042) (xy 346.271089 -237.907258) (xy 346.29038 -237.861982) (xy 346.316683 -237.820386)
			(xy 346.349318 -237.783549) (xy 346.387439 -237.752424) (xy 346.43006 -237.727817) (xy 346.476076 -237.710365)
			(xy 346.524295 -237.700521) (xy 346.57347 -237.69854) (xy 346.622325 -237.704472) (xy 346.669596 -237.718164)
			(xy 346.714058 -237.739262) (xy 346.754561 -237.767218) (xy 346.790054 -237.80131) (xy 346.819619 -237.840654)
			(xy 346.84249 -237.884231) (xy 346.858074 -237.930912) (xy 346.865969 -237.979489) (xy 346.866464 -238.004096)
			(xy 347.195406 -238.004096) (xy 347.199366 -237.955042) (xy 347.211143 -237.907258) (xy 347.230434 -237.861982)
			(xy 347.256737 -237.820386) (xy 347.289372 -237.783549) (xy 347.327493 -237.752424) (xy 347.370114 -237.727817)
			(xy 347.41613 -237.710365) (xy 347.464349 -237.700521) (xy 347.513524 -237.69854) (xy 347.562379 -237.704472)
			(xy 347.60965 -237.718164) (xy 347.654112 -237.739262) (xy 347.694615 -237.767218) (xy 347.730108 -237.80131)
			(xy 347.759673 -237.840654) (xy 347.782544 -237.884231) (xy 347.798128 -237.930912) (xy 347.806023 -237.979489)
			(xy 347.806518 -238.004096) (xy 348.135206 -238.004096) (xy 348.139166 -237.955042) (xy 348.150943 -237.907258)
			(xy 348.170234 -237.861982) (xy 348.196537 -237.820386) (xy 348.229172 -237.783549) (xy 348.267293 -237.752424)
			(xy 348.309914 -237.727817) (xy 348.35593 -237.710365) (xy 348.404149 -237.700521) (xy 348.453324 -237.69854)
			(xy 348.502179 -237.704472) (xy 348.54945 -237.718164) (xy 348.593912 -237.739262) (xy 348.634415 -237.767218)
			(xy 348.669908 -237.80131) (xy 348.699473 -237.840654) (xy 348.722344 -237.884231) (xy 348.737928 -237.930912)
			(xy 348.745823 -237.979489) (xy 348.746318 -238.004096) (xy 349.07526 -238.004096) (xy 349.07922 -237.955042)
			(xy 349.090997 -237.907258) (xy 349.110288 -237.861982) (xy 349.136591 -237.820386) (xy 349.169226 -237.783549)
			(xy 349.207347 -237.752424) (xy 349.249968 -237.727817) (xy 349.295984 -237.710365) (xy 349.344203 -237.700521)
			(xy 349.393378 -237.69854) (xy 349.442233 -237.704472) (xy 349.489504 -237.718164) (xy 349.533966 -237.739262)
			(xy 349.574469 -237.767218) (xy 349.609962 -237.80131) (xy 349.639527 -237.840654) (xy 349.662398 -237.884231)
			(xy 349.677982 -237.930912) (xy 349.685877 -237.979489) (xy 349.686372 -238.004096) (xy 350.015314 -238.004096)
			(xy 350.019274 -237.955042) (xy 350.031051 -237.907258) (xy 350.050342 -237.861982) (xy 350.076645 -237.820386)
			(xy 350.10928 -237.783549) (xy 350.147401 -237.752424) (xy 350.190022 -237.727817) (xy 350.236038 -237.710365)
			(xy 350.284257 -237.700521) (xy 350.333432 -237.69854) (xy 350.382287 -237.704472) (xy 350.429558 -237.718164)
			(xy 350.47402 -237.739262) (xy 350.514523 -237.767218) (xy 350.550016 -237.80131) (xy 350.579581 -237.840654)
			(xy 350.602452 -237.884231) (xy 350.618036 -237.930912) (xy 350.625931 -237.979489) (xy 350.626426 -238.004096)
			(xy 350.955368 -238.004096) (xy 350.959328 -237.955042) (xy 350.971105 -237.907258) (xy 350.990396 -237.861982)
			(xy 351.016699 -237.820386) (xy 351.049334 -237.783549) (xy 351.087455 -237.752424) (xy 351.130076 -237.727817)
			(xy 351.176092 -237.710365) (xy 351.224311 -237.700521) (xy 351.273486 -237.69854) (xy 351.322341 -237.704472)
			(xy 351.369612 -237.718164) (xy 351.414074 -237.739262) (xy 351.454577 -237.767218) (xy 351.49007 -237.80131)
			(xy 351.519635 -237.840654) (xy 351.542506 -237.884231) (xy 351.55809 -237.930912) (xy 351.565985 -237.979489)
			(xy 351.56648 -238.004096) (xy 351.895422 -238.004096) (xy 351.899382 -237.955042) (xy 351.911159 -237.907258)
			(xy 351.93045 -237.861982) (xy 351.956753 -237.820386) (xy 351.989388 -237.783549) (xy 352.027509 -237.752424)
			(xy 352.07013 -237.727817) (xy 352.116146 -237.710365) (xy 352.164365 -237.700521) (xy 352.21354 -237.69854)
			(xy 352.262395 -237.704472) (xy 352.309666 -237.718164) (xy 352.354128 -237.739262) (xy 352.394631 -237.767218)
			(xy 352.430124 -237.80131) (xy 352.459689 -237.840654) (xy 352.48256 -237.884231) (xy 352.498144 -237.930912)
			(xy 352.506039 -237.979489) (xy 352.506534 -238.004096) (xy 352.835222 -238.004096) (xy 352.839182 -237.955042)
			(xy 352.850959 -237.907258) (xy 352.87025 -237.861982) (xy 352.896553 -237.820386) (xy 352.929188 -237.783549)
			(xy 352.967309 -237.752424) (xy 353.00993 -237.727817) (xy 353.055946 -237.710365) (xy 353.104165 -237.700521)
			(xy 353.15334 -237.69854) (xy 353.202195 -237.704472) (xy 353.249466 -237.718164) (xy 353.293928 -237.739262)
			(xy 353.334431 -237.767218) (xy 353.369924 -237.80131) (xy 353.399489 -237.840654) (xy 353.42236 -237.884231)
			(xy 353.437944 -237.930912) (xy 353.445839 -237.979489) (xy 353.446334 -238.004096) (xy 353.775276 -238.004096)
			(xy 353.779236 -237.955042) (xy 353.791013 -237.907258) (xy 353.810304 -237.861982) (xy 353.836607 -237.820386)
			(xy 353.869242 -237.783549) (xy 353.907363 -237.752424) (xy 353.949984 -237.727817) (xy 353.996 -237.710365)
			(xy 354.044219 -237.700521) (xy 354.093394 -237.69854) (xy 354.142249 -237.704472) (xy 354.18952 -237.718164)
			(xy 354.233982 -237.739262) (xy 354.274485 -237.767218) (xy 354.309978 -237.80131) (xy 354.339543 -237.840654)
			(xy 354.362414 -237.884231) (xy 354.377998 -237.930912) (xy 354.385893 -237.979489) (xy 354.386388 -238.004096)
			(xy 354.71533 -238.004096) (xy 354.71929 -237.955042) (xy 354.731067 -237.907258) (xy 354.750358 -237.861982)
			(xy 354.776661 -237.820386) (xy 354.809296 -237.783549) (xy 354.847417 -237.752424) (xy 354.890038 -237.727817)
			(xy 354.936054 -237.710365) (xy 354.984273 -237.700521) (xy 355.033448 -237.69854) (xy 355.082303 -237.704472)
			(xy 355.129574 -237.718164) (xy 355.174036 -237.739262) (xy 355.214539 -237.767218) (xy 355.250032 -237.80131)
			(xy 355.279597 -237.840654) (xy 355.302468 -237.884231) (xy 355.318052 -237.930912) (xy 355.325947 -237.979489)
			(xy 355.326442 -238.004096) (xy 355.655384 -238.004096) (xy 355.659344 -237.955042) (xy 355.671121 -237.907258)
			(xy 355.690412 -237.861982) (xy 355.716715 -237.820386) (xy 355.74935 -237.783549) (xy 355.787471 -237.752424)
			(xy 355.830092 -237.727817) (xy 355.876108 -237.710365) (xy 355.924327 -237.700521) (xy 355.973502 -237.69854)
			(xy 356.022357 -237.704472) (xy 356.069628 -237.718164) (xy 356.11409 -237.739262) (xy 356.154593 -237.767218)
			(xy 356.190086 -237.80131) (xy 356.219651 -237.840654) (xy 356.242522 -237.884231) (xy 356.258106 -237.930912)
			(xy 356.266001 -237.979489) (xy 356.266496 -238.004096) (xy 356.595438 -238.004096) (xy 356.599398 -237.955042)
			(xy 356.611175 -237.907258) (xy 356.630466 -237.861982) (xy 356.656769 -237.820386) (xy 356.689404 -237.783549)
			(xy 356.727525 -237.752424) (xy 356.770146 -237.727817) (xy 356.816162 -237.710365) (xy 356.864381 -237.700521)
			(xy 356.913556 -237.69854) (xy 356.962411 -237.704472) (xy 357.009682 -237.718164) (xy 357.054144 -237.739262)
			(xy 357.094647 -237.767218) (xy 357.13014 -237.80131) (xy 357.159705 -237.840654) (xy 357.182576 -237.884231)
			(xy 357.19816 -237.930912) (xy 357.206055 -237.979489) (xy 357.20655 -238.004096) (xy 357.535238 -238.004096)
			(xy 357.539198 -237.955042) (xy 357.550975 -237.907258) (xy 357.570266 -237.861982) (xy 357.596569 -237.820386)
			(xy 357.629204 -237.783549) (xy 357.667325 -237.752424) (xy 357.709946 -237.727817) (xy 357.755962 -237.710365)
			(xy 357.804181 -237.700521) (xy 357.853356 -237.69854) (xy 357.902211 -237.704472) (xy 357.949482 -237.718164)
			(xy 357.993944 -237.739262) (xy 358.034447 -237.767218) (xy 358.06994 -237.80131) (xy 358.099505 -237.840654)
			(xy 358.122376 -237.884231) (xy 358.13796 -237.930912) (xy 358.145855 -237.979489) (xy 358.14635 -238.004096)
			(xy 361.289104 -238.004096) (xy 361.293064 -237.955042) (xy 361.304841 -237.907258) (xy 361.324132 -237.861982)
			(xy 361.350435 -237.820386) (xy 361.38307 -237.783549) (xy 361.421191 -237.752424) (xy 361.463812 -237.727817)
			(xy 361.509828 -237.710365) (xy 361.558047 -237.700521) (xy 361.607222 -237.69854) (xy 361.656077 -237.704472)
			(xy 361.703348 -237.718164) (xy 361.74781 -237.739262) (xy 361.788313 -237.767218) (xy 361.823806 -237.80131)
			(xy 361.853371 -237.840654) (xy 361.876242 -237.884231) (xy 361.891826 -237.930912) (xy 361.899721 -237.979489)
			(xy 361.900216 -238.004096) (xy 362.228904 -238.004096) (xy 362.232864 -237.955042) (xy 362.244641 -237.907258)
			(xy 362.263932 -237.861982) (xy 362.290235 -237.820386) (xy 362.32287 -237.783549) (xy 362.360991 -237.752424)
			(xy 362.403612 -237.727817) (xy 362.449628 -237.710365) (xy 362.497847 -237.700521) (xy 362.547022 -237.69854)
			(xy 362.595877 -237.704472) (xy 362.643148 -237.718164) (xy 362.68761 -237.739262) (xy 362.728113 -237.767218)
			(xy 362.763606 -237.80131) (xy 362.793171 -237.840654) (xy 362.816042 -237.884231) (xy 362.831626 -237.930912)
			(xy 362.839521 -237.979489) (xy 362.840016 -238.004096) (xy 363.168958 -238.004096) (xy 363.172918 -237.955042)
			(xy 363.184695 -237.907258) (xy 363.203986 -237.861982) (xy 363.230289 -237.820386) (xy 363.262924 -237.783549)
			(xy 363.301045 -237.752424) (xy 363.343666 -237.727817) (xy 363.389682 -237.710365) (xy 363.437901 -237.700521)
			(xy 363.487076 -237.69854) (xy 363.535931 -237.704472) (xy 363.583202 -237.718164) (xy 363.627664 -237.739262)
			(xy 363.668167 -237.767218) (xy 363.70366 -237.80131) (xy 363.733225 -237.840654) (xy 363.756096 -237.884231)
			(xy 363.77168 -237.930912) (xy 363.779575 -237.979489) (xy 363.78007 -238.004096) (xy 364.109012 -238.004096)
			(xy 364.112972 -237.955042) (xy 364.124749 -237.907258) (xy 364.14404 -237.861982) (xy 364.170343 -237.820386)
			(xy 364.202978 -237.783549) (xy 364.241099 -237.752424) (xy 364.28372 -237.727817) (xy 364.329736 -237.710365)
			(xy 364.377955 -237.700521) (xy 364.42713 -237.69854) (xy 364.475985 -237.704472) (xy 364.523256 -237.718164)
			(xy 364.567718 -237.739262) (xy 364.608221 -237.767218) (xy 364.643714 -237.80131) (xy 364.673279 -237.840654)
			(xy 364.69615 -237.884231) (xy 364.711734 -237.930912) (xy 364.719629 -237.979489) (xy 364.720124 -238.004096)
			(xy 365.049066 -238.004096) (xy 365.053026 -237.955042) (xy 365.064803 -237.907258) (xy 365.084094 -237.861982)
			(xy 365.110397 -237.820386) (xy 365.143032 -237.783549) (xy 365.181153 -237.752424) (xy 365.223774 -237.727817)
			(xy 365.26979 -237.710365) (xy 365.318009 -237.700521) (xy 365.367184 -237.69854) (xy 365.416039 -237.704472)
			(xy 365.46331 -237.718164) (xy 365.507772 -237.739262) (xy 365.548275 -237.767218) (xy 365.583768 -237.80131)
			(xy 365.613333 -237.840654) (xy 365.636204 -237.884231) (xy 365.651788 -237.930912) (xy 365.659683 -237.979489)
			(xy 365.660178 -238.004096) (xy 365.98912 -238.004096) (xy 365.99308 -237.955042) (xy 366.004857 -237.907258)
			(xy 366.024148 -237.861982) (xy 366.050451 -237.820386) (xy 366.083086 -237.783549) (xy 366.121207 -237.752424)
			(xy 366.163828 -237.727817) (xy 366.209844 -237.710365) (xy 366.258063 -237.700521) (xy 366.307238 -237.69854)
			(xy 366.356093 -237.704472) (xy 366.403364 -237.718164) (xy 366.447826 -237.739262) (xy 366.488329 -237.767218)
			(xy 366.523822 -237.80131) (xy 366.553387 -237.840654) (xy 366.576258 -237.884231) (xy 366.591842 -237.930912)
			(xy 366.599737 -237.979489) (xy 366.600232 -238.004096) (xy 366.92892 -238.004096) (xy 366.93288 -237.955042)
			(xy 366.944657 -237.907258) (xy 366.963948 -237.861982) (xy 366.990251 -237.820386) (xy 367.022886 -237.783549)
			(xy 367.061007 -237.752424) (xy 367.103628 -237.727817) (xy 367.149644 -237.710365) (xy 367.197863 -237.700521)
			(xy 367.247038 -237.69854) (xy 367.295893 -237.704472) (xy 367.343164 -237.718164) (xy 367.387626 -237.739262)
			(xy 367.428129 -237.767218) (xy 367.463622 -237.80131) (xy 367.493187 -237.840654) (xy 367.516058 -237.884231)
			(xy 367.531642 -237.930912) (xy 367.539537 -237.979489) (xy 367.540032 -238.004096) (xy 367.868974 -238.004096)
			(xy 367.872934 -237.955042) (xy 367.884711 -237.907258) (xy 367.904002 -237.861982) (xy 367.930305 -237.820386)
			(xy 367.96294 -237.783549) (xy 368.001061 -237.752424) (xy 368.043682 -237.727817) (xy 368.089698 -237.710365)
			(xy 368.137917 -237.700521) (xy 368.187092 -237.69854) (xy 368.235947 -237.704472) (xy 368.283218 -237.718164)
			(xy 368.32768 -237.739262) (xy 368.368183 -237.767218) (xy 368.403676 -237.80131) (xy 368.433241 -237.840654)
			(xy 368.456112 -237.884231) (xy 368.471696 -237.930912) (xy 368.479591 -237.979489) (xy 368.480086 -238.004096)
			(xy 368.809028 -238.004096) (xy 368.812988 -237.955042) (xy 368.824765 -237.907258) (xy 368.844056 -237.861982)
			(xy 368.870359 -237.820386) (xy 368.902994 -237.783549) (xy 368.941115 -237.752424) (xy 368.983736 -237.727817)
			(xy 369.029752 -237.710365) (xy 369.077971 -237.700521) (xy 369.127146 -237.69854) (xy 369.176001 -237.704472)
			(xy 369.223272 -237.718164) (xy 369.267734 -237.739262) (xy 369.308237 -237.767218) (xy 369.34373 -237.80131)
			(xy 369.373295 -237.840654) (xy 369.396166 -237.884231) (xy 369.41175 -237.930912) (xy 369.419645 -237.979489)
			(xy 369.42014 -238.004096) (xy 369.749082 -238.004096) (xy 369.753042 -237.955042) (xy 369.764819 -237.907258)
			(xy 369.78411 -237.861982) (xy 369.810413 -237.820386) (xy 369.843048 -237.783549) (xy 369.881169 -237.752424)
			(xy 369.92379 -237.727817) (xy 369.969806 -237.710365) (xy 370.018025 -237.700521) (xy 370.0672 -237.69854)
			(xy 370.116055 -237.704472) (xy 370.163326 -237.718164) (xy 370.207788 -237.739262) (xy 370.248291 -237.767218)
			(xy 370.283784 -237.80131) (xy 370.313349 -237.840654) (xy 370.33622 -237.884231) (xy 370.351804 -237.930912)
			(xy 370.359699 -237.979489) (xy 370.360194 -238.004096) (xy 370.688882 -238.004096) (xy 370.692842 -237.955042)
			(xy 370.704619 -237.907258) (xy 370.72391 -237.861982) (xy 370.750213 -237.820386) (xy 370.782848 -237.783549)
			(xy 370.820969 -237.752424) (xy 370.86359 -237.727817) (xy 370.909606 -237.710365) (xy 370.957825 -237.700521)
			(xy 371.007 -237.69854) (xy 371.055855 -237.704472) (xy 371.103126 -237.718164) (xy 371.147588 -237.739262)
			(xy 371.188091 -237.767218) (xy 371.223584 -237.80131) (xy 371.253149 -237.840654) (xy 371.27602 -237.884231)
			(xy 371.291604 -237.930912) (xy 371.299499 -237.979489) (xy 371.299994 -238.004096) (xy 371.628936 -238.004096)
			(xy 371.632896 -237.955042) (xy 371.644673 -237.907258) (xy 371.663964 -237.861982) (xy 371.690267 -237.820386)
			(xy 371.722902 -237.783549) (xy 371.761023 -237.752424) (xy 371.803644 -237.727817) (xy 371.84966 -237.710365)
			(xy 371.897879 -237.700521) (xy 371.947054 -237.69854) (xy 371.995909 -237.704472) (xy 372.04318 -237.718164)
			(xy 372.087642 -237.739262) (xy 372.128145 -237.767218) (xy 372.163638 -237.80131) (xy 372.193203 -237.840654)
			(xy 372.216074 -237.884231) (xy 372.231658 -237.930912) (xy 372.239553 -237.979489) (xy 372.240048 -238.004096)
			(xy 372.56899 -238.004096) (xy 372.57295 -237.955042) (xy 372.584727 -237.907258) (xy 372.604018 -237.861982)
			(xy 372.630321 -237.820386) (xy 372.662956 -237.783549) (xy 372.701077 -237.752424) (xy 372.743698 -237.727817)
			(xy 372.789714 -237.710365) (xy 372.837933 -237.700521) (xy 372.887108 -237.69854) (xy 372.935963 -237.704472)
			(xy 372.983234 -237.718164) (xy 373.027696 -237.739262) (xy 373.068199 -237.767218) (xy 373.103692 -237.80131)
			(xy 373.133257 -237.840654) (xy 373.156128 -237.884231) (xy 373.171712 -237.930912) (xy 373.179607 -237.979489)
			(xy 373.180102 -238.004096) (xy 373.509044 -238.004096) (xy 373.513004 -237.955042) (xy 373.524781 -237.907258)
			(xy 373.544072 -237.861982) (xy 373.570375 -237.820386) (xy 373.60301 -237.783549) (xy 373.641131 -237.752424)
			(xy 373.683752 -237.727817) (xy 373.729768 -237.710365) (xy 373.777987 -237.700521) (xy 373.827162 -237.69854)
			(xy 373.876017 -237.704472) (xy 373.923288 -237.718164) (xy 373.96775 -237.739262) (xy 374.008253 -237.767218)
			(xy 374.043746 -237.80131) (xy 374.073311 -237.840654) (xy 374.096182 -237.884231) (xy 374.111766 -237.930912)
			(xy 374.119661 -237.979489) (xy 374.120156 -238.004096) (xy 374.119661 -238.028703) (xy 374.111766 -238.07728)
			(xy 374.096182 -238.123961) (xy 374.073311 -238.167538) (xy 374.043746 -238.206882) (xy 374.008253 -238.240974)
			(xy 373.96775 -238.26893) (xy 373.923288 -238.290028) (xy 373.876017 -238.30372) (xy 373.827162 -238.309652)
			(xy 373.777987 -238.307671) (xy 373.729768 -238.297827) (xy 373.683752 -238.280375) (xy 373.641131 -238.255768)
			(xy 373.60301 -238.224643) (xy 373.570375 -238.187806) (xy 373.544072 -238.14621) (xy 373.524781 -238.100934)
			(xy 373.513004 -238.05315) (xy 373.509044 -238.004096) (xy 373.180102 -238.004096) (xy 373.179607 -238.028703)
			(xy 373.171712 -238.07728) (xy 373.156128 -238.123961) (xy 373.133257 -238.167538) (xy 373.103692 -238.206882)
			(xy 373.068199 -238.240974) (xy 373.027696 -238.26893) (xy 372.983234 -238.290028) (xy 372.935963 -238.30372)
			(xy 372.887108 -238.309652) (xy 372.837933 -238.307671) (xy 372.789714 -238.297827) (xy 372.743698 -238.280375)
			(xy 372.701077 -238.255768) (xy 372.662956 -238.224643) (xy 372.630321 -238.187806) (xy 372.604018 -238.14621)
			(xy 372.584727 -238.100934) (xy 372.57295 -238.05315) (xy 372.56899 -238.004096) (xy 372.240048 -238.004096)
			(xy 372.239553 -238.028703) (xy 372.231658 -238.07728) (xy 372.216074 -238.123961) (xy 372.193203 -238.167538)
			(xy 372.163638 -238.206882) (xy 372.128145 -238.240974) (xy 372.087642 -238.26893) (xy 372.04318 -238.290028)
			(xy 371.995909 -238.30372) (xy 371.947054 -238.309652) (xy 371.897879 -238.307671) (xy 371.84966 -238.297827)
			(xy 371.803644 -238.280375) (xy 371.761023 -238.255768) (xy 371.722902 -238.224643) (xy 371.690267 -238.187806)
			(xy 371.663964 -238.14621) (xy 371.644673 -238.100934) (xy 371.632896 -238.05315) (xy 371.628936 -238.004096)
			(xy 371.299994 -238.004096) (xy 371.299499 -238.028703) (xy 371.291604 -238.07728) (xy 371.27602 -238.123961)
			(xy 371.253149 -238.167538) (xy 371.223584 -238.206882) (xy 371.188091 -238.240974) (xy 371.147588 -238.26893)
			(xy 371.103126 -238.290028) (xy 371.055855 -238.30372) (xy 371.007 -238.309652) (xy 370.957825 -238.307671)
			(xy 370.909606 -238.297827) (xy 370.86359 -238.280375) (xy 370.820969 -238.255768) (xy 370.782848 -238.224643)
			(xy 370.750213 -238.187806) (xy 370.72391 -238.14621) (xy 370.704619 -238.100934) (xy 370.692842 -238.05315)
			(xy 370.688882 -238.004096) (xy 370.360194 -238.004096) (xy 370.359699 -238.028703) (xy 370.351804 -238.07728)
			(xy 370.33622 -238.123961) (xy 370.313349 -238.167538) (xy 370.283784 -238.206882) (xy 370.248291 -238.240974)
			(xy 370.207788 -238.26893) (xy 370.163326 -238.290028) (xy 370.116055 -238.30372) (xy 370.0672 -238.309652)
			(xy 370.018025 -238.307671) (xy 369.969806 -238.297827) (xy 369.92379 -238.280375) (xy 369.881169 -238.255768)
			(xy 369.843048 -238.224643) (xy 369.810413 -238.187806) (xy 369.78411 -238.14621) (xy 369.764819 -238.100934)
			(xy 369.753042 -238.05315) (xy 369.749082 -238.004096) (xy 369.42014 -238.004096) (xy 369.419645 -238.028703)
			(xy 369.41175 -238.07728) (xy 369.396166 -238.123961) (xy 369.373295 -238.167538) (xy 369.34373 -238.206882)
			(xy 369.308237 -238.240974) (xy 369.267734 -238.26893) (xy 369.223272 -238.290028) (xy 369.176001 -238.30372)
			(xy 369.127146 -238.309652) (xy 369.077971 -238.307671) (xy 369.029752 -238.297827) (xy 368.983736 -238.280375)
			(xy 368.941115 -238.255768) (xy 368.902994 -238.224643) (xy 368.870359 -238.187806) (xy 368.844056 -238.14621)
			(xy 368.824765 -238.100934) (xy 368.812988 -238.05315) (xy 368.809028 -238.004096) (xy 368.480086 -238.004096)
			(xy 368.479591 -238.028703) (xy 368.471696 -238.07728) (xy 368.456112 -238.123961) (xy 368.433241 -238.167538)
			(xy 368.403676 -238.206882) (xy 368.368183 -238.240974) (xy 368.32768 -238.26893) (xy 368.283218 -238.290028)
			(xy 368.235947 -238.30372) (xy 368.187092 -238.309652) (xy 368.137917 -238.307671) (xy 368.089698 -238.297827)
			(xy 368.043682 -238.280375) (xy 368.001061 -238.255768) (xy 367.96294 -238.224643) (xy 367.930305 -238.187806)
			(xy 367.904002 -238.14621) (xy 367.884711 -238.100934) (xy 367.872934 -238.05315) (xy 367.868974 -238.004096)
			(xy 367.540032 -238.004096) (xy 367.539537 -238.028703) (xy 367.531642 -238.07728) (xy 367.516058 -238.123961)
			(xy 367.493187 -238.167538) (xy 367.463622 -238.206882) (xy 367.428129 -238.240974) (xy 367.387626 -238.26893)
			(xy 367.343164 -238.290028) (xy 367.295893 -238.30372) (xy 367.247038 -238.309652) (xy 367.197863 -238.307671)
			(xy 367.149644 -238.297827) (xy 367.103628 -238.280375) (xy 367.061007 -238.255768) (xy 367.022886 -238.224643)
			(xy 366.990251 -238.187806) (xy 366.963948 -238.14621) (xy 366.944657 -238.100934) (xy 366.93288 -238.05315)
			(xy 366.92892 -238.004096) (xy 366.600232 -238.004096) (xy 366.599737 -238.028703) (xy 366.591842 -238.07728)
			(xy 366.576258 -238.123961) (xy 366.553387 -238.167538) (xy 366.523822 -238.206882) (xy 366.488329 -238.240974)
			(xy 366.447826 -238.26893) (xy 366.403364 -238.290028) (xy 366.356093 -238.30372) (xy 366.307238 -238.309652)
			(xy 366.258063 -238.307671) (xy 366.209844 -238.297827) (xy 366.163828 -238.280375) (xy 366.121207 -238.255768)
			(xy 366.083086 -238.224643) (xy 366.050451 -238.187806) (xy 366.024148 -238.14621) (xy 366.004857 -238.100934)
			(xy 365.99308 -238.05315) (xy 365.98912 -238.004096) (xy 365.660178 -238.004096) (xy 365.659683 -238.028703)
			(xy 365.651788 -238.07728) (xy 365.636204 -238.123961) (xy 365.613333 -238.167538) (xy 365.583768 -238.206882)
			(xy 365.548275 -238.240974) (xy 365.507772 -238.26893) (xy 365.46331 -238.290028) (xy 365.416039 -238.30372)
			(xy 365.367184 -238.309652) (xy 365.318009 -238.307671) (xy 365.26979 -238.297827) (xy 365.223774 -238.280375)
			(xy 365.181153 -238.255768) (xy 365.143032 -238.224643) (xy 365.110397 -238.187806) (xy 365.084094 -238.14621)
			(xy 365.064803 -238.100934) (xy 365.053026 -238.05315) (xy 365.049066 -238.004096) (xy 364.720124 -238.004096)
			(xy 364.719629 -238.028703) (xy 364.711734 -238.07728) (xy 364.69615 -238.123961) (xy 364.673279 -238.167538)
			(xy 364.643714 -238.206882) (xy 364.608221 -238.240974) (xy 364.567718 -238.26893) (xy 364.523256 -238.290028)
			(xy 364.475985 -238.30372) (xy 364.42713 -238.309652) (xy 364.377955 -238.307671) (xy 364.329736 -238.297827)
			(xy 364.28372 -238.280375) (xy 364.241099 -238.255768) (xy 364.202978 -238.224643) (xy 364.170343 -238.187806)
			(xy 364.14404 -238.14621) (xy 364.124749 -238.100934) (xy 364.112972 -238.05315) (xy 364.109012 -238.004096)
			(xy 363.78007 -238.004096) (xy 363.779575 -238.028703) (xy 363.77168 -238.07728) (xy 363.756096 -238.123961)
			(xy 363.733225 -238.167538) (xy 363.70366 -238.206882) (xy 363.668167 -238.240974) (xy 363.627664 -238.26893)
			(xy 363.583202 -238.290028) (xy 363.535931 -238.30372) (xy 363.487076 -238.309652) (xy 363.437901 -238.307671)
			(xy 363.389682 -238.297827) (xy 363.343666 -238.280375) (xy 363.301045 -238.255768) (xy 363.262924 -238.224643)
			(xy 363.230289 -238.187806) (xy 363.203986 -238.14621) (xy 363.184695 -238.100934) (xy 363.172918 -238.05315)
			(xy 363.168958 -238.004096) (xy 362.840016 -238.004096) (xy 362.839521 -238.028703) (xy 362.831626 -238.07728)
			(xy 362.816042 -238.123961) (xy 362.793171 -238.167538) (xy 362.763606 -238.206882) (xy 362.728113 -238.240974)
			(xy 362.68761 -238.26893) (xy 362.643148 -238.290028) (xy 362.595877 -238.30372) (xy 362.547022 -238.309652)
			(xy 362.497847 -238.307671) (xy 362.449628 -238.297827) (xy 362.403612 -238.280375) (xy 362.360991 -238.255768)
			(xy 362.32287 -238.224643) (xy 362.290235 -238.187806) (xy 362.263932 -238.14621) (xy 362.244641 -238.100934)
			(xy 362.232864 -238.05315) (xy 362.228904 -238.004096) (xy 361.900216 -238.004096) (xy 361.899721 -238.028703)
			(xy 361.891826 -238.07728) (xy 361.876242 -238.123961) (xy 361.853371 -238.167538) (xy 361.823806 -238.206882)
			(xy 361.788313 -238.240974) (xy 361.74781 -238.26893) (xy 361.703348 -238.290028) (xy 361.656077 -238.30372)
			(xy 361.607222 -238.309652) (xy 361.558047 -238.307671) (xy 361.509828 -238.297827) (xy 361.463812 -238.280375)
			(xy 361.421191 -238.255768) (xy 361.38307 -238.224643) (xy 361.350435 -238.187806) (xy 361.324132 -238.14621)
			(xy 361.304841 -238.100934) (xy 361.293064 -238.05315) (xy 361.289104 -238.004096) (xy 358.14635 -238.004096)
			(xy 358.145855 -238.028703) (xy 358.13796 -238.07728) (xy 358.122376 -238.123961) (xy 358.099505 -238.167538)
			(xy 358.06994 -238.206882) (xy 358.034447 -238.240974) (xy 357.993944 -238.26893) (xy 357.949482 -238.290028)
			(xy 357.902211 -238.30372) (xy 357.853356 -238.309652) (xy 357.804181 -238.307671) (xy 357.755962 -238.297827)
			(xy 357.709946 -238.280375) (xy 357.667325 -238.255768) (xy 357.629204 -238.224643) (xy 357.596569 -238.187806)
			(xy 357.570266 -238.14621) (xy 357.550975 -238.100934) (xy 357.539198 -238.05315) (xy 357.535238 -238.004096)
			(xy 357.20655 -238.004096) (xy 357.206055 -238.028703) (xy 357.19816 -238.07728) (xy 357.182576 -238.123961)
			(xy 357.159705 -238.167538) (xy 357.13014 -238.206882) (xy 357.094647 -238.240974) (xy 357.054144 -238.26893)
			(xy 357.009682 -238.290028) (xy 356.962411 -238.30372) (xy 356.913556 -238.309652) (xy 356.864381 -238.307671)
			(xy 356.816162 -238.297827) (xy 356.770146 -238.280375) (xy 356.727525 -238.255768) (xy 356.689404 -238.224643)
			(xy 356.656769 -238.187806) (xy 356.630466 -238.14621) (xy 356.611175 -238.100934) (xy 356.599398 -238.05315)
			(xy 356.595438 -238.004096) (xy 356.266496 -238.004096) (xy 356.266001 -238.028703) (xy 356.258106 -238.07728)
			(xy 356.242522 -238.123961) (xy 356.219651 -238.167538) (xy 356.190086 -238.206882) (xy 356.154593 -238.240974)
			(xy 356.11409 -238.26893) (xy 356.069628 -238.290028) (xy 356.022357 -238.30372) (xy 355.973502 -238.309652)
			(xy 355.924327 -238.307671) (xy 355.876108 -238.297827) (xy 355.830092 -238.280375) (xy 355.787471 -238.255768)
			(xy 355.74935 -238.224643) (xy 355.716715 -238.187806) (xy 355.690412 -238.14621) (xy 355.671121 -238.100934)
			(xy 355.659344 -238.05315) (xy 355.655384 -238.004096) (xy 355.326442 -238.004096) (xy 355.325947 -238.028703)
			(xy 355.318052 -238.07728) (xy 355.302468 -238.123961) (xy 355.279597 -238.167538) (xy 355.250032 -238.206882)
			(xy 355.214539 -238.240974) (xy 355.174036 -238.26893) (xy 355.129574 -238.290028) (xy 355.082303 -238.30372)
			(xy 355.033448 -238.309652) (xy 354.984273 -238.307671) (xy 354.936054 -238.297827) (xy 354.890038 -238.280375)
			(xy 354.847417 -238.255768) (xy 354.809296 -238.224643) (xy 354.776661 -238.187806) (xy 354.750358 -238.14621)
			(xy 354.731067 -238.100934) (xy 354.71929 -238.05315) (xy 354.71533 -238.004096) (xy 354.386388 -238.004096)
			(xy 354.385893 -238.028703) (xy 354.377998 -238.07728) (xy 354.362414 -238.123961) (xy 354.339543 -238.167538)
			(xy 354.309978 -238.206882) (xy 354.274485 -238.240974) (xy 354.233982 -238.26893) (xy 354.18952 -238.290028)
			(xy 354.142249 -238.30372) (xy 354.093394 -238.309652) (xy 354.044219 -238.307671) (xy 353.996 -238.297827)
			(xy 353.949984 -238.280375) (xy 353.907363 -238.255768) (xy 353.869242 -238.224643) (xy 353.836607 -238.187806)
			(xy 353.810304 -238.14621) (xy 353.791013 -238.100934) (xy 353.779236 -238.05315) (xy 353.775276 -238.004096)
			(xy 353.446334 -238.004096) (xy 353.445839 -238.028703) (xy 353.437944 -238.07728) (xy 353.42236 -238.123961)
			(xy 353.399489 -238.167538) (xy 353.369924 -238.206882) (xy 353.334431 -238.240974) (xy 353.293928 -238.26893)
			(xy 353.249466 -238.290028) (xy 353.202195 -238.30372) (xy 353.15334 -238.309652) (xy 353.104165 -238.307671)
			(xy 353.055946 -238.297827) (xy 353.00993 -238.280375) (xy 352.967309 -238.255768) (xy 352.929188 -238.224643)
			(xy 352.896553 -238.187806) (xy 352.87025 -238.14621) (xy 352.850959 -238.100934) (xy 352.839182 -238.05315)
			(xy 352.835222 -238.004096) (xy 352.506534 -238.004096) (xy 352.506039 -238.028703) (xy 352.498144 -238.07728)
			(xy 352.48256 -238.123961) (xy 352.459689 -238.167538) (xy 352.430124 -238.206882) (xy 352.394631 -238.240974)
			(xy 352.354128 -238.26893) (xy 352.309666 -238.290028) (xy 352.262395 -238.30372) (xy 352.21354 -238.309652)
			(xy 352.164365 -238.307671) (xy 352.116146 -238.297827) (xy 352.07013 -238.280375) (xy 352.027509 -238.255768)
			(xy 351.989388 -238.224643) (xy 351.956753 -238.187806) (xy 351.93045 -238.14621) (xy 351.911159 -238.100934)
			(xy 351.899382 -238.05315) (xy 351.895422 -238.004096) (xy 351.56648 -238.004096) (xy 351.565985 -238.028703)
			(xy 351.55809 -238.07728) (xy 351.542506 -238.123961) (xy 351.519635 -238.167538) (xy 351.49007 -238.206882)
			(xy 351.454577 -238.240974) (xy 351.414074 -238.26893) (xy 351.369612 -238.290028) (xy 351.322341 -238.30372)
			(xy 351.273486 -238.309652) (xy 351.224311 -238.307671) (xy 351.176092 -238.297827) (xy 351.130076 -238.280375)
			(xy 351.087455 -238.255768) (xy 351.049334 -238.224643) (xy 351.016699 -238.187806) (xy 350.990396 -238.14621)
			(xy 350.971105 -238.100934) (xy 350.959328 -238.05315) (xy 350.955368 -238.004096) (xy 350.626426 -238.004096)
			(xy 350.625931 -238.028703) (xy 350.618036 -238.07728) (xy 350.602452 -238.123961) (xy 350.579581 -238.167538)
			(xy 350.550016 -238.206882) (xy 350.514523 -238.240974) (xy 350.47402 -238.26893) (xy 350.429558 -238.290028)
			(xy 350.382287 -238.30372) (xy 350.333432 -238.309652) (xy 350.284257 -238.307671) (xy 350.236038 -238.297827)
			(xy 350.190022 -238.280375) (xy 350.147401 -238.255768) (xy 350.10928 -238.224643) (xy 350.076645 -238.187806)
			(xy 350.050342 -238.14621) (xy 350.031051 -238.100934) (xy 350.019274 -238.05315) (xy 350.015314 -238.004096)
			(xy 349.686372 -238.004096) (xy 349.685877 -238.028703) (xy 349.677982 -238.07728) (xy 349.662398 -238.123961)
			(xy 349.639527 -238.167538) (xy 349.609962 -238.206882) (xy 349.574469 -238.240974) (xy 349.533966 -238.26893)
			(xy 349.489504 -238.290028) (xy 349.442233 -238.30372) (xy 349.393378 -238.309652) (xy 349.344203 -238.307671)
			(xy 349.295984 -238.297827) (xy 349.249968 -238.280375) (xy 349.207347 -238.255768) (xy 349.169226 -238.224643)
			(xy 349.136591 -238.187806) (xy 349.110288 -238.14621) (xy 349.090997 -238.100934) (xy 349.07922 -238.05315)
			(xy 349.07526 -238.004096) (xy 348.746318 -238.004096) (xy 348.745823 -238.028703) (xy 348.737928 -238.07728)
			(xy 348.722344 -238.123961) (xy 348.699473 -238.167538) (xy 348.669908 -238.206882) (xy 348.634415 -238.240974)
			(xy 348.593912 -238.26893) (xy 348.54945 -238.290028) (xy 348.502179 -238.30372) (xy 348.453324 -238.309652)
			(xy 348.404149 -238.307671) (xy 348.35593 -238.297827) (xy 348.309914 -238.280375) (xy 348.267293 -238.255768)
			(xy 348.229172 -238.224643) (xy 348.196537 -238.187806) (xy 348.170234 -238.14621) (xy 348.150943 -238.100934)
			(xy 348.139166 -238.05315) (xy 348.135206 -238.004096) (xy 347.806518 -238.004096) (xy 347.806023 -238.028703)
			(xy 347.798128 -238.07728) (xy 347.782544 -238.123961) (xy 347.759673 -238.167538) (xy 347.730108 -238.206882)
			(xy 347.694615 -238.240974) (xy 347.654112 -238.26893) (xy 347.60965 -238.290028) (xy 347.562379 -238.30372)
			(xy 347.513524 -238.309652) (xy 347.464349 -238.307671) (xy 347.41613 -238.297827) (xy 347.370114 -238.280375)
			(xy 347.327493 -238.255768) (xy 347.289372 -238.224643) (xy 347.256737 -238.187806) (xy 347.230434 -238.14621)
			(xy 347.211143 -238.100934) (xy 347.199366 -238.05315) (xy 347.195406 -238.004096) (xy 346.866464 -238.004096)
			(xy 346.865969 -238.028703) (xy 346.858074 -238.07728) (xy 346.84249 -238.123961) (xy 346.819619 -238.167538)
			(xy 346.790054 -238.206882) (xy 346.754561 -238.240974) (xy 346.714058 -238.26893) (xy 346.669596 -238.290028)
			(xy 346.622325 -238.30372) (xy 346.57347 -238.309652) (xy 346.524295 -238.307671) (xy 346.476076 -238.297827)
			(xy 346.43006 -238.280375) (xy 346.387439 -238.255768) (xy 346.349318 -238.224643) (xy 346.316683 -238.187806)
			(xy 346.29038 -238.14621) (xy 346.271089 -238.100934) (xy 346.259312 -238.05315) (xy 346.255352 -238.004096)
			(xy 345.92641 -238.004096) (xy 345.925915 -238.028703) (xy 345.91802 -238.07728) (xy 345.902436 -238.123961)
			(xy 345.879565 -238.167538) (xy 345.85 -238.206882) (xy 345.814507 -238.240974) (xy 345.774004 -238.26893)
			(xy 345.729542 -238.290028) (xy 345.682271 -238.30372) (xy 345.633416 -238.309652) (xy 345.584241 -238.307671)
			(xy 345.536022 -238.297827) (xy 345.490006 -238.280375) (xy 345.447385 -238.255768) (xy 345.409264 -238.224643)
			(xy 345.376629 -238.187806) (xy 345.350326 -238.14621) (xy 345.331035 -238.100934) (xy 345.319258 -238.05315)
			(xy 345.315298 -238.004096) (xy 344.986925 -238.004096) (xy 344.986925 -238.0041) (xy 344.98301 -238.052889)
			(xy 344.971364 -238.100429) (xy 344.952285 -238.145503) (xy 344.926262 -238.186957) (xy 344.893961 -238.223731)
			(xy 344.856208 -238.254883) (xy 344.813971 -238.279616) (xy 344.76833 -238.297296) (xy 344.720454 -238.30747)
			(xy 344.696034 -238.30915) (xy 344.686636 -238.309404) (xy 344.669618 -238.317024) (xy 344.641424 -238.34471)
			(xy 344.634602 -238.351973) (xy 344.626857 -238.370315) (xy 344.626438 -238.38027) (xy 344.626438 -238.814102)
			(xy 346.725252 -238.814102) (xy 346.729212 -238.765048) (xy 346.740989 -238.717264) (xy 346.76028 -238.671988)
			(xy 346.786583 -238.630392) (xy 346.819218 -238.593555) (xy 346.857339 -238.56243) (xy 346.89996 -238.537823)
			(xy 346.945976 -238.520371) (xy 346.994195 -238.510527) (xy 347.04337 -238.508546) (xy 347.092225 -238.514478)
			(xy 347.139496 -238.52817) (xy 347.183958 -238.549268) (xy 347.224461 -238.577224) (xy 347.259954 -238.611316)
			(xy 347.289519 -238.65066) (xy 347.31239 -238.694237) (xy 347.327974 -238.740918) (xy 347.335869 -238.789495)
			(xy 347.336364 -238.814102) (xy 349.545414 -238.814102) (xy 349.549374 -238.765048) (xy 349.561151 -238.717264)
			(xy 349.580442 -238.671988) (xy 349.606745 -238.630392) (xy 349.63938 -238.593555) (xy 349.677501 -238.56243)
			(xy 349.720122 -238.537823) (xy 349.766138 -238.520371) (xy 349.814357 -238.510527) (xy 349.863532 -238.508546)
			(xy 349.912387 -238.514478) (xy 349.959658 -238.52817) (xy 350.00412 -238.549268) (xy 350.044623 -238.577224)
			(xy 350.080116 -238.611316) (xy 350.109681 -238.65066) (xy 350.132552 -238.694237) (xy 350.148136 -238.740918)
			(xy 350.156031 -238.789495) (xy 350.156526 -238.814102) (xy 352.365322 -238.814102) (xy 352.369282 -238.765048)
			(xy 352.381059 -238.717264) (xy 352.40035 -238.671988) (xy 352.426653 -238.630392) (xy 352.459288 -238.593555)
			(xy 352.497409 -238.56243) (xy 352.54003 -238.537823) (xy 352.586046 -238.520371) (xy 352.634265 -238.510527)
			(xy 352.68344 -238.508546) (xy 352.732295 -238.514478) (xy 352.779566 -238.52817) (xy 352.824028 -238.549268)
			(xy 352.864531 -238.577224) (xy 352.900024 -238.611316) (xy 352.929589 -238.65066) (xy 352.95246 -238.694237)
			(xy 352.968044 -238.740918) (xy 352.975939 -238.789495) (xy 352.976434 -238.814102) (xy 355.18523 -238.814102)
			(xy 355.18919 -238.765048) (xy 355.200967 -238.717264) (xy 355.220258 -238.671988) (xy 355.246561 -238.630392)
			(xy 355.279196 -238.593555) (xy 355.317317 -238.56243) (xy 355.359938 -238.537823) (xy 355.405954 -238.520371)
			(xy 355.454173 -238.510527) (xy 355.503348 -238.508546) (xy 355.552203 -238.514478) (xy 355.599474 -238.52817)
			(xy 355.643936 -238.549268) (xy 355.684439 -238.577224) (xy 355.719932 -238.611316) (xy 355.749497 -238.65066)
			(xy 355.772368 -238.694237) (xy 355.787952 -238.740918) (xy 355.795847 -238.789495) (xy 355.796342 -238.814102)
			(xy 356.125284 -238.814102) (xy 356.129244 -238.765048) (xy 356.141021 -238.717264) (xy 356.160312 -238.671988)
			(xy 356.186615 -238.630392) (xy 356.21925 -238.593555) (xy 356.257371 -238.56243) (xy 356.299992 -238.537823)
			(xy 356.346008 -238.520371) (xy 356.394227 -238.510527) (xy 356.443402 -238.508546) (xy 356.492257 -238.514478)
			(xy 356.539528 -238.52817) (xy 356.58399 -238.549268) (xy 356.624493 -238.577224) (xy 356.659986 -238.611316)
			(xy 356.689551 -238.65066) (xy 356.712422 -238.694237) (xy 356.728006 -238.740918) (xy 356.735901 -238.789495)
			(xy 356.736396 -238.814102) (xy 357.065338 -238.814102) (xy 357.069298 -238.765048) (xy 357.081075 -238.717264)
			(xy 357.100366 -238.671988) (xy 357.126669 -238.630392) (xy 357.159304 -238.593555) (xy 357.197425 -238.56243)
			(xy 357.240046 -238.537823) (xy 357.286062 -238.520371) (xy 357.334281 -238.510527) (xy 357.383456 -238.508546)
			(xy 357.432311 -238.514478) (xy 357.479582 -238.52817) (xy 357.524044 -238.549268) (xy 357.564547 -238.577224)
			(xy 357.60004 -238.611316) (xy 357.629605 -238.65066) (xy 357.652476 -238.694237) (xy 357.66806 -238.740918)
			(xy 357.675955 -238.789495) (xy 357.67645 -238.814102) (xy 358.005392 -238.814102) (xy 358.009352 -238.765048)
			(xy 358.021129 -238.717264) (xy 358.04042 -238.671988) (xy 358.066723 -238.630392) (xy 358.099358 -238.593555)
			(xy 358.137479 -238.56243) (xy 358.1801 -238.537823) (xy 358.226116 -238.520371) (xy 358.274335 -238.510527)
			(xy 358.32351 -238.508546) (xy 358.372365 -238.514478) (xy 358.419636 -238.52817) (xy 358.464098 -238.549268)
			(xy 358.504601 -238.577224) (xy 358.540094 -238.611316) (xy 358.569659 -238.65066) (xy 358.59253 -238.694237)
			(xy 358.608114 -238.740918) (xy 358.616009 -238.789495) (xy 358.616504 -238.814102) (xy 360.81895 -238.814102)
			(xy 360.82291 -238.765048) (xy 360.834687 -238.717264) (xy 360.853978 -238.671988) (xy 360.880281 -238.630392)
			(xy 360.912916 -238.593555) (xy 360.951037 -238.56243) (xy 360.993658 -238.537823) (xy 361.039674 -238.520371)
			(xy 361.087893 -238.510527) (xy 361.137068 -238.508546) (xy 361.185923 -238.514478) (xy 361.233194 -238.52817)
			(xy 361.277656 -238.549268) (xy 361.318159 -238.577224) (xy 361.353652 -238.611316) (xy 361.383217 -238.65066)
			(xy 361.406088 -238.694237) (xy 361.421672 -238.740918) (xy 361.429567 -238.789495) (xy 361.430062 -238.814102)
			(xy 361.759004 -238.814102) (xy 361.762964 -238.765048) (xy 361.774741 -238.717264) (xy 361.794032 -238.671988)
			(xy 361.820335 -238.630392) (xy 361.85297 -238.593555) (xy 361.891091 -238.56243) (xy 361.933712 -238.537823)
			(xy 361.979728 -238.520371) (xy 362.027947 -238.510527) (xy 362.077122 -238.508546) (xy 362.125977 -238.514478)
			(xy 362.173248 -238.52817) (xy 362.21771 -238.549268) (xy 362.258213 -238.577224) (xy 362.293706 -238.611316)
			(xy 362.323271 -238.65066) (xy 362.346142 -238.694237) (xy 362.361726 -238.740918) (xy 362.369621 -238.789495)
			(xy 362.370116 -238.814102) (xy 362.699058 -238.814102) (xy 362.703018 -238.765048) (xy 362.714795 -238.717264)
			(xy 362.734086 -238.671988) (xy 362.760389 -238.630392) (xy 362.793024 -238.593555) (xy 362.831145 -238.56243)
			(xy 362.873766 -238.537823) (xy 362.919782 -238.520371) (xy 362.968001 -238.510527) (xy 363.017176 -238.508546)
			(xy 363.066031 -238.514478) (xy 363.113302 -238.52817) (xy 363.157764 -238.549268) (xy 363.198267 -238.577224)
			(xy 363.23376 -238.611316) (xy 363.263325 -238.65066) (xy 363.286196 -238.694237) (xy 363.30178 -238.740918)
			(xy 363.309675 -238.789495) (xy 363.31017 -238.814102) (xy 363.639112 -238.814102) (xy 363.643072 -238.765048)
			(xy 363.654849 -238.717264) (xy 363.67414 -238.671988) (xy 363.700443 -238.630392) (xy 363.733078 -238.593555)
			(xy 363.771199 -238.56243) (xy 363.81382 -238.537823) (xy 363.859836 -238.520371) (xy 363.908055 -238.510527)
			(xy 363.95723 -238.508546) (xy 364.006085 -238.514478) (xy 364.053356 -238.52817) (xy 364.097818 -238.549268)
			(xy 364.138321 -238.577224) (xy 364.173814 -238.611316) (xy 364.203379 -238.65066) (xy 364.22625 -238.694237)
			(xy 364.241834 -238.740918) (xy 364.249729 -238.789495) (xy 364.250224 -238.814102) (xy 366.45902 -238.814102)
			(xy 366.46298 -238.765048) (xy 366.474757 -238.717264) (xy 366.494048 -238.671988) (xy 366.520351 -238.630392)
			(xy 366.552986 -238.593555) (xy 366.591107 -238.56243) (xy 366.633728 -238.537823) (xy 366.679744 -238.520371)
			(xy 366.727963 -238.510527) (xy 366.777138 -238.508546) (xy 366.825993 -238.514478) (xy 366.873264 -238.52817)
			(xy 366.917726 -238.549268) (xy 366.958229 -238.577224) (xy 366.993722 -238.611316) (xy 367.023287 -238.65066)
			(xy 367.046158 -238.694237) (xy 367.061742 -238.740918) (xy 367.069637 -238.789495) (xy 367.070132 -238.814102)
			(xy 369.278928 -238.814102) (xy 369.282888 -238.765048) (xy 369.294665 -238.717264) (xy 369.313956 -238.671988)
			(xy 369.340259 -238.630392) (xy 369.372894 -238.593555) (xy 369.411015 -238.56243) (xy 369.453636 -238.537823)
			(xy 369.499652 -238.520371) (xy 369.547871 -238.510527) (xy 369.597046 -238.508546) (xy 369.645901 -238.514478)
			(xy 369.693172 -238.52817) (xy 369.737634 -238.549268) (xy 369.778137 -238.577224) (xy 369.81363 -238.611316)
			(xy 369.843195 -238.65066) (xy 369.866066 -238.694237) (xy 369.88165 -238.740918) (xy 369.889545 -238.789495)
			(xy 369.89004 -238.814102) (xy 372.09909 -238.814102) (xy 372.10305 -238.765048) (xy 372.114827 -238.717264)
			(xy 372.134118 -238.671988) (xy 372.160421 -238.630392) (xy 372.193056 -238.593555) (xy 372.231177 -238.56243)
			(xy 372.273798 -238.537823) (xy 372.319814 -238.520371) (xy 372.368033 -238.510527) (xy 372.417208 -238.508546)
			(xy 372.466063 -238.514478) (xy 372.513334 -238.52817) (xy 372.557796 -238.549268) (xy 372.598299 -238.577224)
			(xy 372.633792 -238.611316) (xy 372.663357 -238.65066) (xy 372.686228 -238.694237) (xy 372.701812 -238.740918)
			(xy 372.709707 -238.789495) (xy 372.710202 -238.814102) (xy 372.709707 -238.838709) (xy 372.701812 -238.887286)
			(xy 372.686228 -238.933967) (xy 372.663357 -238.977544) (xy 372.633792 -239.016888) (xy 372.598299 -239.05098)
			(xy 372.557796 -239.078936) (xy 372.513334 -239.100034) (xy 372.466063 -239.113726) (xy 372.417208 -239.119658)
			(xy 372.368033 -239.117677) (xy 372.319814 -239.107833) (xy 372.273798 -239.090381) (xy 372.231177 -239.065774)
			(xy 372.193056 -239.034649) (xy 372.160421 -238.997812) (xy 372.134118 -238.956216) (xy 372.114827 -238.91094)
			(xy 372.10305 -238.863156) (xy 372.09909 -238.814102) (xy 369.89004 -238.814102) (xy 369.889545 -238.838709)
			(xy 369.88165 -238.887286) (xy 369.866066 -238.933967) (xy 369.843195 -238.977544) (xy 369.81363 -239.016888)
			(xy 369.778137 -239.05098) (xy 369.737634 -239.078936) (xy 369.693172 -239.100034) (xy 369.645901 -239.113726)
			(xy 369.597046 -239.119658) (xy 369.547871 -239.117677) (xy 369.499652 -239.107833) (xy 369.453636 -239.090381)
			(xy 369.411015 -239.065774) (xy 369.372894 -239.034649) (xy 369.340259 -238.997812) (xy 369.313956 -238.956216)
			(xy 369.294665 -238.91094) (xy 369.282888 -238.863156) (xy 369.278928 -238.814102) (xy 367.070132 -238.814102)
			(xy 367.069637 -238.838709) (xy 367.061742 -238.887286) (xy 367.046158 -238.933967) (xy 367.023287 -238.977544)
			(xy 366.993722 -239.016888) (xy 366.958229 -239.05098) (xy 366.917726 -239.078936) (xy 366.873264 -239.100034)
			(xy 366.825993 -239.113726) (xy 366.777138 -239.119658) (xy 366.727963 -239.117677) (xy 366.679744 -239.107833)
			(xy 366.633728 -239.090381) (xy 366.591107 -239.065774) (xy 366.552986 -239.034649) (xy 366.520351 -238.997812)
			(xy 366.494048 -238.956216) (xy 366.474757 -238.91094) (xy 366.46298 -238.863156) (xy 366.45902 -238.814102)
			(xy 364.250224 -238.814102) (xy 364.249729 -238.838709) (xy 364.241834 -238.887286) (xy 364.22625 -238.933967)
			(xy 364.203379 -238.977544) (xy 364.173814 -239.016888) (xy 364.138321 -239.05098) (xy 364.097818 -239.078936)
			(xy 364.053356 -239.100034) (xy 364.006085 -239.113726) (xy 363.95723 -239.119658) (xy 363.908055 -239.117677)
			(xy 363.859836 -239.107833) (xy 363.81382 -239.090381) (xy 363.771199 -239.065774) (xy 363.733078 -239.034649)
			(xy 363.700443 -238.997812) (xy 363.67414 -238.956216) (xy 363.654849 -238.91094) (xy 363.643072 -238.863156)
			(xy 363.639112 -238.814102) (xy 363.31017 -238.814102) (xy 363.309675 -238.838709) (xy 363.30178 -238.887286)
			(xy 363.286196 -238.933967) (xy 363.263325 -238.977544) (xy 363.23376 -239.016888) (xy 363.198267 -239.05098)
			(xy 363.157764 -239.078936) (xy 363.113302 -239.100034) (xy 363.066031 -239.113726) (xy 363.017176 -239.119658)
			(xy 362.968001 -239.117677) (xy 362.919782 -239.107833) (xy 362.873766 -239.090381) (xy 362.831145 -239.065774)
			(xy 362.793024 -239.034649) (xy 362.760389 -238.997812) (xy 362.734086 -238.956216) (xy 362.714795 -238.91094)
			(xy 362.703018 -238.863156) (xy 362.699058 -238.814102) (xy 362.370116 -238.814102) (xy 362.369621 -238.838709)
			(xy 362.361726 -238.887286) (xy 362.346142 -238.933967) (xy 362.323271 -238.977544) (xy 362.293706 -239.016888)
			(xy 362.258213 -239.05098) (xy 362.21771 -239.078936) (xy 362.173248 -239.100034) (xy 362.125977 -239.113726)
			(xy 362.077122 -239.119658) (xy 362.027947 -239.117677) (xy 361.979728 -239.107833) (xy 361.933712 -239.090381)
			(xy 361.891091 -239.065774) (xy 361.85297 -239.034649) (xy 361.820335 -238.997812) (xy 361.794032 -238.956216)
			(xy 361.774741 -238.91094) (xy 361.762964 -238.863156) (xy 361.759004 -238.814102) (xy 361.430062 -238.814102)
			(xy 361.429567 -238.838709) (xy 361.421672 -238.887286) (xy 361.406088 -238.933967) (xy 361.383217 -238.977544)
			(xy 361.353652 -239.016888) (xy 361.318159 -239.05098) (xy 361.277656 -239.078936) (xy 361.233194 -239.100034)
			(xy 361.185923 -239.113726) (xy 361.137068 -239.119658) (xy 361.087893 -239.117677) (xy 361.039674 -239.107833)
			(xy 360.993658 -239.090381) (xy 360.951037 -239.065774) (xy 360.912916 -239.034649) (xy 360.880281 -238.997812)
			(xy 360.853978 -238.956216) (xy 360.834687 -238.91094) (xy 360.82291 -238.863156) (xy 360.81895 -238.814102)
			(xy 358.616504 -238.814102) (xy 358.616009 -238.838709) (xy 358.608114 -238.887286) (xy 358.59253 -238.933967)
			(xy 358.569659 -238.977544) (xy 358.540094 -239.016888) (xy 358.504601 -239.05098) (xy 358.464098 -239.078936)
			(xy 358.419636 -239.100034) (xy 358.372365 -239.113726) (xy 358.32351 -239.119658) (xy 358.274335 -239.117677)
			(xy 358.226116 -239.107833) (xy 358.1801 -239.090381) (xy 358.137479 -239.065774) (xy 358.099358 -239.034649)
			(xy 358.066723 -238.997812) (xy 358.04042 -238.956216) (xy 358.021129 -238.91094) (xy 358.009352 -238.863156)
			(xy 358.005392 -238.814102) (xy 357.67645 -238.814102) (xy 357.675955 -238.838709) (xy 357.66806 -238.887286)
			(xy 357.652476 -238.933967) (xy 357.629605 -238.977544) (xy 357.60004 -239.016888) (xy 357.564547 -239.05098)
			(xy 357.524044 -239.078936) (xy 357.479582 -239.100034) (xy 357.432311 -239.113726) (xy 357.383456 -239.119658)
			(xy 357.334281 -239.117677) (xy 357.286062 -239.107833) (xy 357.240046 -239.090381) (xy 357.197425 -239.065774)
			(xy 357.159304 -239.034649) (xy 357.126669 -238.997812) (xy 357.100366 -238.956216) (xy 357.081075 -238.91094)
			(xy 357.069298 -238.863156) (xy 357.065338 -238.814102) (xy 356.736396 -238.814102) (xy 356.735901 -238.838709)
			(xy 356.728006 -238.887286) (xy 356.712422 -238.933967) (xy 356.689551 -238.977544) (xy 356.659986 -239.016888)
			(xy 356.624493 -239.05098) (xy 356.58399 -239.078936) (xy 356.539528 -239.100034) (xy 356.492257 -239.113726)
			(xy 356.443402 -239.119658) (xy 356.394227 -239.117677) (xy 356.346008 -239.107833) (xy 356.299992 -239.090381)
			(xy 356.257371 -239.065774) (xy 356.21925 -239.034649) (xy 356.186615 -238.997812) (xy 356.160312 -238.956216)
			(xy 356.141021 -238.91094) (xy 356.129244 -238.863156) (xy 356.125284 -238.814102) (xy 355.796342 -238.814102)
			(xy 355.795847 -238.838709) (xy 355.787952 -238.887286) (xy 355.772368 -238.933967) (xy 355.749497 -238.977544)
			(xy 355.719932 -239.016888) (xy 355.684439 -239.05098) (xy 355.643936 -239.078936) (xy 355.599474 -239.100034)
			(xy 355.552203 -239.113726) (xy 355.503348 -239.119658) (xy 355.454173 -239.117677) (xy 355.405954 -239.107833)
			(xy 355.359938 -239.090381) (xy 355.317317 -239.065774) (xy 355.279196 -239.034649) (xy 355.246561 -238.997812)
			(xy 355.220258 -238.956216) (xy 355.200967 -238.91094) (xy 355.18919 -238.863156) (xy 355.18523 -238.814102)
			(xy 352.976434 -238.814102) (xy 352.975939 -238.838709) (xy 352.968044 -238.887286) (xy 352.95246 -238.933967)
			(xy 352.929589 -238.977544) (xy 352.900024 -239.016888) (xy 352.864531 -239.05098) (xy 352.824028 -239.078936)
			(xy 352.779566 -239.100034) (xy 352.732295 -239.113726) (xy 352.68344 -239.119658) (xy 352.634265 -239.117677)
			(xy 352.586046 -239.107833) (xy 352.54003 -239.090381) (xy 352.497409 -239.065774) (xy 352.459288 -239.034649)
			(xy 352.426653 -238.997812) (xy 352.40035 -238.956216) (xy 352.381059 -238.91094) (xy 352.369282 -238.863156)
			(xy 352.365322 -238.814102) (xy 350.156526 -238.814102) (xy 350.156031 -238.838709) (xy 350.148136 -238.887286)
			(xy 350.132552 -238.933967) (xy 350.109681 -238.977544) (xy 350.080116 -239.016888) (xy 350.044623 -239.05098)
			(xy 350.00412 -239.078936) (xy 349.959658 -239.100034) (xy 349.912387 -239.113726) (xy 349.863532 -239.119658)
			(xy 349.814357 -239.117677) (xy 349.766138 -239.107833) (xy 349.720122 -239.090381) (xy 349.677501 -239.065774)
			(xy 349.63938 -239.034649) (xy 349.606745 -238.997812) (xy 349.580442 -238.956216) (xy 349.561151 -238.91094)
			(xy 349.549374 -238.863156) (xy 349.545414 -238.814102) (xy 347.336364 -238.814102) (xy 347.335869 -238.838709)
			(xy 347.327974 -238.887286) (xy 347.31239 -238.933967) (xy 347.289519 -238.977544) (xy 347.259954 -239.016888)
			(xy 347.224461 -239.05098) (xy 347.183958 -239.078936) (xy 347.139496 -239.100034) (xy 347.092225 -239.113726)
			(xy 347.04337 -239.119658) (xy 346.994195 -239.117677) (xy 346.945976 -239.107833) (xy 346.89996 -239.090381)
			(xy 346.857339 -239.065774) (xy 346.819218 -239.034649) (xy 346.786583 -238.997812) (xy 346.76028 -238.956216)
			(xy 346.740989 -238.91094) (xy 346.729212 -238.863156) (xy 346.725252 -238.814102) (xy 344.626438 -238.814102)
			(xy 344.626438 -239.247426) (xy 344.626884 -239.257582) (xy 344.634744 -239.276313) (xy 344.641678 -239.283748)
			(xy 344.669618 -239.31118) (xy 344.686636 -239.3188) (xy 344.696034 -239.319054) (xy 344.720452 -239.320741)
			(xy 344.768327 -239.330916) (xy 344.813966 -239.348595) (xy 344.856202 -239.373327) (xy 344.893953 -239.404477)
			(xy 344.926252 -239.44125) (xy 344.952274 -239.482703) (xy 344.971352 -239.527775) (xy 344.982998 -239.575313)
			(xy 344.986913 -239.6241) (xy 344.986912 -239.624108) (xy 345.315298 -239.624108) (xy 345.319258 -239.575054)
			(xy 345.331035 -239.52727) (xy 345.350326 -239.481994) (xy 345.376629 -239.440398) (xy 345.409264 -239.403561)
			(xy 345.447385 -239.372436) (xy 345.490006 -239.347829) (xy 345.536022 -239.330377) (xy 345.584241 -239.320533)
			(xy 345.633416 -239.318552) (xy 345.682271 -239.324484) (xy 345.729542 -239.338176) (xy 345.774004 -239.359274)
			(xy 345.814507 -239.38723) (xy 345.85 -239.421322) (xy 345.879565 -239.460666) (xy 345.902436 -239.504243)
			(xy 345.91802 -239.550924) (xy 345.925915 -239.599501) (xy 345.92641 -239.624108) (xy 346.255352 -239.624108)
			(xy 346.259312 -239.575054) (xy 346.271089 -239.52727) (xy 346.29038 -239.481994) (xy 346.316683 -239.440398)
			(xy 346.349318 -239.403561) (xy 346.387439 -239.372436) (xy 346.43006 -239.347829) (xy 346.476076 -239.330377)
			(xy 346.524295 -239.320533) (xy 346.57347 -239.318552) (xy 346.622325 -239.324484) (xy 346.669596 -239.338176)
			(xy 346.714058 -239.359274) (xy 346.754561 -239.38723) (xy 346.790054 -239.421322) (xy 346.819619 -239.460666)
			(xy 346.84249 -239.504243) (xy 346.858074 -239.550924) (xy 346.865969 -239.599501) (xy 346.866464 -239.624108)
			(xy 347.195406 -239.624108) (xy 347.199366 -239.575054) (xy 347.211143 -239.52727) (xy 347.230434 -239.481994)
			(xy 347.256737 -239.440398) (xy 347.289372 -239.403561) (xy 347.327493 -239.372436) (xy 347.370114 -239.347829)
			(xy 347.41613 -239.330377) (xy 347.464349 -239.320533) (xy 347.513524 -239.318552) (xy 347.562379 -239.324484)
			(xy 347.60965 -239.338176) (xy 347.654112 -239.359274) (xy 347.694615 -239.38723) (xy 347.730108 -239.421322)
			(xy 347.759673 -239.460666) (xy 347.782544 -239.504243) (xy 347.798128 -239.550924) (xy 347.806023 -239.599501)
			(xy 347.806518 -239.624108) (xy 348.135206 -239.624108) (xy 348.139166 -239.575054) (xy 348.150943 -239.52727)
			(xy 348.170234 -239.481994) (xy 348.196537 -239.440398) (xy 348.229172 -239.403561) (xy 348.267293 -239.372436)
			(xy 348.309914 -239.347829) (xy 348.35593 -239.330377) (xy 348.404149 -239.320533) (xy 348.453324 -239.318552)
			(xy 348.502179 -239.324484) (xy 348.54945 -239.338176) (xy 348.593912 -239.359274) (xy 348.634415 -239.38723)
			(xy 348.669908 -239.421322) (xy 348.699473 -239.460666) (xy 348.722344 -239.504243) (xy 348.737928 -239.550924)
			(xy 348.745823 -239.599501) (xy 348.746318 -239.624108) (xy 349.07526 -239.624108) (xy 349.07922 -239.575054)
			(xy 349.090997 -239.52727) (xy 349.110288 -239.481994) (xy 349.136591 -239.440398) (xy 349.169226 -239.403561)
			(xy 349.207347 -239.372436) (xy 349.249968 -239.347829) (xy 349.295984 -239.330377) (xy 349.344203 -239.320533)
			(xy 349.393378 -239.318552) (xy 349.442233 -239.324484) (xy 349.489504 -239.338176) (xy 349.533966 -239.359274)
			(xy 349.574469 -239.38723) (xy 349.609962 -239.421322) (xy 349.639527 -239.460666) (xy 349.662398 -239.504243)
			(xy 349.677982 -239.550924) (xy 349.685877 -239.599501) (xy 349.686372 -239.624108) (xy 350.015314 -239.624108)
			(xy 350.019274 -239.575054) (xy 350.031051 -239.52727) (xy 350.050342 -239.481994) (xy 350.076645 -239.440398)
			(xy 350.10928 -239.403561) (xy 350.147401 -239.372436) (xy 350.190022 -239.347829) (xy 350.236038 -239.330377)
			(xy 350.284257 -239.320533) (xy 350.333432 -239.318552) (xy 350.382287 -239.324484) (xy 350.429558 -239.338176)
			(xy 350.47402 -239.359274) (xy 350.514523 -239.38723) (xy 350.550016 -239.421322) (xy 350.579581 -239.460666)
			(xy 350.602452 -239.504243) (xy 350.618036 -239.550924) (xy 350.625931 -239.599501) (xy 350.626426 -239.624108)
			(xy 350.955368 -239.624108) (xy 350.959328 -239.575054) (xy 350.971105 -239.52727) (xy 350.990396 -239.481994)
			(xy 351.016699 -239.440398) (xy 351.049334 -239.403561) (xy 351.087455 -239.372436) (xy 351.130076 -239.347829)
			(xy 351.176092 -239.330377) (xy 351.224311 -239.320533) (xy 351.273486 -239.318552) (xy 351.322341 -239.324484)
			(xy 351.369612 -239.338176) (xy 351.414074 -239.359274) (xy 351.454577 -239.38723) (xy 351.49007 -239.421322)
			(xy 351.519635 -239.460666) (xy 351.542506 -239.504243) (xy 351.55809 -239.550924) (xy 351.565985 -239.599501)
			(xy 351.56648 -239.624108) (xy 351.895422 -239.624108) (xy 351.899382 -239.575054) (xy 351.911159 -239.52727)
			(xy 351.93045 -239.481994) (xy 351.956753 -239.440398) (xy 351.989388 -239.403561) (xy 352.027509 -239.372436)
			(xy 352.07013 -239.347829) (xy 352.116146 -239.330377) (xy 352.164365 -239.320533) (xy 352.21354 -239.318552)
			(xy 352.262395 -239.324484) (xy 352.309666 -239.338176) (xy 352.354128 -239.359274) (xy 352.394631 -239.38723)
			(xy 352.430124 -239.421322) (xy 352.459689 -239.460666) (xy 352.48256 -239.504243) (xy 352.498144 -239.550924)
			(xy 352.506039 -239.599501) (xy 352.506534 -239.624108) (xy 352.835222 -239.624108) (xy 352.839182 -239.575054)
			(xy 352.850959 -239.52727) (xy 352.87025 -239.481994) (xy 352.896553 -239.440398) (xy 352.929188 -239.403561)
			(xy 352.967309 -239.372436) (xy 353.00993 -239.347829) (xy 353.055946 -239.330377) (xy 353.104165 -239.320533)
			(xy 353.15334 -239.318552) (xy 353.202195 -239.324484) (xy 353.249466 -239.338176) (xy 353.293928 -239.359274)
			(xy 353.334431 -239.38723) (xy 353.369924 -239.421322) (xy 353.399489 -239.460666) (xy 353.42236 -239.504243)
			(xy 353.437944 -239.550924) (xy 353.445839 -239.599501) (xy 353.446334 -239.624108) (xy 353.775276 -239.624108)
			(xy 353.779236 -239.575054) (xy 353.791013 -239.52727) (xy 353.810304 -239.481994) (xy 353.836607 -239.440398)
			(xy 353.869242 -239.403561) (xy 353.907363 -239.372436) (xy 353.949984 -239.347829) (xy 353.996 -239.330377)
			(xy 354.044219 -239.320533) (xy 354.093394 -239.318552) (xy 354.142249 -239.324484) (xy 354.18952 -239.338176)
			(xy 354.233982 -239.359274) (xy 354.274485 -239.38723) (xy 354.309978 -239.421322) (xy 354.339543 -239.460666)
			(xy 354.362414 -239.504243) (xy 354.377998 -239.550924) (xy 354.385893 -239.599501) (xy 354.386388 -239.624108)
			(xy 354.71533 -239.624108) (xy 354.71929 -239.575054) (xy 354.731067 -239.52727) (xy 354.750358 -239.481994)
			(xy 354.776661 -239.440398) (xy 354.809296 -239.403561) (xy 354.847417 -239.372436) (xy 354.890038 -239.347829)
			(xy 354.936054 -239.330377) (xy 354.984273 -239.320533) (xy 355.033448 -239.318552) (xy 355.082303 -239.324484)
			(xy 355.129574 -239.338176) (xy 355.174036 -239.359274) (xy 355.214539 -239.38723) (xy 355.250032 -239.421322)
			(xy 355.279597 -239.460666) (xy 355.302468 -239.504243) (xy 355.318052 -239.550924) (xy 355.325947 -239.599501)
			(xy 355.326442 -239.624108) (xy 355.655384 -239.624108) (xy 355.659344 -239.575054) (xy 355.671121 -239.52727)
			(xy 355.690412 -239.481994) (xy 355.716715 -239.440398) (xy 355.74935 -239.403561) (xy 355.787471 -239.372436)
			(xy 355.830092 -239.347829) (xy 355.876108 -239.330377) (xy 355.924327 -239.320533) (xy 355.973502 -239.318552)
			(xy 356.022357 -239.324484) (xy 356.069628 -239.338176) (xy 356.11409 -239.359274) (xy 356.154593 -239.38723)
			(xy 356.190086 -239.421322) (xy 356.219651 -239.460666) (xy 356.242522 -239.504243) (xy 356.258106 -239.550924)
			(xy 356.266001 -239.599501) (xy 356.266496 -239.624108) (xy 363.168958 -239.624108) (xy 363.172918 -239.575054)
			(xy 363.184695 -239.52727) (xy 363.203986 -239.481994) (xy 363.230289 -239.440398) (xy 363.262924 -239.403561)
			(xy 363.301045 -239.372436) (xy 363.343666 -239.347829) (xy 363.389682 -239.330377) (xy 363.437901 -239.320533)
			(xy 363.487076 -239.318552) (xy 363.535931 -239.324484) (xy 363.583202 -239.338176) (xy 363.627664 -239.359274)
			(xy 363.668167 -239.38723) (xy 363.70366 -239.421322) (xy 363.733225 -239.460666) (xy 363.756096 -239.504243)
			(xy 363.77168 -239.550924) (xy 363.779575 -239.599501) (xy 363.78007 -239.624108) (xy 364.109012 -239.624108)
			(xy 364.112972 -239.575054) (xy 364.124749 -239.52727) (xy 364.14404 -239.481994) (xy 364.170343 -239.440398)
			(xy 364.202978 -239.403561) (xy 364.241099 -239.372436) (xy 364.28372 -239.347829) (xy 364.329736 -239.330377)
			(xy 364.377955 -239.320533) (xy 364.42713 -239.318552) (xy 364.475985 -239.324484) (xy 364.523256 -239.338176)
			(xy 364.567718 -239.359274) (xy 364.608221 -239.38723) (xy 364.643714 -239.421322) (xy 364.673279 -239.460666)
			(xy 364.69615 -239.504243) (xy 364.711734 -239.550924) (xy 364.719629 -239.599501) (xy 364.720124 -239.624108)
			(xy 365.049066 -239.624108) (xy 365.053026 -239.575054) (xy 365.064803 -239.52727) (xy 365.084094 -239.481994)
			(xy 365.110397 -239.440398) (xy 365.143032 -239.403561) (xy 365.181153 -239.372436) (xy 365.223774 -239.347829)
			(xy 365.26979 -239.330377) (xy 365.318009 -239.320533) (xy 365.367184 -239.318552) (xy 365.416039 -239.324484)
			(xy 365.46331 -239.338176) (xy 365.507772 -239.359274) (xy 365.548275 -239.38723) (xy 365.583768 -239.421322)
			(xy 365.613333 -239.460666) (xy 365.636204 -239.504243) (xy 365.651788 -239.550924) (xy 365.659683 -239.599501)
			(xy 365.660178 -239.624108) (xy 365.98912 -239.624108) (xy 365.99308 -239.575054) (xy 366.004857 -239.52727)
			(xy 366.024148 -239.481994) (xy 366.050451 -239.440398) (xy 366.083086 -239.403561) (xy 366.121207 -239.372436)
			(xy 366.163828 -239.347829) (xy 366.209844 -239.330377) (xy 366.258063 -239.320533) (xy 366.307238 -239.318552)
			(xy 366.356093 -239.324484) (xy 366.403364 -239.338176) (xy 366.447826 -239.359274) (xy 366.488329 -239.38723)
			(xy 366.523822 -239.421322) (xy 366.553387 -239.460666) (xy 366.576258 -239.504243) (xy 366.591842 -239.550924)
			(xy 366.599737 -239.599501) (xy 366.600232 -239.624108) (xy 366.92892 -239.624108) (xy 366.93288 -239.575054)
			(xy 366.944657 -239.52727) (xy 366.963948 -239.481994) (xy 366.990251 -239.440398) (xy 367.022886 -239.403561)
			(xy 367.061007 -239.372436) (xy 367.103628 -239.347829) (xy 367.149644 -239.330377) (xy 367.197863 -239.320533)
			(xy 367.247038 -239.318552) (xy 367.295893 -239.324484) (xy 367.343164 -239.338176) (xy 367.387626 -239.359274)
			(xy 367.428129 -239.38723) (xy 367.463622 -239.421322) (xy 367.493187 -239.460666) (xy 367.516058 -239.504243)
			(xy 367.531642 -239.550924) (xy 367.539537 -239.599501) (xy 367.540032 -239.624108) (xy 367.868974 -239.624108)
			(xy 367.872934 -239.575054) (xy 367.884711 -239.52727) (xy 367.904002 -239.481994) (xy 367.930305 -239.440398)
			(xy 367.96294 -239.403561) (xy 368.001061 -239.372436) (xy 368.043682 -239.347829) (xy 368.089698 -239.330377)
			(xy 368.137917 -239.320533) (xy 368.187092 -239.318552) (xy 368.235947 -239.324484) (xy 368.283218 -239.338176)
			(xy 368.32768 -239.359274) (xy 368.368183 -239.38723) (xy 368.403676 -239.421322) (xy 368.433241 -239.460666)
			(xy 368.456112 -239.504243) (xy 368.471696 -239.550924) (xy 368.479591 -239.599501) (xy 368.480086 -239.624108)
			(xy 368.809028 -239.624108) (xy 368.812988 -239.575054) (xy 368.824765 -239.52727) (xy 368.844056 -239.481994)
			(xy 368.870359 -239.440398) (xy 368.902994 -239.403561) (xy 368.941115 -239.372436) (xy 368.983736 -239.347829)
			(xy 369.029752 -239.330377) (xy 369.077971 -239.320533) (xy 369.127146 -239.318552) (xy 369.176001 -239.324484)
			(xy 369.223272 -239.338176) (xy 369.267734 -239.359274) (xy 369.308237 -239.38723) (xy 369.34373 -239.421322)
			(xy 369.373295 -239.460666) (xy 369.396166 -239.504243) (xy 369.41175 -239.550924) (xy 369.419645 -239.599501)
			(xy 369.42014 -239.624108) (xy 369.749082 -239.624108) (xy 369.753042 -239.575054) (xy 369.764819 -239.52727)
			(xy 369.78411 -239.481994) (xy 369.810413 -239.440398) (xy 369.843048 -239.403561) (xy 369.881169 -239.372436)
			(xy 369.92379 -239.347829) (xy 369.969806 -239.330377) (xy 370.018025 -239.320533) (xy 370.0672 -239.318552)
			(xy 370.116055 -239.324484) (xy 370.163326 -239.338176) (xy 370.207788 -239.359274) (xy 370.248291 -239.38723)
			(xy 370.283784 -239.421322) (xy 370.313349 -239.460666) (xy 370.33622 -239.504243) (xy 370.351804 -239.550924)
			(xy 370.359699 -239.599501) (xy 370.360194 -239.624108) (xy 370.688882 -239.624108) (xy 370.692842 -239.575054)
			(xy 370.704619 -239.52727) (xy 370.72391 -239.481994) (xy 370.750213 -239.440398) (xy 370.782848 -239.403561)
			(xy 370.820969 -239.372436) (xy 370.86359 -239.347829) (xy 370.909606 -239.330377) (xy 370.957825 -239.320533)
			(xy 371.007 -239.318552) (xy 371.055855 -239.324484) (xy 371.103126 -239.338176) (xy 371.147588 -239.359274)
			(xy 371.188091 -239.38723) (xy 371.223584 -239.421322) (xy 371.253149 -239.460666) (xy 371.27602 -239.504243)
			(xy 371.291604 -239.550924) (xy 371.299499 -239.599501) (xy 371.299994 -239.624108) (xy 371.628936 -239.624108)
			(xy 371.632896 -239.575054) (xy 371.644673 -239.52727) (xy 371.663964 -239.481994) (xy 371.690267 -239.440398)
			(xy 371.722902 -239.403561) (xy 371.761023 -239.372436) (xy 371.803644 -239.347829) (xy 371.84966 -239.330377)
			(xy 371.897879 -239.320533) (xy 371.947054 -239.318552) (xy 371.995909 -239.324484) (xy 372.04318 -239.338176)
			(xy 372.087642 -239.359274) (xy 372.128145 -239.38723) (xy 372.163638 -239.421322) (xy 372.193203 -239.460666)
			(xy 372.216074 -239.504243) (xy 372.231658 -239.550924) (xy 372.239553 -239.599501) (xy 372.240048 -239.624108)
			(xy 372.56899 -239.624108) (xy 372.57295 -239.575054) (xy 372.584727 -239.52727) (xy 372.604018 -239.481994)
			(xy 372.630321 -239.440398) (xy 372.662956 -239.403561) (xy 372.701077 -239.372436) (xy 372.743698 -239.347829)
			(xy 372.789714 -239.330377) (xy 372.837933 -239.320533) (xy 372.887108 -239.318552) (xy 372.935963 -239.324484)
			(xy 372.983234 -239.338176) (xy 373.027696 -239.359274) (xy 373.068199 -239.38723) (xy 373.103692 -239.421322)
			(xy 373.133257 -239.460666) (xy 373.156128 -239.504243) (xy 373.171712 -239.550924) (xy 373.179607 -239.599501)
			(xy 373.180102 -239.624108) (xy 373.509044 -239.624108) (xy 373.513004 -239.575054) (xy 373.524781 -239.52727)
			(xy 373.544072 -239.481994) (xy 373.570375 -239.440398) (xy 373.60301 -239.403561) (xy 373.641131 -239.372436)
			(xy 373.683752 -239.347829) (xy 373.729768 -239.330377) (xy 373.777987 -239.320533) (xy 373.827162 -239.318552)
			(xy 373.876017 -239.324484) (xy 373.923288 -239.338176) (xy 373.96775 -239.359274) (xy 374.008253 -239.38723)
			(xy 374.043746 -239.421322) (xy 374.073311 -239.460666) (xy 374.096182 -239.504243) (xy 374.111766 -239.550924)
			(xy 374.119661 -239.599501) (xy 374.120156 -239.624108) (xy 374.119661 -239.648715) (xy 374.111766 -239.697292)
			(xy 374.096182 -239.743973) (xy 374.073311 -239.78755) (xy 374.043746 -239.826894) (xy 374.008253 -239.860986)
			(xy 373.96775 -239.888942) (xy 373.923288 -239.91004) (xy 373.876017 -239.923732) (xy 373.827162 -239.929664)
			(xy 373.777987 -239.927683) (xy 373.729768 -239.917839) (xy 373.683752 -239.900387) (xy 373.641131 -239.87578)
			(xy 373.60301 -239.844655) (xy 373.570375 -239.807818) (xy 373.544072 -239.766222) (xy 373.524781 -239.720946)
			(xy 373.513004 -239.673162) (xy 373.509044 -239.624108) (xy 373.180102 -239.624108) (xy 373.179607 -239.648715)
			(xy 373.171712 -239.697292) (xy 373.156128 -239.743973) (xy 373.133257 -239.78755) (xy 373.103692 -239.826894)
			(xy 373.068199 -239.860986) (xy 373.027696 -239.888942) (xy 372.983234 -239.91004) (xy 372.935963 -239.923732)
			(xy 372.887108 -239.929664) (xy 372.837933 -239.927683) (xy 372.789714 -239.917839) (xy 372.743698 -239.900387)
			(xy 372.701077 -239.87578) (xy 372.662956 -239.844655) (xy 372.630321 -239.807818) (xy 372.604018 -239.766222)
			(xy 372.584727 -239.720946) (xy 372.57295 -239.673162) (xy 372.56899 -239.624108) (xy 372.240048 -239.624108)
			(xy 372.239553 -239.648715) (xy 372.231658 -239.697292) (xy 372.216074 -239.743973) (xy 372.193203 -239.78755)
			(xy 372.163638 -239.826894) (xy 372.128145 -239.860986) (xy 372.087642 -239.888942) (xy 372.04318 -239.91004)
			(xy 371.995909 -239.923732) (xy 371.947054 -239.929664) (xy 371.897879 -239.927683) (xy 371.84966 -239.917839)
			(xy 371.803644 -239.900387) (xy 371.761023 -239.87578) (xy 371.722902 -239.844655) (xy 371.690267 -239.807818)
			(xy 371.663964 -239.766222) (xy 371.644673 -239.720946) (xy 371.632896 -239.673162) (xy 371.628936 -239.624108)
			(xy 371.299994 -239.624108) (xy 371.299499 -239.648715) (xy 371.291604 -239.697292) (xy 371.27602 -239.743973)
			(xy 371.253149 -239.78755) (xy 371.223584 -239.826894) (xy 371.188091 -239.860986) (xy 371.147588 -239.888942)
			(xy 371.103126 -239.91004) (xy 371.055855 -239.923732) (xy 371.007 -239.929664) (xy 370.957825 -239.927683)
			(xy 370.909606 -239.917839) (xy 370.86359 -239.900387) (xy 370.820969 -239.87578) (xy 370.782848 -239.844655)
			(xy 370.750213 -239.807818) (xy 370.72391 -239.766222) (xy 370.704619 -239.720946) (xy 370.692842 -239.673162)
			(xy 370.688882 -239.624108) (xy 370.360194 -239.624108) (xy 370.359699 -239.648715) (xy 370.351804 -239.697292)
			(xy 370.33622 -239.743973) (xy 370.313349 -239.78755) (xy 370.283784 -239.826894) (xy 370.248291 -239.860986)
			(xy 370.207788 -239.888942) (xy 370.163326 -239.91004) (xy 370.116055 -239.923732) (xy 370.0672 -239.929664)
			(xy 370.018025 -239.927683) (xy 369.969806 -239.917839) (xy 369.92379 -239.900387) (xy 369.881169 -239.87578)
			(xy 369.843048 -239.844655) (xy 369.810413 -239.807818) (xy 369.78411 -239.766222) (xy 369.764819 -239.720946)
			(xy 369.753042 -239.673162) (xy 369.749082 -239.624108) (xy 369.42014 -239.624108) (xy 369.419645 -239.648715)
			(xy 369.41175 -239.697292) (xy 369.396166 -239.743973) (xy 369.373295 -239.78755) (xy 369.34373 -239.826894)
			(xy 369.308237 -239.860986) (xy 369.267734 -239.888942) (xy 369.223272 -239.91004) (xy 369.176001 -239.923732)
			(xy 369.127146 -239.929664) (xy 369.077971 -239.927683) (xy 369.029752 -239.917839) (xy 368.983736 -239.900387)
			(xy 368.941115 -239.87578) (xy 368.902994 -239.844655) (xy 368.870359 -239.807818) (xy 368.844056 -239.766222)
			(xy 368.824765 -239.720946) (xy 368.812988 -239.673162) (xy 368.809028 -239.624108) (xy 368.480086 -239.624108)
			(xy 368.479591 -239.648715) (xy 368.471696 -239.697292) (xy 368.456112 -239.743973) (xy 368.433241 -239.78755)
			(xy 368.403676 -239.826894) (xy 368.368183 -239.860986) (xy 368.32768 -239.888942) (xy 368.283218 -239.91004)
			(xy 368.235947 -239.923732) (xy 368.187092 -239.929664) (xy 368.137917 -239.927683) (xy 368.089698 -239.917839)
			(xy 368.043682 -239.900387) (xy 368.001061 -239.87578) (xy 367.96294 -239.844655) (xy 367.930305 -239.807818)
			(xy 367.904002 -239.766222) (xy 367.884711 -239.720946) (xy 367.872934 -239.673162) (xy 367.868974 -239.624108)
			(xy 367.540032 -239.624108) (xy 367.539537 -239.648715) (xy 367.531642 -239.697292) (xy 367.516058 -239.743973)
			(xy 367.493187 -239.78755) (xy 367.463622 -239.826894) (xy 367.428129 -239.860986) (xy 367.387626 -239.888942)
			(xy 367.343164 -239.91004) (xy 367.295893 -239.923732) (xy 367.247038 -239.929664) (xy 367.197863 -239.927683)
			(xy 367.149644 -239.917839) (xy 367.103628 -239.900387) (xy 367.061007 -239.87578) (xy 367.022886 -239.844655)
			(xy 366.990251 -239.807818) (xy 366.963948 -239.766222) (xy 366.944657 -239.720946) (xy 366.93288 -239.673162)
			(xy 366.92892 -239.624108) (xy 366.600232 -239.624108) (xy 366.599737 -239.648715) (xy 366.591842 -239.697292)
			(xy 366.576258 -239.743973) (xy 366.553387 -239.78755) (xy 366.523822 -239.826894) (xy 366.488329 -239.860986)
			(xy 366.447826 -239.888942) (xy 366.403364 -239.91004) (xy 366.356093 -239.923732) (xy 366.307238 -239.929664)
			(xy 366.258063 -239.927683) (xy 366.209844 -239.917839) (xy 366.163828 -239.900387) (xy 366.121207 -239.87578)
			(xy 366.083086 -239.844655) (xy 366.050451 -239.807818) (xy 366.024148 -239.766222) (xy 366.004857 -239.720946)
			(xy 365.99308 -239.673162) (xy 365.98912 -239.624108) (xy 365.660178 -239.624108) (xy 365.659683 -239.648715)
			(xy 365.651788 -239.697292) (xy 365.636204 -239.743973) (xy 365.613333 -239.78755) (xy 365.583768 -239.826894)
			(xy 365.548275 -239.860986) (xy 365.507772 -239.888942) (xy 365.46331 -239.91004) (xy 365.416039 -239.923732)
			(xy 365.367184 -239.929664) (xy 365.318009 -239.927683) (xy 365.26979 -239.917839) (xy 365.223774 -239.900387)
			(xy 365.181153 -239.87578) (xy 365.143032 -239.844655) (xy 365.110397 -239.807818) (xy 365.084094 -239.766222)
			(xy 365.064803 -239.720946) (xy 365.053026 -239.673162) (xy 365.049066 -239.624108) (xy 364.720124 -239.624108)
			(xy 364.719629 -239.648715) (xy 364.711734 -239.697292) (xy 364.69615 -239.743973) (xy 364.673279 -239.78755)
			(xy 364.643714 -239.826894) (xy 364.608221 -239.860986) (xy 364.567718 -239.888942) (xy 364.523256 -239.91004)
			(xy 364.475985 -239.923732) (xy 364.42713 -239.929664) (xy 364.377955 -239.927683) (xy 364.329736 -239.917839)
			(xy 364.28372 -239.900387) (xy 364.241099 -239.87578) (xy 364.202978 -239.844655) (xy 364.170343 -239.807818)
			(xy 364.14404 -239.766222) (xy 364.124749 -239.720946) (xy 364.112972 -239.673162) (xy 364.109012 -239.624108)
			(xy 363.78007 -239.624108) (xy 363.779575 -239.648715) (xy 363.77168 -239.697292) (xy 363.756096 -239.743973)
			(xy 363.733225 -239.78755) (xy 363.70366 -239.826894) (xy 363.668167 -239.860986) (xy 363.627664 -239.888942)
			(xy 363.583202 -239.91004) (xy 363.535931 -239.923732) (xy 363.487076 -239.929664) (xy 363.437901 -239.927683)
			(xy 363.389682 -239.917839) (xy 363.343666 -239.900387) (xy 363.301045 -239.87578) (xy 363.262924 -239.844655)
			(xy 363.230289 -239.807818) (xy 363.203986 -239.766222) (xy 363.184695 -239.720946) (xy 363.172918 -239.673162)
			(xy 363.168958 -239.624108) (xy 356.266496 -239.624108) (xy 356.266001 -239.648715) (xy 356.258106 -239.697292)
			(xy 356.242522 -239.743973) (xy 356.219651 -239.78755) (xy 356.190086 -239.826894) (xy 356.154593 -239.860986)
			(xy 356.11409 -239.888942) (xy 356.069628 -239.91004) (xy 356.022357 -239.923732) (xy 355.973502 -239.929664)
			(xy 355.924327 -239.927683) (xy 355.876108 -239.917839) (xy 355.830092 -239.900387) (xy 355.787471 -239.87578)
			(xy 355.74935 -239.844655) (xy 355.716715 -239.807818) (xy 355.690412 -239.766222) (xy 355.671121 -239.720946)
			(xy 355.659344 -239.673162) (xy 355.655384 -239.624108) (xy 355.326442 -239.624108) (xy 355.325947 -239.648715)
			(xy 355.318052 -239.697292) (xy 355.302468 -239.743973) (xy 355.279597 -239.78755) (xy 355.250032 -239.826894)
			(xy 355.214539 -239.860986) (xy 355.174036 -239.888942) (xy 355.129574 -239.91004) (xy 355.082303 -239.923732)
			(xy 355.033448 -239.929664) (xy 354.984273 -239.927683) (xy 354.936054 -239.917839) (xy 354.890038 -239.900387)
			(xy 354.847417 -239.87578) (xy 354.809296 -239.844655) (xy 354.776661 -239.807818) (xy 354.750358 -239.766222)
			(xy 354.731067 -239.720946) (xy 354.71929 -239.673162) (xy 354.71533 -239.624108) (xy 354.386388 -239.624108)
			(xy 354.385893 -239.648715) (xy 354.377998 -239.697292) (xy 354.362414 -239.743973) (xy 354.339543 -239.78755)
			(xy 354.309978 -239.826894) (xy 354.274485 -239.860986) (xy 354.233982 -239.888942) (xy 354.18952 -239.91004)
			(xy 354.142249 -239.923732) (xy 354.093394 -239.929664) (xy 354.044219 -239.927683) (xy 353.996 -239.917839)
			(xy 353.949984 -239.900387) (xy 353.907363 -239.87578) (xy 353.869242 -239.844655) (xy 353.836607 -239.807818)
			(xy 353.810304 -239.766222) (xy 353.791013 -239.720946) (xy 353.779236 -239.673162) (xy 353.775276 -239.624108)
			(xy 353.446334 -239.624108) (xy 353.445839 -239.648715) (xy 353.437944 -239.697292) (xy 353.42236 -239.743973)
			(xy 353.399489 -239.78755) (xy 353.369924 -239.826894) (xy 353.334431 -239.860986) (xy 353.293928 -239.888942)
			(xy 353.249466 -239.91004) (xy 353.202195 -239.923732) (xy 353.15334 -239.929664) (xy 353.104165 -239.927683)
			(xy 353.055946 -239.917839) (xy 353.00993 -239.900387) (xy 352.967309 -239.87578) (xy 352.929188 -239.844655)
			(xy 352.896553 -239.807818) (xy 352.87025 -239.766222) (xy 352.850959 -239.720946) (xy 352.839182 -239.673162)
			(xy 352.835222 -239.624108) (xy 352.506534 -239.624108) (xy 352.506039 -239.648715) (xy 352.498144 -239.697292)
			(xy 352.48256 -239.743973) (xy 352.459689 -239.78755) (xy 352.430124 -239.826894) (xy 352.394631 -239.860986)
			(xy 352.354128 -239.888942) (xy 352.309666 -239.91004) (xy 352.262395 -239.923732) (xy 352.21354 -239.929664)
			(xy 352.164365 -239.927683) (xy 352.116146 -239.917839) (xy 352.07013 -239.900387) (xy 352.027509 -239.87578)
			(xy 351.989388 -239.844655) (xy 351.956753 -239.807818) (xy 351.93045 -239.766222) (xy 351.911159 -239.720946)
			(xy 351.899382 -239.673162) (xy 351.895422 -239.624108) (xy 351.56648 -239.624108) (xy 351.565985 -239.648715)
			(xy 351.55809 -239.697292) (xy 351.542506 -239.743973) (xy 351.519635 -239.78755) (xy 351.49007 -239.826894)
			(xy 351.454577 -239.860986) (xy 351.414074 -239.888942) (xy 351.369612 -239.91004) (xy 351.322341 -239.923732)
			(xy 351.273486 -239.929664) (xy 351.224311 -239.927683) (xy 351.176092 -239.917839) (xy 351.130076 -239.900387)
			(xy 351.087455 -239.87578) (xy 351.049334 -239.844655) (xy 351.016699 -239.807818) (xy 350.990396 -239.766222)
			(xy 350.971105 -239.720946) (xy 350.959328 -239.673162) (xy 350.955368 -239.624108) (xy 350.626426 -239.624108)
			(xy 350.625931 -239.648715) (xy 350.618036 -239.697292) (xy 350.602452 -239.743973) (xy 350.579581 -239.78755)
			(xy 350.550016 -239.826894) (xy 350.514523 -239.860986) (xy 350.47402 -239.888942) (xy 350.429558 -239.91004)
			(xy 350.382287 -239.923732) (xy 350.333432 -239.929664) (xy 350.284257 -239.927683) (xy 350.236038 -239.917839)
			(xy 350.190022 -239.900387) (xy 350.147401 -239.87578) (xy 350.10928 -239.844655) (xy 350.076645 -239.807818)
			(xy 350.050342 -239.766222) (xy 350.031051 -239.720946) (xy 350.019274 -239.673162) (xy 350.015314 -239.624108)
			(xy 349.686372 -239.624108) (xy 349.685877 -239.648715) (xy 349.677982 -239.697292) (xy 349.662398 -239.743973)
			(xy 349.639527 -239.78755) (xy 349.609962 -239.826894) (xy 349.574469 -239.860986) (xy 349.533966 -239.888942)
			(xy 349.489504 -239.91004) (xy 349.442233 -239.923732) (xy 349.393378 -239.929664) (xy 349.344203 -239.927683)
			(xy 349.295984 -239.917839) (xy 349.249968 -239.900387) (xy 349.207347 -239.87578) (xy 349.169226 -239.844655)
			(xy 349.136591 -239.807818) (xy 349.110288 -239.766222) (xy 349.090997 -239.720946) (xy 349.07922 -239.673162)
			(xy 349.07526 -239.624108) (xy 348.746318 -239.624108) (xy 348.745823 -239.648715) (xy 348.737928 -239.697292)
			(xy 348.722344 -239.743973) (xy 348.699473 -239.78755) (xy 348.669908 -239.826894) (xy 348.634415 -239.860986)
			(xy 348.593912 -239.888942) (xy 348.54945 -239.91004) (xy 348.502179 -239.923732) (xy 348.453324 -239.929664)
			(xy 348.404149 -239.927683) (xy 348.35593 -239.917839) (xy 348.309914 -239.900387) (xy 348.267293 -239.87578)
			(xy 348.229172 -239.844655) (xy 348.196537 -239.807818) (xy 348.170234 -239.766222) (xy 348.150943 -239.720946)
			(xy 348.139166 -239.673162) (xy 348.135206 -239.624108) (xy 347.806518 -239.624108) (xy 347.806023 -239.648715)
			(xy 347.798128 -239.697292) (xy 347.782544 -239.743973) (xy 347.759673 -239.78755) (xy 347.730108 -239.826894)
			(xy 347.694615 -239.860986) (xy 347.654112 -239.888942) (xy 347.60965 -239.91004) (xy 347.562379 -239.923732)
			(xy 347.513524 -239.929664) (xy 347.464349 -239.927683) (xy 347.41613 -239.917839) (xy 347.370114 -239.900387)
			(xy 347.327493 -239.87578) (xy 347.289372 -239.844655) (xy 347.256737 -239.807818) (xy 347.230434 -239.766222)
			(xy 347.211143 -239.720946) (xy 347.199366 -239.673162) (xy 347.195406 -239.624108) (xy 346.866464 -239.624108)
			(xy 346.865969 -239.648715) (xy 346.858074 -239.697292) (xy 346.84249 -239.743973) (xy 346.819619 -239.78755)
			(xy 346.790054 -239.826894) (xy 346.754561 -239.860986) (xy 346.714058 -239.888942) (xy 346.669596 -239.91004)
			(xy 346.622325 -239.923732) (xy 346.57347 -239.929664) (xy 346.524295 -239.927683) (xy 346.476076 -239.917839)
			(xy 346.43006 -239.900387) (xy 346.387439 -239.87578) (xy 346.349318 -239.844655) (xy 346.316683 -239.807818)
			(xy 346.29038 -239.766222) (xy 346.271089 -239.720946) (xy 346.259312 -239.673162) (xy 346.255352 -239.624108)
			(xy 345.92641 -239.624108) (xy 345.925915 -239.648715) (xy 345.91802 -239.697292) (xy 345.902436 -239.743973)
			(xy 345.879565 -239.78755) (xy 345.85 -239.826894) (xy 345.814507 -239.860986) (xy 345.774004 -239.888942)
			(xy 345.729542 -239.91004) (xy 345.682271 -239.923732) (xy 345.633416 -239.929664) (xy 345.584241 -239.927683)
			(xy 345.536022 -239.917839) (xy 345.490006 -239.900387) (xy 345.447385 -239.87578) (xy 345.409264 -239.844655)
			(xy 345.376629 -239.807818) (xy 345.350326 -239.766222) (xy 345.331035 -239.720946) (xy 345.319258 -239.673162)
			(xy 345.315298 -239.624108) (xy 344.986912 -239.624108) (xy 344.982998 -239.672887) (xy 344.971352 -239.720425)
			(xy 344.952274 -239.765498) (xy 344.926252 -239.806951) (xy 344.893952 -239.843723) (xy 344.856201 -239.874874)
			(xy 344.813965 -239.899605) (xy 344.768326 -239.917284) (xy 344.720452 -239.927459) (xy 344.696034 -239.929162)
			(xy 344.686636 -239.929416) (xy 344.669618 -239.937036) (xy 344.641424 -239.964722) (xy 344.634603 -239.971986)
			(xy 344.626864 -239.990328) (xy 344.626438 -240.000282) (xy 344.626438 -240.434114) (xy 344.845398 -240.434114)
			(xy 344.849358 -240.38506) (xy 344.861135 -240.337276) (xy 344.880426 -240.292) (xy 344.906729 -240.250404)
			(xy 344.939364 -240.213567) (xy 344.977485 -240.182442) (xy 345.020106 -240.157835) (xy 345.066122 -240.140383)
			(xy 345.114341 -240.130539) (xy 345.163516 -240.128558) (xy 345.212371 -240.13449) (xy 345.259642 -240.148182)
			(xy 345.304104 -240.16928) (xy 345.344607 -240.197236) (xy 345.3801 -240.231328) (xy 345.409665 -240.270672)
			(xy 345.432536 -240.314249) (xy 345.44812 -240.36093) (xy 345.456015 -240.409507) (xy 345.45651 -240.434114)
			(xy 345.785198 -240.434114) (xy 345.789158 -240.38506) (xy 345.800935 -240.337276) (xy 345.820226 -240.292)
			(xy 345.846529 -240.250404) (xy 345.879164 -240.213567) (xy 345.917285 -240.182442) (xy 345.959906 -240.157835)
			(xy 346.005922 -240.140383) (xy 346.054141 -240.130539) (xy 346.103316 -240.128558) (xy 346.152171 -240.13449)
			(xy 346.199442 -240.148182) (xy 346.243904 -240.16928) (xy 346.284407 -240.197236) (xy 346.3199 -240.231328)
			(xy 346.349465 -240.270672) (xy 346.372336 -240.314249) (xy 346.38792 -240.36093) (xy 346.395815 -240.409507)
			(xy 346.39631 -240.434114) (xy 346.725252 -240.434114) (xy 346.729212 -240.38506) (xy 346.740989 -240.337276)
			(xy 346.76028 -240.292) (xy 346.786583 -240.250404) (xy 346.819218 -240.213567) (xy 346.857339 -240.182442)
			(xy 346.89996 -240.157835) (xy 346.945976 -240.140383) (xy 346.994195 -240.130539) (xy 347.04337 -240.128558)
			(xy 347.092225 -240.13449) (xy 347.139496 -240.148182) (xy 347.183958 -240.16928) (xy 347.224461 -240.197236)
			(xy 347.259954 -240.231328) (xy 347.289519 -240.270672) (xy 347.31239 -240.314249) (xy 347.327974 -240.36093)
			(xy 347.335869 -240.409507) (xy 347.336364 -240.434114) (xy 347.665306 -240.434114) (xy 347.669266 -240.38506)
			(xy 347.681043 -240.337276) (xy 347.700334 -240.292) (xy 347.726637 -240.250404) (xy 347.759272 -240.213567)
			(xy 347.797393 -240.182442) (xy 347.840014 -240.157835) (xy 347.88603 -240.140383) (xy 347.934249 -240.130539)
			(xy 347.983424 -240.128558) (xy 348.032279 -240.13449) (xy 348.07955 -240.148182) (xy 348.124012 -240.16928)
			(xy 348.164515 -240.197236) (xy 348.200008 -240.231328) (xy 348.229573 -240.270672) (xy 348.252444 -240.314249)
			(xy 348.268028 -240.36093) (xy 348.275923 -240.409507) (xy 348.276418 -240.434114) (xy 348.60536 -240.434114)
			(xy 348.60932 -240.38506) (xy 348.621097 -240.337276) (xy 348.640388 -240.292) (xy 348.666691 -240.250404)
			(xy 348.699326 -240.213567) (xy 348.737447 -240.182442) (xy 348.780068 -240.157835) (xy 348.826084 -240.140383)
			(xy 348.874303 -240.130539) (xy 348.923478 -240.128558) (xy 348.972333 -240.13449) (xy 349.019604 -240.148182)
			(xy 349.064066 -240.16928) (xy 349.104569 -240.197236) (xy 349.140062 -240.231328) (xy 349.169627 -240.270672)
			(xy 349.192498 -240.314249) (xy 349.208082 -240.36093) (xy 349.215977 -240.409507) (xy 349.216472 -240.434114)
			(xy 349.545414 -240.434114) (xy 349.549374 -240.38506) (xy 349.561151 -240.337276) (xy 349.580442 -240.292)
			(xy 349.606745 -240.250404) (xy 349.63938 -240.213567) (xy 349.677501 -240.182442) (xy 349.720122 -240.157835)
			(xy 349.766138 -240.140383) (xy 349.814357 -240.130539) (xy 349.863532 -240.128558) (xy 349.912387 -240.13449)
			(xy 349.959658 -240.148182) (xy 350.00412 -240.16928) (xy 350.044623 -240.197236) (xy 350.080116 -240.231328)
			(xy 350.109681 -240.270672) (xy 350.132552 -240.314249) (xy 350.148136 -240.36093) (xy 350.156031 -240.409507)
			(xy 350.156526 -240.434114) (xy 350.485214 -240.434114) (xy 350.489174 -240.38506) (xy 350.500951 -240.337276)
			(xy 350.520242 -240.292) (xy 350.546545 -240.250404) (xy 350.57918 -240.213567) (xy 350.617301 -240.182442)
			(xy 350.659922 -240.157835) (xy 350.705938 -240.140383) (xy 350.754157 -240.130539) (xy 350.803332 -240.128558)
			(xy 350.852187 -240.13449) (xy 350.899458 -240.148182) (xy 350.94392 -240.16928) (xy 350.984423 -240.197236)
			(xy 351.019916 -240.231328) (xy 351.049481 -240.270672) (xy 351.072352 -240.314249) (xy 351.087936 -240.36093)
			(xy 351.095831 -240.409507) (xy 351.096326 -240.434114) (xy 351.425268 -240.434114) (xy 351.429228 -240.38506)
			(xy 351.441005 -240.337276) (xy 351.460296 -240.292) (xy 351.486599 -240.250404) (xy 351.519234 -240.213567)
			(xy 351.557355 -240.182442) (xy 351.599976 -240.157835) (xy 351.645992 -240.140383) (xy 351.694211 -240.130539)
			(xy 351.743386 -240.128558) (xy 351.792241 -240.13449) (xy 351.839512 -240.148182) (xy 351.883974 -240.16928)
			(xy 351.924477 -240.197236) (xy 351.95997 -240.231328) (xy 351.989535 -240.270672) (xy 352.012406 -240.314249)
			(xy 352.02799 -240.36093) (xy 352.035885 -240.409507) (xy 352.03638 -240.434114) (xy 352.365322 -240.434114)
			(xy 352.369282 -240.38506) (xy 352.381059 -240.337276) (xy 352.40035 -240.292) (xy 352.426653 -240.250404)
			(xy 352.459288 -240.213567) (xy 352.497409 -240.182442) (xy 352.54003 -240.157835) (xy 352.586046 -240.140383)
			(xy 352.634265 -240.130539) (xy 352.68344 -240.128558) (xy 352.732295 -240.13449) (xy 352.779566 -240.148182)
			(xy 352.824028 -240.16928) (xy 352.864531 -240.197236) (xy 352.900024 -240.231328) (xy 352.929589 -240.270672)
			(xy 352.95246 -240.314249) (xy 352.968044 -240.36093) (xy 352.975939 -240.409507) (xy 352.976434 -240.434114)
			(xy 353.305376 -240.434114) (xy 353.309336 -240.38506) (xy 353.321113 -240.337276) (xy 353.340404 -240.292)
			(xy 353.366707 -240.250404) (xy 353.399342 -240.213567) (xy 353.437463 -240.182442) (xy 353.480084 -240.157835)
			(xy 353.5261 -240.140383) (xy 353.574319 -240.130539) (xy 353.623494 -240.128558) (xy 353.672349 -240.13449)
			(xy 353.71962 -240.148182) (xy 353.764082 -240.16928) (xy 353.804585 -240.197236) (xy 353.840078 -240.231328)
			(xy 353.869643 -240.270672) (xy 353.892514 -240.314249) (xy 353.908098 -240.36093) (xy 353.915993 -240.409507)
			(xy 353.916488 -240.434114) (xy 354.24543 -240.434114) (xy 354.24939 -240.38506) (xy 354.261167 -240.337276)
			(xy 354.280458 -240.292) (xy 354.306761 -240.250404) (xy 354.339396 -240.213567) (xy 354.377517 -240.182442)
			(xy 354.420138 -240.157835) (xy 354.466154 -240.140383) (xy 354.514373 -240.130539) (xy 354.563548 -240.128558)
			(xy 354.612403 -240.13449) (xy 354.659674 -240.148182) (xy 354.704136 -240.16928) (xy 354.744639 -240.197236)
			(xy 354.780132 -240.231328) (xy 354.809697 -240.270672) (xy 354.832568 -240.314249) (xy 354.848152 -240.36093)
			(xy 354.856047 -240.409507) (xy 354.856542 -240.434114) (xy 355.18523 -240.434114) (xy 355.18919 -240.38506)
			(xy 355.200967 -240.337276) (xy 355.220258 -240.292) (xy 355.246561 -240.250404) (xy 355.279196 -240.213567)
			(xy 355.317317 -240.182442) (xy 355.359938 -240.157835) (xy 355.405954 -240.140383) (xy 355.454173 -240.130539)
			(xy 355.503348 -240.128558) (xy 355.552203 -240.13449) (xy 355.599474 -240.148182) (xy 355.643936 -240.16928)
			(xy 355.684439 -240.197236) (xy 355.719932 -240.231328) (xy 355.749497 -240.270672) (xy 355.772368 -240.314249)
			(xy 355.787952 -240.36093) (xy 355.795847 -240.409507) (xy 355.796342 -240.434114) (xy 356.125284 -240.434114)
			(xy 356.129244 -240.38506) (xy 356.141021 -240.337276) (xy 356.160312 -240.292) (xy 356.186615 -240.250404)
			(xy 356.21925 -240.213567) (xy 356.257371 -240.182442) (xy 356.299992 -240.157835) (xy 356.346008 -240.140383)
			(xy 356.394227 -240.130539) (xy 356.443402 -240.128558) (xy 356.492257 -240.13449) (xy 356.539528 -240.148182)
			(xy 356.58399 -240.16928) (xy 356.624493 -240.197236) (xy 356.659986 -240.231328) (xy 356.689551 -240.270672)
			(xy 356.712422 -240.314249) (xy 356.728006 -240.36093) (xy 356.735901 -240.409507) (xy 356.736396 -240.434114)
			(xy 357.065338 -240.434114) (xy 357.069298 -240.38506) (xy 357.081075 -240.337276) (xy 357.100366 -240.292)
			(xy 357.126669 -240.250404) (xy 357.159304 -240.213567) (xy 357.197425 -240.182442) (xy 357.240046 -240.157835)
			(xy 357.286062 -240.140383) (xy 357.334281 -240.130539) (xy 357.383456 -240.128558) (xy 357.432311 -240.13449)
			(xy 357.479582 -240.148182) (xy 357.524044 -240.16928) (xy 357.564547 -240.197236) (xy 357.60004 -240.231328)
			(xy 357.629605 -240.270672) (xy 357.652476 -240.314249) (xy 357.66806 -240.36093) (xy 357.675955 -240.409507)
			(xy 357.67645 -240.434114) (xy 358.005392 -240.434114) (xy 358.009352 -240.38506) (xy 358.021129 -240.337276)
			(xy 358.04042 -240.292) (xy 358.066723 -240.250404) (xy 358.099358 -240.213567) (xy 358.137479 -240.182442)
			(xy 358.1801 -240.157835) (xy 358.226116 -240.140383) (xy 358.274335 -240.130539) (xy 358.32351 -240.128558)
			(xy 358.372365 -240.13449) (xy 358.419636 -240.148182) (xy 358.464098 -240.16928) (xy 358.504601 -240.197236)
			(xy 358.540094 -240.231328) (xy 358.569659 -240.270672) (xy 358.59253 -240.314249) (xy 358.608114 -240.36093)
			(xy 358.616009 -240.409507) (xy 358.616504 -240.434114) (xy 360.81895 -240.434114) (xy 360.82291 -240.38506)
			(xy 360.834687 -240.337276) (xy 360.853978 -240.292) (xy 360.880281 -240.250404) (xy 360.912916 -240.213567)
			(xy 360.951037 -240.182442) (xy 360.993658 -240.157835) (xy 361.039674 -240.140383) (xy 361.087893 -240.130539)
			(xy 361.137068 -240.128558) (xy 361.185923 -240.13449) (xy 361.233194 -240.148182) (xy 361.277656 -240.16928)
			(xy 361.318159 -240.197236) (xy 361.353652 -240.231328) (xy 361.383217 -240.270672) (xy 361.406088 -240.314249)
			(xy 361.421672 -240.36093) (xy 361.429567 -240.409507) (xy 361.430062 -240.434114) (xy 361.759004 -240.434114)
			(xy 361.762964 -240.38506) (xy 361.774741 -240.337276) (xy 361.794032 -240.292) (xy 361.820335 -240.250404)
			(xy 361.85297 -240.213567) (xy 361.891091 -240.182442) (xy 361.933712 -240.157835) (xy 361.979728 -240.140383)
			(xy 362.027947 -240.130539) (xy 362.077122 -240.128558) (xy 362.125977 -240.13449) (xy 362.173248 -240.148182)
			(xy 362.21771 -240.16928) (xy 362.258213 -240.197236) (xy 362.293706 -240.231328) (xy 362.323271 -240.270672)
			(xy 362.346142 -240.314249) (xy 362.361726 -240.36093) (xy 362.369621 -240.409507) (xy 362.370116 -240.434114)
			(xy 362.699058 -240.434114) (xy 362.703018 -240.38506) (xy 362.714795 -240.337276) (xy 362.734086 -240.292)
			(xy 362.760389 -240.250404) (xy 362.793024 -240.213567) (xy 362.831145 -240.182442) (xy 362.873766 -240.157835)
			(xy 362.919782 -240.140383) (xy 362.968001 -240.130539) (xy 363.017176 -240.128558) (xy 363.066031 -240.13449)
			(xy 363.113302 -240.148182) (xy 363.157764 -240.16928) (xy 363.198267 -240.197236) (xy 363.23376 -240.231328)
			(xy 363.263325 -240.270672) (xy 363.286196 -240.314249) (xy 363.30178 -240.36093) (xy 363.309675 -240.409507)
			(xy 363.31017 -240.434114) (xy 363.639112 -240.434114) (xy 363.643072 -240.38506) (xy 363.654849 -240.337276)
			(xy 363.67414 -240.292) (xy 363.700443 -240.250404) (xy 363.733078 -240.213567) (xy 363.771199 -240.182442)
			(xy 363.81382 -240.157835) (xy 363.859836 -240.140383) (xy 363.908055 -240.130539) (xy 363.95723 -240.128558)
			(xy 364.006085 -240.13449) (xy 364.053356 -240.148182) (xy 364.097818 -240.16928) (xy 364.138321 -240.197236)
			(xy 364.173814 -240.231328) (xy 364.203379 -240.270672) (xy 364.22625 -240.314249) (xy 364.241834 -240.36093)
			(xy 364.249729 -240.409507) (xy 364.250224 -240.434114) (xy 364.578912 -240.434114) (xy 364.582872 -240.38506)
			(xy 364.594649 -240.337276) (xy 364.61394 -240.292) (xy 364.640243 -240.250404) (xy 364.672878 -240.213567)
			(xy 364.710999 -240.182442) (xy 364.75362 -240.157835) (xy 364.799636 -240.140383) (xy 364.847855 -240.130539)
			(xy 364.89703 -240.128558) (xy 364.945885 -240.13449) (xy 364.993156 -240.148182) (xy 365.037618 -240.16928)
			(xy 365.078121 -240.197236) (xy 365.113614 -240.231328) (xy 365.143179 -240.270672) (xy 365.16605 -240.314249)
			(xy 365.181634 -240.36093) (xy 365.189529 -240.409507) (xy 365.190024 -240.434114) (xy 365.518966 -240.434114)
			(xy 365.522926 -240.38506) (xy 365.534703 -240.337276) (xy 365.553994 -240.292) (xy 365.580297 -240.250404)
			(xy 365.612932 -240.213567) (xy 365.651053 -240.182442) (xy 365.693674 -240.157835) (xy 365.73969 -240.140383)
			(xy 365.787909 -240.130539) (xy 365.837084 -240.128558) (xy 365.885939 -240.13449) (xy 365.93321 -240.148182)
			(xy 365.977672 -240.16928) (xy 366.018175 -240.197236) (xy 366.053668 -240.231328) (xy 366.083233 -240.270672)
			(xy 366.106104 -240.314249) (xy 366.121688 -240.36093) (xy 366.129583 -240.409507) (xy 366.130078 -240.434114)
			(xy 366.45902 -240.434114) (xy 366.46298 -240.38506) (xy 366.474757 -240.337276) (xy 366.494048 -240.292)
			(xy 366.520351 -240.250404) (xy 366.552986 -240.213567) (xy 366.591107 -240.182442) (xy 366.633728 -240.157835)
			(xy 366.679744 -240.140383) (xy 366.727963 -240.130539) (xy 366.777138 -240.128558) (xy 366.825993 -240.13449)
			(xy 366.873264 -240.148182) (xy 366.917726 -240.16928) (xy 366.958229 -240.197236) (xy 366.993722 -240.231328)
			(xy 367.023287 -240.270672) (xy 367.046158 -240.314249) (xy 367.061742 -240.36093) (xy 367.069637 -240.409507)
			(xy 367.070132 -240.434114) (xy 367.399074 -240.434114) (xy 367.403034 -240.38506) (xy 367.414811 -240.337276)
			(xy 367.434102 -240.292) (xy 367.460405 -240.250404) (xy 367.49304 -240.213567) (xy 367.531161 -240.182442)
			(xy 367.573782 -240.157835) (xy 367.619798 -240.140383) (xy 367.668017 -240.130539) (xy 367.717192 -240.128558)
			(xy 367.766047 -240.13449) (xy 367.813318 -240.148182) (xy 367.85778 -240.16928) (xy 367.898283 -240.197236)
			(xy 367.933776 -240.231328) (xy 367.963341 -240.270672) (xy 367.986212 -240.314249) (xy 368.001796 -240.36093)
			(xy 368.009691 -240.409507) (xy 368.010186 -240.434114) (xy 368.338874 -240.434114) (xy 368.342834 -240.38506)
			(xy 368.354611 -240.337276) (xy 368.373902 -240.292) (xy 368.400205 -240.250404) (xy 368.43284 -240.213567)
			(xy 368.470961 -240.182442) (xy 368.513582 -240.157835) (xy 368.559598 -240.140383) (xy 368.607817 -240.130539)
			(xy 368.656992 -240.128558) (xy 368.705847 -240.13449) (xy 368.753118 -240.148182) (xy 368.79758 -240.16928)
			(xy 368.838083 -240.197236) (xy 368.873576 -240.231328) (xy 368.903141 -240.270672) (xy 368.926012 -240.314249)
			(xy 368.941596 -240.36093) (xy 368.949491 -240.409507) (xy 368.949986 -240.434114) (xy 369.278928 -240.434114)
			(xy 369.282888 -240.38506) (xy 369.294665 -240.337276) (xy 369.313956 -240.292) (xy 369.340259 -240.250404)
			(xy 369.372894 -240.213567) (xy 369.411015 -240.182442) (xy 369.453636 -240.157835) (xy 369.499652 -240.140383)
			(xy 369.547871 -240.130539) (xy 369.597046 -240.128558) (xy 369.645901 -240.13449) (xy 369.693172 -240.148182)
			(xy 369.737634 -240.16928) (xy 369.778137 -240.197236) (xy 369.81363 -240.231328) (xy 369.843195 -240.270672)
			(xy 369.866066 -240.314249) (xy 369.88165 -240.36093) (xy 369.889545 -240.409507) (xy 369.89004 -240.434114)
			(xy 370.218982 -240.434114) (xy 370.222942 -240.38506) (xy 370.234719 -240.337276) (xy 370.25401 -240.292)
			(xy 370.280313 -240.250404) (xy 370.312948 -240.213567) (xy 370.351069 -240.182442) (xy 370.39369 -240.157835)
			(xy 370.439706 -240.140383) (xy 370.487925 -240.130539) (xy 370.5371 -240.128558) (xy 370.585955 -240.13449)
			(xy 370.633226 -240.148182) (xy 370.677688 -240.16928) (xy 370.718191 -240.197236) (xy 370.753684 -240.231328)
			(xy 370.783249 -240.270672) (xy 370.80612 -240.314249) (xy 370.821704 -240.36093) (xy 370.829599 -240.409507)
			(xy 370.830094 -240.434114) (xy 371.159036 -240.434114) (xy 371.162996 -240.38506) (xy 371.174773 -240.337276)
			(xy 371.194064 -240.292) (xy 371.220367 -240.250404) (xy 371.253002 -240.213567) (xy 371.291123 -240.182442)
			(xy 371.333744 -240.157835) (xy 371.37976 -240.140383) (xy 371.427979 -240.130539) (xy 371.477154 -240.128558)
			(xy 371.526009 -240.13449) (xy 371.57328 -240.148182) (xy 371.617742 -240.16928) (xy 371.658245 -240.197236)
			(xy 371.693738 -240.231328) (xy 371.723303 -240.270672) (xy 371.746174 -240.314249) (xy 371.761758 -240.36093)
			(xy 371.769653 -240.409507) (xy 371.770148 -240.434114) (xy 372.09909 -240.434114) (xy 372.10305 -240.38506)
			(xy 372.114827 -240.337276) (xy 372.134118 -240.292) (xy 372.160421 -240.250404) (xy 372.193056 -240.213567)
			(xy 372.231177 -240.182442) (xy 372.273798 -240.157835) (xy 372.319814 -240.140383) (xy 372.368033 -240.130539)
			(xy 372.417208 -240.128558) (xy 372.466063 -240.13449) (xy 372.513334 -240.148182) (xy 372.557796 -240.16928)
			(xy 372.598299 -240.197236) (xy 372.633792 -240.231328) (xy 372.663357 -240.270672) (xy 372.686228 -240.314249)
			(xy 372.701812 -240.36093) (xy 372.709707 -240.409507) (xy 372.710202 -240.434114) (xy 373.03889 -240.434114)
			(xy 373.04285 -240.38506) (xy 373.054627 -240.337276) (xy 373.073918 -240.292) (xy 373.100221 -240.250404)
			(xy 373.132856 -240.213567) (xy 373.170977 -240.182442) (xy 373.213598 -240.157835) (xy 373.259614 -240.140383)
			(xy 373.307833 -240.130539) (xy 373.357008 -240.128558) (xy 373.405863 -240.13449) (xy 373.453134 -240.148182)
			(xy 373.497596 -240.16928) (xy 373.538099 -240.197236) (xy 373.573592 -240.231328) (xy 373.603157 -240.270672)
			(xy 373.626028 -240.314249) (xy 373.641612 -240.36093) (xy 373.649507 -240.409507) (xy 373.650002 -240.434114)
			(xy 373.978944 -240.434114) (xy 373.982904 -240.38506) (xy 373.994681 -240.337276) (xy 374.013972 -240.292)
			(xy 374.040275 -240.250404) (xy 374.07291 -240.213567) (xy 374.111031 -240.182442) (xy 374.153652 -240.157835)
			(xy 374.199668 -240.140383) (xy 374.247887 -240.130539) (xy 374.297062 -240.128558) (xy 374.345917 -240.13449)
			(xy 374.393188 -240.148182) (xy 374.43765 -240.16928) (xy 374.478153 -240.197236) (xy 374.513646 -240.231328)
			(xy 374.543211 -240.270672) (xy 374.566082 -240.314249) (xy 374.581666 -240.36093) (xy 374.589561 -240.409507)
			(xy 374.590056 -240.434114) (xy 374.589561 -240.458721) (xy 374.581666 -240.507298) (xy 374.566082 -240.553979)
			(xy 374.543211 -240.597556) (xy 374.513646 -240.6369) (xy 374.478153 -240.670992) (xy 374.43765 -240.698948)
			(xy 374.393188 -240.720046) (xy 374.345917 -240.733738) (xy 374.297062 -240.73967) (xy 374.247887 -240.737689)
			(xy 374.199668 -240.727845) (xy 374.153652 -240.710393) (xy 374.111031 -240.685786) (xy 374.07291 -240.654661)
			(xy 374.040275 -240.617824) (xy 374.013972 -240.576228) (xy 373.994681 -240.530952) (xy 373.982904 -240.483168)
			(xy 373.978944 -240.434114) (xy 373.650002 -240.434114) (xy 373.649507 -240.458721) (xy 373.641612 -240.507298)
			(xy 373.626028 -240.553979) (xy 373.603157 -240.597556) (xy 373.573592 -240.6369) (xy 373.538099 -240.670992)
			(xy 373.497596 -240.698948) (xy 373.453134 -240.720046) (xy 373.405863 -240.733738) (xy 373.357008 -240.73967)
			(xy 373.307833 -240.737689) (xy 373.259614 -240.727845) (xy 373.213598 -240.710393) (xy 373.170977 -240.685786)
			(xy 373.132856 -240.654661) (xy 373.100221 -240.617824) (xy 373.073918 -240.576228) (xy 373.054627 -240.530952)
			(xy 373.04285 -240.483168) (xy 373.03889 -240.434114) (xy 372.710202 -240.434114) (xy 372.709707 -240.458721)
			(xy 372.701812 -240.507298) (xy 372.686228 -240.553979) (xy 372.663357 -240.597556) (xy 372.633792 -240.6369)
			(xy 372.598299 -240.670992) (xy 372.557796 -240.698948) (xy 372.513334 -240.720046) (xy 372.466063 -240.733738)
			(xy 372.417208 -240.73967) (xy 372.368033 -240.737689) (xy 372.319814 -240.727845) (xy 372.273798 -240.710393)
			(xy 372.231177 -240.685786) (xy 372.193056 -240.654661) (xy 372.160421 -240.617824) (xy 372.134118 -240.576228)
			(xy 372.114827 -240.530952) (xy 372.10305 -240.483168) (xy 372.09909 -240.434114) (xy 371.770148 -240.434114)
			(xy 371.769653 -240.458721) (xy 371.761758 -240.507298) (xy 371.746174 -240.553979) (xy 371.723303 -240.597556)
			(xy 371.693738 -240.6369) (xy 371.658245 -240.670992) (xy 371.617742 -240.698948) (xy 371.57328 -240.720046)
			(xy 371.526009 -240.733738) (xy 371.477154 -240.73967) (xy 371.427979 -240.737689) (xy 371.37976 -240.727845)
			(xy 371.333744 -240.710393) (xy 371.291123 -240.685786) (xy 371.253002 -240.654661) (xy 371.220367 -240.617824)
			(xy 371.194064 -240.576228) (xy 371.174773 -240.530952) (xy 371.162996 -240.483168) (xy 371.159036 -240.434114)
			(xy 370.830094 -240.434114) (xy 370.829599 -240.458721) (xy 370.821704 -240.507298) (xy 370.80612 -240.553979)
			(xy 370.783249 -240.597556) (xy 370.753684 -240.6369) (xy 370.718191 -240.670992) (xy 370.677688 -240.698948)
			(xy 370.633226 -240.720046) (xy 370.585955 -240.733738) (xy 370.5371 -240.73967) (xy 370.487925 -240.737689)
			(xy 370.439706 -240.727845) (xy 370.39369 -240.710393) (xy 370.351069 -240.685786) (xy 370.312948 -240.654661)
			(xy 370.280313 -240.617824) (xy 370.25401 -240.576228) (xy 370.234719 -240.530952) (xy 370.222942 -240.483168)
			(xy 370.218982 -240.434114) (xy 369.89004 -240.434114) (xy 369.889545 -240.458721) (xy 369.88165 -240.507298)
			(xy 369.866066 -240.553979) (xy 369.843195 -240.597556) (xy 369.81363 -240.6369) (xy 369.778137 -240.670992)
			(xy 369.737634 -240.698948) (xy 369.693172 -240.720046) (xy 369.645901 -240.733738) (xy 369.597046 -240.73967)
			(xy 369.547871 -240.737689) (xy 369.499652 -240.727845) (xy 369.453636 -240.710393) (xy 369.411015 -240.685786)
			(xy 369.372894 -240.654661) (xy 369.340259 -240.617824) (xy 369.313956 -240.576228) (xy 369.294665 -240.530952)
			(xy 369.282888 -240.483168) (xy 369.278928 -240.434114) (xy 368.949986 -240.434114) (xy 368.949491 -240.458721)
			(xy 368.941596 -240.507298) (xy 368.926012 -240.553979) (xy 368.903141 -240.597556) (xy 368.873576 -240.6369)
			(xy 368.838083 -240.670992) (xy 368.79758 -240.698948) (xy 368.753118 -240.720046) (xy 368.705847 -240.733738)
			(xy 368.656992 -240.73967) (xy 368.607817 -240.737689) (xy 368.559598 -240.727845) (xy 368.513582 -240.710393)
			(xy 368.470961 -240.685786) (xy 368.43284 -240.654661) (xy 368.400205 -240.617824) (xy 368.373902 -240.576228)
			(xy 368.354611 -240.530952) (xy 368.342834 -240.483168) (xy 368.338874 -240.434114) (xy 368.010186 -240.434114)
			(xy 368.009691 -240.458721) (xy 368.001796 -240.507298) (xy 367.986212 -240.553979) (xy 367.963341 -240.597556)
			(xy 367.933776 -240.6369) (xy 367.898283 -240.670992) (xy 367.85778 -240.698948) (xy 367.813318 -240.720046)
			(xy 367.766047 -240.733738) (xy 367.717192 -240.73967) (xy 367.668017 -240.737689) (xy 367.619798 -240.727845)
			(xy 367.573782 -240.710393) (xy 367.531161 -240.685786) (xy 367.49304 -240.654661) (xy 367.460405 -240.617824)
			(xy 367.434102 -240.576228) (xy 367.414811 -240.530952) (xy 367.403034 -240.483168) (xy 367.399074 -240.434114)
			(xy 367.070132 -240.434114) (xy 367.069637 -240.458721) (xy 367.061742 -240.507298) (xy 367.046158 -240.553979)
			(xy 367.023287 -240.597556) (xy 366.993722 -240.6369) (xy 366.958229 -240.670992) (xy 366.917726 -240.698948)
			(xy 366.873264 -240.720046) (xy 366.825993 -240.733738) (xy 366.777138 -240.73967) (xy 366.727963 -240.737689)
			(xy 366.679744 -240.727845) (xy 366.633728 -240.710393) (xy 366.591107 -240.685786) (xy 366.552986 -240.654661)
			(xy 366.520351 -240.617824) (xy 366.494048 -240.576228) (xy 366.474757 -240.530952) (xy 366.46298 -240.483168)
			(xy 366.45902 -240.434114) (xy 366.130078 -240.434114) (xy 366.129583 -240.458721) (xy 366.121688 -240.507298)
			(xy 366.106104 -240.553979) (xy 366.083233 -240.597556) (xy 366.053668 -240.6369) (xy 366.018175 -240.670992)
			(xy 365.977672 -240.698948) (xy 365.93321 -240.720046) (xy 365.885939 -240.733738) (xy 365.837084 -240.73967)
			(xy 365.787909 -240.737689) (xy 365.73969 -240.727845) (xy 365.693674 -240.710393) (xy 365.651053 -240.685786)
			(xy 365.612932 -240.654661) (xy 365.580297 -240.617824) (xy 365.553994 -240.576228) (xy 365.534703 -240.530952)
			(xy 365.522926 -240.483168) (xy 365.518966 -240.434114) (xy 365.190024 -240.434114) (xy 365.189529 -240.458721)
			(xy 365.181634 -240.507298) (xy 365.16605 -240.553979) (xy 365.143179 -240.597556) (xy 365.113614 -240.6369)
			(xy 365.078121 -240.670992) (xy 365.037618 -240.698948) (xy 364.993156 -240.720046) (xy 364.945885 -240.733738)
			(xy 364.89703 -240.73967) (xy 364.847855 -240.737689) (xy 364.799636 -240.727845) (xy 364.75362 -240.710393)
			(xy 364.710999 -240.685786) (xy 364.672878 -240.654661) (xy 364.640243 -240.617824) (xy 364.61394 -240.576228)
			(xy 364.594649 -240.530952) (xy 364.582872 -240.483168) (xy 364.578912 -240.434114) (xy 364.250224 -240.434114)
			(xy 364.249729 -240.458721) (xy 364.241834 -240.507298) (xy 364.22625 -240.553979) (xy 364.203379 -240.597556)
			(xy 364.173814 -240.6369) (xy 364.138321 -240.670992) (xy 364.097818 -240.698948) (xy 364.053356 -240.720046)
			(xy 364.006085 -240.733738) (xy 363.95723 -240.73967) (xy 363.908055 -240.737689) (xy 363.859836 -240.727845)
			(xy 363.81382 -240.710393) (xy 363.771199 -240.685786) (xy 363.733078 -240.654661) (xy 363.700443 -240.617824)
			(xy 363.67414 -240.576228) (xy 363.654849 -240.530952) (xy 363.643072 -240.483168) (xy 363.639112 -240.434114)
			(xy 363.31017 -240.434114) (xy 363.309675 -240.458721) (xy 363.30178 -240.507298) (xy 363.286196 -240.553979)
			(xy 363.263325 -240.597556) (xy 363.23376 -240.6369) (xy 363.198267 -240.670992) (xy 363.157764 -240.698948)
			(xy 363.113302 -240.720046) (xy 363.066031 -240.733738) (xy 363.017176 -240.73967) (xy 362.968001 -240.737689)
			(xy 362.919782 -240.727845) (xy 362.873766 -240.710393) (xy 362.831145 -240.685786) (xy 362.793024 -240.654661)
			(xy 362.760389 -240.617824) (xy 362.734086 -240.576228) (xy 362.714795 -240.530952) (xy 362.703018 -240.483168)
			(xy 362.699058 -240.434114) (xy 362.370116 -240.434114) (xy 362.369621 -240.458721) (xy 362.361726 -240.507298)
			(xy 362.346142 -240.553979) (xy 362.323271 -240.597556) (xy 362.293706 -240.6369) (xy 362.258213 -240.670992)
			(xy 362.21771 -240.698948) (xy 362.173248 -240.720046) (xy 362.125977 -240.733738) (xy 362.077122 -240.73967)
			(xy 362.027947 -240.737689) (xy 361.979728 -240.727845) (xy 361.933712 -240.710393) (xy 361.891091 -240.685786)
			(xy 361.85297 -240.654661) (xy 361.820335 -240.617824) (xy 361.794032 -240.576228) (xy 361.774741 -240.530952)
			(xy 361.762964 -240.483168) (xy 361.759004 -240.434114) (xy 361.430062 -240.434114) (xy 361.429567 -240.458721)
			(xy 361.421672 -240.507298) (xy 361.406088 -240.553979) (xy 361.383217 -240.597556) (xy 361.353652 -240.6369)
			(xy 361.318159 -240.670992) (xy 361.277656 -240.698948) (xy 361.233194 -240.720046) (xy 361.185923 -240.733738)
			(xy 361.137068 -240.73967) (xy 361.087893 -240.737689) (xy 361.039674 -240.727845) (xy 360.993658 -240.710393)
			(xy 360.951037 -240.685786) (xy 360.912916 -240.654661) (xy 360.880281 -240.617824) (xy 360.853978 -240.576228)
			(xy 360.834687 -240.530952) (xy 360.82291 -240.483168) (xy 360.81895 -240.434114) (xy 358.616504 -240.434114)
			(xy 358.616009 -240.458721) (xy 358.608114 -240.507298) (xy 358.59253 -240.553979) (xy 358.569659 -240.597556)
			(xy 358.540094 -240.6369) (xy 358.504601 -240.670992) (xy 358.464098 -240.698948) (xy 358.419636 -240.720046)
			(xy 358.372365 -240.733738) (xy 358.32351 -240.73967) (xy 358.274335 -240.737689) (xy 358.226116 -240.727845)
			(xy 358.1801 -240.710393) (xy 358.137479 -240.685786) (xy 358.099358 -240.654661) (xy 358.066723 -240.617824)
			(xy 358.04042 -240.576228) (xy 358.021129 -240.530952) (xy 358.009352 -240.483168) (xy 358.005392 -240.434114)
			(xy 357.67645 -240.434114) (xy 357.675955 -240.458721) (xy 357.66806 -240.507298) (xy 357.652476 -240.553979)
			(xy 357.629605 -240.597556) (xy 357.60004 -240.6369) (xy 357.564547 -240.670992) (xy 357.524044 -240.698948)
			(xy 357.479582 -240.720046) (xy 357.432311 -240.733738) (xy 357.383456 -240.73967) (xy 357.334281 -240.737689)
			(xy 357.286062 -240.727845) (xy 357.240046 -240.710393) (xy 357.197425 -240.685786) (xy 357.159304 -240.654661)
			(xy 357.126669 -240.617824) (xy 357.100366 -240.576228) (xy 357.081075 -240.530952) (xy 357.069298 -240.483168)
			(xy 357.065338 -240.434114) (xy 356.736396 -240.434114) (xy 356.735901 -240.458721) (xy 356.728006 -240.507298)
			(xy 356.712422 -240.553979) (xy 356.689551 -240.597556) (xy 356.659986 -240.6369) (xy 356.624493 -240.670992)
			(xy 356.58399 -240.698948) (xy 356.539528 -240.720046) (xy 356.492257 -240.733738) (xy 356.443402 -240.73967)
			(xy 356.394227 -240.737689) (xy 356.346008 -240.727845) (xy 356.299992 -240.710393) (xy 356.257371 -240.685786)
			(xy 356.21925 -240.654661) (xy 356.186615 -240.617824) (xy 356.160312 -240.576228) (xy 356.141021 -240.530952)
			(xy 356.129244 -240.483168) (xy 356.125284 -240.434114) (xy 355.796342 -240.434114) (xy 355.795847 -240.458721)
			(xy 355.787952 -240.507298) (xy 355.772368 -240.553979) (xy 355.749497 -240.597556) (xy 355.719932 -240.6369)
			(xy 355.684439 -240.670992) (xy 355.643936 -240.698948) (xy 355.599474 -240.720046) (xy 355.552203 -240.733738)
			(xy 355.503348 -240.73967) (xy 355.454173 -240.737689) (xy 355.405954 -240.727845) (xy 355.359938 -240.710393)
			(xy 355.317317 -240.685786) (xy 355.279196 -240.654661) (xy 355.246561 -240.617824) (xy 355.220258 -240.576228)
			(xy 355.200967 -240.530952) (xy 355.18919 -240.483168) (xy 355.18523 -240.434114) (xy 354.856542 -240.434114)
			(xy 354.856047 -240.458721) (xy 354.848152 -240.507298) (xy 354.832568 -240.553979) (xy 354.809697 -240.597556)
			(xy 354.780132 -240.6369) (xy 354.744639 -240.670992) (xy 354.704136 -240.698948) (xy 354.659674 -240.720046)
			(xy 354.612403 -240.733738) (xy 354.563548 -240.73967) (xy 354.514373 -240.737689) (xy 354.466154 -240.727845)
			(xy 354.420138 -240.710393) (xy 354.377517 -240.685786) (xy 354.339396 -240.654661) (xy 354.306761 -240.617824)
			(xy 354.280458 -240.576228) (xy 354.261167 -240.530952) (xy 354.24939 -240.483168) (xy 354.24543 -240.434114)
			(xy 353.916488 -240.434114) (xy 353.915993 -240.458721) (xy 353.908098 -240.507298) (xy 353.892514 -240.553979)
			(xy 353.869643 -240.597556) (xy 353.840078 -240.6369) (xy 353.804585 -240.670992) (xy 353.764082 -240.698948)
			(xy 353.71962 -240.720046) (xy 353.672349 -240.733738) (xy 353.623494 -240.73967) (xy 353.574319 -240.737689)
			(xy 353.5261 -240.727845) (xy 353.480084 -240.710393) (xy 353.437463 -240.685786) (xy 353.399342 -240.654661)
			(xy 353.366707 -240.617824) (xy 353.340404 -240.576228) (xy 353.321113 -240.530952) (xy 353.309336 -240.483168)
			(xy 353.305376 -240.434114) (xy 352.976434 -240.434114) (xy 352.975939 -240.458721) (xy 352.968044 -240.507298)
			(xy 352.95246 -240.553979) (xy 352.929589 -240.597556) (xy 352.900024 -240.6369) (xy 352.864531 -240.670992)
			(xy 352.824028 -240.698948) (xy 352.779566 -240.720046) (xy 352.732295 -240.733738) (xy 352.68344 -240.73967)
			(xy 352.634265 -240.737689) (xy 352.586046 -240.727845) (xy 352.54003 -240.710393) (xy 352.497409 -240.685786)
			(xy 352.459288 -240.654661) (xy 352.426653 -240.617824) (xy 352.40035 -240.576228) (xy 352.381059 -240.530952)
			(xy 352.369282 -240.483168) (xy 352.365322 -240.434114) (xy 352.03638 -240.434114) (xy 352.035885 -240.458721)
			(xy 352.02799 -240.507298) (xy 352.012406 -240.553979) (xy 351.989535 -240.597556) (xy 351.95997 -240.6369)
			(xy 351.924477 -240.670992) (xy 351.883974 -240.698948) (xy 351.839512 -240.720046) (xy 351.792241 -240.733738)
			(xy 351.743386 -240.73967) (xy 351.694211 -240.737689) (xy 351.645992 -240.727845) (xy 351.599976 -240.710393)
			(xy 351.557355 -240.685786) (xy 351.519234 -240.654661) (xy 351.486599 -240.617824) (xy 351.460296 -240.576228)
			(xy 351.441005 -240.530952) (xy 351.429228 -240.483168) (xy 351.425268 -240.434114) (xy 351.096326 -240.434114)
			(xy 351.095831 -240.458721) (xy 351.087936 -240.507298) (xy 351.072352 -240.553979) (xy 351.049481 -240.597556)
			(xy 351.019916 -240.6369) (xy 350.984423 -240.670992) (xy 350.94392 -240.698948) (xy 350.899458 -240.720046)
			(xy 350.852187 -240.733738) (xy 350.803332 -240.73967) (xy 350.754157 -240.737689) (xy 350.705938 -240.727845)
			(xy 350.659922 -240.710393) (xy 350.617301 -240.685786) (xy 350.57918 -240.654661) (xy 350.546545 -240.617824)
			(xy 350.520242 -240.576228) (xy 350.500951 -240.530952) (xy 350.489174 -240.483168) (xy 350.485214 -240.434114)
			(xy 350.156526 -240.434114) (xy 350.156031 -240.458721) (xy 350.148136 -240.507298) (xy 350.132552 -240.553979)
			(xy 350.109681 -240.597556) (xy 350.080116 -240.6369) (xy 350.044623 -240.670992) (xy 350.00412 -240.698948)
			(xy 349.959658 -240.720046) (xy 349.912387 -240.733738) (xy 349.863532 -240.73967) (xy 349.814357 -240.737689)
			(xy 349.766138 -240.727845) (xy 349.720122 -240.710393) (xy 349.677501 -240.685786) (xy 349.63938 -240.654661)
			(xy 349.606745 -240.617824) (xy 349.580442 -240.576228) (xy 349.561151 -240.530952) (xy 349.549374 -240.483168)
			(xy 349.545414 -240.434114) (xy 349.216472 -240.434114) (xy 349.215977 -240.458721) (xy 349.208082 -240.507298)
			(xy 349.192498 -240.553979) (xy 349.169627 -240.597556) (xy 349.140062 -240.6369) (xy 349.104569 -240.670992)
			(xy 349.064066 -240.698948) (xy 349.019604 -240.720046) (xy 348.972333 -240.733738) (xy 348.923478 -240.73967)
			(xy 348.874303 -240.737689) (xy 348.826084 -240.727845) (xy 348.780068 -240.710393) (xy 348.737447 -240.685786)
			(xy 348.699326 -240.654661) (xy 348.666691 -240.617824) (xy 348.640388 -240.576228) (xy 348.621097 -240.530952)
			(xy 348.60932 -240.483168) (xy 348.60536 -240.434114) (xy 348.276418 -240.434114) (xy 348.275923 -240.458721)
			(xy 348.268028 -240.507298) (xy 348.252444 -240.553979) (xy 348.229573 -240.597556) (xy 348.200008 -240.6369)
			(xy 348.164515 -240.670992) (xy 348.124012 -240.698948) (xy 348.07955 -240.720046) (xy 348.032279 -240.733738)
			(xy 347.983424 -240.73967) (xy 347.934249 -240.737689) (xy 347.88603 -240.727845) (xy 347.840014 -240.710393)
			(xy 347.797393 -240.685786) (xy 347.759272 -240.654661) (xy 347.726637 -240.617824) (xy 347.700334 -240.576228)
			(xy 347.681043 -240.530952) (xy 347.669266 -240.483168) (xy 347.665306 -240.434114) (xy 347.336364 -240.434114)
			(xy 347.335869 -240.458721) (xy 347.327974 -240.507298) (xy 347.31239 -240.553979) (xy 347.289519 -240.597556)
			(xy 347.259954 -240.6369) (xy 347.224461 -240.670992) (xy 347.183958 -240.698948) (xy 347.139496 -240.720046)
			(xy 347.092225 -240.733738) (xy 347.04337 -240.73967) (xy 346.994195 -240.737689) (xy 346.945976 -240.727845)
			(xy 346.89996 -240.710393) (xy 346.857339 -240.685786) (xy 346.819218 -240.654661) (xy 346.786583 -240.617824)
			(xy 346.76028 -240.576228) (xy 346.740989 -240.530952) (xy 346.729212 -240.483168) (xy 346.725252 -240.434114)
			(xy 346.39631 -240.434114) (xy 346.395815 -240.458721) (xy 346.38792 -240.507298) (xy 346.372336 -240.553979)
			(xy 346.349465 -240.597556) (xy 346.3199 -240.6369) (xy 346.284407 -240.670992) (xy 346.243904 -240.698948)
			(xy 346.199442 -240.720046) (xy 346.152171 -240.733738) (xy 346.103316 -240.73967) (xy 346.054141 -240.737689)
			(xy 346.005922 -240.727845) (xy 345.959906 -240.710393) (xy 345.917285 -240.685786) (xy 345.879164 -240.654661)
			(xy 345.846529 -240.617824) (xy 345.820226 -240.576228) (xy 345.800935 -240.530952) (xy 345.789158 -240.483168)
			(xy 345.785198 -240.434114) (xy 345.45651 -240.434114) (xy 345.456015 -240.458721) (xy 345.44812 -240.507298)
			(xy 345.432536 -240.553979) (xy 345.409665 -240.597556) (xy 345.3801 -240.6369) (xy 345.344607 -240.670992)
			(xy 345.304104 -240.698948) (xy 345.259642 -240.720046) (xy 345.212371 -240.733738) (xy 345.163516 -240.73967)
			(xy 345.114341 -240.737689) (xy 345.066122 -240.727845) (xy 345.020106 -240.710393) (xy 344.977485 -240.685786)
			(xy 344.939364 -240.654661) (xy 344.906729 -240.617824) (xy 344.880426 -240.576228) (xy 344.861135 -240.530952)
			(xy 344.849358 -240.483168) (xy 344.845398 -240.434114) (xy 344.626438 -240.434114) (xy 344.626438 -240.867438)
			(xy 344.626887 -240.877593) (xy 344.634749 -240.896321) (xy 344.641678 -240.90376) (xy 344.669618 -240.931192)
			(xy 344.686636 -240.938812) (xy 344.696034 -240.939066) (xy 344.720451 -240.940753) (xy 344.768324 -240.950928)
			(xy 344.813962 -240.968606) (xy 344.856195 -240.993337) (xy 344.893945 -241.024486) (xy 344.926243 -241.061258)
			(xy 344.952264 -241.102709) (xy 344.971341 -241.14778) (xy 344.982986 -241.195316) (xy 344.986901 -241.244101)
			(xy 344.986899 -241.24412) (xy 345.315298 -241.24412) (xy 345.319258 -241.195066) (xy 345.331035 -241.147282)
			(xy 345.350326 -241.102006) (xy 345.376629 -241.06041) (xy 345.409264 -241.023573) (xy 345.447385 -240.992448)
			(xy 345.490006 -240.967841) (xy 345.536022 -240.950389) (xy 345.584241 -240.940545) (xy 345.633416 -240.938564)
			(xy 345.682271 -240.944496) (xy 345.729542 -240.958188) (xy 345.774004 -240.979286) (xy 345.814507 -241.007242)
			(xy 345.85 -241.041334) (xy 345.879565 -241.080678) (xy 345.902436 -241.124255) (xy 345.91802 -241.170936)
			(xy 345.925915 -241.219513) (xy 345.92641 -241.24412) (xy 346.255352 -241.24412) (xy 346.259312 -241.195066)
			(xy 346.271089 -241.147282) (xy 346.29038 -241.102006) (xy 346.316683 -241.06041) (xy 346.349318 -241.023573)
			(xy 346.387439 -240.992448) (xy 346.43006 -240.967841) (xy 346.476076 -240.950389) (xy 346.524295 -240.940545)
			(xy 346.57347 -240.938564) (xy 346.622325 -240.944496) (xy 346.669596 -240.958188) (xy 346.714058 -240.979286)
			(xy 346.754561 -241.007242) (xy 346.790054 -241.041334) (xy 346.819619 -241.080678) (xy 346.84249 -241.124255)
			(xy 346.858074 -241.170936) (xy 346.865969 -241.219513) (xy 346.866464 -241.24412) (xy 347.195406 -241.24412)
			(xy 347.199366 -241.195066) (xy 347.211143 -241.147282) (xy 347.230434 -241.102006) (xy 347.256737 -241.06041)
			(xy 347.289372 -241.023573) (xy 347.327493 -240.992448) (xy 347.370114 -240.967841) (xy 347.41613 -240.950389)
			(xy 347.464349 -240.940545) (xy 347.513524 -240.938564) (xy 347.562379 -240.944496) (xy 347.60965 -240.958188)
			(xy 347.654112 -240.979286) (xy 347.694615 -241.007242) (xy 347.730108 -241.041334) (xy 347.759673 -241.080678)
			(xy 347.782544 -241.124255) (xy 347.798128 -241.170936) (xy 347.806023 -241.219513) (xy 347.806518 -241.24412)
			(xy 348.135206 -241.24412) (xy 348.139166 -241.195066) (xy 348.150943 -241.147282) (xy 348.170234 -241.102006)
			(xy 348.196537 -241.06041) (xy 348.229172 -241.023573) (xy 348.267293 -240.992448) (xy 348.309914 -240.967841)
			(xy 348.35593 -240.950389) (xy 348.404149 -240.940545) (xy 348.453324 -240.938564) (xy 348.502179 -240.944496)
			(xy 348.54945 -240.958188) (xy 348.593912 -240.979286) (xy 348.634415 -241.007242) (xy 348.669908 -241.041334)
			(xy 348.699473 -241.080678) (xy 348.722344 -241.124255) (xy 348.737928 -241.170936) (xy 348.745823 -241.219513)
			(xy 348.746318 -241.24412) (xy 349.07526 -241.24412) (xy 349.07922 -241.195066) (xy 349.090997 -241.147282)
			(xy 349.110288 -241.102006) (xy 349.136591 -241.06041) (xy 349.169226 -241.023573) (xy 349.207347 -240.992448)
			(xy 349.249968 -240.967841) (xy 349.295984 -240.950389) (xy 349.344203 -240.940545) (xy 349.393378 -240.938564)
			(xy 349.442233 -240.944496) (xy 349.489504 -240.958188) (xy 349.533966 -240.979286) (xy 349.574469 -241.007242)
			(xy 349.609962 -241.041334) (xy 349.639527 -241.080678) (xy 349.662398 -241.124255) (xy 349.677982 -241.170936)
			(xy 349.685877 -241.219513) (xy 349.686372 -241.24412) (xy 350.015314 -241.24412) (xy 350.019274 -241.195066)
			(xy 350.031051 -241.147282) (xy 350.050342 -241.102006) (xy 350.076645 -241.06041) (xy 350.10928 -241.023573)
			(xy 350.147401 -240.992448) (xy 350.190022 -240.967841) (xy 350.236038 -240.950389) (xy 350.284257 -240.940545)
			(xy 350.333432 -240.938564) (xy 350.382287 -240.944496) (xy 350.429558 -240.958188) (xy 350.47402 -240.979286)
			(xy 350.514523 -241.007242) (xy 350.550016 -241.041334) (xy 350.579581 -241.080678) (xy 350.602452 -241.124255)
			(xy 350.618036 -241.170936) (xy 350.625931 -241.219513) (xy 350.626426 -241.24412) (xy 350.955368 -241.24412)
			(xy 350.959328 -241.195066) (xy 350.971105 -241.147282) (xy 350.990396 -241.102006) (xy 351.016699 -241.06041)
			(xy 351.049334 -241.023573) (xy 351.087455 -240.992448) (xy 351.130076 -240.967841) (xy 351.176092 -240.950389)
			(xy 351.224311 -240.940545) (xy 351.273486 -240.938564) (xy 351.322341 -240.944496) (xy 351.369612 -240.958188)
			(xy 351.414074 -240.979286) (xy 351.454577 -241.007242) (xy 351.49007 -241.041334) (xy 351.519635 -241.080678)
			(xy 351.542506 -241.124255) (xy 351.55809 -241.170936) (xy 351.565985 -241.219513) (xy 351.56648 -241.24412)
			(xy 351.895422 -241.24412) (xy 351.899382 -241.195066) (xy 351.911159 -241.147282) (xy 351.93045 -241.102006)
			(xy 351.956753 -241.06041) (xy 351.989388 -241.023573) (xy 352.027509 -240.992448) (xy 352.07013 -240.967841)
			(xy 352.116146 -240.950389) (xy 352.164365 -240.940545) (xy 352.21354 -240.938564) (xy 352.262395 -240.944496)
			(xy 352.309666 -240.958188) (xy 352.354128 -240.979286) (xy 352.394631 -241.007242) (xy 352.430124 -241.041334)
			(xy 352.459689 -241.080678) (xy 352.48256 -241.124255) (xy 352.498144 -241.170936) (xy 352.506039 -241.219513)
			(xy 352.506534 -241.24412) (xy 352.835222 -241.24412) (xy 352.839182 -241.195066) (xy 352.850959 -241.147282)
			(xy 352.87025 -241.102006) (xy 352.896553 -241.06041) (xy 352.929188 -241.023573) (xy 352.967309 -240.992448)
			(xy 353.00993 -240.967841) (xy 353.055946 -240.950389) (xy 353.104165 -240.940545) (xy 353.15334 -240.938564)
			(xy 353.202195 -240.944496) (xy 353.249466 -240.958188) (xy 353.293928 -240.979286) (xy 353.334431 -241.007242)
			(xy 353.369924 -241.041334) (xy 353.399489 -241.080678) (xy 353.42236 -241.124255) (xy 353.437944 -241.170936)
			(xy 353.445839 -241.219513) (xy 353.446334 -241.24412) (xy 353.775276 -241.24412) (xy 353.779236 -241.195066)
			(xy 353.791013 -241.147282) (xy 353.810304 -241.102006) (xy 353.836607 -241.06041) (xy 353.869242 -241.023573)
			(xy 353.907363 -240.992448) (xy 353.949984 -240.967841) (xy 353.996 -240.950389) (xy 354.044219 -240.940545)
			(xy 354.093394 -240.938564) (xy 354.142249 -240.944496) (xy 354.18952 -240.958188) (xy 354.233982 -240.979286)
			(xy 354.274485 -241.007242) (xy 354.309978 -241.041334) (xy 354.339543 -241.080678) (xy 354.362414 -241.124255)
			(xy 354.377998 -241.170936) (xy 354.385893 -241.219513) (xy 354.386388 -241.24412) (xy 354.71533 -241.24412)
			(xy 354.71929 -241.195066) (xy 354.731067 -241.147282) (xy 354.750358 -241.102006) (xy 354.776661 -241.06041)
			(xy 354.809296 -241.023573) (xy 354.847417 -240.992448) (xy 354.890038 -240.967841) (xy 354.936054 -240.950389)
			(xy 354.984273 -240.940545) (xy 355.033448 -240.938564) (xy 355.082303 -240.944496) (xy 355.129574 -240.958188)
			(xy 355.174036 -240.979286) (xy 355.214539 -241.007242) (xy 355.250032 -241.041334) (xy 355.279597 -241.080678)
			(xy 355.302468 -241.124255) (xy 355.318052 -241.170936) (xy 355.325947 -241.219513) (xy 355.326442 -241.24412)
			(xy 355.655384 -241.24412) (xy 355.659344 -241.195066) (xy 355.671121 -241.147282) (xy 355.690412 -241.102006)
			(xy 355.716715 -241.06041) (xy 355.74935 -241.023573) (xy 355.787471 -240.992448) (xy 355.830092 -240.967841)
			(xy 355.876108 -240.950389) (xy 355.924327 -240.940545) (xy 355.973502 -240.938564) (xy 356.022357 -240.944496)
			(xy 356.069628 -240.958188) (xy 356.11409 -240.979286) (xy 356.154593 -241.007242) (xy 356.190086 -241.041334)
			(xy 356.219651 -241.080678) (xy 356.242522 -241.124255) (xy 356.258106 -241.170936) (xy 356.266001 -241.219513)
			(xy 356.266496 -241.24412) (xy 356.595438 -241.24412) (xy 356.599398 -241.195066) (xy 356.611175 -241.147282)
			(xy 356.630466 -241.102006) (xy 356.656769 -241.06041) (xy 356.689404 -241.023573) (xy 356.727525 -240.992448)
			(xy 356.770146 -240.967841) (xy 356.816162 -240.950389) (xy 356.864381 -240.940545) (xy 356.913556 -240.938564)
			(xy 356.962411 -240.944496) (xy 357.009682 -240.958188) (xy 357.054144 -240.979286) (xy 357.094647 -241.007242)
			(xy 357.13014 -241.041334) (xy 357.159705 -241.080678) (xy 357.182576 -241.124255) (xy 357.19816 -241.170936)
			(xy 357.206055 -241.219513) (xy 357.20655 -241.24412) (xy 357.535238 -241.24412) (xy 357.539198 -241.195066)
			(xy 357.550975 -241.147282) (xy 357.570266 -241.102006) (xy 357.596569 -241.06041) (xy 357.629204 -241.023573)
			(xy 357.667325 -240.992448) (xy 357.709946 -240.967841) (xy 357.755962 -240.950389) (xy 357.804181 -240.940545)
			(xy 357.853356 -240.938564) (xy 357.902211 -240.944496) (xy 357.949482 -240.958188) (xy 357.993944 -240.979286)
			(xy 358.034447 -241.007242) (xy 358.06994 -241.041334) (xy 358.099505 -241.080678) (xy 358.122376 -241.124255)
			(xy 358.13796 -241.170936) (xy 358.145855 -241.219513) (xy 358.14635 -241.24412) (xy 361.289104 -241.24412)
			(xy 361.293064 -241.195066) (xy 361.304841 -241.147282) (xy 361.324132 -241.102006) (xy 361.350435 -241.06041)
			(xy 361.38307 -241.023573) (xy 361.421191 -240.992448) (xy 361.463812 -240.967841) (xy 361.509828 -240.950389)
			(xy 361.558047 -240.940545) (xy 361.607222 -240.938564) (xy 361.656077 -240.944496) (xy 361.703348 -240.958188)
			(xy 361.74781 -240.979286) (xy 361.788313 -241.007242) (xy 361.823806 -241.041334) (xy 361.853371 -241.080678)
			(xy 361.876242 -241.124255) (xy 361.891826 -241.170936) (xy 361.899721 -241.219513) (xy 361.900216 -241.24412)
			(xy 362.228904 -241.24412) (xy 362.232864 -241.195066) (xy 362.244641 -241.147282) (xy 362.263932 -241.102006)
			(xy 362.290235 -241.06041) (xy 362.32287 -241.023573) (xy 362.360991 -240.992448) (xy 362.403612 -240.967841)
			(xy 362.449628 -240.950389) (xy 362.497847 -240.940545) (xy 362.547022 -240.938564) (xy 362.595877 -240.944496)
			(xy 362.643148 -240.958188) (xy 362.68761 -240.979286) (xy 362.728113 -241.007242) (xy 362.763606 -241.041334)
			(xy 362.793171 -241.080678) (xy 362.816042 -241.124255) (xy 362.831626 -241.170936) (xy 362.839521 -241.219513)
			(xy 362.840016 -241.24412) (xy 363.168958 -241.24412) (xy 363.172918 -241.195066) (xy 363.184695 -241.147282)
			(xy 363.203986 -241.102006) (xy 363.230289 -241.06041) (xy 363.262924 -241.023573) (xy 363.301045 -240.992448)
			(xy 363.343666 -240.967841) (xy 363.389682 -240.950389) (xy 363.437901 -240.940545) (xy 363.487076 -240.938564)
			(xy 363.535931 -240.944496) (xy 363.583202 -240.958188) (xy 363.627664 -240.979286) (xy 363.668167 -241.007242)
			(xy 363.70366 -241.041334) (xy 363.733225 -241.080678) (xy 363.756096 -241.124255) (xy 363.77168 -241.170936)
			(xy 363.779575 -241.219513) (xy 363.78007 -241.24412) (xy 364.109012 -241.24412) (xy 364.112972 -241.195066)
			(xy 364.124749 -241.147282) (xy 364.14404 -241.102006) (xy 364.170343 -241.06041) (xy 364.202978 -241.023573)
			(xy 364.241099 -240.992448) (xy 364.28372 -240.967841) (xy 364.329736 -240.950389) (xy 364.377955 -240.940545)
			(xy 364.42713 -240.938564) (xy 364.475985 -240.944496) (xy 364.523256 -240.958188) (xy 364.567718 -240.979286)
			(xy 364.608221 -241.007242) (xy 364.643714 -241.041334) (xy 364.673279 -241.080678) (xy 364.69615 -241.124255)
			(xy 364.711734 -241.170936) (xy 364.719629 -241.219513) (xy 364.720124 -241.24412) (xy 365.049066 -241.24412)
			(xy 365.053026 -241.195066) (xy 365.064803 -241.147282) (xy 365.084094 -241.102006) (xy 365.110397 -241.06041)
			(xy 365.143032 -241.023573) (xy 365.181153 -240.992448) (xy 365.223774 -240.967841) (xy 365.26979 -240.950389)
			(xy 365.318009 -240.940545) (xy 365.367184 -240.938564) (xy 365.416039 -240.944496) (xy 365.46331 -240.958188)
			(xy 365.507772 -240.979286) (xy 365.548275 -241.007242) (xy 365.583768 -241.041334) (xy 365.613333 -241.080678)
			(xy 365.636204 -241.124255) (xy 365.651788 -241.170936) (xy 365.659683 -241.219513) (xy 365.660178 -241.24412)
			(xy 365.98912 -241.24412) (xy 365.99308 -241.195066) (xy 366.004857 -241.147282) (xy 366.024148 -241.102006)
			(xy 366.050451 -241.06041) (xy 366.083086 -241.023573) (xy 366.121207 -240.992448) (xy 366.163828 -240.967841)
			(xy 366.209844 -240.950389) (xy 366.258063 -240.940545) (xy 366.307238 -240.938564) (xy 366.356093 -240.944496)
			(xy 366.403364 -240.958188) (xy 366.447826 -240.979286) (xy 366.488329 -241.007242) (xy 366.523822 -241.041334)
			(xy 366.553387 -241.080678) (xy 366.576258 -241.124255) (xy 366.591842 -241.170936) (xy 366.599737 -241.219513)
			(xy 366.600232 -241.24412) (xy 366.92892 -241.24412) (xy 366.93288 -241.195066) (xy 366.944657 -241.147282)
			(xy 366.963948 -241.102006) (xy 366.990251 -241.06041) (xy 367.022886 -241.023573) (xy 367.061007 -240.992448)
			(xy 367.103628 -240.967841) (xy 367.149644 -240.950389) (xy 367.197863 -240.940545) (xy 367.247038 -240.938564)
			(xy 367.295893 -240.944496) (xy 367.343164 -240.958188) (xy 367.387626 -240.979286) (xy 367.428129 -241.007242)
			(xy 367.463622 -241.041334) (xy 367.493187 -241.080678) (xy 367.516058 -241.124255) (xy 367.531642 -241.170936)
			(xy 367.539537 -241.219513) (xy 367.540032 -241.24412) (xy 367.868974 -241.24412) (xy 367.872934 -241.195066)
			(xy 367.884711 -241.147282) (xy 367.904002 -241.102006) (xy 367.930305 -241.06041) (xy 367.96294 -241.023573)
			(xy 368.001061 -240.992448) (xy 368.043682 -240.967841) (xy 368.089698 -240.950389) (xy 368.137917 -240.940545)
			(xy 368.187092 -240.938564) (xy 368.235947 -240.944496) (xy 368.283218 -240.958188) (xy 368.32768 -240.979286)
			(xy 368.368183 -241.007242) (xy 368.403676 -241.041334) (xy 368.433241 -241.080678) (xy 368.456112 -241.124255)
			(xy 368.471696 -241.170936) (xy 368.479591 -241.219513) (xy 368.480086 -241.24412) (xy 368.809028 -241.24412)
			(xy 368.812988 -241.195066) (xy 368.824765 -241.147282) (xy 368.844056 -241.102006) (xy 368.870359 -241.06041)
			(xy 368.902994 -241.023573) (xy 368.941115 -240.992448) (xy 368.983736 -240.967841) (xy 369.029752 -240.950389)
			(xy 369.077971 -240.940545) (xy 369.127146 -240.938564) (xy 369.176001 -240.944496) (xy 369.223272 -240.958188)
			(xy 369.267734 -240.979286) (xy 369.308237 -241.007242) (xy 369.34373 -241.041334) (xy 369.373295 -241.080678)
			(xy 369.396166 -241.124255) (xy 369.41175 -241.170936) (xy 369.419645 -241.219513) (xy 369.42014 -241.24412)
			(xy 369.749082 -241.24412) (xy 369.753042 -241.195066) (xy 369.764819 -241.147282) (xy 369.78411 -241.102006)
			(xy 369.810413 -241.06041) (xy 369.843048 -241.023573) (xy 369.881169 -240.992448) (xy 369.92379 -240.967841)
			(xy 369.969806 -240.950389) (xy 370.018025 -240.940545) (xy 370.0672 -240.938564) (xy 370.116055 -240.944496)
			(xy 370.163326 -240.958188) (xy 370.207788 -240.979286) (xy 370.248291 -241.007242) (xy 370.283784 -241.041334)
			(xy 370.313349 -241.080678) (xy 370.33622 -241.124255) (xy 370.351804 -241.170936) (xy 370.359699 -241.219513)
			(xy 370.360194 -241.24412) (xy 370.688882 -241.24412) (xy 370.692842 -241.195066) (xy 370.704619 -241.147282)
			(xy 370.72391 -241.102006) (xy 370.750213 -241.06041) (xy 370.782848 -241.023573) (xy 370.820969 -240.992448)
			(xy 370.86359 -240.967841) (xy 370.909606 -240.950389) (xy 370.957825 -240.940545) (xy 371.007 -240.938564)
			(xy 371.055855 -240.944496) (xy 371.103126 -240.958188) (xy 371.147588 -240.979286) (xy 371.188091 -241.007242)
			(xy 371.223584 -241.041334) (xy 371.253149 -241.080678) (xy 371.27602 -241.124255) (xy 371.291604 -241.170936)
			(xy 371.299499 -241.219513) (xy 371.299994 -241.24412) (xy 371.628936 -241.24412) (xy 371.632896 -241.195066)
			(xy 371.644673 -241.147282) (xy 371.663964 -241.102006) (xy 371.690267 -241.06041) (xy 371.722902 -241.023573)
			(xy 371.761023 -240.992448) (xy 371.803644 -240.967841) (xy 371.84966 -240.950389) (xy 371.897879 -240.940545)
			(xy 371.947054 -240.938564) (xy 371.995909 -240.944496) (xy 372.04318 -240.958188) (xy 372.087642 -240.979286)
			(xy 372.128145 -241.007242) (xy 372.163638 -241.041334) (xy 372.193203 -241.080678) (xy 372.216074 -241.124255)
			(xy 372.231658 -241.170936) (xy 372.239553 -241.219513) (xy 372.240048 -241.24412) (xy 372.56899 -241.24412)
			(xy 372.57295 -241.195066) (xy 372.584727 -241.147282) (xy 372.604018 -241.102006) (xy 372.630321 -241.06041)
			(xy 372.662956 -241.023573) (xy 372.701077 -240.992448) (xy 372.743698 -240.967841) (xy 372.789714 -240.950389)
			(xy 372.837933 -240.940545) (xy 372.887108 -240.938564) (xy 372.935963 -240.944496) (xy 372.983234 -240.958188)
			(xy 373.027696 -240.979286) (xy 373.068199 -241.007242) (xy 373.103692 -241.041334) (xy 373.133257 -241.080678)
			(xy 373.156128 -241.124255) (xy 373.171712 -241.170936) (xy 373.179607 -241.219513) (xy 373.180102 -241.24412)
			(xy 373.509044 -241.24412) (xy 373.513004 -241.195066) (xy 373.524781 -241.147282) (xy 373.544072 -241.102006)
			(xy 373.570375 -241.06041) (xy 373.60301 -241.023573) (xy 373.641131 -240.992448) (xy 373.683752 -240.967841)
			(xy 373.729768 -240.950389) (xy 373.777987 -240.940545) (xy 373.827162 -240.938564) (xy 373.876017 -240.944496)
			(xy 373.923288 -240.958188) (xy 373.96775 -240.979286) (xy 374.008253 -241.007242) (xy 374.043746 -241.041334)
			(xy 374.073311 -241.080678) (xy 374.096182 -241.124255) (xy 374.111766 -241.170936) (xy 374.119661 -241.219513)
			(xy 374.120156 -241.24412) (xy 374.119661 -241.268727) (xy 374.111766 -241.317304) (xy 374.096182 -241.363985)
			(xy 374.073311 -241.407562) (xy 374.043746 -241.446906) (xy 374.008253 -241.480998) (xy 373.96775 -241.508954)
			(xy 373.923288 -241.530052) (xy 373.876017 -241.543744) (xy 373.827162 -241.549676) (xy 373.777987 -241.547695)
			(xy 373.729768 -241.537851) (xy 373.683752 -241.520399) (xy 373.641131 -241.495792) (xy 373.60301 -241.464667)
			(xy 373.570375 -241.42783) (xy 373.544072 -241.386234) (xy 373.524781 -241.340958) (xy 373.513004 -241.293174)
			(xy 373.509044 -241.24412) (xy 373.180102 -241.24412) (xy 373.179607 -241.268727) (xy 373.171712 -241.317304)
			(xy 373.156128 -241.363985) (xy 373.133257 -241.407562) (xy 373.103692 -241.446906) (xy 373.068199 -241.480998)
			(xy 373.027696 -241.508954) (xy 372.983234 -241.530052) (xy 372.935963 -241.543744) (xy 372.887108 -241.549676)
			(xy 372.837933 -241.547695) (xy 372.789714 -241.537851) (xy 372.743698 -241.520399) (xy 372.701077 -241.495792)
			(xy 372.662956 -241.464667) (xy 372.630321 -241.42783) (xy 372.604018 -241.386234) (xy 372.584727 -241.340958)
			(xy 372.57295 -241.293174) (xy 372.56899 -241.24412) (xy 372.240048 -241.24412) (xy 372.239553 -241.268727)
			(xy 372.231658 -241.317304) (xy 372.216074 -241.363985) (xy 372.193203 -241.407562) (xy 372.163638 -241.446906)
			(xy 372.128145 -241.480998) (xy 372.087642 -241.508954) (xy 372.04318 -241.530052) (xy 371.995909 -241.543744)
			(xy 371.947054 -241.549676) (xy 371.897879 -241.547695) (xy 371.84966 -241.537851) (xy 371.803644 -241.520399)
			(xy 371.761023 -241.495792) (xy 371.722902 -241.464667) (xy 371.690267 -241.42783) (xy 371.663964 -241.386234)
			(xy 371.644673 -241.340958) (xy 371.632896 -241.293174) (xy 371.628936 -241.24412) (xy 371.299994 -241.24412)
			(xy 371.299499 -241.268727) (xy 371.291604 -241.317304) (xy 371.27602 -241.363985) (xy 371.253149 -241.407562)
			(xy 371.223584 -241.446906) (xy 371.188091 -241.480998) (xy 371.147588 -241.508954) (xy 371.103126 -241.530052)
			(xy 371.055855 -241.543744) (xy 371.007 -241.549676) (xy 370.957825 -241.547695) (xy 370.909606 -241.537851)
			(xy 370.86359 -241.520399) (xy 370.820969 -241.495792) (xy 370.782848 -241.464667) (xy 370.750213 -241.42783)
			(xy 370.72391 -241.386234) (xy 370.704619 -241.340958) (xy 370.692842 -241.293174) (xy 370.688882 -241.24412)
			(xy 370.360194 -241.24412) (xy 370.359699 -241.268727) (xy 370.351804 -241.317304) (xy 370.33622 -241.363985)
			(xy 370.313349 -241.407562) (xy 370.283784 -241.446906) (xy 370.248291 -241.480998) (xy 370.207788 -241.508954)
			(xy 370.163326 -241.530052) (xy 370.116055 -241.543744) (xy 370.0672 -241.549676) (xy 370.018025 -241.547695)
			(xy 369.969806 -241.537851) (xy 369.92379 -241.520399) (xy 369.881169 -241.495792) (xy 369.843048 -241.464667)
			(xy 369.810413 -241.42783) (xy 369.78411 -241.386234) (xy 369.764819 -241.340958) (xy 369.753042 -241.293174)
			(xy 369.749082 -241.24412) (xy 369.42014 -241.24412) (xy 369.419645 -241.268727) (xy 369.41175 -241.317304)
			(xy 369.396166 -241.363985) (xy 369.373295 -241.407562) (xy 369.34373 -241.446906) (xy 369.308237 -241.480998)
			(xy 369.267734 -241.508954) (xy 369.223272 -241.530052) (xy 369.176001 -241.543744) (xy 369.127146 -241.549676)
			(xy 369.077971 -241.547695) (xy 369.029752 -241.537851) (xy 368.983736 -241.520399) (xy 368.941115 -241.495792)
			(xy 368.902994 -241.464667) (xy 368.870359 -241.42783) (xy 368.844056 -241.386234) (xy 368.824765 -241.340958)
			(xy 368.812988 -241.293174) (xy 368.809028 -241.24412) (xy 368.480086 -241.24412) (xy 368.479591 -241.268727)
			(xy 368.471696 -241.317304) (xy 368.456112 -241.363985) (xy 368.433241 -241.407562) (xy 368.403676 -241.446906)
			(xy 368.368183 -241.480998) (xy 368.32768 -241.508954) (xy 368.283218 -241.530052) (xy 368.235947 -241.543744)
			(xy 368.187092 -241.549676) (xy 368.137917 -241.547695) (xy 368.089698 -241.537851) (xy 368.043682 -241.520399)
			(xy 368.001061 -241.495792) (xy 367.96294 -241.464667) (xy 367.930305 -241.42783) (xy 367.904002 -241.386234)
			(xy 367.884711 -241.340958) (xy 367.872934 -241.293174) (xy 367.868974 -241.24412) (xy 367.540032 -241.24412)
			(xy 367.539537 -241.268727) (xy 367.531642 -241.317304) (xy 367.516058 -241.363985) (xy 367.493187 -241.407562)
			(xy 367.463622 -241.446906) (xy 367.428129 -241.480998) (xy 367.387626 -241.508954) (xy 367.343164 -241.530052)
			(xy 367.295893 -241.543744) (xy 367.247038 -241.549676) (xy 367.197863 -241.547695) (xy 367.149644 -241.537851)
			(xy 367.103628 -241.520399) (xy 367.061007 -241.495792) (xy 367.022886 -241.464667) (xy 366.990251 -241.42783)
			(xy 366.963948 -241.386234) (xy 366.944657 -241.340958) (xy 366.93288 -241.293174) (xy 366.92892 -241.24412)
			(xy 366.600232 -241.24412) (xy 366.599737 -241.268727) (xy 366.591842 -241.317304) (xy 366.576258 -241.363985)
			(xy 366.553387 -241.407562) (xy 366.523822 -241.446906) (xy 366.488329 -241.480998) (xy 366.447826 -241.508954)
			(xy 366.403364 -241.530052) (xy 366.356093 -241.543744) (xy 366.307238 -241.549676) (xy 366.258063 -241.547695)
			(xy 366.209844 -241.537851) (xy 366.163828 -241.520399) (xy 366.121207 -241.495792) (xy 366.083086 -241.464667)
			(xy 366.050451 -241.42783) (xy 366.024148 -241.386234) (xy 366.004857 -241.340958) (xy 365.99308 -241.293174)
			(xy 365.98912 -241.24412) (xy 365.660178 -241.24412) (xy 365.659683 -241.268727) (xy 365.651788 -241.317304)
			(xy 365.636204 -241.363985) (xy 365.613333 -241.407562) (xy 365.583768 -241.446906) (xy 365.548275 -241.480998)
			(xy 365.507772 -241.508954) (xy 365.46331 -241.530052) (xy 365.416039 -241.543744) (xy 365.367184 -241.549676)
			(xy 365.318009 -241.547695) (xy 365.26979 -241.537851) (xy 365.223774 -241.520399) (xy 365.181153 -241.495792)
			(xy 365.143032 -241.464667) (xy 365.110397 -241.42783) (xy 365.084094 -241.386234) (xy 365.064803 -241.340958)
			(xy 365.053026 -241.293174) (xy 365.049066 -241.24412) (xy 364.720124 -241.24412) (xy 364.719629 -241.268727)
			(xy 364.711734 -241.317304) (xy 364.69615 -241.363985) (xy 364.673279 -241.407562) (xy 364.643714 -241.446906)
			(xy 364.608221 -241.480998) (xy 364.567718 -241.508954) (xy 364.523256 -241.530052) (xy 364.475985 -241.543744)
			(xy 364.42713 -241.549676) (xy 364.377955 -241.547695) (xy 364.329736 -241.537851) (xy 364.28372 -241.520399)
			(xy 364.241099 -241.495792) (xy 364.202978 -241.464667) (xy 364.170343 -241.42783) (xy 364.14404 -241.386234)
			(xy 364.124749 -241.340958) (xy 364.112972 -241.293174) (xy 364.109012 -241.24412) (xy 363.78007 -241.24412)
			(xy 363.779575 -241.268727) (xy 363.77168 -241.317304) (xy 363.756096 -241.363985) (xy 363.733225 -241.407562)
			(xy 363.70366 -241.446906) (xy 363.668167 -241.480998) (xy 363.627664 -241.508954) (xy 363.583202 -241.530052)
			(xy 363.535931 -241.543744) (xy 363.487076 -241.549676) (xy 363.437901 -241.547695) (xy 363.389682 -241.537851)
			(xy 363.343666 -241.520399) (xy 363.301045 -241.495792) (xy 363.262924 -241.464667) (xy 363.230289 -241.42783)
			(xy 363.203986 -241.386234) (xy 363.184695 -241.340958) (xy 363.172918 -241.293174) (xy 363.168958 -241.24412)
			(xy 362.840016 -241.24412) (xy 362.839521 -241.268727) (xy 362.831626 -241.317304) (xy 362.816042 -241.363985)
			(xy 362.793171 -241.407562) (xy 362.763606 -241.446906) (xy 362.728113 -241.480998) (xy 362.68761 -241.508954)
			(xy 362.643148 -241.530052) (xy 362.595877 -241.543744) (xy 362.547022 -241.549676) (xy 362.497847 -241.547695)
			(xy 362.449628 -241.537851) (xy 362.403612 -241.520399) (xy 362.360991 -241.495792) (xy 362.32287 -241.464667)
			(xy 362.290235 -241.42783) (xy 362.263932 -241.386234) (xy 362.244641 -241.340958) (xy 362.232864 -241.293174)
			(xy 362.228904 -241.24412) (xy 361.900216 -241.24412) (xy 361.899721 -241.268727) (xy 361.891826 -241.317304)
			(xy 361.876242 -241.363985) (xy 361.853371 -241.407562) (xy 361.823806 -241.446906) (xy 361.788313 -241.480998)
			(xy 361.74781 -241.508954) (xy 361.703348 -241.530052) (xy 361.656077 -241.543744) (xy 361.607222 -241.549676)
			(xy 361.558047 -241.547695) (xy 361.509828 -241.537851) (xy 361.463812 -241.520399) (xy 361.421191 -241.495792)
			(xy 361.38307 -241.464667) (xy 361.350435 -241.42783) (xy 361.324132 -241.386234) (xy 361.304841 -241.340958)
			(xy 361.293064 -241.293174) (xy 361.289104 -241.24412) (xy 358.14635 -241.24412) (xy 358.145855 -241.268727)
			(xy 358.13796 -241.317304) (xy 358.122376 -241.363985) (xy 358.099505 -241.407562) (xy 358.06994 -241.446906)
			(xy 358.034447 -241.480998) (xy 357.993944 -241.508954) (xy 357.949482 -241.530052) (xy 357.902211 -241.543744)
			(xy 357.853356 -241.549676) (xy 357.804181 -241.547695) (xy 357.755962 -241.537851) (xy 357.709946 -241.520399)
			(xy 357.667325 -241.495792) (xy 357.629204 -241.464667) (xy 357.596569 -241.42783) (xy 357.570266 -241.386234)
			(xy 357.550975 -241.340958) (xy 357.539198 -241.293174) (xy 357.535238 -241.24412) (xy 357.20655 -241.24412)
			(xy 357.206055 -241.268727) (xy 357.19816 -241.317304) (xy 357.182576 -241.363985) (xy 357.159705 -241.407562)
			(xy 357.13014 -241.446906) (xy 357.094647 -241.480998) (xy 357.054144 -241.508954) (xy 357.009682 -241.530052)
			(xy 356.962411 -241.543744) (xy 356.913556 -241.549676) (xy 356.864381 -241.547695) (xy 356.816162 -241.537851)
			(xy 356.770146 -241.520399) (xy 356.727525 -241.495792) (xy 356.689404 -241.464667) (xy 356.656769 -241.42783)
			(xy 356.630466 -241.386234) (xy 356.611175 -241.340958) (xy 356.599398 -241.293174) (xy 356.595438 -241.24412)
			(xy 356.266496 -241.24412) (xy 356.266001 -241.268727) (xy 356.258106 -241.317304) (xy 356.242522 -241.363985)
			(xy 356.219651 -241.407562) (xy 356.190086 -241.446906) (xy 356.154593 -241.480998) (xy 356.11409 -241.508954)
			(xy 356.069628 -241.530052) (xy 356.022357 -241.543744) (xy 355.973502 -241.549676) (xy 355.924327 -241.547695)
			(xy 355.876108 -241.537851) (xy 355.830092 -241.520399) (xy 355.787471 -241.495792) (xy 355.74935 -241.464667)
			(xy 355.716715 -241.42783) (xy 355.690412 -241.386234) (xy 355.671121 -241.340958) (xy 355.659344 -241.293174)
			(xy 355.655384 -241.24412) (xy 355.326442 -241.24412) (xy 355.325947 -241.268727) (xy 355.318052 -241.317304)
			(xy 355.302468 -241.363985) (xy 355.279597 -241.407562) (xy 355.250032 -241.446906) (xy 355.214539 -241.480998)
			(xy 355.174036 -241.508954) (xy 355.129574 -241.530052) (xy 355.082303 -241.543744) (xy 355.033448 -241.549676)
			(xy 354.984273 -241.547695) (xy 354.936054 -241.537851) (xy 354.890038 -241.520399) (xy 354.847417 -241.495792)
			(xy 354.809296 -241.464667) (xy 354.776661 -241.42783) (xy 354.750358 -241.386234) (xy 354.731067 -241.340958)
			(xy 354.71929 -241.293174) (xy 354.71533 -241.24412) (xy 354.386388 -241.24412) (xy 354.385893 -241.268727)
			(xy 354.377998 -241.317304) (xy 354.362414 -241.363985) (xy 354.339543 -241.407562) (xy 354.309978 -241.446906)
			(xy 354.274485 -241.480998) (xy 354.233982 -241.508954) (xy 354.18952 -241.530052) (xy 354.142249 -241.543744)
			(xy 354.093394 -241.549676) (xy 354.044219 -241.547695) (xy 353.996 -241.537851) (xy 353.949984 -241.520399)
			(xy 353.907363 -241.495792) (xy 353.869242 -241.464667) (xy 353.836607 -241.42783) (xy 353.810304 -241.386234)
			(xy 353.791013 -241.340958) (xy 353.779236 -241.293174) (xy 353.775276 -241.24412) (xy 353.446334 -241.24412)
			(xy 353.445839 -241.268727) (xy 353.437944 -241.317304) (xy 353.42236 -241.363985) (xy 353.399489 -241.407562)
			(xy 353.369924 -241.446906) (xy 353.334431 -241.480998) (xy 353.293928 -241.508954) (xy 353.249466 -241.530052)
			(xy 353.202195 -241.543744) (xy 353.15334 -241.549676) (xy 353.104165 -241.547695) (xy 353.055946 -241.537851)
			(xy 353.00993 -241.520399) (xy 352.967309 -241.495792) (xy 352.929188 -241.464667) (xy 352.896553 -241.42783)
			(xy 352.87025 -241.386234) (xy 352.850959 -241.340958) (xy 352.839182 -241.293174) (xy 352.835222 -241.24412)
			(xy 352.506534 -241.24412) (xy 352.506039 -241.268727) (xy 352.498144 -241.317304) (xy 352.48256 -241.363985)
			(xy 352.459689 -241.407562) (xy 352.430124 -241.446906) (xy 352.394631 -241.480998) (xy 352.354128 -241.508954)
			(xy 352.309666 -241.530052) (xy 352.262395 -241.543744) (xy 352.21354 -241.549676) (xy 352.164365 -241.547695)
			(xy 352.116146 -241.537851) (xy 352.07013 -241.520399) (xy 352.027509 -241.495792) (xy 351.989388 -241.464667)
			(xy 351.956753 -241.42783) (xy 351.93045 -241.386234) (xy 351.911159 -241.340958) (xy 351.899382 -241.293174)
			(xy 351.895422 -241.24412) (xy 351.56648 -241.24412) (xy 351.565985 -241.268727) (xy 351.55809 -241.317304)
			(xy 351.542506 -241.363985) (xy 351.519635 -241.407562) (xy 351.49007 -241.446906) (xy 351.454577 -241.480998)
			(xy 351.414074 -241.508954) (xy 351.369612 -241.530052) (xy 351.322341 -241.543744) (xy 351.273486 -241.549676)
			(xy 351.224311 -241.547695) (xy 351.176092 -241.537851) (xy 351.130076 -241.520399) (xy 351.087455 -241.495792)
			(xy 351.049334 -241.464667) (xy 351.016699 -241.42783) (xy 350.990396 -241.386234) (xy 350.971105 -241.340958)
			(xy 350.959328 -241.293174) (xy 350.955368 -241.24412) (xy 350.626426 -241.24412) (xy 350.625931 -241.268727)
			(xy 350.618036 -241.317304) (xy 350.602452 -241.363985) (xy 350.579581 -241.407562) (xy 350.550016 -241.446906)
			(xy 350.514523 -241.480998) (xy 350.47402 -241.508954) (xy 350.429558 -241.530052) (xy 350.382287 -241.543744)
			(xy 350.333432 -241.549676) (xy 350.284257 -241.547695) (xy 350.236038 -241.537851) (xy 350.190022 -241.520399)
			(xy 350.147401 -241.495792) (xy 350.10928 -241.464667) (xy 350.076645 -241.42783) (xy 350.050342 -241.386234)
			(xy 350.031051 -241.340958) (xy 350.019274 -241.293174) (xy 350.015314 -241.24412) (xy 349.686372 -241.24412)
			(xy 349.685877 -241.268727) (xy 349.677982 -241.317304) (xy 349.662398 -241.363985) (xy 349.639527 -241.407562)
			(xy 349.609962 -241.446906) (xy 349.574469 -241.480998) (xy 349.533966 -241.508954) (xy 349.489504 -241.530052)
			(xy 349.442233 -241.543744) (xy 349.393378 -241.549676) (xy 349.344203 -241.547695) (xy 349.295984 -241.537851)
			(xy 349.249968 -241.520399) (xy 349.207347 -241.495792) (xy 349.169226 -241.464667) (xy 349.136591 -241.42783)
			(xy 349.110288 -241.386234) (xy 349.090997 -241.340958) (xy 349.07922 -241.293174) (xy 349.07526 -241.24412)
			(xy 348.746318 -241.24412) (xy 348.745823 -241.268727) (xy 348.737928 -241.317304) (xy 348.722344 -241.363985)
			(xy 348.699473 -241.407562) (xy 348.669908 -241.446906) (xy 348.634415 -241.480998) (xy 348.593912 -241.508954)
			(xy 348.54945 -241.530052) (xy 348.502179 -241.543744) (xy 348.453324 -241.549676) (xy 348.404149 -241.547695)
			(xy 348.35593 -241.537851) (xy 348.309914 -241.520399) (xy 348.267293 -241.495792) (xy 348.229172 -241.464667)
			(xy 348.196537 -241.42783) (xy 348.170234 -241.386234) (xy 348.150943 -241.340958) (xy 348.139166 -241.293174)
			(xy 348.135206 -241.24412) (xy 347.806518 -241.24412) (xy 347.806023 -241.268727) (xy 347.798128 -241.317304)
			(xy 347.782544 -241.363985) (xy 347.759673 -241.407562) (xy 347.730108 -241.446906) (xy 347.694615 -241.480998)
			(xy 347.654112 -241.508954) (xy 347.60965 -241.530052) (xy 347.562379 -241.543744) (xy 347.513524 -241.549676)
			(xy 347.464349 -241.547695) (xy 347.41613 -241.537851) (xy 347.370114 -241.520399) (xy 347.327493 -241.495792)
			(xy 347.289372 -241.464667) (xy 347.256737 -241.42783) (xy 347.230434 -241.386234) (xy 347.211143 -241.340958)
			(xy 347.199366 -241.293174) (xy 347.195406 -241.24412) (xy 346.866464 -241.24412) (xy 346.865969 -241.268727)
			(xy 346.858074 -241.317304) (xy 346.84249 -241.363985) (xy 346.819619 -241.407562) (xy 346.790054 -241.446906)
			(xy 346.754561 -241.480998) (xy 346.714058 -241.508954) (xy 346.669596 -241.530052) (xy 346.622325 -241.543744)
			(xy 346.57347 -241.549676) (xy 346.524295 -241.547695) (xy 346.476076 -241.537851) (xy 346.43006 -241.520399)
			(xy 346.387439 -241.495792) (xy 346.349318 -241.464667) (xy 346.316683 -241.42783) (xy 346.29038 -241.386234)
			(xy 346.271089 -241.340958) (xy 346.259312 -241.293174) (xy 346.255352 -241.24412) (xy 345.92641 -241.24412)
			(xy 345.925915 -241.268727) (xy 345.91802 -241.317304) (xy 345.902436 -241.363985) (xy 345.879565 -241.407562)
			(xy 345.85 -241.446906) (xy 345.814507 -241.480998) (xy 345.774004 -241.508954) (xy 345.729542 -241.530052)
			(xy 345.682271 -241.543744) (xy 345.633416 -241.549676) (xy 345.584241 -241.547695) (xy 345.536022 -241.537851)
			(xy 345.490006 -241.520399) (xy 345.447385 -241.495792) (xy 345.409264 -241.464667) (xy 345.376629 -241.42783)
			(xy 345.350326 -241.386234) (xy 345.331035 -241.340958) (xy 345.319258 -241.293174) (xy 345.315298 -241.24412)
			(xy 344.986899 -241.24412) (xy 344.982986 -241.292886) (xy 344.971341 -241.340422) (xy 344.952263 -241.385493)
			(xy 344.926242 -241.426944) (xy 344.893943 -241.463715) (xy 344.856194 -241.494864) (xy 344.81396 -241.519595)
			(xy 344.768322 -241.537273) (xy 344.72045 -241.547447) (xy 344.696034 -241.549174) (xy 344.686636 -241.549428)
			(xy 344.669618 -241.557048) (xy 344.641424 -241.584734) (xy 344.634605 -241.591998) (xy 344.62687 -241.610341)
			(xy 344.626438 -241.620294) (xy 344.626438 -242.054126) (xy 346.725252 -242.054126) (xy 346.729212 -242.005072)
			(xy 346.740989 -241.957288) (xy 346.76028 -241.912012) (xy 346.786583 -241.870416) (xy 346.819218 -241.833579)
			(xy 346.857339 -241.802454) (xy 346.89996 -241.777847) (xy 346.945976 -241.760395) (xy 346.994195 -241.750551)
			(xy 347.04337 -241.74857) (xy 347.092225 -241.754502) (xy 347.139496 -241.768194) (xy 347.183958 -241.789292)
			(xy 347.224461 -241.817248) (xy 347.259954 -241.85134) (xy 347.289519 -241.890684) (xy 347.31239 -241.934261)
			(xy 347.327974 -241.980942) (xy 347.335869 -242.029519) (xy 347.336364 -242.054126) (xy 349.545414 -242.054126)
			(xy 349.549374 -242.005072) (xy 349.561151 -241.957288) (xy 349.580442 -241.912012) (xy 349.606745 -241.870416)
			(xy 349.63938 -241.833579) (xy 349.677501 -241.802454) (xy 349.720122 -241.777847) (xy 349.766138 -241.760395)
			(xy 349.814357 -241.750551) (xy 349.863532 -241.74857) (xy 349.912387 -241.754502) (xy 349.959658 -241.768194)
			(xy 350.00412 -241.789292) (xy 350.044623 -241.817248) (xy 350.080116 -241.85134) (xy 350.109681 -241.890684)
			(xy 350.132552 -241.934261) (xy 350.148136 -241.980942) (xy 350.156031 -242.029519) (xy 350.156526 -242.054126)
			(xy 352.365322 -242.054126) (xy 352.369282 -242.005072) (xy 352.381059 -241.957288) (xy 352.40035 -241.912012)
			(xy 352.426653 -241.870416) (xy 352.459288 -241.833579) (xy 352.497409 -241.802454) (xy 352.54003 -241.777847)
			(xy 352.586046 -241.760395) (xy 352.634265 -241.750551) (xy 352.68344 -241.74857) (xy 352.732295 -241.754502)
			(xy 352.779566 -241.768194) (xy 352.824028 -241.789292) (xy 352.864531 -241.817248) (xy 352.900024 -241.85134)
			(xy 352.929589 -241.890684) (xy 352.95246 -241.934261) (xy 352.968044 -241.980942) (xy 352.975939 -242.029519)
			(xy 352.976434 -242.054126) (xy 355.18523 -242.054126) (xy 355.18919 -242.005072) (xy 355.200967 -241.957288)
			(xy 355.220258 -241.912012) (xy 355.246561 -241.870416) (xy 355.279196 -241.833579) (xy 355.317317 -241.802454)
			(xy 355.359938 -241.777847) (xy 355.405954 -241.760395) (xy 355.454173 -241.750551) (xy 355.503348 -241.74857)
			(xy 355.552203 -241.754502) (xy 355.599474 -241.768194) (xy 355.643936 -241.789292) (xy 355.684439 -241.817248)
			(xy 355.719932 -241.85134) (xy 355.749497 -241.890684) (xy 355.772368 -241.934261) (xy 355.787952 -241.980942)
			(xy 355.795847 -242.029519) (xy 355.796342 -242.054126) (xy 356.125284 -242.054126) (xy 356.129244 -242.005072)
			(xy 356.141021 -241.957288) (xy 356.160312 -241.912012) (xy 356.186615 -241.870416) (xy 356.21925 -241.833579)
			(xy 356.257371 -241.802454) (xy 356.299992 -241.777847) (xy 356.346008 -241.760395) (xy 356.394227 -241.750551)
			(xy 356.443402 -241.74857) (xy 356.492257 -241.754502) (xy 356.539528 -241.768194) (xy 356.58399 -241.789292)
			(xy 356.624493 -241.817248) (xy 356.659986 -241.85134) (xy 356.689551 -241.890684) (xy 356.712422 -241.934261)
			(xy 356.728006 -241.980942) (xy 356.735901 -242.029519) (xy 356.736396 -242.054126) (xy 357.065338 -242.054126)
			(xy 357.069298 -242.005072) (xy 357.081075 -241.957288) (xy 357.100366 -241.912012) (xy 357.126669 -241.870416)
			(xy 357.159304 -241.833579) (xy 357.197425 -241.802454) (xy 357.240046 -241.777847) (xy 357.286062 -241.760395)
			(xy 357.334281 -241.750551) (xy 357.383456 -241.74857) (xy 357.432311 -241.754502) (xy 357.479582 -241.768194)
			(xy 357.524044 -241.789292) (xy 357.564547 -241.817248) (xy 357.60004 -241.85134) (xy 357.629605 -241.890684)
			(xy 357.652476 -241.934261) (xy 357.66806 -241.980942) (xy 357.675955 -242.029519) (xy 357.67645 -242.054126)
			(xy 358.005392 -242.054126) (xy 358.009352 -242.005072) (xy 358.021129 -241.957288) (xy 358.04042 -241.912012)
			(xy 358.066723 -241.870416) (xy 358.099358 -241.833579) (xy 358.137479 -241.802454) (xy 358.1801 -241.777847)
			(xy 358.226116 -241.760395) (xy 358.274335 -241.750551) (xy 358.32351 -241.74857) (xy 358.372365 -241.754502)
			(xy 358.419636 -241.768194) (xy 358.464098 -241.789292) (xy 358.504601 -241.817248) (xy 358.540094 -241.85134)
			(xy 358.569659 -241.890684) (xy 358.59253 -241.934261) (xy 358.608114 -241.980942) (xy 358.616009 -242.029519)
			(xy 358.616504 -242.054126) (xy 360.81895 -242.054126) (xy 360.82291 -242.005072) (xy 360.834687 -241.957288)
			(xy 360.853978 -241.912012) (xy 360.880281 -241.870416) (xy 360.912916 -241.833579) (xy 360.951037 -241.802454)
			(xy 360.993658 -241.777847) (xy 361.039674 -241.760395) (xy 361.087893 -241.750551) (xy 361.137068 -241.74857)
			(xy 361.185923 -241.754502) (xy 361.233194 -241.768194) (xy 361.277656 -241.789292) (xy 361.318159 -241.817248)
			(xy 361.353652 -241.85134) (xy 361.383217 -241.890684) (xy 361.406088 -241.934261) (xy 361.421672 -241.980942)
			(xy 361.429567 -242.029519) (xy 361.430062 -242.054126) (xy 361.759004 -242.054126) (xy 361.762964 -242.005072)
			(xy 361.774741 -241.957288) (xy 361.794032 -241.912012) (xy 361.820335 -241.870416) (xy 361.85297 -241.833579)
			(xy 361.891091 -241.802454) (xy 361.933712 -241.777847) (xy 361.979728 -241.760395) (xy 362.027947 -241.750551)
			(xy 362.077122 -241.74857) (xy 362.125977 -241.754502) (xy 362.173248 -241.768194) (xy 362.21771 -241.789292)
			(xy 362.258213 -241.817248) (xy 362.293706 -241.85134) (xy 362.323271 -241.890684) (xy 362.346142 -241.934261)
			(xy 362.361726 -241.980942) (xy 362.369621 -242.029519) (xy 362.370116 -242.054126) (xy 362.699058 -242.054126)
			(xy 362.703018 -242.005072) (xy 362.714795 -241.957288) (xy 362.734086 -241.912012) (xy 362.760389 -241.870416)
			(xy 362.793024 -241.833579) (xy 362.831145 -241.802454) (xy 362.873766 -241.777847) (xy 362.919782 -241.760395)
			(xy 362.968001 -241.750551) (xy 363.017176 -241.74857) (xy 363.066031 -241.754502) (xy 363.113302 -241.768194)
			(xy 363.157764 -241.789292) (xy 363.198267 -241.817248) (xy 363.23376 -241.85134) (xy 363.263325 -241.890684)
			(xy 363.286196 -241.934261) (xy 363.30178 -241.980942) (xy 363.309675 -242.029519) (xy 363.31017 -242.054126)
			(xy 363.639112 -242.054126) (xy 363.643072 -242.005072) (xy 363.654849 -241.957288) (xy 363.67414 -241.912012)
			(xy 363.700443 -241.870416) (xy 363.733078 -241.833579) (xy 363.771199 -241.802454) (xy 363.81382 -241.777847)
			(xy 363.859836 -241.760395) (xy 363.908055 -241.750551) (xy 363.95723 -241.74857) (xy 364.006085 -241.754502)
			(xy 364.053356 -241.768194) (xy 364.097818 -241.789292) (xy 364.138321 -241.817248) (xy 364.173814 -241.85134)
			(xy 364.203379 -241.890684) (xy 364.22625 -241.934261) (xy 364.241834 -241.980942) (xy 364.249729 -242.029519)
			(xy 364.250224 -242.054126) (xy 366.45902 -242.054126) (xy 366.46298 -242.005072) (xy 366.474757 -241.957288)
			(xy 366.494048 -241.912012) (xy 366.520351 -241.870416) (xy 366.552986 -241.833579) (xy 366.591107 -241.802454)
			(xy 366.633728 -241.777847) (xy 366.679744 -241.760395) (xy 366.727963 -241.750551) (xy 366.777138 -241.74857)
			(xy 366.825993 -241.754502) (xy 366.873264 -241.768194) (xy 366.917726 -241.789292) (xy 366.958229 -241.817248)
			(xy 366.993722 -241.85134) (xy 367.023287 -241.890684) (xy 367.046158 -241.934261) (xy 367.061742 -241.980942)
			(xy 367.069637 -242.029519) (xy 367.070132 -242.054126) (xy 369.278928 -242.054126) (xy 369.282888 -242.005072)
			(xy 369.294665 -241.957288) (xy 369.313956 -241.912012) (xy 369.340259 -241.870416) (xy 369.372894 -241.833579)
			(xy 369.411015 -241.802454) (xy 369.453636 -241.777847) (xy 369.499652 -241.760395) (xy 369.547871 -241.750551)
			(xy 369.597046 -241.74857) (xy 369.645901 -241.754502) (xy 369.693172 -241.768194) (xy 369.737634 -241.789292)
			(xy 369.778137 -241.817248) (xy 369.81363 -241.85134) (xy 369.843195 -241.890684) (xy 369.866066 -241.934261)
			(xy 369.88165 -241.980942) (xy 369.889545 -242.029519) (xy 369.89004 -242.054126) (xy 372.09909 -242.054126)
			(xy 372.10305 -242.005072) (xy 372.114827 -241.957288) (xy 372.134118 -241.912012) (xy 372.160421 -241.870416)
			(xy 372.193056 -241.833579) (xy 372.231177 -241.802454) (xy 372.273798 -241.777847) (xy 372.319814 -241.760395)
			(xy 372.368033 -241.750551) (xy 372.417208 -241.74857) (xy 372.466063 -241.754502) (xy 372.513334 -241.768194)
			(xy 372.557796 -241.789292) (xy 372.598299 -241.817248) (xy 372.633792 -241.85134) (xy 372.663357 -241.890684)
			(xy 372.686228 -241.934261) (xy 372.701812 -241.980942) (xy 372.709707 -242.029519) (xy 372.710202 -242.054126)
			(xy 372.709707 -242.078733) (xy 372.701812 -242.12731) (xy 372.686228 -242.173991) (xy 372.663357 -242.217568)
			(xy 372.633792 -242.256912) (xy 372.598299 -242.291004) (xy 372.557796 -242.31896) (xy 372.513334 -242.340058)
			(xy 372.466063 -242.35375) (xy 372.417208 -242.359682) (xy 372.368033 -242.357701) (xy 372.319814 -242.347857)
			(xy 372.273798 -242.330405) (xy 372.231177 -242.305798) (xy 372.193056 -242.274673) (xy 372.160421 -242.237836)
			(xy 372.134118 -242.19624) (xy 372.114827 -242.150964) (xy 372.10305 -242.10318) (xy 372.09909 -242.054126)
			(xy 369.89004 -242.054126) (xy 369.889545 -242.078733) (xy 369.88165 -242.12731) (xy 369.866066 -242.173991)
			(xy 369.843195 -242.217568) (xy 369.81363 -242.256912) (xy 369.778137 -242.291004) (xy 369.737634 -242.31896)
			(xy 369.693172 -242.340058) (xy 369.645901 -242.35375) (xy 369.597046 -242.359682) (xy 369.547871 -242.357701)
			(xy 369.499652 -242.347857) (xy 369.453636 -242.330405) (xy 369.411015 -242.305798) (xy 369.372894 -242.274673)
			(xy 369.340259 -242.237836) (xy 369.313956 -242.19624) (xy 369.294665 -242.150964) (xy 369.282888 -242.10318)
			(xy 369.278928 -242.054126) (xy 367.070132 -242.054126) (xy 367.069637 -242.078733) (xy 367.061742 -242.12731)
			(xy 367.046158 -242.173991) (xy 367.023287 -242.217568) (xy 366.993722 -242.256912) (xy 366.958229 -242.291004)
			(xy 366.917726 -242.31896) (xy 366.873264 -242.340058) (xy 366.825993 -242.35375) (xy 366.777138 -242.359682)
			(xy 366.727963 -242.357701) (xy 366.679744 -242.347857) (xy 366.633728 -242.330405) (xy 366.591107 -242.305798)
			(xy 366.552986 -242.274673) (xy 366.520351 -242.237836) (xy 366.494048 -242.19624) (xy 366.474757 -242.150964)
			(xy 366.46298 -242.10318) (xy 366.45902 -242.054126) (xy 364.250224 -242.054126) (xy 364.249729 -242.078733)
			(xy 364.241834 -242.12731) (xy 364.22625 -242.173991) (xy 364.203379 -242.217568) (xy 364.173814 -242.256912)
			(xy 364.138321 -242.291004) (xy 364.097818 -242.31896) (xy 364.053356 -242.340058) (xy 364.006085 -242.35375)
			(xy 363.95723 -242.359682) (xy 363.908055 -242.357701) (xy 363.859836 -242.347857) (xy 363.81382 -242.330405)
			(xy 363.771199 -242.305798) (xy 363.733078 -242.274673) (xy 363.700443 -242.237836) (xy 363.67414 -242.19624)
			(xy 363.654849 -242.150964) (xy 363.643072 -242.10318) (xy 363.639112 -242.054126) (xy 363.31017 -242.054126)
			(xy 363.309675 -242.078733) (xy 363.30178 -242.12731) (xy 363.286196 -242.173991) (xy 363.263325 -242.217568)
			(xy 363.23376 -242.256912) (xy 363.198267 -242.291004) (xy 363.157764 -242.31896) (xy 363.113302 -242.340058)
			(xy 363.066031 -242.35375) (xy 363.017176 -242.359682) (xy 362.968001 -242.357701) (xy 362.919782 -242.347857)
			(xy 362.873766 -242.330405) (xy 362.831145 -242.305798) (xy 362.793024 -242.274673) (xy 362.760389 -242.237836)
			(xy 362.734086 -242.19624) (xy 362.714795 -242.150964) (xy 362.703018 -242.10318) (xy 362.699058 -242.054126)
			(xy 362.370116 -242.054126) (xy 362.369621 -242.078733) (xy 362.361726 -242.12731) (xy 362.346142 -242.173991)
			(xy 362.323271 -242.217568) (xy 362.293706 -242.256912) (xy 362.258213 -242.291004) (xy 362.21771 -242.31896)
			(xy 362.173248 -242.340058) (xy 362.125977 -242.35375) (xy 362.077122 -242.359682) (xy 362.027947 -242.357701)
			(xy 361.979728 -242.347857) (xy 361.933712 -242.330405) (xy 361.891091 -242.305798) (xy 361.85297 -242.274673)
			(xy 361.820335 -242.237836) (xy 361.794032 -242.19624) (xy 361.774741 -242.150964) (xy 361.762964 -242.10318)
			(xy 361.759004 -242.054126) (xy 361.430062 -242.054126) (xy 361.429567 -242.078733) (xy 361.421672 -242.12731)
			(xy 361.406088 -242.173991) (xy 361.383217 -242.217568) (xy 361.353652 -242.256912) (xy 361.318159 -242.291004)
			(xy 361.277656 -242.31896) (xy 361.233194 -242.340058) (xy 361.185923 -242.35375) (xy 361.137068 -242.359682)
			(xy 361.087893 -242.357701) (xy 361.039674 -242.347857) (xy 360.993658 -242.330405) (xy 360.951037 -242.305798)
			(xy 360.912916 -242.274673) (xy 360.880281 -242.237836) (xy 360.853978 -242.19624) (xy 360.834687 -242.150964)
			(xy 360.82291 -242.10318) (xy 360.81895 -242.054126) (xy 358.616504 -242.054126) (xy 358.616009 -242.078733)
			(xy 358.608114 -242.12731) (xy 358.59253 -242.173991) (xy 358.569659 -242.217568) (xy 358.540094 -242.256912)
			(xy 358.504601 -242.291004) (xy 358.464098 -242.31896) (xy 358.419636 -242.340058) (xy 358.372365 -242.35375)
			(xy 358.32351 -242.359682) (xy 358.274335 -242.357701) (xy 358.226116 -242.347857) (xy 358.1801 -242.330405)
			(xy 358.137479 -242.305798) (xy 358.099358 -242.274673) (xy 358.066723 -242.237836) (xy 358.04042 -242.19624)
			(xy 358.021129 -242.150964) (xy 358.009352 -242.10318) (xy 358.005392 -242.054126) (xy 357.67645 -242.054126)
			(xy 357.675955 -242.078733) (xy 357.66806 -242.12731) (xy 357.652476 -242.173991) (xy 357.629605 -242.217568)
			(xy 357.60004 -242.256912) (xy 357.564547 -242.291004) (xy 357.524044 -242.31896) (xy 357.479582 -242.340058)
			(xy 357.432311 -242.35375) (xy 357.383456 -242.359682) (xy 357.334281 -242.357701) (xy 357.286062 -242.347857)
			(xy 357.240046 -242.330405) (xy 357.197425 -242.305798) (xy 357.159304 -242.274673) (xy 357.126669 -242.237836)
			(xy 357.100366 -242.19624) (xy 357.081075 -242.150964) (xy 357.069298 -242.10318) (xy 357.065338 -242.054126)
			(xy 356.736396 -242.054126) (xy 356.735901 -242.078733) (xy 356.728006 -242.12731) (xy 356.712422 -242.173991)
			(xy 356.689551 -242.217568) (xy 356.659986 -242.256912) (xy 356.624493 -242.291004) (xy 356.58399 -242.31896)
			(xy 356.539528 -242.340058) (xy 356.492257 -242.35375) (xy 356.443402 -242.359682) (xy 356.394227 -242.357701)
			(xy 356.346008 -242.347857) (xy 356.299992 -242.330405) (xy 356.257371 -242.305798) (xy 356.21925 -242.274673)
			(xy 356.186615 -242.237836) (xy 356.160312 -242.19624) (xy 356.141021 -242.150964) (xy 356.129244 -242.10318)
			(xy 356.125284 -242.054126) (xy 355.796342 -242.054126) (xy 355.795847 -242.078733) (xy 355.787952 -242.12731)
			(xy 355.772368 -242.173991) (xy 355.749497 -242.217568) (xy 355.719932 -242.256912) (xy 355.684439 -242.291004)
			(xy 355.643936 -242.31896) (xy 355.599474 -242.340058) (xy 355.552203 -242.35375) (xy 355.503348 -242.359682)
			(xy 355.454173 -242.357701) (xy 355.405954 -242.347857) (xy 355.359938 -242.330405) (xy 355.317317 -242.305798)
			(xy 355.279196 -242.274673) (xy 355.246561 -242.237836) (xy 355.220258 -242.19624) (xy 355.200967 -242.150964)
			(xy 355.18919 -242.10318) (xy 355.18523 -242.054126) (xy 352.976434 -242.054126) (xy 352.975939 -242.078733)
			(xy 352.968044 -242.12731) (xy 352.95246 -242.173991) (xy 352.929589 -242.217568) (xy 352.900024 -242.256912)
			(xy 352.864531 -242.291004) (xy 352.824028 -242.31896) (xy 352.779566 -242.340058) (xy 352.732295 -242.35375)
			(xy 352.68344 -242.359682) (xy 352.634265 -242.357701) (xy 352.586046 -242.347857) (xy 352.54003 -242.330405)
			(xy 352.497409 -242.305798) (xy 352.459288 -242.274673) (xy 352.426653 -242.237836) (xy 352.40035 -242.19624)
			(xy 352.381059 -242.150964) (xy 352.369282 -242.10318) (xy 352.365322 -242.054126) (xy 350.156526 -242.054126)
			(xy 350.156031 -242.078733) (xy 350.148136 -242.12731) (xy 350.132552 -242.173991) (xy 350.109681 -242.217568)
			(xy 350.080116 -242.256912) (xy 350.044623 -242.291004) (xy 350.00412 -242.31896) (xy 349.959658 -242.340058)
			(xy 349.912387 -242.35375) (xy 349.863532 -242.359682) (xy 349.814357 -242.357701) (xy 349.766138 -242.347857)
			(xy 349.720122 -242.330405) (xy 349.677501 -242.305798) (xy 349.63938 -242.274673) (xy 349.606745 -242.237836)
			(xy 349.580442 -242.19624) (xy 349.561151 -242.150964) (xy 349.549374 -242.10318) (xy 349.545414 -242.054126)
			(xy 347.336364 -242.054126) (xy 347.335869 -242.078733) (xy 347.327974 -242.12731) (xy 347.31239 -242.173991)
			(xy 347.289519 -242.217568) (xy 347.259954 -242.256912) (xy 347.224461 -242.291004) (xy 347.183958 -242.31896)
			(xy 347.139496 -242.340058) (xy 347.092225 -242.35375) (xy 347.04337 -242.359682) (xy 346.994195 -242.357701)
			(xy 346.945976 -242.347857) (xy 346.89996 -242.330405) (xy 346.857339 -242.305798) (xy 346.819218 -242.274673)
			(xy 346.786583 -242.237836) (xy 346.76028 -242.19624) (xy 346.740989 -242.150964) (xy 346.729212 -242.10318)
			(xy 346.725252 -242.054126) (xy 344.626438 -242.054126) (xy 344.626438 -242.48745) (xy 344.626889 -242.497604)
			(xy 344.634755 -242.516329) (xy 344.641678 -242.523772) (xy 344.669618 -242.551204) (xy 344.686636 -242.558824)
			(xy 344.696034 -242.559078) (xy 344.720451 -242.560765) (xy 344.768321 -242.570939) (xy 344.813957 -242.588617)
			(xy 344.856189 -242.613347) (xy 344.893937 -242.644495) (xy 344.926234 -242.681265) (xy 344.952254 -242.722715)
			(xy 344.97133 -242.767784) (xy 344.982975 -242.815318) (xy 344.986889 -242.864102) (xy 344.986887 -242.864132)
			(xy 345.315298 -242.864132) (xy 345.319258 -242.815078) (xy 345.331035 -242.767294) (xy 345.350326 -242.722018)
			(xy 345.376629 -242.680422) (xy 345.409264 -242.643585) (xy 345.447385 -242.61246) (xy 345.490006 -242.587853)
			(xy 345.536022 -242.570401) (xy 345.584241 -242.560557) (xy 345.633416 -242.558576) (xy 345.682271 -242.564508)
			(xy 345.729542 -242.5782) (xy 345.774004 -242.599298) (xy 345.814507 -242.627254) (xy 345.85 -242.661346)
			(xy 345.879565 -242.70069) (xy 345.902436 -242.744267) (xy 345.91802 -242.790948) (xy 345.925915 -242.839525)
			(xy 345.92641 -242.864132) (xy 346.255352 -242.864132) (xy 346.259312 -242.815078) (xy 346.271089 -242.767294)
			(xy 346.29038 -242.722018) (xy 346.316683 -242.680422) (xy 346.349318 -242.643585) (xy 346.387439 -242.61246)
			(xy 346.43006 -242.587853) (xy 346.476076 -242.570401) (xy 346.524295 -242.560557) (xy 346.57347 -242.558576)
			(xy 346.622325 -242.564508) (xy 346.669596 -242.5782) (xy 346.714058 -242.599298) (xy 346.754561 -242.627254)
			(xy 346.790054 -242.661346) (xy 346.819619 -242.70069) (xy 346.84249 -242.744267) (xy 346.858074 -242.790948)
			(xy 346.865969 -242.839525) (xy 346.866464 -242.864132) (xy 347.195406 -242.864132) (xy 347.199366 -242.815078)
			(xy 347.211143 -242.767294) (xy 347.230434 -242.722018) (xy 347.256737 -242.680422) (xy 347.289372 -242.643585)
			(xy 347.327493 -242.61246) (xy 347.370114 -242.587853) (xy 347.41613 -242.570401) (xy 347.464349 -242.560557)
			(xy 347.513524 -242.558576) (xy 347.562379 -242.564508) (xy 347.60965 -242.5782) (xy 347.654112 -242.599298)
			(xy 347.694615 -242.627254) (xy 347.730108 -242.661346) (xy 347.759673 -242.70069) (xy 347.782544 -242.744267)
			(xy 347.798128 -242.790948) (xy 347.806023 -242.839525) (xy 347.806518 -242.864132) (xy 348.135206 -242.864132)
			(xy 348.139166 -242.815078) (xy 348.150943 -242.767294) (xy 348.170234 -242.722018) (xy 348.196537 -242.680422)
			(xy 348.229172 -242.643585) (xy 348.267293 -242.61246) (xy 348.309914 -242.587853) (xy 348.35593 -242.570401)
			(xy 348.404149 -242.560557) (xy 348.453324 -242.558576) (xy 348.502179 -242.564508) (xy 348.54945 -242.5782)
			(xy 348.593912 -242.599298) (xy 348.634415 -242.627254) (xy 348.669908 -242.661346) (xy 348.699473 -242.70069)
			(xy 348.722344 -242.744267) (xy 348.737928 -242.790948) (xy 348.745823 -242.839525) (xy 348.746318 -242.864132)
			(xy 349.07526 -242.864132) (xy 349.07922 -242.815078) (xy 349.090997 -242.767294) (xy 349.110288 -242.722018)
			(xy 349.136591 -242.680422) (xy 349.169226 -242.643585) (xy 349.207347 -242.61246) (xy 349.249968 -242.587853)
			(xy 349.295984 -242.570401) (xy 349.344203 -242.560557) (xy 349.393378 -242.558576) (xy 349.442233 -242.564508)
			(xy 349.489504 -242.5782) (xy 349.533966 -242.599298) (xy 349.574469 -242.627254) (xy 349.609962 -242.661346)
			(xy 349.639527 -242.70069) (xy 349.662398 -242.744267) (xy 349.677982 -242.790948) (xy 349.685877 -242.839525)
			(xy 349.686372 -242.864132) (xy 350.015314 -242.864132) (xy 350.019274 -242.815078) (xy 350.031051 -242.767294)
			(xy 350.050342 -242.722018) (xy 350.076645 -242.680422) (xy 350.10928 -242.643585) (xy 350.147401 -242.61246)
			(xy 350.190022 -242.587853) (xy 350.236038 -242.570401) (xy 350.284257 -242.560557) (xy 350.333432 -242.558576)
			(xy 350.382287 -242.564508) (xy 350.429558 -242.5782) (xy 350.47402 -242.599298) (xy 350.514523 -242.627254)
			(xy 350.550016 -242.661346) (xy 350.579581 -242.70069) (xy 350.602452 -242.744267) (xy 350.618036 -242.790948)
			(xy 350.625931 -242.839525) (xy 350.626426 -242.864132) (xy 350.955368 -242.864132) (xy 350.959328 -242.815078)
			(xy 350.971105 -242.767294) (xy 350.990396 -242.722018) (xy 351.016699 -242.680422) (xy 351.049334 -242.643585)
			(xy 351.087455 -242.61246) (xy 351.130076 -242.587853) (xy 351.176092 -242.570401) (xy 351.224311 -242.560557)
			(xy 351.273486 -242.558576) (xy 351.322341 -242.564508) (xy 351.369612 -242.5782) (xy 351.414074 -242.599298)
			(xy 351.454577 -242.627254) (xy 351.49007 -242.661346) (xy 351.519635 -242.70069) (xy 351.542506 -242.744267)
			(xy 351.55809 -242.790948) (xy 351.565985 -242.839525) (xy 351.56648 -242.864132) (xy 351.895422 -242.864132)
			(xy 351.899382 -242.815078) (xy 351.911159 -242.767294) (xy 351.93045 -242.722018) (xy 351.956753 -242.680422)
			(xy 351.989388 -242.643585) (xy 352.027509 -242.61246) (xy 352.07013 -242.587853) (xy 352.116146 -242.570401)
			(xy 352.164365 -242.560557) (xy 352.21354 -242.558576) (xy 352.262395 -242.564508) (xy 352.309666 -242.5782)
			(xy 352.354128 -242.599298) (xy 352.394631 -242.627254) (xy 352.430124 -242.661346) (xy 352.459689 -242.70069)
			(xy 352.48256 -242.744267) (xy 352.498144 -242.790948) (xy 352.506039 -242.839525) (xy 352.506534 -242.864132)
			(xy 352.835222 -242.864132) (xy 352.839182 -242.815078) (xy 352.850959 -242.767294) (xy 352.87025 -242.722018)
			(xy 352.896553 -242.680422) (xy 352.929188 -242.643585) (xy 352.967309 -242.61246) (xy 353.00993 -242.587853)
			(xy 353.055946 -242.570401) (xy 353.104165 -242.560557) (xy 353.15334 -242.558576) (xy 353.202195 -242.564508)
			(xy 353.249466 -242.5782) (xy 353.293928 -242.599298) (xy 353.334431 -242.627254) (xy 353.369924 -242.661346)
			(xy 353.399489 -242.70069) (xy 353.42236 -242.744267) (xy 353.437944 -242.790948) (xy 353.445839 -242.839525)
			(xy 353.446334 -242.864132) (xy 353.775276 -242.864132) (xy 353.779236 -242.815078) (xy 353.791013 -242.767294)
			(xy 353.810304 -242.722018) (xy 353.836607 -242.680422) (xy 353.869242 -242.643585) (xy 353.907363 -242.61246)
			(xy 353.949984 -242.587853) (xy 353.996 -242.570401) (xy 354.044219 -242.560557) (xy 354.093394 -242.558576)
			(xy 354.142249 -242.564508) (xy 354.18952 -242.5782) (xy 354.233982 -242.599298) (xy 354.274485 -242.627254)
			(xy 354.309978 -242.661346) (xy 354.339543 -242.70069) (xy 354.362414 -242.744267) (xy 354.377998 -242.790948)
			(xy 354.385893 -242.839525) (xy 354.386388 -242.864132) (xy 354.71533 -242.864132) (xy 354.71929 -242.815078)
			(xy 354.731067 -242.767294) (xy 354.750358 -242.722018) (xy 354.776661 -242.680422) (xy 354.809296 -242.643585)
			(xy 354.847417 -242.61246) (xy 354.890038 -242.587853) (xy 354.936054 -242.570401) (xy 354.984273 -242.560557)
			(xy 355.033448 -242.558576) (xy 355.082303 -242.564508) (xy 355.129574 -242.5782) (xy 355.174036 -242.599298)
			(xy 355.214539 -242.627254) (xy 355.250032 -242.661346) (xy 355.279597 -242.70069) (xy 355.302468 -242.744267)
			(xy 355.318052 -242.790948) (xy 355.325947 -242.839525) (xy 355.326442 -242.864132) (xy 355.655384 -242.864132)
			(xy 355.659344 -242.815078) (xy 355.671121 -242.767294) (xy 355.690412 -242.722018) (xy 355.716715 -242.680422)
			(xy 355.74935 -242.643585) (xy 355.787471 -242.61246) (xy 355.830092 -242.587853) (xy 355.876108 -242.570401)
			(xy 355.924327 -242.560557) (xy 355.973502 -242.558576) (xy 356.022357 -242.564508) (xy 356.069628 -242.5782)
			(xy 356.11409 -242.599298) (xy 356.154593 -242.627254) (xy 356.190086 -242.661346) (xy 356.219651 -242.70069)
			(xy 356.242522 -242.744267) (xy 356.258106 -242.790948) (xy 356.266001 -242.839525) (xy 356.266496 -242.864132)
			(xy 363.168958 -242.864132) (xy 363.172918 -242.815078) (xy 363.184695 -242.767294) (xy 363.203986 -242.722018)
			(xy 363.230289 -242.680422) (xy 363.262924 -242.643585) (xy 363.301045 -242.61246) (xy 363.343666 -242.587853)
			(xy 363.389682 -242.570401) (xy 363.437901 -242.560557) (xy 363.487076 -242.558576) (xy 363.535931 -242.564508)
			(xy 363.583202 -242.5782) (xy 363.627664 -242.599298) (xy 363.668167 -242.627254) (xy 363.70366 -242.661346)
			(xy 363.733225 -242.70069) (xy 363.756096 -242.744267) (xy 363.77168 -242.790948) (xy 363.779575 -242.839525)
			(xy 363.78007 -242.864132) (xy 364.109012 -242.864132) (xy 364.112972 -242.815078) (xy 364.124749 -242.767294)
			(xy 364.14404 -242.722018) (xy 364.170343 -242.680422) (xy 364.202978 -242.643585) (xy 364.241099 -242.61246)
			(xy 364.28372 -242.587853) (xy 364.329736 -242.570401) (xy 364.377955 -242.560557) (xy 364.42713 -242.558576)
			(xy 364.475985 -242.564508) (xy 364.523256 -242.5782) (xy 364.567718 -242.599298) (xy 364.608221 -242.627254)
			(xy 364.643714 -242.661346) (xy 364.673279 -242.70069) (xy 364.69615 -242.744267) (xy 364.711734 -242.790948)
			(xy 364.719629 -242.839525) (xy 364.720124 -242.864132) (xy 365.049066 -242.864132) (xy 365.053026 -242.815078)
			(xy 365.064803 -242.767294) (xy 365.084094 -242.722018) (xy 365.110397 -242.680422) (xy 365.143032 -242.643585)
			(xy 365.181153 -242.61246) (xy 365.223774 -242.587853) (xy 365.26979 -242.570401) (xy 365.318009 -242.560557)
			(xy 365.367184 -242.558576) (xy 365.416039 -242.564508) (xy 365.46331 -242.5782) (xy 365.507772 -242.599298)
			(xy 365.548275 -242.627254) (xy 365.583768 -242.661346) (xy 365.613333 -242.70069) (xy 365.636204 -242.744267)
			(xy 365.651788 -242.790948) (xy 365.659683 -242.839525) (xy 365.660178 -242.864132) (xy 365.98912 -242.864132)
			(xy 365.99308 -242.815078) (xy 366.004857 -242.767294) (xy 366.024148 -242.722018) (xy 366.050451 -242.680422)
			(xy 366.083086 -242.643585) (xy 366.121207 -242.61246) (xy 366.163828 -242.587853) (xy 366.209844 -242.570401)
			(xy 366.258063 -242.560557) (xy 366.307238 -242.558576) (xy 366.356093 -242.564508) (xy 366.403364 -242.5782)
			(xy 366.447826 -242.599298) (xy 366.488329 -242.627254) (xy 366.523822 -242.661346) (xy 366.553387 -242.70069)
			(xy 366.576258 -242.744267) (xy 366.591842 -242.790948) (xy 366.599737 -242.839525) (xy 366.600232 -242.864132)
			(xy 366.92892 -242.864132) (xy 366.93288 -242.815078) (xy 366.944657 -242.767294) (xy 366.963948 -242.722018)
			(xy 366.990251 -242.680422) (xy 367.022886 -242.643585) (xy 367.061007 -242.61246) (xy 367.103628 -242.587853)
			(xy 367.149644 -242.570401) (xy 367.197863 -242.560557) (xy 367.247038 -242.558576) (xy 367.295893 -242.564508)
			(xy 367.343164 -242.5782) (xy 367.387626 -242.599298) (xy 367.428129 -242.627254) (xy 367.463622 -242.661346)
			(xy 367.493187 -242.70069) (xy 367.516058 -242.744267) (xy 367.531642 -242.790948) (xy 367.539537 -242.839525)
			(xy 367.540032 -242.864132) (xy 367.868974 -242.864132) (xy 367.872934 -242.815078) (xy 367.884711 -242.767294)
			(xy 367.904002 -242.722018) (xy 367.930305 -242.680422) (xy 367.96294 -242.643585) (xy 368.001061 -242.61246)
			(xy 368.043682 -242.587853) (xy 368.089698 -242.570401) (xy 368.137917 -242.560557) (xy 368.187092 -242.558576)
			(xy 368.235947 -242.564508) (xy 368.283218 -242.5782) (xy 368.32768 -242.599298) (xy 368.368183 -242.627254)
			(xy 368.403676 -242.661346) (xy 368.433241 -242.70069) (xy 368.456112 -242.744267) (xy 368.471696 -242.790948)
			(xy 368.479591 -242.839525) (xy 368.480086 -242.864132) (xy 368.809028 -242.864132) (xy 368.812988 -242.815078)
			(xy 368.824765 -242.767294) (xy 368.844056 -242.722018) (xy 368.870359 -242.680422) (xy 368.902994 -242.643585)
			(xy 368.941115 -242.61246) (xy 368.983736 -242.587853) (xy 369.029752 -242.570401) (xy 369.077971 -242.560557)
			(xy 369.127146 -242.558576) (xy 369.176001 -242.564508) (xy 369.223272 -242.5782) (xy 369.267734 -242.599298)
			(xy 369.308237 -242.627254) (xy 369.34373 -242.661346) (xy 369.373295 -242.70069) (xy 369.396166 -242.744267)
			(xy 369.41175 -242.790948) (xy 369.419645 -242.839525) (xy 369.42014 -242.864132) (xy 369.749082 -242.864132)
			(xy 369.753042 -242.815078) (xy 369.764819 -242.767294) (xy 369.78411 -242.722018) (xy 369.810413 -242.680422)
			(xy 369.843048 -242.643585) (xy 369.881169 -242.61246) (xy 369.92379 -242.587853) (xy 369.969806 -242.570401)
			(xy 370.018025 -242.560557) (xy 370.0672 -242.558576) (xy 370.116055 -242.564508) (xy 370.163326 -242.5782)
			(xy 370.207788 -242.599298) (xy 370.248291 -242.627254) (xy 370.283784 -242.661346) (xy 370.313349 -242.70069)
			(xy 370.33622 -242.744267) (xy 370.351804 -242.790948) (xy 370.359699 -242.839525) (xy 370.360194 -242.864132)
			(xy 370.688882 -242.864132) (xy 370.692842 -242.815078) (xy 370.704619 -242.767294) (xy 370.72391 -242.722018)
			(xy 370.750213 -242.680422) (xy 370.782848 -242.643585) (xy 370.820969 -242.61246) (xy 370.86359 -242.587853)
			(xy 370.909606 -242.570401) (xy 370.957825 -242.560557) (xy 371.007 -242.558576) (xy 371.055855 -242.564508)
			(xy 371.103126 -242.5782) (xy 371.147588 -242.599298) (xy 371.188091 -242.627254) (xy 371.223584 -242.661346)
			(xy 371.253149 -242.70069) (xy 371.27602 -242.744267) (xy 371.291604 -242.790948) (xy 371.299499 -242.839525)
			(xy 371.299994 -242.864132) (xy 371.628936 -242.864132) (xy 371.632896 -242.815078) (xy 371.644673 -242.767294)
			(xy 371.663964 -242.722018) (xy 371.690267 -242.680422) (xy 371.722902 -242.643585) (xy 371.761023 -242.61246)
			(xy 371.803644 -242.587853) (xy 371.84966 -242.570401) (xy 371.897879 -242.560557) (xy 371.947054 -242.558576)
			(xy 371.995909 -242.564508) (xy 372.04318 -242.5782) (xy 372.087642 -242.599298) (xy 372.128145 -242.627254)
			(xy 372.163638 -242.661346) (xy 372.193203 -242.70069) (xy 372.216074 -242.744267) (xy 372.231658 -242.790948)
			(xy 372.239553 -242.839525) (xy 372.240048 -242.864132) (xy 372.56899 -242.864132) (xy 372.57295 -242.815078)
			(xy 372.584727 -242.767294) (xy 372.604018 -242.722018) (xy 372.630321 -242.680422) (xy 372.662956 -242.643585)
			(xy 372.701077 -242.61246) (xy 372.743698 -242.587853) (xy 372.789714 -242.570401) (xy 372.837933 -242.560557)
			(xy 372.887108 -242.558576) (xy 372.935963 -242.564508) (xy 372.983234 -242.5782) (xy 373.027696 -242.599298)
			(xy 373.068199 -242.627254) (xy 373.103692 -242.661346) (xy 373.133257 -242.70069) (xy 373.156128 -242.744267)
			(xy 373.171712 -242.790948) (xy 373.179607 -242.839525) (xy 373.180102 -242.864132) (xy 373.509044 -242.864132)
			(xy 373.513004 -242.815078) (xy 373.524781 -242.767294) (xy 373.544072 -242.722018) (xy 373.570375 -242.680422)
			(xy 373.60301 -242.643585) (xy 373.641131 -242.61246) (xy 373.683752 -242.587853) (xy 373.729768 -242.570401)
			(xy 373.777987 -242.560557) (xy 373.827162 -242.558576) (xy 373.876017 -242.564508) (xy 373.923288 -242.5782)
			(xy 373.96775 -242.599298) (xy 374.008253 -242.627254) (xy 374.043746 -242.661346) (xy 374.073311 -242.70069)
			(xy 374.096182 -242.744267) (xy 374.111766 -242.790948) (xy 374.119661 -242.839525) (xy 374.120156 -242.864132)
			(xy 374.119661 -242.888739) (xy 374.111766 -242.937316) (xy 374.096182 -242.983997) (xy 374.073311 -243.027574)
			(xy 374.043746 -243.066918) (xy 374.008253 -243.10101) (xy 373.96775 -243.128966) (xy 373.923288 -243.150064)
			(xy 373.876017 -243.163756) (xy 373.827162 -243.169688) (xy 373.777987 -243.167707) (xy 373.729768 -243.157863)
			(xy 373.683752 -243.140411) (xy 373.641131 -243.115804) (xy 373.60301 -243.084679) (xy 373.570375 -243.047842)
			(xy 373.544072 -243.006246) (xy 373.524781 -242.96097) (xy 373.513004 -242.913186) (xy 373.509044 -242.864132)
			(xy 373.180102 -242.864132) (xy 373.179607 -242.888739) (xy 373.171712 -242.937316) (xy 373.156128 -242.983997)
			(xy 373.133257 -243.027574) (xy 373.103692 -243.066918) (xy 373.068199 -243.10101) (xy 373.027696 -243.128966)
			(xy 372.983234 -243.150064) (xy 372.935963 -243.163756) (xy 372.887108 -243.169688) (xy 372.837933 -243.167707)
			(xy 372.789714 -243.157863) (xy 372.743698 -243.140411) (xy 372.701077 -243.115804) (xy 372.662956 -243.084679)
			(xy 372.630321 -243.047842) (xy 372.604018 -243.006246) (xy 372.584727 -242.96097) (xy 372.57295 -242.913186)
			(xy 372.56899 -242.864132) (xy 372.240048 -242.864132) (xy 372.239553 -242.888739) (xy 372.231658 -242.937316)
			(xy 372.216074 -242.983997) (xy 372.193203 -243.027574) (xy 372.163638 -243.066918) (xy 372.128145 -243.10101)
			(xy 372.087642 -243.128966) (xy 372.04318 -243.150064) (xy 371.995909 -243.163756) (xy 371.947054 -243.169688)
			(xy 371.897879 -243.167707) (xy 371.84966 -243.157863) (xy 371.803644 -243.140411) (xy 371.761023 -243.115804)
			(xy 371.722902 -243.084679) (xy 371.690267 -243.047842) (xy 371.663964 -243.006246) (xy 371.644673 -242.96097)
			(xy 371.632896 -242.913186) (xy 371.628936 -242.864132) (xy 371.299994 -242.864132) (xy 371.299499 -242.888739)
			(xy 371.291604 -242.937316) (xy 371.27602 -242.983997) (xy 371.253149 -243.027574) (xy 371.223584 -243.066918)
			(xy 371.188091 -243.10101) (xy 371.147588 -243.128966) (xy 371.103126 -243.150064) (xy 371.055855 -243.163756)
			(xy 371.007 -243.169688) (xy 370.957825 -243.167707) (xy 370.909606 -243.157863) (xy 370.86359 -243.140411)
			(xy 370.820969 -243.115804) (xy 370.782848 -243.084679) (xy 370.750213 -243.047842) (xy 370.72391 -243.006246)
			(xy 370.704619 -242.96097) (xy 370.692842 -242.913186) (xy 370.688882 -242.864132) (xy 370.360194 -242.864132)
			(xy 370.359699 -242.888739) (xy 370.351804 -242.937316) (xy 370.33622 -242.983997) (xy 370.313349 -243.027574)
			(xy 370.283784 -243.066918) (xy 370.248291 -243.10101) (xy 370.207788 -243.128966) (xy 370.163326 -243.150064)
			(xy 370.116055 -243.163756) (xy 370.0672 -243.169688) (xy 370.018025 -243.167707) (xy 369.969806 -243.157863)
			(xy 369.92379 -243.140411) (xy 369.881169 -243.115804) (xy 369.843048 -243.084679) (xy 369.810413 -243.047842)
			(xy 369.78411 -243.006246) (xy 369.764819 -242.96097) (xy 369.753042 -242.913186) (xy 369.749082 -242.864132)
			(xy 369.42014 -242.864132) (xy 369.419645 -242.888739) (xy 369.41175 -242.937316) (xy 369.396166 -242.983997)
			(xy 369.373295 -243.027574) (xy 369.34373 -243.066918) (xy 369.308237 -243.10101) (xy 369.267734 -243.128966)
			(xy 369.223272 -243.150064) (xy 369.176001 -243.163756) (xy 369.127146 -243.169688) (xy 369.077971 -243.167707)
			(xy 369.029752 -243.157863) (xy 368.983736 -243.140411) (xy 368.941115 -243.115804) (xy 368.902994 -243.084679)
			(xy 368.870359 -243.047842) (xy 368.844056 -243.006246) (xy 368.824765 -242.96097) (xy 368.812988 -242.913186)
			(xy 368.809028 -242.864132) (xy 368.480086 -242.864132) (xy 368.479591 -242.888739) (xy 368.471696 -242.937316)
			(xy 368.456112 -242.983997) (xy 368.433241 -243.027574) (xy 368.403676 -243.066918) (xy 368.368183 -243.10101)
			(xy 368.32768 -243.128966) (xy 368.283218 -243.150064) (xy 368.235947 -243.163756) (xy 368.187092 -243.169688)
			(xy 368.137917 -243.167707) (xy 368.089698 -243.157863) (xy 368.043682 -243.140411) (xy 368.001061 -243.115804)
			(xy 367.96294 -243.084679) (xy 367.930305 -243.047842) (xy 367.904002 -243.006246) (xy 367.884711 -242.96097)
			(xy 367.872934 -242.913186) (xy 367.868974 -242.864132) (xy 367.540032 -242.864132) (xy 367.539537 -242.888739)
			(xy 367.531642 -242.937316) (xy 367.516058 -242.983997) (xy 367.493187 -243.027574) (xy 367.463622 -243.066918)
			(xy 367.428129 -243.10101) (xy 367.387626 -243.128966) (xy 367.343164 -243.150064) (xy 367.295893 -243.163756)
			(xy 367.247038 -243.169688) (xy 367.197863 -243.167707) (xy 367.149644 -243.157863) (xy 367.103628 -243.140411)
			(xy 367.061007 -243.115804) (xy 367.022886 -243.084679) (xy 366.990251 -243.047842) (xy 366.963948 -243.006246)
			(xy 366.944657 -242.96097) (xy 366.93288 -242.913186) (xy 366.92892 -242.864132) (xy 366.600232 -242.864132)
			(xy 366.599737 -242.888739) (xy 366.591842 -242.937316) (xy 366.576258 -242.983997) (xy 366.553387 -243.027574)
			(xy 366.523822 -243.066918) (xy 366.488329 -243.10101) (xy 366.447826 -243.128966) (xy 366.403364 -243.150064)
			(xy 366.356093 -243.163756) (xy 366.307238 -243.169688) (xy 366.258063 -243.167707) (xy 366.209844 -243.157863)
			(xy 366.163828 -243.140411) (xy 366.121207 -243.115804) (xy 366.083086 -243.084679) (xy 366.050451 -243.047842)
			(xy 366.024148 -243.006246) (xy 366.004857 -242.96097) (xy 365.99308 -242.913186) (xy 365.98912 -242.864132)
			(xy 365.660178 -242.864132) (xy 365.659683 -242.888739) (xy 365.651788 -242.937316) (xy 365.636204 -242.983997)
			(xy 365.613333 -243.027574) (xy 365.583768 -243.066918) (xy 365.548275 -243.10101) (xy 365.507772 -243.128966)
			(xy 365.46331 -243.150064) (xy 365.416039 -243.163756) (xy 365.367184 -243.169688) (xy 365.318009 -243.167707)
			(xy 365.26979 -243.157863) (xy 365.223774 -243.140411) (xy 365.181153 -243.115804) (xy 365.143032 -243.084679)
			(xy 365.110397 -243.047842) (xy 365.084094 -243.006246) (xy 365.064803 -242.96097) (xy 365.053026 -242.913186)
			(xy 365.049066 -242.864132) (xy 364.720124 -242.864132) (xy 364.719629 -242.888739) (xy 364.711734 -242.937316)
			(xy 364.69615 -242.983997) (xy 364.673279 -243.027574) (xy 364.643714 -243.066918) (xy 364.608221 -243.10101)
			(xy 364.567718 -243.128966) (xy 364.523256 -243.150064) (xy 364.475985 -243.163756) (xy 364.42713 -243.169688)
			(xy 364.377955 -243.167707) (xy 364.329736 -243.157863) (xy 364.28372 -243.140411) (xy 364.241099 -243.115804)
			(xy 364.202978 -243.084679) (xy 364.170343 -243.047842) (xy 364.14404 -243.006246) (xy 364.124749 -242.96097)
			(xy 364.112972 -242.913186) (xy 364.109012 -242.864132) (xy 363.78007 -242.864132) (xy 363.779575 -242.888739)
			(xy 363.77168 -242.937316) (xy 363.756096 -242.983997) (xy 363.733225 -243.027574) (xy 363.70366 -243.066918)
			(xy 363.668167 -243.10101) (xy 363.627664 -243.128966) (xy 363.583202 -243.150064) (xy 363.535931 -243.163756)
			(xy 363.487076 -243.169688) (xy 363.437901 -243.167707) (xy 363.389682 -243.157863) (xy 363.343666 -243.140411)
			(xy 363.301045 -243.115804) (xy 363.262924 -243.084679) (xy 363.230289 -243.047842) (xy 363.203986 -243.006246)
			(xy 363.184695 -242.96097) (xy 363.172918 -242.913186) (xy 363.168958 -242.864132) (xy 356.266496 -242.864132)
			(xy 356.266001 -242.888739) (xy 356.258106 -242.937316) (xy 356.242522 -242.983997) (xy 356.219651 -243.027574)
			(xy 356.190086 -243.066918) (xy 356.154593 -243.10101) (xy 356.11409 -243.128966) (xy 356.069628 -243.150064)
			(xy 356.022357 -243.163756) (xy 355.973502 -243.169688) (xy 355.924327 -243.167707) (xy 355.876108 -243.157863)
			(xy 355.830092 -243.140411) (xy 355.787471 -243.115804) (xy 355.74935 -243.084679) (xy 355.716715 -243.047842)
			(xy 355.690412 -243.006246) (xy 355.671121 -242.96097) (xy 355.659344 -242.913186) (xy 355.655384 -242.864132)
			(xy 355.326442 -242.864132) (xy 355.325947 -242.888739) (xy 355.318052 -242.937316) (xy 355.302468 -242.983997)
			(xy 355.279597 -243.027574) (xy 355.250032 -243.066918) (xy 355.214539 -243.10101) (xy 355.174036 -243.128966)
			(xy 355.129574 -243.150064) (xy 355.082303 -243.163756) (xy 355.033448 -243.169688) (xy 354.984273 -243.167707)
			(xy 354.936054 -243.157863) (xy 354.890038 -243.140411) (xy 354.847417 -243.115804) (xy 354.809296 -243.084679)
			(xy 354.776661 -243.047842) (xy 354.750358 -243.006246) (xy 354.731067 -242.96097) (xy 354.71929 -242.913186)
			(xy 354.71533 -242.864132) (xy 354.386388 -242.864132) (xy 354.385893 -242.888739) (xy 354.377998 -242.937316)
			(xy 354.362414 -242.983997) (xy 354.339543 -243.027574) (xy 354.309978 -243.066918) (xy 354.274485 -243.10101)
			(xy 354.233982 -243.128966) (xy 354.18952 -243.150064) (xy 354.142249 -243.163756) (xy 354.093394 -243.169688)
			(xy 354.044219 -243.167707) (xy 353.996 -243.157863) (xy 353.949984 -243.140411) (xy 353.907363 -243.115804)
			(xy 353.869242 -243.084679) (xy 353.836607 -243.047842) (xy 353.810304 -243.006246) (xy 353.791013 -242.96097)
			(xy 353.779236 -242.913186) (xy 353.775276 -242.864132) (xy 353.446334 -242.864132) (xy 353.445839 -242.888739)
			(xy 353.437944 -242.937316) (xy 353.42236 -242.983997) (xy 353.399489 -243.027574) (xy 353.369924 -243.066918)
			(xy 353.334431 -243.10101) (xy 353.293928 -243.128966) (xy 353.249466 -243.150064) (xy 353.202195 -243.163756)
			(xy 353.15334 -243.169688) (xy 353.104165 -243.167707) (xy 353.055946 -243.157863) (xy 353.00993 -243.140411)
			(xy 352.967309 -243.115804) (xy 352.929188 -243.084679) (xy 352.896553 -243.047842) (xy 352.87025 -243.006246)
			(xy 352.850959 -242.96097) (xy 352.839182 -242.913186) (xy 352.835222 -242.864132) (xy 352.506534 -242.864132)
			(xy 352.506039 -242.888739) (xy 352.498144 -242.937316) (xy 352.48256 -242.983997) (xy 352.459689 -243.027574)
			(xy 352.430124 -243.066918) (xy 352.394631 -243.10101) (xy 352.354128 -243.128966) (xy 352.309666 -243.150064)
			(xy 352.262395 -243.163756) (xy 352.21354 -243.169688) (xy 352.164365 -243.167707) (xy 352.116146 -243.157863)
			(xy 352.07013 -243.140411) (xy 352.027509 -243.115804) (xy 351.989388 -243.084679) (xy 351.956753 -243.047842)
			(xy 351.93045 -243.006246) (xy 351.911159 -242.96097) (xy 351.899382 -242.913186) (xy 351.895422 -242.864132)
			(xy 351.56648 -242.864132) (xy 351.565985 -242.888739) (xy 351.55809 -242.937316) (xy 351.542506 -242.983997)
			(xy 351.519635 -243.027574) (xy 351.49007 -243.066918) (xy 351.454577 -243.10101) (xy 351.414074 -243.128966)
			(xy 351.369612 -243.150064) (xy 351.322341 -243.163756) (xy 351.273486 -243.169688) (xy 351.224311 -243.167707)
			(xy 351.176092 -243.157863) (xy 351.130076 -243.140411) (xy 351.087455 -243.115804) (xy 351.049334 -243.084679)
			(xy 351.016699 -243.047842) (xy 350.990396 -243.006246) (xy 350.971105 -242.96097) (xy 350.959328 -242.913186)
			(xy 350.955368 -242.864132) (xy 350.626426 -242.864132) (xy 350.625931 -242.888739) (xy 350.618036 -242.937316)
			(xy 350.602452 -242.983997) (xy 350.579581 -243.027574) (xy 350.550016 -243.066918) (xy 350.514523 -243.10101)
			(xy 350.47402 -243.128966) (xy 350.429558 -243.150064) (xy 350.382287 -243.163756) (xy 350.333432 -243.169688)
			(xy 350.284257 -243.167707) (xy 350.236038 -243.157863) (xy 350.190022 -243.140411) (xy 350.147401 -243.115804)
			(xy 350.10928 -243.084679) (xy 350.076645 -243.047842) (xy 350.050342 -243.006246) (xy 350.031051 -242.96097)
			(xy 350.019274 -242.913186) (xy 350.015314 -242.864132) (xy 349.686372 -242.864132) (xy 349.685877 -242.888739)
			(xy 349.677982 -242.937316) (xy 349.662398 -242.983997) (xy 349.639527 -243.027574) (xy 349.609962 -243.066918)
			(xy 349.574469 -243.10101) (xy 349.533966 -243.128966) (xy 349.489504 -243.150064) (xy 349.442233 -243.163756)
			(xy 349.393378 -243.169688) (xy 349.344203 -243.167707) (xy 349.295984 -243.157863) (xy 349.249968 -243.140411)
			(xy 349.207347 -243.115804) (xy 349.169226 -243.084679) (xy 349.136591 -243.047842) (xy 349.110288 -243.006246)
			(xy 349.090997 -242.96097) (xy 349.07922 -242.913186) (xy 349.07526 -242.864132) (xy 348.746318 -242.864132)
			(xy 348.745823 -242.888739) (xy 348.737928 -242.937316) (xy 348.722344 -242.983997) (xy 348.699473 -243.027574)
			(xy 348.669908 -243.066918) (xy 348.634415 -243.10101) (xy 348.593912 -243.128966) (xy 348.54945 -243.150064)
			(xy 348.502179 -243.163756) (xy 348.453324 -243.169688) (xy 348.404149 -243.167707) (xy 348.35593 -243.157863)
			(xy 348.309914 -243.140411) (xy 348.267293 -243.115804) (xy 348.229172 -243.084679) (xy 348.196537 -243.047842)
			(xy 348.170234 -243.006246) (xy 348.150943 -242.96097) (xy 348.139166 -242.913186) (xy 348.135206 -242.864132)
			(xy 347.806518 -242.864132) (xy 347.806023 -242.888739) (xy 347.798128 -242.937316) (xy 347.782544 -242.983997)
			(xy 347.759673 -243.027574) (xy 347.730108 -243.066918) (xy 347.694615 -243.10101) (xy 347.654112 -243.128966)
			(xy 347.60965 -243.150064) (xy 347.562379 -243.163756) (xy 347.513524 -243.169688) (xy 347.464349 -243.167707)
			(xy 347.41613 -243.157863) (xy 347.370114 -243.140411) (xy 347.327493 -243.115804) (xy 347.289372 -243.084679)
			(xy 347.256737 -243.047842) (xy 347.230434 -243.006246) (xy 347.211143 -242.96097) (xy 347.199366 -242.913186)
			(xy 347.195406 -242.864132) (xy 346.866464 -242.864132) (xy 346.865969 -242.888739) (xy 346.858074 -242.937316)
			(xy 346.84249 -242.983997) (xy 346.819619 -243.027574) (xy 346.790054 -243.066918) (xy 346.754561 -243.10101)
			(xy 346.714058 -243.128966) (xy 346.669596 -243.150064) (xy 346.622325 -243.163756) (xy 346.57347 -243.169688)
			(xy 346.524295 -243.167707) (xy 346.476076 -243.157863) (xy 346.43006 -243.140411) (xy 346.387439 -243.115804)
			(xy 346.349318 -243.084679) (xy 346.316683 -243.047842) (xy 346.29038 -243.006246) (xy 346.271089 -242.96097)
			(xy 346.259312 -242.913186) (xy 346.255352 -242.864132) (xy 345.92641 -242.864132) (xy 345.925915 -242.888739)
			(xy 345.91802 -242.937316) (xy 345.902436 -242.983997) (xy 345.879565 -243.027574) (xy 345.85 -243.066918)
			(xy 345.814507 -243.10101) (xy 345.774004 -243.128966) (xy 345.729542 -243.150064) (xy 345.682271 -243.163756)
			(xy 345.633416 -243.169688) (xy 345.584241 -243.167707) (xy 345.536022 -243.157863) (xy 345.490006 -243.140411)
			(xy 345.447385 -243.115804) (xy 345.409264 -243.084679) (xy 345.376629 -243.047842) (xy 345.350326 -243.006246)
			(xy 345.331035 -242.96097) (xy 345.319258 -242.913186) (xy 345.315298 -242.864132) (xy 344.986887 -242.864132)
			(xy 344.982974 -242.912885) (xy 344.971329 -242.960419) (xy 344.952252 -243.005488) (xy 344.926232 -243.046937)
			(xy 344.893935 -243.083707) (xy 344.856186 -243.114855) (xy 344.813954 -243.139584) (xy 344.768318 -243.157262)
			(xy 344.720447 -243.167435) (xy 344.696034 -243.169186) (xy 344.686636 -243.16944) (xy 344.669618 -243.17706)
			(xy 344.641424 -243.204746) (xy 344.634607 -243.212011) (xy 344.626876 -243.230353) (xy 344.626438 -243.240306)
			(xy 344.626438 -243.674138) (xy 344.845398 -243.674138) (xy 344.849358 -243.625084) (xy 344.861135 -243.5773)
			(xy 344.880426 -243.532024) (xy 344.906729 -243.490428) (xy 344.939364 -243.453591) (xy 344.977485 -243.422466)
			(xy 345.020106 -243.397859) (xy 345.066122 -243.380407) (xy 345.114341 -243.370563) (xy 345.163516 -243.368582)
			(xy 345.212371 -243.374514) (xy 345.259642 -243.388206) (xy 345.304104 -243.409304) (xy 345.344607 -243.43726)
			(xy 345.3801 -243.471352) (xy 345.409665 -243.510696) (xy 345.432536 -243.554273) (xy 345.44812 -243.600954)
			(xy 345.456015 -243.649531) (xy 345.45651 -243.674138) (xy 345.785198 -243.674138) (xy 345.789158 -243.625084)
			(xy 345.800935 -243.5773) (xy 345.820226 -243.532024) (xy 345.846529 -243.490428) (xy 345.879164 -243.453591)
			(xy 345.917285 -243.422466) (xy 345.959906 -243.397859) (xy 346.005922 -243.380407) (xy 346.054141 -243.370563)
			(xy 346.103316 -243.368582) (xy 346.152171 -243.374514) (xy 346.199442 -243.388206) (xy 346.243904 -243.409304)
			(xy 346.284407 -243.43726) (xy 346.3199 -243.471352) (xy 346.349465 -243.510696) (xy 346.372336 -243.554273)
			(xy 346.38792 -243.600954) (xy 346.395815 -243.649531) (xy 346.39631 -243.674138) (xy 346.725252 -243.674138)
			(xy 346.729212 -243.625084) (xy 346.740989 -243.5773) (xy 346.76028 -243.532024) (xy 346.786583 -243.490428)
			(xy 346.819218 -243.453591) (xy 346.857339 -243.422466) (xy 346.89996 -243.397859) (xy 346.945976 -243.380407)
			(xy 346.994195 -243.370563) (xy 347.04337 -243.368582) (xy 347.092225 -243.374514) (xy 347.139496 -243.388206)
			(xy 347.183958 -243.409304) (xy 347.224461 -243.43726) (xy 347.259954 -243.471352) (xy 347.289519 -243.510696)
			(xy 347.31239 -243.554273) (xy 347.327974 -243.600954) (xy 347.335869 -243.649531) (xy 347.336364 -243.674138)
			(xy 347.665306 -243.674138) (xy 347.669266 -243.625084) (xy 347.681043 -243.5773) (xy 347.700334 -243.532024)
			(xy 347.726637 -243.490428) (xy 347.759272 -243.453591) (xy 347.797393 -243.422466) (xy 347.840014 -243.397859)
			(xy 347.88603 -243.380407) (xy 347.934249 -243.370563) (xy 347.983424 -243.368582) (xy 348.032279 -243.374514)
			(xy 348.07955 -243.388206) (xy 348.124012 -243.409304) (xy 348.164515 -243.43726) (xy 348.200008 -243.471352)
			(xy 348.229573 -243.510696) (xy 348.252444 -243.554273) (xy 348.268028 -243.600954) (xy 348.275923 -243.649531)
			(xy 348.276418 -243.674138) (xy 348.60536 -243.674138) (xy 348.60932 -243.625084) (xy 348.621097 -243.5773)
			(xy 348.640388 -243.532024) (xy 348.666691 -243.490428) (xy 348.699326 -243.453591) (xy 348.737447 -243.422466)
			(xy 348.780068 -243.397859) (xy 348.826084 -243.380407) (xy 348.874303 -243.370563) (xy 348.923478 -243.368582)
			(xy 348.972333 -243.374514) (xy 349.019604 -243.388206) (xy 349.064066 -243.409304) (xy 349.104569 -243.43726)
			(xy 349.140062 -243.471352) (xy 349.169627 -243.510696) (xy 349.192498 -243.554273) (xy 349.208082 -243.600954)
			(xy 349.215977 -243.649531) (xy 349.216472 -243.674138) (xy 349.545414 -243.674138) (xy 349.549374 -243.625084)
			(xy 349.561151 -243.5773) (xy 349.580442 -243.532024) (xy 349.606745 -243.490428) (xy 349.63938 -243.453591)
			(xy 349.677501 -243.422466) (xy 349.720122 -243.397859) (xy 349.766138 -243.380407) (xy 349.814357 -243.370563)
			(xy 349.863532 -243.368582) (xy 349.912387 -243.374514) (xy 349.959658 -243.388206) (xy 350.00412 -243.409304)
			(xy 350.044623 -243.43726) (xy 350.080116 -243.471352) (xy 350.109681 -243.510696) (xy 350.132552 -243.554273)
			(xy 350.148136 -243.600954) (xy 350.156031 -243.649531) (xy 350.156526 -243.674138) (xy 350.485214 -243.674138)
			(xy 350.489174 -243.625084) (xy 350.500951 -243.5773) (xy 350.520242 -243.532024) (xy 350.546545 -243.490428)
			(xy 350.57918 -243.453591) (xy 350.617301 -243.422466) (xy 350.659922 -243.397859) (xy 350.705938 -243.380407)
			(xy 350.754157 -243.370563) (xy 350.803332 -243.368582) (xy 350.852187 -243.374514) (xy 350.899458 -243.388206)
			(xy 350.94392 -243.409304) (xy 350.984423 -243.43726) (xy 351.019916 -243.471352) (xy 351.049481 -243.510696)
			(xy 351.072352 -243.554273) (xy 351.087936 -243.600954) (xy 351.095831 -243.649531) (xy 351.096326 -243.674138)
			(xy 351.425268 -243.674138) (xy 351.429228 -243.625084) (xy 351.441005 -243.5773) (xy 351.460296 -243.532024)
			(xy 351.486599 -243.490428) (xy 351.519234 -243.453591) (xy 351.557355 -243.422466) (xy 351.599976 -243.397859)
			(xy 351.645992 -243.380407) (xy 351.694211 -243.370563) (xy 351.743386 -243.368582) (xy 351.792241 -243.374514)
			(xy 351.839512 -243.388206) (xy 351.883974 -243.409304) (xy 351.924477 -243.43726) (xy 351.95997 -243.471352)
			(xy 351.989535 -243.510696) (xy 352.012406 -243.554273) (xy 352.02799 -243.600954) (xy 352.035885 -243.649531)
			(xy 352.03638 -243.674138) (xy 352.365322 -243.674138) (xy 352.369282 -243.625084) (xy 352.381059 -243.5773)
			(xy 352.40035 -243.532024) (xy 352.426653 -243.490428) (xy 352.459288 -243.453591) (xy 352.497409 -243.422466)
			(xy 352.54003 -243.397859) (xy 352.586046 -243.380407) (xy 352.634265 -243.370563) (xy 352.68344 -243.368582)
			(xy 352.732295 -243.374514) (xy 352.779566 -243.388206) (xy 352.824028 -243.409304) (xy 352.864531 -243.43726)
			(xy 352.900024 -243.471352) (xy 352.929589 -243.510696) (xy 352.95246 -243.554273) (xy 352.968044 -243.600954)
			(xy 352.975939 -243.649531) (xy 352.976434 -243.674138) (xy 353.305376 -243.674138) (xy 353.309336 -243.625084)
			(xy 353.321113 -243.5773) (xy 353.340404 -243.532024) (xy 353.366707 -243.490428) (xy 353.399342 -243.453591)
			(xy 353.437463 -243.422466) (xy 353.480084 -243.397859) (xy 353.5261 -243.380407) (xy 353.574319 -243.370563)
			(xy 353.623494 -243.368582) (xy 353.672349 -243.374514) (xy 353.71962 -243.388206) (xy 353.764082 -243.409304)
			(xy 353.804585 -243.43726) (xy 353.840078 -243.471352) (xy 353.869643 -243.510696) (xy 353.892514 -243.554273)
			(xy 353.908098 -243.600954) (xy 353.915993 -243.649531) (xy 353.916488 -243.674138) (xy 354.24543 -243.674138)
			(xy 354.24939 -243.625084) (xy 354.261167 -243.5773) (xy 354.280458 -243.532024) (xy 354.306761 -243.490428)
			(xy 354.339396 -243.453591) (xy 354.377517 -243.422466) (xy 354.420138 -243.397859) (xy 354.466154 -243.380407)
			(xy 354.514373 -243.370563) (xy 354.563548 -243.368582) (xy 354.612403 -243.374514) (xy 354.659674 -243.388206)
			(xy 354.704136 -243.409304) (xy 354.744639 -243.43726) (xy 354.780132 -243.471352) (xy 354.809697 -243.510696)
			(xy 354.832568 -243.554273) (xy 354.848152 -243.600954) (xy 354.856047 -243.649531) (xy 354.856542 -243.674138)
			(xy 355.18523 -243.674138) (xy 355.18919 -243.625084) (xy 355.200967 -243.5773) (xy 355.220258 -243.532024)
			(xy 355.246561 -243.490428) (xy 355.279196 -243.453591) (xy 355.317317 -243.422466) (xy 355.359938 -243.397859)
			(xy 355.405954 -243.380407) (xy 355.454173 -243.370563) (xy 355.503348 -243.368582) (xy 355.552203 -243.374514)
			(xy 355.599474 -243.388206) (xy 355.643936 -243.409304) (xy 355.684439 -243.43726) (xy 355.719932 -243.471352)
			(xy 355.749497 -243.510696) (xy 355.772368 -243.554273) (xy 355.787952 -243.600954) (xy 355.795847 -243.649531)
			(xy 355.796342 -243.674138) (xy 356.125284 -243.674138) (xy 356.129244 -243.625084) (xy 356.141021 -243.5773)
			(xy 356.160312 -243.532024) (xy 356.186615 -243.490428) (xy 356.21925 -243.453591) (xy 356.257371 -243.422466)
			(xy 356.299992 -243.397859) (xy 356.346008 -243.380407) (xy 356.394227 -243.370563) (xy 356.443402 -243.368582)
			(xy 356.492257 -243.374514) (xy 356.539528 -243.388206) (xy 356.58399 -243.409304) (xy 356.624493 -243.43726)
			(xy 356.659986 -243.471352) (xy 356.689551 -243.510696) (xy 356.712422 -243.554273) (xy 356.728006 -243.600954)
			(xy 356.735901 -243.649531) (xy 356.736396 -243.674138) (xy 357.065338 -243.674138) (xy 357.069298 -243.625084)
			(xy 357.081075 -243.5773) (xy 357.100366 -243.532024) (xy 357.126669 -243.490428) (xy 357.159304 -243.453591)
			(xy 357.197425 -243.422466) (xy 357.240046 -243.397859) (xy 357.286062 -243.380407) (xy 357.334281 -243.370563)
			(xy 357.383456 -243.368582) (xy 357.432311 -243.374514) (xy 357.479582 -243.388206) (xy 357.524044 -243.409304)
			(xy 357.564547 -243.43726) (xy 357.60004 -243.471352) (xy 357.629605 -243.510696) (xy 357.652476 -243.554273)
			(xy 357.66806 -243.600954) (xy 357.675955 -243.649531) (xy 357.67645 -243.674138) (xy 358.005392 -243.674138)
			(xy 358.009352 -243.625084) (xy 358.021129 -243.5773) (xy 358.04042 -243.532024) (xy 358.066723 -243.490428)
			(xy 358.099358 -243.453591) (xy 358.137479 -243.422466) (xy 358.1801 -243.397859) (xy 358.226116 -243.380407)
			(xy 358.274335 -243.370563) (xy 358.32351 -243.368582) (xy 358.372365 -243.374514) (xy 358.419636 -243.388206)
			(xy 358.464098 -243.409304) (xy 358.504601 -243.43726) (xy 358.540094 -243.471352) (xy 358.569659 -243.510696)
			(xy 358.59253 -243.554273) (xy 358.608114 -243.600954) (xy 358.616009 -243.649531) (xy 358.616504 -243.674138)
			(xy 360.81895 -243.674138) (xy 360.82291 -243.625084) (xy 360.834687 -243.5773) (xy 360.853978 -243.532024)
			(xy 360.880281 -243.490428) (xy 360.912916 -243.453591) (xy 360.951037 -243.422466) (xy 360.993658 -243.397859)
			(xy 361.039674 -243.380407) (xy 361.087893 -243.370563) (xy 361.137068 -243.368582) (xy 361.185923 -243.374514)
			(xy 361.233194 -243.388206) (xy 361.277656 -243.409304) (xy 361.318159 -243.43726) (xy 361.353652 -243.471352)
			(xy 361.383217 -243.510696) (xy 361.406088 -243.554273) (xy 361.421672 -243.600954) (xy 361.429567 -243.649531)
			(xy 361.430061 -243.6741) (xy 361.758723 -243.6741) (xy 361.762898 -243.623721) (xy 361.775308 -243.574716)
			(xy 361.795615 -243.528421) (xy 361.823265 -243.486101) (xy 361.857503 -243.448909) (xy 361.897396 -243.41786)
			(xy 361.941856 -243.393801) (xy 361.989669 -243.377388) (xy 362.039532 -243.369068) (xy 362.064808 -243.368576)
			(xy 363.004862 -243.368576) (xy 363.030146 -243.36899) (xy 363.080025 -243.377308) (xy 363.127854 -243.393722)
			(xy 363.172329 -243.417786) (xy 363.212237 -243.448843) (xy 363.246487 -243.486045) (xy 363.274147 -243.528377)
			(xy 363.294462 -243.574685) (xy 363.306876 -243.623705) (xy 363.311053 -243.6741) (xy 363.31105 -243.674138)
			(xy 363.639112 -243.674138) (xy 363.643072 -243.625084) (xy 363.654849 -243.5773) (xy 363.67414 -243.532024)
			(xy 363.700443 -243.490428) (xy 363.733078 -243.453591) (xy 363.771199 -243.422466) (xy 363.81382 -243.397859)
			(xy 363.859836 -243.380407) (xy 363.908055 -243.370563) (xy 363.95723 -243.368582) (xy 364.006085 -243.374514)
			(xy 364.053356 -243.388206) (xy 364.097818 -243.409304) (xy 364.138321 -243.43726) (xy 364.173814 -243.471352)
			(xy 364.203379 -243.510696) (xy 364.22625 -243.554273) (xy 364.241834 -243.600954) (xy 364.249729 -243.649531)
			(xy 364.250224 -243.674138) (xy 364.578912 -243.674138) (xy 364.582872 -243.625084) (xy 364.594649 -243.5773)
			(xy 364.61394 -243.532024) (xy 364.640243 -243.490428) (xy 364.672878 -243.453591) (xy 364.710999 -243.422466)
			(xy 364.75362 -243.397859) (xy 364.799636 -243.380407) (xy 364.847855 -243.370563) (xy 364.89703 -243.368582)
			(xy 364.945885 -243.374514) (xy 364.993156 -243.388206) (xy 365.037618 -243.409304) (xy 365.078121 -243.43726)
			(xy 365.113614 -243.471352) (xy 365.143179 -243.510696) (xy 365.16605 -243.554273) (xy 365.181634 -243.600954)
			(xy 365.189529 -243.649531) (xy 365.190024 -243.674138) (xy 365.518966 -243.674138) (xy 365.522926 -243.625084)
			(xy 365.534703 -243.5773) (xy 365.553994 -243.532024) (xy 365.580297 -243.490428) (xy 365.612932 -243.453591)
			(xy 365.651053 -243.422466) (xy 365.693674 -243.397859) (xy 365.73969 -243.380407) (xy 365.787909 -243.370563)
			(xy 365.837084 -243.368582) (xy 365.885939 -243.374514) (xy 365.93321 -243.388206) (xy 365.977672 -243.409304)
			(xy 366.018175 -243.43726) (xy 366.053668 -243.471352) (xy 366.083233 -243.510696) (xy 366.106104 -243.554273)
			(xy 366.121688 -243.600954) (xy 366.129583 -243.649531) (xy 366.130078 -243.674138) (xy 366.45902 -243.674138)
			(xy 366.46298 -243.625084) (xy 366.474757 -243.5773) (xy 366.494048 -243.532024) (xy 366.520351 -243.490428)
			(xy 366.552986 -243.453591) (xy 366.591107 -243.422466) (xy 366.633728 -243.397859) (xy 366.679744 -243.380407)
			(xy 366.727963 -243.370563) (xy 366.777138 -243.368582) (xy 366.825993 -243.374514) (xy 366.873264 -243.388206)
			(xy 366.917726 -243.409304) (xy 366.958229 -243.43726) (xy 366.993722 -243.471352) (xy 367.023287 -243.510696)
			(xy 367.046158 -243.554273) (xy 367.061742 -243.600954) (xy 367.069637 -243.649531) (xy 367.070132 -243.674138)
			(xy 367.399074 -243.674138) (xy 367.403034 -243.625084) (xy 367.414811 -243.5773) (xy 367.434102 -243.532024)
			(xy 367.460405 -243.490428) (xy 367.49304 -243.453591) (xy 367.531161 -243.422466) (xy 367.573782 -243.397859)
			(xy 367.619798 -243.380407) (xy 367.668017 -243.370563) (xy 367.717192 -243.368582) (xy 367.766047 -243.374514)
			(xy 367.813318 -243.388206) (xy 367.85778 -243.409304) (xy 367.898283 -243.43726) (xy 367.933776 -243.471352)
			(xy 367.963341 -243.510696) (xy 367.986212 -243.554273) (xy 368.001796 -243.600954) (xy 368.009691 -243.649531)
			(xy 368.010186 -243.674138) (xy 368.338874 -243.674138) (xy 368.342834 -243.625084) (xy 368.354611 -243.5773)
			(xy 368.373902 -243.532024) (xy 368.400205 -243.490428) (xy 368.43284 -243.453591) (xy 368.470961 -243.422466)
			(xy 368.513582 -243.397859) (xy 368.559598 -243.380407) (xy 368.607817 -243.370563) (xy 368.656992 -243.368582)
			(xy 368.705847 -243.374514) (xy 368.753118 -243.388206) (xy 368.79758 -243.409304) (xy 368.838083 -243.43726)
			(xy 368.873576 -243.471352) (xy 368.903141 -243.510696) (xy 368.926012 -243.554273) (xy 368.941596 -243.600954)
			(xy 368.949491 -243.649531) (xy 368.949986 -243.674138) (xy 369.278928 -243.674138) (xy 369.282888 -243.625084)
			(xy 369.294665 -243.5773) (xy 369.313956 -243.532024) (xy 369.340259 -243.490428) (xy 369.372894 -243.453591)
			(xy 369.411015 -243.422466) (xy 369.453636 -243.397859) (xy 369.499652 -243.380407) (xy 369.547871 -243.370563)
			(xy 369.597046 -243.368582) (xy 369.645901 -243.374514) (xy 369.693172 -243.388206) (xy 369.737634 -243.409304)
			(xy 369.778137 -243.43726) (xy 369.81363 -243.471352) (xy 369.843195 -243.510696) (xy 369.866066 -243.554273)
			(xy 369.88165 -243.600954) (xy 369.889545 -243.649531) (xy 369.89004 -243.674138) (xy 370.218982 -243.674138)
			(xy 370.222942 -243.625084) (xy 370.234719 -243.5773) (xy 370.25401 -243.532024) (xy 370.280313 -243.490428)
			(xy 370.312948 -243.453591) (xy 370.351069 -243.422466) (xy 370.39369 -243.397859) (xy 370.439706 -243.380407)
			(xy 370.487925 -243.370563) (xy 370.5371 -243.368582) (xy 370.585955 -243.374514) (xy 370.633226 -243.388206)
			(xy 370.677688 -243.409304) (xy 370.718191 -243.43726) (xy 370.753684 -243.471352) (xy 370.783249 -243.510696)
			(xy 370.80612 -243.554273) (xy 370.821704 -243.600954) (xy 370.829599 -243.649531) (xy 370.830094 -243.674138)
			(xy 371.159036 -243.674138) (xy 371.162996 -243.625084) (xy 371.174773 -243.5773) (xy 371.194064 -243.532024)
			(xy 371.220367 -243.490428) (xy 371.253002 -243.453591) (xy 371.291123 -243.422466) (xy 371.333744 -243.397859)
			(xy 371.37976 -243.380407) (xy 371.427979 -243.370563) (xy 371.477154 -243.368582) (xy 371.526009 -243.374514)
			(xy 371.57328 -243.388206) (xy 371.617742 -243.409304) (xy 371.658245 -243.43726) (xy 371.693738 -243.471352)
			(xy 371.723303 -243.510696) (xy 371.746174 -243.554273) (xy 371.761758 -243.600954) (xy 371.769653 -243.649531)
			(xy 371.770148 -243.674138) (xy 372.09909 -243.674138) (xy 372.10305 -243.625084) (xy 372.114827 -243.5773)
			(xy 372.134118 -243.532024) (xy 372.160421 -243.490428) (xy 372.193056 -243.453591) (xy 372.231177 -243.422466)
			(xy 372.273798 -243.397859) (xy 372.319814 -243.380407) (xy 372.368033 -243.370563) (xy 372.417208 -243.368582)
			(xy 372.466063 -243.374514) (xy 372.513334 -243.388206) (xy 372.557796 -243.409304) (xy 372.598299 -243.43726)
			(xy 372.633792 -243.471352) (xy 372.663357 -243.510696) (xy 372.686228 -243.554273) (xy 372.701812 -243.600954)
			(xy 372.709707 -243.649531) (xy 372.710202 -243.674138) (xy 373.03889 -243.674138) (xy 373.04285 -243.625084)
			(xy 373.054627 -243.5773) (xy 373.073918 -243.532024) (xy 373.100221 -243.490428) (xy 373.132856 -243.453591)
			(xy 373.170977 -243.422466) (xy 373.213598 -243.397859) (xy 373.259614 -243.380407) (xy 373.307833 -243.370563)
			(xy 373.357008 -243.368582) (xy 373.405863 -243.374514) (xy 373.453134 -243.388206) (xy 373.497596 -243.409304)
			(xy 373.538099 -243.43726) (xy 373.573592 -243.471352) (xy 373.603157 -243.510696) (xy 373.626028 -243.554273)
			(xy 373.641612 -243.600954) (xy 373.649507 -243.649531) (xy 373.650002 -243.674138) (xy 373.978944 -243.674138)
			(xy 373.982904 -243.625084) (xy 373.994681 -243.5773) (xy 374.013972 -243.532024) (xy 374.040275 -243.490428)
			(xy 374.07291 -243.453591) (xy 374.111031 -243.422466) (xy 374.153652 -243.397859) (xy 374.199668 -243.380407)
			(xy 374.247887 -243.370563) (xy 374.297062 -243.368582) (xy 374.345917 -243.374514) (xy 374.393188 -243.388206)
			(xy 374.43765 -243.409304) (xy 374.478153 -243.43726) (xy 374.513646 -243.471352) (xy 374.543211 -243.510696)
			(xy 374.566082 -243.554273) (xy 374.581666 -243.600954) (xy 374.589561 -243.649531) (xy 374.590056 -243.674138)
			(xy 374.589561 -243.698745) (xy 374.581666 -243.747322) (xy 374.566082 -243.794003) (xy 374.543211 -243.83758)
			(xy 374.513646 -243.876924) (xy 374.478153 -243.911016) (xy 374.43765 -243.938972) (xy 374.393188 -243.96007)
			(xy 374.345917 -243.973762) (xy 374.297062 -243.979694) (xy 374.247887 -243.977713) (xy 374.199668 -243.967869)
			(xy 374.153652 -243.950417) (xy 374.111031 -243.92581) (xy 374.07291 -243.894685) (xy 374.040275 -243.857848)
			(xy 374.013972 -243.816252) (xy 373.994681 -243.770976) (xy 373.982904 -243.723192) (xy 373.978944 -243.674138)
			(xy 373.650002 -243.674138) (xy 373.649507 -243.698745) (xy 373.641612 -243.747322) (xy 373.626028 -243.794003)
			(xy 373.603157 -243.83758) (xy 373.573592 -243.876924) (xy 373.538099 -243.911016) (xy 373.497596 -243.938972)
			(xy 373.453134 -243.96007) (xy 373.405863 -243.973762) (xy 373.357008 -243.979694) (xy 373.307833 -243.977713)
			(xy 373.259614 -243.967869) (xy 373.213598 -243.950417) (xy 373.170977 -243.92581) (xy 373.132856 -243.894685)
			(xy 373.100221 -243.857848) (xy 373.073918 -243.816252) (xy 373.054627 -243.770976) (xy 373.04285 -243.723192)
			(xy 373.03889 -243.674138) (xy 372.710202 -243.674138) (xy 372.709707 -243.698745) (xy 372.701812 -243.747322)
			(xy 372.686228 -243.794003) (xy 372.663357 -243.83758) (xy 372.633792 -243.876924) (xy 372.598299 -243.911016)
			(xy 372.557796 -243.938972) (xy 372.513334 -243.96007) (xy 372.466063 -243.973762) (xy 372.417208 -243.979694)
			(xy 372.368033 -243.977713) (xy 372.319814 -243.967869) (xy 372.273798 -243.950417) (xy 372.231177 -243.92581)
			(xy 372.193056 -243.894685) (xy 372.160421 -243.857848) (xy 372.134118 -243.816252) (xy 372.114827 -243.770976)
			(xy 372.10305 -243.723192) (xy 372.09909 -243.674138) (xy 371.770148 -243.674138) (xy 371.769653 -243.698745)
			(xy 371.761758 -243.747322) (xy 371.746174 -243.794003) (xy 371.723303 -243.83758) (xy 371.693738 -243.876924)
			(xy 371.658245 -243.911016) (xy 371.617742 -243.938972) (xy 371.57328 -243.96007) (xy 371.526009 -243.973762)
			(xy 371.477154 -243.979694) (xy 371.427979 -243.977713) (xy 371.37976 -243.967869) (xy 371.333744 -243.950417)
			(xy 371.291123 -243.92581) (xy 371.253002 -243.894685) (xy 371.220367 -243.857848) (xy 371.194064 -243.816252)
			(xy 371.174773 -243.770976) (xy 371.162996 -243.723192) (xy 371.159036 -243.674138) (xy 370.830094 -243.674138)
			(xy 370.829599 -243.698745) (xy 370.821704 -243.747322) (xy 370.80612 -243.794003) (xy 370.783249 -243.83758)
			(xy 370.753684 -243.876924) (xy 370.718191 -243.911016) (xy 370.677688 -243.938972) (xy 370.633226 -243.96007)
			(xy 370.585955 -243.973762) (xy 370.5371 -243.979694) (xy 370.487925 -243.977713) (xy 370.439706 -243.967869)
			(xy 370.39369 -243.950417) (xy 370.351069 -243.92581) (xy 370.312948 -243.894685) (xy 370.280313 -243.857848)
			(xy 370.25401 -243.816252) (xy 370.234719 -243.770976) (xy 370.222942 -243.723192) (xy 370.218982 -243.674138)
			(xy 369.89004 -243.674138) (xy 369.889545 -243.698745) (xy 369.88165 -243.747322) (xy 369.866066 -243.794003)
			(xy 369.843195 -243.83758) (xy 369.81363 -243.876924) (xy 369.778137 -243.911016) (xy 369.737634 -243.938972)
			(xy 369.693172 -243.96007) (xy 369.645901 -243.973762) (xy 369.597046 -243.979694) (xy 369.547871 -243.977713)
			(xy 369.499652 -243.967869) (xy 369.453636 -243.950417) (xy 369.411015 -243.92581) (xy 369.372894 -243.894685)
			(xy 369.340259 -243.857848) (xy 369.313956 -243.816252) (xy 369.294665 -243.770976) (xy 369.282888 -243.723192)
			(xy 369.278928 -243.674138) (xy 368.949986 -243.674138) (xy 368.949491 -243.698745) (xy 368.941596 -243.747322)
			(xy 368.926012 -243.794003) (xy 368.903141 -243.83758) (xy 368.873576 -243.876924) (xy 368.838083 -243.911016)
			(xy 368.79758 -243.938972) (xy 368.753118 -243.96007) (xy 368.705847 -243.973762) (xy 368.656992 -243.979694)
			(xy 368.607817 -243.977713) (xy 368.559598 -243.967869) (xy 368.513582 -243.950417) (xy 368.470961 -243.92581)
			(xy 368.43284 -243.894685) (xy 368.400205 -243.857848) (xy 368.373902 -243.816252) (xy 368.354611 -243.770976)
			(xy 368.342834 -243.723192) (xy 368.338874 -243.674138) (xy 368.010186 -243.674138) (xy 368.009691 -243.698745)
			(xy 368.001796 -243.747322) (xy 367.986212 -243.794003) (xy 367.963341 -243.83758) (xy 367.933776 -243.876924)
			(xy 367.898283 -243.911016) (xy 367.85778 -243.938972) (xy 367.813318 -243.96007) (xy 367.766047 -243.973762)
			(xy 367.717192 -243.979694) (xy 367.668017 -243.977713) (xy 367.619798 -243.967869) (xy 367.573782 -243.950417)
			(xy 367.531161 -243.92581) (xy 367.49304 -243.894685) (xy 367.460405 -243.857848) (xy 367.434102 -243.816252)
			(xy 367.414811 -243.770976) (xy 367.403034 -243.723192) (xy 367.399074 -243.674138) (xy 367.070132 -243.674138)
			(xy 367.069637 -243.698745) (xy 367.061742 -243.747322) (xy 367.046158 -243.794003) (xy 367.023287 -243.83758)
			(xy 366.993722 -243.876924) (xy 366.958229 -243.911016) (xy 366.917726 -243.938972) (xy 366.873264 -243.96007)
			(xy 366.825993 -243.973762) (xy 366.777138 -243.979694) (xy 366.727963 -243.977713) (xy 366.679744 -243.967869)
			(xy 366.633728 -243.950417) (xy 366.591107 -243.92581) (xy 366.552986 -243.894685) (xy 366.520351 -243.857848)
			(xy 366.494048 -243.816252) (xy 366.474757 -243.770976) (xy 366.46298 -243.723192) (xy 366.45902 -243.674138)
			(xy 366.130078 -243.674138) (xy 366.129583 -243.698745) (xy 366.121688 -243.747322) (xy 366.106104 -243.794003)
			(xy 366.083233 -243.83758) (xy 366.053668 -243.876924) (xy 366.018175 -243.911016) (xy 365.977672 -243.938972)
			(xy 365.93321 -243.96007) (xy 365.885939 -243.973762) (xy 365.837084 -243.979694) (xy 365.787909 -243.977713)
			(xy 365.73969 -243.967869) (xy 365.693674 -243.950417) (xy 365.651053 -243.92581) (xy 365.612932 -243.894685)
			(xy 365.580297 -243.857848) (xy 365.553994 -243.816252) (xy 365.534703 -243.770976) (xy 365.522926 -243.723192)
			(xy 365.518966 -243.674138) (xy 365.190024 -243.674138) (xy 365.189529 -243.698745) (xy 365.181634 -243.747322)
			(xy 365.16605 -243.794003) (xy 365.143179 -243.83758) (xy 365.113614 -243.876924) (xy 365.078121 -243.911016)
			(xy 365.037618 -243.938972) (xy 364.993156 -243.96007) (xy 364.945885 -243.973762) (xy 364.89703 -243.979694)
			(xy 364.847855 -243.977713) (xy 364.799636 -243.967869) (xy 364.75362 -243.950417) (xy 364.710999 -243.92581)
			(xy 364.672878 -243.894685) (xy 364.640243 -243.857848) (xy 364.61394 -243.816252) (xy 364.594649 -243.770976)
			(xy 364.582872 -243.723192) (xy 364.578912 -243.674138) (xy 364.250224 -243.674138) (xy 364.249729 -243.698745)
			(xy 364.241834 -243.747322) (xy 364.22625 -243.794003) (xy 364.203379 -243.83758) (xy 364.173814 -243.876924)
			(xy 364.138321 -243.911016) (xy 364.097818 -243.938972) (xy 364.053356 -243.96007) (xy 364.006085 -243.973762)
			(xy 363.95723 -243.979694) (xy 363.908055 -243.977713) (xy 363.859836 -243.967869) (xy 363.81382 -243.950417)
			(xy 363.771199 -243.92581) (xy 363.733078 -243.894685) (xy 363.700443 -243.857848) (xy 363.67414 -243.816252)
			(xy 363.654849 -243.770976) (xy 363.643072 -243.723192) (xy 363.639112 -243.674138) (xy 363.31105 -243.674138)
			(xy 363.306876 -243.724495) (xy 363.294462 -243.773515) (xy 363.274147 -243.819823) (xy 363.246487 -243.862155)
			(xy 363.212237 -243.899357) (xy 363.172329 -243.930414) (xy 363.127854 -243.954478) (xy 363.080025 -243.970892)
			(xy 363.030146 -243.97921) (xy 363.004862 -243.9797) (xy 362.064808 -243.9797) (xy 362.039532 -243.979132)
			(xy 361.989669 -243.970812) (xy 361.941856 -243.954399) (xy 361.897396 -243.93034) (xy 361.857503 -243.899291)
			(xy 361.823265 -243.862099) (xy 361.795615 -243.819779) (xy 361.775308 -243.773484) (xy 361.762898 -243.724479)
			(xy 361.758723 -243.6741) (xy 361.430061 -243.6741) (xy 361.430062 -243.674138) (xy 361.429567 -243.698745)
			(xy 361.421672 -243.747322) (xy 361.406088 -243.794003) (xy 361.383217 -243.83758) (xy 361.353652 -243.876924)
			(xy 361.318159 -243.911016) (xy 361.277656 -243.938972) (xy 361.233194 -243.96007) (xy 361.185923 -243.973762)
			(xy 361.137068 -243.979694) (xy 361.087893 -243.977713) (xy 361.039674 -243.967869) (xy 360.993658 -243.950417)
			(xy 360.951037 -243.92581) (xy 360.912916 -243.894685) (xy 360.880281 -243.857848) (xy 360.853978 -243.816252)
			(xy 360.834687 -243.770976) (xy 360.82291 -243.723192) (xy 360.81895 -243.674138) (xy 358.616504 -243.674138)
			(xy 358.616009 -243.698745) (xy 358.608114 -243.747322) (xy 358.59253 -243.794003) (xy 358.569659 -243.83758)
			(xy 358.540094 -243.876924) (xy 358.504601 -243.911016) (xy 358.464098 -243.938972) (xy 358.419636 -243.96007)
			(xy 358.372365 -243.973762) (xy 358.32351 -243.979694) (xy 358.274335 -243.977713) (xy 358.226116 -243.967869)
			(xy 358.1801 -243.950417) (xy 358.137479 -243.92581) (xy 358.099358 -243.894685) (xy 358.066723 -243.857848)
			(xy 358.04042 -243.816252) (xy 358.021129 -243.770976) (xy 358.009352 -243.723192) (xy 358.005392 -243.674138)
			(xy 357.67645 -243.674138) (xy 357.675955 -243.698745) (xy 357.66806 -243.747322) (xy 357.652476 -243.794003)
			(xy 357.629605 -243.83758) (xy 357.60004 -243.876924) (xy 357.564547 -243.911016) (xy 357.524044 -243.938972)
			(xy 357.479582 -243.96007) (xy 357.432311 -243.973762) (xy 357.383456 -243.979694) (xy 357.334281 -243.977713)
			(xy 357.286062 -243.967869) (xy 357.240046 -243.950417) (xy 357.197425 -243.92581) (xy 357.159304 -243.894685)
			(xy 357.126669 -243.857848) (xy 357.100366 -243.816252) (xy 357.081075 -243.770976) (xy 357.069298 -243.723192)
			(xy 357.065338 -243.674138) (xy 356.736396 -243.674138) (xy 356.735901 -243.698745) (xy 356.728006 -243.747322)
			(xy 356.712422 -243.794003) (xy 356.689551 -243.83758) (xy 356.659986 -243.876924) (xy 356.624493 -243.911016)
			(xy 356.58399 -243.938972) (xy 356.539528 -243.96007) (xy 356.492257 -243.973762) (xy 356.443402 -243.979694)
			(xy 356.394227 -243.977713) (xy 356.346008 -243.967869) (xy 356.299992 -243.950417) (xy 356.257371 -243.92581)
			(xy 356.21925 -243.894685) (xy 356.186615 -243.857848) (xy 356.160312 -243.816252) (xy 356.141021 -243.770976)
			(xy 356.129244 -243.723192) (xy 356.125284 -243.674138) (xy 355.796342 -243.674138) (xy 355.795847 -243.698745)
			(xy 355.787952 -243.747322) (xy 355.772368 -243.794003) (xy 355.749497 -243.83758) (xy 355.719932 -243.876924)
			(xy 355.684439 -243.911016) (xy 355.643936 -243.938972) (xy 355.599474 -243.96007) (xy 355.552203 -243.973762)
			(xy 355.503348 -243.979694) (xy 355.454173 -243.977713) (xy 355.405954 -243.967869) (xy 355.359938 -243.950417)
			(xy 355.317317 -243.92581) (xy 355.279196 -243.894685) (xy 355.246561 -243.857848) (xy 355.220258 -243.816252)
			(xy 355.200967 -243.770976) (xy 355.18919 -243.723192) (xy 355.18523 -243.674138) (xy 354.856542 -243.674138)
			(xy 354.856047 -243.698745) (xy 354.848152 -243.747322) (xy 354.832568 -243.794003) (xy 354.809697 -243.83758)
			(xy 354.780132 -243.876924) (xy 354.744639 -243.911016) (xy 354.704136 -243.938972) (xy 354.659674 -243.96007)
			(xy 354.612403 -243.973762) (xy 354.563548 -243.979694) (xy 354.514373 -243.977713) (xy 354.466154 -243.967869)
			(xy 354.420138 -243.950417) (xy 354.377517 -243.92581) (xy 354.339396 -243.894685) (xy 354.306761 -243.857848)
			(xy 354.280458 -243.816252) (xy 354.261167 -243.770976) (xy 354.24939 -243.723192) (xy 354.24543 -243.674138)
			(xy 353.916488 -243.674138) (xy 353.915993 -243.698745) (xy 353.908098 -243.747322) (xy 353.892514 -243.794003)
			(xy 353.869643 -243.83758) (xy 353.840078 -243.876924) (xy 353.804585 -243.911016) (xy 353.764082 -243.938972)
			(xy 353.71962 -243.96007) (xy 353.672349 -243.973762) (xy 353.623494 -243.979694) (xy 353.574319 -243.977713)
			(xy 353.5261 -243.967869) (xy 353.480084 -243.950417) (xy 353.437463 -243.92581) (xy 353.399342 -243.894685)
			(xy 353.366707 -243.857848) (xy 353.340404 -243.816252) (xy 353.321113 -243.770976) (xy 353.309336 -243.723192)
			(xy 353.305376 -243.674138) (xy 352.976434 -243.674138) (xy 352.975939 -243.698745) (xy 352.968044 -243.747322)
			(xy 352.95246 -243.794003) (xy 352.929589 -243.83758) (xy 352.900024 -243.876924) (xy 352.864531 -243.911016)
			(xy 352.824028 -243.938972) (xy 352.779566 -243.96007) (xy 352.732295 -243.973762) (xy 352.68344 -243.979694)
			(xy 352.634265 -243.977713) (xy 352.586046 -243.967869) (xy 352.54003 -243.950417) (xy 352.497409 -243.92581)
			(xy 352.459288 -243.894685) (xy 352.426653 -243.857848) (xy 352.40035 -243.816252) (xy 352.381059 -243.770976)
			(xy 352.369282 -243.723192) (xy 352.365322 -243.674138) (xy 352.03638 -243.674138) (xy 352.035885 -243.698745)
			(xy 352.02799 -243.747322) (xy 352.012406 -243.794003) (xy 351.989535 -243.83758) (xy 351.95997 -243.876924)
			(xy 351.924477 -243.911016) (xy 351.883974 -243.938972) (xy 351.839512 -243.96007) (xy 351.792241 -243.973762)
			(xy 351.743386 -243.979694) (xy 351.694211 -243.977713) (xy 351.645992 -243.967869) (xy 351.599976 -243.950417)
			(xy 351.557355 -243.92581) (xy 351.519234 -243.894685) (xy 351.486599 -243.857848) (xy 351.460296 -243.816252)
			(xy 351.441005 -243.770976) (xy 351.429228 -243.723192) (xy 351.425268 -243.674138) (xy 351.096326 -243.674138)
			(xy 351.095831 -243.698745) (xy 351.087936 -243.747322) (xy 351.072352 -243.794003) (xy 351.049481 -243.83758)
			(xy 351.019916 -243.876924) (xy 350.984423 -243.911016) (xy 350.94392 -243.938972) (xy 350.899458 -243.96007)
			(xy 350.852187 -243.973762) (xy 350.803332 -243.979694) (xy 350.754157 -243.977713) (xy 350.705938 -243.967869)
			(xy 350.659922 -243.950417) (xy 350.617301 -243.92581) (xy 350.57918 -243.894685) (xy 350.546545 -243.857848)
			(xy 350.520242 -243.816252) (xy 350.500951 -243.770976) (xy 350.489174 -243.723192) (xy 350.485214 -243.674138)
			(xy 350.156526 -243.674138) (xy 350.156031 -243.698745) (xy 350.148136 -243.747322) (xy 350.132552 -243.794003)
			(xy 350.109681 -243.83758) (xy 350.080116 -243.876924) (xy 350.044623 -243.911016) (xy 350.00412 -243.938972)
			(xy 349.959658 -243.96007) (xy 349.912387 -243.973762) (xy 349.863532 -243.979694) (xy 349.814357 -243.977713)
			(xy 349.766138 -243.967869) (xy 349.720122 -243.950417) (xy 349.677501 -243.92581) (xy 349.63938 -243.894685)
			(xy 349.606745 -243.857848) (xy 349.580442 -243.816252) (xy 349.561151 -243.770976) (xy 349.549374 -243.723192)
			(xy 349.545414 -243.674138) (xy 349.216472 -243.674138) (xy 349.215977 -243.698745) (xy 349.208082 -243.747322)
			(xy 349.192498 -243.794003) (xy 349.169627 -243.83758) (xy 349.140062 -243.876924) (xy 349.104569 -243.911016)
			(xy 349.064066 -243.938972) (xy 349.019604 -243.96007) (xy 348.972333 -243.973762) (xy 348.923478 -243.979694)
			(xy 348.874303 -243.977713) (xy 348.826084 -243.967869) (xy 348.780068 -243.950417) (xy 348.737447 -243.92581)
			(xy 348.699326 -243.894685) (xy 348.666691 -243.857848) (xy 348.640388 -243.816252) (xy 348.621097 -243.770976)
			(xy 348.60932 -243.723192) (xy 348.60536 -243.674138) (xy 348.276418 -243.674138) (xy 348.275923 -243.698745)
			(xy 348.268028 -243.747322) (xy 348.252444 -243.794003) (xy 348.229573 -243.83758) (xy 348.200008 -243.876924)
			(xy 348.164515 -243.911016) (xy 348.124012 -243.938972) (xy 348.07955 -243.96007) (xy 348.032279 -243.973762)
			(xy 347.983424 -243.979694) (xy 347.934249 -243.977713) (xy 347.88603 -243.967869) (xy 347.840014 -243.950417)
			(xy 347.797393 -243.92581) (xy 347.759272 -243.894685) (xy 347.726637 -243.857848) (xy 347.700334 -243.816252)
			(xy 347.681043 -243.770976) (xy 347.669266 -243.723192) (xy 347.665306 -243.674138) (xy 347.336364 -243.674138)
			(xy 347.335869 -243.698745) (xy 347.327974 -243.747322) (xy 347.31239 -243.794003) (xy 347.289519 -243.83758)
			(xy 347.259954 -243.876924) (xy 347.224461 -243.911016) (xy 347.183958 -243.938972) (xy 347.139496 -243.96007)
			(xy 347.092225 -243.973762) (xy 347.04337 -243.979694) (xy 346.994195 -243.977713) (xy 346.945976 -243.967869)
			(xy 346.89996 -243.950417) (xy 346.857339 -243.92581) (xy 346.819218 -243.894685) (xy 346.786583 -243.857848)
			(xy 346.76028 -243.816252) (xy 346.740989 -243.770976) (xy 346.729212 -243.723192) (xy 346.725252 -243.674138)
			(xy 346.39631 -243.674138) (xy 346.395815 -243.698745) (xy 346.38792 -243.747322) (xy 346.372336 -243.794003)
			(xy 346.349465 -243.83758) (xy 346.3199 -243.876924) (xy 346.284407 -243.911016) (xy 346.243904 -243.938972)
			(xy 346.199442 -243.96007) (xy 346.152171 -243.973762) (xy 346.103316 -243.979694) (xy 346.054141 -243.977713)
			(xy 346.005922 -243.967869) (xy 345.959906 -243.950417) (xy 345.917285 -243.92581) (xy 345.879164 -243.894685)
			(xy 345.846529 -243.857848) (xy 345.820226 -243.816252) (xy 345.800935 -243.770976) (xy 345.789158 -243.723192)
			(xy 345.785198 -243.674138) (xy 345.45651 -243.674138) (xy 345.456015 -243.698745) (xy 345.44812 -243.747322)
			(xy 345.432536 -243.794003) (xy 345.409665 -243.83758) (xy 345.3801 -243.876924) (xy 345.344607 -243.911016)
			(xy 345.304104 -243.938972) (xy 345.259642 -243.96007) (xy 345.212371 -243.973762) (xy 345.163516 -243.979694)
			(xy 345.114341 -243.977713) (xy 345.066122 -243.967869) (xy 345.020106 -243.950417) (xy 344.977485 -243.92581)
			(xy 344.939364 -243.894685) (xy 344.906729 -243.857848) (xy 344.880426 -243.816252) (xy 344.861135 -243.770976)
			(xy 344.849358 -243.723192) (xy 344.845398 -243.674138) (xy 344.626438 -243.674138) (xy 344.626438 -244.107462)
			(xy 344.626891 -244.117615) (xy 344.63476 -244.136337) (xy 344.641678 -244.143784) (xy 344.669618 -244.171216)
			(xy 344.686636 -244.178836) (xy 344.696034 -244.17909) (xy 344.720449 -244.180778) (xy 344.768318 -244.190951)
			(xy 344.813952 -244.208629) (xy 344.856182 -244.233358) (xy 344.893929 -244.264505) (xy 344.926224 -244.301273)
			(xy 344.952243 -244.342721) (xy 344.971318 -244.387789) (xy 344.982962 -244.435321) (xy 344.986877 -244.484102)
			(xy 344.986874 -244.484144) (xy 345.315298 -244.484144) (xy 345.319258 -244.43509) (xy 345.331035 -244.387306)
			(xy 345.350326 -244.34203) (xy 345.376629 -244.300434) (xy 345.409264 -244.263597) (xy 345.447385 -244.232472)
			(xy 345.490006 -244.207865) (xy 345.536022 -244.190413) (xy 345.584241 -244.180569) (xy 345.633416 -244.178588)
			(xy 345.682271 -244.18452) (xy 345.729542 -244.198212) (xy 345.774004 -244.21931) (xy 345.814507 -244.247266)
			(xy 345.85 -244.281358) (xy 345.879565 -244.320702) (xy 345.902436 -244.364279) (xy 345.91802 -244.41096)
			(xy 345.925915 -244.459537) (xy 345.92641 -244.484144) (xy 346.255352 -244.484144) (xy 346.259312 -244.43509)
			(xy 346.271089 -244.387306) (xy 346.29038 -244.34203) (xy 346.316683 -244.300434) (xy 346.349318 -244.263597)
			(xy 346.387439 -244.232472) (xy 346.43006 -244.207865) (xy 346.476076 -244.190413) (xy 346.524295 -244.180569)
			(xy 346.57347 -244.178588) (xy 346.622325 -244.18452) (xy 346.669596 -244.198212) (xy 346.714058 -244.21931)
			(xy 346.754561 -244.247266) (xy 346.790054 -244.281358) (xy 346.819619 -244.320702) (xy 346.84249 -244.364279)
			(xy 346.858074 -244.41096) (xy 346.865969 -244.459537) (xy 346.866464 -244.484144) (xy 347.195406 -244.484144)
			(xy 347.199366 -244.43509) (xy 347.211143 -244.387306) (xy 347.230434 -244.34203) (xy 347.256737 -244.300434)
			(xy 347.289372 -244.263597) (xy 347.327493 -244.232472) (xy 347.370114 -244.207865) (xy 347.41613 -244.190413)
			(xy 347.464349 -244.180569) (xy 347.513524 -244.178588) (xy 347.562379 -244.18452) (xy 347.60965 -244.198212)
			(xy 347.654112 -244.21931) (xy 347.694615 -244.247266) (xy 347.730108 -244.281358) (xy 347.759673 -244.320702)
			(xy 347.782544 -244.364279) (xy 347.798128 -244.41096) (xy 347.806023 -244.459537) (xy 347.806518 -244.484144)
			(xy 348.135206 -244.484144) (xy 348.139166 -244.43509) (xy 348.150943 -244.387306) (xy 348.170234 -244.34203)
			(xy 348.196537 -244.300434) (xy 348.229172 -244.263597) (xy 348.267293 -244.232472) (xy 348.309914 -244.207865)
			(xy 348.35593 -244.190413) (xy 348.404149 -244.180569) (xy 348.453324 -244.178588) (xy 348.502179 -244.18452)
			(xy 348.54945 -244.198212) (xy 348.593912 -244.21931) (xy 348.634415 -244.247266) (xy 348.669908 -244.281358)
			(xy 348.699473 -244.320702) (xy 348.722344 -244.364279) (xy 348.737928 -244.41096) (xy 348.745823 -244.459537)
			(xy 348.746318 -244.484144) (xy 349.07526 -244.484144) (xy 349.07922 -244.43509) (xy 349.090997 -244.387306)
			(xy 349.110288 -244.34203) (xy 349.136591 -244.300434) (xy 349.169226 -244.263597) (xy 349.207347 -244.232472)
			(xy 349.249968 -244.207865) (xy 349.295984 -244.190413) (xy 349.344203 -244.180569) (xy 349.393378 -244.178588)
			(xy 349.442233 -244.18452) (xy 349.489504 -244.198212) (xy 349.533966 -244.21931) (xy 349.574469 -244.247266)
			(xy 349.609962 -244.281358) (xy 349.639527 -244.320702) (xy 349.662398 -244.364279) (xy 349.677982 -244.41096)
			(xy 349.685877 -244.459537) (xy 349.686372 -244.484144) (xy 350.015314 -244.484144) (xy 350.019274 -244.43509)
			(xy 350.031051 -244.387306) (xy 350.050342 -244.34203) (xy 350.076645 -244.300434) (xy 350.10928 -244.263597)
			(xy 350.147401 -244.232472) (xy 350.190022 -244.207865) (xy 350.236038 -244.190413) (xy 350.284257 -244.180569)
			(xy 350.333432 -244.178588) (xy 350.382287 -244.18452) (xy 350.429558 -244.198212) (xy 350.47402 -244.21931)
			(xy 350.514523 -244.247266) (xy 350.550016 -244.281358) (xy 350.579581 -244.320702) (xy 350.602452 -244.364279)
			(xy 350.618036 -244.41096) (xy 350.625931 -244.459537) (xy 350.626426 -244.484144) (xy 350.955368 -244.484144)
			(xy 350.959328 -244.43509) (xy 350.971105 -244.387306) (xy 350.990396 -244.34203) (xy 351.016699 -244.300434)
			(xy 351.049334 -244.263597) (xy 351.087455 -244.232472) (xy 351.130076 -244.207865) (xy 351.176092 -244.190413)
			(xy 351.224311 -244.180569) (xy 351.273486 -244.178588) (xy 351.322341 -244.18452) (xy 351.369612 -244.198212)
			(xy 351.414074 -244.21931) (xy 351.454577 -244.247266) (xy 351.49007 -244.281358) (xy 351.519635 -244.320702)
			(xy 351.542506 -244.364279) (xy 351.55809 -244.41096) (xy 351.565985 -244.459537) (xy 351.56648 -244.484144)
			(xy 351.895422 -244.484144) (xy 351.899382 -244.43509) (xy 351.911159 -244.387306) (xy 351.93045 -244.34203)
			(xy 351.956753 -244.300434) (xy 351.989388 -244.263597) (xy 352.027509 -244.232472) (xy 352.07013 -244.207865)
			(xy 352.116146 -244.190413) (xy 352.164365 -244.180569) (xy 352.21354 -244.178588) (xy 352.262395 -244.18452)
			(xy 352.309666 -244.198212) (xy 352.354128 -244.21931) (xy 352.394631 -244.247266) (xy 352.430124 -244.281358)
			(xy 352.459689 -244.320702) (xy 352.48256 -244.364279) (xy 352.498144 -244.41096) (xy 352.506039 -244.459537)
			(xy 352.506534 -244.484144) (xy 352.835222 -244.484144) (xy 352.839182 -244.43509) (xy 352.850959 -244.387306)
			(xy 352.87025 -244.34203) (xy 352.896553 -244.300434) (xy 352.929188 -244.263597) (xy 352.967309 -244.232472)
			(xy 353.00993 -244.207865) (xy 353.055946 -244.190413) (xy 353.104165 -244.180569) (xy 353.15334 -244.178588)
			(xy 353.202195 -244.18452) (xy 353.249466 -244.198212) (xy 353.293928 -244.21931) (xy 353.334431 -244.247266)
			(xy 353.369924 -244.281358) (xy 353.399489 -244.320702) (xy 353.42236 -244.364279) (xy 353.437944 -244.41096)
			(xy 353.445839 -244.459537) (xy 353.446334 -244.484144) (xy 353.775276 -244.484144) (xy 353.779236 -244.43509)
			(xy 353.791013 -244.387306) (xy 353.810304 -244.34203) (xy 353.836607 -244.300434) (xy 353.869242 -244.263597)
			(xy 353.907363 -244.232472) (xy 353.949984 -244.207865) (xy 353.996 -244.190413) (xy 354.044219 -244.180569)
			(xy 354.093394 -244.178588) (xy 354.142249 -244.18452) (xy 354.18952 -244.198212) (xy 354.233982 -244.21931)
			(xy 354.274485 -244.247266) (xy 354.309978 -244.281358) (xy 354.339543 -244.320702) (xy 354.362414 -244.364279)
			(xy 354.377998 -244.41096) (xy 354.385893 -244.459537) (xy 354.386388 -244.484144) (xy 354.71533 -244.484144)
			(xy 354.71929 -244.43509) (xy 354.731067 -244.387306) (xy 354.750358 -244.34203) (xy 354.776661 -244.300434)
			(xy 354.809296 -244.263597) (xy 354.847417 -244.232472) (xy 354.890038 -244.207865) (xy 354.936054 -244.190413)
			(xy 354.984273 -244.180569) (xy 355.033448 -244.178588) (xy 355.082303 -244.18452) (xy 355.129574 -244.198212)
			(xy 355.174036 -244.21931) (xy 355.214539 -244.247266) (xy 355.250032 -244.281358) (xy 355.279597 -244.320702)
			(xy 355.302468 -244.364279) (xy 355.318052 -244.41096) (xy 355.325947 -244.459537) (xy 355.326442 -244.484144)
			(xy 355.655384 -244.484144) (xy 355.659344 -244.43509) (xy 355.671121 -244.387306) (xy 355.690412 -244.34203)
			(xy 355.716715 -244.300434) (xy 355.74935 -244.263597) (xy 355.787471 -244.232472) (xy 355.830092 -244.207865)
			(xy 355.876108 -244.190413) (xy 355.924327 -244.180569) (xy 355.973502 -244.178588) (xy 356.022357 -244.18452)
			(xy 356.069628 -244.198212) (xy 356.11409 -244.21931) (xy 356.154593 -244.247266) (xy 356.190086 -244.281358)
			(xy 356.219651 -244.320702) (xy 356.242522 -244.364279) (xy 356.258106 -244.41096) (xy 356.266001 -244.459537)
			(xy 356.266496 -244.484144) (xy 356.595438 -244.484144) (xy 356.599398 -244.43509) (xy 356.611175 -244.387306)
			(xy 356.630466 -244.34203) (xy 356.656769 -244.300434) (xy 356.689404 -244.263597) (xy 356.727525 -244.232472)
			(xy 356.770146 -244.207865) (xy 356.816162 -244.190413) (xy 356.864381 -244.180569) (xy 356.913556 -244.178588)
			(xy 356.962411 -244.18452) (xy 357.009682 -244.198212) (xy 357.054144 -244.21931) (xy 357.094647 -244.247266)
			(xy 357.13014 -244.281358) (xy 357.159705 -244.320702) (xy 357.182576 -244.364279) (xy 357.19816 -244.41096)
			(xy 357.206055 -244.459537) (xy 357.20655 -244.484144) (xy 357.535238 -244.484144) (xy 357.539198 -244.43509)
			(xy 357.550975 -244.387306) (xy 357.570266 -244.34203) (xy 357.596569 -244.300434) (xy 357.629204 -244.263597)
			(xy 357.667325 -244.232472) (xy 357.709946 -244.207865) (xy 357.755962 -244.190413) (xy 357.804181 -244.180569)
			(xy 357.853356 -244.178588) (xy 357.902211 -244.18452) (xy 357.949482 -244.198212) (xy 357.993944 -244.21931)
			(xy 358.034447 -244.247266) (xy 358.06994 -244.281358) (xy 358.099505 -244.320702) (xy 358.122376 -244.364279)
			(xy 358.13796 -244.41096) (xy 358.145855 -244.459537) (xy 358.14635 -244.484144) (xy 361.289104 -244.484144)
			(xy 361.293064 -244.43509) (xy 361.304841 -244.387306) (xy 361.324132 -244.34203) (xy 361.350435 -244.300434)
			(xy 361.38307 -244.263597) (xy 361.421191 -244.232472) (xy 361.463812 -244.207865) (xy 361.509828 -244.190413)
			(xy 361.558047 -244.180569) (xy 361.607222 -244.178588) (xy 361.656077 -244.18452) (xy 361.703348 -244.198212)
			(xy 361.74781 -244.21931) (xy 361.788313 -244.247266) (xy 361.823806 -244.281358) (xy 361.853371 -244.320702)
			(xy 361.876242 -244.364279) (xy 361.891826 -244.41096) (xy 361.899721 -244.459537) (xy 361.900216 -244.484144)
			(xy 362.228904 -244.484144) (xy 362.232864 -244.43509) (xy 362.244641 -244.387306) (xy 362.263932 -244.34203)
			(xy 362.290235 -244.300434) (xy 362.32287 -244.263597) (xy 362.360991 -244.232472) (xy 362.403612 -244.207865)
			(xy 362.449628 -244.190413) (xy 362.497847 -244.180569) (xy 362.547022 -244.178588) (xy 362.595877 -244.18452)
			(xy 362.643148 -244.198212) (xy 362.68761 -244.21931) (xy 362.728113 -244.247266) (xy 362.763606 -244.281358)
			(xy 362.793171 -244.320702) (xy 362.816042 -244.364279) (xy 362.831626 -244.41096) (xy 362.839521 -244.459537)
			(xy 362.840016 -244.484144) (xy 363.168958 -244.484144) (xy 363.172918 -244.43509) (xy 363.184695 -244.387306)
			(xy 363.203986 -244.34203) (xy 363.230289 -244.300434) (xy 363.262924 -244.263597) (xy 363.301045 -244.232472)
			(xy 363.343666 -244.207865) (xy 363.389682 -244.190413) (xy 363.437901 -244.180569) (xy 363.487076 -244.178588)
			(xy 363.535931 -244.18452) (xy 363.583202 -244.198212) (xy 363.627664 -244.21931) (xy 363.668167 -244.247266)
			(xy 363.70366 -244.281358) (xy 363.733225 -244.320702) (xy 363.756096 -244.364279) (xy 363.77168 -244.41096)
			(xy 363.779575 -244.459537) (xy 363.780069 -244.4841) (xy 364.108984 -244.4841) (xy 364.113155 -244.433763)
			(xy 364.125555 -244.384799) (xy 364.145845 -244.338543) (xy 364.173472 -244.296259) (xy 364.207683 -244.259098)
			(xy 364.247543 -244.228076) (xy 364.291966 -244.204037) (xy 364.33974 -244.187639) (xy 364.389561 -244.179327)
			(xy 364.414816 -244.178836) (xy 365.35487 -244.178836) (xy 365.380133 -244.179238) (xy 365.42997 -244.18755)
			(xy 365.47776 -244.203952) (xy 365.522198 -244.227997) (xy 365.562072 -244.259028) (xy 365.596293 -244.2962)
			(xy 365.62393 -244.338497) (xy 365.644227 -244.384767) (xy 365.656631 -244.433747) (xy 365.660804 -244.4841)
			(xy 365.6608 -244.484144) (xy 365.98912 -244.484144) (xy 365.99308 -244.43509) (xy 366.004857 -244.387306)
			(xy 366.024148 -244.34203) (xy 366.050451 -244.300434) (xy 366.083086 -244.263597) (xy 366.121207 -244.232472)
			(xy 366.163828 -244.207865) (xy 366.209844 -244.190413) (xy 366.258063 -244.180569) (xy 366.307238 -244.178588)
			(xy 366.356093 -244.18452) (xy 366.403364 -244.198212) (xy 366.447826 -244.21931) (xy 366.488329 -244.247266)
			(xy 366.523822 -244.281358) (xy 366.553387 -244.320702) (xy 366.576258 -244.364279) (xy 366.591842 -244.41096)
			(xy 366.599737 -244.459537) (xy 366.600231 -244.4841) (xy 366.928884 -244.4841) (xy 366.933055 -244.433762)
			(xy 366.945456 -244.384797) (xy 366.965746 -244.338541) (xy 366.993374 -244.296256) (xy 367.027586 -244.259095)
			(xy 367.067447 -244.228073) (xy 367.111871 -244.204035) (xy 367.159646 -244.187637) (xy 367.209469 -244.179327)
			(xy 367.234724 -244.178836) (xy 368.174778 -244.178836) (xy 368.200041 -244.179239) (xy 368.249877 -244.187552)
			(xy 368.297665 -244.203955) (xy 368.342102 -244.228) (xy 368.381975 -244.259031) (xy 368.416196 -244.296203)
			(xy 368.443831 -244.3385) (xy 368.464128 -244.384769) (xy 368.476531 -244.433748) (xy 368.480704 -244.4841)
			(xy 368.4807 -244.484144) (xy 368.809028 -244.484144) (xy 368.812988 -244.43509) (xy 368.824765 -244.387306)
			(xy 368.844056 -244.34203) (xy 368.870359 -244.300434) (xy 368.902994 -244.263597) (xy 368.941115 -244.232472)
			(xy 368.983736 -244.207865) (xy 369.029752 -244.190413) (xy 369.077971 -244.180569) (xy 369.127146 -244.178588)
			(xy 369.176001 -244.18452) (xy 369.223272 -244.198212) (xy 369.267734 -244.21931) (xy 369.308237 -244.247266)
			(xy 369.34373 -244.281358) (xy 369.373295 -244.320702) (xy 369.396166 -244.364279) (xy 369.41175 -244.41096)
			(xy 369.419645 -244.459537) (xy 369.420139 -244.4841) (xy 369.749113 -244.4841) (xy 369.753283 -244.433771)
			(xy 369.76568 -244.384814) (xy 369.785966 -244.338565) (xy 369.813587 -244.296286) (xy 369.847791 -244.25913)
			(xy 369.887643 -244.22811) (xy 369.932057 -244.204073) (xy 369.979822 -244.187673) (xy 370.029635 -244.179359)
			(xy 370.054886 -244.178836) (xy 370.99494 -244.178836) (xy 371.020197 -244.179272) (xy 371.070021 -244.187592)
			(xy 371.117796 -244.203999) (xy 371.162219 -244.228045) (xy 371.202079 -244.259074) (xy 371.236289 -244.296241)
			(xy 371.263916 -244.33853) (xy 371.284205 -244.38479) (xy 371.296604 -244.433759) (xy 371.300776 -244.4841)
			(xy 371.300772 -244.484144) (xy 371.628936 -244.484144) (xy 371.632896 -244.43509) (xy 371.644673 -244.387306)
			(xy 371.663964 -244.34203) (xy 371.690267 -244.300434) (xy 371.722902 -244.263597) (xy 371.761023 -244.232472)
			(xy 371.803644 -244.207865) (xy 371.84966 -244.190413) (xy 371.897879 -244.180569) (xy 371.947054 -244.178588)
			(xy 371.995909 -244.18452) (xy 372.04318 -244.198212) (xy 372.087642 -244.21931) (xy 372.128145 -244.247266)
			(xy 372.163638 -244.281358) (xy 372.193203 -244.320702) (xy 372.216074 -244.364279) (xy 372.231658 -244.41096)
			(xy 372.239553 -244.459537) (xy 372.240047 -244.4841) (xy 372.569013 -244.4841) (xy 372.573183 -244.43377)
			(xy 372.585581 -244.384812) (xy 372.605867 -244.338563) (xy 372.63349 -244.296284) (xy 372.667694 -244.259127)
			(xy 372.707547 -244.228107) (xy 372.751963 -244.20407) (xy 372.799729 -244.187671) (xy 372.849543 -244.179358)
			(xy 372.874794 -244.178836) (xy 373.814848 -244.178836) (xy 373.840104 -244.179273) (xy 373.889927 -244.187594)
			(xy 373.937701 -244.204002) (xy 373.982123 -244.228048) (xy 374.021982 -244.259077) (xy 374.056191 -244.296243)
			(xy 374.083817 -244.338533) (xy 374.104106 -244.384792) (xy 374.116505 -244.43376) (xy 374.120676 -244.4841)
			(xy 374.116505 -244.53444) (xy 374.104106 -244.583408) (xy 374.083817 -244.629667) (xy 374.056191 -244.671957)
			(xy 374.021982 -244.709123) (xy 373.982123 -244.740152) (xy 373.937701 -244.764198) (xy 373.889927 -244.780606)
			(xy 373.840104 -244.788927) (xy 373.814848 -244.789452) (xy 372.874794 -244.789452) (xy 372.849543 -244.788842)
			(xy 372.799729 -244.780529) (xy 372.751963 -244.76413) (xy 372.707547 -244.740093) (xy 372.667694 -244.709073)
			(xy 372.63349 -244.671916) (xy 372.605867 -244.629637) (xy 372.585581 -244.583388) (xy 372.573183 -244.53443)
			(xy 372.569013 -244.4841) (xy 372.240047 -244.4841) (xy 372.240048 -244.484144) (xy 372.239553 -244.508751)
			(xy 372.231658 -244.557328) (xy 372.216074 -244.604009) (xy 372.193203 -244.647586) (xy 372.163638 -244.68693)
			(xy 372.128145 -244.721022) (xy 372.087642 -244.748978) (xy 372.04318 -244.770076) (xy 371.995909 -244.783768)
			(xy 371.947054 -244.7897) (xy 371.897879 -244.787719) (xy 371.84966 -244.777875) (xy 371.803644 -244.760423)
			(xy 371.761023 -244.735816) (xy 371.722902 -244.704691) (xy 371.690267 -244.667854) (xy 371.663964 -244.626258)
			(xy 371.644673 -244.580982) (xy 371.632896 -244.533198) (xy 371.628936 -244.484144) (xy 371.300772 -244.484144)
			(xy 371.296604 -244.534441) (xy 371.284205 -244.58341) (xy 371.263915 -244.62967) (xy 371.236289 -244.671959)
			(xy 371.202079 -244.709126) (xy 371.162219 -244.740155) (xy 371.117796 -244.764201) (xy 371.070021 -244.780608)
			(xy 371.020197 -244.788928) (xy 370.99494 -244.789452) (xy 370.054886 -244.789452) (xy 370.029635 -244.788841)
			(xy 369.979822 -244.780527) (xy 369.932057 -244.764127) (xy 369.887643 -244.74009) (xy 369.847791 -244.70907)
			(xy 369.813587 -244.671914) (xy 369.785966 -244.629635) (xy 369.76568 -244.583386) (xy 369.753283 -244.534429)
			(xy 369.749113 -244.4841) (xy 369.420139 -244.4841) (xy 369.42014 -244.484144) (xy 369.419645 -244.508751)
			(xy 369.41175 -244.557328) (xy 369.396166 -244.604009) (xy 369.373295 -244.647586) (xy 369.34373 -244.68693)
			(xy 369.308237 -244.721022) (xy 369.267734 -244.748978) (xy 369.223272 -244.770076) (xy 369.176001 -244.783768)
			(xy 369.127146 -244.7897) (xy 369.077971 -244.787719) (xy 369.029752 -244.777875) (xy 368.983736 -244.760423)
			(xy 368.941115 -244.735816) (xy 368.902994 -244.704691) (xy 368.870359 -244.667854) (xy 368.844056 -244.626258)
			(xy 368.824765 -244.580982) (xy 368.812988 -244.533198) (xy 368.809028 -244.484144) (xy 368.4807 -244.484144)
			(xy 368.476531 -244.534452) (xy 368.464128 -244.583431) (xy 368.443831 -244.6297) (xy 368.416196 -244.671997)
			(xy 368.381975 -244.709169) (xy 368.342102 -244.7402) (xy 368.297665 -244.764245) (xy 368.249877 -244.780648)
			(xy 368.200041 -244.788961) (xy 368.174778 -244.789452) (xy 367.234724 -244.789452) (xy 367.209469 -244.788873)
			(xy 367.159646 -244.780563) (xy 367.111871 -244.764165) (xy 367.067447 -244.740127) (xy 367.027586 -244.709105)
			(xy 366.993374 -244.671944) (xy 366.965746 -244.629659) (xy 366.945456 -244.583403) (xy 366.933055 -244.534438)
			(xy 366.928884 -244.4841) (xy 366.600231 -244.4841) (xy 366.600232 -244.484144) (xy 366.599737 -244.508751)
			(xy 366.591842 -244.557328) (xy 366.576258 -244.604009) (xy 366.553387 -244.647586) (xy 366.523822 -244.68693)
			(xy 366.488329 -244.721022) (xy 366.447826 -244.748978) (xy 366.403364 -244.770076) (xy 366.356093 -244.783768)
			(xy 366.307238 -244.7897) (xy 366.258063 -244.787719) (xy 366.209844 -244.777875) (xy 366.163828 -244.760423)
			(xy 366.121207 -244.735816) (xy 366.083086 -244.704691) (xy 366.050451 -244.667854) (xy 366.024148 -244.626258)
			(xy 366.004857 -244.580982) (xy 365.99308 -244.533198) (xy 365.98912 -244.484144) (xy 365.6608 -244.484144)
			(xy 365.656631 -244.534453) (xy 365.644227 -244.583433) (xy 365.62393 -244.629703) (xy 365.596293 -244.672)
			(xy 365.562072 -244.709172) (xy 365.522198 -244.740203) (xy 365.47776 -244.764248) (xy 365.42997 -244.78065)
			(xy 365.380133 -244.788962) (xy 365.35487 -244.789452) (xy 364.414816 -244.789452) (xy 364.389561 -244.788873)
			(xy 364.33974 -244.780561) (xy 364.291966 -244.764163) (xy 364.247543 -244.740124) (xy 364.207683 -244.709102)
			(xy 364.173472 -244.671941) (xy 364.145845 -244.629657) (xy 364.125555 -244.583401) (xy 364.113155 -244.534437)
			(xy 364.108984 -244.4841) (xy 363.780069 -244.4841) (xy 363.78007 -244.484144) (xy 363.779575 -244.508751)
			(xy 363.77168 -244.557328) (xy 363.756096 -244.604009) (xy 363.733225 -244.647586) (xy 363.70366 -244.68693)
			(xy 363.668167 -244.721022) (xy 363.627664 -244.748978) (xy 363.583202 -244.770076) (xy 363.535931 -244.783768)
			(xy 363.487076 -244.7897) (xy 363.437901 -244.787719) (xy 363.389682 -244.777875) (xy 363.343666 -244.760423)
			(xy 363.301045 -244.735816) (xy 363.262924 -244.704691) (xy 363.230289 -244.667854) (xy 363.203986 -244.626258)
			(xy 363.184695 -244.580982) (xy 363.172918 -244.533198) (xy 363.168958 -244.484144) (xy 362.840016 -244.484144)
			(xy 362.839521 -244.508751) (xy 362.831626 -244.557328) (xy 362.816042 -244.604009) (xy 362.793171 -244.647586)
			(xy 362.763606 -244.68693) (xy 362.728113 -244.721022) (xy 362.68761 -244.748978) (xy 362.643148 -244.770076)
			(xy 362.595877 -244.783768) (xy 362.547022 -244.7897) (xy 362.497847 -244.787719) (xy 362.449628 -244.777875)
			(xy 362.403612 -244.760423) (xy 362.360991 -244.735816) (xy 362.32287 -244.704691) (xy 362.290235 -244.667854)
			(xy 362.263932 -244.626258) (xy 362.244641 -244.580982) (xy 362.232864 -244.533198) (xy 362.228904 -244.484144)
			(xy 361.900216 -244.484144) (xy 361.899721 -244.508751) (xy 361.891826 -244.557328) (xy 361.876242 -244.604009)
			(xy 361.853371 -244.647586) (xy 361.823806 -244.68693) (xy 361.788313 -244.721022) (xy 361.74781 -244.748978)
			(xy 361.703348 -244.770076) (xy 361.656077 -244.783768) (xy 361.607222 -244.7897) (xy 361.558047 -244.787719)
			(xy 361.509828 -244.777875) (xy 361.463812 -244.760423) (xy 361.421191 -244.735816) (xy 361.38307 -244.704691)
			(xy 361.350435 -244.667854) (xy 361.324132 -244.626258) (xy 361.304841 -244.580982) (xy 361.293064 -244.533198)
			(xy 361.289104 -244.484144) (xy 358.14635 -244.484144) (xy 358.145855 -244.508751) (xy 358.13796 -244.557328)
			(xy 358.122376 -244.604009) (xy 358.099505 -244.647586) (xy 358.06994 -244.68693) (xy 358.034447 -244.721022)
			(xy 357.993944 -244.748978) (xy 357.949482 -244.770076) (xy 357.902211 -244.783768) (xy 357.853356 -244.7897)
			(xy 357.804181 -244.787719) (xy 357.755962 -244.777875) (xy 357.709946 -244.760423) (xy 357.667325 -244.735816)
			(xy 357.629204 -244.704691) (xy 357.596569 -244.667854) (xy 357.570266 -244.626258) (xy 357.550975 -244.580982)
			(xy 357.539198 -244.533198) (xy 357.535238 -244.484144) (xy 357.20655 -244.484144) (xy 357.206055 -244.508751)
			(xy 357.19816 -244.557328) (xy 357.182576 -244.604009) (xy 357.159705 -244.647586) (xy 357.13014 -244.68693)
			(xy 357.094647 -244.721022) (xy 357.054144 -244.748978) (xy 357.009682 -244.770076) (xy 356.962411 -244.783768)
			(xy 356.913556 -244.7897) (xy 356.864381 -244.787719) (xy 356.816162 -244.777875) (xy 356.770146 -244.760423)
			(xy 356.727525 -244.735816) (xy 356.689404 -244.704691) (xy 356.656769 -244.667854) (xy 356.630466 -244.626258)
			(xy 356.611175 -244.580982) (xy 356.599398 -244.533198) (xy 356.595438 -244.484144) (xy 356.266496 -244.484144)
			(xy 356.266001 -244.508751) (xy 356.258106 -244.557328) (xy 356.242522 -244.604009) (xy 356.219651 -244.647586)
			(xy 356.190086 -244.68693) (xy 356.154593 -244.721022) (xy 356.11409 -244.748978) (xy 356.069628 -244.770076)
			(xy 356.022357 -244.783768) (xy 355.973502 -244.7897) (xy 355.924327 -244.787719) (xy 355.876108 -244.777875)
			(xy 355.830092 -244.760423) (xy 355.787471 -244.735816) (xy 355.74935 -244.704691) (xy 355.716715 -244.667854)
			(xy 355.690412 -244.626258) (xy 355.671121 -244.580982) (xy 355.659344 -244.533198) (xy 355.655384 -244.484144)
			(xy 355.326442 -244.484144) (xy 355.325947 -244.508751) (xy 355.318052 -244.557328) (xy 355.302468 -244.604009)
			(xy 355.279597 -244.647586) (xy 355.250032 -244.68693) (xy 355.214539 -244.721022) (xy 355.174036 -244.748978)
			(xy 355.129574 -244.770076) (xy 355.082303 -244.783768) (xy 355.033448 -244.7897) (xy 354.984273 -244.787719)
			(xy 354.936054 -244.777875) (xy 354.890038 -244.760423) (xy 354.847417 -244.735816) (xy 354.809296 -244.704691)
			(xy 354.776661 -244.667854) (xy 354.750358 -244.626258) (xy 354.731067 -244.580982) (xy 354.71929 -244.533198)
			(xy 354.71533 -244.484144) (xy 354.386388 -244.484144) (xy 354.385893 -244.508751) (xy 354.377998 -244.557328)
			(xy 354.362414 -244.604009) (xy 354.339543 -244.647586) (xy 354.309978 -244.68693) (xy 354.274485 -244.721022)
			(xy 354.233982 -244.748978) (xy 354.18952 -244.770076) (xy 354.142249 -244.783768) (xy 354.093394 -244.7897)
			(xy 354.044219 -244.787719) (xy 353.996 -244.777875) (xy 353.949984 -244.760423) (xy 353.907363 -244.735816)
			(xy 353.869242 -244.704691) (xy 353.836607 -244.667854) (xy 353.810304 -244.626258) (xy 353.791013 -244.580982)
			(xy 353.779236 -244.533198) (xy 353.775276 -244.484144) (xy 353.446334 -244.484144) (xy 353.445839 -244.508751)
			(xy 353.437944 -244.557328) (xy 353.42236 -244.604009) (xy 353.399489 -244.647586) (xy 353.369924 -244.68693)
			(xy 353.334431 -244.721022) (xy 353.293928 -244.748978) (xy 353.249466 -244.770076) (xy 353.202195 -244.783768)
			(xy 353.15334 -244.7897) (xy 353.104165 -244.787719) (xy 353.055946 -244.777875) (xy 353.00993 -244.760423)
			(xy 352.967309 -244.735816) (xy 352.929188 -244.704691) (xy 352.896553 -244.667854) (xy 352.87025 -244.626258)
			(xy 352.850959 -244.580982) (xy 352.839182 -244.533198) (xy 352.835222 -244.484144) (xy 352.506534 -244.484144)
			(xy 352.506039 -244.508751) (xy 352.498144 -244.557328) (xy 352.48256 -244.604009) (xy 352.459689 -244.647586)
			(xy 352.430124 -244.68693) (xy 352.394631 -244.721022) (xy 352.354128 -244.748978) (xy 352.309666 -244.770076)
			(xy 352.262395 -244.783768) (xy 352.21354 -244.7897) (xy 352.164365 -244.787719) (xy 352.116146 -244.777875)
			(xy 352.07013 -244.760423) (xy 352.027509 -244.735816) (xy 351.989388 -244.704691) (xy 351.956753 -244.667854)
			(xy 351.93045 -244.626258) (xy 351.911159 -244.580982) (xy 351.899382 -244.533198) (xy 351.895422 -244.484144)
			(xy 351.56648 -244.484144) (xy 351.565985 -244.508751) (xy 351.55809 -244.557328) (xy 351.542506 -244.604009)
			(xy 351.519635 -244.647586) (xy 351.49007 -244.68693) (xy 351.454577 -244.721022) (xy 351.414074 -244.748978)
			(xy 351.369612 -244.770076) (xy 351.322341 -244.783768) (xy 351.273486 -244.7897) (xy 351.224311 -244.787719)
			(xy 351.176092 -244.777875) (xy 351.130076 -244.760423) (xy 351.087455 -244.735816) (xy 351.049334 -244.704691)
			(xy 351.016699 -244.667854) (xy 350.990396 -244.626258) (xy 350.971105 -244.580982) (xy 350.959328 -244.533198)
			(xy 350.955368 -244.484144) (xy 350.626426 -244.484144) (xy 350.625931 -244.508751) (xy 350.618036 -244.557328)
			(xy 350.602452 -244.604009) (xy 350.579581 -244.647586) (xy 350.550016 -244.68693) (xy 350.514523 -244.721022)
			(xy 350.47402 -244.748978) (xy 350.429558 -244.770076) (xy 350.382287 -244.783768) (xy 350.333432 -244.7897)
			(xy 350.284257 -244.787719) (xy 350.236038 -244.777875) (xy 350.190022 -244.760423) (xy 350.147401 -244.735816)
			(xy 350.10928 -244.704691) (xy 350.076645 -244.667854) (xy 350.050342 -244.626258) (xy 350.031051 -244.580982)
			(xy 350.019274 -244.533198) (xy 350.015314 -244.484144) (xy 349.686372 -244.484144) (xy 349.685877 -244.508751)
			(xy 349.677982 -244.557328) (xy 349.662398 -244.604009) (xy 349.639527 -244.647586) (xy 349.609962 -244.68693)
			(xy 349.574469 -244.721022) (xy 349.533966 -244.748978) (xy 349.489504 -244.770076) (xy 349.442233 -244.783768)
			(xy 349.393378 -244.7897) (xy 349.344203 -244.787719) (xy 349.295984 -244.777875) (xy 349.249968 -244.760423)
			(xy 349.207347 -244.735816) (xy 349.169226 -244.704691) (xy 349.136591 -244.667854) (xy 349.110288 -244.626258)
			(xy 349.090997 -244.580982) (xy 349.07922 -244.533198) (xy 349.07526 -244.484144) (xy 348.746318 -244.484144)
			(xy 348.745823 -244.508751) (xy 348.737928 -244.557328) (xy 348.722344 -244.604009) (xy 348.699473 -244.647586)
			(xy 348.669908 -244.68693) (xy 348.634415 -244.721022) (xy 348.593912 -244.748978) (xy 348.54945 -244.770076)
			(xy 348.502179 -244.783768) (xy 348.453324 -244.7897) (xy 348.404149 -244.787719) (xy 348.35593 -244.777875)
			(xy 348.309914 -244.760423) (xy 348.267293 -244.735816) (xy 348.229172 -244.704691) (xy 348.196537 -244.667854)
			(xy 348.170234 -244.626258) (xy 348.150943 -244.580982) (xy 348.139166 -244.533198) (xy 348.135206 -244.484144)
			(xy 347.806518 -244.484144) (xy 347.806023 -244.508751) (xy 347.798128 -244.557328) (xy 347.782544 -244.604009)
			(xy 347.759673 -244.647586) (xy 347.730108 -244.68693) (xy 347.694615 -244.721022) (xy 347.654112 -244.748978)
			(xy 347.60965 -244.770076) (xy 347.562379 -244.783768) (xy 347.513524 -244.7897) (xy 347.464349 -244.787719)
			(xy 347.41613 -244.777875) (xy 347.370114 -244.760423) (xy 347.327493 -244.735816) (xy 347.289372 -244.704691)
			(xy 347.256737 -244.667854) (xy 347.230434 -244.626258) (xy 347.211143 -244.580982) (xy 347.199366 -244.533198)
			(xy 347.195406 -244.484144) (xy 346.866464 -244.484144) (xy 346.865969 -244.508751) (xy 346.858074 -244.557328)
			(xy 346.84249 -244.604009) (xy 346.819619 -244.647586) (xy 346.790054 -244.68693) (xy 346.754561 -244.721022)
			(xy 346.714058 -244.748978) (xy 346.669596 -244.770076) (xy 346.622325 -244.783768) (xy 346.57347 -244.7897)
			(xy 346.524295 -244.787719) (xy 346.476076 -244.777875) (xy 346.43006 -244.760423) (xy 346.387439 -244.735816)
			(xy 346.349318 -244.704691) (xy 346.316683 -244.667854) (xy 346.29038 -244.626258) (xy 346.271089 -244.580982)
			(xy 346.259312 -244.533198) (xy 346.255352 -244.484144) (xy 345.92641 -244.484144) (xy 345.925915 -244.508751)
			(xy 345.91802 -244.557328) (xy 345.902436 -244.604009) (xy 345.879565 -244.647586) (xy 345.85 -244.68693)
			(xy 345.814507 -244.721022) (xy 345.774004 -244.748978) (xy 345.729542 -244.770076) (xy 345.682271 -244.783768)
			(xy 345.633416 -244.7897) (xy 345.584241 -244.787719) (xy 345.536022 -244.777875) (xy 345.490006 -244.760423)
			(xy 345.447385 -244.735816) (xy 345.409264 -244.704691) (xy 345.376629 -244.667854) (xy 345.350326 -244.626258)
			(xy 345.331035 -244.580982) (xy 345.319258 -244.533198) (xy 345.315298 -244.484144) (xy 344.986874 -244.484144)
			(xy 344.982962 -244.532883) (xy 344.971317 -244.580416) (xy 344.952241 -244.625483) (xy 344.926222 -244.66693)
			(xy 344.893925 -244.703698) (xy 344.856179 -244.734845) (xy 344.813948 -244.759573) (xy 344.768314 -244.77725)
			(xy 344.720445 -244.787423) (xy 344.696034 -244.789198) (xy 344.686636 -244.789452) (xy 344.669618 -244.797072)
			(xy 344.641424 -244.824758) (xy 344.634609 -244.832024) (xy 344.626883 -244.850366) (xy 344.626438 -244.860318)
			(xy 344.626438 -245.29415) (xy 346.725252 -245.29415) (xy 346.729212 -245.245096) (xy 346.740989 -245.197312)
			(xy 346.76028 -245.152036) (xy 346.786583 -245.11044) (xy 346.819218 -245.073603) (xy 346.857339 -245.042478)
			(xy 346.89996 -245.017871) (xy 346.945976 -245.000419) (xy 346.994195 -244.990575) (xy 347.04337 -244.988594)
			(xy 347.092225 -244.994526) (xy 347.139496 -245.008218) (xy 347.183958 -245.029316) (xy 347.224461 -245.057272)
			(xy 347.259954 -245.091364) (xy 347.289519 -245.130708) (xy 347.31239 -245.174285) (xy 347.327974 -245.220966)
			(xy 347.335869 -245.269543) (xy 347.336364 -245.29415) (xy 349.545414 -245.29415) (xy 349.549374 -245.245096)
			(xy 349.561151 -245.197312) (xy 349.580442 -245.152036) (xy 349.606745 -245.11044) (xy 349.63938 -245.073603)
			(xy 349.677501 -245.042478) (xy 349.720122 -245.017871) (xy 349.766138 -245.000419) (xy 349.814357 -244.990575)
			(xy 349.863532 -244.988594) (xy 349.912387 -244.994526) (xy 349.959658 -245.008218) (xy 350.00412 -245.029316)
			(xy 350.044623 -245.057272) (xy 350.080116 -245.091364) (xy 350.109681 -245.130708) (xy 350.132552 -245.174285)
			(xy 350.148136 -245.220966) (xy 350.156031 -245.269543) (xy 350.156526 -245.29415) (xy 352.365322 -245.29415)
			(xy 352.369282 -245.245096) (xy 352.381059 -245.197312) (xy 352.40035 -245.152036) (xy 352.426653 -245.11044)
			(xy 352.459288 -245.073603) (xy 352.497409 -245.042478) (xy 352.54003 -245.017871) (xy 352.586046 -245.000419)
			(xy 352.634265 -244.990575) (xy 352.68344 -244.988594) (xy 352.732295 -244.994526) (xy 352.779566 -245.008218)
			(xy 352.824028 -245.029316) (xy 352.864531 -245.057272) (xy 352.900024 -245.091364) (xy 352.929589 -245.130708)
			(xy 352.95246 -245.174285) (xy 352.968044 -245.220966) (xy 352.975939 -245.269543) (xy 352.976434 -245.29415)
			(xy 355.18523 -245.29415) (xy 355.18919 -245.245096) (xy 355.200967 -245.197312) (xy 355.220258 -245.152036)
			(xy 355.246561 -245.11044) (xy 355.279196 -245.073603) (xy 355.317317 -245.042478) (xy 355.359938 -245.017871)
			(xy 355.405954 -245.000419) (xy 355.454173 -244.990575) (xy 355.503348 -244.988594) (xy 355.552203 -244.994526)
			(xy 355.599474 -245.008218) (xy 355.643936 -245.029316) (xy 355.684439 -245.057272) (xy 355.719932 -245.091364)
			(xy 355.749497 -245.130708) (xy 355.772368 -245.174285) (xy 355.787952 -245.220966) (xy 355.795847 -245.269543)
			(xy 355.796342 -245.29415) (xy 356.125284 -245.29415) (xy 356.129244 -245.245096) (xy 356.141021 -245.197312)
			(xy 356.160312 -245.152036) (xy 356.186615 -245.11044) (xy 356.21925 -245.073603) (xy 356.257371 -245.042478)
			(xy 356.299992 -245.017871) (xy 356.346008 -245.000419) (xy 356.394227 -244.990575) (xy 356.443402 -244.988594)
			(xy 356.492257 -244.994526) (xy 356.539528 -245.008218) (xy 356.58399 -245.029316) (xy 356.624493 -245.057272)
			(xy 356.659986 -245.091364) (xy 356.689551 -245.130708) (xy 356.712422 -245.174285) (xy 356.728006 -245.220966)
			(xy 356.735901 -245.269543) (xy 356.736396 -245.29415) (xy 357.065338 -245.29415) (xy 357.069298 -245.245096)
			(xy 357.081075 -245.197312) (xy 357.100366 -245.152036) (xy 357.126669 -245.11044) (xy 357.159304 -245.073603)
			(xy 357.197425 -245.042478) (xy 357.240046 -245.017871) (xy 357.286062 -245.000419) (xy 357.334281 -244.990575)
			(xy 357.383456 -244.988594) (xy 357.432311 -244.994526) (xy 357.479582 -245.008218) (xy 357.524044 -245.029316)
			(xy 357.564547 -245.057272) (xy 357.60004 -245.091364) (xy 357.629605 -245.130708) (xy 357.652476 -245.174285)
			(xy 357.66806 -245.220966) (xy 357.675955 -245.269543) (xy 357.67645 -245.29415) (xy 358.005392 -245.29415)
			(xy 358.009352 -245.245096) (xy 358.021129 -245.197312) (xy 358.04042 -245.152036) (xy 358.066723 -245.11044)
			(xy 358.099358 -245.073603) (xy 358.137479 -245.042478) (xy 358.1801 -245.017871) (xy 358.226116 -245.000419)
			(xy 358.274335 -244.990575) (xy 358.32351 -244.988594) (xy 358.372365 -244.994526) (xy 358.419636 -245.008218)
			(xy 358.464098 -245.029316) (xy 358.504601 -245.057272) (xy 358.540094 -245.091364) (xy 358.569659 -245.130708)
			(xy 358.59253 -245.174285) (xy 358.608114 -245.220966) (xy 358.616009 -245.269543) (xy 358.616504 -245.29415)
			(xy 358.616009 -245.318757) (xy 358.608114 -245.367334) (xy 358.59253 -245.414015) (xy 358.569659 -245.457592)
			(xy 358.540094 -245.496936) (xy 358.504601 -245.531028) (xy 358.474274 -245.55196) (xy 359.396541 -245.55196)
			(xy 359.400571 -245.499462) (xy 359.412568 -245.448194) (xy 359.432251 -245.399359) (xy 359.459157 -245.3541)
			(xy 359.492657 -245.313479) (xy 359.531965 -245.278448) (xy 359.57616 -245.249828) (xy 359.624205 -245.228289)
			(xy 359.674976 -245.214337) (xy 359.727281 -245.208299) (xy 359.779895 -245.210316) (xy 359.831585 -245.22034)
			(xy 359.881138 -245.238138) (xy 359.927394 -245.263291) (xy 359.967877 -245.29415) (xy 360.81895 -245.29415)
			(xy 360.82291 -245.245096) (xy 360.834687 -245.197312) (xy 360.853978 -245.152036) (xy 360.880281 -245.11044)
			(xy 360.912916 -245.073603) (xy 360.951037 -245.042478) (xy 360.993658 -245.017871) (xy 361.039674 -245.000419)
			(xy 361.087893 -244.990575) (xy 361.137068 -244.988594) (xy 361.185923 -244.994526) (xy 361.233194 -245.008218)
			(xy 361.277656 -245.029316) (xy 361.318159 -245.057272) (xy 361.353652 -245.091364) (xy 361.383217 -245.130708)
			(xy 361.406088 -245.174285) (xy 361.421672 -245.220966) (xy 361.429567 -245.269543) (xy 361.430061 -245.2941)
			(xy 361.758735 -245.2941) (xy 361.76291 -245.243723) (xy 361.775319 -245.194719) (xy 361.795626 -245.148427)
			(xy 361.823274 -245.106109) (xy 361.857511 -245.068918) (xy 361.897403 -245.03787) (xy 361.941861 -245.013812)
			(xy 361.989672 -244.997399) (xy 362.039533 -244.98908) (xy 362.064808 -244.988588) (xy 363.004862 -244.988588)
			(xy 363.030147 -244.988978) (xy 363.080028 -244.997296) (xy 363.127859 -245.013711) (xy 363.172336 -245.037776)
			(xy 363.212245 -245.068834) (xy 363.246497 -245.106037) (xy 363.274158 -245.148371) (xy 363.294473 -245.194681)
			(xy 363.306888 -245.243703) (xy 363.311065 -245.2941) (xy 363.311061 -245.29415) (xy 363.639112 -245.29415)
			(xy 363.643072 -245.245096) (xy 363.654849 -245.197312) (xy 363.67414 -245.152036) (xy 363.700443 -245.11044)
			(xy 363.733078 -245.073603) (xy 363.771199 -245.042478) (xy 363.81382 -245.017871) (xy 363.859836 -245.000419)
			(xy 363.908055 -244.990575) (xy 363.95723 -244.988594) (xy 364.006085 -244.994526) (xy 364.053356 -245.008218)
			(xy 364.097818 -245.029316) (xy 364.138321 -245.057272) (xy 364.173814 -245.091364) (xy 364.203379 -245.130708)
			(xy 364.22625 -245.174285) (xy 364.241834 -245.220966) (xy 364.249729 -245.269543) (xy 364.250224 -245.29415)
			(xy 366.45902 -245.29415) (xy 366.46298 -245.245096) (xy 366.474757 -245.197312) (xy 366.494048 -245.152036)
			(xy 366.520351 -245.11044) (xy 366.552986 -245.073603) (xy 366.591107 -245.042478) (xy 366.633728 -245.017871)
			(xy 366.679744 -245.000419) (xy 366.727963 -244.990575) (xy 366.777138 -244.988594) (xy 366.825993 -244.994526)
			(xy 366.873264 -245.008218) (xy 366.917726 -245.029316) (xy 366.958229 -245.057272) (xy 366.993722 -245.091364)
			(xy 367.023287 -245.130708) (xy 367.046158 -245.174285) (xy 367.061742 -245.220966) (xy 367.069637 -245.269543)
			(xy 367.070132 -245.29415) (xy 369.278928 -245.29415) (xy 369.282888 -245.245096) (xy 369.294665 -245.197312)
			(xy 369.313956 -245.152036) (xy 369.340259 -245.11044) (xy 369.372894 -245.073603) (xy 369.411015 -245.042478)
			(xy 369.453636 -245.017871) (xy 369.499652 -245.000419) (xy 369.547871 -244.990575) (xy 369.597046 -244.988594)
			(xy 369.645901 -244.994526) (xy 369.693172 -245.008218) (xy 369.737634 -245.029316) (xy 369.778137 -245.057272)
			(xy 369.81363 -245.091364) (xy 369.843195 -245.130708) (xy 369.866066 -245.174285) (xy 369.88165 -245.220966)
			(xy 369.889545 -245.269543) (xy 369.89004 -245.29415) (xy 372.09909 -245.29415) (xy 372.10305 -245.245096)
			(xy 372.114827 -245.197312) (xy 372.134118 -245.152036) (xy 372.160421 -245.11044) (xy 372.193056 -245.073603)
			(xy 372.231177 -245.042478) (xy 372.273798 -245.017871) (xy 372.319814 -245.000419) (xy 372.368033 -244.990575)
			(xy 372.417208 -244.988594) (xy 372.466063 -244.994526) (xy 372.513334 -245.008218) (xy 372.557796 -245.029316)
			(xy 372.598299 -245.057272) (xy 372.633792 -245.091364) (xy 372.663357 -245.130708) (xy 372.686228 -245.174285)
			(xy 372.701812 -245.220966) (xy 372.709707 -245.269543) (xy 372.710202 -245.29415) (xy 372.709707 -245.318757)
			(xy 372.701812 -245.367334) (xy 372.686228 -245.414015) (xy 372.663357 -245.457592) (xy 372.633792 -245.496936)
			(xy 372.598299 -245.531028) (xy 372.557796 -245.558984) (xy 372.513334 -245.580082) (xy 372.466063 -245.593774)
			(xy 372.417208 -245.599706) (xy 372.368033 -245.597725) (xy 372.319814 -245.587881) (xy 372.273798 -245.570429)
			(xy 372.231177 -245.545822) (xy 372.193056 -245.514697) (xy 372.160421 -245.47786) (xy 372.134118 -245.436264)
			(xy 372.114827 -245.390988) (xy 372.10305 -245.343204) (xy 372.09909 -245.29415) (xy 369.89004 -245.29415)
			(xy 369.889545 -245.318757) (xy 369.88165 -245.367334) (xy 369.866066 -245.414015) (xy 369.843195 -245.457592)
			(xy 369.81363 -245.496936) (xy 369.778137 -245.531028) (xy 369.737634 -245.558984) (xy 369.693172 -245.580082)
			(xy 369.645901 -245.593774) (xy 369.597046 -245.599706) (xy 369.547871 -245.597725) (xy 369.499652 -245.587881)
			(xy 369.453636 -245.570429) (xy 369.411015 -245.545822) (xy 369.372894 -245.514697) (xy 369.340259 -245.47786)
			(xy 369.313956 -245.436264) (xy 369.294665 -245.390988) (xy 369.282888 -245.343204) (xy 369.278928 -245.29415)
			(xy 367.070132 -245.29415) (xy 367.069637 -245.318757) (xy 367.061742 -245.367334) (xy 367.046158 -245.414015)
			(xy 367.023287 -245.457592) (xy 366.993722 -245.496936) (xy 366.958229 -245.531028) (xy 366.917726 -245.558984)
			(xy 366.873264 -245.580082) (xy 366.825993 -245.593774) (xy 366.777138 -245.599706) (xy 366.727963 -245.597725)
			(xy 366.679744 -245.587881) (xy 366.633728 -245.570429) (xy 366.591107 -245.545822) (xy 366.552986 -245.514697)
			(xy 366.520351 -245.47786) (xy 366.494048 -245.436264) (xy 366.474757 -245.390988) (xy 366.46298 -245.343204)
			(xy 366.45902 -245.29415) (xy 364.250224 -245.29415) (xy 364.249729 -245.318757) (xy 364.241834 -245.367334)
			(xy 364.22625 -245.414015) (xy 364.203379 -245.457592) (xy 364.173814 -245.496936) (xy 364.138321 -245.531028)
			(xy 364.097818 -245.558984) (xy 364.053356 -245.580082) (xy 364.006085 -245.593774) (xy 363.95723 -245.599706)
			(xy 363.908055 -245.597725) (xy 363.859836 -245.587881) (xy 363.81382 -245.570429) (xy 363.771199 -245.545822)
			(xy 363.733078 -245.514697) (xy 363.700443 -245.47786) (xy 363.67414 -245.436264) (xy 363.654849 -245.390988)
			(xy 363.643072 -245.343204) (xy 363.639112 -245.29415) (xy 363.311061 -245.29415) (xy 363.306888 -245.344497)
			(xy 363.294473 -245.393519) (xy 363.274158 -245.439829) (xy 363.246497 -245.482163) (xy 363.212245 -245.519366)
			(xy 363.172336 -245.550424) (xy 363.127859 -245.574489) (xy 363.080028 -245.590904) (xy 363.030147 -245.599222)
			(xy 363.004862 -245.599712) (xy 362.064808 -245.599712) (xy 362.039533 -245.59912) (xy 361.989672 -245.590801)
			(xy 361.941861 -245.574388) (xy 361.897403 -245.55033) (xy 361.857511 -245.519282) (xy 361.823274 -245.482091)
			(xy 361.795626 -245.439773) (xy 361.775319 -245.393481) (xy 361.76291 -245.344477) (xy 361.758735 -245.2941)
			(xy 361.430061 -245.2941) (xy 361.430062 -245.29415) (xy 361.429567 -245.318757) (xy 361.421672 -245.367334)
			(xy 361.406088 -245.414015) (xy 361.383217 -245.457592) (xy 361.353652 -245.496936) (xy 361.318159 -245.531028)
			(xy 361.277656 -245.558984) (xy 361.233194 -245.580082) (xy 361.185923 -245.593774) (xy 361.137068 -245.599706)
			(xy 361.087893 -245.597725) (xy 361.039674 -245.587881) (xy 360.993658 -245.570429) (xy 360.951037 -245.545822)
			(xy 360.912916 -245.514697) (xy 360.880281 -245.47786) (xy 360.853978 -245.436264) (xy 360.834687 -245.390988)
			(xy 360.82291 -245.343204) (xy 360.81895 -245.29415) (xy 359.967877 -245.29415) (xy 359.969268 -245.29521)
			(xy 360.00578 -245.333148) (xy 360.036072 -245.376214) (xy 360.059435 -245.423399) (xy 360.075321 -245.473598)
			(xy 360.083358 -245.525634) (xy 360.083862 -245.55196) (xy 360.083358 -245.578286) (xy 360.075321 -245.630322)
			(xy 360.059435 -245.680521) (xy 360.036072 -245.727706) (xy 360.00578 -245.770772) (xy 359.969268 -245.80871)
			(xy 359.927394 -245.840629) (xy 359.881138 -245.865782) (xy 359.831585 -245.88358) (xy 359.779895 -245.893604)
			(xy 359.727281 -245.895621) (xy 359.674976 -245.889583) (xy 359.624205 -245.875631) (xy 359.57616 -245.854092)
			(xy 359.531965 -245.825472) (xy 359.492657 -245.790441) (xy 359.459157 -245.74982) (xy 359.432251 -245.704561)
			(xy 359.412568 -245.655726) (xy 359.400571 -245.604458) (xy 359.396541 -245.55196) (xy 358.474274 -245.55196)
			(xy 358.464098 -245.558984) (xy 358.419636 -245.580082) (xy 358.372365 -245.593774) (xy 358.32351 -245.599706)
			(xy 358.274335 -245.597725) (xy 358.226116 -245.587881) (xy 358.1801 -245.570429) (xy 358.137479 -245.545822)
			(xy 358.099358 -245.514697) (xy 358.066723 -245.47786) (xy 358.04042 -245.436264) (xy 358.021129 -245.390988)
			(xy 358.009352 -245.343204) (xy 358.005392 -245.29415) (xy 357.67645 -245.29415) (xy 357.675955 -245.318757)
			(xy 357.66806 -245.367334) (xy 357.652476 -245.414015) (xy 357.629605 -245.457592) (xy 357.60004 -245.496936)
			(xy 357.564547 -245.531028) (xy 357.524044 -245.558984) (xy 357.479582 -245.580082) (xy 357.432311 -245.593774)
			(xy 357.383456 -245.599706) (xy 357.334281 -245.597725) (xy 357.286062 -245.587881) (xy 357.240046 -245.570429)
			(xy 357.197425 -245.545822) (xy 357.159304 -245.514697) (xy 357.126669 -245.47786) (xy 357.100366 -245.436264)
			(xy 357.081075 -245.390988) (xy 357.069298 -245.343204) (xy 357.065338 -245.29415) (xy 356.736396 -245.29415)
			(xy 356.735901 -245.318757) (xy 356.728006 -245.367334) (xy 356.712422 -245.414015) (xy 356.689551 -245.457592)
			(xy 356.659986 -245.496936) (xy 356.624493 -245.531028) (xy 356.58399 -245.558984) (xy 356.539528 -245.580082)
			(xy 356.492257 -245.593774) (xy 356.443402 -245.599706) (xy 356.394227 -245.597725) (xy 356.346008 -245.587881)
			(xy 356.299992 -245.570429) (xy 356.257371 -245.545822) (xy 356.21925 -245.514697) (xy 356.186615 -245.47786)
			(xy 356.160312 -245.436264) (xy 356.141021 -245.390988) (xy 356.129244 -245.343204) (xy 356.125284 -245.29415)
			(xy 355.796342 -245.29415) (xy 355.795847 -245.318757) (xy 355.787952 -245.367334) (xy 355.772368 -245.414015)
			(xy 355.749497 -245.457592) (xy 355.719932 -245.496936) (xy 355.684439 -245.531028) (xy 355.643936 -245.558984)
			(xy 355.599474 -245.580082) (xy 355.552203 -245.593774) (xy 355.503348 -245.599706) (xy 355.454173 -245.597725)
			(xy 355.405954 -245.587881) (xy 355.359938 -245.570429) (xy 355.317317 -245.545822) (xy 355.279196 -245.514697)
			(xy 355.246561 -245.47786) (xy 355.220258 -245.436264) (xy 355.200967 -245.390988) (xy 355.18919 -245.343204)
			(xy 355.18523 -245.29415) (xy 352.976434 -245.29415) (xy 352.975939 -245.318757) (xy 352.968044 -245.367334)
			(xy 352.95246 -245.414015) (xy 352.929589 -245.457592) (xy 352.900024 -245.496936) (xy 352.864531 -245.531028)
			(xy 352.824028 -245.558984) (xy 352.779566 -245.580082) (xy 352.732295 -245.593774) (xy 352.68344 -245.599706)
			(xy 352.634265 -245.597725) (xy 352.586046 -245.587881) (xy 352.54003 -245.570429) (xy 352.497409 -245.545822)
			(xy 352.459288 -245.514697) (xy 352.426653 -245.47786) (xy 352.40035 -245.436264) (xy 352.381059 -245.390988)
			(xy 352.369282 -245.343204) (xy 352.365322 -245.29415) (xy 350.156526 -245.29415) (xy 350.156031 -245.318757)
			(xy 350.148136 -245.367334) (xy 350.132552 -245.414015) (xy 350.109681 -245.457592) (xy 350.080116 -245.496936)
			(xy 350.044623 -245.531028) (xy 350.00412 -245.558984) (xy 349.959658 -245.580082) (xy 349.912387 -245.593774)
			(xy 349.863532 -245.599706) (xy 349.814357 -245.597725) (xy 349.766138 -245.587881) (xy 349.720122 -245.570429)
			(xy 349.677501 -245.545822) (xy 349.63938 -245.514697) (xy 349.606745 -245.47786) (xy 349.580442 -245.436264)
			(xy 349.561151 -245.390988) (xy 349.549374 -245.343204) (xy 349.545414 -245.29415) (xy 347.336364 -245.29415)
			(xy 347.335869 -245.318757) (xy 347.327974 -245.367334) (xy 347.31239 -245.414015) (xy 347.289519 -245.457592)
			(xy 347.259954 -245.496936) (xy 347.224461 -245.531028) (xy 347.183958 -245.558984) (xy 347.139496 -245.580082)
			(xy 347.092225 -245.593774) (xy 347.04337 -245.599706) (xy 346.994195 -245.597725) (xy 346.945976 -245.587881)
			(xy 346.89996 -245.570429) (xy 346.857339 -245.545822) (xy 346.819218 -245.514697) (xy 346.786583 -245.47786)
			(xy 346.76028 -245.436264) (xy 346.740989 -245.390988) (xy 346.729212 -245.343204) (xy 346.725252 -245.29415)
			(xy 344.626438 -245.29415) (xy 344.626438 -245.727474) (xy 344.626893 -245.737626) (xy 344.634765 -245.756344)
			(xy 344.641678 -245.763796) (xy 344.669618 -245.791228) (xy 344.686636 -245.798848) (xy 344.696034 -245.799102)
			(xy 344.720457 -245.80079) (xy 344.768339 -245.810965) (xy 344.813986 -245.828647) (xy 344.856229 -245.853383)
			(xy 344.893987 -245.884538) (xy 344.926293 -245.921317) (xy 344.952319 -245.962777) (xy 344.971401 -246.007857)
			(xy 344.983049 -246.055403) (xy 344.986962 -246.104156) (xy 345.315298 -246.104156) (xy 345.319258 -246.055102)
			(xy 345.331035 -246.007318) (xy 345.350326 -245.962042) (xy 345.376629 -245.920446) (xy 345.409264 -245.883609)
			(xy 345.447385 -245.852484) (xy 345.490006 -245.827877) (xy 345.536022 -245.810425) (xy 345.584241 -245.800581)
			(xy 345.633416 -245.7986) (xy 345.682271 -245.804532) (xy 345.729542 -245.818224) (xy 345.774004 -245.839322)
			(xy 345.814507 -245.867278) (xy 345.85 -245.90137) (xy 345.879565 -245.940714) (xy 345.902436 -245.984291)
			(xy 345.91802 -246.030972) (xy 345.925915 -246.079549) (xy 345.92641 -246.104156) (xy 346.255352 -246.104156)
			(xy 346.259312 -246.055102) (xy 346.271089 -246.007318) (xy 346.29038 -245.962042) (xy 346.316683 -245.920446)
			(xy 346.349318 -245.883609) (xy 346.387439 -245.852484) (xy 346.43006 -245.827877) (xy 346.476076 -245.810425)
			(xy 346.524295 -245.800581) (xy 346.57347 -245.7986) (xy 346.622325 -245.804532) (xy 346.669596 -245.818224)
			(xy 346.714058 -245.839322) (xy 346.754561 -245.867278) (xy 346.790054 -245.90137) (xy 346.819619 -245.940714)
			(xy 346.84249 -245.984291) (xy 346.858074 -246.030972) (xy 346.865969 -246.079549) (xy 346.866464 -246.104156)
			(xy 347.195406 -246.104156) (xy 347.199366 -246.055102) (xy 347.211143 -246.007318) (xy 347.230434 -245.962042)
			(xy 347.256737 -245.920446) (xy 347.289372 -245.883609) (xy 347.327493 -245.852484) (xy 347.370114 -245.827877)
			(xy 347.41613 -245.810425) (xy 347.464349 -245.800581) (xy 347.513524 -245.7986) (xy 347.562379 -245.804532)
			(xy 347.60965 -245.818224) (xy 347.654112 -245.839322) (xy 347.694615 -245.867278) (xy 347.730108 -245.90137)
			(xy 347.759673 -245.940714) (xy 347.782544 -245.984291) (xy 347.798128 -246.030972) (xy 347.806023 -246.079549)
			(xy 347.806518 -246.104156) (xy 348.135206 -246.104156) (xy 348.139166 -246.055102) (xy 348.150943 -246.007318)
			(xy 348.170234 -245.962042) (xy 348.196537 -245.920446) (xy 348.229172 -245.883609) (xy 348.267293 -245.852484)
			(xy 348.309914 -245.827877) (xy 348.35593 -245.810425) (xy 348.404149 -245.800581) (xy 348.453324 -245.7986)
			(xy 348.502179 -245.804532) (xy 348.54945 -245.818224) (xy 348.593912 -245.839322) (xy 348.634415 -245.867278)
			(xy 348.669908 -245.90137) (xy 348.699473 -245.940714) (xy 348.722344 -245.984291) (xy 348.737928 -246.030972)
			(xy 348.745823 -246.079549) (xy 348.746318 -246.104156) (xy 349.07526 -246.104156) (xy 349.07922 -246.055102)
			(xy 349.090997 -246.007318) (xy 349.110288 -245.962042) (xy 349.136591 -245.920446) (xy 349.169226 -245.883609)
			(xy 349.207347 -245.852484) (xy 349.249968 -245.827877) (xy 349.295984 -245.810425) (xy 349.344203 -245.800581)
			(xy 349.393378 -245.7986) (xy 349.442233 -245.804532) (xy 349.489504 -245.818224) (xy 349.533966 -245.839322)
			(xy 349.574469 -245.867278) (xy 349.609962 -245.90137) (xy 349.639527 -245.940714) (xy 349.662398 -245.984291)
			(xy 349.677982 -246.030972) (xy 349.685877 -246.079549) (xy 349.686372 -246.104156) (xy 350.015314 -246.104156)
			(xy 350.019274 -246.055102) (xy 350.031051 -246.007318) (xy 350.050342 -245.962042) (xy 350.076645 -245.920446)
			(xy 350.10928 -245.883609) (xy 350.147401 -245.852484) (xy 350.190022 -245.827877) (xy 350.236038 -245.810425)
			(xy 350.284257 -245.800581) (xy 350.333432 -245.7986) (xy 350.382287 -245.804532) (xy 350.429558 -245.818224)
			(xy 350.47402 -245.839322) (xy 350.514523 -245.867278) (xy 350.550016 -245.90137) (xy 350.579581 -245.940714)
			(xy 350.602452 -245.984291) (xy 350.618036 -246.030972) (xy 350.625931 -246.079549) (xy 350.626426 -246.104156)
			(xy 350.955368 -246.104156) (xy 350.959328 -246.055102) (xy 350.971105 -246.007318) (xy 350.990396 -245.962042)
			(xy 351.016699 -245.920446) (xy 351.049334 -245.883609) (xy 351.087455 -245.852484) (xy 351.130076 -245.827877)
			(xy 351.176092 -245.810425) (xy 351.224311 -245.800581) (xy 351.273486 -245.7986) (xy 351.322341 -245.804532)
			(xy 351.369612 -245.818224) (xy 351.414074 -245.839322) (xy 351.454577 -245.867278) (xy 351.49007 -245.90137)
			(xy 351.519635 -245.940714) (xy 351.542506 -245.984291) (xy 351.55809 -246.030972) (xy 351.565985 -246.079549)
			(xy 351.56648 -246.104156) (xy 351.895422 -246.104156) (xy 351.899382 -246.055102) (xy 351.911159 -246.007318)
			(xy 351.93045 -245.962042) (xy 351.956753 -245.920446) (xy 351.989388 -245.883609) (xy 352.027509 -245.852484)
			(xy 352.07013 -245.827877) (xy 352.116146 -245.810425) (xy 352.164365 -245.800581) (xy 352.21354 -245.7986)
			(xy 352.262395 -245.804532) (xy 352.309666 -245.818224) (xy 352.354128 -245.839322) (xy 352.394631 -245.867278)
			(xy 352.430124 -245.90137) (xy 352.459689 -245.940714) (xy 352.48256 -245.984291) (xy 352.498144 -246.030972)
			(xy 352.506039 -246.079549) (xy 352.506534 -246.104156) (xy 352.835222 -246.104156) (xy 352.839182 -246.055102)
			(xy 352.850959 -246.007318) (xy 352.87025 -245.962042) (xy 352.896553 -245.920446) (xy 352.929188 -245.883609)
			(xy 352.967309 -245.852484) (xy 353.00993 -245.827877) (xy 353.055946 -245.810425) (xy 353.104165 -245.800581)
			(xy 353.15334 -245.7986) (xy 353.202195 -245.804532) (xy 353.249466 -245.818224) (xy 353.293928 -245.839322)
			(xy 353.334431 -245.867278) (xy 353.369924 -245.90137) (xy 353.399489 -245.940714) (xy 353.42236 -245.984291)
			(xy 353.437944 -246.030972) (xy 353.445839 -246.079549) (xy 353.446334 -246.104156) (xy 353.775276 -246.104156)
			(xy 353.779236 -246.055102) (xy 353.791013 -246.007318) (xy 353.810304 -245.962042) (xy 353.836607 -245.920446)
			(xy 353.869242 -245.883609) (xy 353.907363 -245.852484) (xy 353.949984 -245.827877) (xy 353.996 -245.810425)
			(xy 354.044219 -245.800581) (xy 354.093394 -245.7986) (xy 354.142249 -245.804532) (xy 354.18952 -245.818224)
			(xy 354.233982 -245.839322) (xy 354.274485 -245.867278) (xy 354.309978 -245.90137) (xy 354.339543 -245.940714)
			(xy 354.362414 -245.984291) (xy 354.377998 -246.030972) (xy 354.385893 -246.079549) (xy 354.386388 -246.104156)
			(xy 354.71533 -246.104156) (xy 354.71929 -246.055102) (xy 354.731067 -246.007318) (xy 354.750358 -245.962042)
			(xy 354.776661 -245.920446) (xy 354.809296 -245.883609) (xy 354.847417 -245.852484) (xy 354.890038 -245.827877)
			(xy 354.936054 -245.810425) (xy 354.984273 -245.800581) (xy 355.033448 -245.7986) (xy 355.082303 -245.804532)
			(xy 355.129574 -245.818224) (xy 355.174036 -245.839322) (xy 355.214539 -245.867278) (xy 355.250032 -245.90137)
			(xy 355.279597 -245.940714) (xy 355.302468 -245.984291) (xy 355.318052 -246.030972) (xy 355.325947 -246.079549)
			(xy 355.326442 -246.104156) (xy 355.655384 -246.104156) (xy 355.659344 -246.055102) (xy 355.671121 -246.007318)
			(xy 355.690412 -245.962042) (xy 355.716715 -245.920446) (xy 355.74935 -245.883609) (xy 355.787471 -245.852484)
			(xy 355.830092 -245.827877) (xy 355.876108 -245.810425) (xy 355.924327 -245.800581) (xy 355.973502 -245.7986)
			(xy 356.022357 -245.804532) (xy 356.069628 -245.818224) (xy 356.11409 -245.839322) (xy 356.154593 -245.867278)
			(xy 356.190086 -245.90137) (xy 356.219651 -245.940714) (xy 356.242522 -245.984291) (xy 356.258106 -246.030972)
			(xy 356.266001 -246.079549) (xy 356.266496 -246.104156) (xy 363.168958 -246.104156) (xy 363.172918 -246.055102)
			(xy 363.184695 -246.007318) (xy 363.203986 -245.962042) (xy 363.230289 -245.920446) (xy 363.262924 -245.883609)
			(xy 363.301045 -245.852484) (xy 363.343666 -245.827877) (xy 363.389682 -245.810425) (xy 363.437901 -245.800581)
			(xy 363.487076 -245.7986) (xy 363.535931 -245.804532) (xy 363.583202 -245.818224) (xy 363.627664 -245.839322)
			(xy 363.668167 -245.867278) (xy 363.70366 -245.90137) (xy 363.733225 -245.940714) (xy 363.756096 -245.984291)
			(xy 363.77168 -246.030972) (xy 363.779575 -246.079549) (xy 363.78007 -246.104156) (xy 363.780069 -246.1042)
			(xy 364.108896 -246.1042) (xy 364.113068 -246.053848) (xy 364.125472 -246.00487) (xy 364.145768 -245.958601)
			(xy 364.173403 -245.916305) (xy 364.207623 -245.879133) (xy 364.247495 -245.848102) (xy 364.291931 -245.824057)
			(xy 364.339718 -245.807653) (xy 364.389554 -245.79934) (xy 364.414816 -245.798848) (xy 365.35487 -245.798848)
			(xy 365.380126 -245.799426) (xy 365.429949 -245.807736) (xy 365.477725 -245.824133) (xy 365.52215 -245.848171)
			(xy 365.562012 -245.879193) (xy 365.596224 -245.916354) (xy 365.623853 -245.958639) (xy 365.644144 -246.004896)
			(xy 365.656545 -246.053861) (xy 365.660712 -246.104156) (xy 365.98912 -246.104156) (xy 365.99308 -246.055102)
			(xy 366.004857 -246.007318) (xy 366.024148 -245.962042) (xy 366.050451 -245.920446) (xy 366.083086 -245.883609)
			(xy 366.121207 -245.852484) (xy 366.163828 -245.827877) (xy 366.209844 -245.810425) (xy 366.258063 -245.800581)
			(xy 366.307238 -245.7986) (xy 366.356093 -245.804532) (xy 366.403364 -245.818224) (xy 366.447826 -245.839322)
			(xy 366.488329 -245.867278) (xy 366.523822 -245.90137) (xy 366.553387 -245.940714) (xy 366.576258 -245.984291)
			(xy 366.591842 -246.030972) (xy 366.599737 -246.079549) (xy 366.600232 -246.104156) (xy 366.600231 -246.1042)
			(xy 366.928796 -246.1042) (xy 366.932969 -246.053847) (xy 366.945372 -246.004868) (xy 366.965669 -245.958599)
			(xy 366.993305 -245.916302) (xy 367.027526 -245.879131) (xy 367.067399 -245.848099) (xy 367.111836 -245.824054)
			(xy 367.159625 -245.807652) (xy 367.209461 -245.799339) (xy 367.234724 -245.798848) (xy 368.174778 -245.798848)
			(xy 368.200033 -245.799427) (xy 368.249855 -245.807737) (xy 368.29763 -245.824135) (xy 368.342054 -245.848173)
			(xy 368.381915 -245.879196) (xy 368.416126 -245.916357) (xy 368.443754 -245.958642) (xy 368.464045 -246.004897)
			(xy 368.476445 -246.053862) (xy 368.480612 -246.104156) (xy 368.809028 -246.104156) (xy 368.812988 -246.055102)
			(xy 368.824765 -246.007318) (xy 368.844056 -245.962042) (xy 368.870359 -245.920446) (xy 368.902994 -245.883609)
			(xy 368.941115 -245.852484) (xy 368.983736 -245.827877) (xy 369.029752 -245.810425) (xy 369.077971 -245.800581)
			(xy 369.127146 -245.7986) (xy 369.176001 -245.804532) (xy 369.223272 -245.818224) (xy 369.267734 -245.839322)
			(xy 369.308237 -245.867278) (xy 369.34373 -245.90137) (xy 369.373295 -245.940714) (xy 369.396166 -245.984291)
			(xy 369.41175 -246.030972) (xy 369.419645 -246.079549) (xy 369.42014 -246.104156) (xy 369.420139 -246.1042)
			(xy 369.749024 -246.1042) (xy 369.753196 -246.053856) (xy 369.765597 -246.004885) (xy 369.785888 -245.958623)
			(xy 369.813518 -245.916332) (xy 369.847731 -245.879165) (xy 369.887595 -245.848136) (xy 369.932022 -245.824092)
			(xy 369.979801 -245.807687) (xy 370.029628 -245.79937) (xy 370.054886 -245.798848) (xy 370.99494 -245.798848)
			(xy 371.02019 -245.799461) (xy 371.069999 -245.807778) (xy 371.11776 -245.82418) (xy 371.162171 -245.848219)
			(xy 371.202019 -245.879239) (xy 371.236219 -245.916395) (xy 371.263838 -245.958673) (xy 371.284121 -246.004919)
			(xy 371.296517 -246.053873) (xy 371.300683 -246.104156) (xy 371.628936 -246.104156) (xy 371.632896 -246.055102)
			(xy 371.644673 -246.007318) (xy 371.663964 -245.962042) (xy 371.690267 -245.920446) (xy 371.722902 -245.883609)
			(xy 371.761023 -245.852484) (xy 371.803644 -245.827877) (xy 371.84966 -245.810425) (xy 371.897879 -245.800581)
			(xy 371.947054 -245.7986) (xy 371.995909 -245.804532) (xy 372.04318 -245.818224) (xy 372.087642 -245.839322)
			(xy 372.128145 -245.867278) (xy 372.163638 -245.90137) (xy 372.193203 -245.940714) (xy 372.216074 -245.984291)
			(xy 372.231658 -246.030972) (xy 372.239553 -246.079549) (xy 372.240048 -246.104156) (xy 372.240047 -246.1042)
			(xy 372.568924 -246.1042) (xy 372.573096 -246.053855) (xy 372.585497 -246.004884) (xy 372.60579 -245.958621)
			(xy 372.63342 -245.916329) (xy 372.667634 -245.879162) (xy 372.707499 -245.848133) (xy 372.751927 -245.824089)
			(xy 372.799707 -245.807685) (xy 372.849535 -245.79937) (xy 372.874794 -245.798848) (xy 373.814848 -245.798848)
			(xy 373.840097 -245.799461) (xy 373.889906 -245.80778) (xy 373.937666 -245.824183) (xy 373.982075 -245.848222)
			(xy 374.021923 -245.879242) (xy 374.056121 -245.916398) (xy 374.083739 -245.958675) (xy 374.104022 -246.004921)
			(xy 374.116417 -246.053874) (xy 374.120587 -246.1042) (xy 374.116417 -246.154526) (xy 374.104022 -246.203479)
			(xy 374.083739 -246.249725) (xy 374.056121 -246.292002) (xy 374.021923 -246.329158) (xy 373.982075 -246.360178)
			(xy 373.937666 -246.384217) (xy 373.889906 -246.40062) (xy 373.840097 -246.408939) (xy 373.814848 -246.409464)
			(xy 372.874794 -246.409464) (xy 372.849535 -246.40903) (xy 372.799707 -246.400715) (xy 372.751927 -246.384311)
			(xy 372.707499 -246.360267) (xy 372.667634 -246.329238) (xy 372.63342 -246.292071) (xy 372.60579 -246.249779)
			(xy 372.585497 -246.203516) (xy 372.573096 -246.154545) (xy 372.568924 -246.1042) (xy 372.240047 -246.1042)
			(xy 372.239553 -246.128763) (xy 372.231658 -246.17734) (xy 372.216074 -246.224021) (xy 372.193203 -246.267598)
			(xy 372.163638 -246.306942) (xy 372.128145 -246.341034) (xy 372.087642 -246.36899) (xy 372.04318 -246.390088)
			(xy 371.995909 -246.40378) (xy 371.947054 -246.409712) (xy 371.897879 -246.407731) (xy 371.84966 -246.397887)
			(xy 371.803644 -246.380435) (xy 371.761023 -246.355828) (xy 371.722902 -246.324703) (xy 371.690267 -246.287866)
			(xy 371.663964 -246.24627) (xy 371.644673 -246.200994) (xy 371.632896 -246.15321) (xy 371.628936 -246.104156)
			(xy 371.300683 -246.104156) (xy 371.300687 -246.1042) (xy 371.296517 -246.154527) (xy 371.284121 -246.203481)
			(xy 371.263838 -246.249727) (xy 371.236219 -246.292005) (xy 371.202019 -246.329161) (xy 371.162171 -246.360181)
			(xy 371.11776 -246.38422) (xy 371.069999 -246.400622) (xy 371.02019 -246.408939) (xy 370.99494 -246.409464)
			(xy 370.054886 -246.409464) (xy 370.029628 -246.40903) (xy 369.979801 -246.400713) (xy 369.932022 -246.384308)
			(xy 369.887595 -246.360264) (xy 369.847731 -246.329235) (xy 369.813518 -246.292068) (xy 369.785888 -246.249777)
			(xy 369.765597 -246.203515) (xy 369.753196 -246.154544) (xy 369.749024 -246.1042) (xy 369.420139 -246.1042)
			(xy 369.419645 -246.128763) (xy 369.41175 -246.17734) (xy 369.396166 -246.224021) (xy 369.373295 -246.267598)
			(xy 369.34373 -246.306942) (xy 369.308237 -246.341034) (xy 369.267734 -246.36899) (xy 369.223272 -246.390088)
			(xy 369.176001 -246.40378) (xy 369.127146 -246.409712) (xy 369.077971 -246.407731) (xy 369.029752 -246.397887)
			(xy 368.983736 -246.380435) (xy 368.941115 -246.355828) (xy 368.902994 -246.324703) (xy 368.870359 -246.287866)
			(xy 368.844056 -246.24627) (xy 368.824765 -246.200994) (xy 368.812988 -246.15321) (xy 368.809028 -246.104156)
			(xy 368.480612 -246.104156) (xy 368.480616 -246.1042) (xy 368.476445 -246.154538) (xy 368.464045 -246.203503)
			(xy 368.443754 -246.249758) (xy 368.416126 -246.292043) (xy 368.381915 -246.329204) (xy 368.342054 -246.360227)
			(xy 368.29763 -246.384265) (xy 368.249855 -246.400663) (xy 368.200033 -246.408973) (xy 368.174778 -246.409464)
			(xy 367.234724 -246.409464) (xy 367.209461 -246.409061) (xy 367.159625 -246.400748) (xy 367.111836 -246.384346)
			(xy 367.067399 -246.360301) (xy 367.027526 -246.329269) (xy 366.993305 -246.292098) (xy 366.965669 -246.249801)
			(xy 366.945372 -246.203532) (xy 366.932969 -246.154553) (xy 366.928796 -246.1042) (xy 366.600231 -246.1042)
			(xy 366.599737 -246.128763) (xy 366.591842 -246.17734) (xy 366.576258 -246.224021) (xy 366.553387 -246.267598)
			(xy 366.523822 -246.306942) (xy 366.488329 -246.341034) (xy 366.447826 -246.36899) (xy 366.403364 -246.390088)
			(xy 366.356093 -246.40378) (xy 366.307238 -246.409712) (xy 366.258063 -246.407731) (xy 366.209844 -246.397887)
			(xy 366.163828 -246.380435) (xy 366.121207 -246.355828) (xy 366.083086 -246.324703) (xy 366.050451 -246.287866)
			(xy 366.024148 -246.24627) (xy 366.004857 -246.200994) (xy 365.99308 -246.15321) (xy 365.98912 -246.104156)
			(xy 365.660712 -246.104156) (xy 365.660716 -246.1042) (xy 365.656545 -246.154539) (xy 365.644144 -246.203504)
			(xy 365.623853 -246.249761) (xy 365.596224 -246.292046) (xy 365.562012 -246.329207) (xy 365.52215 -246.360229)
			(xy 365.477725 -246.384267) (xy 365.429949 -246.400664) (xy 365.380126 -246.408974) (xy 365.35487 -246.409464)
			(xy 364.414816 -246.409464) (xy 364.389554 -246.40906) (xy 364.339718 -246.400747) (xy 364.291931 -246.384343)
			(xy 364.247495 -246.360298) (xy 364.207623 -246.329267) (xy 364.173403 -246.292095) (xy 364.145768 -246.249799)
			(xy 364.125472 -246.20353) (xy 364.113068 -246.154552) (xy 364.108896 -246.1042) (xy 363.780069 -246.1042)
			(xy 363.779575 -246.128763) (xy 363.77168 -246.17734) (xy 363.756096 -246.224021) (xy 363.733225 -246.267598)
			(xy 363.70366 -246.306942) (xy 363.668167 -246.341034) (xy 363.627664 -246.36899) (xy 363.583202 -246.390088)
			(xy 363.535931 -246.40378) (xy 363.487076 -246.409712) (xy 363.437901 -246.407731) (xy 363.389682 -246.397887)
			(xy 363.343666 -246.380435) (xy 363.301045 -246.355828) (xy 363.262924 -246.324703) (xy 363.230289 -246.287866)
			(xy 363.203986 -246.24627) (xy 363.184695 -246.200994) (xy 363.172918 -246.15321) (xy 363.168958 -246.104156)
			(xy 356.266496 -246.104156) (xy 356.266001 -246.128763) (xy 356.258106 -246.17734) (xy 356.242522 -246.224021)
			(xy 356.219651 -246.267598) (xy 356.190086 -246.306942) (xy 356.154593 -246.341034) (xy 356.11409 -246.36899)
			(xy 356.069628 -246.390088) (xy 356.022357 -246.40378) (xy 355.973502 -246.409712) (xy 355.924327 -246.407731)
			(xy 355.876108 -246.397887) (xy 355.830092 -246.380435) (xy 355.787471 -246.355828) (xy 355.74935 -246.324703)
			(xy 355.716715 -246.287866) (xy 355.690412 -246.24627) (xy 355.671121 -246.200994) (xy 355.659344 -246.15321)
			(xy 355.655384 -246.104156) (xy 355.326442 -246.104156) (xy 355.325947 -246.128763) (xy 355.318052 -246.17734)
			(xy 355.302468 -246.224021) (xy 355.279597 -246.267598) (xy 355.250032 -246.306942) (xy 355.214539 -246.341034)
			(xy 355.174036 -246.36899) (xy 355.129574 -246.390088) (xy 355.082303 -246.40378) (xy 355.033448 -246.409712)
			(xy 354.984273 -246.407731) (xy 354.936054 -246.397887) (xy 354.890038 -246.380435) (xy 354.847417 -246.355828)
			(xy 354.809296 -246.324703) (xy 354.776661 -246.287866) (xy 354.750358 -246.24627) (xy 354.731067 -246.200994)
			(xy 354.71929 -246.15321) (xy 354.71533 -246.104156) (xy 354.386388 -246.104156) (xy 354.385893 -246.128763)
			(xy 354.377998 -246.17734) (xy 354.362414 -246.224021) (xy 354.339543 -246.267598) (xy 354.309978 -246.306942)
			(xy 354.274485 -246.341034) (xy 354.233982 -246.36899) (xy 354.18952 -246.390088) (xy 354.142249 -246.40378)
			(xy 354.093394 -246.409712) (xy 354.044219 -246.407731) (xy 353.996 -246.397887) (xy 353.949984 -246.380435)
			(xy 353.907363 -246.355828) (xy 353.869242 -246.324703) (xy 353.836607 -246.287866) (xy 353.810304 -246.24627)
			(xy 353.791013 -246.200994) (xy 353.779236 -246.15321) (xy 353.775276 -246.104156) (xy 353.446334 -246.104156)
			(xy 353.445839 -246.128763) (xy 353.437944 -246.17734) (xy 353.42236 -246.224021) (xy 353.399489 -246.267598)
			(xy 353.369924 -246.306942) (xy 353.334431 -246.341034) (xy 353.293928 -246.36899) (xy 353.249466 -246.390088)
			(xy 353.202195 -246.40378) (xy 353.15334 -246.409712) (xy 353.104165 -246.407731) (xy 353.055946 -246.397887)
			(xy 353.00993 -246.380435) (xy 352.967309 -246.355828) (xy 352.929188 -246.324703) (xy 352.896553 -246.287866)
			(xy 352.87025 -246.24627) (xy 352.850959 -246.200994) (xy 352.839182 -246.15321) (xy 352.835222 -246.104156)
			(xy 352.506534 -246.104156) (xy 352.506039 -246.128763) (xy 352.498144 -246.17734) (xy 352.48256 -246.224021)
			(xy 352.459689 -246.267598) (xy 352.430124 -246.306942) (xy 352.394631 -246.341034) (xy 352.354128 -246.36899)
			(xy 352.309666 -246.390088) (xy 352.262395 -246.40378) (xy 352.21354 -246.409712) (xy 352.164365 -246.407731)
			(xy 352.116146 -246.397887) (xy 352.07013 -246.380435) (xy 352.027509 -246.355828) (xy 351.989388 -246.324703)
			(xy 351.956753 -246.287866) (xy 351.93045 -246.24627) (xy 351.911159 -246.200994) (xy 351.899382 -246.15321)
			(xy 351.895422 -246.104156) (xy 351.56648 -246.104156) (xy 351.565985 -246.128763) (xy 351.55809 -246.17734)
			(xy 351.542506 -246.224021) (xy 351.519635 -246.267598) (xy 351.49007 -246.306942) (xy 351.454577 -246.341034)
			(xy 351.414074 -246.36899) (xy 351.369612 -246.390088) (xy 351.322341 -246.40378) (xy 351.273486 -246.409712)
			(xy 351.224311 -246.407731) (xy 351.176092 -246.397887) (xy 351.130076 -246.380435) (xy 351.087455 -246.355828)
			(xy 351.049334 -246.324703) (xy 351.016699 -246.287866) (xy 350.990396 -246.24627) (xy 350.971105 -246.200994)
			(xy 350.959328 -246.15321) (xy 350.955368 -246.104156) (xy 350.626426 -246.104156) (xy 350.625931 -246.128763)
			(xy 350.618036 -246.17734) (xy 350.602452 -246.224021) (xy 350.579581 -246.267598) (xy 350.550016 -246.306942)
			(xy 350.514523 -246.341034) (xy 350.47402 -246.36899) (xy 350.429558 -246.390088) (xy 350.382287 -246.40378)
			(xy 350.333432 -246.409712) (xy 350.284257 -246.407731) (xy 350.236038 -246.397887) (xy 350.190022 -246.380435)
			(xy 350.147401 -246.355828) (xy 350.10928 -246.324703) (xy 350.076645 -246.287866) (xy 350.050342 -246.24627)
			(xy 350.031051 -246.200994) (xy 350.019274 -246.15321) (xy 350.015314 -246.104156) (xy 349.686372 -246.104156)
			(xy 349.685877 -246.128763) (xy 349.677982 -246.17734) (xy 349.662398 -246.224021) (xy 349.639527 -246.267598)
			(xy 349.609962 -246.306942) (xy 349.574469 -246.341034) (xy 349.533966 -246.36899) (xy 349.489504 -246.390088)
			(xy 349.442233 -246.40378) (xy 349.393378 -246.409712) (xy 349.344203 -246.407731) (xy 349.295984 -246.397887)
			(xy 349.249968 -246.380435) (xy 349.207347 -246.355828) (xy 349.169226 -246.324703) (xy 349.136591 -246.287866)
			(xy 349.110288 -246.24627) (xy 349.090997 -246.200994) (xy 349.07922 -246.15321) (xy 349.07526 -246.104156)
			(xy 348.746318 -246.104156) (xy 348.745823 -246.128763) (xy 348.737928 -246.17734) (xy 348.722344 -246.224021)
			(xy 348.699473 -246.267598) (xy 348.669908 -246.306942) (xy 348.634415 -246.341034) (xy 348.593912 -246.36899)
			(xy 348.54945 -246.390088) (xy 348.502179 -246.40378) (xy 348.453324 -246.409712) (xy 348.404149 -246.407731)
			(xy 348.35593 -246.397887) (xy 348.309914 -246.380435) (xy 348.267293 -246.355828) (xy 348.229172 -246.324703)
			(xy 348.196537 -246.287866) (xy 348.170234 -246.24627) (xy 348.150943 -246.200994) (xy 348.139166 -246.15321)
			(xy 348.135206 -246.104156) (xy 347.806518 -246.104156) (xy 347.806023 -246.128763) (xy 347.798128 -246.17734)
			(xy 347.782544 -246.224021) (xy 347.759673 -246.267598) (xy 347.730108 -246.306942) (xy 347.694615 -246.341034)
			(xy 347.654112 -246.36899) (xy 347.60965 -246.390088) (xy 347.562379 -246.40378) (xy 347.513524 -246.409712)
			(xy 347.464349 -246.407731) (xy 347.41613 -246.397887) (xy 347.370114 -246.380435) (xy 347.327493 -246.355828)
			(xy 347.289372 -246.324703) (xy 347.256737 -246.287866) (xy 347.230434 -246.24627) (xy 347.211143 -246.200994)
			(xy 347.199366 -246.15321) (xy 347.195406 -246.104156) (xy 346.866464 -246.104156) (xy 346.865969 -246.128763)
			(xy 346.858074 -246.17734) (xy 346.84249 -246.224021) (xy 346.819619 -246.267598) (xy 346.790054 -246.306942)
			(xy 346.754561 -246.341034) (xy 346.714058 -246.36899) (xy 346.669596 -246.390088) (xy 346.622325 -246.40378)
			(xy 346.57347 -246.409712) (xy 346.524295 -246.407731) (xy 346.476076 -246.397887) (xy 346.43006 -246.380435)
			(xy 346.387439 -246.355828) (xy 346.349318 -246.324703) (xy 346.316683 -246.287866) (xy 346.29038 -246.24627)
			(xy 346.271089 -246.200994) (xy 346.259312 -246.15321) (xy 346.255352 -246.104156) (xy 345.92641 -246.104156)
			(xy 345.925915 -246.128763) (xy 345.91802 -246.17734) (xy 345.902436 -246.224021) (xy 345.879565 -246.267598)
			(xy 345.85 -246.306942) (xy 345.814507 -246.341034) (xy 345.774004 -246.36899) (xy 345.729542 -246.390088)
			(xy 345.682271 -246.40378) (xy 345.633416 -246.409712) (xy 345.584241 -246.407731) (xy 345.536022 -246.397887)
			(xy 345.490006 -246.380435) (xy 345.447385 -246.355828) (xy 345.409264 -246.324703) (xy 345.376629 -246.287866)
			(xy 345.350326 -246.24627) (xy 345.331035 -246.200994) (xy 345.319258 -246.15321) (xy 345.315298 -246.104156)
			(xy 344.986962 -246.104156) (xy 344.986965 -246.104198) (xy 344.98305 -246.152993) (xy 344.971402 -246.200539)
			(xy 344.952321 -246.24562) (xy 344.926295 -246.28708) (xy 344.89399 -246.323859) (xy 344.856233 -246.355015)
			(xy 344.81399 -246.379751) (xy 344.768344 -246.397433) (xy 344.720461 -246.40761) (xy 344.696034 -246.40921)
			(xy 344.686636 -246.409464) (xy 344.669618 -246.417084) (xy 344.641424 -246.44477) (xy 344.634611 -246.452036)
			(xy 344.626889 -246.470379) (xy 344.626438 -246.48033) (xy 344.626438 -246.914162) (xy 344.845398 -246.914162)
			(xy 344.849358 -246.865108) (xy 344.861135 -246.817324) (xy 344.880426 -246.772048) (xy 344.906729 -246.730452)
			(xy 344.939364 -246.693615) (xy 344.977485 -246.66249) (xy 345.020106 -246.637883) (xy 345.066122 -246.620431)
			(xy 345.114341 -246.610587) (xy 345.163516 -246.608606) (xy 345.212371 -246.614538) (xy 345.259642 -246.62823)
			(xy 345.304104 -246.649328) (xy 345.344607 -246.677284) (xy 345.3801 -246.711376) (xy 345.409665 -246.75072)
			(xy 345.432536 -246.794297) (xy 345.44812 -246.840978) (xy 345.456015 -246.889555) (xy 345.45651 -246.914162)
			(xy 345.785198 -246.914162) (xy 345.789158 -246.865108) (xy 345.800935 -246.817324) (xy 345.820226 -246.772048)
			(xy 345.846529 -246.730452) (xy 345.879164 -246.693615) (xy 345.917285 -246.66249) (xy 345.959906 -246.637883)
			(xy 346.005922 -246.620431) (xy 346.054141 -246.610587) (xy 346.103316 -246.608606) (xy 346.152171 -246.614538)
			(xy 346.199442 -246.62823) (xy 346.243904 -246.649328) (xy 346.284407 -246.677284) (xy 346.3199 -246.711376)
			(xy 346.349465 -246.75072) (xy 346.372336 -246.794297) (xy 346.38792 -246.840978) (xy 346.395815 -246.889555)
			(xy 346.39631 -246.914162) (xy 346.725252 -246.914162) (xy 346.729212 -246.865108) (xy 346.740989 -246.817324)
			(xy 346.76028 -246.772048) (xy 346.786583 -246.730452) (xy 346.819218 -246.693615) (xy 346.857339 -246.66249)
			(xy 346.89996 -246.637883) (xy 346.945976 -246.620431) (xy 346.994195 -246.610587) (xy 347.04337 -246.608606)
			(xy 347.092225 -246.614538) (xy 347.139496 -246.62823) (xy 347.183958 -246.649328) (xy 347.224461 -246.677284)
			(xy 347.259954 -246.711376) (xy 347.289519 -246.75072) (xy 347.31239 -246.794297) (xy 347.327974 -246.840978)
			(xy 347.335869 -246.889555) (xy 347.336364 -246.914162) (xy 347.665306 -246.914162) (xy 347.669266 -246.865108)
			(xy 347.681043 -246.817324) (xy 347.700334 -246.772048) (xy 347.726637 -246.730452) (xy 347.759272 -246.693615)
			(xy 347.797393 -246.66249) (xy 347.840014 -246.637883) (xy 347.88603 -246.620431) (xy 347.934249 -246.610587)
			(xy 347.983424 -246.608606) (xy 348.032279 -246.614538) (xy 348.07955 -246.62823) (xy 348.124012 -246.649328)
			(xy 348.164515 -246.677284) (xy 348.200008 -246.711376) (xy 348.229573 -246.75072) (xy 348.252444 -246.794297)
			(xy 348.268028 -246.840978) (xy 348.275923 -246.889555) (xy 348.276418 -246.914162) (xy 348.60536 -246.914162)
			(xy 348.60932 -246.865108) (xy 348.621097 -246.817324) (xy 348.640388 -246.772048) (xy 348.666691 -246.730452)
			(xy 348.699326 -246.693615) (xy 348.737447 -246.66249) (xy 348.780068 -246.637883) (xy 348.826084 -246.620431)
			(xy 348.874303 -246.610587) (xy 348.923478 -246.608606) (xy 348.972333 -246.614538) (xy 349.019604 -246.62823)
			(xy 349.064066 -246.649328) (xy 349.104569 -246.677284) (xy 349.140062 -246.711376) (xy 349.169627 -246.75072)
			(xy 349.192498 -246.794297) (xy 349.208082 -246.840978) (xy 349.215977 -246.889555) (xy 349.216472 -246.914162)
			(xy 349.545414 -246.914162) (xy 349.549374 -246.865108) (xy 349.561151 -246.817324) (xy 349.580442 -246.772048)
			(xy 349.606745 -246.730452) (xy 349.63938 -246.693615) (xy 349.677501 -246.66249) (xy 349.720122 -246.637883)
			(xy 349.766138 -246.620431) (xy 349.814357 -246.610587) (xy 349.863532 -246.608606) (xy 349.912387 -246.614538)
			(xy 349.959658 -246.62823) (xy 350.00412 -246.649328) (xy 350.044623 -246.677284) (xy 350.080116 -246.711376)
			(xy 350.109681 -246.75072) (xy 350.132552 -246.794297) (xy 350.148136 -246.840978) (xy 350.156031 -246.889555)
			(xy 350.156526 -246.914162) (xy 350.485214 -246.914162) (xy 350.489174 -246.865108) (xy 350.500951 -246.817324)
			(xy 350.520242 -246.772048) (xy 350.546545 -246.730452) (xy 350.57918 -246.693615) (xy 350.617301 -246.66249)
			(xy 350.659922 -246.637883) (xy 350.705938 -246.620431) (xy 350.754157 -246.610587) (xy 350.803332 -246.608606)
			(xy 350.852187 -246.614538) (xy 350.899458 -246.62823) (xy 350.94392 -246.649328) (xy 350.984423 -246.677284)
			(xy 351.019916 -246.711376) (xy 351.049481 -246.75072) (xy 351.072352 -246.794297) (xy 351.087936 -246.840978)
			(xy 351.095831 -246.889555) (xy 351.096326 -246.914162) (xy 351.425268 -246.914162) (xy 351.429228 -246.865108)
			(xy 351.441005 -246.817324) (xy 351.460296 -246.772048) (xy 351.486599 -246.730452) (xy 351.519234 -246.693615)
			(xy 351.557355 -246.66249) (xy 351.599976 -246.637883) (xy 351.645992 -246.620431) (xy 351.694211 -246.610587)
			(xy 351.743386 -246.608606) (xy 351.792241 -246.614538) (xy 351.839512 -246.62823) (xy 351.883974 -246.649328)
			(xy 351.924477 -246.677284) (xy 351.95997 -246.711376) (xy 351.989535 -246.75072) (xy 352.012406 -246.794297)
			(xy 352.02799 -246.840978) (xy 352.035885 -246.889555) (xy 352.03638 -246.914162) (xy 352.365322 -246.914162)
			(xy 352.369282 -246.865108) (xy 352.381059 -246.817324) (xy 352.40035 -246.772048) (xy 352.426653 -246.730452)
			(xy 352.459288 -246.693615) (xy 352.497409 -246.66249) (xy 352.54003 -246.637883) (xy 352.586046 -246.620431)
			(xy 352.634265 -246.610587) (xy 352.68344 -246.608606) (xy 352.732295 -246.614538) (xy 352.779566 -246.62823)
			(xy 352.824028 -246.649328) (xy 352.864531 -246.677284) (xy 352.900024 -246.711376) (xy 352.929589 -246.75072)
			(xy 352.95246 -246.794297) (xy 352.968044 -246.840978) (xy 352.975939 -246.889555) (xy 352.976434 -246.914162)
			(xy 353.305376 -246.914162) (xy 353.309336 -246.865108) (xy 353.321113 -246.817324) (xy 353.340404 -246.772048)
			(xy 353.366707 -246.730452) (xy 353.399342 -246.693615) (xy 353.437463 -246.66249) (xy 353.480084 -246.637883)
			(xy 353.5261 -246.620431) (xy 353.574319 -246.610587) (xy 353.623494 -246.608606) (xy 353.672349 -246.614538)
			(xy 353.71962 -246.62823) (xy 353.764082 -246.649328) (xy 353.804585 -246.677284) (xy 353.840078 -246.711376)
			(xy 353.869643 -246.75072) (xy 353.892514 -246.794297) (xy 353.908098 -246.840978) (xy 353.915993 -246.889555)
			(xy 353.916488 -246.914162) (xy 354.24543 -246.914162) (xy 354.24939 -246.865108) (xy 354.261167 -246.817324)
			(xy 354.280458 -246.772048) (xy 354.306761 -246.730452) (xy 354.339396 -246.693615) (xy 354.377517 -246.66249)
			(xy 354.420138 -246.637883) (xy 354.466154 -246.620431) (xy 354.514373 -246.610587) (xy 354.563548 -246.608606)
			(xy 354.612403 -246.614538) (xy 354.659674 -246.62823) (xy 354.704136 -246.649328) (xy 354.744639 -246.677284)
			(xy 354.780132 -246.711376) (xy 354.809697 -246.75072) (xy 354.832568 -246.794297) (xy 354.848152 -246.840978)
			(xy 354.856047 -246.889555) (xy 354.856542 -246.914162) (xy 355.18523 -246.914162) (xy 355.18919 -246.865108)
			(xy 355.200967 -246.817324) (xy 355.220258 -246.772048) (xy 355.246561 -246.730452) (xy 355.279196 -246.693615)
			(xy 355.317317 -246.66249) (xy 355.359938 -246.637883) (xy 355.405954 -246.620431) (xy 355.454173 -246.610587)
			(xy 355.503348 -246.608606) (xy 355.552203 -246.614538) (xy 355.599474 -246.62823) (xy 355.643936 -246.649328)
			(xy 355.684439 -246.677284) (xy 355.719932 -246.711376) (xy 355.749497 -246.75072) (xy 355.772368 -246.794297)
			(xy 355.787952 -246.840978) (xy 355.795847 -246.889555) (xy 355.796342 -246.914162) (xy 356.125284 -246.914162)
			(xy 356.129244 -246.865108) (xy 356.141021 -246.817324) (xy 356.160312 -246.772048) (xy 356.186615 -246.730452)
			(xy 356.21925 -246.693615) (xy 356.257371 -246.66249) (xy 356.299992 -246.637883) (xy 356.346008 -246.620431)
			(xy 356.394227 -246.610587) (xy 356.443402 -246.608606) (xy 356.492257 -246.614538) (xy 356.539528 -246.62823)
			(xy 356.58399 -246.649328) (xy 356.624493 -246.677284) (xy 356.659986 -246.711376) (xy 356.689551 -246.75072)
			(xy 356.712422 -246.794297) (xy 356.728006 -246.840978) (xy 356.735901 -246.889555) (xy 356.736396 -246.914162)
			(xy 357.065338 -246.914162) (xy 357.069298 -246.865108) (xy 357.081075 -246.817324) (xy 357.100366 -246.772048)
			(xy 357.126669 -246.730452) (xy 357.159304 -246.693615) (xy 357.197425 -246.66249) (xy 357.240046 -246.637883)
			(xy 357.286062 -246.620431) (xy 357.334281 -246.610587) (xy 357.383456 -246.608606) (xy 357.432311 -246.614538)
			(xy 357.479582 -246.62823) (xy 357.524044 -246.649328) (xy 357.564547 -246.677284) (xy 357.60004 -246.711376)
			(xy 357.629605 -246.75072) (xy 357.652476 -246.794297) (xy 357.66806 -246.840978) (xy 357.675955 -246.889555)
			(xy 357.67645 -246.914162) (xy 358.005392 -246.914162) (xy 358.009352 -246.865108) (xy 358.021129 -246.817324)
			(xy 358.04042 -246.772048) (xy 358.066723 -246.730452) (xy 358.099358 -246.693615) (xy 358.137479 -246.66249)
			(xy 358.1801 -246.637883) (xy 358.226116 -246.620431) (xy 358.274335 -246.610587) (xy 358.32351 -246.608606)
			(xy 358.372365 -246.614538) (xy 358.419636 -246.62823) (xy 358.464098 -246.649328) (xy 358.504601 -246.677284)
			(xy 358.540094 -246.711376) (xy 358.569659 -246.75072) (xy 358.59253 -246.794297) (xy 358.608114 -246.840978)
			(xy 358.616009 -246.889555) (xy 358.616504 -246.914162) (xy 360.81895 -246.914162) (xy 360.82291 -246.865108)
			(xy 360.834687 -246.817324) (xy 360.853978 -246.772048) (xy 360.880281 -246.730452) (xy 360.912916 -246.693615)
			(xy 360.951037 -246.66249) (xy 360.993658 -246.637883) (xy 361.039674 -246.620431) (xy 361.087893 -246.610587)
			(xy 361.137068 -246.608606) (xy 361.185923 -246.614538) (xy 361.233194 -246.62823) (xy 361.277656 -246.649328)
			(xy 361.318159 -246.677284) (xy 361.353652 -246.711376) (xy 361.383217 -246.75072) (xy 361.406088 -246.794297)
			(xy 361.421672 -246.840978) (xy 361.429567 -246.889555) (xy 361.430062 -246.914162) (xy 361.430061 -246.9142)
			(xy 361.758647 -246.9142) (xy 361.762823 -246.863808) (xy 361.775236 -246.814791) (xy 361.795548 -246.768485)
			(xy 361.823205 -246.726155) (xy 361.857452 -246.688953) (xy 361.897355 -246.657897) (xy 361.941825 -246.633831)
			(xy 361.989651 -246.617414) (xy 362.039526 -246.609093) (xy 362.064808 -246.6086) (xy 363.004862 -246.6086)
			(xy 363.03014 -246.609166) (xy 363.080006 -246.617481) (xy 363.127824 -246.633892) (xy 363.172288 -246.65795)
			(xy 363.212185 -246.688999) (xy 363.246428 -246.726191) (xy 363.274081 -246.768513) (xy 363.29439 -246.81481)
			(xy 363.306801 -246.863818) (xy 363.310974 -246.914162) (xy 363.639112 -246.914162) (xy 363.643072 -246.865108)
			(xy 363.654849 -246.817324) (xy 363.67414 -246.772048) (xy 363.700443 -246.730452) (xy 363.733078 -246.693615)
			(xy 363.771199 -246.66249) (xy 363.81382 -246.637883) (xy 363.859836 -246.620431) (xy 363.908055 -246.610587)
			(xy 363.95723 -246.608606) (xy 364.006085 -246.614538) (xy 364.053356 -246.62823) (xy 364.097818 -246.649328)
			(xy 364.138321 -246.677284) (xy 364.173814 -246.711376) (xy 364.203379 -246.75072) (xy 364.22625 -246.794297)
			(xy 364.241834 -246.840978) (xy 364.249729 -246.889555) (xy 364.250224 -246.914162) (xy 364.578912 -246.914162)
			(xy 364.582872 -246.865108) (xy 364.594649 -246.817324) (xy 364.61394 -246.772048) (xy 364.640243 -246.730452)
			(xy 364.672878 -246.693615) (xy 364.710999 -246.66249) (xy 364.75362 -246.637883) (xy 364.799636 -246.620431)
			(xy 364.847855 -246.610587) (xy 364.89703 -246.608606) (xy 364.945885 -246.614538) (xy 364.993156 -246.62823)
			(xy 365.037618 -246.649328) (xy 365.078121 -246.677284) (xy 365.113614 -246.711376) (xy 365.143179 -246.75072)
			(xy 365.16605 -246.794297) (xy 365.181634 -246.840978) (xy 365.189529 -246.889555) (xy 365.190024 -246.914162)
			(xy 365.518966 -246.914162) (xy 365.522926 -246.865108) (xy 365.534703 -246.817324) (xy 365.553994 -246.772048)
			(xy 365.580297 -246.730452) (xy 365.612932 -246.693615) (xy 365.651053 -246.66249) (xy 365.693674 -246.637883)
			(xy 365.73969 -246.620431) (xy 365.787909 -246.610587) (xy 365.837084 -246.608606) (xy 365.885939 -246.614538)
			(xy 365.93321 -246.62823) (xy 365.977672 -246.649328) (xy 366.018175 -246.677284) (xy 366.053668 -246.711376)
			(xy 366.083233 -246.75072) (xy 366.106104 -246.794297) (xy 366.121688 -246.840978) (xy 366.129583 -246.889555)
			(xy 366.130078 -246.914162) (xy 366.45902 -246.914162) (xy 366.46298 -246.865108) (xy 366.474757 -246.817324)
			(xy 366.494048 -246.772048) (xy 366.520351 -246.730452) (xy 366.552986 -246.693615) (xy 366.591107 -246.66249)
			(xy 366.633728 -246.637883) (xy 366.679744 -246.620431) (xy 366.727963 -246.610587) (xy 366.777138 -246.608606)
			(xy 366.825993 -246.614538) (xy 366.873264 -246.62823) (xy 366.917726 -246.649328) (xy 366.958229 -246.677284)
			(xy 366.993722 -246.711376) (xy 367.023287 -246.75072) (xy 367.046158 -246.794297) (xy 367.061742 -246.840978)
			(xy 367.069637 -246.889555) (xy 367.070132 -246.914162) (xy 367.399074 -246.914162) (xy 367.403034 -246.865108)
			(xy 367.414811 -246.817324) (xy 367.434102 -246.772048) (xy 367.460405 -246.730452) (xy 367.49304 -246.693615)
			(xy 367.531161 -246.66249) (xy 367.573782 -246.637883) (xy 367.619798 -246.620431) (xy 367.668017 -246.610587)
			(xy 367.717192 -246.608606) (xy 367.766047 -246.614538) (xy 367.813318 -246.62823) (xy 367.85778 -246.649328)
			(xy 367.898283 -246.677284) (xy 367.933776 -246.711376) (xy 367.963341 -246.75072) (xy 367.986212 -246.794297)
			(xy 368.001796 -246.840978) (xy 368.009691 -246.889555) (xy 368.010186 -246.914162) (xy 368.338874 -246.914162)
			(xy 368.342834 -246.865108) (xy 368.354611 -246.817324) (xy 368.373902 -246.772048) (xy 368.400205 -246.730452)
			(xy 368.43284 -246.693615) (xy 368.470961 -246.66249) (xy 368.513582 -246.637883) (xy 368.559598 -246.620431)
			(xy 368.607817 -246.610587) (xy 368.656992 -246.608606) (xy 368.705847 -246.614538) (xy 368.753118 -246.62823)
			(xy 368.79758 -246.649328) (xy 368.838083 -246.677284) (xy 368.873576 -246.711376) (xy 368.903141 -246.75072)
			(xy 368.926012 -246.794297) (xy 368.941596 -246.840978) (xy 368.949491 -246.889555) (xy 368.949986 -246.914162)
			(xy 369.278928 -246.914162) (xy 369.282888 -246.865108) (xy 369.294665 -246.817324) (xy 369.313956 -246.772048)
			(xy 369.340259 -246.730452) (xy 369.372894 -246.693615) (xy 369.411015 -246.66249) (xy 369.453636 -246.637883)
			(xy 369.499652 -246.620431) (xy 369.547871 -246.610587) (xy 369.597046 -246.608606) (xy 369.645901 -246.614538)
			(xy 369.693172 -246.62823) (xy 369.737634 -246.649328) (xy 369.778137 -246.677284) (xy 369.81363 -246.711376)
			(xy 369.843195 -246.75072) (xy 369.866066 -246.794297) (xy 369.88165 -246.840978) (xy 369.889545 -246.889555)
			(xy 369.89004 -246.914162) (xy 370.218982 -246.914162) (xy 370.222942 -246.865108) (xy 370.234719 -246.817324)
			(xy 370.25401 -246.772048) (xy 370.280313 -246.730452) (xy 370.312948 -246.693615) (xy 370.351069 -246.66249)
			(xy 370.39369 -246.637883) (xy 370.439706 -246.620431) (xy 370.487925 -246.610587) (xy 370.5371 -246.608606)
			(xy 370.585955 -246.614538) (xy 370.633226 -246.62823) (xy 370.677688 -246.649328) (xy 370.718191 -246.677284)
			(xy 370.753684 -246.711376) (xy 370.783249 -246.75072) (xy 370.80612 -246.794297) (xy 370.821704 -246.840978)
			(xy 370.829599 -246.889555) (xy 370.830094 -246.914162) (xy 371.159036 -246.914162) (xy 371.162996 -246.865108)
			(xy 371.174773 -246.817324) (xy 371.194064 -246.772048) (xy 371.220367 -246.730452) (xy 371.253002 -246.693615)
			(xy 371.291123 -246.66249) (xy 371.333744 -246.637883) (xy 371.37976 -246.620431) (xy 371.427979 -246.610587)
			(xy 371.477154 -246.608606) (xy 371.526009 -246.614538) (xy 371.57328 -246.62823) (xy 371.617742 -246.649328)
			(xy 371.658245 -246.677284) (xy 371.693738 -246.711376) (xy 371.723303 -246.75072) (xy 371.746174 -246.794297)
			(xy 371.761758 -246.840978) (xy 371.769653 -246.889555) (xy 371.770148 -246.914162) (xy 372.09909 -246.914162)
			(xy 372.10305 -246.865108) (xy 372.114827 -246.817324) (xy 372.134118 -246.772048) (xy 372.160421 -246.730452)
			(xy 372.193056 -246.693615) (xy 372.231177 -246.66249) (xy 372.273798 -246.637883) (xy 372.319814 -246.620431)
			(xy 372.368033 -246.610587) (xy 372.417208 -246.608606) (xy 372.466063 -246.614538) (xy 372.513334 -246.62823)
			(xy 372.557796 -246.649328) (xy 372.598299 -246.677284) (xy 372.633792 -246.711376) (xy 372.663357 -246.75072)
			(xy 372.686228 -246.794297) (xy 372.701812 -246.840978) (xy 372.709707 -246.889555) (xy 372.710202 -246.914162)
			(xy 373.03889 -246.914162) (xy 373.04285 -246.865108) (xy 373.054627 -246.817324) (xy 373.073918 -246.772048)
			(xy 373.100221 -246.730452) (xy 373.132856 -246.693615) (xy 373.170977 -246.66249) (xy 373.213598 -246.637883)
			(xy 373.259614 -246.620431) (xy 373.307833 -246.610587) (xy 373.357008 -246.608606) (xy 373.405863 -246.614538)
			(xy 373.453134 -246.62823) (xy 373.497596 -246.649328) (xy 373.538099 -246.677284) (xy 373.573592 -246.711376)
			(xy 373.603157 -246.75072) (xy 373.626028 -246.794297) (xy 373.641612 -246.840978) (xy 373.649507 -246.889555)
			(xy 373.650002 -246.914162) (xy 373.978944 -246.914162) (xy 373.982904 -246.865108) (xy 373.994681 -246.817324)
			(xy 374.013972 -246.772048) (xy 374.040275 -246.730452) (xy 374.07291 -246.693615) (xy 374.111031 -246.66249)
			(xy 374.153652 -246.637883) (xy 374.199668 -246.620431) (xy 374.247887 -246.610587) (xy 374.297062 -246.608606)
			(xy 374.345917 -246.614538) (xy 374.393188 -246.62823) (xy 374.43765 -246.649328) (xy 374.478153 -246.677284)
			(xy 374.513646 -246.711376) (xy 374.543211 -246.75072) (xy 374.566082 -246.794297) (xy 374.581666 -246.840978)
			(xy 374.589561 -246.889555) (xy 374.590056 -246.914162) (xy 374.589561 -246.938769) (xy 374.581666 -246.987346)
			(xy 374.566082 -247.034027) (xy 374.543211 -247.077604) (xy 374.513646 -247.116948) (xy 374.478153 -247.15104)
			(xy 374.43765 -247.178996) (xy 374.393188 -247.200094) (xy 374.345917 -247.213786) (xy 374.297062 -247.219718)
			(xy 374.247887 -247.217737) (xy 374.199668 -247.207893) (xy 374.153652 -247.190441) (xy 374.111031 -247.165834)
			(xy 374.07291 -247.134709) (xy 374.040275 -247.097872) (xy 374.013972 -247.056276) (xy 373.994681 -247.011)
			(xy 373.982904 -246.963216) (xy 373.978944 -246.914162) (xy 373.650002 -246.914162) (xy 373.649507 -246.938769)
			(xy 373.641612 -246.987346) (xy 373.626028 -247.034027) (xy 373.603157 -247.077604) (xy 373.573592 -247.116948)
			(xy 373.538099 -247.15104) (xy 373.497596 -247.178996) (xy 373.453134 -247.200094) (xy 373.405863 -247.213786)
			(xy 373.357008 -247.219718) (xy 373.307833 -247.217737) (xy 373.259614 -247.207893) (xy 373.213598 -247.190441)
			(xy 373.170977 -247.165834) (xy 373.132856 -247.134709) (xy 373.100221 -247.097872) (xy 373.073918 -247.056276)
			(xy 373.054627 -247.011) (xy 373.04285 -246.963216) (xy 373.03889 -246.914162) (xy 372.710202 -246.914162)
			(xy 372.709707 -246.938769) (xy 372.701812 -246.987346) (xy 372.686228 -247.034027) (xy 372.663357 -247.077604)
			(xy 372.633792 -247.116948) (xy 372.598299 -247.15104) (xy 372.557796 -247.178996) (xy 372.513334 -247.200094)
			(xy 372.466063 -247.213786) (xy 372.417208 -247.219718) (xy 372.368033 -247.217737) (xy 372.319814 -247.207893)
			(xy 372.273798 -247.190441) (xy 372.231177 -247.165834) (xy 372.193056 -247.134709) (xy 372.160421 -247.097872)
			(xy 372.134118 -247.056276) (xy 372.114827 -247.011) (xy 372.10305 -246.963216) (xy 372.09909 -246.914162)
			(xy 371.770148 -246.914162) (xy 371.769653 -246.938769) (xy 371.761758 -246.987346) (xy 371.746174 -247.034027)
			(xy 371.723303 -247.077604) (xy 371.693738 -247.116948) (xy 371.658245 -247.15104) (xy 371.617742 -247.178996)
			(xy 371.57328 -247.200094) (xy 371.526009 -247.213786) (xy 371.477154 -247.219718) (xy 371.427979 -247.217737)
			(xy 371.37976 -247.207893) (xy 371.333744 -247.190441) (xy 371.291123 -247.165834) (xy 371.253002 -247.134709)
			(xy 371.220367 -247.097872) (xy 371.194064 -247.056276) (xy 371.174773 -247.011) (xy 371.162996 -246.963216)
			(xy 371.159036 -246.914162) (xy 370.830094 -246.914162) (xy 370.829599 -246.938769) (xy 370.821704 -246.987346)
			(xy 370.80612 -247.034027) (xy 370.783249 -247.077604) (xy 370.753684 -247.116948) (xy 370.718191 -247.15104)
			(xy 370.677688 -247.178996) (xy 370.633226 -247.200094) (xy 370.585955 -247.213786) (xy 370.5371 -247.219718)
			(xy 370.487925 -247.217737) (xy 370.439706 -247.207893) (xy 370.39369 -247.190441) (xy 370.351069 -247.165834)
			(xy 370.312948 -247.134709) (xy 370.280313 -247.097872) (xy 370.25401 -247.056276) (xy 370.234719 -247.011)
			(xy 370.222942 -246.963216) (xy 370.218982 -246.914162) (xy 369.89004 -246.914162) (xy 369.889545 -246.938769)
			(xy 369.88165 -246.987346) (xy 369.866066 -247.034027) (xy 369.843195 -247.077604) (xy 369.81363 -247.116948)
			(xy 369.778137 -247.15104) (xy 369.737634 -247.178996) (xy 369.693172 -247.200094) (xy 369.645901 -247.213786)
			(xy 369.597046 -247.219718) (xy 369.547871 -247.217737) (xy 369.499652 -247.207893) (xy 369.453636 -247.190441)
			(xy 369.411015 -247.165834) (xy 369.372894 -247.134709) (xy 369.340259 -247.097872) (xy 369.313956 -247.056276)
			(xy 369.294665 -247.011) (xy 369.282888 -246.963216) (xy 369.278928 -246.914162) (xy 368.949986 -246.914162)
			(xy 368.949491 -246.938769) (xy 368.941596 -246.987346) (xy 368.926012 -247.034027) (xy 368.903141 -247.077604)
			(xy 368.873576 -247.116948) (xy 368.838083 -247.15104) (xy 368.79758 -247.178996) (xy 368.753118 -247.200094)
			(xy 368.705847 -247.213786) (xy 368.656992 -247.219718) (xy 368.607817 -247.217737) (xy 368.559598 -247.207893)
			(xy 368.513582 -247.190441) (xy 368.470961 -247.165834) (xy 368.43284 -247.134709) (xy 368.400205 -247.097872)
			(xy 368.373902 -247.056276) (xy 368.354611 -247.011) (xy 368.342834 -246.963216) (xy 368.338874 -246.914162)
			(xy 368.010186 -246.914162) (xy 368.009691 -246.938769) (xy 368.001796 -246.987346) (xy 367.986212 -247.034027)
			(xy 367.963341 -247.077604) (xy 367.933776 -247.116948) (xy 367.898283 -247.15104) (xy 367.85778 -247.178996)
			(xy 367.813318 -247.200094) (xy 367.766047 -247.213786) (xy 367.717192 -247.219718) (xy 367.668017 -247.217737)
			(xy 367.619798 -247.207893) (xy 367.573782 -247.190441) (xy 367.531161 -247.165834) (xy 367.49304 -247.134709)
			(xy 367.460405 -247.097872) (xy 367.434102 -247.056276) (xy 367.414811 -247.011) (xy 367.403034 -246.963216)
			(xy 367.399074 -246.914162) (xy 367.070132 -246.914162) (xy 367.069637 -246.938769) (xy 367.061742 -246.987346)
			(xy 367.046158 -247.034027) (xy 367.023287 -247.077604) (xy 366.993722 -247.116948) (xy 366.958229 -247.15104)
			(xy 366.917726 -247.178996) (xy 366.873264 -247.200094) (xy 366.825993 -247.213786) (xy 366.777138 -247.219718)
			(xy 366.727963 -247.217737) (xy 366.679744 -247.207893) (xy 366.633728 -247.190441) (xy 366.591107 -247.165834)
			(xy 366.552986 -247.134709) (xy 366.520351 -247.097872) (xy 366.494048 -247.056276) (xy 366.474757 -247.011)
			(xy 366.46298 -246.963216) (xy 366.45902 -246.914162) (xy 366.130078 -246.914162) (xy 366.129583 -246.938769)
			(xy 366.121688 -246.987346) (xy 366.106104 -247.034027) (xy 366.083233 -247.077604) (xy 366.053668 -247.116948)
			(xy 366.018175 -247.15104) (xy 365.977672 -247.178996) (xy 365.93321 -247.200094) (xy 365.885939 -247.213786)
			(xy 365.837084 -247.219718) (xy 365.787909 -247.217737) (xy 365.73969 -247.207893) (xy 365.693674 -247.190441)
			(xy 365.651053 -247.165834) (xy 365.612932 -247.134709) (xy 365.580297 -247.097872) (xy 365.553994 -247.056276)
			(xy 365.534703 -247.011) (xy 365.522926 -246.963216) (xy 365.518966 -246.914162) (xy 365.190024 -246.914162)
			(xy 365.189529 -246.938769) (xy 365.181634 -246.987346) (xy 365.16605 -247.034027) (xy 365.143179 -247.077604)
			(xy 365.113614 -247.116948) (xy 365.078121 -247.15104) (xy 365.037618 -247.178996) (xy 364.993156 -247.200094)
			(xy 364.945885 -247.213786) (xy 364.89703 -247.219718) (xy 364.847855 -247.217737) (xy 364.799636 -247.207893)
			(xy 364.75362 -247.190441) (xy 364.710999 -247.165834) (xy 364.672878 -247.134709) (xy 364.640243 -247.097872)
			(xy 364.61394 -247.056276) (xy 364.594649 -247.011) (xy 364.582872 -246.963216) (xy 364.578912 -246.914162)
			(xy 364.250224 -246.914162) (xy 364.249729 -246.938769) (xy 364.241834 -246.987346) (xy 364.22625 -247.034027)
			(xy 364.203379 -247.077604) (xy 364.173814 -247.116948) (xy 364.138321 -247.15104) (xy 364.097818 -247.178996)
			(xy 364.053356 -247.200094) (xy 364.006085 -247.213786) (xy 363.95723 -247.219718) (xy 363.908055 -247.217737)
			(xy 363.859836 -247.207893) (xy 363.81382 -247.190441) (xy 363.771199 -247.165834) (xy 363.733078 -247.134709)
			(xy 363.700443 -247.097872) (xy 363.67414 -247.056276) (xy 363.654849 -247.011) (xy 363.643072 -246.963216)
			(xy 363.639112 -246.914162) (xy 363.310974 -246.914162) (xy 363.310977 -246.9142) (xy 363.306801 -246.964582)
			(xy 363.29439 -247.01359) (xy 363.274081 -247.059887) (xy 363.246428 -247.102209) (xy 363.212185 -247.139401)
			(xy 363.172288 -247.17045) (xy 363.127824 -247.194508) (xy 363.080006 -247.210919) (xy 363.03014 -247.219234)
			(xy 363.004862 -247.219724) (xy 362.064808 -247.219724) (xy 362.039526 -247.219307) (xy 361.989651 -247.210986)
			(xy 361.941825 -247.194569) (xy 361.897355 -247.170503) (xy 361.857452 -247.139447) (xy 361.823205 -247.102245)
			(xy 361.795548 -247.059915) (xy 361.775236 -247.013609) (xy 361.762823 -246.964592) (xy 361.758647 -246.9142)
			(xy 361.430061 -246.9142) (xy 361.429567 -246.938769) (xy 361.421672 -246.987346) (xy 361.406088 -247.034027)
			(xy 361.383217 -247.077604) (xy 361.353652 -247.116948) (xy 361.318159 -247.15104) (xy 361.277656 -247.178996)
			(xy 361.233194 -247.200094) (xy 361.185923 -247.213786) (xy 361.137068 -247.219718) (xy 361.087893 -247.217737)
			(xy 361.039674 -247.207893) (xy 360.993658 -247.190441) (xy 360.951037 -247.165834) (xy 360.912916 -247.134709)
			(xy 360.880281 -247.097872) (xy 360.853978 -247.056276) (xy 360.834687 -247.011) (xy 360.82291 -246.963216)
			(xy 360.81895 -246.914162) (xy 358.616504 -246.914162) (xy 358.616009 -246.938769) (xy 358.608114 -246.987346)
			(xy 358.59253 -247.034027) (xy 358.569659 -247.077604) (xy 358.540094 -247.116948) (xy 358.504601 -247.15104)
			(xy 358.464098 -247.178996) (xy 358.419636 -247.200094) (xy 358.372365 -247.213786) (xy 358.32351 -247.219718)
			(xy 358.274335 -247.217737) (xy 358.226116 -247.207893) (xy 358.1801 -247.190441) (xy 358.137479 -247.165834)
			(xy 358.099358 -247.134709) (xy 358.066723 -247.097872) (xy 358.04042 -247.056276) (xy 358.021129 -247.011)
			(xy 358.009352 -246.963216) (xy 358.005392 -246.914162) (xy 357.67645 -246.914162) (xy 357.675955 -246.938769)
			(xy 357.66806 -246.987346) (xy 357.652476 -247.034027) (xy 357.629605 -247.077604) (xy 357.60004 -247.116948)
			(xy 357.564547 -247.15104) (xy 357.524044 -247.178996) (xy 357.479582 -247.200094) (xy 357.432311 -247.213786)
			(xy 357.383456 -247.219718) (xy 357.334281 -247.217737) (xy 357.286062 -247.207893) (xy 357.240046 -247.190441)
			(xy 357.197425 -247.165834) (xy 357.159304 -247.134709) (xy 357.126669 -247.097872) (xy 357.100366 -247.056276)
			(xy 357.081075 -247.011) (xy 357.069298 -246.963216) (xy 357.065338 -246.914162) (xy 356.736396 -246.914162)
			(xy 356.735901 -246.938769) (xy 356.728006 -246.987346) (xy 356.712422 -247.034027) (xy 356.689551 -247.077604)
			(xy 356.659986 -247.116948) (xy 356.624493 -247.15104) (xy 356.58399 -247.178996) (xy 356.539528 -247.200094)
			(xy 356.492257 -247.213786) (xy 356.443402 -247.219718) (xy 356.394227 -247.217737) (xy 356.346008 -247.207893)
			(xy 356.299992 -247.190441) (xy 356.257371 -247.165834) (xy 356.21925 -247.134709) (xy 356.186615 -247.097872)
			(xy 356.160312 -247.056276) (xy 356.141021 -247.011) (xy 356.129244 -246.963216) (xy 356.125284 -246.914162)
			(xy 355.796342 -246.914162) (xy 355.795847 -246.938769) (xy 355.787952 -246.987346) (xy 355.772368 -247.034027)
			(xy 355.749497 -247.077604) (xy 355.719932 -247.116948) (xy 355.684439 -247.15104) (xy 355.643936 -247.178996)
			(xy 355.599474 -247.200094) (xy 355.552203 -247.213786) (xy 355.503348 -247.219718) (xy 355.454173 -247.217737)
			(xy 355.405954 -247.207893) (xy 355.359938 -247.190441) (xy 355.317317 -247.165834) (xy 355.279196 -247.134709)
			(xy 355.246561 -247.097872) (xy 355.220258 -247.056276) (xy 355.200967 -247.011) (xy 355.18919 -246.963216)
			(xy 355.18523 -246.914162) (xy 354.856542 -246.914162) (xy 354.856047 -246.938769) (xy 354.848152 -246.987346)
			(xy 354.832568 -247.034027) (xy 354.809697 -247.077604) (xy 354.780132 -247.116948) (xy 354.744639 -247.15104)
			(xy 354.704136 -247.178996) (xy 354.659674 -247.200094) (xy 354.612403 -247.213786) (xy 354.563548 -247.219718)
			(xy 354.514373 -247.217737) (xy 354.466154 -247.207893) (xy 354.420138 -247.190441) (xy 354.377517 -247.165834)
			(xy 354.339396 -247.134709) (xy 354.306761 -247.097872) (xy 354.280458 -247.056276) (xy 354.261167 -247.011)
			(xy 354.24939 -246.963216) (xy 354.24543 -246.914162) (xy 353.916488 -246.914162) (xy 353.915993 -246.938769)
			(xy 353.908098 -246.987346) (xy 353.892514 -247.034027) (xy 353.869643 -247.077604) (xy 353.840078 -247.116948)
			(xy 353.804585 -247.15104) (xy 353.764082 -247.178996) (xy 353.71962 -247.200094) (xy 353.672349 -247.213786)
			(xy 353.623494 -247.219718) (xy 353.574319 -247.217737) (xy 353.5261 -247.207893) (xy 353.480084 -247.190441)
			(xy 353.437463 -247.165834) (xy 353.399342 -247.134709) (xy 353.366707 -247.097872) (xy 353.340404 -247.056276)
			(xy 353.321113 -247.011) (xy 353.309336 -246.963216) (xy 353.305376 -246.914162) (xy 352.976434 -246.914162)
			(xy 352.975939 -246.938769) (xy 352.968044 -246.987346) (xy 352.95246 -247.034027) (xy 352.929589 -247.077604)
			(xy 352.900024 -247.116948) (xy 352.864531 -247.15104) (xy 352.824028 -247.178996) (xy 352.779566 -247.200094)
			(xy 352.732295 -247.213786) (xy 352.68344 -247.219718) (xy 352.634265 -247.217737) (xy 352.586046 -247.207893)
			(xy 352.54003 -247.190441) (xy 352.497409 -247.165834) (xy 352.459288 -247.134709) (xy 352.426653 -247.097872)
			(xy 352.40035 -247.056276) (xy 352.381059 -247.011) (xy 352.369282 -246.963216) (xy 352.365322 -246.914162)
			(xy 352.03638 -246.914162) (xy 352.035885 -246.938769) (xy 352.02799 -246.987346) (xy 352.012406 -247.034027)
			(xy 351.989535 -247.077604) (xy 351.95997 -247.116948) (xy 351.924477 -247.15104) (xy 351.883974 -247.178996)
			(xy 351.839512 -247.200094) (xy 351.792241 -247.213786) (xy 351.743386 -247.219718) (xy 351.694211 -247.217737)
			(xy 351.645992 -247.207893) (xy 351.599976 -247.190441) (xy 351.557355 -247.165834) (xy 351.519234 -247.134709)
			(xy 351.486599 -247.097872) (xy 351.460296 -247.056276) (xy 351.441005 -247.011) (xy 351.429228 -246.963216)
			(xy 351.425268 -246.914162) (xy 351.096326 -246.914162) (xy 351.095831 -246.938769) (xy 351.087936 -246.987346)
			(xy 351.072352 -247.034027) (xy 351.049481 -247.077604) (xy 351.019916 -247.116948) (xy 350.984423 -247.15104)
			(xy 350.94392 -247.178996) (xy 350.899458 -247.200094) (xy 350.852187 -247.213786) (xy 350.803332 -247.219718)
			(xy 350.754157 -247.217737) (xy 350.705938 -247.207893) (xy 350.659922 -247.190441) (xy 350.617301 -247.165834)
			(xy 350.57918 -247.134709) (xy 350.546545 -247.097872) (xy 350.520242 -247.056276) (xy 350.500951 -247.011)
			(xy 350.489174 -246.963216) (xy 350.485214 -246.914162) (xy 350.156526 -246.914162) (xy 350.156031 -246.938769)
			(xy 350.148136 -246.987346) (xy 350.132552 -247.034027) (xy 350.109681 -247.077604) (xy 350.080116 -247.116948)
			(xy 350.044623 -247.15104) (xy 350.00412 -247.178996) (xy 349.959658 -247.200094) (xy 349.912387 -247.213786)
			(xy 349.863532 -247.219718) (xy 349.814357 -247.217737) (xy 349.766138 -247.207893) (xy 349.720122 -247.190441)
			(xy 349.677501 -247.165834) (xy 349.63938 -247.134709) (xy 349.606745 -247.097872) (xy 349.580442 -247.056276)
			(xy 349.561151 -247.011) (xy 349.549374 -246.963216) (xy 349.545414 -246.914162) (xy 349.216472 -246.914162)
			(xy 349.215977 -246.938769) (xy 349.208082 -246.987346) (xy 349.192498 -247.034027) (xy 349.169627 -247.077604)
			(xy 349.140062 -247.116948) (xy 349.104569 -247.15104) (xy 349.064066 -247.178996) (xy 349.019604 -247.200094)
			(xy 348.972333 -247.213786) (xy 348.923478 -247.219718) (xy 348.874303 -247.217737) (xy 348.826084 -247.207893)
			(xy 348.780068 -247.190441) (xy 348.737447 -247.165834) (xy 348.699326 -247.134709) (xy 348.666691 -247.097872)
			(xy 348.640388 -247.056276) (xy 348.621097 -247.011) (xy 348.60932 -246.963216) (xy 348.60536 -246.914162)
			(xy 348.276418 -246.914162) (xy 348.275923 -246.938769) (xy 348.268028 -246.987346) (xy 348.252444 -247.034027)
			(xy 348.229573 -247.077604) (xy 348.200008 -247.116948) (xy 348.164515 -247.15104) (xy 348.124012 -247.178996)
			(xy 348.07955 -247.200094) (xy 348.032279 -247.213786) (xy 347.983424 -247.219718) (xy 347.934249 -247.217737)
			(xy 347.88603 -247.207893) (xy 347.840014 -247.190441) (xy 347.797393 -247.165834) (xy 347.759272 -247.134709)
			(xy 347.726637 -247.097872) (xy 347.700334 -247.056276) (xy 347.681043 -247.011) (xy 347.669266 -246.963216)
			(xy 347.665306 -246.914162) (xy 347.336364 -246.914162) (xy 347.335869 -246.938769) (xy 347.327974 -246.987346)
			(xy 347.31239 -247.034027) (xy 347.289519 -247.077604) (xy 347.259954 -247.116948) (xy 347.224461 -247.15104)
			(xy 347.183958 -247.178996) (xy 347.139496 -247.200094) (xy 347.092225 -247.213786) (xy 347.04337 -247.219718)
			(xy 346.994195 -247.217737) (xy 346.945976 -247.207893) (xy 346.89996 -247.190441) (xy 346.857339 -247.165834)
			(xy 346.819218 -247.134709) (xy 346.786583 -247.097872) (xy 346.76028 -247.056276) (xy 346.740989 -247.011)
			(xy 346.729212 -246.963216) (xy 346.725252 -246.914162) (xy 346.39631 -246.914162) (xy 346.395815 -246.938769)
			(xy 346.38792 -246.987346) (xy 346.372336 -247.034027) (xy 346.349465 -247.077604) (xy 346.3199 -247.116948)
			(xy 346.284407 -247.15104) (xy 346.243904 -247.178996) (xy 346.199442 -247.200094) (xy 346.152171 -247.213786)
			(xy 346.103316 -247.219718) (xy 346.054141 -247.217737) (xy 346.005922 -247.207893) (xy 345.959906 -247.190441)
			(xy 345.917285 -247.165834) (xy 345.879164 -247.134709) (xy 345.846529 -247.097872) (xy 345.820226 -247.056276)
			(xy 345.800935 -247.011) (xy 345.789158 -246.963216) (xy 345.785198 -246.914162) (xy 345.45651 -246.914162)
			(xy 345.456015 -246.938769) (xy 345.44812 -246.987346) (xy 345.432536 -247.034027) (xy 345.409665 -247.077604)
			(xy 345.3801 -247.116948) (xy 345.344607 -247.15104) (xy 345.304104 -247.178996) (xy 345.259642 -247.200094)
			(xy 345.212371 -247.213786) (xy 345.163516 -247.219718) (xy 345.114341 -247.217737) (xy 345.066122 -247.207893)
			(xy 345.020106 -247.190441) (xy 344.977485 -247.165834) (xy 344.939364 -247.134709) (xy 344.906729 -247.097872)
			(xy 344.880426 -247.056276) (xy 344.861135 -247.011) (xy 344.849358 -246.963216) (xy 344.845398 -246.914162)
			(xy 344.626438 -246.914162) (xy 344.626438 -247.347486) (xy 344.626896 -247.357637) (xy 344.634771 -247.376352)
			(xy 344.641678 -247.383808) (xy 344.669618 -247.41124) (xy 344.686636 -247.41886) (xy 344.696034 -247.419114)
			(xy 344.720456 -247.420802) (xy 344.768337 -247.430977) (xy 344.813982 -247.448658) (xy 344.856223 -247.473393)
			(xy 344.893979 -247.504547) (xy 344.926283 -247.541324) (xy 344.952309 -247.582783) (xy 344.97139 -247.627861)
			(xy 344.983037 -247.675405) (xy 344.986951 -247.724168) (xy 345.315298 -247.724168) (xy 345.319258 -247.675114)
			(xy 345.331035 -247.62733) (xy 345.350326 -247.582054) (xy 345.376629 -247.540458) (xy 345.409264 -247.503621)
			(xy 345.447385 -247.472496) (xy 345.490006 -247.447889) (xy 345.536022 -247.430437) (xy 345.584241 -247.420593)
			(xy 345.633416 -247.418612) (xy 345.682271 -247.424544) (xy 345.729542 -247.438236) (xy 345.774004 -247.459334)
			(xy 345.814507 -247.48729) (xy 345.85 -247.521382) (xy 345.879565 -247.560726) (xy 345.902436 -247.604303)
			(xy 345.91802 -247.650984) (xy 345.925915 -247.699561) (xy 345.92641 -247.724168) (xy 346.255352 -247.724168)
			(xy 346.259312 -247.675114) (xy 346.271089 -247.62733) (xy 346.29038 -247.582054) (xy 346.316683 -247.540458)
			(xy 346.349318 -247.503621) (xy 346.387439 -247.472496) (xy 346.43006 -247.447889) (xy 346.476076 -247.430437)
			(xy 346.524295 -247.420593) (xy 346.57347 -247.418612) (xy 346.622325 -247.424544) (xy 346.669596 -247.438236)
			(xy 346.714058 -247.459334) (xy 346.754561 -247.48729) (xy 346.790054 -247.521382) (xy 346.819619 -247.560726)
			(xy 346.84249 -247.604303) (xy 346.858074 -247.650984) (xy 346.865969 -247.699561) (xy 346.866464 -247.724168)
			(xy 347.195406 -247.724168) (xy 347.199366 -247.675114) (xy 347.211143 -247.62733) (xy 347.230434 -247.582054)
			(xy 347.256737 -247.540458) (xy 347.289372 -247.503621) (xy 347.327493 -247.472496) (xy 347.370114 -247.447889)
			(xy 347.41613 -247.430437) (xy 347.464349 -247.420593) (xy 347.513524 -247.418612) (xy 347.562379 -247.424544)
			(xy 347.60965 -247.438236) (xy 347.654112 -247.459334) (xy 347.694615 -247.48729) (xy 347.730108 -247.521382)
			(xy 347.759673 -247.560726) (xy 347.782544 -247.604303) (xy 347.798128 -247.650984) (xy 347.806023 -247.699561)
			(xy 347.806518 -247.724168) (xy 348.135206 -247.724168) (xy 348.139166 -247.675114) (xy 348.150943 -247.62733)
			(xy 348.170234 -247.582054) (xy 348.196537 -247.540458) (xy 348.229172 -247.503621) (xy 348.267293 -247.472496)
			(xy 348.309914 -247.447889) (xy 348.35593 -247.430437) (xy 348.404149 -247.420593) (xy 348.453324 -247.418612)
			(xy 348.502179 -247.424544) (xy 348.54945 -247.438236) (xy 348.593912 -247.459334) (xy 348.634415 -247.48729)
			(xy 348.669908 -247.521382) (xy 348.699473 -247.560726) (xy 348.722344 -247.604303) (xy 348.737928 -247.650984)
			(xy 348.745823 -247.699561) (xy 348.746318 -247.724168) (xy 349.07526 -247.724168) (xy 349.07922 -247.675114)
			(xy 349.090997 -247.62733) (xy 349.110288 -247.582054) (xy 349.136591 -247.540458) (xy 349.169226 -247.503621)
			(xy 349.207347 -247.472496) (xy 349.249968 -247.447889) (xy 349.295984 -247.430437) (xy 349.344203 -247.420593)
			(xy 349.393378 -247.418612) (xy 349.442233 -247.424544) (xy 349.489504 -247.438236) (xy 349.533966 -247.459334)
			(xy 349.574469 -247.48729) (xy 349.609962 -247.521382) (xy 349.639527 -247.560726) (xy 349.662398 -247.604303)
			(xy 349.677982 -247.650984) (xy 349.685877 -247.699561) (xy 349.686372 -247.724168) (xy 350.015314 -247.724168)
			(xy 350.019274 -247.675114) (xy 350.031051 -247.62733) (xy 350.050342 -247.582054) (xy 350.076645 -247.540458)
			(xy 350.10928 -247.503621) (xy 350.147401 -247.472496) (xy 350.190022 -247.447889) (xy 350.236038 -247.430437)
			(xy 350.284257 -247.420593) (xy 350.333432 -247.418612) (xy 350.382287 -247.424544) (xy 350.429558 -247.438236)
			(xy 350.47402 -247.459334) (xy 350.514523 -247.48729) (xy 350.550016 -247.521382) (xy 350.579581 -247.560726)
			(xy 350.602452 -247.604303) (xy 350.618036 -247.650984) (xy 350.625931 -247.699561) (xy 350.626426 -247.724168)
			(xy 350.955368 -247.724168) (xy 350.959328 -247.675114) (xy 350.971105 -247.62733) (xy 350.990396 -247.582054)
			(xy 351.016699 -247.540458) (xy 351.049334 -247.503621) (xy 351.087455 -247.472496) (xy 351.130076 -247.447889)
			(xy 351.176092 -247.430437) (xy 351.224311 -247.420593) (xy 351.273486 -247.418612) (xy 351.322341 -247.424544)
			(xy 351.369612 -247.438236) (xy 351.414074 -247.459334) (xy 351.454577 -247.48729) (xy 351.49007 -247.521382)
			(xy 351.519635 -247.560726) (xy 351.542506 -247.604303) (xy 351.55809 -247.650984) (xy 351.565985 -247.699561)
			(xy 351.56648 -247.724168) (xy 351.895422 -247.724168) (xy 351.899382 -247.675114) (xy 351.911159 -247.62733)
			(xy 351.93045 -247.582054) (xy 351.956753 -247.540458) (xy 351.989388 -247.503621) (xy 352.027509 -247.472496)
			(xy 352.07013 -247.447889) (xy 352.116146 -247.430437) (xy 352.164365 -247.420593) (xy 352.21354 -247.418612)
			(xy 352.262395 -247.424544) (xy 352.309666 -247.438236) (xy 352.354128 -247.459334) (xy 352.394631 -247.48729)
			(xy 352.430124 -247.521382) (xy 352.459689 -247.560726) (xy 352.48256 -247.604303) (xy 352.498144 -247.650984)
			(xy 352.506039 -247.699561) (xy 352.506534 -247.724168) (xy 352.835222 -247.724168) (xy 352.839182 -247.675114)
			(xy 352.850959 -247.62733) (xy 352.87025 -247.582054) (xy 352.896553 -247.540458) (xy 352.929188 -247.503621)
			(xy 352.967309 -247.472496) (xy 353.00993 -247.447889) (xy 353.055946 -247.430437) (xy 353.104165 -247.420593)
			(xy 353.15334 -247.418612) (xy 353.202195 -247.424544) (xy 353.249466 -247.438236) (xy 353.293928 -247.459334)
			(xy 353.334431 -247.48729) (xy 353.369924 -247.521382) (xy 353.399489 -247.560726) (xy 353.42236 -247.604303)
			(xy 353.437944 -247.650984) (xy 353.445839 -247.699561) (xy 353.446334 -247.724168) (xy 353.775276 -247.724168)
			(xy 353.779236 -247.675114) (xy 353.791013 -247.62733) (xy 353.810304 -247.582054) (xy 353.836607 -247.540458)
			(xy 353.869242 -247.503621) (xy 353.907363 -247.472496) (xy 353.949984 -247.447889) (xy 353.996 -247.430437)
			(xy 354.044219 -247.420593) (xy 354.093394 -247.418612) (xy 354.142249 -247.424544) (xy 354.18952 -247.438236)
			(xy 354.233982 -247.459334) (xy 354.274485 -247.48729) (xy 354.309978 -247.521382) (xy 354.339543 -247.560726)
			(xy 354.362414 -247.604303) (xy 354.377998 -247.650984) (xy 354.385893 -247.699561) (xy 354.386388 -247.724168)
			(xy 354.71533 -247.724168) (xy 354.71929 -247.675114) (xy 354.731067 -247.62733) (xy 354.750358 -247.582054)
			(xy 354.776661 -247.540458) (xy 354.809296 -247.503621) (xy 354.847417 -247.472496) (xy 354.890038 -247.447889)
			(xy 354.936054 -247.430437) (xy 354.984273 -247.420593) (xy 355.033448 -247.418612) (xy 355.082303 -247.424544)
			(xy 355.129574 -247.438236) (xy 355.174036 -247.459334) (xy 355.214539 -247.48729) (xy 355.250032 -247.521382)
			(xy 355.279597 -247.560726) (xy 355.302468 -247.604303) (xy 355.318052 -247.650984) (xy 355.325947 -247.699561)
			(xy 355.326442 -247.724168) (xy 355.655384 -247.724168) (xy 355.659344 -247.675114) (xy 355.671121 -247.62733)
			(xy 355.690412 -247.582054) (xy 355.716715 -247.540458) (xy 355.74935 -247.503621) (xy 355.787471 -247.472496)
			(xy 355.830092 -247.447889) (xy 355.876108 -247.430437) (xy 355.924327 -247.420593) (xy 355.973502 -247.418612)
			(xy 356.022357 -247.424544) (xy 356.069628 -247.438236) (xy 356.11409 -247.459334) (xy 356.154593 -247.48729)
			(xy 356.190086 -247.521382) (xy 356.219651 -247.560726) (xy 356.242522 -247.604303) (xy 356.258106 -247.650984)
			(xy 356.266001 -247.699561) (xy 356.266496 -247.724168) (xy 356.595438 -247.724168) (xy 356.599398 -247.675114)
			(xy 356.611175 -247.62733) (xy 356.630466 -247.582054) (xy 356.656769 -247.540458) (xy 356.689404 -247.503621)
			(xy 356.727525 -247.472496) (xy 356.770146 -247.447889) (xy 356.816162 -247.430437) (xy 356.864381 -247.420593)
			(xy 356.913556 -247.418612) (xy 356.962411 -247.424544) (xy 357.009682 -247.438236) (xy 357.054144 -247.459334)
			(xy 357.094647 -247.48729) (xy 357.13014 -247.521382) (xy 357.159705 -247.560726) (xy 357.182576 -247.604303)
			(xy 357.19816 -247.650984) (xy 357.206055 -247.699561) (xy 357.20655 -247.724168) (xy 357.535238 -247.724168)
			(xy 357.539198 -247.675114) (xy 357.550975 -247.62733) (xy 357.570266 -247.582054) (xy 357.596569 -247.540458)
			(xy 357.629204 -247.503621) (xy 357.667325 -247.472496) (xy 357.709946 -247.447889) (xy 357.755962 -247.430437)
			(xy 357.804181 -247.420593) (xy 357.853356 -247.418612) (xy 357.902211 -247.424544) (xy 357.949482 -247.438236)
			(xy 357.988941 -247.45696) (xy 359.396541 -247.45696) (xy 359.400571 -247.404462) (xy 359.412568 -247.353194)
			(xy 359.432251 -247.304359) (xy 359.459157 -247.2591) (xy 359.492657 -247.218479) (xy 359.531965 -247.183448)
			(xy 359.57616 -247.154828) (xy 359.624205 -247.133289) (xy 359.674976 -247.119337) (xy 359.727281 -247.113299)
			(xy 359.779895 -247.115316) (xy 359.831585 -247.12534) (xy 359.881138 -247.143138) (xy 359.927394 -247.168291)
			(xy 359.969268 -247.20021) (xy 360.00578 -247.238148) (xy 360.036072 -247.281214) (xy 360.059435 -247.328399)
			(xy 360.075321 -247.378598) (xy 360.083358 -247.430634) (xy 360.083862 -247.45696) (xy 360.083358 -247.483286)
			(xy 360.075321 -247.535322) (xy 360.059435 -247.585521) (xy 360.036072 -247.632706) (xy 360.00578 -247.675772)
			(xy 359.969268 -247.71371) (xy 359.955548 -247.724168) (xy 361.289104 -247.724168) (xy 361.293064 -247.675114)
			(xy 361.304841 -247.62733) (xy 361.324132 -247.582054) (xy 361.350435 -247.540458) (xy 361.38307 -247.503621)
			(xy 361.421191 -247.472496) (xy 361.463812 -247.447889) (xy 361.509828 -247.430437) (xy 361.558047 -247.420593)
			(xy 361.607222 -247.418612) (xy 361.656077 -247.424544) (xy 361.703348 -247.438236) (xy 361.74781 -247.459334)
			(xy 361.788313 -247.48729) (xy 361.823806 -247.521382) (xy 361.853371 -247.560726) (xy 361.876242 -247.604303)
			(xy 361.891826 -247.650984) (xy 361.899721 -247.699561) (xy 361.900216 -247.724168) (xy 362.228904 -247.724168)
			(xy 362.232864 -247.675114) (xy 362.244641 -247.62733) (xy 362.263932 -247.582054) (xy 362.290235 -247.540458)
			(xy 362.32287 -247.503621) (xy 362.360991 -247.472496) (xy 362.403612 -247.447889) (xy 362.449628 -247.430437)
			(xy 362.497847 -247.420593) (xy 362.547022 -247.418612) (xy 362.595877 -247.424544) (xy 362.643148 -247.438236)
			(xy 362.68761 -247.459334) (xy 362.728113 -247.48729) (xy 362.763606 -247.521382) (xy 362.793171 -247.560726)
			(xy 362.816042 -247.604303) (xy 362.831626 -247.650984) (xy 362.839521 -247.699561) (xy 362.840016 -247.724168)
			(xy 363.168958 -247.724168) (xy 363.172918 -247.675114) (xy 363.184695 -247.62733) (xy 363.203986 -247.582054)
			(xy 363.230289 -247.540458) (xy 363.262924 -247.503621) (xy 363.301045 -247.472496) (xy 363.343666 -247.447889)
			(xy 363.389682 -247.430437) (xy 363.437901 -247.420593) (xy 363.487076 -247.418612) (xy 363.535931 -247.424544)
			(xy 363.583202 -247.438236) (xy 363.627664 -247.459334) (xy 363.668167 -247.48729) (xy 363.70366 -247.521382)
			(xy 363.733225 -247.560726) (xy 363.756096 -247.604303) (xy 363.77168 -247.650984) (xy 363.779575 -247.699561)
			(xy 363.78007 -247.724168) (xy 363.780069 -247.7242) (xy 364.108908 -247.7242) (xy 364.11308 -247.67385)
			(xy 364.125483 -247.624874) (xy 364.145778 -247.578607) (xy 364.173412 -247.536312) (xy 364.207631 -247.499142)
			(xy 364.247501 -247.468112) (xy 364.291935 -247.444068) (xy 364.339721 -247.427665) (xy 364.389555 -247.419352)
			(xy 364.414816 -247.41886) (xy 365.35487 -247.41886) (xy 365.380127 -247.419414) (xy 365.429952 -247.427724)
			(xy 365.477729 -247.444122) (xy 365.522156 -247.468161) (xy 365.56202 -247.499184) (xy 365.596233 -247.536347)
			(xy 365.623863 -247.578634) (xy 365.644155 -247.624892) (xy 365.656556 -247.673859) (xy 365.660725 -247.724168)
			(xy 365.98912 -247.724168) (xy 365.99308 -247.675114) (xy 366.004857 -247.62733) (xy 366.024148 -247.582054)
			(xy 366.050451 -247.540458) (xy 366.083086 -247.503621) (xy 366.121207 -247.472496) (xy 366.163828 -247.447889)
			(xy 366.209844 -247.430437) (xy 366.258063 -247.420593) (xy 366.307238 -247.418612) (xy 366.356093 -247.424544)
			(xy 366.403364 -247.438236) (xy 366.447826 -247.459334) (xy 366.488329 -247.48729) (xy 366.523822 -247.521382)
			(xy 366.553387 -247.560726) (xy 366.576258 -247.604303) (xy 366.591842 -247.650984) (xy 366.599737 -247.699561)
			(xy 366.600232 -247.724168) (xy 366.600231 -247.7242) (xy 366.928808 -247.7242) (xy 366.93298 -247.673849)
			(xy 366.945384 -247.624872) (xy 366.96568 -247.578605) (xy 366.993314 -247.536309) (xy 367.027534 -247.499139)
			(xy 367.067406 -247.468109) (xy 367.111841 -247.444065) (xy 367.159628 -247.427663) (xy 367.209462 -247.419351)
			(xy 367.234724 -247.41886) (xy 368.174778 -247.41886) (xy 368.200034 -247.419415) (xy 368.249858 -247.427726)
			(xy 368.297635 -247.444124) (xy 368.34206 -247.468163) (xy 368.381923 -247.499187) (xy 368.416136 -247.536349)
			(xy 368.443764 -247.578636) (xy 368.464056 -247.624893) (xy 368.476457 -247.67386) (xy 368.480625 -247.724168)
			(xy 368.809028 -247.724168) (xy 368.812988 -247.675114) (xy 368.824765 -247.62733) (xy 368.844056 -247.582054)
			(xy 368.870359 -247.540458) (xy 368.902994 -247.503621) (xy 368.941115 -247.472496) (xy 368.983736 -247.447889)
			(xy 369.029752 -247.430437) (xy 369.077971 -247.420593) (xy 369.127146 -247.418612) (xy 369.176001 -247.424544)
			(xy 369.223272 -247.438236) (xy 369.267734 -247.459334) (xy 369.308237 -247.48729) (xy 369.34373 -247.521382)
			(xy 369.373295 -247.560726) (xy 369.396166 -247.604303) (xy 369.41175 -247.650984) (xy 369.419645 -247.699561)
			(xy 369.42014 -247.724168) (xy 369.420139 -247.7242) (xy 369.749037 -247.7242) (xy 369.753208 -247.673858)
			(xy 369.765609 -247.624889) (xy 369.785899 -247.578629) (xy 369.813527 -247.53634) (xy 369.847739 -247.499174)
			(xy 369.887601 -247.468147) (xy 369.932027 -247.444103) (xy 369.979804 -247.427699) (xy 370.029629 -247.419383)
			(xy 370.054886 -247.41886) (xy 370.99494 -247.41886) (xy 371.020191 -247.419449) (xy 371.070002 -247.427767)
			(xy 371.117765 -247.444169) (xy 371.162177 -247.468209) (xy 371.202028 -247.499231) (xy 371.236229 -247.536388)
			(xy 371.263848 -247.578667) (xy 371.284133 -247.624915) (xy 371.296529 -247.673871) (xy 371.300696 -247.724168)
			(xy 371.628936 -247.724168) (xy 371.632896 -247.675114) (xy 371.644673 -247.62733) (xy 371.663964 -247.582054)
			(xy 371.690267 -247.540458) (xy 371.722902 -247.503621) (xy 371.761023 -247.472496) (xy 371.803644 -247.447889)
			(xy 371.84966 -247.430437) (xy 371.897879 -247.420593) (xy 371.947054 -247.418612) (xy 371.995909 -247.424544)
			(xy 372.04318 -247.438236) (xy 372.087642 -247.459334) (xy 372.128145 -247.48729) (xy 372.163638 -247.521382)
			(xy 372.193203 -247.560726) (xy 372.216074 -247.604303) (xy 372.231658 -247.650984) (xy 372.239553 -247.699561)
			(xy 372.240048 -247.724168) (xy 372.240047 -247.7242) (xy 372.568937 -247.7242) (xy 372.573108 -247.673857)
			(xy 372.585509 -247.624888) (xy 372.605801 -247.578627) (xy 372.63343 -247.536337) (xy 372.667642 -247.499171)
			(xy 372.707506 -247.468144) (xy 372.751932 -247.444101) (xy 372.79971 -247.427698) (xy 372.849536 -247.419382)
			(xy 372.874794 -247.41886) (xy 373.814848 -247.41886) (xy 373.840098 -247.419449) (xy 373.889908 -247.427768)
			(xy 373.93767 -247.444172) (xy 373.982082 -247.468212) (xy 374.021931 -247.499233) (xy 374.056131 -247.53639)
			(xy 374.083749 -247.578669) (xy 374.104033 -247.624917) (xy 374.116429 -247.673872) (xy 374.120599 -247.7242)
			(xy 374.116429 -247.774528) (xy 374.104033 -247.823483) (xy 374.083749 -247.869731) (xy 374.056131 -247.91201)
			(xy 374.021931 -247.949166) (xy 373.982082 -247.980188) (xy 373.937671 -248.004228) (xy 373.889908 -248.020632)
			(xy 373.840098 -248.028951) (xy 373.814848 -248.029476) (xy 372.874794 -248.029476) (xy 372.849536 -248.029018)
			(xy 372.79971 -248.020702) (xy 372.751932 -248.004299) (xy 372.707506 -247.980256) (xy 372.667642 -247.949229)
			(xy 372.63343 -247.912063) (xy 372.605801 -247.869773) (xy 372.585509 -247.823512) (xy 372.573108 -247.774543)
			(xy 372.568937 -247.7242) (xy 372.240047 -247.7242) (xy 372.239553 -247.748775) (xy 372.231658 -247.797352)
			(xy 372.216074 -247.844033) (xy 372.193203 -247.88761) (xy 372.163638 -247.926954) (xy 372.128145 -247.961046)
			(xy 372.087642 -247.989002) (xy 372.04318 -248.0101) (xy 371.995909 -248.023792) (xy 371.947054 -248.029724)
			(xy 371.897879 -248.027743) (xy 371.84966 -248.017899) (xy 371.803644 -248.000447) (xy 371.761023 -247.97584)
			(xy 371.722902 -247.944715) (xy 371.690267 -247.907878) (xy 371.663964 -247.866282) (xy 371.644673 -247.821006)
			(xy 371.632896 -247.773222) (xy 371.628936 -247.724168) (xy 371.300696 -247.724168) (xy 371.300699 -247.7242)
			(xy 371.296529 -247.774529) (xy 371.284133 -247.823485) (xy 371.263848 -247.869733) (xy 371.236229 -247.912012)
			(xy 371.202028 -247.949169) (xy 371.162177 -247.980191) (xy 371.117765 -248.004231) (xy 371.070002 -248.020633)
			(xy 371.020191 -248.028951) (xy 370.99494 -248.029476) (xy 370.054886 -248.029476) (xy 370.029629 -248.029017)
			(xy 369.979804 -248.020701) (xy 369.932027 -248.004297) (xy 369.887601 -247.980253) (xy 369.847739 -247.949226)
			(xy 369.813527 -247.91206) (xy 369.785899 -247.869771) (xy 369.765609 -247.823511) (xy 369.753208 -247.774542)
			(xy 369.749037 -247.7242) (xy 369.420139 -247.7242) (xy 369.419645 -247.748775) (xy 369.41175 -247.797352)
			(xy 369.396166 -247.844033) (xy 369.373295 -247.88761) (xy 369.34373 -247.926954) (xy 369.308237 -247.961046)
			(xy 369.267734 -247.989002) (xy 369.223272 -248.0101) (xy 369.176001 -248.023792) (xy 369.127146 -248.029724)
			(xy 369.077971 -248.027743) (xy 369.029752 -248.017899) (xy 368.983736 -248.000447) (xy 368.941115 -247.97584)
			(xy 368.902994 -247.944715) (xy 368.870359 -247.907878) (xy 368.844056 -247.866282) (xy 368.824765 -247.821006)
			(xy 368.812988 -247.773222) (xy 368.809028 -247.724168) (xy 368.480625 -247.724168) (xy 368.480628 -247.7242)
			(xy 368.476457 -247.77454) (xy 368.464056 -247.823507) (xy 368.443764 -247.869764) (xy 368.416136 -247.912051)
			(xy 368.381923 -247.949213) (xy 368.34206 -247.980237) (xy 368.297635 -248.004276) (xy 368.249858 -248.020674)
			(xy 368.200034 -248.028985) (xy 368.174778 -248.029476) (xy 367.234724 -248.029476) (xy 367.209462 -248.029049)
			(xy 367.159628 -248.020737) (xy 367.111841 -248.004335) (xy 367.067406 -247.980291) (xy 367.027534 -247.949261)
			(xy 366.993314 -247.912091) (xy 366.96568 -247.869795) (xy 366.945384 -247.823528) (xy 366.93298 -247.774551)
			(xy 366.928808 -247.7242) (xy 366.600231 -247.7242) (xy 366.599737 -247.748775) (xy 366.591842 -247.797352)
			(xy 366.576258 -247.844033) (xy 366.553387 -247.88761) (xy 366.523822 -247.926954) (xy 366.488329 -247.961046)
			(xy 366.447826 -247.989002) (xy 366.403364 -248.0101) (xy 366.356093 -248.023792) (xy 366.307238 -248.029724)
			(xy 366.258063 -248.027743) (xy 366.209844 -248.017899) (xy 366.163828 -248.000447) (xy 366.121207 -247.97584)
			(xy 366.083086 -247.944715) (xy 366.050451 -247.907878) (xy 366.024148 -247.866282) (xy 366.004857 -247.821006)
			(xy 365.99308 -247.773222) (xy 365.98912 -247.724168) (xy 365.660725 -247.724168) (xy 365.660728 -247.7242)
			(xy 365.656556 -247.774541) (xy 365.644155 -247.823508) (xy 365.623863 -247.869766) (xy 365.596233 -247.912053)
			(xy 365.56202 -247.949216) (xy 365.522156 -247.980239) (xy 365.477729 -248.004278) (xy 365.429952 -248.020676)
			(xy 365.380127 -248.028986) (xy 365.35487 -248.029476) (xy 364.414816 -248.029476) (xy 364.389555 -248.029048)
			(xy 364.339721 -248.020735) (xy 364.291935 -248.004332) (xy 364.247501 -247.980288) (xy 364.207631 -247.949258)
			(xy 364.173412 -247.912088) (xy 364.145778 -247.869793) (xy 364.125483 -247.823526) (xy 364.11308 -247.77455)
			(xy 364.108908 -247.7242) (xy 363.780069 -247.7242) (xy 363.779575 -247.748775) (xy 363.77168 -247.797352)
			(xy 363.756096 -247.844033) (xy 363.733225 -247.88761) (xy 363.70366 -247.926954) (xy 363.668167 -247.961046)
			(xy 363.627664 -247.989002) (xy 363.583202 -248.0101) (xy 363.535931 -248.023792) (xy 363.487076 -248.029724)
			(xy 363.437901 -248.027743) (xy 363.389682 -248.017899) (xy 363.343666 -248.000447) (xy 363.301045 -247.97584)
			(xy 363.262924 -247.944715) (xy 363.230289 -247.907878) (xy 363.203986 -247.866282) (xy 363.184695 -247.821006)
			(xy 363.172918 -247.773222) (xy 363.168958 -247.724168) (xy 362.840016 -247.724168) (xy 362.839521 -247.748775)
			(xy 362.831626 -247.797352) (xy 362.816042 -247.844033) (xy 362.793171 -247.88761) (xy 362.763606 -247.926954)
			(xy 362.728113 -247.961046) (xy 362.68761 -247.989002) (xy 362.643148 -248.0101) (xy 362.595877 -248.023792)
			(xy 362.547022 -248.029724) (xy 362.497847 -248.027743) (xy 362.449628 -248.017899) (xy 362.403612 -248.000447)
			(xy 362.360991 -247.97584) (xy 362.32287 -247.944715) (xy 362.290235 -247.907878) (xy 362.263932 -247.866282)
			(xy 362.244641 -247.821006) (xy 362.232864 -247.773222) (xy 362.228904 -247.724168) (xy 361.900216 -247.724168)
			(xy 361.899721 -247.748775) (xy 361.891826 -247.797352) (xy 361.876242 -247.844033) (xy 361.853371 -247.88761)
			(xy 361.823806 -247.926954) (xy 361.788313 -247.961046) (xy 361.74781 -247.989002) (xy 361.703348 -248.0101)
			(xy 361.656077 -248.023792) (xy 361.607222 -248.029724) (xy 361.558047 -248.027743) (xy 361.509828 -248.017899)
			(xy 361.463812 -248.000447) (xy 361.421191 -247.97584) (xy 361.38307 -247.944715) (xy 361.350435 -247.907878)
			(xy 361.324132 -247.866282) (xy 361.304841 -247.821006) (xy 361.293064 -247.773222) (xy 361.289104 -247.724168)
			(xy 359.955548 -247.724168) (xy 359.927394 -247.745629) (xy 359.881138 -247.770782) (xy 359.831585 -247.78858)
			(xy 359.779895 -247.798604) (xy 359.727281 -247.800621) (xy 359.674976 -247.794583) (xy 359.624205 -247.780631)
			(xy 359.57616 -247.759092) (xy 359.531965 -247.730472) (xy 359.492657 -247.695441) (xy 359.459157 -247.65482)
			(xy 359.432251 -247.609561) (xy 359.412568 -247.560726) (xy 359.400571 -247.509458) (xy 359.396541 -247.45696)
			(xy 357.988941 -247.45696) (xy 357.993944 -247.459334) (xy 358.034447 -247.48729) (xy 358.06994 -247.521382)
			(xy 358.099505 -247.560726) (xy 358.122376 -247.604303) (xy 358.13796 -247.650984) (xy 358.145855 -247.699561)
			(xy 358.14635 -247.724168) (xy 358.145855 -247.748775) (xy 358.13796 -247.797352) (xy 358.122376 -247.844033)
			(xy 358.099505 -247.88761) (xy 358.06994 -247.926954) (xy 358.034447 -247.961046) (xy 357.993944 -247.989002)
			(xy 357.949482 -248.0101) (xy 357.902211 -248.023792) (xy 357.853356 -248.029724) (xy 357.804181 -248.027743)
			(xy 357.755962 -248.017899) (xy 357.709946 -248.000447) (xy 357.667325 -247.97584) (xy 357.629204 -247.944715)
			(xy 357.596569 -247.907878) (xy 357.570266 -247.866282) (xy 357.550975 -247.821006) (xy 357.539198 -247.773222)
			(xy 357.535238 -247.724168) (xy 357.20655 -247.724168) (xy 357.206055 -247.748775) (xy 357.19816 -247.797352)
			(xy 357.182576 -247.844033) (xy 357.159705 -247.88761) (xy 357.13014 -247.926954) (xy 357.094647 -247.961046)
			(xy 357.054144 -247.989002) (xy 357.009682 -248.0101) (xy 356.962411 -248.023792) (xy 356.913556 -248.029724)
			(xy 356.864381 -248.027743) (xy 356.816162 -248.017899) (xy 356.770146 -248.000447) (xy 356.727525 -247.97584)
			(xy 356.689404 -247.944715) (xy 356.656769 -247.907878) (xy 356.630466 -247.866282) (xy 356.611175 -247.821006)
			(xy 356.599398 -247.773222) (xy 356.595438 -247.724168) (xy 356.266496 -247.724168) (xy 356.266001 -247.748775)
			(xy 356.258106 -247.797352) (xy 356.242522 -247.844033) (xy 356.219651 -247.88761) (xy 356.190086 -247.926954)
			(xy 356.154593 -247.961046) (xy 356.11409 -247.989002) (xy 356.069628 -248.0101) (xy 356.022357 -248.023792)
			(xy 355.973502 -248.029724) (xy 355.924327 -248.027743) (xy 355.876108 -248.017899) (xy 355.830092 -248.000447)
			(xy 355.787471 -247.97584) (xy 355.74935 -247.944715) (xy 355.716715 -247.907878) (xy 355.690412 -247.866282)
			(xy 355.671121 -247.821006) (xy 355.659344 -247.773222) (xy 355.655384 -247.724168) (xy 355.326442 -247.724168)
			(xy 355.325947 -247.748775) (xy 355.318052 -247.797352) (xy 355.302468 -247.844033) (xy 355.279597 -247.88761)
			(xy 355.250032 -247.926954) (xy 355.214539 -247.961046) (xy 355.174036 -247.989002) (xy 355.129574 -248.0101)
			(xy 355.082303 -248.023792) (xy 355.033448 -248.029724) (xy 354.984273 -248.027743) (xy 354.936054 -248.017899)
			(xy 354.890038 -248.000447) (xy 354.847417 -247.97584) (xy 354.809296 -247.944715) (xy 354.776661 -247.907878)
			(xy 354.750358 -247.866282) (xy 354.731067 -247.821006) (xy 354.71929 -247.773222) (xy 354.71533 -247.724168)
			(xy 354.386388 -247.724168) (xy 354.385893 -247.748775) (xy 354.377998 -247.797352) (xy 354.362414 -247.844033)
			(xy 354.339543 -247.88761) (xy 354.309978 -247.926954) (xy 354.274485 -247.961046) (xy 354.233982 -247.989002)
			(xy 354.18952 -248.0101) (xy 354.142249 -248.023792) (xy 354.093394 -248.029724) (xy 354.044219 -248.027743)
			(xy 353.996 -248.017899) (xy 353.949984 -248.000447) (xy 353.907363 -247.97584) (xy 353.869242 -247.944715)
			(xy 353.836607 -247.907878) (xy 353.810304 -247.866282) (xy 353.791013 -247.821006) (xy 353.779236 -247.773222)
			(xy 353.775276 -247.724168) (xy 353.446334 -247.724168) (xy 353.445839 -247.748775) (xy 353.437944 -247.797352)
			(xy 353.42236 -247.844033) (xy 353.399489 -247.88761) (xy 353.369924 -247.926954) (xy 353.334431 -247.961046)
			(xy 353.293928 -247.989002) (xy 353.249466 -248.0101) (xy 353.202195 -248.023792) (xy 353.15334 -248.029724)
			(xy 353.104165 -248.027743) (xy 353.055946 -248.017899) (xy 353.00993 -248.000447) (xy 352.967309 -247.97584)
			(xy 352.929188 -247.944715) (xy 352.896553 -247.907878) (xy 352.87025 -247.866282) (xy 352.850959 -247.821006)
			(xy 352.839182 -247.773222) (xy 352.835222 -247.724168) (xy 352.506534 -247.724168) (xy 352.506039 -247.748775)
			(xy 352.498144 -247.797352) (xy 352.48256 -247.844033) (xy 352.459689 -247.88761) (xy 352.430124 -247.926954)
			(xy 352.394631 -247.961046) (xy 352.354128 -247.989002) (xy 352.309666 -248.0101) (xy 352.262395 -248.023792)
			(xy 352.21354 -248.029724) (xy 352.164365 -248.027743) (xy 352.116146 -248.017899) (xy 352.07013 -248.000447)
			(xy 352.027509 -247.97584) (xy 351.989388 -247.944715) (xy 351.956753 -247.907878) (xy 351.93045 -247.866282)
			(xy 351.911159 -247.821006) (xy 351.899382 -247.773222) (xy 351.895422 -247.724168) (xy 351.56648 -247.724168)
			(xy 351.565985 -247.748775) (xy 351.55809 -247.797352) (xy 351.542506 -247.844033) (xy 351.519635 -247.88761)
			(xy 351.49007 -247.926954) (xy 351.454577 -247.961046) (xy 351.414074 -247.989002) (xy 351.369612 -248.0101)
			(xy 351.322341 -248.023792) (xy 351.273486 -248.029724) (xy 351.224311 -248.027743) (xy 351.176092 -248.017899)
			(xy 351.130076 -248.000447) (xy 351.087455 -247.97584) (xy 351.049334 -247.944715) (xy 351.016699 -247.907878)
			(xy 350.990396 -247.866282) (xy 350.971105 -247.821006) (xy 350.959328 -247.773222) (xy 350.955368 -247.724168)
			(xy 350.626426 -247.724168) (xy 350.625931 -247.748775) (xy 350.618036 -247.797352) (xy 350.602452 -247.844033)
			(xy 350.579581 -247.88761) (xy 350.550016 -247.926954) (xy 350.514523 -247.961046) (xy 350.47402 -247.989002)
			(xy 350.429558 -248.0101) (xy 350.382287 -248.023792) (xy 350.333432 -248.029724) (xy 350.284257 -248.027743)
			(xy 350.236038 -248.017899) (xy 350.190022 -248.000447) (xy 350.147401 -247.97584) (xy 350.10928 -247.944715)
			(xy 350.076645 -247.907878) (xy 350.050342 -247.866282) (xy 350.031051 -247.821006) (xy 350.019274 -247.773222)
			(xy 350.015314 -247.724168) (xy 349.686372 -247.724168) (xy 349.685877 -247.748775) (xy 349.677982 -247.797352)
			(xy 349.662398 -247.844033) (xy 349.639527 -247.88761) (xy 349.609962 -247.926954) (xy 349.574469 -247.961046)
			(xy 349.533966 -247.989002) (xy 349.489504 -248.0101) (xy 349.442233 -248.023792) (xy 349.393378 -248.029724)
			(xy 349.344203 -248.027743) (xy 349.295984 -248.017899) (xy 349.249968 -248.000447) (xy 349.207347 -247.97584)
			(xy 349.169226 -247.944715) (xy 349.136591 -247.907878) (xy 349.110288 -247.866282) (xy 349.090997 -247.821006)
			(xy 349.07922 -247.773222) (xy 349.07526 -247.724168) (xy 348.746318 -247.724168) (xy 348.745823 -247.748775)
			(xy 348.737928 -247.797352) (xy 348.722344 -247.844033) (xy 348.699473 -247.88761) (xy 348.669908 -247.926954)
			(xy 348.634415 -247.961046) (xy 348.593912 -247.989002) (xy 348.54945 -248.0101) (xy 348.502179 -248.023792)
			(xy 348.453324 -248.029724) (xy 348.404149 -248.027743) (xy 348.35593 -248.017899) (xy 348.309914 -248.000447)
			(xy 348.267293 -247.97584) (xy 348.229172 -247.944715) (xy 348.196537 -247.907878) (xy 348.170234 -247.866282)
			(xy 348.150943 -247.821006) (xy 348.139166 -247.773222) (xy 348.135206 -247.724168) (xy 347.806518 -247.724168)
			(xy 347.806023 -247.748775) (xy 347.798128 -247.797352) (xy 347.782544 -247.844033) (xy 347.759673 -247.88761)
			(xy 347.730108 -247.926954) (xy 347.694615 -247.961046) (xy 347.654112 -247.989002) (xy 347.60965 -248.0101)
			(xy 347.562379 -248.023792) (xy 347.513524 -248.029724) (xy 347.464349 -248.027743) (xy 347.41613 -248.017899)
			(xy 347.370114 -248.000447) (xy 347.327493 -247.97584) (xy 347.289372 -247.944715) (xy 347.256737 -247.907878)
			(xy 347.230434 -247.866282) (xy 347.211143 -247.821006) (xy 347.199366 -247.773222) (xy 347.195406 -247.724168)
			(xy 346.866464 -247.724168) (xy 346.865969 -247.748775) (xy 346.858074 -247.797352) (xy 346.84249 -247.844033)
			(xy 346.819619 -247.88761) (xy 346.790054 -247.926954) (xy 346.754561 -247.961046) (xy 346.714058 -247.989002)
			(xy 346.669596 -248.0101) (xy 346.622325 -248.023792) (xy 346.57347 -248.029724) (xy 346.524295 -248.027743)
			(xy 346.476076 -248.017899) (xy 346.43006 -248.000447) (xy 346.387439 -247.97584) (xy 346.349318 -247.944715)
			(xy 346.316683 -247.907878) (xy 346.29038 -247.866282) (xy 346.271089 -247.821006) (xy 346.259312 -247.773222)
			(xy 346.255352 -247.724168) (xy 345.92641 -247.724168) (xy 345.925915 -247.748775) (xy 345.91802 -247.797352)
			(xy 345.902436 -247.844033) (xy 345.879565 -247.88761) (xy 345.85 -247.926954) (xy 345.814507 -247.961046)
			(xy 345.774004 -247.989002) (xy 345.729542 -248.0101) (xy 345.682271 -248.023792) (xy 345.633416 -248.029724)
			(xy 345.584241 -248.027743) (xy 345.536022 -248.017899) (xy 345.490006 -248.000447) (xy 345.447385 -247.97584)
			(xy 345.409264 -247.944715) (xy 345.376629 -247.907878) (xy 345.350326 -247.866282) (xy 345.331035 -247.821006)
			(xy 345.319258 -247.773222) (xy 345.315298 -247.724168) (xy 344.986951 -247.724168) (xy 344.986953 -247.724198)
			(xy 344.983038 -247.772992) (xy 344.971391 -247.820536) (xy 344.95231 -247.865614) (xy 344.926285 -247.907073)
			(xy 344.893981 -247.94385) (xy 344.856226 -247.975005) (xy 344.813985 -247.99974) (xy 344.76834 -248.017422)
			(xy 344.720459 -248.027598) (xy 344.696034 -248.029222) (xy 344.686636 -248.029476) (xy 344.669618 -248.037096)
			(xy 344.641424 -248.064782) (xy 344.634613 -248.072049) (xy 344.626895 -248.090392) (xy 344.626438 -248.100342)
			(xy 344.626438 -248.53519) (xy 344.62686 -248.54526) (xy 344.634576 -248.563864) (xy 344.641424 -248.571258)
			(xy 344.921332 -248.851166) (xy 344.928731 -248.858011) (xy 344.947329 -248.865739) (xy 344.9574 -248.866152)
			(xy 346.697808 -248.866152) (xy 346.707086 -248.865797) (xy 346.724458 -248.859285) (xy 346.738368 -248.847009)
			(xy 346.74302 -248.838974) (xy 346.782136 -248.764044) (xy 346.786367 -248.754923) (xy 346.788198 -248.73492)
			(xy 346.785692 -248.725182) (xy 346.780612 -248.70918) (xy 346.776548 -248.703084) (xy 346.764516 -248.684213)
			(xy 346.74551 -248.643694) (xy 346.732625 -248.600834) (xy 346.726137 -248.556552) (xy 346.725748 -248.534174)
			(xy 346.725748 -248.52757) (xy 346.7267 -248.503919) (xy 346.735005 -248.457321) (xy 346.750405 -248.412563)
			(xy 346.772529 -248.37072) (xy 346.800847 -248.332793) (xy 346.834681 -248.299693) (xy 346.873219 -248.272212)
			(xy 346.915537 -248.25101) (xy 346.960621 -248.236594) (xy 347.00739 -248.229312) (xy 347.031056 -248.228866)
			(xy 347.055052 -248.229309) (xy 347.102454 -248.23681) (xy 347.1481 -248.251634) (xy 347.190864 -248.273417)
			(xy 347.229694 -248.301621) (xy 347.263633 -248.335553) (xy 347.291846 -248.374376) (xy 347.313639 -248.417136)
			(xy 347.328474 -248.462777) (xy 347.335986 -248.510178) (xy 347.336364 -248.534174) (xy 349.545414 -248.534174)
			(xy 349.549374 -248.48512) (xy 349.561151 -248.437336) (xy 349.580442 -248.39206) (xy 349.606745 -248.350464)
			(xy 349.63938 -248.313627) (xy 349.677501 -248.282502) (xy 349.720122 -248.257895) (xy 349.766138 -248.240443)
			(xy 349.814357 -248.230599) (xy 349.863532 -248.228618) (xy 349.912387 -248.23455) (xy 349.959658 -248.248242)
			(xy 350.00412 -248.26934) (xy 350.044623 -248.297296) (xy 350.080116 -248.331388) (xy 350.109681 -248.370732)
			(xy 350.132552 -248.414309) (xy 350.148136 -248.46099) (xy 350.156031 -248.509567) (xy 350.156526 -248.534174)
			(xy 352.365322 -248.534174) (xy 352.369282 -248.48512) (xy 352.381059 -248.437336) (xy 352.40035 -248.39206)
			(xy 352.426653 -248.350464) (xy 352.459288 -248.313627) (xy 352.497409 -248.282502) (xy 352.54003 -248.257895)
			(xy 352.586046 -248.240443) (xy 352.634265 -248.230599) (xy 352.68344 -248.228618) (xy 352.732295 -248.23455)
			(xy 352.779566 -248.248242) (xy 352.824028 -248.26934) (xy 352.864531 -248.297296) (xy 352.900024 -248.331388)
			(xy 352.929589 -248.370732) (xy 352.95246 -248.414309) (xy 352.968044 -248.46099) (xy 352.975939 -248.509567)
			(xy 352.976434 -248.534174) (xy 355.18523 -248.534174) (xy 355.18919 -248.48512) (xy 355.200967 -248.437336)
			(xy 355.220258 -248.39206) (xy 355.246561 -248.350464) (xy 355.279196 -248.313627) (xy 355.317317 -248.282502)
			(xy 355.359938 -248.257895) (xy 355.405954 -248.240443) (xy 355.454173 -248.230599) (xy 355.503348 -248.228618)
			(xy 355.552203 -248.23455) (xy 355.599474 -248.248242) (xy 355.643936 -248.26934) (xy 355.684439 -248.297296)
			(xy 355.719932 -248.331388) (xy 355.749497 -248.370732) (xy 355.772368 -248.414309) (xy 355.787952 -248.46099)
			(xy 355.795847 -248.509567) (xy 355.796342 -248.534174) (xy 356.125284 -248.534174) (xy 356.129244 -248.48512)
			(xy 356.141021 -248.437336) (xy 356.160312 -248.39206) (xy 356.186615 -248.350464) (xy 356.21925 -248.313627)
			(xy 356.257371 -248.282502) (xy 356.299992 -248.257895) (xy 356.346008 -248.240443) (xy 356.394227 -248.230599)
			(xy 356.443402 -248.228618) (xy 356.492257 -248.23455) (xy 356.539528 -248.248242) (xy 356.58399 -248.26934)
			(xy 356.624493 -248.297296) (xy 356.659986 -248.331388) (xy 356.689551 -248.370732) (xy 356.712422 -248.414309)
			(xy 356.728006 -248.46099) (xy 356.735901 -248.509567) (xy 356.736396 -248.534174) (xy 357.065338 -248.534174)
			(xy 357.069298 -248.48512) (xy 357.081075 -248.437336) (xy 357.100366 -248.39206) (xy 357.126669 -248.350464)
			(xy 357.159304 -248.313627) (xy 357.197425 -248.282502) (xy 357.240046 -248.257895) (xy 357.286062 -248.240443)
			(xy 357.334281 -248.230599) (xy 357.383456 -248.228618) (xy 357.432311 -248.23455) (xy 357.479582 -248.248242)
			(xy 357.524044 -248.26934) (xy 357.564547 -248.297296) (xy 357.60004 -248.331388) (xy 357.629605 -248.370732)
			(xy 357.652476 -248.414309) (xy 357.66806 -248.46099) (xy 357.675955 -248.509567) (xy 357.67645 -248.534174)
			(xy 358.005392 -248.534174) (xy 358.009352 -248.48512) (xy 358.021129 -248.437336) (xy 358.04042 -248.39206)
			(xy 358.066723 -248.350464) (xy 358.099358 -248.313627) (xy 358.137479 -248.282502) (xy 358.1801 -248.257895)
			(xy 358.226116 -248.240443) (xy 358.274335 -248.230599) (xy 358.32351 -248.228618) (xy 358.372365 -248.23455)
			(xy 358.419636 -248.248242) (xy 358.464098 -248.26934) (xy 358.504601 -248.297296) (xy 358.540094 -248.331388)
			(xy 358.569659 -248.370732) (xy 358.59253 -248.414309) (xy 358.608114 -248.46099) (xy 358.616009 -248.509567)
			(xy 358.616504 -248.534174) (xy 360.81895 -248.534174) (xy 360.82291 -248.48512) (xy 360.834687 -248.437336)
			(xy 360.853978 -248.39206) (xy 360.880281 -248.350464) (xy 360.912916 -248.313627) (xy 360.951037 -248.282502)
			(xy 360.993658 -248.257895) (xy 361.039674 -248.240443) (xy 361.087893 -248.230599) (xy 361.137068 -248.228618)
			(xy 361.185923 -248.23455) (xy 361.233194 -248.248242) (xy 361.277656 -248.26934) (xy 361.318159 -248.297296)
			(xy 361.353652 -248.331388) (xy 361.383217 -248.370732) (xy 361.406088 -248.414309) (xy 361.421672 -248.46099)
			(xy 361.429567 -248.509567) (xy 361.430062 -248.534174) (xy 361.430061 -248.5342) (xy 361.758659 -248.5342)
			(xy 361.762835 -248.48381) (xy 361.775248 -248.434795) (xy 361.795559 -248.388491) (xy 361.823214 -248.346162)
			(xy 361.85746 -248.308962) (xy 361.897361 -248.277907) (xy 361.94183 -248.253842) (xy 361.989653 -248.237426)
			(xy 362.039527 -248.229104) (xy 362.064808 -248.228612) (xy 363.004862 -248.228612) (xy 363.030141 -248.229154)
			(xy 363.080009 -248.23747) (xy 363.127829 -248.253881) (xy 363.172294 -248.27794) (xy 363.212193 -248.30899)
			(xy 363.246437 -248.346184) (xy 363.274091 -248.388507) (xy 363.294401 -248.434806) (xy 363.306813 -248.483816)
			(xy 363.310987 -248.534174) (xy 363.639112 -248.534174) (xy 363.643072 -248.48512) (xy 363.654849 -248.437336)
			(xy 363.67414 -248.39206) (xy 363.700443 -248.350464) (xy 363.733078 -248.313627) (xy 363.771199 -248.282502)
			(xy 363.81382 -248.257895) (xy 363.859836 -248.240443) (xy 363.908055 -248.230599) (xy 363.95723 -248.228618)
			(xy 364.006085 -248.23455) (xy 364.053356 -248.248242) (xy 364.097818 -248.26934) (xy 364.138321 -248.297296)
			(xy 364.173814 -248.331388) (xy 364.203379 -248.370732) (xy 364.22625 -248.414309) (xy 364.241834 -248.46099)
			(xy 364.249729 -248.509567) (xy 364.250224 -248.534174) (xy 366.45902 -248.534174) (xy 366.46298 -248.48512)
			(xy 366.474757 -248.437336) (xy 366.494048 -248.39206) (xy 366.520351 -248.350464) (xy 366.552986 -248.313627)
			(xy 366.591107 -248.282502) (xy 366.633728 -248.257895) (xy 366.679744 -248.240443) (xy 366.727963 -248.230599)
			(xy 366.777138 -248.228618) (xy 366.825993 -248.23455) (xy 366.873264 -248.248242) (xy 366.917726 -248.26934)
			(xy 366.958229 -248.297296) (xy 366.993722 -248.331388) (xy 367.023287 -248.370732) (xy 367.046158 -248.414309)
			(xy 367.061742 -248.46099) (xy 367.069637 -248.509567) (xy 367.070132 -248.534174) (xy 369.278928 -248.534174)
			(xy 369.282888 -248.48512) (xy 369.294665 -248.437336) (xy 369.313956 -248.39206) (xy 369.340259 -248.350464)
			(xy 369.372894 -248.313627) (xy 369.411015 -248.282502) (xy 369.453636 -248.257895) (xy 369.499652 -248.240443)
			(xy 369.547871 -248.230599) (xy 369.597046 -248.228618) (xy 369.645901 -248.23455) (xy 369.693172 -248.248242)
			(xy 369.737634 -248.26934) (xy 369.778137 -248.297296) (xy 369.81363 -248.331388) (xy 369.843195 -248.370732)
			(xy 369.866066 -248.414309) (xy 369.88165 -248.46099) (xy 369.889545 -248.509567) (xy 369.89004 -248.534174)
			(xy 372.09909 -248.534174) (xy 372.10305 -248.48512) (xy 372.114827 -248.437336) (xy 372.134118 -248.39206)
			(xy 372.160421 -248.350464) (xy 372.193056 -248.313627) (xy 372.231177 -248.282502) (xy 372.273798 -248.257895)
			(xy 372.319814 -248.240443) (xy 372.368033 -248.230599) (xy 372.417208 -248.228618) (xy 372.466063 -248.23455)
			(xy 372.513334 -248.248242) (xy 372.557796 -248.26934) (xy 372.598299 -248.297296) (xy 372.633792 -248.331388)
			(xy 372.663357 -248.370732) (xy 372.686228 -248.414309) (xy 372.701812 -248.46099) (xy 372.709707 -248.509567)
			(xy 372.710202 -248.534174) (xy 372.709707 -248.558781) (xy 372.701812 -248.607358) (xy 372.686228 -248.654039)
			(xy 372.663357 -248.697616) (xy 372.633792 -248.73696) (xy 372.598299 -248.771052) (xy 372.557796 -248.799008)
			(xy 372.513334 -248.820106) (xy 372.466063 -248.833798) (xy 372.417208 -248.83973) (xy 372.368033 -248.837749)
			(xy 372.319814 -248.827905) (xy 372.273798 -248.810453) (xy 372.231177 -248.785846) (xy 372.193056 -248.754721)
			(xy 372.160421 -248.717884) (xy 372.134118 -248.676288) (xy 372.114827 -248.631012) (xy 372.10305 -248.583228)
			(xy 372.09909 -248.534174) (xy 369.89004 -248.534174) (xy 369.889545 -248.558781) (xy 369.88165 -248.607358)
			(xy 369.866066 -248.654039) (xy 369.843195 -248.697616) (xy 369.81363 -248.73696) (xy 369.778137 -248.771052)
			(xy 369.737634 -248.799008) (xy 369.693172 -248.820106) (xy 369.645901 -248.833798) (xy 369.597046 -248.83973)
			(xy 369.547871 -248.837749) (xy 369.499652 -248.827905) (xy 369.453636 -248.810453) (xy 369.411015 -248.785846)
			(xy 369.372894 -248.754721) (xy 369.340259 -248.717884) (xy 369.313956 -248.676288) (xy 369.294665 -248.631012)
			(xy 369.282888 -248.583228) (xy 369.278928 -248.534174) (xy 367.070132 -248.534174) (xy 367.069637 -248.558781)
			(xy 367.061742 -248.607358) (xy 367.046158 -248.654039) (xy 367.023287 -248.697616) (xy 366.993722 -248.73696)
			(xy 366.958229 -248.771052) (xy 366.917726 -248.799008) (xy 366.873264 -248.820106) (xy 366.825993 -248.833798)
			(xy 366.777138 -248.83973) (xy 366.727963 -248.837749) (xy 366.679744 -248.827905) (xy 366.633728 -248.810453)
			(xy 366.591107 -248.785846) (xy 366.552986 -248.754721) (xy 366.520351 -248.717884) (xy 366.494048 -248.676288)
			(xy 366.474757 -248.631012) (xy 366.46298 -248.583228) (xy 366.45902 -248.534174) (xy 364.250224 -248.534174)
			(xy 364.249729 -248.558781) (xy 364.241834 -248.607358) (xy 364.22625 -248.654039) (xy 364.203379 -248.697616)
			(xy 364.173814 -248.73696) (xy 364.138321 -248.771052) (xy 364.097818 -248.799008) (xy 364.053356 -248.820106)
			(xy 364.006085 -248.833798) (xy 363.95723 -248.83973) (xy 363.908055 -248.837749) (xy 363.859836 -248.827905)
			(xy 363.81382 -248.810453) (xy 363.771199 -248.785846) (xy 363.733078 -248.754721) (xy 363.700443 -248.717884)
			(xy 363.67414 -248.676288) (xy 363.654849 -248.631012) (xy 363.643072 -248.583228) (xy 363.639112 -248.534174)
			(xy 363.310987 -248.534174) (xy 363.310989 -248.5342) (xy 363.306813 -248.584584) (xy 363.294401 -248.633594)
			(xy 363.274091 -248.679893) (xy 363.246437 -248.722216) (xy 363.212193 -248.75941) (xy 363.172294 -248.79046)
			(xy 363.127829 -248.814519) (xy 363.080009 -248.83093) (xy 363.030141 -248.839246) (xy 363.004862 -248.839736)
			(xy 362.064808 -248.839736) (xy 362.039527 -248.839296) (xy 361.989653 -248.830974) (xy 361.94183 -248.814558)
			(xy 361.897361 -248.790493) (xy 361.85746 -248.759438) (xy 361.823214 -248.722238) (xy 361.795559 -248.679909)
			(xy 361.775248 -248.633605) (xy 361.762835 -248.58459) (xy 361.758659 -248.5342) (xy 361.430061 -248.5342)
			(xy 361.429567 -248.558781) (xy 361.421672 -248.607358) (xy 361.406088 -248.654039) (xy 361.383217 -248.697616)
			(xy 361.353652 -248.73696) (xy 361.318159 -248.771052) (xy 361.277656 -248.799008) (xy 361.233194 -248.820106)
			(xy 361.185923 -248.833798) (xy 361.137068 -248.83973) (xy 361.087893 -248.837749) (xy 361.039674 -248.827905)
			(xy 360.993658 -248.810453) (xy 360.951037 -248.785846) (xy 360.912916 -248.754721) (xy 360.880281 -248.717884)
			(xy 360.853978 -248.676288) (xy 360.834687 -248.631012) (xy 360.82291 -248.583228) (xy 360.81895 -248.534174)
			(xy 358.616504 -248.534174) (xy 358.616009 -248.558781) (xy 358.608114 -248.607358) (xy 358.59253 -248.654039)
			(xy 358.569659 -248.697616) (xy 358.540094 -248.73696) (xy 358.504601 -248.771052) (xy 358.464098 -248.799008)
			(xy 358.419636 -248.820106) (xy 358.372365 -248.833798) (xy 358.32351 -248.83973) (xy 358.274335 -248.837749)
			(xy 358.226116 -248.827905) (xy 358.1801 -248.810453) (xy 358.137479 -248.785846) (xy 358.099358 -248.754721)
			(xy 358.066723 -248.717884) (xy 358.04042 -248.676288) (xy 358.021129 -248.631012) (xy 358.009352 -248.583228)
			(xy 358.005392 -248.534174) (xy 357.67645 -248.534174) (xy 357.675955 -248.558781) (xy 357.66806 -248.607358)
			(xy 357.652476 -248.654039) (xy 357.629605 -248.697616) (xy 357.60004 -248.73696) (xy 357.564547 -248.771052)
			(xy 357.524044 -248.799008) (xy 357.479582 -248.820106) (xy 357.432311 -248.833798) (xy 357.383456 -248.83973)
			(xy 357.334281 -248.837749) (xy 357.286062 -248.827905) (xy 357.240046 -248.810453) (xy 357.197425 -248.785846)
			(xy 357.159304 -248.754721) (xy 357.126669 -248.717884) (xy 357.100366 -248.676288) (xy 357.081075 -248.631012)
			(xy 357.069298 -248.583228) (xy 357.065338 -248.534174) (xy 356.736396 -248.534174) (xy 356.735901 -248.558781)
			(xy 356.728006 -248.607358) (xy 356.712422 -248.654039) (xy 356.689551 -248.697616) (xy 356.659986 -248.73696)
			(xy 356.624493 -248.771052) (xy 356.58399 -248.799008) (xy 356.539528 -248.820106) (xy 356.492257 -248.833798)
			(xy 356.443402 -248.83973) (xy 356.394227 -248.837749) (xy 356.346008 -248.827905) (xy 356.299992 -248.810453)
			(xy 356.257371 -248.785846) (xy 356.21925 -248.754721) (xy 356.186615 -248.717884) (xy 356.160312 -248.676288)
			(xy 356.141021 -248.631012) (xy 356.129244 -248.583228) (xy 356.125284 -248.534174) (xy 355.796342 -248.534174)
			(xy 355.795847 -248.558781) (xy 355.787952 -248.607358) (xy 355.772368 -248.654039) (xy 355.749497 -248.697616)
			(xy 355.719932 -248.73696) (xy 355.684439 -248.771052) (xy 355.643936 -248.799008) (xy 355.599474 -248.820106)
			(xy 355.552203 -248.833798) (xy 355.503348 -248.83973) (xy 355.454173 -248.837749) (xy 355.405954 -248.827905)
			(xy 355.359938 -248.810453) (xy 355.317317 -248.785846) (xy 355.279196 -248.754721) (xy 355.246561 -248.717884)
			(xy 355.220258 -248.676288) (xy 355.200967 -248.631012) (xy 355.18919 -248.583228) (xy 355.18523 -248.534174)
			(xy 352.976434 -248.534174) (xy 352.975939 -248.558781) (xy 352.968044 -248.607358) (xy 352.95246 -248.654039)
			(xy 352.929589 -248.697616) (xy 352.900024 -248.73696) (xy 352.864531 -248.771052) (xy 352.824028 -248.799008)
			(xy 352.779566 -248.820106) (xy 352.732295 -248.833798) (xy 352.68344 -248.83973) (xy 352.634265 -248.837749)
			(xy 352.586046 -248.827905) (xy 352.54003 -248.810453) (xy 352.497409 -248.785846) (xy 352.459288 -248.754721)
			(xy 352.426653 -248.717884) (xy 352.40035 -248.676288) (xy 352.381059 -248.631012) (xy 352.369282 -248.583228)
			(xy 352.365322 -248.534174) (xy 350.156526 -248.534174) (xy 350.156031 -248.558781) (xy 350.148136 -248.607358)
			(xy 350.132552 -248.654039) (xy 350.109681 -248.697616) (xy 350.080116 -248.73696) (xy 350.044623 -248.771052)
			(xy 350.00412 -248.799008) (xy 349.959658 -248.820106) (xy 349.912387 -248.833798) (xy 349.863532 -248.83973)
			(xy 349.814357 -248.837749) (xy 349.766138 -248.827905) (xy 349.720122 -248.810453) (xy 349.677501 -248.785846)
			(xy 349.63938 -248.754721) (xy 349.606745 -248.717884) (xy 349.580442 -248.676288) (xy 349.561151 -248.631012)
			(xy 349.549374 -248.583228) (xy 349.545414 -248.534174) (xy 347.336364 -248.534174) (xy 347.335915 -248.557513)
			(xy 347.328795 -248.603646) (xy 347.314732 -248.648156) (xy 347.294055 -248.690005) (xy 347.267246 -248.728218)
			(xy 347.23493 -248.761901) (xy 347.197861 -248.790271) (xy 347.177614 -248.80189) (xy 347.166946 -248.807732)
			(xy 347.153484 -248.82729) (xy 347.140276 -248.917968) (xy 347.139228 -248.929814) (xy 347.14677 -248.952336)
			(xy 347.154754 -248.961148) (xy 347.286326 -249.09272) (xy 347.321632 -249.09653) (xy 347.336872 -249.086878)
			(xy 347.355366 -249.07552) (xy 347.394885 -249.057575) (xy 347.436545 -249.045408) (xy 347.479509 -249.039264)
			(xy 347.50121 -249.038872) (xy 347.505274 -249.038872) (xy 347.529053 -249.039644) (xy 347.57595 -249.047652)
			(xy 347.621037 -249.062838) (xy 347.663221 -249.084835) (xy 347.701482 -249.113111) (xy 347.734893 -249.14698)
			(xy 347.762646 -249.185622) (xy 347.784067 -249.228102) (xy 347.798638 -249.273391) (xy 347.806007 -249.320392)
			(xy 347.806518 -249.34418) (xy 349.07526 -249.34418) (xy 349.07922 -249.295126) (xy 349.090997 -249.247342)
			(xy 349.110288 -249.202066) (xy 349.136591 -249.16047) (xy 349.169226 -249.123633) (xy 349.207347 -249.092508)
			(xy 349.249968 -249.067901) (xy 349.295984 -249.050449) (xy 349.344203 -249.040605) (xy 349.393378 -249.038624)
			(xy 349.442233 -249.044556) (xy 349.489504 -249.058248) (xy 349.533966 -249.079346) (xy 349.574469 -249.107302)
			(xy 349.609962 -249.141394) (xy 349.639527 -249.180738) (xy 349.662398 -249.224315) (xy 349.677982 -249.270996)
			(xy 349.685877 -249.319573) (xy 349.686372 -249.34418) (xy 350.955368 -249.34418) (xy 350.959328 -249.295126)
			(xy 350.971105 -249.247342) (xy 350.990396 -249.202066) (xy 351.016699 -249.16047) (xy 351.049334 -249.123633)
			(xy 351.087455 -249.092508) (xy 351.130076 -249.067901) (xy 351.176092 -249.050449) (xy 351.224311 -249.040605)
			(xy 351.273486 -249.038624) (xy 351.322341 -249.044556) (xy 351.369612 -249.058248) (xy 351.414074 -249.079346)
			(xy 351.454577 -249.107302) (xy 351.49007 -249.141394) (xy 351.519635 -249.180738) (xy 351.542506 -249.224315)
			(xy 351.55809 -249.270996) (xy 351.565985 -249.319573) (xy 351.56648 -249.34418) (xy 352.835222 -249.34418)
			(xy 352.839182 -249.295126) (xy 352.850959 -249.247342) (xy 352.87025 -249.202066) (xy 352.896553 -249.16047)
			(xy 352.929188 -249.123633) (xy 352.967309 -249.092508) (xy 353.00993 -249.067901) (xy 353.055946 -249.050449)
			(xy 353.104165 -249.040605) (xy 353.15334 -249.038624) (xy 353.202195 -249.044556) (xy 353.249466 -249.058248)
			(xy 353.293928 -249.079346) (xy 353.334431 -249.107302) (xy 353.369924 -249.141394) (xy 353.399489 -249.180738)
			(xy 353.42236 -249.224315) (xy 353.437944 -249.270996) (xy 353.445839 -249.319573) (xy 353.446334 -249.34418)
			(xy 354.71533 -249.34418) (xy 354.71929 -249.295126) (xy 354.731067 -249.247342) (xy 354.750358 -249.202066)
			(xy 354.776661 -249.16047) (xy 354.809296 -249.123633) (xy 354.847417 -249.092508) (xy 354.890038 -249.067901)
			(xy 354.936054 -249.050449) (xy 354.984273 -249.040605) (xy 355.033448 -249.038624) (xy 355.082303 -249.044556)
			(xy 355.129574 -249.058248) (xy 355.174036 -249.079346) (xy 355.214539 -249.107302) (xy 355.250032 -249.141394)
			(xy 355.279597 -249.180738) (xy 355.302468 -249.224315) (xy 355.318052 -249.270996) (xy 355.325947 -249.319573)
			(xy 355.326442 -249.34418) (xy 356.595438 -249.34418) (xy 356.599398 -249.295126) (xy 356.611175 -249.247342)
			(xy 356.630466 -249.202066) (xy 356.656769 -249.16047) (xy 356.689404 -249.123633) (xy 356.727525 -249.092508)
			(xy 356.770146 -249.067901) (xy 356.816162 -249.050449) (xy 356.864381 -249.040605) (xy 356.913556 -249.038624)
			(xy 356.962411 -249.044556) (xy 357.009682 -249.058248) (xy 357.054144 -249.079346) (xy 357.094647 -249.107302)
			(xy 357.13014 -249.141394) (xy 357.159705 -249.180738) (xy 357.182576 -249.224315) (xy 357.19816 -249.270996)
			(xy 357.206055 -249.319573) (xy 357.20655 -249.34418) (xy 357.206192 -249.36196) (xy 359.396541 -249.36196)
			(xy 359.400571 -249.309462) (xy 359.412568 -249.258194) (xy 359.432251 -249.209359) (xy 359.459157 -249.1641)
			(xy 359.492657 -249.123479) (xy 359.531965 -249.088448) (xy 359.57616 -249.059828) (xy 359.624205 -249.038289)
			(xy 359.674976 -249.024337) (xy 359.727281 -249.018299) (xy 359.779895 -249.020316) (xy 359.831585 -249.03034)
			(xy 359.881138 -249.048138) (xy 359.927394 -249.073291) (xy 359.969268 -249.10521) (xy 360.00578 -249.143148)
			(xy 360.036072 -249.186214) (xy 360.059435 -249.233399) (xy 360.075321 -249.283598) (xy 360.083358 -249.335634)
			(xy 360.083522 -249.34418) (xy 361.289104 -249.34418) (xy 361.293064 -249.295126) (xy 361.304841 -249.247342)
			(xy 361.324132 -249.202066) (xy 361.350435 -249.16047) (xy 361.38307 -249.123633) (xy 361.421191 -249.092508)
			(xy 361.463812 -249.067901) (xy 361.509828 -249.050449) (xy 361.558047 -249.040605) (xy 361.607222 -249.038624)
			(xy 361.656077 -249.044556) (xy 361.703348 -249.058248) (xy 361.74781 -249.079346) (xy 361.788313 -249.107302)
			(xy 361.823806 -249.141394) (xy 361.853371 -249.180738) (xy 361.876242 -249.224315) (xy 361.891826 -249.270996)
			(xy 361.899721 -249.319573) (xy 361.900216 -249.34418) (xy 363.168958 -249.34418) (xy 363.172918 -249.295126)
			(xy 363.184695 -249.247342) (xy 363.203986 -249.202066) (xy 363.230289 -249.16047) (xy 363.262924 -249.123633)
			(xy 363.301045 -249.092508) (xy 363.343666 -249.067901) (xy 363.389682 -249.050449) (xy 363.437901 -249.040605)
			(xy 363.487076 -249.038624) (xy 363.535931 -249.044556) (xy 363.583202 -249.058248) (xy 363.627664 -249.079346)
			(xy 363.668167 -249.107302) (xy 363.70366 -249.141394) (xy 363.733225 -249.180738) (xy 363.756096 -249.224315)
			(xy 363.77168 -249.270996) (xy 363.779575 -249.319573) (xy 363.78007 -249.34418) (xy 365.049066 -249.34418)
			(xy 365.053026 -249.295126) (xy 365.064803 -249.247342) (xy 365.084094 -249.202066) (xy 365.110397 -249.16047)
			(xy 365.143032 -249.123633) (xy 365.181153 -249.092508) (xy 365.223774 -249.067901) (xy 365.26979 -249.050449)
			(xy 365.318009 -249.040605) (xy 365.367184 -249.038624) (xy 365.416039 -249.044556) (xy 365.46331 -249.058248)
			(xy 365.507772 -249.079346) (xy 365.548275 -249.107302) (xy 365.583768 -249.141394) (xy 365.613333 -249.180738)
			(xy 365.636204 -249.224315) (xy 365.651788 -249.270996) (xy 365.659683 -249.319573) (xy 365.660178 -249.34418)
			(xy 366.92892 -249.34418) (xy 366.93288 -249.295126) (xy 366.944657 -249.247342) (xy 366.963948 -249.202066)
			(xy 366.990251 -249.16047) (xy 367.022886 -249.123633) (xy 367.061007 -249.092508) (xy 367.103628 -249.067901)
			(xy 367.149644 -249.050449) (xy 367.197863 -249.040605) (xy 367.247038 -249.038624) (xy 367.295893 -249.044556)
			(xy 367.343164 -249.058248) (xy 367.387626 -249.079346) (xy 367.428129 -249.107302) (xy 367.463622 -249.141394)
			(xy 367.493187 -249.180738) (xy 367.516058 -249.224315) (xy 367.531642 -249.270996) (xy 367.539537 -249.319573)
			(xy 367.540032 -249.34418) (xy 368.809028 -249.34418) (xy 368.812988 -249.295126) (xy 368.824765 -249.247342)
			(xy 368.844056 -249.202066) (xy 368.870359 -249.16047) (xy 368.902994 -249.123633) (xy 368.941115 -249.092508)
			(xy 368.983736 -249.067901) (xy 369.029752 -249.050449) (xy 369.077971 -249.040605) (xy 369.127146 -249.038624)
			(xy 369.176001 -249.044556) (xy 369.223272 -249.058248) (xy 369.267734 -249.079346) (xy 369.308237 -249.107302)
			(xy 369.34373 -249.141394) (xy 369.373295 -249.180738) (xy 369.396166 -249.224315) (xy 369.41175 -249.270996)
			(xy 369.419645 -249.319573) (xy 369.42014 -249.34418) (xy 370.688882 -249.34418) (xy 370.692842 -249.295126)
			(xy 370.704619 -249.247342) (xy 370.72391 -249.202066) (xy 370.750213 -249.16047) (xy 370.782848 -249.123633)
			(xy 370.820969 -249.092508) (xy 370.86359 -249.067901) (xy 370.909606 -249.050449) (xy 370.957825 -249.040605)
			(xy 371.007 -249.038624) (xy 371.055855 -249.044556) (xy 371.103126 -249.058248) (xy 371.147588 -249.079346)
			(xy 371.188091 -249.107302) (xy 371.223584 -249.141394) (xy 371.253149 -249.180738) (xy 371.27602 -249.224315)
			(xy 371.291604 -249.270996) (xy 371.299499 -249.319573) (xy 371.299994 -249.34418) (xy 372.56899 -249.34418)
			(xy 372.57295 -249.295126) (xy 372.584727 -249.247342) (xy 372.604018 -249.202066) (xy 372.630321 -249.16047)
			(xy 372.662956 -249.123633) (xy 372.701077 -249.092508) (xy 372.743698 -249.067901) (xy 372.789714 -249.050449)
			(xy 372.837933 -249.040605) (xy 372.887108 -249.038624) (xy 372.935963 -249.044556) (xy 372.983234 -249.058248)
			(xy 373.027696 -249.079346) (xy 373.068199 -249.107302) (xy 373.103692 -249.141394) (xy 373.133257 -249.180738)
			(xy 373.156128 -249.224315) (xy 373.171712 -249.270996) (xy 373.179607 -249.319573) (xy 373.180102 -249.34418)
			(xy 373.179607 -249.368787) (xy 373.171712 -249.417364) (xy 373.156128 -249.464045) (xy 373.133257 -249.507622)
			(xy 373.103692 -249.546966) (xy 373.068199 -249.581058) (xy 373.027696 -249.609014) (xy 372.983234 -249.630112)
			(xy 372.935963 -249.643804) (xy 372.887108 -249.649736) (xy 372.837933 -249.647755) (xy 372.789714 -249.637911)
			(xy 372.743698 -249.620459) (xy 372.701077 -249.595852) (xy 372.662956 -249.564727) (xy 372.630321 -249.52789)
			(xy 372.604018 -249.486294) (xy 372.584727 -249.441018) (xy 372.57295 -249.393234) (xy 372.56899 -249.34418)
			(xy 371.299994 -249.34418) (xy 371.299499 -249.368787) (xy 371.291604 -249.417364) (xy 371.27602 -249.464045)
			(xy 371.253149 -249.507622) (xy 371.223584 -249.546966) (xy 371.188091 -249.581058) (xy 371.147588 -249.609014)
			(xy 371.103126 -249.630112) (xy 371.055855 -249.643804) (xy 371.007 -249.649736) (xy 370.957825 -249.647755)
			(xy 370.909606 -249.637911) (xy 370.86359 -249.620459) (xy 370.820969 -249.595852) (xy 370.782848 -249.564727)
			(xy 370.750213 -249.52789) (xy 370.72391 -249.486294) (xy 370.704619 -249.441018) (xy 370.692842 -249.393234)
			(xy 370.688882 -249.34418) (xy 369.42014 -249.34418) (xy 369.419645 -249.368787) (xy 369.41175 -249.417364)
			(xy 369.396166 -249.464045) (xy 369.373295 -249.507622) (xy 369.34373 -249.546966) (xy 369.308237 -249.581058)
			(xy 369.267734 -249.609014) (xy 369.223272 -249.630112) (xy 369.176001 -249.643804) (xy 369.127146 -249.649736)
			(xy 369.077971 -249.647755) (xy 369.029752 -249.637911) (xy 368.983736 -249.620459) (xy 368.941115 -249.595852)
			(xy 368.902994 -249.564727) (xy 368.870359 -249.52789) (xy 368.844056 -249.486294) (xy 368.824765 -249.441018)
			(xy 368.812988 -249.393234) (xy 368.809028 -249.34418) (xy 367.540032 -249.34418) (xy 367.539537 -249.368787)
			(xy 367.531642 -249.417364) (xy 367.516058 -249.464045) (xy 367.493187 -249.507622) (xy 367.463622 -249.546966)
			(xy 367.428129 -249.581058) (xy 367.387626 -249.609014) (xy 367.343164 -249.630112) (xy 367.295893 -249.643804)
			(xy 367.247038 -249.649736) (xy 367.197863 -249.647755) (xy 367.149644 -249.637911) (xy 367.103628 -249.620459)
			(xy 367.061007 -249.595852) (xy 367.022886 -249.564727) (xy 366.990251 -249.52789) (xy 366.963948 -249.486294)
			(xy 366.944657 -249.441018) (xy 366.93288 -249.393234) (xy 366.92892 -249.34418) (xy 365.660178 -249.34418)
			(xy 365.659683 -249.368787) (xy 365.651788 -249.417364) (xy 365.636204 -249.464045) (xy 365.613333 -249.507622)
			(xy 365.583768 -249.546966) (xy 365.548275 -249.581058) (xy 365.507772 -249.609014) (xy 365.46331 -249.630112)
			(xy 365.416039 -249.643804) (xy 365.367184 -249.649736) (xy 365.318009 -249.647755) (xy 365.26979 -249.637911)
			(xy 365.223774 -249.620459) (xy 365.181153 -249.595852) (xy 365.143032 -249.564727) (xy 365.110397 -249.52789)
			(xy 365.084094 -249.486294) (xy 365.064803 -249.441018) (xy 365.053026 -249.393234) (xy 365.049066 -249.34418)
			(xy 363.78007 -249.34418) (xy 363.779575 -249.368787) (xy 363.77168 -249.417364) (xy 363.756096 -249.464045)
			(xy 363.733225 -249.507622) (xy 363.70366 -249.546966) (xy 363.668167 -249.581058) (xy 363.627664 -249.609014)
			(xy 363.583202 -249.630112) (xy 363.535931 -249.643804) (xy 363.487076 -249.649736) (xy 363.437901 -249.647755)
			(xy 363.389682 -249.637911) (xy 363.343666 -249.620459) (xy 363.301045 -249.595852) (xy 363.262924 -249.564727)
			(xy 363.230289 -249.52789) (xy 363.203986 -249.486294) (xy 363.184695 -249.441018) (xy 363.172918 -249.393234)
			(xy 363.168958 -249.34418) (xy 361.900216 -249.34418) (xy 361.899721 -249.368787) (xy 361.891826 -249.417364)
			(xy 361.876242 -249.464045) (xy 361.853371 -249.507622) (xy 361.823806 -249.546966) (xy 361.788313 -249.581058)
			(xy 361.74781 -249.609014) (xy 361.703348 -249.630112) (xy 361.656077 -249.643804) (xy 361.607222 -249.649736)
			(xy 361.558047 -249.647755) (xy 361.509828 -249.637911) (xy 361.463812 -249.620459) (xy 361.421191 -249.595852)
			(xy 361.38307 -249.564727) (xy 361.350435 -249.52789) (xy 361.324132 -249.486294) (xy 361.304841 -249.441018)
			(xy 361.293064 -249.393234) (xy 361.289104 -249.34418) (xy 360.083522 -249.34418) (xy 360.083862 -249.36196)
			(xy 360.083358 -249.388286) (xy 360.075321 -249.440322) (xy 360.059435 -249.490521) (xy 360.036072 -249.537706)
			(xy 360.00578 -249.580772) (xy 359.969268 -249.61871) (xy 359.927394 -249.650629) (xy 359.881138 -249.675782)
			(xy 359.831585 -249.69358) (xy 359.779895 -249.703604) (xy 359.727281 -249.705621) (xy 359.674976 -249.699583)
			(xy 359.624205 -249.685631) (xy 359.57616 -249.664092) (xy 359.531965 -249.635472) (xy 359.492657 -249.600441)
			(xy 359.459157 -249.55982) (xy 359.432251 -249.514561) (xy 359.412568 -249.465726) (xy 359.400571 -249.414458)
			(xy 359.396541 -249.36196) (xy 357.206192 -249.36196) (xy 357.206055 -249.368787) (xy 357.19816 -249.417364)
			(xy 357.182576 -249.464045) (xy 357.159705 -249.507622) (xy 357.13014 -249.546966) (xy 357.094647 -249.581058)
			(xy 357.054144 -249.609014) (xy 357.009682 -249.630112) (xy 356.962411 -249.643804) (xy 356.913556 -249.649736)
			(xy 356.864381 -249.647755) (xy 356.816162 -249.637911) (xy 356.770146 -249.620459) (xy 356.727525 -249.595852)
			(xy 356.689404 -249.564727) (xy 356.656769 -249.52789) (xy 356.630466 -249.486294) (xy 356.611175 -249.441018)
			(xy 356.599398 -249.393234) (xy 356.595438 -249.34418) (xy 355.326442 -249.34418) (xy 355.325947 -249.368787)
			(xy 355.318052 -249.417364) (xy 355.302468 -249.464045) (xy 355.279597 -249.507622) (xy 355.250032 -249.546966)
			(xy 355.214539 -249.581058) (xy 355.174036 -249.609014) (xy 355.129574 -249.630112) (xy 355.082303 -249.643804)
			(xy 355.033448 -249.649736) (xy 354.984273 -249.647755) (xy 354.936054 -249.637911) (xy 354.890038 -249.620459)
			(xy 354.847417 -249.595852) (xy 354.809296 -249.564727) (xy 354.776661 -249.52789) (xy 354.750358 -249.486294)
			(xy 354.731067 -249.441018) (xy 354.71929 -249.393234) (xy 354.71533 -249.34418) (xy 353.446334 -249.34418)
			(xy 353.445839 -249.368787) (xy 353.437944 -249.417364) (xy 353.42236 -249.464045) (xy 353.399489 -249.507622)
			(xy 353.369924 -249.546966) (xy 353.334431 -249.581058) (xy 353.293928 -249.609014) (xy 353.249466 -249.630112)
			(xy 353.202195 -249.643804) (xy 353.15334 -249.649736) (xy 353.104165 -249.647755) (xy 353.055946 -249.637911)
			(xy 353.00993 -249.620459) (xy 352.967309 -249.595852) (xy 352.929188 -249.564727) (xy 352.896553 -249.52789)
			(xy 352.87025 -249.486294) (xy 352.850959 -249.441018) (xy 352.839182 -249.393234) (xy 352.835222 -249.34418)
			(xy 351.56648 -249.34418) (xy 351.565985 -249.368787) (xy 351.55809 -249.417364) (xy 351.542506 -249.464045)
			(xy 351.519635 -249.507622) (xy 351.49007 -249.546966) (xy 351.454577 -249.581058) (xy 351.414074 -249.609014)
			(xy 351.369612 -249.630112) (xy 351.322341 -249.643804) (xy 351.273486 -249.649736) (xy 351.224311 -249.647755)
			(xy 351.176092 -249.637911) (xy 351.130076 -249.620459) (xy 351.087455 -249.595852) (xy 351.049334 -249.564727)
			(xy 351.016699 -249.52789) (xy 350.990396 -249.486294) (xy 350.971105 -249.441018) (xy 350.959328 -249.393234)
			(xy 350.955368 -249.34418) (xy 349.686372 -249.34418) (xy 349.685877 -249.368787) (xy 349.677982 -249.417364)
			(xy 349.662398 -249.464045) (xy 349.639527 -249.507622) (xy 349.609962 -249.546966) (xy 349.574469 -249.581058)
			(xy 349.533966 -249.609014) (xy 349.489504 -249.630112) (xy 349.442233 -249.643804) (xy 349.393378 -249.649736)
			(xy 349.344203 -249.647755) (xy 349.295984 -249.637911) (xy 349.249968 -249.620459) (xy 349.207347 -249.595852)
			(xy 349.169226 -249.564727) (xy 349.136591 -249.52789) (xy 349.110288 -249.486294) (xy 349.090997 -249.441018)
			(xy 349.07922 -249.393234) (xy 349.07526 -249.34418) (xy 347.806518 -249.34418) (xy 347.805892 -249.372116)
			(xy 347.795748 -249.427059) (xy 347.77581 -249.479252) (xy 347.761814 -249.503438) (xy 347.758258 -249.50928)
			(xy 347.754194 -249.52325) (xy 347.752009 -249.532046) (xy 347.753292 -249.550114) (xy 347.760764 -249.566614)
			(xy 347.766894 -249.573288) (xy 348.049088 -249.855482) (xy 348.059248 -249.861832) (xy 348.06509 -249.86361)
			(xy 348.087852 -249.871447) (xy 348.130762 -249.893262) (xy 348.169719 -249.921539) (xy 348.203758 -249.955577)
			(xy 348.232035 -249.994534) (xy 348.253852 -250.037444) (xy 348.261686 -250.060206) (xy 348.263464 -250.066048)
			(xy 348.269814 -250.076208) (xy 348.347792 -250.154186) (xy 349.545414 -250.154186) (xy 349.549374 -250.105132)
			(xy 349.561151 -250.057348) (xy 349.580442 -250.012072) (xy 349.606745 -249.970476) (xy 349.63938 -249.933639)
			(xy 349.677501 -249.902514) (xy 349.720122 -249.877907) (xy 349.766138 -249.860455) (xy 349.814357 -249.850611)
			(xy 349.863532 -249.84863) (xy 349.912387 -249.854562) (xy 349.959658 -249.868254) (xy 350.00412 -249.889352)
			(xy 350.044623 -249.917308) (xy 350.080116 -249.9514) (xy 350.109681 -249.990744) (xy 350.132552 -250.034321)
			(xy 350.148136 -250.081002) (xy 350.156031 -250.129579) (xy 350.156526 -250.154186) (xy 351.425268 -250.154186)
			(xy 351.429228 -250.105132) (xy 351.441005 -250.057348) (xy 351.460296 -250.012072) (xy 351.486599 -249.970476)
			(xy 351.519234 -249.933639) (xy 351.557355 -249.902514) (xy 351.599976 -249.877907) (xy 351.645992 -249.860455)
			(xy 351.694211 -249.850611) (xy 351.743386 -249.84863) (xy 351.792241 -249.854562) (xy 351.839512 -249.868254)
			(xy 351.883974 -249.889352) (xy 351.924477 -249.917308) (xy 351.95997 -249.9514) (xy 351.989535 -249.990744)
			(xy 352.012406 -250.034321) (xy 352.02799 -250.081002) (xy 352.035885 -250.129579) (xy 352.03638 -250.154186)
			(xy 353.305376 -250.154186) (xy 353.309336 -250.105132) (xy 353.321113 -250.057348) (xy 353.340404 -250.012072)
			(xy 353.366707 -249.970476) (xy 353.399342 -249.933639) (xy 353.437463 -249.902514) (xy 353.480084 -249.877907)
			(xy 353.5261 -249.860455) (xy 353.574319 -249.850611) (xy 353.623494 -249.84863) (xy 353.672349 -249.854562)
			(xy 353.71962 -249.868254) (xy 353.764082 -249.889352) (xy 353.804585 -249.917308) (xy 353.840078 -249.9514)
			(xy 353.869643 -249.990744) (xy 353.892514 -250.034321) (xy 353.908098 -250.081002) (xy 353.915993 -250.129579)
			(xy 353.916488 -250.154186) (xy 355.18523 -250.154186) (xy 355.18919 -250.105132) (xy 355.200967 -250.057348)
			(xy 355.220258 -250.012072) (xy 355.246561 -249.970476) (xy 355.279196 -249.933639) (xy 355.317317 -249.902514)
			(xy 355.359938 -249.877907) (xy 355.405954 -249.860455) (xy 355.454173 -249.850611) (xy 355.503348 -249.84863)
			(xy 355.552203 -249.854562) (xy 355.599474 -249.868254) (xy 355.643936 -249.889352) (xy 355.684439 -249.917308)
			(xy 355.719932 -249.9514) (xy 355.749497 -249.990744) (xy 355.772368 -250.034321) (xy 355.787952 -250.081002)
			(xy 355.795847 -250.129579) (xy 355.796342 -250.154186) (xy 355.795847 -250.178793) (xy 355.787952 -250.22737)
			(xy 355.772368 -250.274051) (xy 355.749497 -250.317628) (xy 355.719932 -250.356972) (xy 355.684439 -250.391064)
			(xy 355.643936 -250.41902) (xy 355.599474 -250.440118) (xy 355.552203 -250.45381) (xy 355.503348 -250.459742)
			(xy 355.454173 -250.457761) (xy 355.405954 -250.447917) (xy 355.359938 -250.430465) (xy 355.317317 -250.405858)
			(xy 355.279196 -250.374733) (xy 355.246561 -250.337896) (xy 355.220258 -250.2963) (xy 355.200967 -250.251024)
			(xy 355.18919 -250.20324) (xy 355.18523 -250.154186) (xy 353.916488 -250.154186) (xy 353.915993 -250.178793)
			(xy 353.908098 -250.22737) (xy 353.892514 -250.274051) (xy 353.869643 -250.317628) (xy 353.840078 -250.356972)
			(xy 353.804585 -250.391064) (xy 353.764082 -250.41902) (xy 353.71962 -250.440118) (xy 353.672349 -250.45381)
			(xy 353.623494 -250.459742) (xy 353.574319 -250.457761) (xy 353.5261 -250.447917) (xy 353.480084 -250.430465)
			(xy 353.437463 -250.405858) (xy 353.399342 -250.374733) (xy 353.366707 -250.337896) (xy 353.340404 -250.2963)
			(xy 353.321113 -250.251024) (xy 353.309336 -250.20324) (xy 353.305376 -250.154186) (xy 352.03638 -250.154186)
			(xy 352.035885 -250.178793) (xy 352.02799 -250.22737) (xy 352.012406 -250.274051) (xy 351.989535 -250.317628)
			(xy 351.95997 -250.356972) (xy 351.924477 -250.391064) (xy 351.883974 -250.41902) (xy 351.839512 -250.440118)
			(xy 351.792241 -250.45381) (xy 351.743386 -250.459742) (xy 351.694211 -250.457761) (xy 351.645992 -250.447917)
			(xy 351.599976 -250.430465) (xy 351.557355 -250.405858) (xy 351.519234 -250.374733) (xy 351.486599 -250.337896)
			(xy 351.460296 -250.2963) (xy 351.441005 -250.251024) (xy 351.429228 -250.20324) (xy 351.425268 -250.154186)
			(xy 350.156526 -250.154186) (xy 350.156031 -250.178793) (xy 350.148136 -250.22737) (xy 350.132552 -250.274051)
			(xy 350.109681 -250.317628) (xy 350.080116 -250.356972) (xy 350.044623 -250.391064) (xy 350.00412 -250.41902)
			(xy 349.959658 -250.440118) (xy 349.912387 -250.45381) (xy 349.863532 -250.459742) (xy 349.814357 -250.457761)
			(xy 349.766138 -250.447917) (xy 349.720122 -250.430465) (xy 349.677501 -250.405858) (xy 349.63938 -250.374733)
			(xy 349.606745 -250.337896) (xy 349.580442 -250.2963) (xy 349.561151 -250.251024) (xy 349.549374 -250.20324)
			(xy 349.545414 -250.154186) (xy 348.347792 -250.154186) (xy 348.586552 -250.392946) (xy 348.593951 -250.39979)
			(xy 348.61255 -250.407514) (xy 348.62262 -250.407932) (xy 349.028004 -250.407932) (xy 349.037846 -250.408457)
			(xy 349.056021 -250.416031) (xy 349.06331 -250.422664) (xy 349.297752 -250.657106) (xy 349.320612 -250.664472)
			(xy 349.332804 -250.662694) (xy 349.344789 -250.660909) (xy 349.368947 -250.659005) (xy 349.381064 -250.658884)
			(xy 349.405059 -250.659327) (xy 349.45246 -250.66683) (xy 349.498103 -250.681655) (xy 349.540864 -250.703438)
			(xy 349.579692 -250.731643) (xy 349.613628 -250.765575) (xy 349.641839 -250.804398) (xy 349.663628 -250.847157)
			(xy 349.67846 -250.892798) (xy 349.685969 -250.940197) (xy 349.686372 -250.964192) (xy 349.686265 -250.976309)
			(xy 349.684357 -251.000468) (xy 349.682562 -251.012452) (xy 349.680784 -251.024644) (xy 349.68815 -251.047504)
			(xy 349.765112 -251.124466) (xy 349.77251 -251.131314) (xy 349.791108 -251.13905) (xy 349.80118 -251.139452)
			(xy 350.862392 -251.139452) (xy 350.873589 -251.138865) (xy 350.893874 -251.129377) (xy 350.901508 -251.121164)
			(xy 350.950022 -251.06249) (xy 350.956173 -251.054557) (xy 350.962211 -251.03543) (xy 350.961706 -251.025406)
			(xy 350.961198 -251.021342) (xy 350.960944 -251.019056) (xy 350.958598 -251.005461) (xy 350.956054 -250.977987)
			(xy 350.955864 -250.964192) (xy 350.956386 -250.938937) (xy 350.964699 -250.889115) (xy 350.9811 -250.841341)
			(xy 351.005141 -250.796918) (xy 351.036165 -250.757058) (xy 351.073327 -250.722848) (xy 351.115613 -250.695222)
			(xy 351.161869 -250.674932) (xy 351.210834 -250.662532) (xy 351.261172 -250.658361) (xy 351.31151 -250.662532)
			(xy 351.360475 -250.674932) (xy 351.406731 -250.695222) (xy 351.449017 -250.722848) (xy 351.486179 -250.757058)
			(xy 351.517203 -250.796918) (xy 351.541244 -250.841341) (xy 351.557645 -250.889115) (xy 351.565958 -250.938937)
			(xy 351.56648 -250.964192) (xy 351.566294 -250.978374) (xy 351.563621 -251.006614) (xy 351.561146 -251.02058)
			(xy 351.559114 -251.031756) (xy 351.564702 -251.053346) (xy 351.620836 -251.121164) (xy 351.628446 -251.129404)
			(xy 351.648748 -251.138875) (xy 351.659952 -251.139452) (xy 352.742246 -251.139452) (xy 352.753447 -251.138874)
			(xy 352.773747 -251.129397) (xy 352.781362 -251.121164) (xy 352.829876 -251.06249) (xy 352.836032 -251.054559)
			(xy 352.842076 -251.035431) (xy 352.84156 -251.025406) (xy 352.841052 -251.021342) (xy 352.840798 -251.019056)
			(xy 352.838447 -251.005461) (xy 352.835902 -250.977987) (xy 352.835718 -250.964192) (xy 352.83624 -250.938937)
			(xy 352.844553 -250.889115) (xy 352.860954 -250.841341) (xy 352.884995 -250.796918) (xy 352.916019 -250.757058)
			(xy 352.953181 -250.722848) (xy 352.995467 -250.695222) (xy 353.041723 -250.674932) (xy 353.090688 -250.662532)
			(xy 353.141026 -250.658361) (xy 353.191364 -250.662532) (xy 353.240329 -250.674932) (xy 353.286585 -250.695222)
			(xy 353.328871 -250.722848) (xy 353.366033 -250.757058) (xy 353.397057 -250.796918) (xy 353.421098 -250.841341)
			(xy 353.437499 -250.889115) (xy 353.445812 -250.938937) (xy 353.446334 -250.964192) (xy 353.446148 -250.978374)
			(xy 353.443475 -251.006614) (xy 353.441 -251.02058) (xy 353.438968 -251.031756) (xy 353.444556 -251.053346)
			(xy 353.50069 -251.121164) (xy 353.508297 -251.129412) (xy 353.528599 -251.138901) (xy 353.539806 -251.139452)
			(xy 354.622354 -251.139452) (xy 354.633554 -251.138872) (xy 354.653852 -251.129394) (xy 354.66147 -251.121164)
			(xy 354.709984 -251.06249) (xy 354.716139 -251.054558) (xy 354.722182 -251.035431) (xy 354.721668 -251.025406)
			(xy 354.72116 -251.021342) (xy 354.720906 -251.019056) (xy 354.71856 -251.005461) (xy 354.716016 -250.977987)
			(xy 354.715826 -250.964192) (xy 354.716348 -250.938937) (xy 354.724661 -250.889115) (xy 354.741062 -250.841341)
			(xy 354.765103 -250.796918) (xy 354.796127 -250.757058) (xy 354.833289 -250.722848) (xy 354.875575 -250.695222)
			(xy 354.921831 -250.674932) (xy 354.970796 -250.662532) (xy 355.021134 -250.658361) (xy 355.071472 -250.662532)
			(xy 355.120437 -250.674932) (xy 355.166693 -250.695222) (xy 355.208979 -250.722848) (xy 355.246141 -250.757058)
			(xy 355.277165 -250.796918) (xy 355.301206 -250.841341) (xy 355.317607 -250.889115) (xy 355.32592 -250.938937)
			(xy 355.326442 -250.964192) (xy 355.326256 -250.978374) (xy 355.323583 -251.006614) (xy 355.321108 -251.02058)
			(xy 355.319076 -251.031756) (xy 355.324664 -251.053346) (xy 355.380798 -251.121164) (xy 355.388406 -251.129411)
			(xy 355.408707 -251.138896) (xy 355.419914 -251.139452) (xy 356.427024 -251.139452) (xy 356.436866 -251.138925)
			(xy 356.455044 -251.131356) (xy 356.46233 -251.12472) (xy 356.580948 -251.006102) (xy 356.5878 -250.998706)
			(xy 356.595544 -250.980108) (xy 356.595934 -250.970034) (xy 356.595934 -250.964192) (xy 356.596381 -250.9402)
			(xy 356.603889 -250.892808) (xy 356.618719 -250.847174) (xy 356.640505 -250.804423) (xy 356.668712 -250.765605)
			(xy 356.702643 -250.731679) (xy 356.741465 -250.703479) (xy 356.784221 -250.681699) (xy 356.829857 -250.666877)
			(xy 356.87725 -250.659377) (xy 356.901242 -250.658884) (xy 356.907084 -250.658884) (xy 356.917147 -250.658445)
			(xy 356.935728 -250.650707) (xy 356.943152 -250.643898) (xy 357.027226 -250.559824) (xy 357.034463 -250.553109)
			(xy 357.052669 -250.545515) (xy 357.062532 -250.545092) (xy 357.088186 -250.545092) (xy 357.098308 -250.544706)
			(xy 357.117004 -250.53696) (xy 357.131222 -250.522558) (xy 357.13543 -250.513342) (xy 357.175562 -250.413774)
			(xy 357.169212 -250.383802) (xy 357.158036 -250.37288) (xy 357.140917 -250.355506) (xy 357.111868 -250.316328)
			(xy 357.089406 -250.273034) (xy 357.074103 -250.226724) (xy 357.066346 -250.178572) (xy 357.065834 -250.154186)
			(xy 357.066356 -250.128931) (xy 357.074669 -250.079109) (xy 357.09107 -250.031335) (xy 357.115111 -249.986912)
			(xy 357.146135 -249.947052) (xy 357.183297 -249.912842) (xy 357.225583 -249.885216) (xy 357.271839 -249.864926)
			(xy 357.320804 -249.852526) (xy 357.371142 -249.848355) (xy 357.42148 -249.852526) (xy 357.470445 -249.864926)
			(xy 357.516701 -249.885216) (xy 357.558987 -249.912842) (xy 357.596149 -249.947052) (xy 357.627173 -249.986912)
			(xy 357.651214 -250.031335) (xy 357.667615 -250.079109) (xy 357.675928 -250.128931) (xy 357.67645 -250.154186)
			(xy 357.675974 -250.178574) (xy 357.668222 -250.226731) (xy 357.652913 -250.273043) (xy 357.630436 -250.316333)
			(xy 357.601363 -250.355498) (xy 357.584248 -250.37288) (xy 357.573072 -250.383802) (xy 357.566722 -250.413774)
			(xy 357.606854 -250.513342) (xy 357.611068 -250.522546) (xy 357.625313 -250.536905) (xy 357.643985 -250.544683)
			(xy 357.654098 -250.545092) (xy 360.841798 -250.545092) (xy 360.851918 -250.544704) (xy 360.870611 -250.536955)
			(xy 360.884825 -250.522553) (xy 360.889042 -250.513342) (xy 360.929174 -250.413774) (xy 360.922824 -250.383802)
			(xy 360.911648 -250.37288) (xy 360.894529 -250.355506) (xy 360.865478 -250.316328) (xy 360.843016 -250.273035)
			(xy 360.827712 -250.226725) (xy 360.819955 -250.178573) (xy 360.819446 -250.154186) (xy 360.819968 -250.128931)
			(xy 360.828281 -250.079109) (xy 360.844682 -250.031335) (xy 360.868723 -249.986912) (xy 360.899747 -249.947052)
			(xy 360.936909 -249.912842) (xy 360.979195 -249.885216) (xy 361.025451 -249.864926) (xy 361.074416 -249.852526)
			(xy 361.124754 -249.848355) (xy 361.175092 -249.852526) (xy 361.224057 -249.864926) (xy 361.270313 -249.885216)
			(xy 361.312599 -249.912842) (xy 361.349761 -249.947052) (xy 361.380785 -249.986912) (xy 361.404826 -250.031335)
			(xy 361.421227 -250.079109) (xy 361.42954 -250.128931) (xy 361.430062 -250.154186) (xy 361.429586 -250.178575)
			(xy 361.421834 -250.226732) (xy 361.406525 -250.273044) (xy 361.384049 -250.316334) (xy 361.354977 -250.3555)
			(xy 361.33786 -250.37288) (xy 361.326684 -250.383802) (xy 361.320334 -250.413774) (xy 361.360466 -250.513342)
			(xy 361.364681 -250.522544) (xy 361.378927 -250.5369) (xy 361.397598 -250.544673) (xy 361.40771 -250.545092)
			(xy 362.721906 -250.545092) (xy 362.732025 -250.544703) (xy 362.750716 -250.536952) (xy 362.764927 -250.522549)
			(xy 362.76915 -250.513342) (xy 362.809282 -250.413774) (xy 362.802932 -250.383802) (xy 362.791756 -250.37288)
			(xy 362.774636 -250.355506) (xy 362.745585 -250.316329) (xy 362.723122 -250.273036) (xy 362.707818 -250.226725)
			(xy 362.70006 -250.178573) (xy 362.699554 -250.154186) (xy 362.700076 -250.128931) (xy 362.708389 -250.079109)
			(xy 362.72479 -250.031335) (xy 362.748831 -249.986912) (xy 362.779855 -249.947052) (xy 362.817017 -249.912842)
			(xy 362.859303 -249.885216) (xy 362.905559 -249.864926) (xy 362.954524 -249.852526) (xy 363.004862 -249.848355)
			(xy 363.0552 -249.852526) (xy 363.104165 -249.864926) (xy 363.150421 -249.885216) (xy 363.192707 -249.912842)
			(xy 363.229869 -249.947052) (xy 363.260893 -249.986912) (xy 363.284934 -250.031335) (xy 363.301335 -250.079109)
			(xy 363.309648 -250.128931) (xy 363.31017 -250.154186) (xy 364.578912 -250.154186) (xy 364.582872 -250.105132)
			(xy 364.594649 -250.057348) (xy 364.61394 -250.012072) (xy 364.640243 -249.970476) (xy 364.672878 -249.933639)
			(xy 364.710999 -249.902514) (xy 364.75362 -249.877907) (xy 364.799636 -249.860455) (xy 364.847855 -249.850611)
			(xy 364.89703 -249.84863) (xy 364.945885 -249.854562) (xy 364.993156 -249.868254) (xy 365.037618 -249.889352)
			(xy 365.078121 -249.917308) (xy 365.113614 -249.9514) (xy 365.143179 -249.990744) (xy 365.16605 -250.034321)
			(xy 365.181634 -250.081002) (xy 365.189529 -250.129579) (xy 365.190024 -250.154186) (xy 365.189529 -250.178793)
			(xy 365.181634 -250.22737) (xy 365.16605 -250.274051) (xy 365.143179 -250.317628) (xy 365.113614 -250.356972)
			(xy 365.078121 -250.391064) (xy 365.037618 -250.41902) (xy 364.993156 -250.440118) (xy 364.945885 -250.45381)
			(xy 364.89703 -250.459742) (xy 364.847855 -250.457761) (xy 364.799636 -250.447917) (xy 364.75362 -250.430465)
			(xy 364.710999 -250.405858) (xy 364.672878 -250.374733) (xy 364.640243 -250.337896) (xy 364.61394 -250.2963)
			(xy 364.594649 -250.251024) (xy 364.582872 -250.20324) (xy 364.578912 -250.154186) (xy 363.31017 -250.154186)
			(xy 363.309694 -250.178575) (xy 363.301942 -250.226732) (xy 363.286634 -250.273045) (xy 363.264158 -250.316335)
			(xy 363.235087 -250.355502) (xy 363.217968 -250.37288) (xy 363.206792 -250.383802) (xy 363.200442 -250.413774)
			(xy 363.240574 -250.513342) (xy 363.244789 -250.522543) (xy 363.259036 -250.536897) (xy 363.277706 -250.544668)
			(xy 363.287818 -250.545092) (xy 363.574584 -250.545092) (xy 363.584421 -250.54563) (xy 363.602579 -250.55322)
			(xy 363.60989 -250.559824) (xy 364.174532 -251.124466) (xy 364.181931 -251.131311) (xy 364.200529 -251.139039)
			(xy 364.2106 -251.139452) (xy 364.882684 -251.139452) (xy 364.892521 -251.138915) (xy 364.910684 -251.13133)
			(xy 364.91799 -251.12472) (xy 365.042196 -251.000514) (xy 365.049816 -250.981464) (xy 365.049562 -250.971304)
			(xy 365.049562 -250.964192) (xy 365.050033 -250.9402) (xy 365.05754 -250.892808) (xy 365.072368 -250.847173)
			(xy 365.094151 -250.804419) (xy 365.122354 -250.765599) (xy 365.156282 -250.731669) (xy 365.1951 -250.703463)
			(xy 365.237853 -250.681676) (xy 365.283486 -250.666845) (xy 365.330878 -250.659335) (xy 365.35487 -250.658884)
			(xy 365.361982 -250.658884) (xy 365.372142 -250.659138) (xy 365.391192 -250.651518) (xy 365.482886 -250.559824)
			(xy 365.490121 -250.553103) (xy 365.508326 -250.545494) (xy 365.518192 -250.545092) (xy 366.481868 -250.545092)
			(xy 366.491992 -250.544709) (xy 366.510694 -250.536967) (xy 366.524918 -250.522565) (xy 366.529112 -250.513342)
			(xy 366.569244 -250.413774) (xy 366.562894 -250.383802) (xy 366.551718 -250.37288) (xy 366.534596 -250.355507)
			(xy 366.505538 -250.316332) (xy 366.483071 -250.273039) (xy 366.467763 -250.226728) (xy 366.460004 -250.178574)
			(xy 366.459516 -250.154186) (xy 366.460038 -250.128931) (xy 366.468351 -250.079109) (xy 366.484752 -250.031335)
			(xy 366.508793 -249.986912) (xy 366.539817 -249.947052) (xy 366.576979 -249.912842) (xy 366.619265 -249.885216)
			(xy 366.665521 -249.864926) (xy 366.714486 -249.852526) (xy 366.764824 -249.848355) (xy 366.815162 -249.852526)
			(xy 366.864127 -249.864926) (xy 366.910383 -249.885216) (xy 366.952669 -249.912842) (xy 366.989831 -249.947052)
			(xy 367.020855 -249.986912) (xy 367.044896 -250.031335) (xy 367.061297 -250.079109) (xy 367.06961 -250.128931)
			(xy 367.070132 -250.154186) (xy 368.338874 -250.154186) (xy 368.342834 -250.105132) (xy 368.354611 -250.057348)
			(xy 368.373902 -250.012072) (xy 368.400205 -249.970476) (xy 368.43284 -249.933639) (xy 368.470961 -249.902514)
			(xy 368.513582 -249.877907) (xy 368.559598 -249.860455) (xy 368.607817 -249.850611) (xy 368.656992 -249.84863)
			(xy 368.705847 -249.854562) (xy 368.753118 -249.868254) (xy 368.79758 -249.889352) (xy 368.838083 -249.917308)
			(xy 368.873576 -249.9514) (xy 368.903141 -249.990744) (xy 368.926012 -250.034321) (xy 368.941596 -250.081002)
			(xy 368.949491 -250.129579) (xy 368.949986 -250.154186) (xy 368.949491 -250.178793) (xy 368.941596 -250.22737)
			(xy 368.926012 -250.274051) (xy 368.903141 -250.317628) (xy 368.873576 -250.356972) (xy 368.838083 -250.391064)
			(xy 368.79758 -250.41902) (xy 368.753118 -250.440118) (xy 368.705847 -250.45381) (xy 368.656992 -250.459742)
			(xy 368.607817 -250.457761) (xy 368.559598 -250.447917) (xy 368.513582 -250.430465) (xy 368.470961 -250.405858)
			(xy 368.43284 -250.374733) (xy 368.400205 -250.337896) (xy 368.373902 -250.2963) (xy 368.354611 -250.251024)
			(xy 368.342834 -250.20324) (xy 368.338874 -250.154186) (xy 367.070132 -250.154186) (xy 367.069666 -250.178435)
			(xy 367.062 -250.226322) (xy 367.046857 -250.272395) (xy 367.02462 -250.315494) (xy 366.995847 -250.354533)
			(xy 366.961263 -250.388532) (xy 366.921737 -250.416635) (xy 366.878265 -250.438133) (xy 366.855248 -250.445778)
			(xy 366.839246 -250.450858) (xy 366.819688 -250.477528) (xy 366.819688 -250.494292) (xy 366.820175 -250.504302)
			(xy 366.827832 -250.522798) (xy 366.841985 -250.536956) (xy 366.860479 -250.544621) (xy 366.870488 -250.545092)
			(xy 366.919764 -250.545092) (xy 366.929602 -250.545626) (xy 366.947766 -250.553211) (xy 366.95507 -250.559824)
			(xy 367.075974 -250.680728) (xy 367.105946 -250.686824) (xy 367.12017 -250.681236) (xy 367.14766 -250.670834)
			(xy 367.20534 -250.65957) (xy 367.234724 -250.658884) (xy 367.23955 -250.658884) (xy 367.263052 -250.65969)
			(xy 367.309398 -250.667636) (xy 367.353979 -250.682593) (xy 367.39574 -250.704207) (xy 367.433693 -250.731968)
			(xy 367.466942 -250.765219) (xy 367.494701 -250.803174) (xy 367.516313 -250.844936) (xy 367.531268 -250.889518)
			(xy 367.539211 -250.935865) (xy 367.540032 -250.959366) (xy 367.540032 -250.96343) (xy 367.539415 -250.993008)
			(xy 367.528158 -251.051079) (xy 367.51768 -251.078746) (xy 367.512092 -251.09297) (xy 367.518188 -251.122942)
			(xy 367.565432 -251.170186) (xy 367.572832 -251.177029) (xy 367.59143 -251.184754) (xy 367.6015 -251.185172)
		)
		(stroke
			(width 0)
			(type solid)
		)
		(fill yes)
		(layer "In2.Cu")
		(net "PVDDCR_CPU0_P0")
	)
	(gr_poly
		(pts
			(xy 116.747036 -251.248164) (xy 116.752055 -251.248073) (xy 116.761908 -251.246154) (xy 116.766594 -251.244354)
			(xy 116.775484 -251.240544) (xy 117.106192 -250.909836) (xy 117.11432 -250.899168) (xy 117.117622 -250.89358)
			(xy 117.1194 -250.886722) (xy 117.125671 -250.864529) (xy 117.143971 -250.822198) (xy 117.168427 -250.783099)
			(xy 117.198483 -250.748121) (xy 117.233455 -250.718059) (xy 117.27255 -250.693596) (xy 117.314878 -250.675289)
			(xy 117.337078 -250.669044) (xy 117.343936 -250.667266) (xy 117.349524 -250.663964) (xy 117.360192 -250.655836)
			(xy 117.565932 -250.450096) (xy 117.573171 -250.443385) (xy 117.591376 -250.435797) (xy 117.601238 -250.435364)
			(xy 118.46179 -250.435364) (xy 118.468163 -250.435134) (xy 118.4805 -250.431925) (xy 118.486174 -250.429014)
			(xy 118.491508 -250.42622) (xy 118.500906 -250.41733) (xy 118.536212 -250.360688) (xy 118.536212 -250.36018)
			(xy 118.544594 -250.346718) (xy 118.54778 -250.340926) (xy 118.551269 -250.32818) (xy 118.551452 -250.321572)
			(xy 118.551452 -250.291092) (xy 118.549166 -250.286012) (xy 118.54688 -250.281186) (xy 118.538325 -250.261512)
			(xy 118.526195 -250.220362) (xy 118.519944 -250.17792) (xy 118.519448 -250.156472) (xy 118.519448 -250.149614)
			(xy 118.520272 -250.12587) (xy 118.528366 -250.079058) (xy 118.543614 -250.034064) (xy 118.565647 -249.991975)
			(xy 118.593935 -249.953807) (xy 118.627793 -249.920482) (xy 118.666404 -249.892804) (xy 118.708837 -249.871441)
			(xy 118.754067 -249.856909) (xy 118.801002 -249.849558) (xy 118.824756 -249.849132) (xy 118.84875 -249.849575)
			(xy 118.896149 -249.857076) (xy 118.94179 -249.871902) (xy 118.984549 -249.893685) (xy 119.023373 -249.921891)
			(xy 119.057307 -249.955824) (xy 119.085513 -249.994648) (xy 119.107297 -250.037407) (xy 119.122123 -250.083047)
			(xy 119.129625 -250.130446) (xy 119.130064 -250.15444) (xy 120.398806 -250.15444) (xy 120.402766 -250.105386)
			(xy 120.414543 -250.057602) (xy 120.433834 -250.012326) (xy 120.460137 -249.97073) (xy 120.492772 -249.933893)
			(xy 120.530893 -249.902768) (xy 120.573514 -249.878161) (xy 120.61953 -249.860709) (xy 120.667749 -249.850865)
			(xy 120.716924 -249.848884) (xy 120.765779 -249.854816) (xy 120.81305 -249.868508) (xy 120.857512 -249.889606)
			(xy 120.898015 -249.917562) (xy 120.933508 -249.951654) (xy 120.963073 -249.990998) (xy 120.985944 -250.034575)
			(xy 121.001528 -250.081256) (xy 121.009423 -250.129833) (xy 121.009918 -250.15444) (xy 121.009423 -250.179047)
			(xy 121.001528 -250.227624) (xy 120.985944 -250.274305) (xy 120.963073 -250.317882) (xy 120.933508 -250.357226)
			(xy 120.898015 -250.391318) (xy 120.857512 -250.419274) (xy 120.81305 -250.440372) (xy 120.765779 -250.454064)
			(xy 120.716924 -250.459996) (xy 120.667749 -250.458015) (xy 120.61953 -250.448171) (xy 120.573514 -250.430719)
			(xy 120.530893 -250.406112) (xy 120.492772 -250.374987) (xy 120.460137 -250.33815) (xy 120.433834 -250.296554)
			(xy 120.414543 -250.251278) (xy 120.402766 -250.203494) (xy 120.398806 -250.15444) (xy 119.130064 -250.15444)
			(xy 119.129655 -250.177014) (xy 119.123004 -250.221671) (xy 119.109852 -250.264861) (xy 119.090485 -250.305646)
			(xy 119.078248 -250.32462) (xy 119.074184 -250.330716) (xy 119.06885 -250.347226) (xy 119.066529 -250.355787)
			(xy 119.067448 -250.373489) (xy 119.070628 -250.38177) (xy 119.082058 -250.407424) (xy 119.086506 -250.415647)
			(xy 119.10026 -250.428288) (xy 119.117674 -250.435052) (xy 119.127016 -250.435364) (xy 119.130064 -250.435364)
			(xy 119.346472 -250.651772) (xy 119.35714 -250.6599) (xy 119.373396 -250.669298) (xy 119.379492 -250.671076)
			(xy 119.404001 -250.678709) (xy 119.450232 -250.701007) (xy 119.492085 -250.730722) (xy 119.528379 -250.767017)
			(xy 119.558094 -250.80887) (xy 119.580392 -250.855102) (xy 119.588026 -250.87961) (xy 119.589804 -250.885706)
			(xy 119.599202 -250.901962) (xy 119.60733 -250.91263) (xy 119.902732 -251.208032) (xy 119.906349 -251.211466)
			(xy 119.914667 -251.216967) (xy 119.919242 -251.218954) (xy 119.928132 -251.222764) (xy 120.480836 -251.222764)
			(xy 120.485855 -251.222673) (xy 120.495708 -251.220754) (xy 120.500394 -251.218954) (xy 120.509284 -251.215144)
			(xy 120.907302 -250.817126) (xy 120.910604 -250.811538) (xy 120.92439 -250.788852) (xy 120.958517 -250.748196)
			(xy 120.99916 -250.714054) (xy 121.021856 -250.700286) (xy 121.027444 -250.696984) (xy 121.147332 -250.577096)
			(xy 121.154571 -250.570385) (xy 121.172776 -250.562797) (xy 121.182638 -250.562364) (xy 121.372884 -250.562364)
			(xy 121.377456 -250.56211) (xy 121.382181 -250.561426) (xy 121.391261 -250.558482) (xy 121.39549 -250.556268)
			(xy 121.395998 -250.556268) (xy 121.405904 -250.549156) (xy 121.442988 -250.511818) (xy 121.450239 -250.50527)
			(xy 121.468281 -250.49783) (xy 121.47804 -250.49734) (xy 122.259598 -250.49734) (xy 122.265948 -250.496832)
			(xy 122.277989 -250.494512) (xy 122.298024 -250.480442) (xy 122.304302 -250.469908) (xy 122.333766 -250.41098)
			(xy 122.344688 -250.38939) (xy 122.347591 -250.383071) (xy 122.350163 -250.369409) (xy 122.349768 -250.362466)
			(xy 122.348752 -250.349004) (xy 122.340116 -250.337066) (xy 122.339608 -250.336558) (xy 122.325448 -250.316679)
			(xy 122.302963 -250.273364) (xy 122.287651 -250.227026) (xy 122.279901 -250.178842) (xy 122.27941 -250.15444)
			(xy 122.279893 -250.12962) (xy 122.287917 -250.080634) (xy 122.303761 -250.03359) (xy 122.327007 -249.98973)
			(xy 122.357043 -249.950209) (xy 122.393077 -249.916068) (xy 122.43416 -249.888206) (xy 122.479209 -249.867358)
			(xy 122.527038 -249.854072) (xy 122.576386 -249.8487) (xy 122.625953 -249.851382) (xy 122.674433 -249.862048)
			(xy 122.720549 -249.880417) (xy 122.763085 -249.906005) (xy 122.800922 -249.938137) (xy 122.833061 -249.975967)
			(xy 122.858657 -250.018499) (xy 122.877035 -250.064611) (xy 122.88771 -250.113089) (xy 122.889956 -250.15444)
			(xy 124.159022 -250.15444) (xy 124.162982 -250.105386) (xy 124.174759 -250.057602) (xy 124.19405 -250.012326)
			(xy 124.220353 -249.97073) (xy 124.252988 -249.933893) (xy 124.291109 -249.902768) (xy 124.33373 -249.878161)
			(xy 124.379746 -249.860709) (xy 124.427965 -249.850865) (xy 124.47714 -249.848884) (xy 124.525995 -249.854816)
			(xy 124.573266 -249.868508) (xy 124.617728 -249.889606) (xy 124.658231 -249.917562) (xy 124.693724 -249.951654)
			(xy 124.723289 -249.990998) (xy 124.74616 -250.034575) (xy 124.761744 -250.081256) (xy 124.769639 -250.129833)
			(xy 124.770134 -250.15444) (xy 124.769639 -250.179047) (xy 124.761744 -250.227624) (xy 124.74616 -250.274305)
			(xy 124.723289 -250.317882) (xy 124.693724 -250.357226) (xy 124.658231 -250.391318) (xy 124.617728 -250.419274)
			(xy 124.573266 -250.440372) (xy 124.525995 -250.454064) (xy 124.47714 -250.459996) (xy 124.427965 -250.458015)
			(xy 124.379746 -250.448171) (xy 124.33373 -250.430719) (xy 124.291109 -250.406112) (xy 124.252988 -250.374987)
			(xy 124.220353 -250.33815) (xy 124.19405 -250.296554) (xy 124.174759 -250.251278) (xy 124.162982 -250.203494)
			(xy 124.159022 -250.15444) (xy 122.889956 -250.15444) (xy 122.890402 -250.162656) (xy 122.885039 -250.212005)
			(xy 122.871762 -250.259836) (xy 122.850923 -250.304889) (xy 122.823069 -250.345978) (xy 122.788934 -250.382018)
			(xy 122.749419 -250.412061) (xy 122.705563 -250.435316) (xy 122.658523 -250.451169) (xy 122.609538 -250.459203)
			(xy 122.584718 -250.459748) (xy 122.576082 -250.459748) (xy 122.570494 -250.459494) (xy 122.563714 -250.460094)
			(xy 122.550831 -250.464468) (xy 122.545094 -250.46813) (xy 122.531886 -250.481084) (xy 122.525721 -250.491028)
			(xy 122.52237 -250.514155) (xy 122.529701 -250.536344) (xy 122.537474 -250.545092) (xy 122.540014 -250.547632)
			(xy 122.543631 -250.551067) (xy 122.551947 -250.556571) (xy 122.556524 -250.558554) (xy 122.565414 -250.562364)
			(xy 122.79249 -250.562364) (xy 122.802327 -250.562903) (xy 122.820486 -250.570491) (xy 122.827796 -250.577096)
			(xy 122.91187 -250.66117) (xy 122.919135 -250.667815) (xy 122.937338 -250.675274) (xy 122.947176 -250.675648)
			(xy 122.950986 -250.675648) (xy 122.959114 -250.674378) (xy 122.960384 -250.674124) (xy 122.963178 -250.673108)
			(xy 122.985473 -250.666585) (xy 123.031392 -250.659567) (xy 123.054618 -250.659138) (xy 123.05665 -250.659138)
			(xy 123.080433 -250.659752) (xy 123.12738 -250.667448) (xy 123.172565 -250.682333) (xy 123.214893 -250.704047)
			(xy 123.253341 -250.732065) (xy 123.286977 -250.765708) (xy 123.314987 -250.804162) (xy 123.336692 -250.846495)
			(xy 123.351567 -250.891683) (xy 123.359253 -250.938631) (xy 123.359926 -250.962414) (xy 123.359926 -250.963176)
			(xy 123.359556 -250.986858) (xy 123.35241 -251.033678) (xy 123.345702 -251.056394) (xy 123.343416 -251.06376)
			(xy 123.343416 -251.072142) (xy 123.343929 -251.081892) (xy 123.351378 -251.099922) (xy 123.357894 -251.107194)
			(xy 123.484132 -251.233432) (xy 123.487749 -251.236866) (xy 123.496067 -251.242367) (xy 123.500642 -251.244354)
			(xy 123.509532 -251.248164) (xy 124.265436 -251.248164) (xy 124.270455 -251.248073) (xy 124.280308 -251.246154)
			(xy 124.284994 -251.244354) (xy 124.293884 -251.240544) (xy 124.626878 -250.90755) (xy 124.635006 -250.896882)
			(xy 124.6378 -250.892056) (xy 124.639832 -250.884944) (xy 124.647306 -250.859416) (xy 124.669828 -250.811234)
			(xy 124.700354 -250.76768) (xy 124.737961 -250.73007) (xy 124.781512 -250.69954) (xy 124.829693 -250.677014)
			(xy 124.855224 -250.669552) (xy 124.862336 -250.66752) (xy 124.867162 -250.664726) (xy 124.87783 -250.656598)
			(xy 125.160532 -250.373896) (xy 125.167771 -250.367185) (xy 125.185976 -250.359597) (xy 125.195838 -250.359164)
			(xy 125.953012 -250.359164) (xy 125.96453 -250.358598) (xy 125.985186 -250.348408) (xy 125.992636 -250.339606)
			(xy 126.040896 -250.276868) (xy 126.04434 -250.272132) (xy 126.049214 -250.261488) (xy 126.050548 -250.255786)
			(xy 126.052834 -250.24461) (xy 126.05258 -250.243848) (xy 126.049786 -250.23318) (xy 126.044945 -250.213855)
			(xy 126.039724 -250.174359) (xy 126.039372 -250.15444) (xy 126.039815 -250.130444) (xy 126.047317 -250.083043)
			(xy 126.062142 -250.037398) (xy 126.083924 -249.994635) (xy 126.112129 -249.955806) (xy 126.146061 -249.921868)
			(xy 126.184884 -249.893656) (xy 126.227643 -249.871865) (xy 126.273284 -249.857031) (xy 126.320684 -249.84952)
			(xy 126.34468 -249.849132) (xy 126.370047 -249.849633) (xy 126.420082 -249.85802) (xy 126.468041 -249.874565)
			(xy 126.512603 -249.898814) (xy 126.552542 -249.930099) (xy 126.586757 -249.967558) (xy 126.600966 -249.988578)
			(xy 126.604014 -249.993404) (xy 126.611888 -250.001024) (xy 126.61646 -250.003818) (xy 126.621373 -250.00671)
			(xy 126.632146 -250.010426) (xy 126.637796 -250.011184) (xy 126.715012 -250.019312) (xy 126.726117 -250.019839)
			(xy 126.747055 -250.012441) (xy 126.755398 -250.005088) (xy 126.978156 -249.78233) (xy 126.98471 -249.775082)
			(xy 126.99216 -249.757039) (xy 126.992634 -249.747278) (xy 126.992634 -249.742198) (xy 126.992059 -249.731105)
			(xy 126.98257 -249.711055) (xy 126.974346 -249.70359) (xy 126.950724 -249.683778) (xy 126.950216 -249.683778)
			(xy 126.914402 -249.654314) (xy 126.910034 -249.650919) (xy 126.900164 -249.645926) (xy 126.894844 -249.644408)
			(xy 126.884684 -249.641868) (xy 126.873254 -249.644154) (xy 126.860171 -249.646556) (xy 126.833718 -249.649352)
			(xy 126.820422 -249.649742) (xy 126.812802 -249.649742) (xy 126.787652 -249.649064) (xy 126.73808 -249.640494)
			(xy 126.690584 -249.623913) (xy 126.646447 -249.599772) (xy 126.606865 -249.568722) (xy 126.572908 -249.531605)
			(xy 126.545494 -249.489423) (xy 126.525365 -249.443318) (xy 126.513066 -249.394537) (xy 126.508928 -249.3444)
			(xy 126.513066 -249.294263) (xy 126.525365 -249.245483) (xy 126.545494 -249.199378) (xy 126.572907 -249.157196)
			(xy 126.606865 -249.120078) (xy 126.646447 -249.089028) (xy 126.690583 -249.064887) (xy 126.73808 -249.048306)
			(xy 126.787652 -249.039736) (xy 126.812802 -249.039126) (xy 126.815342 -249.039126) (xy 126.829912 -249.039306)
			(xy 126.858919 -249.042103) (xy 126.873254 -249.044714) (xy 126.884684 -249.047) (xy 126.894844 -249.04446)
			(xy 126.900162 -249.042936) (xy 126.91003 -249.037942) (xy 126.914402 -249.034554) (xy 126.950216 -249.00509)
			(xy 126.950724 -249.00509) (xy 126.974346 -248.985278) (xy 126.982535 -248.977786) (xy 126.992029 -248.957752)
			(xy 126.992634 -248.94667) (xy 126.992634 -248.623582) (xy 126.990856 -248.616978) (xy 126.985515 -248.59676)
			(xy 126.979778 -248.555337) (xy 126.979426 -248.534428) (xy 126.979785 -248.513519) (xy 126.985517 -248.472097)
			(xy 126.990856 -248.451878) (xy 126.992634 -248.445274) (xy 126.992634 -248.122186) (xy 126.992057 -248.111095)
			(xy 126.982564 -248.091048) (xy 126.974346 -248.083578) (xy 126.950724 -248.063766) (xy 126.950216 -248.063766)
			(xy 126.914402 -248.034302) (xy 126.910034 -248.030907) (xy 126.900163 -248.025916) (xy 126.894844 -248.024396)
			(xy 126.884684 -248.021856) (xy 126.873254 -248.024142) (xy 126.860171 -248.026544) (xy 126.833718 -248.029338)
			(xy 126.820422 -248.02973) (xy 126.812802 -248.02973) (xy 126.787653 -248.029052) (xy 126.738083 -248.020482)
			(xy 126.690589 -248.003902) (xy 126.646454 -247.979762) (xy 126.606873 -247.948713) (xy 126.572917 -247.911597)
			(xy 126.545504 -247.869417) (xy 126.525376 -247.823314) (xy 126.513077 -247.774535) (xy 126.50894 -247.7244)
			(xy 126.513077 -247.674265) (xy 126.525376 -247.625486) (xy 126.545504 -247.579383) (xy 126.572917 -247.537203)
			(xy 126.606873 -247.500087) (xy 126.646454 -247.469038) (xy 126.690588 -247.444898) (xy 126.738083 -247.428318)
			(xy 126.787653 -247.419748) (xy 126.812802 -247.419114) (xy 126.815342 -247.419114) (xy 126.829912 -247.419294)
			(xy 126.858919 -247.42209) (xy 126.873254 -247.424702) (xy 126.884684 -247.426988) (xy 126.894844 -247.424448)
			(xy 126.900162 -247.422924) (xy 126.910029 -247.417929) (xy 126.914402 -247.414542) (xy 126.950216 -247.385078)
			(xy 126.950724 -247.385078) (xy 126.974346 -247.365266) (xy 126.982533 -247.357773) (xy 126.992022 -247.33774)
			(xy 126.992634 -247.326658) (xy 126.992634 -247.00357) (xy 126.990856 -246.996966) (xy 126.985515 -246.976748)
			(xy 126.97978 -246.935325) (xy 126.979426 -246.914416) (xy 126.979786 -246.893508) (xy 126.98552 -246.852085)
			(xy 126.990856 -246.831866) (xy 126.992634 -246.825262) (xy 126.992634 -246.502174) (xy 126.992054 -246.491084)
			(xy 126.982559 -246.471041) (xy 126.974346 -246.463566) (xy 126.950724 -246.443754) (xy 126.950216 -246.443754)
			(xy 126.914402 -246.41429) (xy 126.910034 -246.410896) (xy 126.900163 -246.405906) (xy 126.894844 -246.404384)
			(xy 126.884684 -246.401844) (xy 126.873254 -246.40413) (xy 126.860171 -246.406532) (xy 126.833718 -246.409326)
			(xy 126.820422 -246.409718) (xy 126.812802 -246.409718) (xy 126.787654 -246.40904) (xy 126.738086 -246.40047)
			(xy 126.690593 -246.383891) (xy 126.64646 -246.359752) (xy 126.606881 -246.328705) (xy 126.572927 -246.29159)
			(xy 126.545515 -246.249411) (xy 126.525388 -246.20331) (xy 126.513089 -246.154533) (xy 126.508952 -246.1044)
			(xy 126.513089 -246.054267) (xy 126.525388 -246.00549) (xy 126.545515 -245.959389) (xy 126.572927 -245.91721)
			(xy 126.606881 -245.880095) (xy 126.64646 -245.849048) (xy 126.690593 -245.824909) (xy 126.738086 -245.80833)
			(xy 126.787654 -245.79976) (xy 126.812802 -245.799102) (xy 126.815342 -245.799102) (xy 126.829912 -245.799282)
			(xy 126.858919 -245.802078) (xy 126.873254 -245.80469) (xy 126.884684 -245.806976) (xy 126.894844 -245.804436)
			(xy 126.900163 -245.802915) (xy 126.910036 -245.797927) (xy 126.914402 -245.79453) (xy 126.950216 -245.765066)
			(xy 126.950724 -245.765066) (xy 126.974346 -245.745254) (xy 126.982531 -245.73776) (xy 126.992015 -245.717727)
			(xy 126.992634 -245.706646) (xy 126.992634 -245.383558) (xy 126.990856 -245.376954) (xy 126.985516 -245.356736)
			(xy 126.979783 -245.315313) (xy 126.979426 -245.294404) (xy 126.979787 -245.273496) (xy 126.985522 -245.232074)
			(xy 126.990856 -245.211854) (xy 126.992634 -245.20525) (xy 126.992634 -244.882162) (xy 126.992052 -244.871073)
			(xy 126.982554 -244.851034) (xy 126.974346 -244.843554) (xy 126.950724 -244.823742) (xy 126.950216 -244.823742)
			(xy 126.914402 -244.794278) (xy 126.910036 -244.790879) (xy 126.900167 -244.785881) (xy 126.894844 -244.784372)
			(xy 126.884684 -244.781832) (xy 126.873254 -244.784118) (xy 126.860171 -244.78652) (xy 126.833718 -244.789315)
			(xy 126.820422 -244.789706) (xy 126.812802 -244.789706) (xy 126.787655 -244.789029) (xy 126.738089 -244.780459)
			(xy 126.690598 -244.76388) (xy 126.646467 -244.739742) (xy 126.606889 -244.708696) (xy 126.572936 -244.671582)
			(xy 126.545525 -244.629405) (xy 126.525399 -244.583306) (xy 126.513101 -244.534531) (xy 126.508964 -244.4844)
			(xy 126.513101 -244.434269) (xy 126.525399 -244.385494) (xy 126.545525 -244.339395) (xy 126.572936 -244.297218)
			(xy 126.606889 -244.260104) (xy 126.646467 -244.229058) (xy 126.690598 -244.20492) (xy 126.738089 -244.188341)
			(xy 126.787655 -244.179771) (xy 126.812802 -244.17909) (xy 126.815342 -244.17909) (xy 126.829912 -244.17927)
			(xy 126.858919 -244.182066) (xy 126.873254 -244.184678) (xy 126.884684 -244.186964) (xy 126.894844 -244.184424)
			(xy 126.900163 -244.182902) (xy 126.910035 -244.177913) (xy 126.914402 -244.174518) (xy 126.950216 -244.145054)
			(xy 126.950724 -244.145054) (xy 126.974346 -244.125242) (xy 126.982529 -244.117747) (xy 126.992008 -244.097714)
			(xy 126.992634 -244.086634) (xy 126.992634 -243.763546) (xy 126.990856 -243.756942) (xy 126.985517 -243.736723)
			(xy 126.979785 -243.695301) (xy 126.979426 -243.674392) (xy 126.979788 -243.653484) (xy 126.985524 -243.612062)
			(xy 126.990856 -243.591842) (xy 126.992634 -243.585238) (xy 126.992634 -243.26215) (xy 126.992049 -243.251062)
			(xy 126.982548 -243.231027) (xy 126.974346 -243.223542) (xy 126.950724 -243.20373) (xy 126.950216 -243.20373)
			(xy 126.914402 -243.174266) (xy 126.910036 -243.170868) (xy 126.900167 -243.165871) (xy 126.894844 -243.16436)
			(xy 126.884684 -243.16182) (xy 126.873254 -243.164106) (xy 126.860171 -243.166508) (xy 126.833718 -243.169303)
			(xy 126.820422 -243.169694) (xy 126.812802 -243.169694) (xy 126.787656 -243.169017) (xy 126.738092 -243.160447)
			(xy 126.690603 -243.143869) (xy 126.646474 -243.119732) (xy 126.606898 -243.088687) (xy 126.572946 -243.051575)
			(xy 126.545536 -243.0094) (xy 126.52541 -242.963302) (xy 126.513113 -242.914529) (xy 126.508976 -242.8644)
			(xy 126.513113 -242.814271) (xy 126.52541 -242.765498) (xy 126.545536 -242.7194) (xy 126.572946 -242.677225)
			(xy 126.606898 -242.640113) (xy 126.646474 -242.609068) (xy 126.690603 -242.584931) (xy 126.738092 -242.568353)
			(xy 126.787656 -242.559783) (xy 126.812802 -242.559078) (xy 126.815342 -242.559078) (xy 126.829912 -242.559258)
			(xy 126.858919 -242.562054) (xy 126.873254 -242.564666) (xy 126.884684 -242.566952) (xy 126.894844 -242.564412)
			(xy 126.900163 -242.56289) (xy 126.910034 -242.5579) (xy 126.914402 -242.554506) (xy 126.950216 -242.525042)
			(xy 126.950724 -242.525042) (xy 126.974346 -242.50523) (xy 126.982527 -242.497735) (xy 126.992002 -242.477701)
			(xy 126.992634 -242.466622) (xy 126.992634 -242.143534) (xy 126.990856 -242.13693) (xy 126.985518 -242.116711)
			(xy 126.979788 -242.075289) (xy 126.979426 -242.05438) (xy 126.979789 -242.033472) (xy 126.985527 -241.992051)
			(xy 126.990856 -241.97183) (xy 126.992634 -241.965226) (xy 126.992634 -241.642138) (xy 126.992047 -241.631052)
			(xy 126.982543 -241.61102) (xy 126.974346 -241.60353) (xy 126.950724 -241.583718) (xy 126.950216 -241.583718)
			(xy 126.914402 -241.554254) (xy 126.910035 -241.550857) (xy 126.900166 -241.545861) (xy 126.894844 -241.544348)
			(xy 126.884684 -241.541808) (xy 126.873254 -241.544094) (xy 126.860171 -241.546496) (xy 126.833718 -241.549291)
			(xy 126.820422 -241.549682) (xy 126.812802 -241.549682) (xy 126.787657 -241.549005) (xy 126.738095 -241.540436)
			(xy 126.690608 -241.523858) (xy 126.64648 -241.499722) (xy 126.606906 -241.468678) (xy 126.572955 -241.431568)
			(xy 126.545546 -241.389394) (xy 126.525422 -241.343298) (xy 126.513125 -241.294527) (xy 126.508988 -241.2444)
			(xy 126.513125 -241.194273) (xy 126.525422 -241.145502) (xy 126.545547 -241.099406) (xy 126.572955 -241.057232)
			(xy 126.606906 -241.020122) (xy 126.64648 -240.989078) (xy 126.690608 -240.964941) (xy 126.738095 -240.948364)
			(xy 126.787657 -240.939795) (xy 126.812802 -240.939066) (xy 126.815342 -240.939066) (xy 126.829912 -240.939246)
			(xy 126.858919 -240.942043) (xy 126.873254 -240.944654) (xy 126.884684 -240.94694) (xy 126.894844 -240.9444)
			(xy 126.900162 -240.942877) (xy 126.910033 -240.937886) (xy 126.914402 -240.934494) (xy 126.950216 -240.90503)
			(xy 126.950724 -240.90503) (xy 126.974346 -240.885218) (xy 126.982542 -240.877728) (xy 126.992051 -240.857695)
			(xy 126.992634 -240.84661) (xy 126.992634 -240.523522) (xy 126.990856 -240.516918) (xy 126.985518 -240.496699)
			(xy 126.97979 -240.455276) (xy 126.979426 -240.434368) (xy 126.97979 -240.41346) (xy 126.985529 -240.372039)
			(xy 126.990856 -240.351818) (xy 126.992634 -240.345214) (xy 126.992634 -240.022126) (xy 126.992045 -240.011041)
			(xy 126.982537 -239.991013) (xy 126.974346 -239.983518) (xy 126.950724 -239.963706) (xy 126.950216 -239.963706)
			(xy 126.914402 -239.934242) (xy 126.910035 -239.930845) (xy 126.900165 -239.925851) (xy 126.894844 -239.924336)
			(xy 126.884684 -239.921796) (xy 126.873254 -239.924082) (xy 126.860171 -239.926484) (xy 126.833718 -239.929279)
			(xy 126.820422 -239.92967) (xy 126.812802 -239.92967) (xy 126.787658 -239.928993) (xy 126.738098 -239.920424)
			(xy 126.690613 -239.903847) (xy 126.646487 -239.879712) (xy 126.606914 -239.848669) (xy 126.572964 -239.81156)
			(xy 126.545557 -239.769388) (xy 126.525433 -239.723294) (xy 126.513137 -239.674525) (xy 126.509 -239.6244)
			(xy 126.513137 -239.574275) (xy 126.525433 -239.525505) (xy 126.545557 -239.479411) (xy 126.572965 -239.437239)
			(xy 126.606914 -239.40013) (xy 126.646487 -239.369088) (xy 126.690613 -239.344952) (xy 126.738098 -239.328376)
			(xy 126.787659 -239.319807) (xy 126.812802 -239.319054) (xy 126.815342 -239.319054) (xy 126.829912 -239.319234)
			(xy 126.858919 -239.322031) (xy 126.873254 -239.324642) (xy 126.884684 -239.326928) (xy 126.894844 -239.324388)
			(xy 126.900162 -239.322865) (xy 126.910032 -239.317873) (xy 126.914402 -239.314482) (xy 126.950216 -239.285018)
			(xy 126.950724 -239.285018) (xy 126.974346 -239.265206) (xy 126.98254 -239.257715) (xy 126.992044 -239.237682)
			(xy 126.992634 -239.226598) (xy 126.992634 -238.90351) (xy 126.990856 -238.896906) (xy 126.985513 -238.876688)
			(xy 126.979772 -238.835265) (xy 126.979426 -238.814356) (xy 126.97979 -238.793448) (xy 126.985531 -238.752028)
			(xy 126.990856 -238.731806) (xy 126.992634 -238.725202) (xy 126.992634 -238.402114) (xy 126.992042 -238.39103)
			(xy 126.982532 -238.371006) (xy 126.974346 -238.363506) (xy 126.950724 -238.343694) (xy 126.950216 -238.343694)
			(xy 126.914402 -238.31423) (xy 126.910035 -238.310834) (xy 126.900165 -238.30584) (xy 126.894844 -238.304324)
			(xy 126.884684 -238.301784) (xy 126.873254 -238.30407) (xy 126.860171 -238.306472) (xy 126.833718 -238.309267)
			(xy 126.820422 -238.309658) (xy 126.812802 -238.309658) (xy 126.787651 -238.308981) (xy 126.738076 -238.30041)
			(xy 126.690577 -238.283828) (xy 126.646438 -238.259686) (xy 126.606854 -238.228634) (xy 126.572895 -238.191515)
			(xy 126.545479 -238.149331) (xy 126.525349 -238.103223) (xy 126.513049 -238.05444) (xy 126.508912 -238.0043)
			(xy 126.513049 -237.954161) (xy 126.525349 -237.905377) (xy 126.545479 -237.85927) (xy 126.572894 -237.817086)
			(xy 126.606854 -237.779966) (xy 126.646438 -237.748915) (xy 126.690577 -237.724772) (xy 126.738076 -237.70819)
			(xy 126.78765 -237.699619) (xy 126.812802 -237.699042) (xy 126.815342 -237.699042) (xy 126.829912 -237.699222)
			(xy 126.858919 -237.702019) (xy 126.873254 -237.70463) (xy 126.884684 -237.706916) (xy 126.894844 -237.704376)
			(xy 126.900162 -237.702853) (xy 126.910031 -237.69786) (xy 126.914402 -237.69447) (xy 126.950216 -237.665006)
			(xy 126.950724 -237.665006) (xy 126.974346 -237.645194) (xy 126.982538 -237.637703) (xy 126.992037 -237.61767)
			(xy 126.992634 -237.606586) (xy 126.992634 -237.283498) (xy 126.990856 -237.276894) (xy 126.985513 -237.256676)
			(xy 126.979775 -237.215253) (xy 126.979426 -237.194344) (xy 126.979784 -237.173435) (xy 126.985514 -237.132012)
			(xy 126.990856 -237.111794) (xy 126.992634 -237.10519) (xy 126.992634 -236.782102) (xy 126.99206 -236.771009)
			(xy 126.982572 -236.750957) (xy 126.974346 -236.743494) (xy 126.950724 -236.723682) (xy 126.950216 -236.723682)
			(xy 126.914402 -236.694218) (xy 126.910034 -236.690822) (xy 126.900164 -236.68583) (xy 126.894844 -236.684312)
			(xy 126.884684 -236.681772) (xy 126.873254 -236.684058) (xy 126.860171 -236.68646) (xy 126.833718 -236.689256)
			(xy 126.820422 -236.689646) (xy 126.812802 -236.689646) (xy 126.787652 -236.688969) (xy 126.738079 -236.680398)
			(xy 126.690582 -236.663817) (xy 126.646445 -236.639676) (xy 126.606862 -236.608626) (xy 126.572904 -236.571507)
			(xy 126.54549 -236.529325) (xy 126.525361 -236.483219) (xy 126.513061 -236.434438) (xy 126.508924 -236.3843)
			(xy 126.513061 -236.334163) (xy 126.525361 -236.285381) (xy 126.54549 -236.239276) (xy 126.572904 -236.197093)
			(xy 126.606862 -236.159975) (xy 126.646445 -236.128925) (xy 126.690582 -236.104783) (xy 126.738079 -236.088202)
			(xy 126.787651 -236.079631) (xy 126.812802 -236.07903) (xy 126.815342 -236.07903) (xy 126.829912 -236.07921)
			(xy 126.858919 -236.082007) (xy 126.873254 -236.084618) (xy 126.884684 -236.086904) (xy 126.894844 -236.084364)
			(xy 126.900162 -236.08284) (xy 126.91003 -236.077847) (xy 126.914402 -236.074458) (xy 126.950216 -236.044994)
			(xy 126.950724 -236.044994) (xy 126.974346 -236.025182) (xy 126.982536 -236.01769) (xy 126.992031 -235.997657)
			(xy 126.992634 -235.986574) (xy 126.992634 -235.663486) (xy 126.990856 -235.656882) (xy 126.985514 -235.636664)
			(xy 126.979777 -235.595241) (xy 126.979426 -235.574332) (xy 126.979785 -235.553423) (xy 126.985516 -235.512)
			(xy 126.990856 -235.491782) (xy 126.992634 -235.485178) (xy 126.992634 -235.16209) (xy 126.992058 -235.150998)
			(xy 126.982566 -235.13095) (xy 126.974346 -235.123482) (xy 126.950724 -235.10367) (xy 126.950216 -235.10367)
			(xy 126.914402 -235.074206) (xy 126.910034 -235.070811) (xy 126.900164 -235.06582) (xy 126.894844 -235.0643)
			(xy 126.884684 -235.06176) (xy 126.873254 -235.064046) (xy 126.860171 -235.066448) (xy 126.833718 -235.069244)
			(xy 126.820422 -235.069634) (xy 126.812802 -235.069634) (xy 126.787653 -235.068956) (xy 126.738082 -235.060386)
			(xy 126.690587 -235.043806) (xy 126.646452 -235.019665) (xy 126.606871 -234.988616) (xy 126.572914 -234.9515)
			(xy 126.545501 -234.909319) (xy 126.525372 -234.863215) (xy 126.513073 -234.814436) (xy 126.508936 -234.7643)
			(xy 126.513073 -234.714165) (xy 126.525372 -234.665385) (xy 126.545501 -234.619281) (xy 126.572914 -234.577101)
			(xy 126.60687 -234.539984) (xy 126.646451 -234.508935) (xy 126.690587 -234.484794) (xy 126.738082 -234.468214)
			(xy 126.787653 -234.459644) (xy 126.812802 -234.459018) (xy 126.815342 -234.459018) (xy 126.829912 -234.459198)
			(xy 126.858919 -234.461994) (xy 126.873254 -234.464606) (xy 126.884684 -234.466892) (xy 126.894844 -234.464352)
			(xy 126.900162 -234.462828) (xy 126.910029 -234.457833) (xy 126.914402 -234.454446) (xy 126.950216 -234.424982)
			(xy 126.950724 -234.424982) (xy 126.974346 -234.40517) (xy 126.982534 -234.397677) (xy 126.992024 -234.377644)
			(xy 126.992634 -234.366562) (xy 126.992634 -234.043474) (xy 126.990856 -234.03687) (xy 126.985515 -234.016652)
			(xy 126.979779 -233.975229) (xy 126.979426 -233.95432) (xy 126.979507 -233.942975) (xy 126.981156 -233.920344)
			(xy 126.982728 -233.909108) (xy 126.984506 -233.89717) (xy 126.984506 -233.545634) (xy 126.98394 -233.534528)
			(xy 126.974585 -233.514379) (xy 126.966472 -233.506772) (xy 126.907036 -233.45648) (xy 126.898264 -233.44984)
			(xy 126.877068 -233.44403) (xy 126.866142 -233.445304) (xy 126.865888 -233.445304) (xy 126.85322 -233.447313)
			(xy 126.82766 -233.449474) (xy 126.814834 -233.449622) (xy 126.789573 -233.449132) (xy 126.73974 -233.440821)
			(xy 126.691955 -233.424421) (xy 126.647521 -233.400379) (xy 126.60765 -233.369351) (xy 126.573431 -233.332183)
			(xy 126.545797 -233.289889) (xy 126.525501 -233.243624) (xy 126.513098 -233.194649) (xy 126.508926 -233.1443)
			(xy 126.513098 -233.093951) (xy 126.525501 -233.044976) (xy 126.545797 -232.998711) (xy 126.573431 -232.956417)
			(xy 126.60765 -232.919249) (xy 126.647521 -232.888221) (xy 126.691955 -232.864179) (xy 126.73974 -232.847779)
			(xy 126.789573 -232.839468) (xy 126.814834 -232.839006) (xy 126.827597 -232.839144) (xy 126.853031 -232.841307)
			(xy 126.865634 -232.843324) (xy 126.866142 -232.843324) (xy 126.877069 -232.844605) (xy 126.898263 -232.838792)
			(xy 126.907036 -232.832148) (xy 126.966472 -232.781856) (xy 126.974602 -232.774264) (xy 126.983949 -232.754105)
			(xy 126.984506 -232.742994) (xy 126.984506 -232.389934) (xy 126.983744 -232.385616) (xy 126.981725 -232.372885)
			(xy 126.979561 -232.347197) (xy 126.979426 -232.334308) (xy 126.979543 -232.321418) (xy 126.981701 -232.295728)
			(xy 126.983744 -232.283) (xy 126.984506 -232.278682) (xy 126.984506 -231.925622) (xy 126.983937 -231.914517)
			(xy 126.974579 -231.894372) (xy 126.966472 -231.88676) (xy 126.907036 -231.836468) (xy 126.898264 -231.829829)
			(xy 126.877068 -231.824021) (xy 126.866142 -231.825292) (xy 126.865888 -231.825292) (xy 126.85322 -231.827301)
			(xy 126.82766 -231.829462) (xy 126.814834 -231.82961) (xy 126.789574 -231.82912) (xy 126.739743 -231.82081)
			(xy 126.69196 -231.80441) (xy 126.647527 -231.780369) (xy 126.607658 -231.749342) (xy 126.573441 -231.712176)
			(xy 126.545808 -231.669884) (xy 126.525513 -231.62362) (xy 126.51311 -231.574647) (xy 126.508938 -231.5243)
			(xy 126.51311 -231.473953) (xy 126.525513 -231.42498) (xy 126.545808 -231.378716) (xy 126.573441 -231.336424)
			(xy 126.607658 -231.299258) (xy 126.647527 -231.268231) (xy 126.69196 -231.24419) (xy 126.739743 -231.22779)
			(xy 126.789574 -231.21948) (xy 126.814834 -231.218994) (xy 126.827597 -231.219132) (xy 126.853031 -231.221295)
			(xy 126.865634 -231.223312) (xy 126.866142 -231.223312) (xy 126.87707 -231.224593) (xy 126.898269 -231.218788)
			(xy 126.907036 -231.212136) (xy 126.966472 -231.161844) (xy 126.9746 -231.154251) (xy 126.983942 -231.134092)
			(xy 126.984506 -231.122982) (xy 126.984506 -230.770176) (xy 126.983744 -230.765858) (xy 126.981727 -230.753127)
			(xy 126.979568 -230.727439) (xy 126.979426 -230.71455) (xy 126.979545 -230.70166) (xy 126.981708 -230.675971)
			(xy 126.983744 -230.663242) (xy 126.984506 -230.658924) (xy 126.984506 -230.30561) (xy 126.983955 -230.294496)
			(xy 126.974619 -230.274324) (xy 126.966472 -230.266748) (xy 126.907036 -230.216456) (xy 126.898263 -230.209819)
			(xy 126.877068 -230.204012) (xy 126.866142 -230.20528) (xy 126.865888 -230.20528) (xy 126.85322 -230.207289)
			(xy 126.82766 -230.20945) (xy 126.814834 -230.209598) (xy 126.789575 -230.209108) (xy 126.739746 -230.200798)
			(xy 126.691964 -230.184399) (xy 126.647534 -230.160359) (xy 126.607667 -230.129333) (xy 126.57345 -230.092168)
			(xy 126.545818 -230.049878) (xy 126.525524 -230.003616) (xy 126.513122 -229.954645) (xy 126.50895 -229.9043)
			(xy 126.513122 -229.853955) (xy 126.525524 -229.804984) (xy 126.545818 -229.758722) (xy 126.57345 -229.716432)
			(xy 126.607667 -229.679267) (xy 126.647534 -229.648241) (xy 126.691964 -229.624201) (xy 126.739746 -229.607802)
			(xy 126.789575 -229.599492) (xy 126.814834 -229.598982) (xy 126.827597 -229.59912) (xy 126.853031 -229.601283)
			(xy 126.865634 -229.6033) (xy 126.866142 -229.6033) (xy 126.87707 -229.604581) (xy 126.898268 -229.598775)
			(xy 126.907036 -229.592124) (xy 126.966472 -229.541832) (xy 126.974598 -229.534238) (xy 126.983935 -229.514079)
			(xy 126.984506 -229.50297) (xy 126.984506 -229.150164) (xy 126.983744 -229.145846) (xy 126.981728 -229.133115)
			(xy 126.97957 -229.107427) (xy 126.979426 -229.094538) (xy 126.979546 -229.081648) (xy 126.98171 -229.055959)
			(xy 126.983744 -229.04323) (xy 126.984506 -229.038912) (xy 126.984506 -228.685852) (xy 126.983943 -228.674744)
			(xy 126.974593 -228.65459) (xy 126.966472 -228.64699) (xy 126.907036 -228.596698) (xy 126.898265 -228.590057)
			(xy 126.877068 -228.584245) (xy 126.866142 -228.585522) (xy 126.865888 -228.585522) (xy 126.85322 -228.587531)
			(xy 126.82766 -228.589692) (xy 126.814834 -228.58984) (xy 126.789572 -228.58935) (xy 126.739736 -228.581039)
			(xy 126.691948 -228.564638) (xy 126.647511 -228.540594) (xy 126.607638 -228.509564) (xy 126.573417 -228.472394)
			(xy 126.545781 -228.430098) (xy 126.525484 -228.38383) (xy 126.513081 -228.334852) (xy 126.508908 -228.2845)
			(xy 126.513081 -228.234148) (xy 126.525484 -228.18517) (xy 126.545781 -228.138902) (xy 126.573417 -228.096606)
			(xy 126.607638 -228.059436) (xy 126.647511 -228.028406) (xy 126.691948 -228.004362) (xy 126.739736 -227.987961)
			(xy 126.789572 -227.97965) (xy 126.814834 -227.979224) (xy 126.827597 -227.979362) (xy 126.853031 -227.981524)
			(xy 126.865634 -227.983542) (xy 126.866142 -227.983542) (xy 126.87707 -227.984823) (xy 126.898265 -227.979011)
			(xy 126.907036 -227.972366) (xy 126.966472 -227.922074) (xy 126.974605 -227.914483) (xy 126.983959 -227.894324)
			(xy 126.984506 -227.883212) (xy 126.984506 -227.530152) (xy 126.983744 -227.525834) (xy 126.981724 -227.513103)
			(xy 126.979559 -227.487415) (xy 126.979426 -227.474526) (xy 126.979546 -227.461636) (xy 126.981711 -227.435947)
			(xy 126.983744 -227.423218) (xy 126.984506 -227.4189) (xy 126.984506 -227.06584) (xy 126.983941 -227.054733)
			(xy 126.974588 -227.034583) (xy 126.966472 -227.026978) (xy 126.907036 -226.976686) (xy 126.898264 -226.970045)
			(xy 126.877068 -226.964235) (xy 126.866142 -226.96551) (xy 126.865888 -226.96551) (xy 126.85322 -226.967519)
			(xy 126.82766 -226.96968) (xy 126.814834 -226.969828) (xy 126.789573 -226.969338) (xy 126.739739 -226.961027)
			(xy 126.691952 -226.944627) (xy 126.647518 -226.920584) (xy 126.607646 -226.889555) (xy 126.573427 -226.852387)
			(xy 126.545792 -226.810092) (xy 126.525496 -226.763826) (xy 126.513092 -226.71485) (xy 126.50892 -226.6645)
			(xy 126.513092 -226.61415) (xy 126.525496 -226.565174) (xy 126.545792 -226.518908) (xy 126.573427 -226.476613)
			(xy 126.607646 -226.439445) (xy 126.647518 -226.408416) (xy 126.691952 -226.384373) (xy 126.739739 -226.367973)
			(xy 126.789573 -226.359662) (xy 126.814834 -226.359212) (xy 126.840035 -226.359702) (xy 126.88976 -226.367937)
			(xy 126.937451 -226.384243) (xy 126.981808 -226.408175) (xy 127.002032 -226.42322) (xy 127.009247 -226.428421)
			(xy 127.026158 -226.433897) (xy 127.035052 -226.433888) (xy 127.065024 -226.432872) (xy 127.074617 -226.432116)
			(xy 127.092229 -226.4244) (xy 127.099314 -226.417886) (xy 127.530606 -225.986594) (xy 127.536956 -225.975672)
			(xy 127.538734 -225.969322) (xy 127.548671 -225.936188) (xy 127.57567 -225.872498) (xy 127.592582 -225.842322)
			(xy 127.74676 -225.576892) (xy 127.75679 -225.560027) (xy 127.778906 -225.527609) (xy 127.790956 -225.512122)
			(xy 127.796233 -225.504783) (xy 127.801748 -225.487581) (xy 127.800985 -225.469532) (xy 127.797814 -225.461068)
			(xy 127.763524 -225.378772) (xy 127.759658 -225.37059) (xy 127.747263 -225.35742) (xy 127.731074 -225.349357)
			(xy 127.722122 -225.348038) (xy 127.721868 -225.348038) (xy 127.697228 -225.344891) (xy 127.649358 -225.331642)
			(xy 127.604264 -225.310818) (xy 127.563135 -225.282969) (xy 127.527058 -225.24883) (xy 127.496982 -225.209301)
			(xy 127.473702 -225.165424) (xy 127.457832 -225.118358) (xy 127.44979 -225.069343) (xy 127.449326 -225.044508)
			(xy 127.449848 -225.019253) (xy 127.458161 -224.969431) (xy 127.474562 -224.921657) (xy 127.498603 -224.877234)
			(xy 127.529627 -224.837374) (xy 127.566789 -224.803164) (xy 127.609075 -224.775538) (xy 127.655331 -224.755248)
			(xy 127.704296 -224.742848) (xy 127.754634 -224.738677) (xy 127.804972 -224.742848) (xy 127.853937 -224.755248)
			(xy 127.900193 -224.775538) (xy 127.942479 -224.803164) (xy 127.979641 -224.837374) (xy 128.010665 -224.877234)
			(xy 128.034706 -224.921657) (xy 128.051107 -224.969431) (xy 128.05942 -225.019253) (xy 128.059942 -225.044508)
			(xy 128.059942 -225.045016) (xy 128.059587 -225.065886) (xy 128.053872 -225.107234) (xy 128.042578 -225.147418)
			(xy 128.034542 -225.166682) (xy 128.028954 -225.179382) (xy 128.032002 -225.206814) (xy 128.094994 -225.288602)
			(xy 128.100776 -225.295481) (xy 128.115987 -225.305027) (xy 128.133548 -225.308783) (xy 128.142492 -225.307906)
			(xy 128.142746 -225.307906) (xy 128.156079 -225.305935) (xy 128.182888 -225.303138) (xy 128.19634 -225.302318)
			(xy 128.205644 -225.301445) (xy 128.22272 -225.293894) (xy 128.229614 -225.287586) (xy 128.37922 -225.13798)
			(xy 128.387187 -225.129015) (xy 128.394589 -225.106233) (xy 128.393444 -225.094292) (xy 128.393444 -225.093784)
			(xy 128.391564 -225.081551) (xy 128.389531 -225.056883) (xy 128.38938 -225.044508) (xy 128.38985 -225.020516)
			(xy 128.397355 -224.973123) (xy 128.412182 -224.927487) (xy 128.433965 -224.884732) (xy 128.462168 -224.845911)
			(xy 128.496096 -224.811981) (xy 128.534915 -224.783775) (xy 128.577668 -224.761989) (xy 128.623303 -224.74716)
			(xy 128.670696 -224.739652) (xy 128.694688 -224.7392) (xy 128.707001 -224.739341) (xy 128.731542 -224.741376)
			(xy 128.74371 -224.743264) (xy 128.744472 -224.743264) (xy 128.756421 -224.744488) (xy 128.779234 -224.737076)
			(xy 128.78816 -224.72904) (xy 128.936242 -224.580958) (xy 128.942855 -224.573787) (xy 128.950576 -224.555892)
			(xy 128.951228 -224.54616) (xy 128.953006 -224.465896) (xy 128.946148 -224.447862) (xy 128.939544 -224.440496)
			(xy 128.924587 -224.423521) (xy 128.899328 -224.385986) (xy 128.87988 -224.345138) (xy 128.866669 -224.301868)
			(xy 128.859982 -224.257123) (xy 128.859534 -224.234502) (xy 128.85998 -224.21051) (xy 128.867487 -224.163117)
			(xy 128.882316 -224.117481) (xy 128.904102 -224.074728) (xy 128.932308 -224.03591) (xy 128.96624 -224.001982)
			(xy 129.005062 -223.973781) (xy 129.047818 -223.952) (xy 129.093456 -223.937177) (xy 129.14085 -223.929677)
			(xy 129.164842 -223.929194) (xy 129.187466 -223.929601) (xy 129.23222 -223.936275) (xy 129.275498 -223.949486)
			(xy 129.316349 -223.968943) (xy 129.353879 -223.994221) (xy 129.370836 -224.009204) (xy 129.378202 -224.015808)
			(xy 129.396236 -224.022666) (xy 129.4765 -224.020888) (xy 129.486226 -224.020207) (xy 129.504117 -224.012498)
			(xy 129.511298 -224.005902) (xy 129.622804 -223.894396) (xy 129.628949 -223.887673) (xy 129.636458 -223.871094)
			(xy 129.637723 -223.852937) (xy 129.635504 -223.844104) (xy 129.610104 -223.758506) (xy 129.607143 -223.749882)
			(xy 129.596176 -223.73533) (xy 129.580826 -223.725511) (xy 129.572004 -223.7232) (xy 129.57175 -223.7232)
			(xy 129.546396 -223.717313) (xy 129.498028 -223.698091) (xy 129.453618 -223.670949) (xy 129.414451 -223.636673)
			(xy 129.381661 -223.596254) (xy 129.356195 -223.550862) (xy 129.338792 -223.501811) (xy 129.329954 -223.450519)
			(xy 129.329434 -223.424496) (xy 129.329881 -223.400504) (xy 129.337388 -223.353112) (xy 129.352217 -223.307477)
			(xy 129.374004 -223.264725) (xy 129.40221 -223.225907) (xy 129.436142 -223.19198) (xy 129.474964 -223.16378)
			(xy 129.51772 -223.142) (xy 129.563357 -223.127177) (xy 129.61075 -223.119677) (xy 129.634742 -223.119188)
			(xy 129.660768 -223.11971) (xy 129.712069 -223.128528) (xy 129.76113 -223.14592) (xy 129.806531 -223.17138)
			(xy 129.846956 -223.204172) (xy 129.881234 -223.243345) (xy 129.908371 -223.287764) (xy 129.927582 -223.336142)
			(xy 129.933446 -223.361504) (xy 129.933446 -223.361758) (xy 129.935714 -223.370601) (xy 129.945523 -223.385982)
			(xy 129.960101 -223.396948) (xy 129.968752 -223.399858) (xy 130.05435 -223.425258) (xy 130.063183 -223.427489)
			(xy 130.081345 -223.426237) (xy 130.097921 -223.418709) (xy 130.104642 -223.412558) (xy 130.179826 -223.337374)
			(xy 130.186507 -223.329965) (xy 130.194096 -223.311537) (xy 130.194085 -223.291607) (xy 130.186475 -223.273188)
			(xy 130.179826 -223.265746) (xy 130.165602 -223.251522) (xy 130.142098 -223.22731) (xy 130.100406 -223.174248)
			(xy 130.065306 -223.116613) (xy 130.037293 -223.05522) (xy 130.016764 -222.990937) (xy 130.0099 -222.957898)
			(xy 130.006824 -222.945619) (xy 129.990833 -222.926037) (xy 129.97942 -222.92056) (xy 129.95696 -222.910891)
			(xy 129.914927 -222.885905) (xy 129.877031 -222.855002) (xy 129.844099 -222.818856) (xy 129.816848 -222.778255)
			(xy 129.795873 -222.734084) (xy 129.78163 -222.687305) (xy 129.774431 -222.638939) (xy 129.773934 -222.61449)
			(xy 129.774486 -222.587288) (xy 129.783388 -222.533618) (xy 129.80095 -222.482126) (xy 129.826699 -222.434202)
			(xy 129.859941 -222.391135) (xy 129.899781 -222.354087) (xy 129.945145 -222.324055) (xy 129.969768 -222.312484)
			(xy 129.978458 -222.308076) (xy 129.991944 -222.294033) (xy 129.999258 -222.275989) (xy 129.99974 -222.266256)
			(xy 129.99974 -221.948502) (xy 129.999316 -221.938433) (xy 129.991595 -221.919834) (xy 129.984754 -221.912434)
			(xy 129.920746 -221.848426) (xy 129.913346 -221.841585) (xy 129.894747 -221.833867) (xy 129.884678 -221.83344)
			(xy 124.341636 -221.83344) (xy 124.330212 -221.834083) (xy 124.309622 -221.843992) (xy 124.295344 -221.861832)
			(xy 124.292106 -221.87281) (xy 124.286265 -221.896267) (xy 124.268186 -221.941098) (xy 124.243265 -221.982517)
			(xy 124.212126 -222.019489) (xy 124.175546 -222.051089) (xy 124.134442 -222.076526) (xy 124.089841 -222.095163)
			(xy 124.042859 -222.106536) (xy 123.994672 -222.110359) (xy 123.946485 -222.106536) (xy 123.899503 -222.095163)
			(xy 123.854902 -222.076526) (xy 123.813798 -222.051089) (xy 123.777218 -222.019489) (xy 123.746079 -221.982517)
			(xy 123.721158 -221.941098) (xy 123.703079 -221.896267) (xy 123.697238 -221.87281) (xy 123.693174 -221.855538)
			(xy 123.665488 -221.83344) (xy 123.401582 -221.83344) (xy 123.390151 -221.834074) (xy 123.369544 -221.843975)
			(xy 123.355251 -221.861818) (xy 123.352052 -221.87281) (xy 123.346211 -221.896267) (xy 123.328132 -221.941098)
			(xy 123.303211 -221.982517) (xy 123.272072 -222.019489) (xy 123.235492 -222.051089) (xy 123.194388 -222.076526)
			(xy 123.149787 -222.095163) (xy 123.102805 -222.106536) (xy 123.054618 -222.110359) (xy 123.006431 -222.106536)
			(xy 122.959449 -222.095163) (xy 122.914848 -222.076526) (xy 122.873744 -222.051089) (xy 122.837164 -222.019489)
			(xy 122.806025 -221.982517) (xy 122.781104 -221.941098) (xy 122.763025 -221.896267) (xy 122.757184 -221.87281)
			(xy 122.75312 -221.855538) (xy 122.725434 -221.83344) (xy 122.461782 -221.83344) (xy 122.450351 -221.834074)
			(xy 122.429744 -221.843975) (xy 122.415451 -221.861818) (xy 122.412252 -221.87281) (xy 122.406411 -221.896267)
			(xy 122.388332 -221.941098) (xy 122.363411 -221.982517) (xy 122.332272 -222.019489) (xy 122.295692 -222.051089)
			(xy 122.254588 -222.076526) (xy 122.209987 -222.095163) (xy 122.163005 -222.106536) (xy 122.114818 -222.110359)
			(xy 122.066631 -222.106536) (xy 122.019649 -222.095163) (xy 121.975048 -222.076526) (xy 121.933944 -222.051089)
			(xy 121.897364 -222.019489) (xy 121.866225 -221.982517) (xy 121.841304 -221.941098) (xy 121.823225 -221.896267)
			(xy 121.817384 -221.87281) (xy 121.81332 -221.855538) (xy 121.785634 -221.83344) (xy 121.521728 -221.83344)
			(xy 121.510305 -221.834085) (xy 121.489718 -221.843996) (xy 121.475442 -221.861835) (xy 121.472198 -221.87281)
			(xy 121.466357 -221.896267) (xy 121.448278 -221.941098) (xy 121.423357 -221.982517) (xy 121.392218 -222.019489)
			(xy 121.355638 -222.051089) (xy 121.314534 -222.076526) (xy 121.269933 -222.095163) (xy 121.222951 -222.106536)
			(xy 121.174764 -222.110359) (xy 121.126577 -222.106536) (xy 121.079595 -222.095163) (xy 121.034994 -222.076526)
			(xy 120.99389 -222.051089) (xy 120.95731 -222.019489) (xy 120.926171 -221.982517) (xy 120.90125 -221.941098)
			(xy 120.883171 -221.896267) (xy 120.87733 -221.87281) (xy 120.873266 -221.855538) (xy 120.84558 -221.83344)
			(xy 120.581674 -221.83344) (xy 120.570244 -221.834076) (xy 120.54964 -221.843978) (xy 120.53535 -221.86182)
			(xy 120.532144 -221.87281) (xy 120.526303 -221.896267) (xy 120.508224 -221.941098) (xy 120.483303 -221.982517)
			(xy 120.452164 -222.019489) (xy 120.415584 -222.051089) (xy 120.37448 -222.076526) (xy 120.329879 -222.095163)
			(xy 120.282897 -222.106536) (xy 120.23471 -222.110359) (xy 120.186523 -222.106536) (xy 120.139541 -222.095163)
			(xy 120.09494 -222.076526) (xy 120.053836 -222.051089) (xy 120.017256 -222.019489) (xy 119.986117 -221.982517)
			(xy 119.961196 -221.941098) (xy 119.943117 -221.896267) (xy 119.937276 -221.87281) (xy 119.933212 -221.855538)
			(xy 119.905526 -221.83344) (xy 118.70182 -221.83344) (xy 118.690384 -221.834067) (xy 118.669763 -221.84396)
			(xy 118.655457 -221.861805) (xy 118.65229 -221.87281) (xy 118.646449 -221.896267) (xy 118.62837 -221.941098)
			(xy 118.603449 -221.982517) (xy 118.57231 -222.019489) (xy 118.53573 -222.051089) (xy 118.494626 -222.076526)
			(xy 118.450025 -222.095163) (xy 118.403043 -222.106536) (xy 118.354856 -222.110359) (xy 118.306669 -222.106536)
			(xy 118.259687 -222.095163) (xy 118.215086 -222.076526) (xy 118.173982 -222.051089) (xy 118.137402 -222.019489)
			(xy 118.106263 -221.982517) (xy 118.081342 -221.941098) (xy 118.063263 -221.896267) (xy 118.057422 -221.87281)
			(xy 118.053358 -221.855538) (xy 118.025672 -221.83344) (xy 117.761766 -221.83344) (xy 117.750338 -221.834077)
			(xy 117.729737 -221.843981) (xy 117.715448 -221.861823) (xy 117.712236 -221.87281) (xy 117.706395 -221.896267)
			(xy 117.688316 -221.941098) (xy 117.663395 -221.982517) (xy 117.632256 -222.019489) (xy 117.595676 -222.051089)
			(xy 117.554572 -222.076526) (xy 117.509971 -222.095163) (xy 117.462989 -222.106536) (xy 117.414802 -222.110359)
			(xy 117.366615 -222.106536) (xy 117.319633 -222.095163) (xy 117.275032 -222.076526) (xy 117.233928 -222.051089)
			(xy 117.197348 -222.019489) (xy 117.166209 -221.982517) (xy 117.141288 -221.941098) (xy 117.123209 -221.896267)
			(xy 117.117368 -221.87281) (xy 117.113304 -221.855538) (xy 117.085618 -221.83344) (xy 116.821712 -221.83344)
			(xy 116.810277 -221.834068) (xy 116.789659 -221.843963) (xy 116.775356 -221.861808) (xy 116.772182 -221.87281)
			(xy 116.766341 -221.896267) (xy 116.748262 -221.941098) (xy 116.723341 -221.982517) (xy 116.692202 -222.019489)
			(xy 116.655622 -222.051089) (xy 116.614518 -222.076526) (xy 116.569917 -222.095163) (xy 116.522935 -222.106536)
			(xy 116.474748 -222.110359) (xy 116.426561 -222.106536) (xy 116.379579 -222.095163) (xy 116.334978 -222.076526)
			(xy 116.293874 -222.051089) (xy 116.257294 -222.019489) (xy 116.226155 -221.982517) (xy 116.201234 -221.941098)
			(xy 116.183155 -221.896267) (xy 116.177314 -221.87281) (xy 116.17325 -221.855538) (xy 116.145564 -221.83344)
			(xy 115.881658 -221.83344) (xy 115.870231 -221.834079) (xy 115.849633 -221.843984) (xy 115.835347 -221.861825)
			(xy 115.832128 -221.87281) (xy 115.826287 -221.896267) (xy 115.808208 -221.941098) (xy 115.783287 -221.982517)
			(xy 115.752148 -222.019489) (xy 115.715568 -222.051089) (xy 115.674464 -222.076526) (xy 115.629863 -222.095163)
			(xy 115.582881 -222.106536) (xy 115.534694 -222.110359) (xy 115.486507 -222.106536) (xy 115.439525 -222.095163)
			(xy 115.394924 -222.076526) (xy 115.35382 -222.051089) (xy 115.31724 -222.019489) (xy 115.286101 -221.982517)
			(xy 115.26118 -221.941098) (xy 115.243101 -221.896267) (xy 115.23726 -221.87281) (xy 115.233196 -221.855538)
			(xy 115.20551 -221.83344) (xy 114.941604 -221.83344) (xy 114.93017 -221.83407) (xy 114.909555 -221.843966)
			(xy 114.895254 -221.86181) (xy 114.892074 -221.87281) (xy 114.886233 -221.896267) (xy 114.868154 -221.941098)
			(xy 114.843233 -221.982517) (xy 114.812094 -222.019489) (xy 114.775514 -222.051089) (xy 114.73441 -222.076526)
			(xy 114.689809 -222.095163) (xy 114.642827 -222.106536) (xy 114.59464 -222.110359) (xy 114.546453 -222.106536)
			(xy 114.499471 -222.095163) (xy 114.45487 -222.076526) (xy 114.413766 -222.051089) (xy 114.377186 -222.019489)
			(xy 114.346047 -221.982517) (xy 114.321126 -221.941098) (xy 114.303047 -221.896267) (xy 114.297206 -221.87281)
			(xy 114.293142 -221.855538) (xy 114.265456 -221.83344) (xy 113.206022 -221.83344) (xy 113.195959 -221.833879)
			(xy 113.177379 -221.841617) (xy 113.169954 -221.848426) (xy 112.40389 -222.61449) (xy 112.878882 -222.61449)
			(xy 112.882842 -222.565436) (xy 112.894619 -222.517652) (xy 112.91391 -222.472376) (xy 112.940213 -222.43078)
			(xy 112.972848 -222.393943) (xy 113.010969 -222.362818) (xy 113.05359 -222.338211) (xy 113.099606 -222.320759)
			(xy 113.147825 -222.310915) (xy 113.197 -222.308934) (xy 113.245855 -222.314866) (xy 113.293126 -222.328558)
			(xy 113.337588 -222.349656) (xy 113.378091 -222.377612) (xy 113.413584 -222.411704) (xy 113.443149 -222.451048)
			(xy 113.46602 -222.494625) (xy 113.481604 -222.541306) (xy 113.489499 -222.589883) (xy 113.489994 -222.61449)
			(xy 113.818936 -222.61449) (xy 113.822896 -222.565436) (xy 113.834673 -222.517652) (xy 113.853964 -222.472376)
			(xy 113.880267 -222.43078) (xy 113.912902 -222.393943) (xy 113.951023 -222.362818) (xy 113.993644 -222.338211)
			(xy 114.03966 -222.320759) (xy 114.087879 -222.310915) (xy 114.137054 -222.308934) (xy 114.185909 -222.314866)
			(xy 114.23318 -222.328558) (xy 114.277642 -222.349656) (xy 114.318145 -222.377612) (xy 114.353638 -222.411704)
			(xy 114.383203 -222.451048) (xy 114.406074 -222.494625) (xy 114.421658 -222.541306) (xy 114.429553 -222.589883)
			(xy 114.430048 -222.61449) (xy 116.638844 -222.61449) (xy 116.642804 -222.565436) (xy 116.654581 -222.517652)
			(xy 116.673872 -222.472376) (xy 116.700175 -222.43078) (xy 116.73281 -222.393943) (xy 116.770931 -222.362818)
			(xy 116.813552 -222.338211) (xy 116.859568 -222.320759) (xy 116.907787 -222.310915) (xy 116.956962 -222.308934)
			(xy 117.005817 -222.314866) (xy 117.053088 -222.328558) (xy 117.09755 -222.349656) (xy 117.138053 -222.377612)
			(xy 117.173546 -222.411704) (xy 117.203111 -222.451048) (xy 117.225982 -222.494625) (xy 117.241566 -222.541306)
			(xy 117.249461 -222.589883) (xy 117.249956 -222.61449) (xy 119.459006 -222.61449) (xy 119.462966 -222.565436)
			(xy 119.474743 -222.517652) (xy 119.494034 -222.472376) (xy 119.520337 -222.43078) (xy 119.552972 -222.393943)
			(xy 119.591093 -222.362818) (xy 119.633714 -222.338211) (xy 119.67973 -222.320759) (xy 119.727949 -222.310915)
			(xy 119.777124 -222.308934) (xy 119.825979 -222.314866) (xy 119.87325 -222.328558) (xy 119.917712 -222.349656)
			(xy 119.958215 -222.377612) (xy 119.993708 -222.411704) (xy 120.023273 -222.451048) (xy 120.046144 -222.494625)
			(xy 120.061728 -222.541306) (xy 120.069623 -222.589883) (xy 120.070118 -222.61449) (xy 122.278914 -222.61449)
			(xy 122.282874 -222.565436) (xy 122.294651 -222.517652) (xy 122.313942 -222.472376) (xy 122.340245 -222.43078)
			(xy 122.37288 -222.393943) (xy 122.411001 -222.362818) (xy 122.453622 -222.338211) (xy 122.499638 -222.320759)
			(xy 122.547857 -222.310915) (xy 122.597032 -222.308934) (xy 122.645887 -222.314866) (xy 122.693158 -222.328558)
			(xy 122.73762 -222.349656) (xy 122.778123 -222.377612) (xy 122.813616 -222.411704) (xy 122.843181 -222.451048)
			(xy 122.866052 -222.494625) (xy 122.881636 -222.541306) (xy 122.889531 -222.589883) (xy 122.890026 -222.61449)
			(xy 125.098822 -222.61449) (xy 125.102782 -222.565436) (xy 125.114559 -222.517652) (xy 125.13385 -222.472376)
			(xy 125.160153 -222.43078) (xy 125.192788 -222.393943) (xy 125.230909 -222.362818) (xy 125.27353 -222.338211)
			(xy 125.319546 -222.320759) (xy 125.367765 -222.310915) (xy 125.41694 -222.308934) (xy 125.465795 -222.314866)
			(xy 125.513066 -222.328558) (xy 125.557528 -222.349656) (xy 125.598031 -222.377612) (xy 125.633524 -222.411704)
			(xy 125.663089 -222.451048) (xy 125.68596 -222.494625) (xy 125.701544 -222.541306) (xy 125.709439 -222.589883)
			(xy 125.709934 -222.61449) (xy 125.709439 -222.639097) (xy 125.701544 -222.687674) (xy 125.68596 -222.734355)
			(xy 125.663089 -222.777932) (xy 125.633524 -222.817276) (xy 125.598031 -222.851368) (xy 125.557528 -222.879324)
			(xy 125.513066 -222.900422) (xy 125.465795 -222.914114) (xy 125.41694 -222.920046) (xy 125.367765 -222.918065)
			(xy 125.319546 -222.908221) (xy 125.27353 -222.890769) (xy 125.230909 -222.866162) (xy 125.192788 -222.835037)
			(xy 125.160153 -222.7982) (xy 125.13385 -222.756604) (xy 125.114559 -222.711328) (xy 125.102782 -222.663544)
			(xy 125.098822 -222.61449) (xy 122.890026 -222.61449) (xy 122.889531 -222.639097) (xy 122.881636 -222.687674)
			(xy 122.866052 -222.734355) (xy 122.843181 -222.777932) (xy 122.813616 -222.817276) (xy 122.778123 -222.851368)
			(xy 122.73762 -222.879324) (xy 122.693158 -222.900422) (xy 122.645887 -222.914114) (xy 122.597032 -222.920046)
			(xy 122.547857 -222.918065) (xy 122.499638 -222.908221) (xy 122.453622 -222.890769) (xy 122.411001 -222.866162)
			(xy 122.37288 -222.835037) (xy 122.340245 -222.7982) (xy 122.313942 -222.756604) (xy 122.294651 -222.711328)
			(xy 122.282874 -222.663544) (xy 122.278914 -222.61449) (xy 120.070118 -222.61449) (xy 120.069623 -222.639097)
			(xy 120.061728 -222.687674) (xy 120.046144 -222.734355) (xy 120.023273 -222.777932) (xy 119.993708 -222.817276)
			(xy 119.958215 -222.851368) (xy 119.917712 -222.879324) (xy 119.87325 -222.900422) (xy 119.825979 -222.914114)
			(xy 119.777124 -222.920046) (xy 119.727949 -222.918065) (xy 119.67973 -222.908221) (xy 119.633714 -222.890769)
			(xy 119.591093 -222.866162) (xy 119.552972 -222.835037) (xy 119.520337 -222.7982) (xy 119.494034 -222.756604)
			(xy 119.474743 -222.711328) (xy 119.462966 -222.663544) (xy 119.459006 -222.61449) (xy 117.249956 -222.61449)
			(xy 117.249461 -222.639097) (xy 117.241566 -222.687674) (xy 117.225982 -222.734355) (xy 117.203111 -222.777932)
			(xy 117.173546 -222.817276) (xy 117.138053 -222.851368) (xy 117.09755 -222.879324) (xy 117.053088 -222.900422)
			(xy 117.005817 -222.914114) (xy 116.956962 -222.920046) (xy 116.907787 -222.918065) (xy 116.859568 -222.908221)
			(xy 116.813552 -222.890769) (xy 116.770931 -222.866162) (xy 116.73281 -222.835037) (xy 116.700175 -222.7982)
			(xy 116.673872 -222.756604) (xy 116.654581 -222.711328) (xy 116.642804 -222.663544) (xy 116.638844 -222.61449)
			(xy 114.430048 -222.61449) (xy 114.429553 -222.639097) (xy 114.421658 -222.687674) (xy 114.406074 -222.734355)
			(xy 114.383203 -222.777932) (xy 114.353638 -222.817276) (xy 114.318145 -222.851368) (xy 114.277642 -222.879324)
			(xy 114.23318 -222.900422) (xy 114.185909 -222.914114) (xy 114.137054 -222.920046) (xy 114.087879 -222.918065)
			(xy 114.03966 -222.908221) (xy 113.993644 -222.890769) (xy 113.951023 -222.866162) (xy 113.912902 -222.835037)
			(xy 113.880267 -222.7982) (xy 113.853964 -222.756604) (xy 113.834673 -222.711328) (xy 113.822896 -222.663544)
			(xy 113.818936 -222.61449) (xy 113.489994 -222.61449) (xy 113.489499 -222.639097) (xy 113.481604 -222.687674)
			(xy 113.46602 -222.734355) (xy 113.443149 -222.777932) (xy 113.413584 -222.817276) (xy 113.378091 -222.851368)
			(xy 113.337588 -222.879324) (xy 113.293126 -222.900422) (xy 113.245855 -222.914114) (xy 113.197 -222.920046)
			(xy 113.147825 -222.918065) (xy 113.099606 -222.908221) (xy 113.05359 -222.890769) (xy 113.010969 -222.866162)
			(xy 112.972848 -222.835037) (xy 112.940213 -222.7982) (xy 112.91391 -222.756604) (xy 112.894619 -222.711328)
			(xy 112.882842 -222.663544) (xy 112.878882 -222.61449) (xy 112.40389 -222.61449) (xy 112.303306 -222.715074)
			(xy 112.296471 -222.722476) (xy 112.288762 -222.741075) (xy 112.28832 -222.751142) (xy 112.28832 -223.424496)
			(xy 113.349036 -223.424496) (xy 113.352996 -223.375442) (xy 113.364773 -223.327658) (xy 113.384064 -223.282382)
			(xy 113.410367 -223.240786) (xy 113.443002 -223.203949) (xy 113.481123 -223.172824) (xy 113.523744 -223.148217)
			(xy 113.56976 -223.130765) (xy 113.617979 -223.120921) (xy 113.667154 -223.11894) (xy 113.716009 -223.124872)
			(xy 113.76328 -223.138564) (xy 113.807742 -223.159662) (xy 113.848245 -223.187618) (xy 113.883738 -223.22171)
			(xy 113.913303 -223.261054) (xy 113.936174 -223.304631) (xy 113.951758 -223.351312) (xy 113.959653 -223.399889)
			(xy 113.960148 -223.424496) (xy 114.288836 -223.424496) (xy 114.292796 -223.375442) (xy 114.304573 -223.327658)
			(xy 114.323864 -223.282382) (xy 114.350167 -223.240786) (xy 114.382802 -223.203949) (xy 114.420923 -223.172824)
			(xy 114.463544 -223.148217) (xy 114.50956 -223.130765) (xy 114.557779 -223.120921) (xy 114.606954 -223.11894)
			(xy 114.655809 -223.124872) (xy 114.70308 -223.138564) (xy 114.747542 -223.159662) (xy 114.788045 -223.187618)
			(xy 114.823538 -223.22171) (xy 114.853103 -223.261054) (xy 114.875974 -223.304631) (xy 114.891558 -223.351312)
			(xy 114.899453 -223.399889) (xy 114.899948 -223.424496) (xy 115.22889 -223.424496) (xy 115.23285 -223.375442)
			(xy 115.244627 -223.327658) (xy 115.263918 -223.282382) (xy 115.290221 -223.240786) (xy 115.322856 -223.203949)
			(xy 115.360977 -223.172824) (xy 115.403598 -223.148217) (xy 115.449614 -223.130765) (xy 115.497833 -223.120921)
			(xy 115.547008 -223.11894) (xy 115.595863 -223.124872) (xy 115.643134 -223.138564) (xy 115.687596 -223.159662)
			(xy 115.728099 -223.187618) (xy 115.763592 -223.22171) (xy 115.793157 -223.261054) (xy 115.816028 -223.304631)
			(xy 115.831612 -223.351312) (xy 115.839507 -223.399889) (xy 115.840002 -223.424496) (xy 116.168944 -223.424496)
			(xy 116.172904 -223.375442) (xy 116.184681 -223.327658) (xy 116.203972 -223.282382) (xy 116.230275 -223.240786)
			(xy 116.26291 -223.203949) (xy 116.301031 -223.172824) (xy 116.343652 -223.148217) (xy 116.389668 -223.130765)
			(xy 116.437887 -223.120921) (xy 116.487062 -223.11894) (xy 116.535917 -223.124872) (xy 116.583188 -223.138564)
			(xy 116.62765 -223.159662) (xy 116.668153 -223.187618) (xy 116.703646 -223.22171) (xy 116.733211 -223.261054)
			(xy 116.756082 -223.304631) (xy 116.771666 -223.351312) (xy 116.779561 -223.399889) (xy 116.780056 -223.424496)
			(xy 117.108998 -223.424496) (xy 117.112958 -223.375442) (xy 117.124735 -223.327658) (xy 117.144026 -223.282382)
			(xy 117.170329 -223.240786) (xy 117.202964 -223.203949) (xy 117.241085 -223.172824) (xy 117.283706 -223.148217)
			(xy 117.329722 -223.130765) (xy 117.377941 -223.120921) (xy 117.427116 -223.11894) (xy 117.475971 -223.124872)
			(xy 117.523242 -223.138564) (xy 117.567704 -223.159662) (xy 117.608207 -223.187618) (xy 117.6437 -223.22171)
			(xy 117.673265 -223.261054) (xy 117.696136 -223.304631) (xy 117.71172 -223.351312) (xy 117.719615 -223.399889)
			(xy 117.72011 -223.424496) (xy 118.049052 -223.424496) (xy 118.053012 -223.375442) (xy 118.064789 -223.327658)
			(xy 118.08408 -223.282382) (xy 118.110383 -223.240786) (xy 118.143018 -223.203949) (xy 118.181139 -223.172824)
			(xy 118.22376 -223.148217) (xy 118.269776 -223.130765) (xy 118.317995 -223.120921) (xy 118.36717 -223.11894)
			(xy 118.416025 -223.124872) (xy 118.463296 -223.138564) (xy 118.507758 -223.159662) (xy 118.548261 -223.187618)
			(xy 118.583754 -223.22171) (xy 118.613319 -223.261054) (xy 118.63619 -223.304631) (xy 118.651774 -223.351312)
			(xy 118.659669 -223.399889) (xy 118.660164 -223.424496) (xy 118.988852 -223.424496) (xy 118.992812 -223.375442)
			(xy 119.004589 -223.327658) (xy 119.02388 -223.282382) (xy 119.050183 -223.240786) (xy 119.082818 -223.203949)
			(xy 119.120939 -223.172824) (xy 119.16356 -223.148217) (xy 119.209576 -223.130765) (xy 119.257795 -223.120921)
			(xy 119.30697 -223.11894) (xy 119.355825 -223.124872) (xy 119.403096 -223.138564) (xy 119.447558 -223.159662)
			(xy 119.488061 -223.187618) (xy 119.523554 -223.22171) (xy 119.553119 -223.261054) (xy 119.57599 -223.304631)
			(xy 119.591574 -223.351312) (xy 119.599469 -223.399889) (xy 119.599964 -223.424496) (xy 119.928906 -223.424496)
			(xy 119.932866 -223.375442) (xy 119.944643 -223.327658) (xy 119.963934 -223.282382) (xy 119.990237 -223.240786)
			(xy 120.022872 -223.203949) (xy 120.060993 -223.172824) (xy 120.103614 -223.148217) (xy 120.14963 -223.130765)
			(xy 120.197849 -223.120921) (xy 120.247024 -223.11894) (xy 120.295879 -223.124872) (xy 120.34315 -223.138564)
			(xy 120.387612 -223.159662) (xy 120.428115 -223.187618) (xy 120.463608 -223.22171) (xy 120.493173 -223.261054)
			(xy 120.516044 -223.304631) (xy 120.531628 -223.351312) (xy 120.539523 -223.399889) (xy 120.540018 -223.424496)
			(xy 120.86896 -223.424496) (xy 120.87292 -223.375442) (xy 120.884697 -223.327658) (xy 120.903988 -223.282382)
			(xy 120.930291 -223.240786) (xy 120.962926 -223.203949) (xy 121.001047 -223.172824) (xy 121.043668 -223.148217)
			(xy 121.089684 -223.130765) (xy 121.137903 -223.120921) (xy 121.187078 -223.11894) (xy 121.235933 -223.124872)
			(xy 121.283204 -223.138564) (xy 121.327666 -223.159662) (xy 121.368169 -223.187618) (xy 121.403662 -223.22171)
			(xy 121.433227 -223.261054) (xy 121.456098 -223.304631) (xy 121.471682 -223.351312) (xy 121.479577 -223.399889)
			(xy 121.480072 -223.424496) (xy 121.809014 -223.424496) (xy 121.812974 -223.375442) (xy 121.824751 -223.327658)
			(xy 121.844042 -223.282382) (xy 121.870345 -223.240786) (xy 121.90298 -223.203949) (xy 121.941101 -223.172824)
			(xy 121.983722 -223.148217) (xy 122.029738 -223.130765) (xy 122.077957 -223.120921) (xy 122.127132 -223.11894)
			(xy 122.175987 -223.124872) (xy 122.223258 -223.138564) (xy 122.26772 -223.159662) (xy 122.308223 -223.187618)
			(xy 122.343716 -223.22171) (xy 122.373281 -223.261054) (xy 122.396152 -223.304631) (xy 122.411736 -223.351312)
			(xy 122.419631 -223.399889) (xy 122.420126 -223.424496) (xy 122.748814 -223.424496) (xy 122.752774 -223.375442)
			(xy 122.764551 -223.327658) (xy 122.783842 -223.282382) (xy 122.810145 -223.240786) (xy 122.84278 -223.203949)
			(xy 122.880901 -223.172824) (xy 122.923522 -223.148217) (xy 122.969538 -223.130765) (xy 123.017757 -223.120921)
			(xy 123.066932 -223.11894) (xy 123.115787 -223.124872) (xy 123.163058 -223.138564) (xy 123.20752 -223.159662)
			(xy 123.248023 -223.187618) (xy 123.283516 -223.22171) (xy 123.313081 -223.261054) (xy 123.335952 -223.304631)
			(xy 123.351536 -223.351312) (xy 123.359431 -223.399889) (xy 123.359926 -223.424496) (xy 123.688868 -223.424496)
			(xy 123.692828 -223.375442) (xy 123.704605 -223.327658) (xy 123.723896 -223.282382) (xy 123.750199 -223.240786)
			(xy 123.782834 -223.203949) (xy 123.820955 -223.172824) (xy 123.863576 -223.148217) (xy 123.909592 -223.130765)
			(xy 123.957811 -223.120921) (xy 124.006986 -223.11894) (xy 124.055841 -223.124872) (xy 124.103112 -223.138564)
			(xy 124.147574 -223.159662) (xy 124.188077 -223.187618) (xy 124.22357 -223.22171) (xy 124.253135 -223.261054)
			(xy 124.276006 -223.304631) (xy 124.29159 -223.351312) (xy 124.299485 -223.399889) (xy 124.29998 -223.424496)
			(xy 124.628922 -223.424496) (xy 124.632882 -223.375442) (xy 124.644659 -223.327658) (xy 124.66395 -223.282382)
			(xy 124.690253 -223.240786) (xy 124.722888 -223.203949) (xy 124.761009 -223.172824) (xy 124.80363 -223.148217)
			(xy 124.849646 -223.130765) (xy 124.897865 -223.120921) (xy 124.94704 -223.11894) (xy 124.995895 -223.124872)
			(xy 125.043166 -223.138564) (xy 125.087628 -223.159662) (xy 125.128131 -223.187618) (xy 125.163624 -223.22171)
			(xy 125.193189 -223.261054) (xy 125.21606 -223.304631) (xy 125.231644 -223.351312) (xy 125.239539 -223.399889)
			(xy 125.240034 -223.424496) (xy 125.568976 -223.424496) (xy 125.572936 -223.375442) (xy 125.584713 -223.327658)
			(xy 125.604004 -223.282382) (xy 125.630307 -223.240786) (xy 125.662942 -223.203949) (xy 125.701063 -223.172824)
			(xy 125.743684 -223.148217) (xy 125.7897 -223.130765) (xy 125.837919 -223.120921) (xy 125.887094 -223.11894)
			(xy 125.935949 -223.124872) (xy 125.98322 -223.138564) (xy 126.027682 -223.159662) (xy 126.068185 -223.187618)
			(xy 126.103678 -223.22171) (xy 126.133243 -223.261054) (xy 126.156114 -223.304631) (xy 126.171698 -223.351312)
			(xy 126.179593 -223.399889) (xy 126.180088 -223.424496) (xy 126.50903 -223.424496) (xy 126.51299 -223.375442)
			(xy 126.524767 -223.327658) (xy 126.544058 -223.282382) (xy 126.570361 -223.240786) (xy 126.602996 -223.203949)
			(xy 126.641117 -223.172824) (xy 126.683738 -223.148217) (xy 126.729754 -223.130765) (xy 126.777973 -223.120921)
			(xy 126.827148 -223.11894) (xy 126.876003 -223.124872) (xy 126.923274 -223.138564) (xy 126.967736 -223.159662)
			(xy 127.008239 -223.187618) (xy 127.043732 -223.22171) (xy 127.073297 -223.261054) (xy 127.096168 -223.304631)
			(xy 127.111752 -223.351312) (xy 127.119647 -223.399889) (xy 127.120142 -223.424496) (xy 127.44883 -223.424496)
			(xy 127.45279 -223.375442) (xy 127.464567 -223.327658) (xy 127.483858 -223.282382) (xy 127.510161 -223.240786)
			(xy 127.542796 -223.203949) (xy 127.580917 -223.172824) (xy 127.623538 -223.148217) (xy 127.669554 -223.130765)
			(xy 127.717773 -223.120921) (xy 127.766948 -223.11894) (xy 127.815803 -223.124872) (xy 127.863074 -223.138564)
			(xy 127.907536 -223.159662) (xy 127.948039 -223.187618) (xy 127.983532 -223.22171) (xy 128.013097 -223.261054)
			(xy 128.035968 -223.304631) (xy 128.051552 -223.351312) (xy 128.059447 -223.399889) (xy 128.059942 -223.424496)
			(xy 128.059447 -223.449103) (xy 128.051552 -223.49768) (xy 128.035968 -223.544361) (xy 128.013097 -223.587938)
			(xy 127.983532 -223.627282) (xy 127.948039 -223.661374) (xy 127.907536 -223.68933) (xy 127.863074 -223.710428)
			(xy 127.815803 -223.72412) (xy 127.766948 -223.730052) (xy 127.717773 -223.728071) (xy 127.669554 -223.718227)
			(xy 127.623538 -223.700775) (xy 127.580917 -223.676168) (xy 127.542796 -223.645043) (xy 127.510161 -223.608206)
			(xy 127.483858 -223.56661) (xy 127.464567 -223.521334) (xy 127.45279 -223.47355) (xy 127.44883 -223.424496)
			(xy 127.120142 -223.424496) (xy 127.119647 -223.449103) (xy 127.111752 -223.49768) (xy 127.096168 -223.544361)
			(xy 127.073297 -223.587938) (xy 127.043732 -223.627282) (xy 127.008239 -223.661374) (xy 126.967736 -223.68933)
			(xy 126.923274 -223.710428) (xy 126.876003 -223.72412) (xy 126.827148 -223.730052) (xy 126.777973 -223.728071)
			(xy 126.729754 -223.718227) (xy 126.683738 -223.700775) (xy 126.641117 -223.676168) (xy 126.602996 -223.645043)
			(xy 126.570361 -223.608206) (xy 126.544058 -223.56661) (xy 126.524767 -223.521334) (xy 126.51299 -223.47355)
			(xy 126.50903 -223.424496) (xy 126.180088 -223.424496) (xy 126.179593 -223.449103) (xy 126.171698 -223.49768)
			(xy 126.156114 -223.544361) (xy 126.133243 -223.587938) (xy 126.103678 -223.627282) (xy 126.068185 -223.661374)
			(xy 126.027682 -223.68933) (xy 125.98322 -223.710428) (xy 125.935949 -223.72412) (xy 125.887094 -223.730052)
			(xy 125.837919 -223.728071) (xy 125.7897 -223.718227) (xy 125.743684 -223.700775) (xy 125.701063 -223.676168)
			(xy 125.662942 -223.645043) (xy 125.630307 -223.608206) (xy 125.604004 -223.56661) (xy 125.584713 -223.521334)
			(xy 125.572936 -223.47355) (xy 125.568976 -223.424496) (xy 125.240034 -223.424496) (xy 125.239539 -223.449103)
			(xy 125.231644 -223.49768) (xy 125.21606 -223.544361) (xy 125.193189 -223.587938) (xy 125.163624 -223.627282)
			(xy 125.128131 -223.661374) (xy 125.087628 -223.68933) (xy 125.043166 -223.710428) (xy 124.995895 -223.72412)
			(xy 124.94704 -223.730052) (xy 124.897865 -223.728071) (xy 124.849646 -223.718227) (xy 124.80363 -223.700775)
			(xy 124.761009 -223.676168) (xy 124.722888 -223.645043) (xy 124.690253 -223.608206) (xy 124.66395 -223.56661)
			(xy 124.644659 -223.521334) (xy 124.632882 -223.47355) (xy 124.628922 -223.424496) (xy 124.29998 -223.424496)
			(xy 124.299485 -223.449103) (xy 124.29159 -223.49768) (xy 124.276006 -223.544361) (xy 124.253135 -223.587938)
			(xy 124.22357 -223.627282) (xy 124.188077 -223.661374) (xy 124.147574 -223.68933) (xy 124.103112 -223.710428)
			(xy 124.055841 -223.72412) (xy 124.006986 -223.730052) (xy 123.957811 -223.728071) (xy 123.909592 -223.718227)
			(xy 123.863576 -223.700775) (xy 123.820955 -223.676168) (xy 123.782834 -223.645043) (xy 123.750199 -223.608206)
			(xy 123.723896 -223.56661) (xy 123.704605 -223.521334) (xy 123.692828 -223.47355) (xy 123.688868 -223.424496)
			(xy 123.359926 -223.424496) (xy 123.359431 -223.449103) (xy 123.351536 -223.49768) (xy 123.335952 -223.544361)
			(xy 123.313081 -223.587938) (xy 123.283516 -223.627282) (xy 123.248023 -223.661374) (xy 123.20752 -223.68933)
			(xy 123.163058 -223.710428) (xy 123.115787 -223.72412) (xy 123.066932 -223.730052) (xy 123.017757 -223.728071)
			(xy 122.969538 -223.718227) (xy 122.923522 -223.700775) (xy 122.880901 -223.676168) (xy 122.84278 -223.645043)
			(xy 122.810145 -223.608206) (xy 122.783842 -223.56661) (xy 122.764551 -223.521334) (xy 122.752774 -223.47355)
			(xy 122.748814 -223.424496) (xy 122.420126 -223.424496) (xy 122.419631 -223.449103) (xy 122.411736 -223.49768)
			(xy 122.396152 -223.544361) (xy 122.373281 -223.587938) (xy 122.343716 -223.627282) (xy 122.308223 -223.661374)
			(xy 122.26772 -223.68933) (xy 122.223258 -223.710428) (xy 122.175987 -223.72412) (xy 122.127132 -223.730052)
			(xy 122.077957 -223.728071) (xy 122.029738 -223.718227) (xy 121.983722 -223.700775) (xy 121.941101 -223.676168)
			(xy 121.90298 -223.645043) (xy 121.870345 -223.608206) (xy 121.844042 -223.56661) (xy 121.824751 -223.521334)
			(xy 121.812974 -223.47355) (xy 121.809014 -223.424496) (xy 121.480072 -223.424496) (xy 121.479577 -223.449103)
			(xy 121.471682 -223.49768) (xy 121.456098 -223.544361) (xy 121.433227 -223.587938) (xy 121.403662 -223.627282)
			(xy 121.368169 -223.661374) (xy 121.327666 -223.68933) (xy 121.283204 -223.710428) (xy 121.235933 -223.72412)
			(xy 121.187078 -223.730052) (xy 121.137903 -223.728071) (xy 121.089684 -223.718227) (xy 121.043668 -223.700775)
			(xy 121.001047 -223.676168) (xy 120.962926 -223.645043) (xy 120.930291 -223.608206) (xy 120.903988 -223.56661)
			(xy 120.884697 -223.521334) (xy 120.87292 -223.47355) (xy 120.86896 -223.424496) (xy 120.540018 -223.424496)
			(xy 120.539523 -223.449103) (xy 120.531628 -223.49768) (xy 120.516044 -223.544361) (xy 120.493173 -223.587938)
			(xy 120.463608 -223.627282) (xy 120.428115 -223.661374) (xy 120.387612 -223.68933) (xy 120.34315 -223.710428)
			(xy 120.295879 -223.72412) (xy 120.247024 -223.730052) (xy 120.197849 -223.728071) (xy 120.14963 -223.718227)
			(xy 120.103614 -223.700775) (xy 120.060993 -223.676168) (xy 120.022872 -223.645043) (xy 119.990237 -223.608206)
			(xy 119.963934 -223.56661) (xy 119.944643 -223.521334) (xy 119.932866 -223.47355) (xy 119.928906 -223.424496)
			(xy 119.599964 -223.424496) (xy 119.599469 -223.449103) (xy 119.591574 -223.49768) (xy 119.57599 -223.544361)
			(xy 119.553119 -223.587938) (xy 119.523554 -223.627282) (xy 119.488061 -223.661374) (xy 119.447558 -223.68933)
			(xy 119.403096 -223.710428) (xy 119.355825 -223.72412) (xy 119.30697 -223.730052) (xy 119.257795 -223.728071)
			(xy 119.209576 -223.718227) (xy 119.16356 -223.700775) (xy 119.120939 -223.676168) (xy 119.082818 -223.645043)
			(xy 119.050183 -223.608206) (xy 119.02388 -223.56661) (xy 119.004589 -223.521334) (xy 118.992812 -223.47355)
			(xy 118.988852 -223.424496) (xy 118.660164 -223.424496) (xy 118.659669 -223.449103) (xy 118.651774 -223.49768)
			(xy 118.63619 -223.544361) (xy 118.613319 -223.587938) (xy 118.583754 -223.627282) (xy 118.548261 -223.661374)
			(xy 118.507758 -223.68933) (xy 118.463296 -223.710428) (xy 118.416025 -223.72412) (xy 118.36717 -223.730052)
			(xy 118.317995 -223.728071) (xy 118.269776 -223.718227) (xy 118.22376 -223.700775) (xy 118.181139 -223.676168)
			(xy 118.143018 -223.645043) (xy 118.110383 -223.608206) (xy 118.08408 -223.56661) (xy 118.064789 -223.521334)
			(xy 118.053012 -223.47355) (xy 118.049052 -223.424496) (xy 117.72011 -223.424496) (xy 117.719615 -223.449103)
			(xy 117.71172 -223.49768) (xy 117.696136 -223.544361) (xy 117.673265 -223.587938) (xy 117.6437 -223.627282)
			(xy 117.608207 -223.661374) (xy 117.567704 -223.68933) (xy 117.523242 -223.710428) (xy 117.475971 -223.72412)
			(xy 117.427116 -223.730052) (xy 117.377941 -223.728071) (xy 117.329722 -223.718227) (xy 117.283706 -223.700775)
			(xy 117.241085 -223.676168) (xy 117.202964 -223.645043) (xy 117.170329 -223.608206) (xy 117.144026 -223.56661)
			(xy 117.124735 -223.521334) (xy 117.112958 -223.47355) (xy 117.108998 -223.424496) (xy 116.780056 -223.424496)
			(xy 116.779561 -223.449103) (xy 116.771666 -223.49768) (xy 116.756082 -223.544361) (xy 116.733211 -223.587938)
			(xy 116.703646 -223.627282) (xy 116.668153 -223.661374) (xy 116.62765 -223.68933) (xy 116.583188 -223.710428)
			(xy 116.535917 -223.72412) (xy 116.487062 -223.730052) (xy 116.437887 -223.728071) (xy 116.389668 -223.718227)
			(xy 116.343652 -223.700775) (xy 116.301031 -223.676168) (xy 116.26291 -223.645043) (xy 116.230275 -223.608206)
			(xy 116.203972 -223.56661) (xy 116.184681 -223.521334) (xy 116.172904 -223.47355) (xy 116.168944 -223.424496)
			(xy 115.840002 -223.424496) (xy 115.839507 -223.449103) (xy 115.831612 -223.49768) (xy 115.816028 -223.544361)
			(xy 115.793157 -223.587938) (xy 115.763592 -223.627282) (xy 115.728099 -223.661374) (xy 115.687596 -223.68933)
			(xy 115.643134 -223.710428) (xy 115.595863 -223.72412) (xy 115.547008 -223.730052) (xy 115.497833 -223.728071)
			(xy 115.449614 -223.718227) (xy 115.403598 -223.700775) (xy 115.360977 -223.676168) (xy 115.322856 -223.645043)
			(xy 115.290221 -223.608206) (xy 115.263918 -223.56661) (xy 115.244627 -223.521334) (xy 115.23285 -223.47355)
			(xy 115.22889 -223.424496) (xy 114.899948 -223.424496) (xy 114.899453 -223.449103) (xy 114.891558 -223.49768)
			(xy 114.875974 -223.544361) (xy 114.853103 -223.587938) (xy 114.823538 -223.627282) (xy 114.788045 -223.661374)
			(xy 114.747542 -223.68933) (xy 114.70308 -223.710428) (xy 114.655809 -223.72412) (xy 114.606954 -223.730052)
			(xy 114.557779 -223.728071) (xy 114.50956 -223.718227) (xy 114.463544 -223.700775) (xy 114.420923 -223.676168)
			(xy 114.382802 -223.645043) (xy 114.350167 -223.608206) (xy 114.323864 -223.56661) (xy 114.304573 -223.521334)
			(xy 114.292796 -223.47355) (xy 114.288836 -223.424496) (xy 113.960148 -223.424496) (xy 113.959653 -223.449103)
			(xy 113.951758 -223.49768) (xy 113.936174 -223.544361) (xy 113.913303 -223.587938) (xy 113.883738 -223.627282)
			(xy 113.848245 -223.661374) (xy 113.807742 -223.68933) (xy 113.76328 -223.710428) (xy 113.716009 -223.72412)
			(xy 113.667154 -223.730052) (xy 113.617979 -223.728071) (xy 113.56976 -223.718227) (xy 113.523744 -223.700775)
			(xy 113.481123 -223.676168) (xy 113.443002 -223.645043) (xy 113.410367 -223.608206) (xy 113.384064 -223.56661)
			(xy 113.364773 -223.521334) (xy 113.352996 -223.47355) (xy 113.349036 -223.424496) (xy 112.28832 -223.424496)
			(xy 112.28832 -224.234502) (xy 112.878882 -224.234502) (xy 112.882842 -224.185448) (xy 112.894619 -224.137664)
			(xy 112.91391 -224.092388) (xy 112.940213 -224.050792) (xy 112.972848 -224.013955) (xy 113.010969 -223.98283)
			(xy 113.05359 -223.958223) (xy 113.099606 -223.940771) (xy 113.147825 -223.930927) (xy 113.197 -223.928946)
			(xy 113.245855 -223.934878) (xy 113.293126 -223.94857) (xy 113.337588 -223.969668) (xy 113.378091 -223.997624)
			(xy 113.413584 -224.031716) (xy 113.443149 -224.07106) (xy 113.46602 -224.114637) (xy 113.481604 -224.161318)
			(xy 113.489499 -224.209895) (xy 113.489994 -224.234502) (xy 113.818936 -224.234502) (xy 113.822896 -224.185448)
			(xy 113.834673 -224.137664) (xy 113.853964 -224.092388) (xy 113.880267 -224.050792) (xy 113.912902 -224.013955)
			(xy 113.951023 -223.98283) (xy 113.993644 -223.958223) (xy 114.03966 -223.940771) (xy 114.087879 -223.930927)
			(xy 114.137054 -223.928946) (xy 114.185909 -223.934878) (xy 114.23318 -223.94857) (xy 114.277642 -223.969668)
			(xy 114.318145 -223.997624) (xy 114.353638 -224.031716) (xy 114.383203 -224.07106) (xy 114.406074 -224.114637)
			(xy 114.421658 -224.161318) (xy 114.429553 -224.209895) (xy 114.430048 -224.234502) (xy 114.75899 -224.234502)
			(xy 114.76295 -224.185448) (xy 114.774727 -224.137664) (xy 114.794018 -224.092388) (xy 114.820321 -224.050792)
			(xy 114.852956 -224.013955) (xy 114.891077 -223.98283) (xy 114.933698 -223.958223) (xy 114.979714 -223.940771)
			(xy 115.027933 -223.930927) (xy 115.077108 -223.928946) (xy 115.125963 -223.934878) (xy 115.173234 -223.94857)
			(xy 115.217696 -223.969668) (xy 115.258199 -223.997624) (xy 115.293692 -224.031716) (xy 115.323257 -224.07106)
			(xy 115.346128 -224.114637) (xy 115.361712 -224.161318) (xy 115.369607 -224.209895) (xy 115.370102 -224.234502)
			(xy 115.699044 -224.234502) (xy 115.703004 -224.185448) (xy 115.714781 -224.137664) (xy 115.734072 -224.092388)
			(xy 115.760375 -224.050792) (xy 115.79301 -224.013955) (xy 115.831131 -223.98283) (xy 115.873752 -223.958223)
			(xy 115.919768 -223.940771) (xy 115.967987 -223.930927) (xy 116.017162 -223.928946) (xy 116.066017 -223.934878)
			(xy 116.113288 -223.94857) (xy 116.15775 -223.969668) (xy 116.198253 -223.997624) (xy 116.233746 -224.031716)
			(xy 116.263311 -224.07106) (xy 116.286182 -224.114637) (xy 116.301766 -224.161318) (xy 116.309661 -224.209895)
			(xy 116.310156 -224.234502) (xy 116.638844 -224.234502) (xy 116.642804 -224.185448) (xy 116.654581 -224.137664)
			(xy 116.673872 -224.092388) (xy 116.700175 -224.050792) (xy 116.73281 -224.013955) (xy 116.770931 -223.98283)
			(xy 116.813552 -223.958223) (xy 116.859568 -223.940771) (xy 116.907787 -223.930927) (xy 116.956962 -223.928946)
			(xy 117.005817 -223.934878) (xy 117.053088 -223.94857) (xy 117.09755 -223.969668) (xy 117.138053 -223.997624)
			(xy 117.173546 -224.031716) (xy 117.203111 -224.07106) (xy 117.225982 -224.114637) (xy 117.241566 -224.161318)
			(xy 117.249461 -224.209895) (xy 117.249956 -224.234502) (xy 117.578898 -224.234502) (xy 117.582858 -224.185448)
			(xy 117.594635 -224.137664) (xy 117.613926 -224.092388) (xy 117.640229 -224.050792) (xy 117.672864 -224.013955)
			(xy 117.710985 -223.98283) (xy 117.753606 -223.958223) (xy 117.799622 -223.940771) (xy 117.847841 -223.930927)
			(xy 117.897016 -223.928946) (xy 117.945871 -223.934878) (xy 117.993142 -223.94857) (xy 118.037604 -223.969668)
			(xy 118.078107 -223.997624) (xy 118.1136 -224.031716) (xy 118.143165 -224.07106) (xy 118.166036 -224.114637)
			(xy 118.18162 -224.161318) (xy 118.189515 -224.209895) (xy 118.19001 -224.234502) (xy 118.518952 -224.234502)
			(xy 118.522912 -224.185448) (xy 118.534689 -224.137664) (xy 118.55398 -224.092388) (xy 118.580283 -224.050792)
			(xy 118.612918 -224.013955) (xy 118.651039 -223.98283) (xy 118.69366 -223.958223) (xy 118.739676 -223.940771)
			(xy 118.787895 -223.930927) (xy 118.83707 -223.928946) (xy 118.885925 -223.934878) (xy 118.933196 -223.94857)
			(xy 118.977658 -223.969668) (xy 119.018161 -223.997624) (xy 119.053654 -224.031716) (xy 119.083219 -224.07106)
			(xy 119.10609 -224.114637) (xy 119.121674 -224.161318) (xy 119.129569 -224.209895) (xy 119.130064 -224.234502)
			(xy 119.459006 -224.234502) (xy 119.462966 -224.185448) (xy 119.474743 -224.137664) (xy 119.494034 -224.092388)
			(xy 119.520337 -224.050792) (xy 119.552972 -224.013955) (xy 119.591093 -223.98283) (xy 119.633714 -223.958223)
			(xy 119.67973 -223.940771) (xy 119.727949 -223.930927) (xy 119.777124 -223.928946) (xy 119.825979 -223.934878)
			(xy 119.87325 -223.94857) (xy 119.917712 -223.969668) (xy 119.958215 -223.997624) (xy 119.993708 -224.031716)
			(xy 120.023273 -224.07106) (xy 120.046144 -224.114637) (xy 120.061728 -224.161318) (xy 120.069623 -224.209895)
			(xy 120.070118 -224.234502) (xy 120.398806 -224.234502) (xy 120.402766 -224.185448) (xy 120.414543 -224.137664)
			(xy 120.433834 -224.092388) (xy 120.460137 -224.050792) (xy 120.492772 -224.013955) (xy 120.530893 -223.98283)
			(xy 120.573514 -223.958223) (xy 120.61953 -223.940771) (xy 120.667749 -223.930927) (xy 120.716924 -223.928946)
			(xy 120.765779 -223.934878) (xy 120.81305 -223.94857) (xy 120.857512 -223.969668) (xy 120.898015 -223.997624)
			(xy 120.933508 -224.031716) (xy 120.963073 -224.07106) (xy 120.985944 -224.114637) (xy 121.001528 -224.161318)
			(xy 121.009423 -224.209895) (xy 121.009918 -224.234502) (xy 121.33886 -224.234502) (xy 121.34282 -224.185448)
			(xy 121.354597 -224.137664) (xy 121.373888 -224.092388) (xy 121.400191 -224.050792) (xy 121.432826 -224.013955)
			(xy 121.470947 -223.98283) (xy 121.513568 -223.958223) (xy 121.559584 -223.940771) (xy 121.607803 -223.930927)
			(xy 121.656978 -223.928946) (xy 121.705833 -223.934878) (xy 121.753104 -223.94857) (xy 121.797566 -223.969668)
			(xy 121.838069 -223.997624) (xy 121.873562 -224.031716) (xy 121.903127 -224.07106) (xy 121.925998 -224.114637)
			(xy 121.941582 -224.161318) (xy 121.949477 -224.209895) (xy 121.949972 -224.234502) (xy 122.278914 -224.234502)
			(xy 122.282874 -224.185448) (xy 122.294651 -224.137664) (xy 122.313942 -224.092388) (xy 122.340245 -224.050792)
			(xy 122.37288 -224.013955) (xy 122.411001 -223.98283) (xy 122.453622 -223.958223) (xy 122.499638 -223.940771)
			(xy 122.547857 -223.930927) (xy 122.597032 -223.928946) (xy 122.645887 -223.934878) (xy 122.693158 -223.94857)
			(xy 122.73762 -223.969668) (xy 122.778123 -223.997624) (xy 122.813616 -224.031716) (xy 122.843181 -224.07106)
			(xy 122.866052 -224.114637) (xy 122.881636 -224.161318) (xy 122.889531 -224.209895) (xy 122.890026 -224.234502)
			(xy 123.218968 -224.234502) (xy 123.222928 -224.185448) (xy 123.234705 -224.137664) (xy 123.253996 -224.092388)
			(xy 123.280299 -224.050792) (xy 123.312934 -224.013955) (xy 123.351055 -223.98283) (xy 123.393676 -223.958223)
			(xy 123.439692 -223.940771) (xy 123.487911 -223.930927) (xy 123.537086 -223.928946) (xy 123.585941 -223.934878)
			(xy 123.633212 -223.94857) (xy 123.677674 -223.969668) (xy 123.718177 -223.997624) (xy 123.75367 -224.031716)
			(xy 123.783235 -224.07106) (xy 123.806106 -224.114637) (xy 123.82169 -224.161318) (xy 123.829585 -224.209895)
			(xy 123.83008 -224.234502) (xy 124.159022 -224.234502) (xy 124.162982 -224.185448) (xy 124.174759 -224.137664)
			(xy 124.19405 -224.092388) (xy 124.220353 -224.050792) (xy 124.252988 -224.013955) (xy 124.291109 -223.98283)
			(xy 124.33373 -223.958223) (xy 124.379746 -223.940771) (xy 124.427965 -223.930927) (xy 124.47714 -223.928946)
			(xy 124.525995 -223.934878) (xy 124.573266 -223.94857) (xy 124.617728 -223.969668) (xy 124.658231 -223.997624)
			(xy 124.693724 -224.031716) (xy 124.723289 -224.07106) (xy 124.74616 -224.114637) (xy 124.761744 -224.161318)
			(xy 124.769639 -224.209895) (xy 124.770134 -224.234502) (xy 125.098822 -224.234502) (xy 125.102782 -224.185448)
			(xy 125.114559 -224.137664) (xy 125.13385 -224.092388) (xy 125.160153 -224.050792) (xy 125.192788 -224.013955)
			(xy 125.230909 -223.98283) (xy 125.27353 -223.958223) (xy 125.319546 -223.940771) (xy 125.367765 -223.930927)
			(xy 125.41694 -223.928946) (xy 125.465795 -223.934878) (xy 125.513066 -223.94857) (xy 125.557528 -223.969668)
			(xy 125.598031 -223.997624) (xy 125.633524 -224.031716) (xy 125.663089 -224.07106) (xy 125.68596 -224.114637)
			(xy 125.701544 -224.161318) (xy 125.709439 -224.209895) (xy 125.709934 -224.234502) (xy 126.038876 -224.234502)
			(xy 126.042836 -224.185448) (xy 126.054613 -224.137664) (xy 126.073904 -224.092388) (xy 126.100207 -224.050792)
			(xy 126.132842 -224.013955) (xy 126.170963 -223.98283) (xy 126.213584 -223.958223) (xy 126.2596 -223.940771)
			(xy 126.307819 -223.930927) (xy 126.356994 -223.928946) (xy 126.405849 -223.934878) (xy 126.45312 -223.94857)
			(xy 126.497582 -223.969668) (xy 126.538085 -223.997624) (xy 126.573578 -224.031716) (xy 126.603143 -224.07106)
			(xy 126.626014 -224.114637) (xy 126.641598 -224.161318) (xy 126.649493 -224.209895) (xy 126.649988 -224.234502)
			(xy 126.97893 -224.234502) (xy 126.98289 -224.185448) (xy 126.994667 -224.137664) (xy 127.013958 -224.092388)
			(xy 127.040261 -224.050792) (xy 127.072896 -224.013955) (xy 127.111017 -223.98283) (xy 127.153638 -223.958223)
			(xy 127.199654 -223.940771) (xy 127.247873 -223.930927) (xy 127.297048 -223.928946) (xy 127.345903 -223.934878)
			(xy 127.393174 -223.94857) (xy 127.437636 -223.969668) (xy 127.478139 -223.997624) (xy 127.513632 -224.031716)
			(xy 127.543197 -224.07106) (xy 127.566068 -224.114637) (xy 127.581652 -224.161318) (xy 127.589547 -224.209895)
			(xy 127.590042 -224.234502) (xy 127.918984 -224.234502) (xy 127.922944 -224.185448) (xy 127.934721 -224.137664)
			(xy 127.954012 -224.092388) (xy 127.980315 -224.050792) (xy 128.01295 -224.013955) (xy 128.051071 -223.98283)
			(xy 128.093692 -223.958223) (xy 128.139708 -223.940771) (xy 128.187927 -223.930927) (xy 128.237102 -223.928946)
			(xy 128.285957 -223.934878) (xy 128.333228 -223.94857) (xy 128.37769 -223.969668) (xy 128.418193 -223.997624)
			(xy 128.453686 -224.031716) (xy 128.483251 -224.07106) (xy 128.506122 -224.114637) (xy 128.521706 -224.161318)
			(xy 128.529601 -224.209895) (xy 128.530096 -224.234502) (xy 128.529601 -224.259109) (xy 128.521706 -224.307686)
			(xy 128.506122 -224.354367) (xy 128.483251 -224.397944) (xy 128.453686 -224.437288) (xy 128.418193 -224.47138)
			(xy 128.37769 -224.499336) (xy 128.333228 -224.520434) (xy 128.285957 -224.534126) (xy 128.237102 -224.540058)
			(xy 128.187927 -224.538077) (xy 128.139708 -224.528233) (xy 128.093692 -224.510781) (xy 128.051071 -224.486174)
			(xy 128.01295 -224.455049) (xy 127.980315 -224.418212) (xy 127.954012 -224.376616) (xy 127.934721 -224.33134)
			(xy 127.922944 -224.283556) (xy 127.918984 -224.234502) (xy 127.590042 -224.234502) (xy 127.589547 -224.259109)
			(xy 127.581652 -224.307686) (xy 127.566068 -224.354367) (xy 127.543197 -224.397944) (xy 127.513632 -224.437288)
			(xy 127.478139 -224.47138) (xy 127.437636 -224.499336) (xy 127.393174 -224.520434) (xy 127.345903 -224.534126)
			(xy 127.297048 -224.540058) (xy 127.247873 -224.538077) (xy 127.199654 -224.528233) (xy 127.153638 -224.510781)
			(xy 127.111017 -224.486174) (xy 127.072896 -224.455049) (xy 127.040261 -224.418212) (xy 127.013958 -224.376616)
			(xy 126.994667 -224.33134) (xy 126.98289 -224.283556) (xy 126.97893 -224.234502) (xy 126.649988 -224.234502)
			(xy 126.649493 -224.259109) (xy 126.641598 -224.307686) (xy 126.626014 -224.354367) (xy 126.603143 -224.397944)
			(xy 126.573578 -224.437288) (xy 126.538085 -224.47138) (xy 126.497582 -224.499336) (xy 126.45312 -224.520434)
			(xy 126.405849 -224.534126) (xy 126.356994 -224.540058) (xy 126.307819 -224.538077) (xy 126.2596 -224.528233)
			(xy 126.213584 -224.510781) (xy 126.170963 -224.486174) (xy 126.132842 -224.455049) (xy 126.100207 -224.418212)
			(xy 126.073904 -224.376616) (xy 126.054613 -224.33134) (xy 126.042836 -224.283556) (xy 126.038876 -224.234502)
			(xy 125.709934 -224.234502) (xy 125.709439 -224.259109) (xy 125.701544 -224.307686) (xy 125.68596 -224.354367)
			(xy 125.663089 -224.397944) (xy 125.633524 -224.437288) (xy 125.598031 -224.47138) (xy 125.557528 -224.499336)
			(xy 125.513066 -224.520434) (xy 125.465795 -224.534126) (xy 125.41694 -224.540058) (xy 125.367765 -224.538077)
			(xy 125.319546 -224.528233) (xy 125.27353 -224.510781) (xy 125.230909 -224.486174) (xy 125.192788 -224.455049)
			(xy 125.160153 -224.418212) (xy 125.13385 -224.376616) (xy 125.114559 -224.33134) (xy 125.102782 -224.283556)
			(xy 125.098822 -224.234502) (xy 124.770134 -224.234502) (xy 124.769639 -224.259109) (xy 124.761744 -224.307686)
			(xy 124.74616 -224.354367) (xy 124.723289 -224.397944) (xy 124.693724 -224.437288) (xy 124.658231 -224.47138)
			(xy 124.617728 -224.499336) (xy 124.573266 -224.520434) (xy 124.525995 -224.534126) (xy 124.47714 -224.540058)
			(xy 124.427965 -224.538077) (xy 124.379746 -224.528233) (xy 124.33373 -224.510781) (xy 124.291109 -224.486174)
			(xy 124.252988 -224.455049) (xy 124.220353 -224.418212) (xy 124.19405 -224.376616) (xy 124.174759 -224.33134)
			(xy 124.162982 -224.283556) (xy 124.159022 -224.234502) (xy 123.83008 -224.234502) (xy 123.829585 -224.259109)
			(xy 123.82169 -224.307686) (xy 123.806106 -224.354367) (xy 123.783235 -224.397944) (xy 123.75367 -224.437288)
			(xy 123.718177 -224.47138) (xy 123.677674 -224.499336) (xy 123.633212 -224.520434) (xy 123.585941 -224.534126)
			(xy 123.537086 -224.540058) (xy 123.487911 -224.538077) (xy 123.439692 -224.528233) (xy 123.393676 -224.510781)
			(xy 123.351055 -224.486174) (xy 123.312934 -224.455049) (xy 123.280299 -224.418212) (xy 123.253996 -224.376616)
			(xy 123.234705 -224.33134) (xy 123.222928 -224.283556) (xy 123.218968 -224.234502) (xy 122.890026 -224.234502)
			(xy 122.889531 -224.259109) (xy 122.881636 -224.307686) (xy 122.866052 -224.354367) (xy 122.843181 -224.397944)
			(xy 122.813616 -224.437288) (xy 122.778123 -224.47138) (xy 122.73762 -224.499336) (xy 122.693158 -224.520434)
			(xy 122.645887 -224.534126) (xy 122.597032 -224.540058) (xy 122.547857 -224.538077) (xy 122.499638 -224.528233)
			(xy 122.453622 -224.510781) (xy 122.411001 -224.486174) (xy 122.37288 -224.455049) (xy 122.340245 -224.418212)
			(xy 122.313942 -224.376616) (xy 122.294651 -224.33134) (xy 122.282874 -224.283556) (xy 122.278914 -224.234502)
			(xy 121.949972 -224.234502) (xy 121.949477 -224.259109) (xy 121.941582 -224.307686) (xy 121.925998 -224.354367)
			(xy 121.903127 -224.397944) (xy 121.873562 -224.437288) (xy 121.838069 -224.47138) (xy 121.797566 -224.499336)
			(xy 121.753104 -224.520434) (xy 121.705833 -224.534126) (xy 121.656978 -224.540058) (xy 121.607803 -224.538077)
			(xy 121.559584 -224.528233) (xy 121.513568 -224.510781) (xy 121.470947 -224.486174) (xy 121.432826 -224.455049)
			(xy 121.400191 -224.418212) (xy 121.373888 -224.376616) (xy 121.354597 -224.33134) (xy 121.34282 -224.283556)
			(xy 121.33886 -224.234502) (xy 121.009918 -224.234502) (xy 121.009423 -224.259109) (xy 121.001528 -224.307686)
			(xy 120.985944 -224.354367) (xy 120.963073 -224.397944) (xy 120.933508 -224.437288) (xy 120.898015 -224.47138)
			(xy 120.857512 -224.499336) (xy 120.81305 -224.520434) (xy 120.765779 -224.534126) (xy 120.716924 -224.540058)
			(xy 120.667749 -224.538077) (xy 120.61953 -224.528233) (xy 120.573514 -224.510781) (xy 120.530893 -224.486174)
			(xy 120.492772 -224.455049) (xy 120.460137 -224.418212) (xy 120.433834 -224.376616) (xy 120.414543 -224.33134)
			(xy 120.402766 -224.283556) (xy 120.398806 -224.234502) (xy 120.070118 -224.234502) (xy 120.069623 -224.259109)
			(xy 120.061728 -224.307686) (xy 120.046144 -224.354367) (xy 120.023273 -224.397944) (xy 119.993708 -224.437288)
			(xy 119.958215 -224.47138) (xy 119.917712 -224.499336) (xy 119.87325 -224.520434) (xy 119.825979 -224.534126)
			(xy 119.777124 -224.540058) (xy 119.727949 -224.538077) (xy 119.67973 -224.528233) (xy 119.633714 -224.510781)
			(xy 119.591093 -224.486174) (xy 119.552972 -224.455049) (xy 119.520337 -224.418212) (xy 119.494034 -224.376616)
			(xy 119.474743 -224.33134) (xy 119.462966 -224.283556) (xy 119.459006 -224.234502) (xy 119.130064 -224.234502)
			(xy 119.129569 -224.259109) (xy 119.121674 -224.307686) (xy 119.10609 -224.354367) (xy 119.083219 -224.397944)
			(xy 119.053654 -224.437288) (xy 119.018161 -224.47138) (xy 118.977658 -224.499336) (xy 118.933196 -224.520434)
			(xy 118.885925 -224.534126) (xy 118.83707 -224.540058) (xy 118.787895 -224.538077) (xy 118.739676 -224.528233)
			(xy 118.69366 -224.510781) (xy 118.651039 -224.486174) (xy 118.612918 -224.455049) (xy 118.580283 -224.418212)
			(xy 118.55398 -224.376616) (xy 118.534689 -224.33134) (xy 118.522912 -224.283556) (xy 118.518952 -224.234502)
			(xy 118.19001 -224.234502) (xy 118.189515 -224.259109) (xy 118.18162 -224.307686) (xy 118.166036 -224.354367)
			(xy 118.143165 -224.397944) (xy 118.1136 -224.437288) (xy 118.078107 -224.47138) (xy 118.037604 -224.499336)
			(xy 117.993142 -224.520434) (xy 117.945871 -224.534126) (xy 117.897016 -224.540058) (xy 117.847841 -224.538077)
			(xy 117.799622 -224.528233) (xy 117.753606 -224.510781) (xy 117.710985 -224.486174) (xy 117.672864 -224.455049)
			(xy 117.640229 -224.418212) (xy 117.613926 -224.376616) (xy 117.594635 -224.33134) (xy 117.582858 -224.283556)
			(xy 117.578898 -224.234502) (xy 117.249956 -224.234502) (xy 117.249461 -224.259109) (xy 117.241566 -224.307686)
			(xy 117.225982 -224.354367) (xy 117.203111 -224.397944) (xy 117.173546 -224.437288) (xy 117.138053 -224.47138)
			(xy 117.09755 -224.499336) (xy 117.053088 -224.520434) (xy 117.005817 -224.534126) (xy 116.956962 -224.540058)
			(xy 116.907787 -224.538077) (xy 116.859568 -224.528233) (xy 116.813552 -224.510781) (xy 116.770931 -224.486174)
			(xy 116.73281 -224.455049) (xy 116.700175 -224.418212) (xy 116.673872 -224.376616) (xy 116.654581 -224.33134)
			(xy 116.642804 -224.283556) (xy 116.638844 -224.234502) (xy 116.310156 -224.234502) (xy 116.309661 -224.259109)
			(xy 116.301766 -224.307686) (xy 116.286182 -224.354367) (xy 116.263311 -224.397944) (xy 116.233746 -224.437288)
			(xy 116.198253 -224.47138) (xy 116.15775 -224.499336) (xy 116.113288 -224.520434) (xy 116.066017 -224.534126)
			(xy 116.017162 -224.540058) (xy 115.967987 -224.538077) (xy 115.919768 -224.528233) (xy 115.873752 -224.510781)
			(xy 115.831131 -224.486174) (xy 115.79301 -224.455049) (xy 115.760375 -224.418212) (xy 115.734072 -224.376616)
			(xy 115.714781 -224.33134) (xy 115.703004 -224.283556) (xy 115.699044 -224.234502) (xy 115.370102 -224.234502)
			(xy 115.369607 -224.259109) (xy 115.361712 -224.307686) (xy 115.346128 -224.354367) (xy 115.323257 -224.397944)
			(xy 115.293692 -224.437288) (xy 115.258199 -224.47138) (xy 115.217696 -224.499336) (xy 115.173234 -224.520434)
			(xy 115.125963 -224.534126) (xy 115.077108 -224.540058) (xy 115.027933 -224.538077) (xy 114.979714 -224.528233)
			(xy 114.933698 -224.510781) (xy 114.891077 -224.486174) (xy 114.852956 -224.455049) (xy 114.820321 -224.418212)
			(xy 114.794018 -224.376616) (xy 114.774727 -224.33134) (xy 114.76295 -224.283556) (xy 114.75899 -224.234502)
			(xy 114.430048 -224.234502) (xy 114.429553 -224.259109) (xy 114.421658 -224.307686) (xy 114.406074 -224.354367)
			(xy 114.383203 -224.397944) (xy 114.353638 -224.437288) (xy 114.318145 -224.47138) (xy 114.277642 -224.499336)
			(xy 114.23318 -224.520434) (xy 114.185909 -224.534126) (xy 114.137054 -224.540058) (xy 114.087879 -224.538077)
			(xy 114.03966 -224.528233) (xy 113.993644 -224.510781) (xy 113.951023 -224.486174) (xy 113.912902 -224.455049)
			(xy 113.880267 -224.418212) (xy 113.853964 -224.376616) (xy 113.834673 -224.33134) (xy 113.822896 -224.283556)
			(xy 113.818936 -224.234502) (xy 113.489994 -224.234502) (xy 113.489499 -224.259109) (xy 113.481604 -224.307686)
			(xy 113.46602 -224.354367) (xy 113.443149 -224.397944) (xy 113.413584 -224.437288) (xy 113.378091 -224.47138)
			(xy 113.337588 -224.499336) (xy 113.293126 -224.520434) (xy 113.245855 -224.534126) (xy 113.197 -224.540058)
			(xy 113.147825 -224.538077) (xy 113.099606 -224.528233) (xy 113.05359 -224.510781) (xy 113.010969 -224.486174)
			(xy 112.972848 -224.455049) (xy 112.940213 -224.418212) (xy 112.91391 -224.376616) (xy 112.894619 -224.33134)
			(xy 112.882842 -224.283556) (xy 112.878882 -224.234502) (xy 112.28832 -224.234502) (xy 112.28832 -225.044508)
			(xy 113.349036 -225.044508) (xy 113.352996 -224.995454) (xy 113.364773 -224.94767) (xy 113.384064 -224.902394)
			(xy 113.410367 -224.860798) (xy 113.443002 -224.823961) (xy 113.481123 -224.792836) (xy 113.523744 -224.768229)
			(xy 113.56976 -224.750777) (xy 113.617979 -224.740933) (xy 113.667154 -224.738952) (xy 113.716009 -224.744884)
			(xy 113.76328 -224.758576) (xy 113.807742 -224.779674) (xy 113.848245 -224.80763) (xy 113.883738 -224.841722)
			(xy 113.913303 -224.881066) (xy 113.936174 -224.924643) (xy 113.951758 -224.971324) (xy 113.959653 -225.019901)
			(xy 113.960148 -225.044508) (xy 116.168944 -225.044508) (xy 116.172904 -224.995454) (xy 116.184681 -224.94767)
			(xy 116.203972 -224.902394) (xy 116.230275 -224.860798) (xy 116.26291 -224.823961) (xy 116.301031 -224.792836)
			(xy 116.343652 -224.768229) (xy 116.389668 -224.750777) (xy 116.437887 -224.740933) (xy 116.487062 -224.738952)
			(xy 116.535917 -224.744884) (xy 116.583188 -224.758576) (xy 116.62765 -224.779674) (xy 116.668153 -224.80763)
			(xy 116.703646 -224.841722) (xy 116.733211 -224.881066) (xy 116.756082 -224.924643) (xy 116.771666 -224.971324)
			(xy 116.779561 -225.019901) (xy 116.780056 -225.044508) (xy 117.108998 -225.044508) (xy 117.112958 -224.995454)
			(xy 117.124735 -224.94767) (xy 117.144026 -224.902394) (xy 117.170329 -224.860798) (xy 117.202964 -224.823961)
			(xy 117.241085 -224.792836) (xy 117.283706 -224.768229) (xy 117.329722 -224.750777) (xy 117.377941 -224.740933)
			(xy 117.427116 -224.738952) (xy 117.475971 -224.744884) (xy 117.523242 -224.758576) (xy 117.567704 -224.779674)
			(xy 117.608207 -224.80763) (xy 117.6437 -224.841722) (xy 117.673265 -224.881066) (xy 117.696136 -224.924643)
			(xy 117.71172 -224.971324) (xy 117.719615 -225.019901) (xy 117.72011 -225.044508) (xy 118.988852 -225.044508)
			(xy 118.992812 -224.995454) (xy 119.004589 -224.94767) (xy 119.02388 -224.902394) (xy 119.050183 -224.860798)
			(xy 119.082818 -224.823961) (xy 119.120939 -224.792836) (xy 119.16356 -224.768229) (xy 119.209576 -224.750777)
			(xy 119.257795 -224.740933) (xy 119.30697 -224.738952) (xy 119.355825 -224.744884) (xy 119.403096 -224.758576)
			(xy 119.447558 -224.779674) (xy 119.488061 -224.80763) (xy 119.523554 -224.841722) (xy 119.553119 -224.881066)
			(xy 119.57599 -224.924643) (xy 119.591574 -224.971324) (xy 119.599469 -225.019901) (xy 119.599964 -225.044508)
			(xy 119.928906 -225.044508) (xy 119.932866 -224.995454) (xy 119.944643 -224.94767) (xy 119.963934 -224.902394)
			(xy 119.990237 -224.860798) (xy 120.022872 -224.823961) (xy 120.060993 -224.792836) (xy 120.103614 -224.768229)
			(xy 120.14963 -224.750777) (xy 120.197849 -224.740933) (xy 120.247024 -224.738952) (xy 120.295879 -224.744884)
			(xy 120.34315 -224.758576) (xy 120.387612 -224.779674) (xy 120.428115 -224.80763) (xy 120.463608 -224.841722)
			(xy 120.493173 -224.881066) (xy 120.516044 -224.924643) (xy 120.531628 -224.971324) (xy 120.539523 -225.019901)
			(xy 120.540018 -225.044508) (xy 121.809014 -225.044508) (xy 121.812974 -224.995454) (xy 121.824751 -224.94767)
			(xy 121.844042 -224.902394) (xy 121.870345 -224.860798) (xy 121.90298 -224.823961) (xy 121.941101 -224.792836)
			(xy 121.983722 -224.768229) (xy 122.029738 -224.750777) (xy 122.077957 -224.740933) (xy 122.127132 -224.738952)
			(xy 122.175987 -224.744884) (xy 122.223258 -224.758576) (xy 122.26772 -224.779674) (xy 122.308223 -224.80763)
			(xy 122.343716 -224.841722) (xy 122.373281 -224.881066) (xy 122.396152 -224.924643) (xy 122.411736 -224.971324)
			(xy 122.419631 -225.019901) (xy 122.420126 -225.044508) (xy 122.748814 -225.044508) (xy 122.752774 -224.995454)
			(xy 122.764551 -224.94767) (xy 122.783842 -224.902394) (xy 122.810145 -224.860798) (xy 122.84278 -224.823961)
			(xy 122.880901 -224.792836) (xy 122.923522 -224.768229) (xy 122.969538 -224.750777) (xy 123.017757 -224.740933)
			(xy 123.066932 -224.738952) (xy 123.115787 -224.744884) (xy 123.163058 -224.758576) (xy 123.20752 -224.779674)
			(xy 123.248023 -224.80763) (xy 123.283516 -224.841722) (xy 123.313081 -224.881066) (xy 123.335952 -224.924643)
			(xy 123.351536 -224.971324) (xy 123.359431 -225.019901) (xy 123.359926 -225.044508) (xy 124.628922 -225.044508)
			(xy 124.632882 -224.995454) (xy 124.644659 -224.94767) (xy 124.66395 -224.902394) (xy 124.690253 -224.860798)
			(xy 124.722888 -224.823961) (xy 124.761009 -224.792836) (xy 124.80363 -224.768229) (xy 124.849646 -224.750777)
			(xy 124.897865 -224.740933) (xy 124.94704 -224.738952) (xy 124.995895 -224.744884) (xy 125.043166 -224.758576)
			(xy 125.087628 -224.779674) (xy 125.128131 -224.80763) (xy 125.163624 -224.841722) (xy 125.193189 -224.881066)
			(xy 125.21606 -224.924643) (xy 125.231644 -224.971324) (xy 125.239539 -225.019901) (xy 125.240034 -225.044508)
			(xy 125.568976 -225.044508) (xy 125.572936 -224.995454) (xy 125.584713 -224.94767) (xy 125.604004 -224.902394)
			(xy 125.630307 -224.860798) (xy 125.662942 -224.823961) (xy 125.701063 -224.792836) (xy 125.743684 -224.768229)
			(xy 125.7897 -224.750777) (xy 125.837919 -224.740933) (xy 125.887094 -224.738952) (xy 125.935949 -224.744884)
			(xy 125.98322 -224.758576) (xy 126.027682 -224.779674) (xy 126.068185 -224.80763) (xy 126.103678 -224.841722)
			(xy 126.133243 -224.881066) (xy 126.156114 -224.924643) (xy 126.171698 -224.971324) (xy 126.179593 -225.019901)
			(xy 126.180088 -225.044508) (xy 126.179593 -225.069115) (xy 126.171698 -225.117692) (xy 126.156114 -225.164373)
			(xy 126.133243 -225.20795) (xy 126.103678 -225.247294) (xy 126.068185 -225.281386) (xy 126.027682 -225.309342)
			(xy 125.98322 -225.33044) (xy 125.935949 -225.344132) (xy 125.887094 -225.350064) (xy 125.837919 -225.348083)
			(xy 125.7897 -225.338239) (xy 125.743684 -225.320787) (xy 125.701063 -225.29618) (xy 125.662942 -225.265055)
			(xy 125.630307 -225.228218) (xy 125.604004 -225.186622) (xy 125.584713 -225.141346) (xy 125.572936 -225.093562)
			(xy 125.568976 -225.044508) (xy 125.240034 -225.044508) (xy 125.239539 -225.069115) (xy 125.231644 -225.117692)
			(xy 125.21606 -225.164373) (xy 125.193189 -225.20795) (xy 125.163624 -225.247294) (xy 125.128131 -225.281386)
			(xy 125.087628 -225.309342) (xy 125.043166 -225.33044) (xy 124.995895 -225.344132) (xy 124.94704 -225.350064)
			(xy 124.897865 -225.348083) (xy 124.849646 -225.338239) (xy 124.80363 -225.320787) (xy 124.761009 -225.29618)
			(xy 124.722888 -225.265055) (xy 124.690253 -225.228218) (xy 124.66395 -225.186622) (xy 124.644659 -225.141346)
			(xy 124.632882 -225.093562) (xy 124.628922 -225.044508) (xy 123.359926 -225.044508) (xy 123.359431 -225.069115)
			(xy 123.351536 -225.117692) (xy 123.335952 -225.164373) (xy 123.313081 -225.20795) (xy 123.283516 -225.247294)
			(xy 123.248023 -225.281386) (xy 123.20752 -225.309342) (xy 123.163058 -225.33044) (xy 123.115787 -225.344132)
			(xy 123.066932 -225.350064) (xy 123.017757 -225.348083) (xy 122.969538 -225.338239) (xy 122.923522 -225.320787)
			(xy 122.880901 -225.29618) (xy 122.84278 -225.265055) (xy 122.810145 -225.228218) (xy 122.783842 -225.186622)
			(xy 122.764551 -225.141346) (xy 122.752774 -225.093562) (xy 122.748814 -225.044508) (xy 122.420126 -225.044508)
			(xy 122.419631 -225.069115) (xy 122.411736 -225.117692) (xy 122.396152 -225.164373) (xy 122.373281 -225.20795)
			(xy 122.343716 -225.247294) (xy 122.308223 -225.281386) (xy 122.26772 -225.309342) (xy 122.223258 -225.33044)
			(xy 122.175987 -225.344132) (xy 122.127132 -225.350064) (xy 122.077957 -225.348083) (xy 122.029738 -225.338239)
			(xy 121.983722 -225.320787) (xy 121.941101 -225.29618) (xy 121.90298 -225.265055) (xy 121.870345 -225.228218)
			(xy 121.844042 -225.186622) (xy 121.824751 -225.141346) (xy 121.812974 -225.093562) (xy 121.809014 -225.044508)
			(xy 120.540018 -225.044508) (xy 120.539523 -225.069115) (xy 120.531628 -225.117692) (xy 120.516044 -225.164373)
			(xy 120.493173 -225.20795) (xy 120.463608 -225.247294) (xy 120.428115 -225.281386) (xy 120.387612 -225.309342)
			(xy 120.34315 -225.33044) (xy 120.295879 -225.344132) (xy 120.247024 -225.350064) (xy 120.197849 -225.348083)
			(xy 120.14963 -225.338239) (xy 120.103614 -225.320787) (xy 120.060993 -225.29618) (xy 120.022872 -225.265055)
			(xy 119.990237 -225.228218) (xy 119.963934 -225.186622) (xy 119.944643 -225.141346) (xy 119.932866 -225.093562)
			(xy 119.928906 -225.044508) (xy 119.599964 -225.044508) (xy 119.599469 -225.069115) (xy 119.591574 -225.117692)
			(xy 119.57599 -225.164373) (xy 119.553119 -225.20795) (xy 119.523554 -225.247294) (xy 119.488061 -225.281386)
			(xy 119.447558 -225.309342) (xy 119.403096 -225.33044) (xy 119.355825 -225.344132) (xy 119.30697 -225.350064)
			(xy 119.257795 -225.348083) (xy 119.209576 -225.338239) (xy 119.16356 -225.320787) (xy 119.120939 -225.29618)
			(xy 119.082818 -225.265055) (xy 119.050183 -225.228218) (xy 119.02388 -225.186622) (xy 119.004589 -225.141346)
			(xy 118.992812 -225.093562) (xy 118.988852 -225.044508) (xy 117.72011 -225.044508) (xy 117.719615 -225.069115)
			(xy 117.71172 -225.117692) (xy 117.696136 -225.164373) (xy 117.673265 -225.20795) (xy 117.6437 -225.247294)
			(xy 117.608207 -225.281386) (xy 117.567704 -225.309342) (xy 117.523242 -225.33044) (xy 117.475971 -225.344132)
			(xy 117.427116 -225.350064) (xy 117.377941 -225.348083) (xy 117.329722 -225.338239) (xy 117.283706 -225.320787)
			(xy 117.241085 -225.29618) (xy 117.202964 -225.265055) (xy 117.170329 -225.228218) (xy 117.144026 -225.186622)
			(xy 117.124735 -225.141346) (xy 117.112958 -225.093562) (xy 117.108998 -225.044508) (xy 116.780056 -225.044508)
			(xy 116.779561 -225.069115) (xy 116.771666 -225.117692) (xy 116.756082 -225.164373) (xy 116.733211 -225.20795)
			(xy 116.703646 -225.247294) (xy 116.668153 -225.281386) (xy 116.62765 -225.309342) (xy 116.583188 -225.33044)
			(xy 116.535917 -225.344132) (xy 116.487062 -225.350064) (xy 116.437887 -225.348083) (xy 116.389668 -225.338239)
			(xy 116.343652 -225.320787) (xy 116.301031 -225.29618) (xy 116.26291 -225.265055) (xy 116.230275 -225.228218)
			(xy 116.203972 -225.186622) (xy 116.184681 -225.141346) (xy 116.172904 -225.093562) (xy 116.168944 -225.044508)
			(xy 113.960148 -225.044508) (xy 113.959653 -225.069115) (xy 113.951758 -225.117692) (xy 113.936174 -225.164373)
			(xy 113.913303 -225.20795) (xy 113.883738 -225.247294) (xy 113.848245 -225.281386) (xy 113.807742 -225.309342)
			(xy 113.76328 -225.33044) (xy 113.716009 -225.344132) (xy 113.667154 -225.350064) (xy 113.617979 -225.348083)
			(xy 113.56976 -225.338239) (xy 113.523744 -225.320787) (xy 113.481123 -225.29618) (xy 113.443002 -225.265055)
			(xy 113.410367 -225.228218) (xy 113.384064 -225.186622) (xy 113.364773 -225.141346) (xy 113.352996 -225.093562)
			(xy 113.349036 -225.044508) (xy 112.28832 -225.044508) (xy 112.28832 -225.854514) (xy 112.878882 -225.854514)
			(xy 112.882842 -225.80546) (xy 112.894619 -225.757676) (xy 112.91391 -225.7124) (xy 112.940213 -225.670804)
			(xy 112.972848 -225.633967) (xy 113.010969 -225.602842) (xy 113.05359 -225.578235) (xy 113.099606 -225.560783)
			(xy 113.147825 -225.550939) (xy 113.197 -225.548958) (xy 113.245855 -225.55489) (xy 113.293126 -225.568582)
			(xy 113.337588 -225.58968) (xy 113.378091 -225.617636) (xy 113.413584 -225.651728) (xy 113.443149 -225.691072)
			(xy 113.46602 -225.734649) (xy 113.481604 -225.78133) (xy 113.489499 -225.829907) (xy 113.489994 -225.854514)
			(xy 113.818936 -225.854514) (xy 113.822896 -225.80546) (xy 113.834673 -225.757676) (xy 113.853964 -225.7124)
			(xy 113.880267 -225.670804) (xy 113.912902 -225.633967) (xy 113.951023 -225.602842) (xy 113.993644 -225.578235)
			(xy 114.03966 -225.560783) (xy 114.087879 -225.550939) (xy 114.137054 -225.548958) (xy 114.185909 -225.55489)
			(xy 114.23318 -225.568582) (xy 114.277642 -225.58968) (xy 114.318145 -225.617636) (xy 114.353638 -225.651728)
			(xy 114.383203 -225.691072) (xy 114.406074 -225.734649) (xy 114.421658 -225.78133) (xy 114.429553 -225.829907)
			(xy 114.430048 -225.854514) (xy 114.75899 -225.854514) (xy 114.76295 -225.80546) (xy 114.774727 -225.757676)
			(xy 114.794018 -225.7124) (xy 114.820321 -225.670804) (xy 114.852956 -225.633967) (xy 114.891077 -225.602842)
			(xy 114.933698 -225.578235) (xy 114.979714 -225.560783) (xy 115.027933 -225.550939) (xy 115.077108 -225.548958)
			(xy 115.125963 -225.55489) (xy 115.173234 -225.568582) (xy 115.217696 -225.58968) (xy 115.258199 -225.617636)
			(xy 115.293692 -225.651728) (xy 115.323257 -225.691072) (xy 115.346128 -225.734649) (xy 115.361712 -225.78133)
			(xy 115.369607 -225.829907) (xy 115.370102 -225.854514) (xy 116.638844 -225.854514) (xy 116.642804 -225.80546)
			(xy 116.654581 -225.757676) (xy 116.673872 -225.7124) (xy 116.700175 -225.670804) (xy 116.73281 -225.633967)
			(xy 116.770931 -225.602842) (xy 116.813552 -225.578235) (xy 116.859568 -225.560783) (xy 116.907787 -225.550939)
			(xy 116.956962 -225.548958) (xy 117.005817 -225.55489) (xy 117.053088 -225.568582) (xy 117.09755 -225.58968)
			(xy 117.138053 -225.617636) (xy 117.173546 -225.651728) (xy 117.203111 -225.691072) (xy 117.225982 -225.734649)
			(xy 117.241566 -225.78133) (xy 117.249461 -225.829907) (xy 117.249956 -225.854514) (xy 117.578898 -225.854514)
			(xy 117.582858 -225.80546) (xy 117.594635 -225.757676) (xy 117.613926 -225.7124) (xy 117.640229 -225.670804)
			(xy 117.672864 -225.633967) (xy 117.710985 -225.602842) (xy 117.753606 -225.578235) (xy 117.799622 -225.560783)
			(xy 117.847841 -225.550939) (xy 117.897016 -225.548958) (xy 117.945871 -225.55489) (xy 117.993142 -225.568582)
			(xy 118.037604 -225.58968) (xy 118.078107 -225.617636) (xy 118.1136 -225.651728) (xy 118.143165 -225.691072)
			(xy 118.166036 -225.734649) (xy 118.18162 -225.78133) (xy 118.189515 -225.829907) (xy 118.19001 -225.854514)
			(xy 119.459006 -225.854514) (xy 119.462966 -225.80546) (xy 119.474743 -225.757676) (xy 119.494034 -225.7124)
			(xy 119.520337 -225.670804) (xy 119.552972 -225.633967) (xy 119.591093 -225.602842) (xy 119.633714 -225.578235)
			(xy 119.67973 -225.560783) (xy 119.727949 -225.550939) (xy 119.777124 -225.548958) (xy 119.825979 -225.55489)
			(xy 119.87325 -225.568582) (xy 119.917712 -225.58968) (xy 119.958215 -225.617636) (xy 119.993708 -225.651728)
			(xy 120.023273 -225.691072) (xy 120.046144 -225.734649) (xy 120.061728 -225.78133) (xy 120.069623 -225.829907)
			(xy 120.070118 -225.854514) (xy 120.398806 -225.854514) (xy 120.402766 -225.80546) (xy 120.414543 -225.757676)
			(xy 120.433834 -225.7124) (xy 120.460137 -225.670804) (xy 120.492772 -225.633967) (xy 120.530893 -225.602842)
			(xy 120.573514 -225.578235) (xy 120.61953 -225.560783) (xy 120.667749 -225.550939) (xy 120.716924 -225.548958)
			(xy 120.765779 -225.55489) (xy 120.81305 -225.568582) (xy 120.857512 -225.58968) (xy 120.898015 -225.617636)
			(xy 120.933508 -225.651728) (xy 120.963073 -225.691072) (xy 120.985944 -225.734649) (xy 121.001528 -225.78133)
			(xy 121.009423 -225.829907) (xy 121.009918 -225.854514) (xy 122.278914 -225.854514) (xy 122.282874 -225.80546)
			(xy 122.294651 -225.757676) (xy 122.313942 -225.7124) (xy 122.340245 -225.670804) (xy 122.37288 -225.633967)
			(xy 122.411001 -225.602842) (xy 122.453622 -225.578235) (xy 122.499638 -225.560783) (xy 122.547857 -225.550939)
			(xy 122.597032 -225.548958) (xy 122.645887 -225.55489) (xy 122.693158 -225.568582) (xy 122.73762 -225.58968)
			(xy 122.778123 -225.617636) (xy 122.813616 -225.651728) (xy 122.843181 -225.691072) (xy 122.866052 -225.734649)
			(xy 122.881636 -225.78133) (xy 122.889531 -225.829907) (xy 122.890026 -225.854514) (xy 123.218968 -225.854514)
			(xy 123.222928 -225.80546) (xy 123.234705 -225.757676) (xy 123.253996 -225.7124) (xy 123.280299 -225.670804)
			(xy 123.312934 -225.633967) (xy 123.351055 -225.602842) (xy 123.393676 -225.578235) (xy 123.439692 -225.560783)
			(xy 123.487911 -225.550939) (xy 123.537086 -225.548958) (xy 123.585941 -225.55489) (xy 123.633212 -225.568582)
			(xy 123.677674 -225.58968) (xy 123.718177 -225.617636) (xy 123.75367 -225.651728) (xy 123.783235 -225.691072)
			(xy 123.806106 -225.734649) (xy 123.82169 -225.78133) (xy 123.829585 -225.829907) (xy 123.83008 -225.854514)
			(xy 125.098822 -225.854514) (xy 125.102782 -225.80546) (xy 125.114559 -225.757676) (xy 125.13385 -225.7124)
			(xy 125.160153 -225.670804) (xy 125.192788 -225.633967) (xy 125.230909 -225.602842) (xy 125.27353 -225.578235)
			(xy 125.319546 -225.560783) (xy 125.367765 -225.550939) (xy 125.41694 -225.548958) (xy 125.465795 -225.55489)
			(xy 125.513066 -225.568582) (xy 125.557528 -225.58968) (xy 125.598031 -225.617636) (xy 125.633524 -225.651728)
			(xy 125.663089 -225.691072) (xy 125.68596 -225.734649) (xy 125.701544 -225.78133) (xy 125.709439 -225.829907)
			(xy 125.709934 -225.854514) (xy 126.038876 -225.854514) (xy 126.042836 -225.80546) (xy 126.054613 -225.757676)
			(xy 126.073904 -225.7124) (xy 126.100207 -225.670804) (xy 126.132842 -225.633967) (xy 126.170963 -225.602842)
			(xy 126.213584 -225.578235) (xy 126.2596 -225.560783) (xy 126.307819 -225.550939) (xy 126.356994 -225.548958)
			(xy 126.405849 -225.55489) (xy 126.45312 -225.568582) (xy 126.497582 -225.58968) (xy 126.538085 -225.617636)
			(xy 126.573578 -225.651728) (xy 126.603143 -225.691072) (xy 126.626014 -225.734649) (xy 126.641598 -225.78133)
			(xy 126.649493 -225.829907) (xy 126.649988 -225.854514) (xy 126.649493 -225.879121) (xy 126.641598 -225.927698)
			(xy 126.626014 -225.974379) (xy 126.603143 -226.017956) (xy 126.573578 -226.0573) (xy 126.538085 -226.091392)
			(xy 126.497582 -226.119348) (xy 126.45312 -226.140446) (xy 126.405849 -226.154138) (xy 126.356994 -226.16007)
			(xy 126.307819 -226.158089) (xy 126.2596 -226.148245) (xy 126.213584 -226.130793) (xy 126.170963 -226.106186)
			(xy 126.132842 -226.075061) (xy 126.100207 -226.038224) (xy 126.073904 -225.996628) (xy 126.054613 -225.951352)
			(xy 126.042836 -225.903568) (xy 126.038876 -225.854514) (xy 125.709934 -225.854514) (xy 125.709439 -225.879121)
			(xy 125.701544 -225.927698) (xy 125.68596 -225.974379) (xy 125.663089 -226.017956) (xy 125.633524 -226.0573)
			(xy 125.598031 -226.091392) (xy 125.557528 -226.119348) (xy 125.513066 -226.140446) (xy 125.465795 -226.154138)
			(xy 125.41694 -226.16007) (xy 125.367765 -226.158089) (xy 125.319546 -226.148245) (xy 125.27353 -226.130793)
			(xy 125.230909 -226.106186) (xy 125.192788 -226.075061) (xy 125.160153 -226.038224) (xy 125.13385 -225.996628)
			(xy 125.114559 -225.951352) (xy 125.102782 -225.903568) (xy 125.098822 -225.854514) (xy 123.83008 -225.854514)
			(xy 123.829585 -225.879121) (xy 123.82169 -225.927698) (xy 123.806106 -225.974379) (xy 123.783235 -226.017956)
			(xy 123.75367 -226.0573) (xy 123.718177 -226.091392) (xy 123.677674 -226.119348) (xy 123.633212 -226.140446)
			(xy 123.585941 -226.154138) (xy 123.537086 -226.16007) (xy 123.487911 -226.158089) (xy 123.439692 -226.148245)
			(xy 123.393676 -226.130793) (xy 123.351055 -226.106186) (xy 123.312934 -226.075061) (xy 123.280299 -226.038224)
			(xy 123.253996 -225.996628) (xy 123.234705 -225.951352) (xy 123.222928 -225.903568) (xy 123.218968 -225.854514)
			(xy 122.890026 -225.854514) (xy 122.889531 -225.879121) (xy 122.881636 -225.927698) (xy 122.866052 -225.974379)
			(xy 122.843181 -226.017956) (xy 122.813616 -226.0573) (xy 122.778123 -226.091392) (xy 122.73762 -226.119348)
			(xy 122.693158 -226.140446) (xy 122.645887 -226.154138) (xy 122.597032 -226.16007) (xy 122.547857 -226.158089)
			(xy 122.499638 -226.148245) (xy 122.453622 -226.130793) (xy 122.411001 -226.106186) (xy 122.37288 -226.075061)
			(xy 122.340245 -226.038224) (xy 122.313942 -225.996628) (xy 122.294651 -225.951352) (xy 122.282874 -225.903568)
			(xy 122.278914 -225.854514) (xy 121.009918 -225.854514) (xy 121.009423 -225.879121) (xy 121.001528 -225.927698)
			(xy 120.985944 -225.974379) (xy 120.963073 -226.017956) (xy 120.933508 -226.0573) (xy 120.898015 -226.091392)
			(xy 120.857512 -226.119348) (xy 120.81305 -226.140446) (xy 120.765779 -226.154138) (xy 120.716924 -226.16007)
			(xy 120.667749 -226.158089) (xy 120.61953 -226.148245) (xy 120.573514 -226.130793) (xy 120.530893 -226.106186)
			(xy 120.492772 -226.075061) (xy 120.460137 -226.038224) (xy 120.433834 -225.996628) (xy 120.414543 -225.951352)
			(xy 120.402766 -225.903568) (xy 120.398806 -225.854514) (xy 120.070118 -225.854514) (xy 120.069623 -225.879121)
			(xy 120.061728 -225.927698) (xy 120.046144 -225.974379) (xy 120.023273 -226.017956) (xy 119.993708 -226.0573)
			(xy 119.958215 -226.091392) (xy 119.917712 -226.119348) (xy 119.87325 -226.140446) (xy 119.825979 -226.154138)
			(xy 119.777124 -226.16007) (xy 119.727949 -226.158089) (xy 119.67973 -226.148245) (xy 119.633714 -226.130793)
			(xy 119.591093 -226.106186) (xy 119.552972 -226.075061) (xy 119.520337 -226.038224) (xy 119.494034 -225.996628)
			(xy 119.474743 -225.951352) (xy 119.462966 -225.903568) (xy 119.459006 -225.854514) (xy 118.19001 -225.854514)
			(xy 118.189515 -225.879121) (xy 118.18162 -225.927698) (xy 118.166036 -225.974379) (xy 118.143165 -226.017956)
			(xy 118.1136 -226.0573) (xy 118.078107 -226.091392) (xy 118.037604 -226.119348) (xy 117.993142 -226.140446)
			(xy 117.945871 -226.154138) (xy 117.897016 -226.16007) (xy 117.847841 -226.158089) (xy 117.799622 -226.148245)
			(xy 117.753606 -226.130793) (xy 117.710985 -226.106186) (xy 117.672864 -226.075061) (xy 117.640229 -226.038224)
			(xy 117.613926 -225.996628) (xy 117.594635 -225.951352) (xy 117.582858 -225.903568) (xy 117.578898 -225.854514)
			(xy 117.249956 -225.854514) (xy 117.249461 -225.879121) (xy 117.241566 -225.927698) (xy 117.225982 -225.974379)
			(xy 117.203111 -226.017956) (xy 117.173546 -226.0573) (xy 117.138053 -226.091392) (xy 117.09755 -226.119348)
			(xy 117.053088 -226.140446) (xy 117.005817 -226.154138) (xy 116.956962 -226.16007) (xy 116.907787 -226.158089)
			(xy 116.859568 -226.148245) (xy 116.813552 -226.130793) (xy 116.770931 -226.106186) (xy 116.73281 -226.075061)
			(xy 116.700175 -226.038224) (xy 116.673872 -225.996628) (xy 116.654581 -225.951352) (xy 116.642804 -225.903568)
			(xy 116.638844 -225.854514) (xy 115.370102 -225.854514) (xy 115.369607 -225.879121) (xy 115.361712 -225.927698)
			(xy 115.346128 -225.974379) (xy 115.323257 -226.017956) (xy 115.293692 -226.0573) (xy 115.258199 -226.091392)
			(xy 115.217696 -226.119348) (xy 115.173234 -226.140446) (xy 115.125963 -226.154138) (xy 115.077108 -226.16007)
			(xy 115.027933 -226.158089) (xy 114.979714 -226.148245) (xy 114.933698 -226.130793) (xy 114.891077 -226.106186)
			(xy 114.852956 -226.075061) (xy 114.820321 -226.038224) (xy 114.794018 -225.996628) (xy 114.774727 -225.951352)
			(xy 114.76295 -225.903568) (xy 114.75899 -225.854514) (xy 114.430048 -225.854514) (xy 114.429553 -225.879121)
			(xy 114.421658 -225.927698) (xy 114.406074 -225.974379) (xy 114.383203 -226.017956) (xy 114.353638 -226.0573)
			(xy 114.318145 -226.091392) (xy 114.277642 -226.119348) (xy 114.23318 -226.140446) (xy 114.185909 -226.154138)
			(xy 114.137054 -226.16007) (xy 114.087879 -226.158089) (xy 114.03966 -226.148245) (xy 113.993644 -226.130793)
			(xy 113.951023 -226.106186) (xy 113.912902 -226.075061) (xy 113.880267 -226.038224) (xy 113.853964 -225.996628)
			(xy 113.834673 -225.951352) (xy 113.822896 -225.903568) (xy 113.818936 -225.854514) (xy 113.489994 -225.854514)
			(xy 113.489499 -225.879121) (xy 113.481604 -225.927698) (xy 113.46602 -225.974379) (xy 113.443149 -226.017956)
			(xy 113.413584 -226.0573) (xy 113.378091 -226.091392) (xy 113.337588 -226.119348) (xy 113.293126 -226.140446)
			(xy 113.245855 -226.154138) (xy 113.197 -226.16007) (xy 113.147825 -226.158089) (xy 113.099606 -226.148245)
			(xy 113.05359 -226.130793) (xy 113.010969 -226.106186) (xy 112.972848 -226.075061) (xy 112.940213 -226.038224)
			(xy 112.91391 -225.996628) (xy 112.894619 -225.951352) (xy 112.882842 -225.903568) (xy 112.878882 -225.854514)
			(xy 112.28832 -225.854514) (xy 112.28832 -226.66452) (xy 115.22889 -226.66452) (xy 115.23285 -226.615466)
			(xy 115.244627 -226.567682) (xy 115.263918 -226.522406) (xy 115.290221 -226.48081) (xy 115.322856 -226.443973)
			(xy 115.360977 -226.412848) (xy 115.403598 -226.388241) (xy 115.449614 -226.370789) (xy 115.497833 -226.360945)
			(xy 115.547008 -226.358964) (xy 115.595863 -226.364896) (xy 115.643134 -226.378588) (xy 115.687596 -226.399686)
			(xy 115.728099 -226.427642) (xy 115.763592 -226.461734) (xy 115.793157 -226.501078) (xy 115.816028 -226.544655)
			(xy 115.831612 -226.591336) (xy 115.839507 -226.639913) (xy 115.840002 -226.66452) (xy 116.168944 -226.66452)
			(xy 116.172904 -226.615466) (xy 116.184681 -226.567682) (xy 116.203972 -226.522406) (xy 116.230275 -226.48081)
			(xy 116.26291 -226.443973) (xy 116.301031 -226.412848) (xy 116.343652 -226.388241) (xy 116.389668 -226.370789)
			(xy 116.437887 -226.360945) (xy 116.487062 -226.358964) (xy 116.535917 -226.364896) (xy 116.583188 -226.378588)
			(xy 116.62765 -226.399686) (xy 116.668153 -226.427642) (xy 116.703646 -226.461734) (xy 116.733211 -226.501078)
			(xy 116.756082 -226.544655) (xy 116.771666 -226.591336) (xy 116.779561 -226.639913) (xy 116.780056 -226.66452)
			(xy 117.108998 -226.66452) (xy 117.112958 -226.615466) (xy 117.124735 -226.567682) (xy 117.144026 -226.522406)
			(xy 117.170329 -226.48081) (xy 117.202964 -226.443973) (xy 117.241085 -226.412848) (xy 117.283706 -226.388241)
			(xy 117.329722 -226.370789) (xy 117.377941 -226.360945) (xy 117.427116 -226.358964) (xy 117.475971 -226.364896)
			(xy 117.523242 -226.378588) (xy 117.567704 -226.399686) (xy 117.608207 -226.427642) (xy 117.6437 -226.461734)
			(xy 117.673265 -226.501078) (xy 117.696136 -226.544655) (xy 117.71172 -226.591336) (xy 117.719615 -226.639913)
			(xy 117.72011 -226.66452) (xy 118.049052 -226.66452) (xy 118.053012 -226.615466) (xy 118.064789 -226.567682)
			(xy 118.08408 -226.522406) (xy 118.110383 -226.48081) (xy 118.143018 -226.443973) (xy 118.181139 -226.412848)
			(xy 118.22376 -226.388241) (xy 118.269776 -226.370789) (xy 118.317995 -226.360945) (xy 118.36717 -226.358964)
			(xy 118.416025 -226.364896) (xy 118.463296 -226.378588) (xy 118.507758 -226.399686) (xy 118.548261 -226.427642)
			(xy 118.583754 -226.461734) (xy 118.613319 -226.501078) (xy 118.63619 -226.544655) (xy 118.651774 -226.591336)
			(xy 118.659669 -226.639913) (xy 118.660164 -226.66452) (xy 118.988852 -226.66452) (xy 118.992812 -226.615466)
			(xy 119.004589 -226.567682) (xy 119.02388 -226.522406) (xy 119.050183 -226.48081) (xy 119.082818 -226.443973)
			(xy 119.120939 -226.412848) (xy 119.16356 -226.388241) (xy 119.209576 -226.370789) (xy 119.257795 -226.360945)
			(xy 119.30697 -226.358964) (xy 119.355825 -226.364896) (xy 119.403096 -226.378588) (xy 119.447558 -226.399686)
			(xy 119.488061 -226.427642) (xy 119.523554 -226.461734) (xy 119.553119 -226.501078) (xy 119.57599 -226.544655)
			(xy 119.591574 -226.591336) (xy 119.599469 -226.639913) (xy 119.599964 -226.66452) (xy 119.928906 -226.66452)
			(xy 119.932866 -226.615466) (xy 119.944643 -226.567682) (xy 119.963934 -226.522406) (xy 119.990237 -226.48081)
			(xy 120.022872 -226.443973) (xy 120.060993 -226.412848) (xy 120.103614 -226.388241) (xy 120.14963 -226.370789)
			(xy 120.197849 -226.360945) (xy 120.247024 -226.358964) (xy 120.295879 -226.364896) (xy 120.34315 -226.378588)
			(xy 120.387612 -226.399686) (xy 120.428115 -226.427642) (xy 120.463608 -226.461734) (xy 120.493173 -226.501078)
			(xy 120.516044 -226.544655) (xy 120.531628 -226.591336) (xy 120.539523 -226.639913) (xy 120.540018 -226.66452)
			(xy 120.86896 -226.66452) (xy 120.87292 -226.615466) (xy 120.884697 -226.567682) (xy 120.903988 -226.522406)
			(xy 120.930291 -226.48081) (xy 120.962926 -226.443973) (xy 121.001047 -226.412848) (xy 121.043668 -226.388241)
			(xy 121.089684 -226.370789) (xy 121.137903 -226.360945) (xy 121.187078 -226.358964) (xy 121.235933 -226.364896)
			(xy 121.283204 -226.378588) (xy 121.327666 -226.399686) (xy 121.368169 -226.427642) (xy 121.403662 -226.461734)
			(xy 121.433227 -226.501078) (xy 121.456098 -226.544655) (xy 121.471682 -226.591336) (xy 121.479577 -226.639913)
			(xy 121.480072 -226.66452) (xy 121.809014 -226.66452) (xy 121.812974 -226.615466) (xy 121.824751 -226.567682)
			(xy 121.844042 -226.522406) (xy 121.870345 -226.48081) (xy 121.90298 -226.443973) (xy 121.941101 -226.412848)
			(xy 121.983722 -226.388241) (xy 122.029738 -226.370789) (xy 122.077957 -226.360945) (xy 122.127132 -226.358964)
			(xy 122.175987 -226.364896) (xy 122.223258 -226.378588) (xy 122.26772 -226.399686) (xy 122.308223 -226.427642)
			(xy 122.343716 -226.461734) (xy 122.373281 -226.501078) (xy 122.396152 -226.544655) (xy 122.411736 -226.591336)
			(xy 122.419631 -226.639913) (xy 122.420126 -226.66452) (xy 122.748814 -226.66452) (xy 122.752774 -226.615466)
			(xy 122.764551 -226.567682) (xy 122.783842 -226.522406) (xy 122.810145 -226.48081) (xy 122.84278 -226.443973)
			(xy 122.880901 -226.412848) (xy 122.923522 -226.388241) (xy 122.969538 -226.370789) (xy 123.017757 -226.360945)
			(xy 123.066932 -226.358964) (xy 123.115787 -226.364896) (xy 123.163058 -226.378588) (xy 123.20752 -226.399686)
			(xy 123.248023 -226.427642) (xy 123.283516 -226.461734) (xy 123.313081 -226.501078) (xy 123.335952 -226.544655)
			(xy 123.351536 -226.591336) (xy 123.359431 -226.639913) (xy 123.359926 -226.66452) (xy 123.688868 -226.66452)
			(xy 123.692828 -226.615466) (xy 123.704605 -226.567682) (xy 123.723896 -226.522406) (xy 123.750199 -226.48081)
			(xy 123.782834 -226.443973) (xy 123.820955 -226.412848) (xy 123.863576 -226.388241) (xy 123.909592 -226.370789)
			(xy 123.957811 -226.360945) (xy 124.006986 -226.358964) (xy 124.055841 -226.364896) (xy 124.103112 -226.378588)
			(xy 124.147574 -226.399686) (xy 124.188077 -226.427642) (xy 124.22357 -226.461734) (xy 124.253135 -226.501078)
			(xy 124.276006 -226.544655) (xy 124.29159 -226.591336) (xy 124.299485 -226.639913) (xy 124.29998 -226.66452)
			(xy 124.628922 -226.66452) (xy 124.632882 -226.615466) (xy 124.644659 -226.567682) (xy 124.66395 -226.522406)
			(xy 124.690253 -226.48081) (xy 124.722888 -226.443973) (xy 124.761009 -226.412848) (xy 124.80363 -226.388241)
			(xy 124.849646 -226.370789) (xy 124.897865 -226.360945) (xy 124.94704 -226.358964) (xy 124.995895 -226.364896)
			(xy 125.043166 -226.378588) (xy 125.087628 -226.399686) (xy 125.128131 -226.427642) (xy 125.163624 -226.461734)
			(xy 125.193189 -226.501078) (xy 125.21606 -226.544655) (xy 125.231644 -226.591336) (xy 125.239539 -226.639913)
			(xy 125.240034 -226.66452) (xy 125.568976 -226.66452) (xy 125.572936 -226.615466) (xy 125.584713 -226.567682)
			(xy 125.604004 -226.522406) (xy 125.630307 -226.48081) (xy 125.662942 -226.443973) (xy 125.701063 -226.412848)
			(xy 125.743684 -226.388241) (xy 125.7897 -226.370789) (xy 125.837919 -226.360945) (xy 125.887094 -226.358964)
			(xy 125.935949 -226.364896) (xy 125.98322 -226.378588) (xy 126.027682 -226.399686) (xy 126.068185 -226.427642)
			(xy 126.103678 -226.461734) (xy 126.133243 -226.501078) (xy 126.156114 -226.544655) (xy 126.171698 -226.591336)
			(xy 126.179593 -226.639913) (xy 126.180088 -226.66452) (xy 126.179593 -226.689127) (xy 126.171698 -226.737704)
			(xy 126.156114 -226.784385) (xy 126.133243 -226.827962) (xy 126.103678 -226.867306) (xy 126.068185 -226.901398)
			(xy 126.027682 -226.929354) (xy 125.98322 -226.950452) (xy 125.935949 -226.964144) (xy 125.887094 -226.970076)
			(xy 125.837919 -226.968095) (xy 125.7897 -226.958251) (xy 125.743684 -226.940799) (xy 125.701063 -226.916192)
			(xy 125.662942 -226.885067) (xy 125.630307 -226.84823) (xy 125.604004 -226.806634) (xy 125.584713 -226.761358)
			(xy 125.572936 -226.713574) (xy 125.568976 -226.66452) (xy 125.240034 -226.66452) (xy 125.239539 -226.689127)
			(xy 125.231644 -226.737704) (xy 125.21606 -226.784385) (xy 125.193189 -226.827962) (xy 125.163624 -226.867306)
			(xy 125.128131 -226.901398) (xy 125.087628 -226.929354) (xy 125.043166 -226.950452) (xy 124.995895 -226.964144)
			(xy 124.94704 -226.970076) (xy 124.897865 -226.968095) (xy 124.849646 -226.958251) (xy 124.80363 -226.940799)
			(xy 124.761009 -226.916192) (xy 124.722888 -226.885067) (xy 124.690253 -226.84823) (xy 124.66395 -226.806634)
			(xy 124.644659 -226.761358) (xy 124.632882 -226.713574) (xy 124.628922 -226.66452) (xy 124.29998 -226.66452)
			(xy 124.299485 -226.689127) (xy 124.29159 -226.737704) (xy 124.276006 -226.784385) (xy 124.253135 -226.827962)
			(xy 124.22357 -226.867306) (xy 124.188077 -226.901398) (xy 124.147574 -226.929354) (xy 124.103112 -226.950452)
			(xy 124.055841 -226.964144) (xy 124.006986 -226.970076) (xy 123.957811 -226.968095) (xy 123.909592 -226.958251)
			(xy 123.863576 -226.940799) (xy 123.820955 -226.916192) (xy 123.782834 -226.885067) (xy 123.750199 -226.84823)
			(xy 123.723896 -226.806634) (xy 123.704605 -226.761358) (xy 123.692828 -226.713574) (xy 123.688868 -226.66452)
			(xy 123.359926 -226.66452) (xy 123.359431 -226.689127) (xy 123.351536 -226.737704) (xy 123.335952 -226.784385)
			(xy 123.313081 -226.827962) (xy 123.283516 -226.867306) (xy 123.248023 -226.901398) (xy 123.20752 -226.929354)
			(xy 123.163058 -226.950452) (xy 123.115787 -226.964144) (xy 123.066932 -226.970076) (xy 123.017757 -226.968095)
			(xy 122.969538 -226.958251) (xy 122.923522 -226.940799) (xy 122.880901 -226.916192) (xy 122.84278 -226.885067)
			(xy 122.810145 -226.84823) (xy 122.783842 -226.806634) (xy 122.764551 -226.761358) (xy 122.752774 -226.713574)
			(xy 122.748814 -226.66452) (xy 122.420126 -226.66452) (xy 122.419631 -226.689127) (xy 122.411736 -226.737704)
			(xy 122.396152 -226.784385) (xy 122.373281 -226.827962) (xy 122.343716 -226.867306) (xy 122.308223 -226.901398)
			(xy 122.26772 -226.929354) (xy 122.223258 -226.950452) (xy 122.175987 -226.964144) (xy 122.127132 -226.970076)
			(xy 122.077957 -226.968095) (xy 122.029738 -226.958251) (xy 121.983722 -226.940799) (xy 121.941101 -226.916192)
			(xy 121.90298 -226.885067) (xy 121.870345 -226.84823) (xy 121.844042 -226.806634) (xy 121.824751 -226.761358)
			(xy 121.812974 -226.713574) (xy 121.809014 -226.66452) (xy 121.480072 -226.66452) (xy 121.479577 -226.689127)
			(xy 121.471682 -226.737704) (xy 121.456098 -226.784385) (xy 121.433227 -226.827962) (xy 121.403662 -226.867306)
			(xy 121.368169 -226.901398) (xy 121.327666 -226.929354) (xy 121.283204 -226.950452) (xy 121.235933 -226.964144)
			(xy 121.187078 -226.970076) (xy 121.137903 -226.968095) (xy 121.089684 -226.958251) (xy 121.043668 -226.940799)
			(xy 121.001047 -226.916192) (xy 120.962926 -226.885067) (xy 120.930291 -226.84823) (xy 120.903988 -226.806634)
			(xy 120.884697 -226.761358) (xy 120.87292 -226.713574) (xy 120.86896 -226.66452) (xy 120.540018 -226.66452)
			(xy 120.539523 -226.689127) (xy 120.531628 -226.737704) (xy 120.516044 -226.784385) (xy 120.493173 -226.827962)
			(xy 120.463608 -226.867306) (xy 120.428115 -226.901398) (xy 120.387612 -226.929354) (xy 120.34315 -226.950452)
			(xy 120.295879 -226.964144) (xy 120.247024 -226.970076) (xy 120.197849 -226.968095) (xy 120.14963 -226.958251)
			(xy 120.103614 -226.940799) (xy 120.060993 -226.916192) (xy 120.022872 -226.885067) (xy 119.990237 -226.84823)
			(xy 119.963934 -226.806634) (xy 119.944643 -226.761358) (xy 119.932866 -226.713574) (xy 119.928906 -226.66452)
			(xy 119.599964 -226.66452) (xy 119.599469 -226.689127) (xy 119.591574 -226.737704) (xy 119.57599 -226.784385)
			(xy 119.553119 -226.827962) (xy 119.523554 -226.867306) (xy 119.488061 -226.901398) (xy 119.447558 -226.929354)
			(xy 119.403096 -226.950452) (xy 119.355825 -226.964144) (xy 119.30697 -226.970076) (xy 119.257795 -226.968095)
			(xy 119.209576 -226.958251) (xy 119.16356 -226.940799) (xy 119.120939 -226.916192) (xy 119.082818 -226.885067)
			(xy 119.050183 -226.84823) (xy 119.02388 -226.806634) (xy 119.004589 -226.761358) (xy 118.992812 -226.713574)
			(xy 118.988852 -226.66452) (xy 118.660164 -226.66452) (xy 118.659669 -226.689127) (xy 118.651774 -226.737704)
			(xy 118.63619 -226.784385) (xy 118.613319 -226.827962) (xy 118.583754 -226.867306) (xy 118.548261 -226.901398)
			(xy 118.507758 -226.929354) (xy 118.463296 -226.950452) (xy 118.416025 -226.964144) (xy 118.36717 -226.970076)
			(xy 118.317995 -226.968095) (xy 118.269776 -226.958251) (xy 118.22376 -226.940799) (xy 118.181139 -226.916192)
			(xy 118.143018 -226.885067) (xy 118.110383 -226.84823) (xy 118.08408 -226.806634) (xy 118.064789 -226.761358)
			(xy 118.053012 -226.713574) (xy 118.049052 -226.66452) (xy 117.72011 -226.66452) (xy 117.719615 -226.689127)
			(xy 117.71172 -226.737704) (xy 117.696136 -226.784385) (xy 117.673265 -226.827962) (xy 117.6437 -226.867306)
			(xy 117.608207 -226.901398) (xy 117.567704 -226.929354) (xy 117.523242 -226.950452) (xy 117.475971 -226.964144)
			(xy 117.427116 -226.970076) (xy 117.377941 -226.968095) (xy 117.329722 -226.958251) (xy 117.283706 -226.940799)
			(xy 117.241085 -226.916192) (xy 117.202964 -226.885067) (xy 117.170329 -226.84823) (xy 117.144026 -226.806634)
			(xy 117.124735 -226.761358) (xy 117.112958 -226.713574) (xy 117.108998 -226.66452) (xy 116.780056 -226.66452)
			(xy 116.779561 -226.689127) (xy 116.771666 -226.737704) (xy 116.756082 -226.784385) (xy 116.733211 -226.827962)
			(xy 116.703646 -226.867306) (xy 116.668153 -226.901398) (xy 116.62765 -226.929354) (xy 116.583188 -226.950452)
			(xy 116.535917 -226.964144) (xy 116.487062 -226.970076) (xy 116.437887 -226.968095) (xy 116.389668 -226.958251)
			(xy 116.343652 -226.940799) (xy 116.301031 -226.916192) (xy 116.26291 -226.885067) (xy 116.230275 -226.84823)
			(xy 116.203972 -226.806634) (xy 116.184681 -226.761358) (xy 116.172904 -226.713574) (xy 116.168944 -226.66452)
			(xy 115.840002 -226.66452) (xy 115.839507 -226.689127) (xy 115.831612 -226.737704) (xy 115.816028 -226.784385)
			(xy 115.793157 -226.827962) (xy 115.763592 -226.867306) (xy 115.728099 -226.901398) (xy 115.687596 -226.929354)
			(xy 115.643134 -226.950452) (xy 115.595863 -226.964144) (xy 115.547008 -226.970076) (xy 115.497833 -226.968095)
			(xy 115.449614 -226.958251) (xy 115.403598 -226.940799) (xy 115.360977 -226.916192) (xy 115.322856 -226.885067)
			(xy 115.290221 -226.84823) (xy 115.263918 -226.806634) (xy 115.244627 -226.761358) (xy 115.23285 -226.713574)
			(xy 115.22889 -226.66452) (xy 112.28832 -226.66452) (xy 112.28832 -227.474526) (xy 112.878882 -227.474526)
			(xy 112.882842 -227.425472) (xy 112.894619 -227.377688) (xy 112.91391 -227.332412) (xy 112.940213 -227.290816)
			(xy 112.972848 -227.253979) (xy 113.010969 -227.222854) (xy 113.05359 -227.198247) (xy 113.099606 -227.180795)
			(xy 113.147825 -227.170951) (xy 113.197 -227.16897) (xy 113.245855 -227.174902) (xy 113.293126 -227.188594)
			(xy 113.337588 -227.209692) (xy 113.378091 -227.237648) (xy 113.413584 -227.27174) (xy 113.443149 -227.311084)
			(xy 113.46602 -227.354661) (xy 113.481604 -227.401342) (xy 113.489499 -227.449919) (xy 113.489994 -227.474526)
			(xy 113.818936 -227.474526) (xy 113.822896 -227.425472) (xy 113.834673 -227.377688) (xy 113.853964 -227.332412)
			(xy 113.880267 -227.290816) (xy 113.912902 -227.253979) (xy 113.951023 -227.222854) (xy 113.993644 -227.198247)
			(xy 114.03966 -227.180795) (xy 114.087879 -227.170951) (xy 114.137054 -227.16897) (xy 114.185909 -227.174902)
			(xy 114.23318 -227.188594) (xy 114.277642 -227.209692) (xy 114.318145 -227.237648) (xy 114.353638 -227.27174)
			(xy 114.383203 -227.311084) (xy 114.406074 -227.354661) (xy 114.421658 -227.401342) (xy 114.429553 -227.449919)
			(xy 114.430048 -227.474526) (xy 114.75899 -227.474526) (xy 114.76295 -227.425472) (xy 114.774727 -227.377688)
			(xy 114.794018 -227.332412) (xy 114.820321 -227.290816) (xy 114.852956 -227.253979) (xy 114.891077 -227.222854)
			(xy 114.933698 -227.198247) (xy 114.979714 -227.180795) (xy 115.027933 -227.170951) (xy 115.077108 -227.16897)
			(xy 115.125963 -227.174902) (xy 115.173234 -227.188594) (xy 115.217696 -227.209692) (xy 115.258199 -227.237648)
			(xy 115.293692 -227.27174) (xy 115.323257 -227.311084) (xy 115.346128 -227.354661) (xy 115.361712 -227.401342)
			(xy 115.369607 -227.449919) (xy 115.370102 -227.474526) (xy 115.699044 -227.474526) (xy 115.703004 -227.425472)
			(xy 115.714781 -227.377688) (xy 115.734072 -227.332412) (xy 115.760375 -227.290816) (xy 115.79301 -227.253979)
			(xy 115.831131 -227.222854) (xy 115.873752 -227.198247) (xy 115.919768 -227.180795) (xy 115.967987 -227.170951)
			(xy 116.017162 -227.16897) (xy 116.066017 -227.174902) (xy 116.113288 -227.188594) (xy 116.15775 -227.209692)
			(xy 116.198253 -227.237648) (xy 116.233746 -227.27174) (xy 116.263311 -227.311084) (xy 116.286182 -227.354661)
			(xy 116.301766 -227.401342) (xy 116.309661 -227.449919) (xy 116.310156 -227.474526) (xy 118.518952 -227.474526)
			(xy 118.522912 -227.425472) (xy 118.534689 -227.377688) (xy 118.55398 -227.332412) (xy 118.580283 -227.290816)
			(xy 118.612918 -227.253979) (xy 118.651039 -227.222854) (xy 118.69366 -227.198247) (xy 118.739676 -227.180795)
			(xy 118.787895 -227.170951) (xy 118.83707 -227.16897) (xy 118.885925 -227.174902) (xy 118.933196 -227.188594)
			(xy 118.977658 -227.209692) (xy 119.018161 -227.237648) (xy 119.053654 -227.27174) (xy 119.083219 -227.311084)
			(xy 119.10609 -227.354661) (xy 119.121674 -227.401342) (xy 119.129569 -227.449919) (xy 119.130064 -227.474526)
			(xy 121.33886 -227.474526) (xy 121.34282 -227.425472) (xy 121.354597 -227.377688) (xy 121.373888 -227.332412)
			(xy 121.400191 -227.290816) (xy 121.432826 -227.253979) (xy 121.470947 -227.222854) (xy 121.513568 -227.198247)
			(xy 121.559584 -227.180795) (xy 121.607803 -227.170951) (xy 121.656978 -227.16897) (xy 121.705833 -227.174902)
			(xy 121.753104 -227.188594) (xy 121.797566 -227.209692) (xy 121.838069 -227.237648) (xy 121.873562 -227.27174)
			(xy 121.903127 -227.311084) (xy 121.925998 -227.354661) (xy 121.941582 -227.401342) (xy 121.949477 -227.449919)
			(xy 121.949972 -227.474526) (xy 124.159022 -227.474526) (xy 124.162982 -227.425472) (xy 124.174759 -227.377688)
			(xy 124.19405 -227.332412) (xy 124.220353 -227.290816) (xy 124.252988 -227.253979) (xy 124.291109 -227.222854)
			(xy 124.33373 -227.198247) (xy 124.379746 -227.180795) (xy 124.427965 -227.170951) (xy 124.47714 -227.16897)
			(xy 124.525995 -227.174902) (xy 124.573266 -227.188594) (xy 124.617728 -227.209692) (xy 124.658231 -227.237648)
			(xy 124.693724 -227.27174) (xy 124.723289 -227.311084) (xy 124.74616 -227.354661) (xy 124.761744 -227.401342)
			(xy 124.769639 -227.449919) (xy 124.770134 -227.474526) (xy 124.769639 -227.499133) (xy 124.761744 -227.54771)
			(xy 124.74616 -227.594391) (xy 124.723289 -227.637968) (xy 124.693724 -227.677312) (xy 124.658231 -227.711404)
			(xy 124.617728 -227.73936) (xy 124.573266 -227.760458) (xy 124.525995 -227.77415) (xy 124.47714 -227.780082)
			(xy 124.427965 -227.778101) (xy 124.379746 -227.768257) (xy 124.33373 -227.750805) (xy 124.291109 -227.726198)
			(xy 124.252988 -227.695073) (xy 124.220353 -227.658236) (xy 124.19405 -227.61664) (xy 124.174759 -227.571364)
			(xy 124.162982 -227.52358) (xy 124.159022 -227.474526) (xy 121.949972 -227.474526) (xy 121.949477 -227.499133)
			(xy 121.941582 -227.54771) (xy 121.925998 -227.594391) (xy 121.903127 -227.637968) (xy 121.873562 -227.677312)
			(xy 121.838069 -227.711404) (xy 121.797566 -227.73936) (xy 121.753104 -227.760458) (xy 121.705833 -227.77415)
			(xy 121.656978 -227.780082) (xy 121.607803 -227.778101) (xy 121.559584 -227.768257) (xy 121.513568 -227.750805)
			(xy 121.470947 -227.726198) (xy 121.432826 -227.695073) (xy 121.400191 -227.658236) (xy 121.373888 -227.61664)
			(xy 121.354597 -227.571364) (xy 121.34282 -227.52358) (xy 121.33886 -227.474526) (xy 119.130064 -227.474526)
			(xy 119.129569 -227.499133) (xy 119.121674 -227.54771) (xy 119.10609 -227.594391) (xy 119.083219 -227.637968)
			(xy 119.053654 -227.677312) (xy 119.018161 -227.711404) (xy 118.977658 -227.73936) (xy 118.933196 -227.760458)
			(xy 118.885925 -227.77415) (xy 118.83707 -227.780082) (xy 118.787895 -227.778101) (xy 118.739676 -227.768257)
			(xy 118.69366 -227.750805) (xy 118.651039 -227.726198) (xy 118.612918 -227.695073) (xy 118.580283 -227.658236)
			(xy 118.55398 -227.61664) (xy 118.534689 -227.571364) (xy 118.522912 -227.52358) (xy 118.518952 -227.474526)
			(xy 116.310156 -227.474526) (xy 116.309661 -227.499133) (xy 116.301766 -227.54771) (xy 116.286182 -227.594391)
			(xy 116.263311 -227.637968) (xy 116.233746 -227.677312) (xy 116.198253 -227.711404) (xy 116.15775 -227.73936)
			(xy 116.113288 -227.760458) (xy 116.066017 -227.77415) (xy 116.017162 -227.780082) (xy 115.967987 -227.778101)
			(xy 115.919768 -227.768257) (xy 115.873752 -227.750805) (xy 115.831131 -227.726198) (xy 115.79301 -227.695073)
			(xy 115.760375 -227.658236) (xy 115.734072 -227.61664) (xy 115.714781 -227.571364) (xy 115.703004 -227.52358)
			(xy 115.699044 -227.474526) (xy 115.370102 -227.474526) (xy 115.369607 -227.499133) (xy 115.361712 -227.54771)
			(xy 115.346128 -227.594391) (xy 115.323257 -227.637968) (xy 115.293692 -227.677312) (xy 115.258199 -227.711404)
			(xy 115.217696 -227.73936) (xy 115.173234 -227.760458) (xy 115.125963 -227.77415) (xy 115.077108 -227.780082)
			(xy 115.027933 -227.778101) (xy 114.979714 -227.768257) (xy 114.933698 -227.750805) (xy 114.891077 -227.726198)
			(xy 114.852956 -227.695073) (xy 114.820321 -227.658236) (xy 114.794018 -227.61664) (xy 114.774727 -227.571364)
			(xy 114.76295 -227.52358) (xy 114.75899 -227.474526) (xy 114.430048 -227.474526) (xy 114.429553 -227.499133)
			(xy 114.421658 -227.54771) (xy 114.406074 -227.594391) (xy 114.383203 -227.637968) (xy 114.353638 -227.677312)
			(xy 114.318145 -227.711404) (xy 114.277642 -227.73936) (xy 114.23318 -227.760458) (xy 114.185909 -227.77415)
			(xy 114.137054 -227.780082) (xy 114.087879 -227.778101) (xy 114.03966 -227.768257) (xy 113.993644 -227.750805)
			(xy 113.951023 -227.726198) (xy 113.912902 -227.695073) (xy 113.880267 -227.658236) (xy 113.853964 -227.61664)
			(xy 113.834673 -227.571364) (xy 113.822896 -227.52358) (xy 113.818936 -227.474526) (xy 113.489994 -227.474526)
			(xy 113.489499 -227.499133) (xy 113.481604 -227.54771) (xy 113.46602 -227.594391) (xy 113.443149 -227.637968)
			(xy 113.413584 -227.677312) (xy 113.378091 -227.711404) (xy 113.337588 -227.73936) (xy 113.293126 -227.760458)
			(xy 113.245855 -227.77415) (xy 113.197 -227.780082) (xy 113.147825 -227.778101) (xy 113.099606 -227.768257)
			(xy 113.05359 -227.750805) (xy 113.010969 -227.726198) (xy 112.972848 -227.695073) (xy 112.940213 -227.658236)
			(xy 112.91391 -227.61664) (xy 112.894619 -227.571364) (xy 112.882842 -227.52358) (xy 112.878882 -227.474526)
			(xy 112.28832 -227.474526) (xy 112.28832 -228.284532) (xy 115.22889 -228.284532) (xy 115.23285 -228.235478)
			(xy 115.244627 -228.187694) (xy 115.263918 -228.142418) (xy 115.290221 -228.100822) (xy 115.322856 -228.063985)
			(xy 115.360977 -228.03286) (xy 115.403598 -228.008253) (xy 115.449614 -227.990801) (xy 115.497833 -227.980957)
			(xy 115.547008 -227.978976) (xy 115.595863 -227.984908) (xy 115.643134 -227.9986) (xy 115.687596 -228.019698)
			(xy 115.728099 -228.047654) (xy 115.763592 -228.081746) (xy 115.793157 -228.12109) (xy 115.816028 -228.164667)
			(xy 115.831612 -228.211348) (xy 115.839507 -228.259925) (xy 115.840002 -228.284532) (xy 116.168944 -228.284532)
			(xy 116.172904 -228.235478) (xy 116.184681 -228.187694) (xy 116.203972 -228.142418) (xy 116.230275 -228.100822)
			(xy 116.26291 -228.063985) (xy 116.301031 -228.03286) (xy 116.343652 -228.008253) (xy 116.389668 -227.990801)
			(xy 116.437887 -227.980957) (xy 116.487062 -227.978976) (xy 116.535917 -227.984908) (xy 116.583188 -227.9986)
			(xy 116.62765 -228.019698) (xy 116.668153 -228.047654) (xy 116.703646 -228.081746) (xy 116.733211 -228.12109)
			(xy 116.756082 -228.164667) (xy 116.771666 -228.211348) (xy 116.779561 -228.259925) (xy 116.780056 -228.284532)
			(xy 117.108998 -228.284532) (xy 117.112958 -228.235478) (xy 117.124735 -228.187694) (xy 117.144026 -228.142418)
			(xy 117.170329 -228.100822) (xy 117.202964 -228.063985) (xy 117.241085 -228.03286) (xy 117.283706 -228.008253)
			(xy 117.329722 -227.990801) (xy 117.377941 -227.980957) (xy 117.427116 -227.978976) (xy 117.475971 -227.984908)
			(xy 117.523242 -227.9986) (xy 117.567704 -228.019698) (xy 117.608207 -228.047654) (xy 117.6437 -228.081746)
			(xy 117.673265 -228.12109) (xy 117.696136 -228.164667) (xy 117.71172 -228.211348) (xy 117.719615 -228.259925)
			(xy 117.72011 -228.284532) (xy 118.049052 -228.284532) (xy 118.053012 -228.235478) (xy 118.064789 -228.187694)
			(xy 118.08408 -228.142418) (xy 118.110383 -228.100822) (xy 118.143018 -228.063985) (xy 118.181139 -228.03286)
			(xy 118.22376 -228.008253) (xy 118.269776 -227.990801) (xy 118.317995 -227.980957) (xy 118.36717 -227.978976)
			(xy 118.416025 -227.984908) (xy 118.463296 -227.9986) (xy 118.507758 -228.019698) (xy 118.548261 -228.047654)
			(xy 118.583754 -228.081746) (xy 118.613319 -228.12109) (xy 118.63619 -228.164667) (xy 118.651774 -228.211348)
			(xy 118.659669 -228.259925) (xy 118.660164 -228.284532) (xy 118.988852 -228.284532) (xy 118.992812 -228.235478)
			(xy 119.004589 -228.187694) (xy 119.02388 -228.142418) (xy 119.050183 -228.100822) (xy 119.082818 -228.063985)
			(xy 119.120939 -228.03286) (xy 119.16356 -228.008253) (xy 119.209576 -227.990801) (xy 119.257795 -227.980957)
			(xy 119.30697 -227.978976) (xy 119.355825 -227.984908) (xy 119.403096 -227.9986) (xy 119.447558 -228.019698)
			(xy 119.488061 -228.047654) (xy 119.523554 -228.081746) (xy 119.553119 -228.12109) (xy 119.57599 -228.164667)
			(xy 119.591574 -228.211348) (xy 119.599469 -228.259925) (xy 119.599964 -228.284532) (xy 119.928906 -228.284532)
			(xy 119.932866 -228.235478) (xy 119.944643 -228.187694) (xy 119.963934 -228.142418) (xy 119.990237 -228.100822)
			(xy 120.022872 -228.063985) (xy 120.060993 -228.03286) (xy 120.103614 -228.008253) (xy 120.14963 -227.990801)
			(xy 120.197849 -227.980957) (xy 120.247024 -227.978976) (xy 120.295879 -227.984908) (xy 120.34315 -227.9986)
			(xy 120.387612 -228.019698) (xy 120.428115 -228.047654) (xy 120.463608 -228.081746) (xy 120.493173 -228.12109)
			(xy 120.516044 -228.164667) (xy 120.531628 -228.211348) (xy 120.539523 -228.259925) (xy 120.540018 -228.284532)
			(xy 120.86896 -228.284532) (xy 120.87292 -228.235478) (xy 120.884697 -228.187694) (xy 120.903988 -228.142418)
			(xy 120.930291 -228.100822) (xy 120.962926 -228.063985) (xy 121.001047 -228.03286) (xy 121.043668 -228.008253)
			(xy 121.089684 -227.990801) (xy 121.137903 -227.980957) (xy 121.187078 -227.978976) (xy 121.235933 -227.984908)
			(xy 121.283204 -227.9986) (xy 121.327666 -228.019698) (xy 121.368169 -228.047654) (xy 121.403662 -228.081746)
			(xy 121.433227 -228.12109) (xy 121.456098 -228.164667) (xy 121.471682 -228.211348) (xy 121.479577 -228.259925)
			(xy 121.480072 -228.284532) (xy 121.809014 -228.284532) (xy 121.812974 -228.235478) (xy 121.824751 -228.187694)
			(xy 121.844042 -228.142418) (xy 121.870345 -228.100822) (xy 121.90298 -228.063985) (xy 121.941101 -228.03286)
			(xy 121.983722 -228.008253) (xy 122.029738 -227.990801) (xy 122.077957 -227.980957) (xy 122.127132 -227.978976)
			(xy 122.175987 -227.984908) (xy 122.223258 -227.9986) (xy 122.26772 -228.019698) (xy 122.308223 -228.047654)
			(xy 122.343716 -228.081746) (xy 122.373281 -228.12109) (xy 122.396152 -228.164667) (xy 122.411736 -228.211348)
			(xy 122.419631 -228.259925) (xy 122.420126 -228.284532) (xy 122.748814 -228.284532) (xy 122.752774 -228.235478)
			(xy 122.764551 -228.187694) (xy 122.783842 -228.142418) (xy 122.810145 -228.100822) (xy 122.84278 -228.063985)
			(xy 122.880901 -228.03286) (xy 122.923522 -228.008253) (xy 122.969538 -227.990801) (xy 123.017757 -227.980957)
			(xy 123.066932 -227.978976) (xy 123.115787 -227.984908) (xy 123.163058 -227.9986) (xy 123.20752 -228.019698)
			(xy 123.248023 -228.047654) (xy 123.283516 -228.081746) (xy 123.313081 -228.12109) (xy 123.335952 -228.164667)
			(xy 123.351536 -228.211348) (xy 123.359431 -228.259925) (xy 123.359926 -228.284532) (xy 123.688868 -228.284532)
			(xy 123.692828 -228.235478) (xy 123.704605 -228.187694) (xy 123.723896 -228.142418) (xy 123.750199 -228.100822)
			(xy 123.782834 -228.063985) (xy 123.820955 -228.03286) (xy 123.863576 -228.008253) (xy 123.909592 -227.990801)
			(xy 123.957811 -227.980957) (xy 124.006986 -227.978976) (xy 124.055841 -227.984908) (xy 124.103112 -227.9986)
			(xy 124.147574 -228.019698) (xy 124.188077 -228.047654) (xy 124.22357 -228.081746) (xy 124.253135 -228.12109)
			(xy 124.276006 -228.164667) (xy 124.29159 -228.211348) (xy 124.299485 -228.259925) (xy 124.29998 -228.284532)
			(xy 124.628922 -228.284532) (xy 124.632882 -228.235478) (xy 124.644659 -228.187694) (xy 124.66395 -228.142418)
			(xy 124.690253 -228.100822) (xy 124.722888 -228.063985) (xy 124.761009 -228.03286) (xy 124.80363 -228.008253)
			(xy 124.849646 -227.990801) (xy 124.897865 -227.980957) (xy 124.94704 -227.978976) (xy 124.995895 -227.984908)
			(xy 125.043166 -227.9986) (xy 125.087628 -228.019698) (xy 125.128131 -228.047654) (xy 125.163624 -228.081746)
			(xy 125.193189 -228.12109) (xy 125.21606 -228.164667) (xy 125.231644 -228.211348) (xy 125.239539 -228.259925)
			(xy 125.240034 -228.284532) (xy 125.568976 -228.284532) (xy 125.572936 -228.235478) (xy 125.584713 -228.187694)
			(xy 125.604004 -228.142418) (xy 125.630307 -228.100822) (xy 125.662942 -228.063985) (xy 125.701063 -228.03286)
			(xy 125.743684 -228.008253) (xy 125.7897 -227.990801) (xy 125.837919 -227.980957) (xy 125.887094 -227.978976)
			(xy 125.935949 -227.984908) (xy 125.98322 -227.9986) (xy 126.027682 -228.019698) (xy 126.068185 -228.047654)
			(xy 126.103678 -228.081746) (xy 126.133243 -228.12109) (xy 126.156114 -228.164667) (xy 126.171698 -228.211348)
			(xy 126.179593 -228.259925) (xy 126.180088 -228.284532) (xy 126.179593 -228.309139) (xy 126.171698 -228.357716)
			(xy 126.156114 -228.404397) (xy 126.133243 -228.447974) (xy 126.103678 -228.487318) (xy 126.068185 -228.52141)
			(xy 126.027682 -228.549366) (xy 125.98322 -228.570464) (xy 125.935949 -228.584156) (xy 125.887094 -228.590088)
			(xy 125.837919 -228.588107) (xy 125.7897 -228.578263) (xy 125.743684 -228.560811) (xy 125.701063 -228.536204)
			(xy 125.662942 -228.505079) (xy 125.630307 -228.468242) (xy 125.604004 -228.426646) (xy 125.584713 -228.38137)
			(xy 125.572936 -228.333586) (xy 125.568976 -228.284532) (xy 125.240034 -228.284532) (xy 125.239539 -228.309139)
			(xy 125.231644 -228.357716) (xy 125.21606 -228.404397) (xy 125.193189 -228.447974) (xy 125.163624 -228.487318)
			(xy 125.128131 -228.52141) (xy 125.087628 -228.549366) (xy 125.043166 -228.570464) (xy 124.995895 -228.584156)
			(xy 124.94704 -228.590088) (xy 124.897865 -228.588107) (xy 124.849646 -228.578263) (xy 124.80363 -228.560811)
			(xy 124.761009 -228.536204) (xy 124.722888 -228.505079) (xy 124.690253 -228.468242) (xy 124.66395 -228.426646)
			(xy 124.644659 -228.38137) (xy 124.632882 -228.333586) (xy 124.628922 -228.284532) (xy 124.29998 -228.284532)
			(xy 124.299485 -228.309139) (xy 124.29159 -228.357716) (xy 124.276006 -228.404397) (xy 124.253135 -228.447974)
			(xy 124.22357 -228.487318) (xy 124.188077 -228.52141) (xy 124.147574 -228.549366) (xy 124.103112 -228.570464)
			(xy 124.055841 -228.584156) (xy 124.006986 -228.590088) (xy 123.957811 -228.588107) (xy 123.909592 -228.578263)
			(xy 123.863576 -228.560811) (xy 123.820955 -228.536204) (xy 123.782834 -228.505079) (xy 123.750199 -228.468242)
			(xy 123.723896 -228.426646) (xy 123.704605 -228.38137) (xy 123.692828 -228.333586) (xy 123.688868 -228.284532)
			(xy 123.359926 -228.284532) (xy 123.359431 -228.309139) (xy 123.351536 -228.357716) (xy 123.335952 -228.404397)
			(xy 123.313081 -228.447974) (xy 123.283516 -228.487318) (xy 123.248023 -228.52141) (xy 123.20752 -228.549366)
			(xy 123.163058 -228.570464) (xy 123.115787 -228.584156) (xy 123.066932 -228.590088) (xy 123.017757 -228.588107)
			(xy 122.969538 -228.578263) (xy 122.923522 -228.560811) (xy 122.880901 -228.536204) (xy 122.84278 -228.505079)
			(xy 122.810145 -228.468242) (xy 122.783842 -228.426646) (xy 122.764551 -228.38137) (xy 122.752774 -228.333586)
			(xy 122.748814 -228.284532) (xy 122.420126 -228.284532) (xy 122.419631 -228.309139) (xy 122.411736 -228.357716)
			(xy 122.396152 -228.404397) (xy 122.373281 -228.447974) (xy 122.343716 -228.487318) (xy 122.308223 -228.52141)
			(xy 122.26772 -228.549366) (xy 122.223258 -228.570464) (xy 122.175987 -228.584156) (xy 122.127132 -228.590088)
			(xy 122.077957 -228.588107) (xy 122.029738 -228.578263) (xy 121.983722 -228.560811) (xy 121.941101 -228.536204)
			(xy 121.90298 -228.505079) (xy 121.870345 -228.468242) (xy 121.844042 -228.426646) (xy 121.824751 -228.38137)
			(xy 121.812974 -228.333586) (xy 121.809014 -228.284532) (xy 121.480072 -228.284532) (xy 121.479577 -228.309139)
			(xy 121.471682 -228.357716) (xy 121.456098 -228.404397) (xy 121.433227 -228.447974) (xy 121.403662 -228.487318)
			(xy 121.368169 -228.52141) (xy 121.327666 -228.549366) (xy 121.283204 -228.570464) (xy 121.235933 -228.584156)
			(xy 121.187078 -228.590088) (xy 121.137903 -228.588107) (xy 121.089684 -228.578263) (xy 121.043668 -228.560811)
			(xy 121.001047 -228.536204) (xy 120.962926 -228.505079) (xy 120.930291 -228.468242) (xy 120.903988 -228.426646)
			(xy 120.884697 -228.38137) (xy 120.87292 -228.333586) (xy 120.86896 -228.284532) (xy 120.540018 -228.284532)
			(xy 120.539523 -228.309139) (xy 120.531628 -228.357716) (xy 120.516044 -228.404397) (xy 120.493173 -228.447974)
			(xy 120.463608 -228.487318) (xy 120.428115 -228.52141) (xy 120.387612 -228.549366) (xy 120.34315 -228.570464)
			(xy 120.295879 -228.584156) (xy 120.247024 -228.590088) (xy 120.197849 -228.588107) (xy 120.14963 -228.578263)
			(xy 120.103614 -228.560811) (xy 120.060993 -228.536204) (xy 120.022872 -228.505079) (xy 119.990237 -228.468242)
			(xy 119.963934 -228.426646) (xy 119.944643 -228.38137) (xy 119.932866 -228.333586) (xy 119.928906 -228.284532)
			(xy 119.599964 -228.284532) (xy 119.599469 -228.309139) (xy 119.591574 -228.357716) (xy 119.57599 -228.404397)
			(xy 119.553119 -228.447974) (xy 119.523554 -228.487318) (xy 119.488061 -228.52141) (xy 119.447558 -228.549366)
			(xy 119.403096 -228.570464) (xy 119.355825 -228.584156) (xy 119.30697 -228.590088) (xy 119.257795 -228.588107)
			(xy 119.209576 -228.578263) (xy 119.16356 -228.560811) (xy 119.120939 -228.536204) (xy 119.082818 -228.505079)
			(xy 119.050183 -228.468242) (xy 119.02388 -228.426646) (xy 119.004589 -228.38137) (xy 118.992812 -228.333586)
			(xy 118.988852 -228.284532) (xy 118.660164 -228.284532) (xy 118.659669 -228.309139) (xy 118.651774 -228.357716)
			(xy 118.63619 -228.404397) (xy 118.613319 -228.447974) (xy 118.583754 -228.487318) (xy 118.548261 -228.52141)
			(xy 118.507758 -228.549366) (xy 118.463296 -228.570464) (xy 118.416025 -228.584156) (xy 118.36717 -228.590088)
			(xy 118.317995 -228.588107) (xy 118.269776 -228.578263) (xy 118.22376 -228.560811) (xy 118.181139 -228.536204)
			(xy 118.143018 -228.505079) (xy 118.110383 -228.468242) (xy 118.08408 -228.426646) (xy 118.064789 -228.38137)
			(xy 118.053012 -228.333586) (xy 118.049052 -228.284532) (xy 117.72011 -228.284532) (xy 117.719615 -228.309139)
			(xy 117.71172 -228.357716) (xy 117.696136 -228.404397) (xy 117.673265 -228.447974) (xy 117.6437 -228.487318)
			(xy 117.608207 -228.52141) (xy 117.567704 -228.549366) (xy 117.523242 -228.570464) (xy 117.475971 -228.584156)
			(xy 117.427116 -228.590088) (xy 117.377941 -228.588107) (xy 117.329722 -228.578263) (xy 117.283706 -228.560811)
			(xy 117.241085 -228.536204) (xy 117.202964 -228.505079) (xy 117.170329 -228.468242) (xy 117.144026 -228.426646)
			(xy 117.124735 -228.38137) (xy 117.112958 -228.333586) (xy 117.108998 -228.284532) (xy 116.780056 -228.284532)
			(xy 116.779561 -228.309139) (xy 116.771666 -228.357716) (xy 116.756082 -228.404397) (xy 116.733211 -228.447974)
			(xy 116.703646 -228.487318) (xy 116.668153 -228.52141) (xy 116.62765 -228.549366) (xy 116.583188 -228.570464)
			(xy 116.535917 -228.584156) (xy 116.487062 -228.590088) (xy 116.437887 -228.588107) (xy 116.389668 -228.578263)
			(xy 116.343652 -228.560811) (xy 116.301031 -228.536204) (xy 116.26291 -228.505079) (xy 116.230275 -228.468242)
			(xy 116.203972 -228.426646) (xy 116.184681 -228.38137) (xy 116.172904 -228.333586) (xy 116.168944 -228.284532)
			(xy 115.840002 -228.284532) (xy 115.839507 -228.309139) (xy 115.831612 -228.357716) (xy 115.816028 -228.404397)
			(xy 115.793157 -228.447974) (xy 115.763592 -228.487318) (xy 115.728099 -228.52141) (xy 115.687596 -228.549366)
			(xy 115.643134 -228.570464) (xy 115.595863 -228.584156) (xy 115.547008 -228.590088) (xy 115.497833 -228.588107)
			(xy 115.449614 -228.578263) (xy 115.403598 -228.560811) (xy 115.360977 -228.536204) (xy 115.322856 -228.505079)
			(xy 115.290221 -228.468242) (xy 115.263918 -228.426646) (xy 115.244627 -228.38137) (xy 115.23285 -228.333586)
			(xy 115.22889 -228.284532) (xy 112.28832 -228.284532) (xy 112.28832 -229.094538) (xy 112.878882 -229.094538)
			(xy 112.882842 -229.045484) (xy 112.894619 -228.9977) (xy 112.91391 -228.952424) (xy 112.940213 -228.910828)
			(xy 112.972848 -228.873991) (xy 113.010969 -228.842866) (xy 113.05359 -228.818259) (xy 113.099606 -228.800807)
			(xy 113.147825 -228.790963) (xy 113.197 -228.788982) (xy 113.245855 -228.794914) (xy 113.293126 -228.808606)
			(xy 113.337588 -228.829704) (xy 113.378091 -228.85766) (xy 113.413584 -228.891752) (xy 113.443149 -228.931096)
			(xy 113.46602 -228.974673) (xy 113.481604 -229.021354) (xy 113.489499 -229.069931) (xy 113.489994 -229.094538)
			(xy 113.818936 -229.094538) (xy 113.822896 -229.045484) (xy 113.834673 -228.9977) (xy 113.853964 -228.952424)
			(xy 113.880267 -228.910828) (xy 113.912902 -228.873991) (xy 113.951023 -228.842866) (xy 113.993644 -228.818259)
			(xy 114.03966 -228.800807) (xy 114.087879 -228.790963) (xy 114.137054 -228.788982) (xy 114.185909 -228.794914)
			(xy 114.23318 -228.808606) (xy 114.277642 -228.829704) (xy 114.318145 -228.85766) (xy 114.353638 -228.891752)
			(xy 114.383203 -228.931096) (xy 114.406074 -228.974673) (xy 114.421658 -229.021354) (xy 114.429553 -229.069931)
			(xy 114.430048 -229.094538) (xy 114.75899 -229.094538) (xy 114.76295 -229.045484) (xy 114.774727 -228.9977)
			(xy 114.794018 -228.952424) (xy 114.820321 -228.910828) (xy 114.852956 -228.873991) (xy 114.891077 -228.842866)
			(xy 114.933698 -228.818259) (xy 114.979714 -228.800807) (xy 115.027933 -228.790963) (xy 115.077108 -228.788982)
			(xy 115.125963 -228.794914) (xy 115.173234 -228.808606) (xy 115.217696 -228.829704) (xy 115.258199 -228.85766)
			(xy 115.293692 -228.891752) (xy 115.323257 -228.931096) (xy 115.346128 -228.974673) (xy 115.361712 -229.021354)
			(xy 115.369607 -229.069931) (xy 115.370102 -229.094538) (xy 115.699044 -229.094538) (xy 115.703004 -229.045484)
			(xy 115.714781 -228.9977) (xy 115.734072 -228.952424) (xy 115.760375 -228.910828) (xy 115.79301 -228.873991)
			(xy 115.831131 -228.842866) (xy 115.873752 -228.818259) (xy 115.919768 -228.800807) (xy 115.967987 -228.790963)
			(xy 116.017162 -228.788982) (xy 116.066017 -228.794914) (xy 116.113288 -228.808606) (xy 116.15775 -228.829704)
			(xy 116.198253 -228.85766) (xy 116.233746 -228.891752) (xy 116.263311 -228.931096) (xy 116.286182 -228.974673)
			(xy 116.301766 -229.021354) (xy 116.309661 -229.069931) (xy 116.310156 -229.094538) (xy 116.638844 -229.094538)
			(xy 116.642804 -229.045484) (xy 116.654581 -228.9977) (xy 116.673872 -228.952424) (xy 116.700175 -228.910828)
			(xy 116.73281 -228.873991) (xy 116.770931 -228.842866) (xy 116.813552 -228.818259) (xy 116.859568 -228.800807)
			(xy 116.907787 -228.790963) (xy 116.956962 -228.788982) (xy 117.005817 -228.794914) (xy 117.053088 -228.808606)
			(xy 117.09755 -228.829704) (xy 117.138053 -228.85766) (xy 117.173546 -228.891752) (xy 117.203111 -228.931096)
			(xy 117.225982 -228.974673) (xy 117.241566 -229.021354) (xy 117.249461 -229.069931) (xy 117.249956 -229.094538)
			(xy 117.578898 -229.094538) (xy 117.582858 -229.045484) (xy 117.594635 -228.9977) (xy 117.613926 -228.952424)
			(xy 117.640229 -228.910828) (xy 117.672864 -228.873991) (xy 117.710985 -228.842866) (xy 117.753606 -228.818259)
			(xy 117.799622 -228.800807) (xy 117.847841 -228.790963) (xy 117.897016 -228.788982) (xy 117.945871 -228.794914)
			(xy 117.993142 -228.808606) (xy 118.037604 -228.829704) (xy 118.078107 -228.85766) (xy 118.1136 -228.891752)
			(xy 118.143165 -228.931096) (xy 118.166036 -228.974673) (xy 118.18162 -229.021354) (xy 118.189515 -229.069931)
			(xy 118.19001 -229.094538) (xy 118.518952 -229.094538) (xy 118.522912 -229.045484) (xy 118.534689 -228.9977)
			(xy 118.55398 -228.952424) (xy 118.580283 -228.910828) (xy 118.612918 -228.873991) (xy 118.651039 -228.842866)
			(xy 118.69366 -228.818259) (xy 118.739676 -228.800807) (xy 118.787895 -228.790963) (xy 118.83707 -228.788982)
			(xy 118.885925 -228.794914) (xy 118.933196 -228.808606) (xy 118.977658 -228.829704) (xy 119.018161 -228.85766)
			(xy 119.053654 -228.891752) (xy 119.083219 -228.931096) (xy 119.10609 -228.974673) (xy 119.121674 -229.021354)
			(xy 119.129569 -229.069931) (xy 119.130064 -229.094538) (xy 119.459006 -229.094538) (xy 119.462966 -229.045484)
			(xy 119.474743 -228.9977) (xy 119.494034 -228.952424) (xy 119.520337 -228.910828) (xy 119.552972 -228.873991)
			(xy 119.591093 -228.842866) (xy 119.633714 -228.818259) (xy 119.67973 -228.800807) (xy 119.727949 -228.790963)
			(xy 119.777124 -228.788982) (xy 119.825979 -228.794914) (xy 119.87325 -228.808606) (xy 119.917712 -228.829704)
			(xy 119.958215 -228.85766) (xy 119.993708 -228.891752) (xy 120.023273 -228.931096) (xy 120.046144 -228.974673)
			(xy 120.061728 -229.021354) (xy 120.069623 -229.069931) (xy 120.070118 -229.094538) (xy 120.398806 -229.094538)
			(xy 120.402766 -229.045484) (xy 120.414543 -228.9977) (xy 120.433834 -228.952424) (xy 120.460137 -228.910828)
			(xy 120.492772 -228.873991) (xy 120.530893 -228.842866) (xy 120.573514 -228.818259) (xy 120.61953 -228.800807)
			(xy 120.667749 -228.790963) (xy 120.716924 -228.788982) (xy 120.765779 -228.794914) (xy 120.81305 -228.808606)
			(xy 120.857512 -228.829704) (xy 120.898015 -228.85766) (xy 120.933508 -228.891752) (xy 120.963073 -228.931096)
			(xy 120.985944 -228.974673) (xy 121.001528 -229.021354) (xy 121.009423 -229.069931) (xy 121.009918 -229.094538)
			(xy 121.33886 -229.094538) (xy 121.34282 -229.045484) (xy 121.354597 -228.9977) (xy 121.373888 -228.952424)
			(xy 121.400191 -228.910828) (xy 121.432826 -228.873991) (xy 121.470947 -228.842866) (xy 121.513568 -228.818259)
			(xy 121.559584 -228.800807) (xy 121.607803 -228.790963) (xy 121.656978 -228.788982) (xy 121.705833 -228.794914)
			(xy 121.753104 -228.808606) (xy 121.797566 -228.829704) (xy 121.838069 -228.85766) (xy 121.873562 -228.891752)
			(xy 121.903127 -228.931096) (xy 121.925998 -228.974673) (xy 121.941582 -229.021354) (xy 121.949477 -229.069931)
			(xy 121.949972 -229.094538) (xy 122.278914 -229.094538) (xy 122.282874 -229.045484) (xy 122.294651 -228.9977)
			(xy 122.313942 -228.952424) (xy 122.340245 -228.910828) (xy 122.37288 -228.873991) (xy 122.411001 -228.842866)
			(xy 122.453622 -228.818259) (xy 122.499638 -228.800807) (xy 122.547857 -228.790963) (xy 122.597032 -228.788982)
			(xy 122.645887 -228.794914) (xy 122.693158 -228.808606) (xy 122.73762 -228.829704) (xy 122.778123 -228.85766)
			(xy 122.813616 -228.891752) (xy 122.843181 -228.931096) (xy 122.866052 -228.974673) (xy 122.881636 -229.021354)
			(xy 122.889531 -229.069931) (xy 122.890026 -229.094538) (xy 123.218968 -229.094538) (xy 123.222928 -229.045484)
			(xy 123.234705 -228.9977) (xy 123.253996 -228.952424) (xy 123.280299 -228.910828) (xy 123.312934 -228.873991)
			(xy 123.351055 -228.842866) (xy 123.393676 -228.818259) (xy 123.439692 -228.800807) (xy 123.487911 -228.790963)
			(xy 123.537086 -228.788982) (xy 123.585941 -228.794914) (xy 123.633212 -228.808606) (xy 123.677674 -228.829704)
			(xy 123.718177 -228.85766) (xy 123.75367 -228.891752) (xy 123.783235 -228.931096) (xy 123.806106 -228.974673)
			(xy 123.82169 -229.021354) (xy 123.829585 -229.069931) (xy 123.83008 -229.094538) (xy 124.159022 -229.094538)
			(xy 124.162982 -229.045484) (xy 124.174759 -228.9977) (xy 124.19405 -228.952424) (xy 124.220353 -228.910828)
			(xy 124.252988 -228.873991) (xy 124.291109 -228.842866) (xy 124.33373 -228.818259) (xy 124.379746 -228.800807)
			(xy 124.427965 -228.790963) (xy 124.47714 -228.788982) (xy 124.525995 -228.794914) (xy 124.573266 -228.808606)
			(xy 124.617728 -228.829704) (xy 124.658231 -228.85766) (xy 124.693724 -228.891752) (xy 124.723289 -228.931096)
			(xy 124.74616 -228.974673) (xy 124.761744 -229.021354) (xy 124.769639 -229.069931) (xy 124.770134 -229.094538)
			(xy 125.098822 -229.094538) (xy 125.102782 -229.045484) (xy 125.114559 -228.9977) (xy 125.13385 -228.952424)
			(xy 125.160153 -228.910828) (xy 125.192788 -228.873991) (xy 125.230909 -228.842866) (xy 125.27353 -228.818259)
			(xy 125.319546 -228.800807) (xy 125.367765 -228.790963) (xy 125.41694 -228.788982) (xy 125.465795 -228.794914)
			(xy 125.513066 -228.808606) (xy 125.557528 -228.829704) (xy 125.598031 -228.85766) (xy 125.633524 -228.891752)
			(xy 125.663089 -228.931096) (xy 125.68596 -228.974673) (xy 125.701544 -229.021354) (xy 125.709439 -229.069931)
			(xy 125.709934 -229.094538) (xy 126.038876 -229.094538) (xy 126.042836 -229.045484) (xy 126.054613 -228.9977)
			(xy 126.073904 -228.952424) (xy 126.100207 -228.910828) (xy 126.132842 -228.873991) (xy 126.170963 -228.842866)
			(xy 126.213584 -228.818259) (xy 126.2596 -228.800807) (xy 126.307819 -228.790963) (xy 126.356994 -228.788982)
			(xy 126.405849 -228.794914) (xy 126.45312 -228.808606) (xy 126.497582 -228.829704) (xy 126.538085 -228.85766)
			(xy 126.573578 -228.891752) (xy 126.603143 -228.931096) (xy 126.626014 -228.974673) (xy 126.641598 -229.021354)
			(xy 126.649493 -229.069931) (xy 126.649988 -229.094538) (xy 126.649493 -229.119145) (xy 126.641598 -229.167722)
			(xy 126.626014 -229.214403) (xy 126.603143 -229.25798) (xy 126.573578 -229.297324) (xy 126.538085 -229.331416)
			(xy 126.497582 -229.359372) (xy 126.45312 -229.38047) (xy 126.405849 -229.394162) (xy 126.356994 -229.400094)
			(xy 126.307819 -229.398113) (xy 126.2596 -229.388269) (xy 126.213584 -229.370817) (xy 126.170963 -229.34621)
			(xy 126.132842 -229.315085) (xy 126.100207 -229.278248) (xy 126.073904 -229.236652) (xy 126.054613 -229.191376)
			(xy 126.042836 -229.143592) (xy 126.038876 -229.094538) (xy 125.709934 -229.094538) (xy 125.709439 -229.119145)
			(xy 125.701544 -229.167722) (xy 125.68596 -229.214403) (xy 125.663089 -229.25798) (xy 125.633524 -229.297324)
			(xy 125.598031 -229.331416) (xy 125.557528 -229.359372) (xy 125.513066 -229.38047) (xy 125.465795 -229.394162)
			(xy 125.41694 -229.400094) (xy 125.367765 -229.398113) (xy 125.319546 -229.388269) (xy 125.27353 -229.370817)
			(xy 125.230909 -229.34621) (xy 125.192788 -229.315085) (xy 125.160153 -229.278248) (xy 125.13385 -229.236652)
			(xy 125.114559 -229.191376) (xy 125.102782 -229.143592) (xy 125.098822 -229.094538) (xy 124.770134 -229.094538)
			(xy 124.769639 -229.119145) (xy 124.761744 -229.167722) (xy 124.74616 -229.214403) (xy 124.723289 -229.25798)
			(xy 124.693724 -229.297324) (xy 124.658231 -229.331416) (xy 124.617728 -229.359372) (xy 124.573266 -229.38047)
			(xy 124.525995 -229.394162) (xy 124.47714 -229.400094) (xy 124.427965 -229.398113) (xy 124.379746 -229.388269)
			(xy 124.33373 -229.370817) (xy 124.291109 -229.34621) (xy 124.252988 -229.315085) (xy 124.220353 -229.278248)
			(xy 124.19405 -229.236652) (xy 124.174759 -229.191376) (xy 124.162982 -229.143592) (xy 124.159022 -229.094538)
			(xy 123.83008 -229.094538) (xy 123.829585 -229.119145) (xy 123.82169 -229.167722) (xy 123.806106 -229.214403)
			(xy 123.783235 -229.25798) (xy 123.75367 -229.297324) (xy 123.718177 -229.331416) (xy 123.677674 -229.359372)
			(xy 123.633212 -229.38047) (xy 123.585941 -229.394162) (xy 123.537086 -229.400094) (xy 123.487911 -229.398113)
			(xy 123.439692 -229.388269) (xy 123.393676 -229.370817) (xy 123.351055 -229.34621) (xy 123.312934 -229.315085)
			(xy 123.280299 -229.278248) (xy 123.253996 -229.236652) (xy 123.234705 -229.191376) (xy 123.222928 -229.143592)
			(xy 123.218968 -229.094538) (xy 122.890026 -229.094538) (xy 122.889531 -229.119145) (xy 122.881636 -229.167722)
			(xy 122.866052 -229.214403) (xy 122.843181 -229.25798) (xy 122.813616 -229.297324) (xy 122.778123 -229.331416)
			(xy 122.73762 -229.359372) (xy 122.693158 -229.38047) (xy 122.645887 -229.394162) (xy 122.597032 -229.400094)
			(xy 122.547857 -229.398113) (xy 122.499638 -229.388269) (xy 122.453622 -229.370817) (xy 122.411001 -229.34621)
			(xy 122.37288 -229.315085) (xy 122.340245 -229.278248) (xy 122.313942 -229.236652) (xy 122.294651 -229.191376)
			(xy 122.282874 -229.143592) (xy 122.278914 -229.094538) (xy 121.949972 -229.094538) (xy 121.949477 -229.119145)
			(xy 121.941582 -229.167722) (xy 121.925998 -229.214403) (xy 121.903127 -229.25798) (xy 121.873562 -229.297324)
			(xy 121.838069 -229.331416) (xy 121.797566 -229.359372) (xy 121.753104 -229.38047) (xy 121.705833 -229.394162)
			(xy 121.656978 -229.400094) (xy 121.607803 -229.398113) (xy 121.559584 -229.388269) (xy 121.513568 -229.370817)
			(xy 121.470947 -229.34621) (xy 121.432826 -229.315085) (xy 121.400191 -229.278248) (xy 121.373888 -229.236652)
			(xy 121.354597 -229.191376) (xy 121.34282 -229.143592) (xy 121.33886 -229.094538) (xy 121.009918 -229.094538)
			(xy 121.009423 -229.119145) (xy 121.001528 -229.167722) (xy 120.985944 -229.214403) (xy 120.963073 -229.25798)
			(xy 120.933508 -229.297324) (xy 120.898015 -229.331416) (xy 120.857512 -229.359372) (xy 120.81305 -229.38047)
			(xy 120.765779 -229.394162) (xy 120.716924 -229.400094) (xy 120.667749 -229.398113) (xy 120.61953 -229.388269)
			(xy 120.573514 -229.370817) (xy 120.530893 -229.34621) (xy 120.492772 -229.315085) (xy 120.460137 -229.278248)
			(xy 120.433834 -229.236652) (xy 120.414543 -229.191376) (xy 120.402766 -229.143592) (xy 120.398806 -229.094538)
			(xy 120.070118 -229.094538) (xy 120.069623 -229.119145) (xy 120.061728 -229.167722) (xy 120.046144 -229.214403)
			(xy 120.023273 -229.25798) (xy 119.993708 -229.297324) (xy 119.958215 -229.331416) (xy 119.917712 -229.359372)
			(xy 119.87325 -229.38047) (xy 119.825979 -229.394162) (xy 119.777124 -229.400094) (xy 119.727949 -229.398113)
			(xy 119.67973 -229.388269) (xy 119.633714 -229.370817) (xy 119.591093 -229.34621) (xy 119.552972 -229.315085)
			(xy 119.520337 -229.278248) (xy 119.494034 -229.236652) (xy 119.474743 -229.191376) (xy 119.462966 -229.143592)
			(xy 119.459006 -229.094538) (xy 119.130064 -229.094538) (xy 119.129569 -229.119145) (xy 119.121674 -229.167722)
			(xy 119.10609 -229.214403) (xy 119.083219 -229.25798) (xy 119.053654 -229.297324) (xy 119.018161 -229.331416)
			(xy 118.977658 -229.359372) (xy 118.933196 -229.38047) (xy 118.885925 -229.394162) (xy 118.83707 -229.400094)
			(xy 118.787895 -229.398113) (xy 118.739676 -229.388269) (xy 118.69366 -229.370817) (xy 118.651039 -229.34621)
			(xy 118.612918 -229.315085) (xy 118.580283 -229.278248) (xy 118.55398 -229.236652) (xy 118.534689 -229.191376)
			(xy 118.522912 -229.143592) (xy 118.518952 -229.094538) (xy 118.19001 -229.094538) (xy 118.189515 -229.119145)
			(xy 118.18162 -229.167722) (xy 118.166036 -229.214403) (xy 118.143165 -229.25798) (xy 118.1136 -229.297324)
			(xy 118.078107 -229.331416) (xy 118.037604 -229.359372) (xy 117.993142 -229.38047) (xy 117.945871 -229.394162)
			(xy 117.897016 -229.400094) (xy 117.847841 -229.398113) (xy 117.799622 -229.388269) (xy 117.753606 -229.370817)
			(xy 117.710985 -229.34621) (xy 117.672864 -229.315085) (xy 117.640229 -229.278248) (xy 117.613926 -229.236652)
			(xy 117.594635 -229.191376) (xy 117.582858 -229.143592) (xy 117.578898 -229.094538) (xy 117.249956 -229.094538)
			(xy 117.249461 -229.119145) (xy 117.241566 -229.167722) (xy 117.225982 -229.214403) (xy 117.203111 -229.25798)
			(xy 117.173546 -229.297324) (xy 117.138053 -229.331416) (xy 117.09755 -229.359372) (xy 117.053088 -229.38047)
			(xy 117.005817 -229.394162) (xy 116.956962 -229.400094) (xy 116.907787 -229.398113) (xy 116.859568 -229.388269)
			(xy 116.813552 -229.370817) (xy 116.770931 -229.34621) (xy 116.73281 -229.315085) (xy 116.700175 -229.278248)
			(xy 116.673872 -229.236652) (xy 116.654581 -229.191376) (xy 116.642804 -229.143592) (xy 116.638844 -229.094538)
			(xy 116.310156 -229.094538) (xy 116.309661 -229.119145) (xy 116.301766 -229.167722) (xy 116.286182 -229.214403)
			(xy 116.263311 -229.25798) (xy 116.233746 -229.297324) (xy 116.198253 -229.331416) (xy 116.15775 -229.359372)
			(xy 116.113288 -229.38047) (xy 116.066017 -229.394162) (xy 116.017162 -229.400094) (xy 115.967987 -229.398113)
			(xy 115.919768 -229.388269) (xy 115.873752 -229.370817) (xy 115.831131 -229.34621) (xy 115.79301 -229.315085)
			(xy 115.760375 -229.278248) (xy 115.734072 -229.236652) (xy 115.714781 -229.191376) (xy 115.703004 -229.143592)
			(xy 115.699044 -229.094538) (xy 115.370102 -229.094538) (xy 115.369607 -229.119145) (xy 115.361712 -229.167722)
			(xy 115.346128 -229.214403) (xy 115.323257 -229.25798) (xy 115.293692 -229.297324) (xy 115.258199 -229.331416)
			(xy 115.217696 -229.359372) (xy 115.173234 -229.38047) (xy 115.125963 -229.394162) (xy 115.077108 -229.400094)
			(xy 115.027933 -229.398113) (xy 114.979714 -229.388269) (xy 114.933698 -229.370817) (xy 114.891077 -229.34621)
			(xy 114.852956 -229.315085) (xy 114.820321 -229.278248) (xy 114.794018 -229.236652) (xy 114.774727 -229.191376)
			(xy 114.76295 -229.143592) (xy 114.75899 -229.094538) (xy 114.430048 -229.094538) (xy 114.429553 -229.119145)
			(xy 114.421658 -229.167722) (xy 114.406074 -229.214403) (xy 114.383203 -229.25798) (xy 114.353638 -229.297324)
			(xy 114.318145 -229.331416) (xy 114.277642 -229.359372) (xy 114.23318 -229.38047) (xy 114.185909 -229.394162)
			(xy 114.137054 -229.400094) (xy 114.087879 -229.398113) (xy 114.03966 -229.388269) (xy 113.993644 -229.370817)
			(xy 113.951023 -229.34621) (xy 113.912902 -229.315085) (xy 113.880267 -229.278248) (xy 113.853964 -229.236652)
			(xy 113.834673 -229.191376) (xy 113.822896 -229.143592) (xy 113.818936 -229.094538) (xy 113.489994 -229.094538)
			(xy 113.489499 -229.119145) (xy 113.481604 -229.167722) (xy 113.46602 -229.214403) (xy 113.443149 -229.25798)
			(xy 113.413584 -229.297324) (xy 113.378091 -229.331416) (xy 113.337588 -229.359372) (xy 113.293126 -229.38047)
			(xy 113.245855 -229.394162) (xy 113.197 -229.400094) (xy 113.147825 -229.398113) (xy 113.099606 -229.388269)
			(xy 113.05359 -229.370817) (xy 113.010969 -229.34621) (xy 112.972848 -229.315085) (xy 112.940213 -229.278248)
			(xy 112.91391 -229.236652) (xy 112.894619 -229.191376) (xy 112.882842 -229.143592) (xy 112.878882 -229.094538)
			(xy 112.28832 -229.094538) (xy 112.28832 -229.218998) (xy 112.287898 -229.229069) (xy 112.280186 -229.247676)
			(xy 112.273334 -229.255066) (xy 111.62411 -229.90429) (xy 113.349036 -229.90429) (xy 113.352996 -229.855236)
			(xy 113.364773 -229.807452) (xy 113.384064 -229.762176) (xy 113.410367 -229.72058) (xy 113.443002 -229.683743)
			(xy 113.481123 -229.652618) (xy 113.523744 -229.628011) (xy 113.56976 -229.610559) (xy 113.617979 -229.600715)
			(xy 113.667154 -229.598734) (xy 113.716009 -229.604666) (xy 113.76328 -229.618358) (xy 113.807742 -229.639456)
			(xy 113.848245 -229.667412) (xy 113.883738 -229.701504) (xy 113.913303 -229.740848) (xy 113.936174 -229.784425)
			(xy 113.951758 -229.831106) (xy 113.959653 -229.879683) (xy 113.960148 -229.90429) (xy 114.288836 -229.90429)
			(xy 114.292796 -229.855236) (xy 114.304573 -229.807452) (xy 114.323864 -229.762176) (xy 114.350167 -229.72058)
			(xy 114.382802 -229.683743) (xy 114.420923 -229.652618) (xy 114.463544 -229.628011) (xy 114.50956 -229.610559)
			(xy 114.557779 -229.600715) (xy 114.606954 -229.598734) (xy 114.655809 -229.604666) (xy 114.70308 -229.618358)
			(xy 114.747542 -229.639456) (xy 114.788045 -229.667412) (xy 114.823538 -229.701504) (xy 114.853103 -229.740848)
			(xy 114.875974 -229.784425) (xy 114.891558 -229.831106) (xy 114.899453 -229.879683) (xy 114.899948 -229.90429)
			(xy 115.22889 -229.90429) (xy 115.23285 -229.855236) (xy 115.244627 -229.807452) (xy 115.263918 -229.762176)
			(xy 115.290221 -229.72058) (xy 115.322856 -229.683743) (xy 115.360977 -229.652618) (xy 115.403598 -229.628011)
			(xy 115.449614 -229.610559) (xy 115.497833 -229.600715) (xy 115.547008 -229.598734) (xy 115.595863 -229.604666)
			(xy 115.643134 -229.618358) (xy 115.687596 -229.639456) (xy 115.728099 -229.667412) (xy 115.763592 -229.701504)
			(xy 115.793157 -229.740848) (xy 115.816028 -229.784425) (xy 115.831612 -229.831106) (xy 115.839507 -229.879683)
			(xy 115.840002 -229.90429) (xy 116.168944 -229.90429) (xy 116.172904 -229.855236) (xy 116.184681 -229.807452)
			(xy 116.203972 -229.762176) (xy 116.230275 -229.72058) (xy 116.26291 -229.683743) (xy 116.301031 -229.652618)
			(xy 116.343652 -229.628011) (xy 116.389668 -229.610559) (xy 116.437887 -229.600715) (xy 116.487062 -229.598734)
			(xy 116.535917 -229.604666) (xy 116.583188 -229.618358) (xy 116.62765 -229.639456) (xy 116.668153 -229.667412)
			(xy 116.703646 -229.701504) (xy 116.733211 -229.740848) (xy 116.756082 -229.784425) (xy 116.771666 -229.831106)
			(xy 116.779561 -229.879683) (xy 116.780056 -229.90429) (xy 117.108998 -229.90429) (xy 117.112958 -229.855236)
			(xy 117.124735 -229.807452) (xy 117.144026 -229.762176) (xy 117.170329 -229.72058) (xy 117.202964 -229.683743)
			(xy 117.241085 -229.652618) (xy 117.283706 -229.628011) (xy 117.329722 -229.610559) (xy 117.377941 -229.600715)
			(xy 117.427116 -229.598734) (xy 117.475971 -229.604666) (xy 117.523242 -229.618358) (xy 117.567704 -229.639456)
			(xy 117.608207 -229.667412) (xy 117.6437 -229.701504) (xy 117.673265 -229.740848) (xy 117.696136 -229.784425)
			(xy 117.71172 -229.831106) (xy 117.719615 -229.879683) (xy 117.72011 -229.90429) (xy 118.049052 -229.90429)
			(xy 118.053012 -229.855236) (xy 118.064789 -229.807452) (xy 118.08408 -229.762176) (xy 118.110383 -229.72058)
			(xy 118.143018 -229.683743) (xy 118.181139 -229.652618) (xy 118.22376 -229.628011) (xy 118.269776 -229.610559)
			(xy 118.317995 -229.600715) (xy 118.36717 -229.598734) (xy 118.416025 -229.604666) (xy 118.463296 -229.618358)
			(xy 118.507758 -229.639456) (xy 118.548261 -229.667412) (xy 118.583754 -229.701504) (xy 118.613319 -229.740848)
			(xy 118.63619 -229.784425) (xy 118.651774 -229.831106) (xy 118.659669 -229.879683) (xy 118.660164 -229.90429)
			(xy 118.988852 -229.90429) (xy 118.992812 -229.855236) (xy 119.004589 -229.807452) (xy 119.02388 -229.762176)
			(xy 119.050183 -229.72058) (xy 119.082818 -229.683743) (xy 119.120939 -229.652618) (xy 119.16356 -229.628011)
			(xy 119.209576 -229.610559) (xy 119.257795 -229.600715) (xy 119.30697 -229.598734) (xy 119.355825 -229.604666)
			(xy 119.403096 -229.618358) (xy 119.447558 -229.639456) (xy 119.488061 -229.667412) (xy 119.523554 -229.701504)
			(xy 119.553119 -229.740848) (xy 119.57599 -229.784425) (xy 119.591574 -229.831106) (xy 119.599469 -229.879683)
			(xy 119.599964 -229.90429) (xy 119.928906 -229.90429) (xy 119.932866 -229.855236) (xy 119.944643 -229.807452)
			(xy 119.963934 -229.762176) (xy 119.990237 -229.72058) (xy 120.022872 -229.683743) (xy 120.060993 -229.652618)
			(xy 120.103614 -229.628011) (xy 120.14963 -229.610559) (xy 120.197849 -229.600715) (xy 120.247024 -229.598734)
			(xy 120.295879 -229.604666) (xy 120.34315 -229.618358) (xy 120.387612 -229.639456) (xy 120.428115 -229.667412)
			(xy 120.463608 -229.701504) (xy 120.493173 -229.740848) (xy 120.516044 -229.784425) (xy 120.531628 -229.831106)
			(xy 120.539523 -229.879683) (xy 120.540018 -229.90429) (xy 120.86896 -229.90429) (xy 120.87292 -229.855236)
			(xy 120.884697 -229.807452) (xy 120.903988 -229.762176) (xy 120.930291 -229.72058) (xy 120.962926 -229.683743)
			(xy 121.001047 -229.652618) (xy 121.043668 -229.628011) (xy 121.089684 -229.610559) (xy 121.137903 -229.600715)
			(xy 121.187078 -229.598734) (xy 121.235933 -229.604666) (xy 121.283204 -229.618358) (xy 121.327666 -229.639456)
			(xy 121.368169 -229.667412) (xy 121.403662 -229.701504) (xy 121.433227 -229.740848) (xy 121.456098 -229.784425)
			(xy 121.471682 -229.831106) (xy 121.479577 -229.879683) (xy 121.480072 -229.90429) (xy 121.809014 -229.90429)
			(xy 121.812974 -229.855236) (xy 121.824751 -229.807452) (xy 121.844042 -229.762176) (xy 121.870345 -229.72058)
			(xy 121.90298 -229.683743) (xy 121.941101 -229.652618) (xy 121.983722 -229.628011) (xy 122.029738 -229.610559)
			(xy 122.077957 -229.600715) (xy 122.127132 -229.598734) (xy 122.175987 -229.604666) (xy 122.223258 -229.618358)
			(xy 122.26772 -229.639456) (xy 122.308223 -229.667412) (xy 122.343716 -229.701504) (xy 122.373281 -229.740848)
			(xy 122.396152 -229.784425) (xy 122.411736 -229.831106) (xy 122.419631 -229.879683) (xy 122.420126 -229.90429)
			(xy 122.748814 -229.90429) (xy 122.752774 -229.855236) (xy 122.764551 -229.807452) (xy 122.783842 -229.762176)
			(xy 122.810145 -229.72058) (xy 122.84278 -229.683743) (xy 122.880901 -229.652618) (xy 122.923522 -229.628011)
			(xy 122.969538 -229.610559) (xy 123.017757 -229.600715) (xy 123.066932 -229.598734) (xy 123.115787 -229.604666)
			(xy 123.163058 -229.618358) (xy 123.20752 -229.639456) (xy 123.248023 -229.667412) (xy 123.283516 -229.701504)
			(xy 123.313081 -229.740848) (xy 123.335952 -229.784425) (xy 123.351536 -229.831106) (xy 123.359431 -229.879683)
			(xy 123.359926 -229.90429) (xy 123.688868 -229.90429) (xy 123.692828 -229.855236) (xy 123.704605 -229.807452)
			(xy 123.723896 -229.762176) (xy 123.750199 -229.72058) (xy 123.782834 -229.683743) (xy 123.820955 -229.652618)
			(xy 123.863576 -229.628011) (xy 123.909592 -229.610559) (xy 123.957811 -229.600715) (xy 124.006986 -229.598734)
			(xy 124.055841 -229.604666) (xy 124.103112 -229.618358) (xy 124.147574 -229.639456) (xy 124.188077 -229.667412)
			(xy 124.22357 -229.701504) (xy 124.253135 -229.740848) (xy 124.276006 -229.784425) (xy 124.29159 -229.831106)
			(xy 124.299485 -229.879683) (xy 124.29998 -229.90429) (xy 124.628922 -229.90429) (xy 124.632882 -229.855236)
			(xy 124.644659 -229.807452) (xy 124.66395 -229.762176) (xy 124.690253 -229.72058) (xy 124.722888 -229.683743)
			(xy 124.761009 -229.652618) (xy 124.80363 -229.628011) (xy 124.849646 -229.610559) (xy 124.897865 -229.600715)
			(xy 124.94704 -229.598734) (xy 124.995895 -229.604666) (xy 125.043166 -229.618358) (xy 125.087628 -229.639456)
			(xy 125.128131 -229.667412) (xy 125.163624 -229.701504) (xy 125.193189 -229.740848) (xy 125.21606 -229.784425)
			(xy 125.231644 -229.831106) (xy 125.239539 -229.879683) (xy 125.240034 -229.90429) (xy 125.568976 -229.90429)
			(xy 125.572936 -229.855236) (xy 125.584713 -229.807452) (xy 125.604004 -229.762176) (xy 125.630307 -229.72058)
			(xy 125.662942 -229.683743) (xy 125.701063 -229.652618) (xy 125.743684 -229.628011) (xy 125.7897 -229.610559)
			(xy 125.837919 -229.600715) (xy 125.887094 -229.598734) (xy 125.935949 -229.604666) (xy 125.98322 -229.618358)
			(xy 126.027682 -229.639456) (xy 126.068185 -229.667412) (xy 126.103678 -229.701504) (xy 126.133243 -229.740848)
			(xy 126.156114 -229.784425) (xy 126.171698 -229.831106) (xy 126.179593 -229.879683) (xy 126.180088 -229.90429)
			(xy 126.179593 -229.928897) (xy 126.171698 -229.977474) (xy 126.156114 -230.024155) (xy 126.133243 -230.067732)
			(xy 126.103678 -230.107076) (xy 126.068185 -230.141168) (xy 126.027682 -230.169124) (xy 125.98322 -230.190222)
			(xy 125.935949 -230.203914) (xy 125.887094 -230.209846) (xy 125.837919 -230.207865) (xy 125.7897 -230.198021)
			(xy 125.743684 -230.180569) (xy 125.701063 -230.155962) (xy 125.662942 -230.124837) (xy 125.630307 -230.088)
			(xy 125.604004 -230.046404) (xy 125.584713 -230.001128) (xy 125.572936 -229.953344) (xy 125.568976 -229.90429)
			(xy 125.240034 -229.90429) (xy 125.239539 -229.928897) (xy 125.231644 -229.977474) (xy 125.21606 -230.024155)
			(xy 125.193189 -230.067732) (xy 125.163624 -230.107076) (xy 125.128131 -230.141168) (xy 125.087628 -230.169124)
			(xy 125.043166 -230.190222) (xy 124.995895 -230.203914) (xy 124.94704 -230.209846) (xy 124.897865 -230.207865)
			(xy 124.849646 -230.198021) (xy 124.80363 -230.180569) (xy 124.761009 -230.155962) (xy 124.722888 -230.124837)
			(xy 124.690253 -230.088) (xy 124.66395 -230.046404) (xy 124.644659 -230.001128) (xy 124.632882 -229.953344)
			(xy 124.628922 -229.90429) (xy 124.29998 -229.90429) (xy 124.299485 -229.928897) (xy 124.29159 -229.977474)
			(xy 124.276006 -230.024155) (xy 124.253135 -230.067732) (xy 124.22357 -230.107076) (xy 124.188077 -230.141168)
			(xy 124.147574 -230.169124) (xy 124.103112 -230.190222) (xy 124.055841 -230.203914) (xy 124.006986 -230.209846)
			(xy 123.957811 -230.207865) (xy 123.909592 -230.198021) (xy 123.863576 -230.180569) (xy 123.820955 -230.155962)
			(xy 123.782834 -230.124837) (xy 123.750199 -230.088) (xy 123.723896 -230.046404) (xy 123.704605 -230.001128)
			(xy 123.692828 -229.953344) (xy 123.688868 -229.90429) (xy 123.359926 -229.90429) (xy 123.359431 -229.928897)
			(xy 123.351536 -229.977474) (xy 123.335952 -230.024155) (xy 123.313081 -230.067732) (xy 123.283516 -230.107076)
			(xy 123.248023 -230.141168) (xy 123.20752 -230.169124) (xy 123.163058 -230.190222) (xy 123.115787 -230.203914)
			(xy 123.066932 -230.209846) (xy 123.017757 -230.207865) (xy 122.969538 -230.198021) (xy 122.923522 -230.180569)
			(xy 122.880901 -230.155962) (xy 122.84278 -230.124837) (xy 122.810145 -230.088) (xy 122.783842 -230.046404)
			(xy 122.764551 -230.001128) (xy 122.752774 -229.953344) (xy 122.748814 -229.90429) (xy 122.420126 -229.90429)
			(xy 122.419631 -229.928897) (xy 122.411736 -229.977474) (xy 122.396152 -230.024155) (xy 122.373281 -230.067732)
			(xy 122.343716 -230.107076) (xy 122.308223 -230.141168) (xy 122.26772 -230.169124) (xy 122.223258 -230.190222)
			(xy 122.175987 -230.203914) (xy 122.127132 -230.209846) (xy 122.077957 -230.207865) (xy 122.029738 -230.198021)
			(xy 121.983722 -230.180569) (xy 121.941101 -230.155962) (xy 121.90298 -230.124837) (xy 121.870345 -230.088)
			(xy 121.844042 -230.046404) (xy 121.824751 -230.001128) (xy 121.812974 -229.953344) (xy 121.809014 -229.90429)
			(xy 121.480072 -229.90429) (xy 121.479577 -229.928897) (xy 121.471682 -229.977474) (xy 121.456098 -230.024155)
			(xy 121.433227 -230.067732) (xy 121.403662 -230.107076) (xy 121.368169 -230.141168) (xy 121.327666 -230.169124)
			(xy 121.283204 -230.190222) (xy 121.235933 -230.203914) (xy 121.187078 -230.209846) (xy 121.137903 -230.207865)
			(xy 121.089684 -230.198021) (xy 121.043668 -230.180569) (xy 121.001047 -230.155962) (xy 120.962926 -230.124837)
			(xy 120.930291 -230.088) (xy 120.903988 -230.046404) (xy 120.884697 -230.001128) (xy 120.87292 -229.953344)
			(xy 120.86896 -229.90429) (xy 120.540018 -229.90429) (xy 120.539523 -229.928897) (xy 120.531628 -229.977474)
			(xy 120.516044 -230.024155) (xy 120.493173 -230.067732) (xy 120.463608 -230.107076) (xy 120.428115 -230.141168)
			(xy 120.387612 -230.169124) (xy 120.34315 -230.190222) (xy 120.295879 -230.203914) (xy 120.247024 -230.209846)
			(xy 120.197849 -230.207865) (xy 120.14963 -230.198021) (xy 120.103614 -230.180569) (xy 120.060993 -230.155962)
			(xy 120.022872 -230.124837) (xy 119.990237 -230.088) (xy 119.963934 -230.046404) (xy 119.944643 -230.001128)
			(xy 119.932866 -229.953344) (xy 119.928906 -229.90429) (xy 119.599964 -229.90429) (xy 119.599469 -229.928897)
			(xy 119.591574 -229.977474) (xy 119.57599 -230.024155) (xy 119.553119 -230.067732) (xy 119.523554 -230.107076)
			(xy 119.488061 -230.141168) (xy 119.447558 -230.169124) (xy 119.403096 -230.190222) (xy 119.355825 -230.203914)
			(xy 119.30697 -230.209846) (xy 119.257795 -230.207865) (xy 119.209576 -230.198021) (xy 119.16356 -230.180569)
			(xy 119.120939 -230.155962) (xy 119.082818 -230.124837) (xy 119.050183 -230.088) (xy 119.02388 -230.046404)
			(xy 119.004589 -230.001128) (xy 118.992812 -229.953344) (xy 118.988852 -229.90429) (xy 118.660164 -229.90429)
			(xy 118.659669 -229.928897) (xy 118.651774 -229.977474) (xy 118.63619 -230.024155) (xy 118.613319 -230.067732)
			(xy 118.583754 -230.107076) (xy 118.548261 -230.141168) (xy 118.507758 -230.169124) (xy 118.463296 -230.190222)
			(xy 118.416025 -230.203914) (xy 118.36717 -230.209846) (xy 118.317995 -230.207865) (xy 118.269776 -230.198021)
			(xy 118.22376 -230.180569) (xy 118.181139 -230.155962) (xy 118.143018 -230.124837) (xy 118.110383 -230.088)
			(xy 118.08408 -230.046404) (xy 118.064789 -230.001128) (xy 118.053012 -229.953344) (xy 118.049052 -229.90429)
			(xy 117.72011 -229.90429) (xy 117.719615 -229.928897) (xy 117.71172 -229.977474) (xy 117.696136 -230.024155)
			(xy 117.673265 -230.067732) (xy 117.6437 -230.107076) (xy 117.608207 -230.141168) (xy 117.567704 -230.169124)
			(xy 117.523242 -230.190222) (xy 117.475971 -230.203914) (xy 117.427116 -230.209846) (xy 117.377941 -230.207865)
			(xy 117.329722 -230.198021) (xy 117.283706 -230.180569) (xy 117.241085 -230.155962) (xy 117.202964 -230.124837)
			(xy 117.170329 -230.088) (xy 117.144026 -230.046404) (xy 117.124735 -230.001128) (xy 117.112958 -229.953344)
			(xy 117.108998 -229.90429) (xy 116.780056 -229.90429) (xy 116.779561 -229.928897) (xy 116.771666 -229.977474)
			(xy 116.756082 -230.024155) (xy 116.733211 -230.067732) (xy 116.703646 -230.107076) (xy 116.668153 -230.141168)
			(xy 116.62765 -230.169124) (xy 116.583188 -230.190222) (xy 116.535917 -230.203914) (xy 116.487062 -230.209846)
			(xy 116.437887 -230.207865) (xy 116.389668 -230.198021) (xy 116.343652 -230.180569) (xy 116.301031 -230.155962)
			(xy 116.26291 -230.124837) (xy 116.230275 -230.088) (xy 116.203972 -230.046404) (xy 116.184681 -230.001128)
			(xy 116.172904 -229.953344) (xy 116.168944 -229.90429) (xy 115.840002 -229.90429) (xy 115.839507 -229.928897)
			(xy 115.831612 -229.977474) (xy 115.816028 -230.024155) (xy 115.793157 -230.067732) (xy 115.763592 -230.107076)
			(xy 115.728099 -230.141168) (xy 115.687596 -230.169124) (xy 115.643134 -230.190222) (xy 115.595863 -230.203914)
			(xy 115.547008 -230.209846) (xy 115.497833 -230.207865) (xy 115.449614 -230.198021) (xy 115.403598 -230.180569)
			(xy 115.360977 -230.155962) (xy 115.322856 -230.124837) (xy 115.290221 -230.088) (xy 115.263918 -230.046404)
			(xy 115.244627 -230.001128) (xy 115.23285 -229.953344) (xy 115.22889 -229.90429) (xy 114.899948 -229.90429)
			(xy 114.899453 -229.928897) (xy 114.891558 -229.977474) (xy 114.875974 -230.024155) (xy 114.853103 -230.067732)
			(xy 114.823538 -230.107076) (xy 114.788045 -230.141168) (xy 114.747542 -230.169124) (xy 114.70308 -230.190222)
			(xy 114.655809 -230.203914) (xy 114.606954 -230.209846) (xy 114.557779 -230.207865) (xy 114.50956 -230.198021)
			(xy 114.463544 -230.180569) (xy 114.420923 -230.155962) (xy 114.382802 -230.124837) (xy 114.350167 -230.088)
			(xy 114.323864 -230.046404) (xy 114.304573 -230.001128) (xy 114.292796 -229.953344) (xy 114.288836 -229.90429)
			(xy 113.960148 -229.90429) (xy 113.959653 -229.928897) (xy 113.951758 -229.977474) (xy 113.936174 -230.024155)
			(xy 113.913303 -230.067732) (xy 113.883738 -230.107076) (xy 113.848245 -230.141168) (xy 113.807742 -230.169124)
			(xy 113.76328 -230.190222) (xy 113.716009 -230.203914) (xy 113.667154 -230.209846) (xy 113.617979 -230.207865)
			(xy 113.56976 -230.198021) (xy 113.523744 -230.180569) (xy 113.481123 -230.155962) (xy 113.443002 -230.124837)
			(xy 113.410367 -230.088) (xy 113.384064 -230.046404) (xy 113.364773 -230.001128) (xy 113.352996 -229.953344)
			(xy 113.349036 -229.90429) (xy 111.62411 -229.90429) (xy 110.81385 -230.71455) (xy 112.878882 -230.71455)
			(xy 112.882842 -230.665496) (xy 112.894619 -230.617712) (xy 112.91391 -230.572436) (xy 112.940213 -230.53084)
			(xy 112.972848 -230.494003) (xy 113.010969 -230.462878) (xy 113.05359 -230.438271) (xy 113.099606 -230.420819)
			(xy 113.147825 -230.410975) (xy 113.197 -230.408994) (xy 113.245855 -230.414926) (xy 113.293126 -230.428618)
			(xy 113.337588 -230.449716) (xy 113.378091 -230.477672) (xy 113.413584 -230.511764) (xy 113.443149 -230.551108)
			(xy 113.46602 -230.594685) (xy 113.481604 -230.641366) (xy 113.489499 -230.689943) (xy 113.489994 -230.71455)
			(xy 113.818936 -230.71455) (xy 113.822896 -230.665496) (xy 113.834673 -230.617712) (xy 113.853964 -230.572436)
			(xy 113.880267 -230.53084) (xy 113.912902 -230.494003) (xy 113.951023 -230.462878) (xy 113.993644 -230.438271)
			(xy 114.03966 -230.420819) (xy 114.087879 -230.410975) (xy 114.137054 -230.408994) (xy 114.185909 -230.414926)
			(xy 114.23318 -230.428618) (xy 114.277642 -230.449716) (xy 114.318145 -230.477672) (xy 114.353638 -230.511764)
			(xy 114.383203 -230.551108) (xy 114.406074 -230.594685) (xy 114.421658 -230.641366) (xy 114.429553 -230.689943)
			(xy 114.430048 -230.71455) (xy 114.75899 -230.71455) (xy 114.76295 -230.665496) (xy 114.774727 -230.617712)
			(xy 114.794018 -230.572436) (xy 114.820321 -230.53084) (xy 114.852956 -230.494003) (xy 114.891077 -230.462878)
			(xy 114.933698 -230.438271) (xy 114.979714 -230.420819) (xy 115.027933 -230.410975) (xy 115.077108 -230.408994)
			(xy 115.125963 -230.414926) (xy 115.173234 -230.428618) (xy 115.217696 -230.449716) (xy 115.258199 -230.477672)
			(xy 115.293692 -230.511764) (xy 115.323257 -230.551108) (xy 115.346128 -230.594685) (xy 115.361712 -230.641366)
			(xy 115.369607 -230.689943) (xy 115.370102 -230.71455) (xy 115.699044 -230.71455) (xy 115.703004 -230.665496)
			(xy 115.714781 -230.617712) (xy 115.734072 -230.572436) (xy 115.760375 -230.53084) (xy 115.79301 -230.494003)
			(xy 115.831131 -230.462878) (xy 115.873752 -230.438271) (xy 115.919768 -230.420819) (xy 115.967987 -230.410975)
			(xy 116.017162 -230.408994) (xy 116.066017 -230.414926) (xy 116.113288 -230.428618) (xy 116.15775 -230.449716)
			(xy 116.198253 -230.477672) (xy 116.233746 -230.511764) (xy 116.263311 -230.551108) (xy 116.286182 -230.594685)
			(xy 116.301766 -230.641366) (xy 116.309661 -230.689943) (xy 116.310156 -230.71455) (xy 118.518952 -230.71455)
			(xy 118.522912 -230.665496) (xy 118.534689 -230.617712) (xy 118.55398 -230.572436) (xy 118.580283 -230.53084)
			(xy 118.612918 -230.494003) (xy 118.651039 -230.462878) (xy 118.69366 -230.438271) (xy 118.739676 -230.420819)
			(xy 118.787895 -230.410975) (xy 118.83707 -230.408994) (xy 118.885925 -230.414926) (xy 118.933196 -230.428618)
			(xy 118.977658 -230.449716) (xy 119.018161 -230.477672) (xy 119.053654 -230.511764) (xy 119.083219 -230.551108)
			(xy 119.10609 -230.594685) (xy 119.121674 -230.641366) (xy 119.129569 -230.689943) (xy 119.130064 -230.71455)
			(xy 121.33886 -230.71455) (xy 121.34282 -230.665496) (xy 121.354597 -230.617712) (xy 121.373888 -230.572436)
			(xy 121.400191 -230.53084) (xy 121.432826 -230.494003) (xy 121.470947 -230.462878) (xy 121.513568 -230.438271)
			(xy 121.559584 -230.420819) (xy 121.607803 -230.410975) (xy 121.656978 -230.408994) (xy 121.705833 -230.414926)
			(xy 121.753104 -230.428618) (xy 121.797566 -230.449716) (xy 121.838069 -230.477672) (xy 121.873562 -230.511764)
			(xy 121.903127 -230.551108) (xy 121.925998 -230.594685) (xy 121.941582 -230.641366) (xy 121.949477 -230.689943)
			(xy 121.949972 -230.71455) (xy 124.159022 -230.71455) (xy 124.162982 -230.665496) (xy 124.174759 -230.617712)
			(xy 124.19405 -230.572436) (xy 124.220353 -230.53084) (xy 124.252988 -230.494003) (xy 124.291109 -230.462878)
			(xy 124.33373 -230.438271) (xy 124.379746 -230.420819) (xy 124.427965 -230.410975) (xy 124.47714 -230.408994)
			(xy 124.525995 -230.414926) (xy 124.573266 -230.428618) (xy 124.617728 -230.449716) (xy 124.658231 -230.477672)
			(xy 124.693724 -230.511764) (xy 124.723289 -230.551108) (xy 124.74616 -230.594685) (xy 124.761744 -230.641366)
			(xy 124.769639 -230.689943) (xy 124.770134 -230.71455) (xy 124.769639 -230.739157) (xy 124.761744 -230.787734)
			(xy 124.74616 -230.834415) (xy 124.723289 -230.877992) (xy 124.693724 -230.917336) (xy 124.658231 -230.951428)
			(xy 124.617728 -230.979384) (xy 124.573266 -231.000482) (xy 124.525995 -231.014174) (xy 124.47714 -231.020106)
			(xy 124.427965 -231.018125) (xy 124.379746 -231.008281) (xy 124.33373 -230.990829) (xy 124.291109 -230.966222)
			(xy 124.252988 -230.935097) (xy 124.220353 -230.89826) (xy 124.19405 -230.856664) (xy 124.174759 -230.811388)
			(xy 124.162982 -230.763604) (xy 124.159022 -230.71455) (xy 121.949972 -230.71455) (xy 121.949477 -230.739157)
			(xy 121.941582 -230.787734) (xy 121.925998 -230.834415) (xy 121.903127 -230.877992) (xy 121.873562 -230.917336)
			(xy 121.838069 -230.951428) (xy 121.797566 -230.979384) (xy 121.753104 -231.000482) (xy 121.705833 -231.014174)
			(xy 121.656978 -231.020106) (xy 121.607803 -231.018125) (xy 121.559584 -231.008281) (xy 121.513568 -230.990829)
			(xy 121.470947 -230.966222) (xy 121.432826 -230.935097) (xy 121.400191 -230.89826) (xy 121.373888 -230.856664)
			(xy 121.354597 -230.811388) (xy 121.34282 -230.763604) (xy 121.33886 -230.71455) (xy 119.130064 -230.71455)
			(xy 119.129569 -230.739157) (xy 119.121674 -230.787734) (xy 119.10609 -230.834415) (xy 119.083219 -230.877992)
			(xy 119.053654 -230.917336) (xy 119.018161 -230.951428) (xy 118.977658 -230.979384) (xy 118.933196 -231.000482)
			(xy 118.885925 -231.014174) (xy 118.83707 -231.020106) (xy 118.787895 -231.018125) (xy 118.739676 -231.008281)
			(xy 118.69366 -230.990829) (xy 118.651039 -230.966222) (xy 118.612918 -230.935097) (xy 118.580283 -230.89826)
			(xy 118.55398 -230.856664) (xy 118.534689 -230.811388) (xy 118.522912 -230.763604) (xy 118.518952 -230.71455)
			(xy 116.310156 -230.71455) (xy 116.309661 -230.739157) (xy 116.301766 -230.787734) (xy 116.286182 -230.834415)
			(xy 116.263311 -230.877992) (xy 116.233746 -230.917336) (xy 116.198253 -230.951428) (xy 116.15775 -230.979384)
			(xy 116.113288 -231.000482) (xy 116.066017 -231.014174) (xy 116.017162 -231.020106) (xy 115.967987 -231.018125)
			(xy 115.919768 -231.008281) (xy 115.873752 -230.990829) (xy 115.831131 -230.966222) (xy 115.79301 -230.935097)
			(xy 115.760375 -230.89826) (xy 115.734072 -230.856664) (xy 115.714781 -230.811388) (xy 115.703004 -230.763604)
			(xy 115.699044 -230.71455) (xy 115.370102 -230.71455) (xy 115.369607 -230.739157) (xy 115.361712 -230.787734)
			(xy 115.346128 -230.834415) (xy 115.323257 -230.877992) (xy 115.293692 -230.917336) (xy 115.258199 -230.951428)
			(xy 115.217696 -230.979384) (xy 115.173234 -231.000482) (xy 115.125963 -231.014174) (xy 115.077108 -231.020106)
			(xy 115.027933 -231.018125) (xy 114.979714 -231.008281) (xy 114.933698 -230.990829) (xy 114.891077 -230.966222)
			(xy 114.852956 -230.935097) (xy 114.820321 -230.89826) (xy 114.794018 -230.856664) (xy 114.774727 -230.811388)
			(xy 114.76295 -230.763604) (xy 114.75899 -230.71455) (xy 114.430048 -230.71455) (xy 114.429553 -230.739157)
			(xy 114.421658 -230.787734) (xy 114.406074 -230.834415) (xy 114.383203 -230.877992) (xy 114.353638 -230.917336)
			(xy 114.318145 -230.951428) (xy 114.277642 -230.979384) (xy 114.23318 -231.000482) (xy 114.185909 -231.014174)
			(xy 114.137054 -231.020106) (xy 114.087879 -231.018125) (xy 114.03966 -231.008281) (xy 113.993644 -230.990829)
			(xy 113.951023 -230.966222) (xy 113.912902 -230.935097) (xy 113.880267 -230.89826) (xy 113.853964 -230.856664)
			(xy 113.834673 -230.811388) (xy 113.822896 -230.763604) (xy 113.818936 -230.71455) (xy 113.489994 -230.71455)
			(xy 113.489499 -230.739157) (xy 113.481604 -230.787734) (xy 113.46602 -230.834415) (xy 113.443149 -230.877992)
			(xy 113.413584 -230.917336) (xy 113.378091 -230.951428) (xy 113.337588 -230.979384) (xy 113.293126 -231.000482)
			(xy 113.245855 -231.014174) (xy 113.197 -231.020106) (xy 113.147825 -231.018125) (xy 113.099606 -231.008281)
			(xy 113.05359 -230.990829) (xy 113.010969 -230.966222) (xy 112.972848 -230.935097) (xy 112.940213 -230.89826)
			(xy 112.91391 -230.856664) (xy 112.894619 -230.811388) (xy 112.882842 -230.763604) (xy 112.878882 -230.71455)
			(xy 110.81385 -230.71455) (xy 110.217966 -231.310434) (xy 110.210569 -231.317282) (xy 110.19197 -231.325015)
			(xy 110.181898 -231.32542) (xy 109.914436 -231.32542) (xy 109.906401 -231.325787) (xy 109.891142 -231.330842)
			(xy 109.884464 -231.335326) (xy 109.851521 -231.358757) (xy 109.7816 -231.399341) (xy 109.707806 -231.432363)
			(xy 109.630954 -231.457458) (xy 109.551894 -231.47435) (xy 109.471497 -231.482853) (xy 109.431074 -231.483408)
			(xy 109.133132 -231.483408) (xy 109.09243 -231.482851) (xy 109.011487 -231.474201) (xy 108.971588 -231.466136)
			(xy 108.9663 -231.46514) (xy 108.95554 -231.46514) (xy 108.950252 -231.466136) (xy 108.910415 -231.474184)
			(xy 108.8296 -231.482838) (xy 108.788962 -231.483408) (xy 108.49102 -231.483408) (xy 108.476144 -231.483276)
			(xy 108.446417 -231.482004) (xy 108.431584 -231.480868) (xy 108.421932 -231.480106) (xy 108.403898 -231.485694)
			(xy 108.355594 -231.524302) (xy 115.22889 -231.524302) (xy 115.23285 -231.475248) (xy 115.244627 -231.427464)
			(xy 115.263918 -231.382188) (xy 115.290221 -231.340592) (xy 115.322856 -231.303755) (xy 115.360977 -231.27263)
			(xy 115.403598 -231.248023) (xy 115.449614 -231.230571) (xy 115.497833 -231.220727) (xy 115.547008 -231.218746)
			(xy 115.595863 -231.224678) (xy 115.643134 -231.23837) (xy 115.687596 -231.259468) (xy 115.728099 -231.287424)
			(xy 115.763592 -231.321516) (xy 115.793157 -231.36086) (xy 115.816028 -231.404437) (xy 115.831612 -231.451118)
			(xy 115.839507 -231.499695) (xy 115.840002 -231.524302) (xy 116.168944 -231.524302) (xy 116.172904 -231.475248)
			(xy 116.184681 -231.427464) (xy 116.203972 -231.382188) (xy 116.230275 -231.340592) (xy 116.26291 -231.303755)
			(xy 116.301031 -231.27263) (xy 116.343652 -231.248023) (xy 116.389668 -231.230571) (xy 116.437887 -231.220727)
			(xy 116.487062 -231.218746) (xy 116.535917 -231.224678) (xy 116.583188 -231.23837) (xy 116.62765 -231.259468)
			(xy 116.668153 -231.287424) (xy 116.703646 -231.321516) (xy 116.733211 -231.36086) (xy 116.756082 -231.404437)
			(xy 116.771666 -231.451118) (xy 116.779561 -231.499695) (xy 116.780056 -231.524302) (xy 117.108998 -231.524302)
			(xy 117.112958 -231.475248) (xy 117.124735 -231.427464) (xy 117.144026 -231.382188) (xy 117.170329 -231.340592)
			(xy 117.202964 -231.303755) (xy 117.241085 -231.27263) (xy 117.283706 -231.248023) (xy 117.329722 -231.230571)
			(xy 117.377941 -231.220727) (xy 117.427116 -231.218746) (xy 117.475971 -231.224678) (xy 117.523242 -231.23837)
			(xy 117.567704 -231.259468) (xy 117.608207 -231.287424) (xy 117.6437 -231.321516) (xy 117.673265 -231.36086)
			(xy 117.696136 -231.404437) (xy 117.71172 -231.451118) (xy 117.719615 -231.499695) (xy 117.72011 -231.524302)
			(xy 118.049052 -231.524302) (xy 118.053012 -231.475248) (xy 118.064789 -231.427464) (xy 118.08408 -231.382188)
			(xy 118.110383 -231.340592) (xy 118.143018 -231.303755) (xy 118.181139 -231.27263) (xy 118.22376 -231.248023)
			(xy 118.269776 -231.230571) (xy 118.317995 -231.220727) (xy 118.36717 -231.218746) (xy 118.416025 -231.224678)
			(xy 118.463296 -231.23837) (xy 118.507758 -231.259468) (xy 118.548261 -231.287424) (xy 118.583754 -231.321516)
			(xy 118.613319 -231.36086) (xy 118.63619 -231.404437) (xy 118.651774 -231.451118) (xy 118.659669 -231.499695)
			(xy 118.660164 -231.524302) (xy 118.988852 -231.524302) (xy 118.992812 -231.475248) (xy 119.004589 -231.427464)
			(xy 119.02388 -231.382188) (xy 119.050183 -231.340592) (xy 119.082818 -231.303755) (xy 119.120939 -231.27263)
			(xy 119.16356 -231.248023) (xy 119.209576 -231.230571) (xy 119.257795 -231.220727) (xy 119.30697 -231.218746)
			(xy 119.355825 -231.224678) (xy 119.403096 -231.23837) (xy 119.447558 -231.259468) (xy 119.488061 -231.287424)
			(xy 119.523554 -231.321516) (xy 119.553119 -231.36086) (xy 119.57599 -231.404437) (xy 119.591574 -231.451118)
			(xy 119.599469 -231.499695) (xy 119.599964 -231.524302) (xy 119.928906 -231.524302) (xy 119.932866 -231.475248)
			(xy 119.944643 -231.427464) (xy 119.963934 -231.382188) (xy 119.990237 -231.340592) (xy 120.022872 -231.303755)
			(xy 120.060993 -231.27263) (xy 120.103614 -231.248023) (xy 120.14963 -231.230571) (xy 120.197849 -231.220727)
			(xy 120.247024 -231.218746) (xy 120.295879 -231.224678) (xy 120.34315 -231.23837) (xy 120.387612 -231.259468)
			(xy 120.428115 -231.287424) (xy 120.463608 -231.321516) (xy 120.493173 -231.36086) (xy 120.516044 -231.404437)
			(xy 120.531628 -231.451118) (xy 120.539523 -231.499695) (xy 120.540018 -231.524302) (xy 120.86896 -231.524302)
			(xy 120.87292 -231.475248) (xy 120.884697 -231.427464) (xy 120.903988 -231.382188) (xy 120.930291 -231.340592)
			(xy 120.962926 -231.303755) (xy 121.001047 -231.27263) (xy 121.043668 -231.248023) (xy 121.089684 -231.230571)
			(xy 121.137903 -231.220727) (xy 121.187078 -231.218746) (xy 121.235933 -231.224678) (xy 121.283204 -231.23837)
			(xy 121.327666 -231.259468) (xy 121.368169 -231.287424) (xy 121.403662 -231.321516) (xy 121.433227 -231.36086)
			(xy 121.456098 -231.404437) (xy 121.471682 -231.451118) (xy 121.479577 -231.499695) (xy 121.480072 -231.524302)
			(xy 121.809014 -231.524302) (xy 121.812974 -231.475248) (xy 121.824751 -231.427464) (xy 121.844042 -231.382188)
			(xy 121.870345 -231.340592) (xy 121.90298 -231.303755) (xy 121.941101 -231.27263) (xy 121.983722 -231.248023)
			(xy 122.029738 -231.230571) (xy 122.077957 -231.220727) (xy 122.127132 -231.218746) (xy 122.175987 -231.224678)
			(xy 122.223258 -231.23837) (xy 122.26772 -231.259468) (xy 122.308223 -231.287424) (xy 122.343716 -231.321516)
			(xy 122.373281 -231.36086) (xy 122.396152 -231.404437) (xy 122.411736 -231.451118) (xy 122.419631 -231.499695)
			(xy 122.420126 -231.524302) (xy 122.748814 -231.524302) (xy 122.752774 -231.475248) (xy 122.764551 -231.427464)
			(xy 122.783842 -231.382188) (xy 122.810145 -231.340592) (xy 122.84278 -231.303755) (xy 122.880901 -231.27263)
			(xy 122.923522 -231.248023) (xy 122.969538 -231.230571) (xy 123.017757 -231.220727) (xy 123.066932 -231.218746)
			(xy 123.115787 -231.224678) (xy 123.163058 -231.23837) (xy 123.20752 -231.259468) (xy 123.248023 -231.287424)
			(xy 123.283516 -231.321516) (xy 123.313081 -231.36086) (xy 123.335952 -231.404437) (xy 123.351536 -231.451118)
			(xy 123.359431 -231.499695) (xy 123.359926 -231.524302) (xy 123.688868 -231.524302) (xy 123.692828 -231.475248)
			(xy 123.704605 -231.427464) (xy 123.723896 -231.382188) (xy 123.750199 -231.340592) (xy 123.782834 -231.303755)
			(xy 123.820955 -231.27263) (xy 123.863576 -231.248023) (xy 123.909592 -231.230571) (xy 123.957811 -231.220727)
			(xy 124.006986 -231.218746) (xy 124.055841 -231.224678) (xy 124.103112 -231.23837) (xy 124.147574 -231.259468)
			(xy 124.188077 -231.287424) (xy 124.22357 -231.321516) (xy 124.253135 -231.36086) (xy 124.276006 -231.404437)
			(xy 124.29159 -231.451118) (xy 124.299485 -231.499695) (xy 124.29998 -231.524302) (xy 124.628922 -231.524302)
			(xy 124.632882 -231.475248) (xy 124.644659 -231.427464) (xy 124.66395 -231.382188) (xy 124.690253 -231.340592)
			(xy 124.722888 -231.303755) (xy 124.761009 -231.27263) (xy 124.80363 -231.248023) (xy 124.849646 -231.230571)
			(xy 124.897865 -231.220727) (xy 124.94704 -231.218746) (xy 124.995895 -231.224678) (xy 125.043166 -231.23837)
			(xy 125.087628 -231.259468) (xy 125.128131 -231.287424) (xy 125.163624 -231.321516) (xy 125.193189 -231.36086)
			(xy 125.21606 -231.404437) (xy 125.231644 -231.451118) (xy 125.239539 -231.499695) (xy 125.240034 -231.524302)
			(xy 125.568976 -231.524302) (xy 125.572936 -231.475248) (xy 125.584713 -231.427464) (xy 125.604004 -231.382188)
			(xy 125.630307 -231.340592) (xy 125.662942 -231.303755) (xy 125.701063 -231.27263) (xy 125.743684 -231.248023)
			(xy 125.7897 -231.230571) (xy 125.837919 -231.220727) (xy 125.887094 -231.218746) (xy 125.935949 -231.224678)
			(xy 125.98322 -231.23837) (xy 126.027682 -231.259468) (xy 126.068185 -231.287424) (xy 126.103678 -231.321516)
			(xy 126.133243 -231.36086) (xy 126.156114 -231.404437) (xy 126.171698 -231.451118) (xy 126.179593 -231.499695)
			(xy 126.180088 -231.524302) (xy 126.179593 -231.548909) (xy 126.171698 -231.597486) (xy 126.156114 -231.644167)
			(xy 126.133243 -231.687744) (xy 126.103678 -231.727088) (xy 126.068185 -231.76118) (xy 126.027682 -231.789136)
			(xy 125.98322 -231.810234) (xy 125.935949 -231.823926) (xy 125.887094 -231.829858) (xy 125.837919 -231.827877)
			(xy 125.7897 -231.818033) (xy 125.743684 -231.800581) (xy 125.701063 -231.775974) (xy 125.662942 -231.744849)
			(xy 125.630307 -231.708012) (xy 125.604004 -231.666416) (xy 125.584713 -231.62114) (xy 125.572936 -231.573356)
			(xy 125.568976 -231.524302) (xy 125.240034 -231.524302) (xy 125.239539 -231.548909) (xy 125.231644 -231.597486)
			(xy 125.21606 -231.644167) (xy 125.193189 -231.687744) (xy 125.163624 -231.727088) (xy 125.128131 -231.76118)
			(xy 125.087628 -231.789136) (xy 125.043166 -231.810234) (xy 124.995895 -231.823926) (xy 124.94704 -231.829858)
			(xy 124.897865 -231.827877) (xy 124.849646 -231.818033) (xy 124.80363 -231.800581) (xy 124.761009 -231.775974)
			(xy 124.722888 -231.744849) (xy 124.690253 -231.708012) (xy 124.66395 -231.666416) (xy 124.644659 -231.62114)
			(xy 124.632882 -231.573356) (xy 124.628922 -231.524302) (xy 124.29998 -231.524302) (xy 124.299485 -231.548909)
			(xy 124.29159 -231.597486) (xy 124.276006 -231.644167) (xy 124.253135 -231.687744) (xy 124.22357 -231.727088)
			(xy 124.188077 -231.76118) (xy 124.147574 -231.789136) (xy 124.103112 -231.810234) (xy 124.055841 -231.823926)
			(xy 124.006986 -231.829858) (xy 123.957811 -231.827877) (xy 123.909592 -231.818033) (xy 123.863576 -231.800581)
			(xy 123.820955 -231.775974) (xy 123.782834 -231.744849) (xy 123.750199 -231.708012) (xy 123.723896 -231.666416)
			(xy 123.704605 -231.62114) (xy 123.692828 -231.573356) (xy 123.688868 -231.524302) (xy 123.359926 -231.524302)
			(xy 123.359431 -231.548909) (xy 123.351536 -231.597486) (xy 123.335952 -231.644167) (xy 123.313081 -231.687744)
			(xy 123.283516 -231.727088) (xy 123.248023 -231.76118) (xy 123.20752 -231.789136) (xy 123.163058 -231.810234)
			(xy 123.115787 -231.823926) (xy 123.066932 -231.829858) (xy 123.017757 -231.827877) (xy 122.969538 -231.818033)
			(xy 122.923522 -231.800581) (xy 122.880901 -231.775974) (xy 122.84278 -231.744849) (xy 122.810145 -231.708012)
			(xy 122.783842 -231.666416) (xy 122.764551 -231.62114) (xy 122.752774 -231.573356) (xy 122.748814 -231.524302)
			(xy 122.420126 -231.524302) (xy 122.419631 -231.548909) (xy 122.411736 -231.597486) (xy 122.396152 -231.644167)
			(xy 122.373281 -231.687744) (xy 122.343716 -231.727088) (xy 122.308223 -231.76118) (xy 122.26772 -231.789136)
			(xy 122.223258 -231.810234) (xy 122.175987 -231.823926) (xy 122.127132 -231.829858) (xy 122.077957 -231.827877)
			(xy 122.029738 -231.818033) (xy 121.983722 -231.800581) (xy 121.941101 -231.775974) (xy 121.90298 -231.744849)
			(xy 121.870345 -231.708012) (xy 121.844042 -231.666416) (xy 121.824751 -231.62114) (xy 121.812974 -231.573356)
			(xy 121.809014 -231.524302) (xy 121.480072 -231.524302) (xy 121.479577 -231.548909) (xy 121.471682 -231.597486)
			(xy 121.456098 -231.644167) (xy 121.433227 -231.687744) (xy 121.403662 -231.727088) (xy 121.368169 -231.76118)
			(xy 121.327666 -231.789136) (xy 121.283204 -231.810234) (xy 121.235933 -231.823926) (xy 121.187078 -231.829858)
			(xy 121.137903 -231.827877) (xy 121.089684 -231.818033) (xy 121.043668 -231.800581) (xy 121.001047 -231.775974)
			(xy 120.962926 -231.744849) (xy 120.930291 -231.708012) (xy 120.903988 -231.666416) (xy 120.884697 -231.62114)
			(xy 120.87292 -231.573356) (xy 120.86896 -231.524302) (xy 120.540018 -231.524302) (xy 120.539523 -231.548909)
			(xy 120.531628 -231.597486) (xy 120.516044 -231.644167) (xy 120.493173 -231.687744) (xy 120.463608 -231.727088)
			(xy 120.428115 -231.76118) (xy 120.387612 -231.789136) (xy 120.34315 -231.810234) (xy 120.295879 -231.823926)
			(xy 120.247024 -231.829858) (xy 120.197849 -231.827877) (xy 120.14963 -231.818033) (xy 120.103614 -231.800581)
			(xy 120.060993 -231.775974) (xy 120.022872 -231.744849) (xy 119.990237 -231.708012) (xy 119.963934 -231.666416)
			(xy 119.944643 -231.62114) (xy 119.932866 -231.573356) (xy 119.928906 -231.524302) (xy 119.599964 -231.524302)
			(xy 119.599469 -231.548909) (xy 119.591574 -231.597486) (xy 119.57599 -231.644167) (xy 119.553119 -231.687744)
			(xy 119.523554 -231.727088) (xy 119.488061 -231.76118) (xy 119.447558 -231.789136) (xy 119.403096 -231.810234)
			(xy 119.355825 -231.823926) (xy 119.30697 -231.829858) (xy 119.257795 -231.827877) (xy 119.209576 -231.818033)
			(xy 119.16356 -231.800581) (xy 119.120939 -231.775974) (xy 119.082818 -231.744849) (xy 119.050183 -231.708012)
			(xy 119.02388 -231.666416) (xy 119.004589 -231.62114) (xy 118.992812 -231.573356) (xy 118.988852 -231.524302)
			(xy 118.660164 -231.524302) (xy 118.659669 -231.548909) (xy 118.651774 -231.597486) (xy 118.63619 -231.644167)
			(xy 118.613319 -231.687744) (xy 118.583754 -231.727088) (xy 118.548261 -231.76118) (xy 118.507758 -231.789136)
			(xy 118.463296 -231.810234) (xy 118.416025 -231.823926) (xy 118.36717 -231.829858) (xy 118.317995 -231.827877)
			(xy 118.269776 -231.818033) (xy 118.22376 -231.800581) (xy 118.181139 -231.775974) (xy 118.143018 -231.744849)
			(xy 118.110383 -231.708012) (xy 118.08408 -231.666416) (xy 118.064789 -231.62114) (xy 118.053012 -231.573356)
			(xy 118.049052 -231.524302) (xy 117.72011 -231.524302) (xy 117.719615 -231.548909) (xy 117.71172 -231.597486)
			(xy 117.696136 -231.644167) (xy 117.673265 -231.687744) (xy 117.6437 -231.727088) (xy 117.608207 -231.76118)
			(xy 117.567704 -231.789136) (xy 117.523242 -231.810234) (xy 117.475971 -231.823926) (xy 117.427116 -231.829858)
			(xy 117.377941 -231.827877) (xy 117.329722 -231.818033) (xy 117.283706 -231.800581) (xy 117.241085 -231.775974)
			(xy 117.202964 -231.744849) (xy 117.170329 -231.708012) (xy 117.144026 -231.666416) (xy 117.124735 -231.62114)
			(xy 117.112958 -231.573356) (xy 117.108998 -231.524302) (xy 116.780056 -231.524302) (xy 116.779561 -231.548909)
			(xy 116.771666 -231.597486) (xy 116.756082 -231.644167) (xy 116.733211 -231.687744) (xy 116.703646 -231.727088)
			(xy 116.668153 -231.76118) (xy 116.62765 -231.789136) (xy 116.583188 -231.810234) (xy 116.535917 -231.823926)
			(xy 116.487062 -231.829858) (xy 116.437887 -231.827877) (xy 116.389668 -231.818033) (xy 116.343652 -231.800581)
			(xy 116.301031 -231.775974) (xy 116.26291 -231.744849) (xy 116.230275 -231.708012) (xy 116.203972 -231.666416)
			(xy 116.184681 -231.62114) (xy 116.172904 -231.573356) (xy 116.168944 -231.524302) (xy 115.840002 -231.524302)
			(xy 115.839507 -231.548909) (xy 115.831612 -231.597486) (xy 115.816028 -231.644167) (xy 115.793157 -231.687744)
			(xy 115.763592 -231.727088) (xy 115.728099 -231.76118) (xy 115.687596 -231.789136) (xy 115.643134 -231.810234)
			(xy 115.595863 -231.823926) (xy 115.547008 -231.829858) (xy 115.497833 -231.827877) (xy 115.449614 -231.818033)
			(xy 115.403598 -231.800581) (xy 115.360977 -231.775974) (xy 115.322856 -231.744849) (xy 115.290221 -231.708012)
			(xy 115.263918 -231.666416) (xy 115.244627 -231.62114) (xy 115.23285 -231.573356) (xy 115.22889 -231.524302)
			(xy 108.355594 -231.524302) (xy 108.334302 -231.54132) (xy 108.32465 -231.558338) (xy 108.32338 -231.567736)
			(xy 108.319477 -231.591667) (xy 108.305094 -231.63797) (xy 108.283573 -231.681417) (xy 108.255455 -231.720916)
			(xy 108.221447 -231.755474) (xy 108.182403 -231.784222) (xy 108.139307 -231.806437) (xy 108.09324 -231.82156)
			(xy 108.045363 -231.829212) (xy 108.02112 -231.82961) (xy 107.997126 -231.829165) (xy 107.949728 -231.821661)
			(xy 107.904087 -231.806834) (xy 107.861328 -231.78505) (xy 107.822504 -231.756845) (xy 107.788569 -231.722913)
			(xy 107.760361 -231.684091) (xy 107.738574 -231.641333) (xy 107.723744 -231.595694) (xy 107.716236 -231.548296)
			(xy 107.715812 -231.524302) (xy 107.716198 -231.501724) (xy 107.722809 -231.457055) (xy 107.735932 -231.413849)
			(xy 107.755281 -231.373049) (xy 107.780432 -231.335546) (xy 107.795314 -231.318562) (xy 107.801346 -231.311435)
			(xy 107.808245 -231.294103) (xy 107.808776 -231.28478) (xy 107.808776 -231.254046) (xy 107.808434 -231.24394)
			(xy 107.800832 -231.22522) (xy 107.794044 -231.217724) (xy 107.602274 -231.025954) (xy 107.581954 -231.018334)
			(xy 107.571032 -231.019096) (xy 107.55122 -231.019858) (xy 107.550712 -231.019858) (xy 107.526477 -231.01937)
			(xy 107.478621 -231.011667) (xy 107.432583 -230.996501) (xy 107.389519 -230.974252) (xy 107.350511 -230.945479)
			(xy 107.316539 -230.910905) (xy 107.288455 -230.871398) (xy 107.266965 -230.827951) (xy 107.252609 -230.781654)
			(xy 107.248706 -230.75773) (xy 107.246981 -230.748196) (xy 107.237454 -230.731345) (xy 107.230164 -230.724964)
			(xy 107.176062 -230.68153) (xy 107.168279 -230.67586) (xy 107.149872 -230.67026) (xy 107.140248 -230.670608)
			(xy 107.125478 -230.671742) (xy 107.095879 -230.673014) (xy 107.081066 -230.673148) (xy 106.783124 -230.673148)
			(xy 106.742422 -230.672591) (xy 106.661479 -230.66394) (xy 106.62158 -230.655876) (xy 106.616292 -230.65488)
			(xy 106.605532 -230.65488) (xy 106.600244 -230.655876) (xy 106.560407 -230.663923) (xy 106.479592 -230.672576)
			(xy 106.438954 -230.673148) (xy 106.141012 -230.673148) (xy 106.104384 -230.672711) (xy 106.031462 -230.665717)
			(xy 105.959535 -230.651819) (xy 105.889257 -230.631143) (xy 105.821263 -230.603878) (xy 105.756171 -230.570269)
			(xy 105.69457 -230.530622) (xy 105.665524 -230.508302) (xy 105.658643 -230.50327) (xy 105.642547 -230.497684)
			(xy 105.634028 -230.49738) (xy 105.121202 -230.49738) (xy 105.109355 -230.497998) (xy 105.08816 -230.50859)
			(xy 105.080562 -230.5177) (xy 105.031794 -230.582978) (xy 105.025169 -230.592824) (xy 105.02091 -230.616141)
			(xy 105.023666 -230.627682) (xy 105.023666 -230.627936) (xy 105.029568 -230.649103) (xy 105.03594 -230.69258)
			(xy 105.036366 -230.71455) (xy 105.035892 -230.738537) (xy 105.028379 -230.785921) (xy 105.013547 -230.831545)
			(xy 104.99176 -230.874288) (xy 104.963555 -230.913096) (xy 104.929626 -230.947015) (xy 104.890809 -230.975208)
			(xy 104.84806 -230.996982) (xy 104.802431 -231.011801) (xy 104.755046 -231.019299) (xy 104.731058 -231.019858)
			(xy 104.706809 -231.019388) (xy 104.65892 -231.011716) (xy 104.612847 -230.99657) (xy 104.569747 -230.974331)
			(xy 104.530704 -230.94556) (xy 104.4967 -230.910978) (xy 104.46859 -230.871456) (xy 104.44708 -230.827988)
			(xy 104.432712 -230.781667) (xy 104.428798 -230.75773) (xy 104.427072 -230.748197) (xy 104.417544 -230.731346)
			(xy 104.410256 -230.724964) (xy 104.356154 -230.68153) (xy 104.348375 -230.675845) (xy 104.329965 -230.670212)
			(xy 104.32034 -230.670608) (xy 104.30557 -230.671742) (xy 104.275971 -230.673013) (xy 104.261158 -230.673148)
			(xy 103.963216 -230.673148) (xy 103.922514 -230.672591) (xy 103.841571 -230.663939) (xy 103.801672 -230.655876)
			(xy 103.796384 -230.65488) (xy 103.785624 -230.65488) (xy 103.780336 -230.655876) (xy 103.740499 -230.663923)
			(xy 103.659684 -230.672574) (xy 103.619046 -230.673148) (xy 103.321104 -230.673148) (xy 103.284476 -230.672711)
			(xy 103.211554 -230.665716) (xy 103.139628 -230.651817) (xy 103.06935 -230.631141) (xy 103.001357 -230.603875)
			(xy 102.936265 -230.570266) (xy 102.874664 -230.530618) (xy 102.845616 -230.508302) (xy 102.838734 -230.503271)
			(xy 102.822639 -230.497687) (xy 102.81412 -230.49738) (xy 102.301294 -230.49738) (xy 102.289448 -230.498)
			(xy 102.268256 -230.508594) (xy 102.260654 -230.5177) (xy 102.211886 -230.582978) (xy 102.205262 -230.592825)
			(xy 102.201003 -230.616141) (xy 102.203758 -230.627682) (xy 102.203758 -230.627936) (xy 102.20966 -230.649103)
			(xy 102.216033 -230.69258) (xy 102.216458 -230.71455) (xy 102.215984 -230.73854) (xy 102.208472 -230.785929)
			(xy 102.19364 -230.831559) (xy 102.171855 -230.874309) (xy 102.143652 -230.913125) (xy 102.109725 -230.947052)
			(xy 102.070909 -230.975255) (xy 102.028159 -230.99704) (xy 101.982529 -231.011872) (xy 101.93514 -231.019384)
			(xy 101.91115 -231.019858) (xy 101.886901 -231.019388) (xy 101.839014 -231.011714) (xy 101.792941 -230.996567)
			(xy 101.749843 -230.974328) (xy 101.710801 -230.945557) (xy 101.676798 -230.910975) (xy 101.648688 -230.871454)
			(xy 101.627179 -230.827986) (xy 101.612811 -230.781665) (xy 101.60889 -230.75773) (xy 101.607164 -230.748197)
			(xy 101.597635 -230.731348) (xy 101.590348 -230.724964) (xy 101.536246 -230.68153) (xy 101.528467 -230.675846)
			(xy 101.510057 -230.670216) (xy 101.500432 -230.670608) (xy 101.485599 -230.671745) (xy 101.455872 -230.673013)
			(xy 101.440996 -230.673148) (xy 101.143054 -230.673148) (xy 101.102416 -230.67258) (xy 101.021601 -230.663926)
			(xy 100.981764 -230.655876) (xy 100.976476 -230.65488) (xy 100.965716 -230.65488) (xy 100.960428 -230.655876)
			(xy 100.920528 -230.663934) (xy 100.839586 -230.672585) (xy 100.798884 -230.673148) (xy 100.500942 -230.673148)
			(xy 100.464313 -230.672713) (xy 100.39139 -230.665721) (xy 100.319462 -230.651826) (xy 100.249182 -230.631152)
			(xy 100.181186 -230.603888) (xy 100.116092 -230.570281) (xy 100.054489 -230.530636) (xy 100.025454 -230.508302)
			(xy 100.0252 -230.508048) (xy 100.018358 -230.503103) (xy 100.002395 -230.497647) (xy 99.993958 -230.49738)
			(xy 99.942142 -230.49738) (xy 99.932076 -230.497813) (xy 99.913485 -230.50554) (xy 99.906074 -230.512366)
			(xy 99.575366 -230.843074) (xy 99.568524 -230.850473) (xy 99.560806 -230.869072) (xy 99.56038 -230.879142)
			(xy 99.56038 -231.1908) (xy 99.585272 -231.219502) (xy 99.604068 -231.222042) (xy 99.628022 -231.225919)
			(xy 99.674376 -231.240261) (xy 99.717878 -231.261754) (xy 99.757433 -231.289858) (xy 99.792044 -231.323865)
			(xy 99.820841 -231.362918) (xy 99.843098 -231.406034) (xy 99.858254 -231.452128) (xy 99.865929 -231.500039)
			(xy 99.865929 -231.5243) (xy 100.194787 -231.5243) (xy 100.198963 -231.473911) (xy 100.211376 -231.424897)
			(xy 100.231688 -231.378595) (xy 100.259345 -231.336268) (xy 100.293592 -231.299071) (xy 100.333495 -231.268018)
			(xy 100.377964 -231.243958) (xy 100.425788 -231.227546) (xy 100.475661 -231.21923) (xy 100.500942 -231.21874)
			(xy 101.440996 -231.21874) (xy 101.466275 -231.219229) (xy 101.516144 -231.22755) (xy 101.563963 -231.243965)
			(xy 101.608428 -231.268028) (xy 101.648326 -231.299081) (xy 101.682568 -231.336278) (xy 101.710221 -231.378604)
			(xy 101.73053 -231.424903) (xy 101.742941 -231.473914) (xy 101.747117 -231.5243) (xy 101.747117 -231.524302)
			(xy 102.075246 -231.524302) (xy 102.079206 -231.475248) (xy 102.090983 -231.427464) (xy 102.110274 -231.382188)
			(xy 102.136577 -231.340592) (xy 102.169212 -231.303755) (xy 102.207333 -231.27263) (xy 102.249954 -231.248023)
			(xy 102.29597 -231.230571) (xy 102.344189 -231.220727) (xy 102.393364 -231.218746) (xy 102.442219 -231.224678)
			(xy 102.48949 -231.23837) (xy 102.533952 -231.259468) (xy 102.574455 -231.287424) (xy 102.609948 -231.321516)
			(xy 102.639513 -231.36086) (xy 102.662384 -231.404437) (xy 102.677968 -231.451118) (xy 102.685863 -231.499695)
			(xy 102.686358 -231.5243) (xy 103.014987 -231.5243) (xy 103.019163 -231.473915) (xy 103.031574 -231.424905)
			(xy 103.051883 -231.378605) (xy 103.079535 -231.33628) (xy 103.113777 -231.299084) (xy 103.153674 -231.268031)
			(xy 103.198139 -231.243969) (xy 103.245957 -231.227554) (xy 103.295825 -231.219233) (xy 103.321104 -231.21874)
			(xy 104.261158 -231.21874) (xy 104.286439 -231.219226) (xy 104.336313 -231.227542) (xy 104.384137 -231.243954)
			(xy 104.428608 -231.268015) (xy 104.468511 -231.299068) (xy 104.502758 -231.336265) (xy 104.530415 -231.378593)
			(xy 104.550727 -231.424896) (xy 104.563141 -231.473911) (xy 104.567317 -231.5243) (xy 104.567317 -231.524302)
			(xy 104.895154 -231.524302) (xy 104.899114 -231.475248) (xy 104.910891 -231.427464) (xy 104.930182 -231.382188)
			(xy 104.956485 -231.340592) (xy 104.98912 -231.303755) (xy 105.027241 -231.27263) (xy 105.069862 -231.248023)
			(xy 105.115878 -231.230571) (xy 105.164097 -231.220727) (xy 105.213272 -231.218746) (xy 105.262127 -231.224678)
			(xy 105.309398 -231.23837) (xy 105.35386 -231.259468) (xy 105.394363 -231.287424) (xy 105.429856 -231.321516)
			(xy 105.459421 -231.36086) (xy 105.482292 -231.404437) (xy 105.497876 -231.451118) (xy 105.505771 -231.499695)
			(xy 105.506266 -231.5243) (xy 105.834887 -231.5243) (xy 105.839063 -231.473914) (xy 105.851474 -231.424903)
			(xy 105.871784 -231.378603) (xy 105.899437 -231.336278) (xy 105.93368 -231.299081) (xy 105.973579 -231.268029)
			(xy 106.018044 -231.243967) (xy 106.065864 -231.227552) (xy 106.115733 -231.219232) (xy 106.141012 -231.21874)
			(xy 107.081066 -231.21874) (xy 107.106347 -231.219226) (xy 107.156219 -231.227544) (xy 107.204043 -231.243957)
			(xy 107.248512 -231.268018) (xy 107.288414 -231.299071) (xy 107.32266 -231.336268) (xy 107.350316 -231.378595)
			(xy 107.370628 -231.424897) (xy 107.383041 -231.473911) (xy 107.387217 -231.5243) (xy 107.383041 -231.574689)
			(xy 107.370628 -231.623703) (xy 107.350316 -231.670005) (xy 107.32266 -231.712332) (xy 107.288414 -231.749529)
			(xy 107.248512 -231.780582) (xy 107.204043 -231.804643) (xy 107.156219 -231.821056) (xy 107.106347 -231.829374)
			(xy 107.081066 -231.829864) (xy 106.141012 -231.829864) (xy 106.115733 -231.829368) (xy 106.065864 -231.821048)
			(xy 106.018044 -231.804633) (xy 105.973579 -231.780571) (xy 105.93368 -231.749519) (xy 105.899437 -231.712322)
			(xy 105.871784 -231.669997) (xy 105.851474 -231.623697) (xy 105.839063 -231.574686) (xy 105.834887 -231.5243)
			(xy 105.506266 -231.5243) (xy 105.506266 -231.524302) (xy 105.505771 -231.548909) (xy 105.497876 -231.597486)
			(xy 105.482292 -231.644167) (xy 105.459421 -231.687744) (xy 105.429856 -231.727088) (xy 105.394363 -231.76118)
			(xy 105.35386 -231.789136) (xy 105.309398 -231.810234) (xy 105.262127 -231.823926) (xy 105.213272 -231.829858)
			(xy 105.164097 -231.827877) (xy 105.115878 -231.818033) (xy 105.069862 -231.800581) (xy 105.027241 -231.775974)
			(xy 104.98912 -231.744849) (xy 104.956485 -231.708012) (xy 104.930182 -231.666416) (xy 104.910891 -231.62114)
			(xy 104.899114 -231.573356) (xy 104.895154 -231.524302) (xy 104.567317 -231.524302) (xy 104.563141 -231.574689)
			(xy 104.550727 -231.623704) (xy 104.530415 -231.670007) (xy 104.502758 -231.712335) (xy 104.468511 -231.749532)
			(xy 104.428608 -231.780585) (xy 104.384137 -231.804646) (xy 104.336313 -231.821058) (xy 104.286439 -231.829374)
			(xy 104.261158 -231.829864) (xy 103.321104 -231.829864) (xy 103.295825 -231.829367) (xy 103.245957 -231.821046)
			(xy 103.198139 -231.804631) (xy 103.153674 -231.780569) (xy 103.113777 -231.749516) (xy 103.079535 -231.71232)
			(xy 103.051883 -231.669995) (xy 103.031574 -231.623695) (xy 103.019163 -231.574685) (xy 103.014987 -231.5243)
			(xy 102.686358 -231.5243) (xy 102.686358 -231.524302) (xy 102.685863 -231.548909) (xy 102.677968 -231.597486)
			(xy 102.662384 -231.644167) (xy 102.639513 -231.687744) (xy 102.609948 -231.727088) (xy 102.574455 -231.76118)
			(xy 102.533952 -231.789136) (xy 102.48949 -231.810234) (xy 102.442219 -231.823926) (xy 102.393364 -231.829858)
			(xy 102.344189 -231.827877) (xy 102.29597 -231.818033) (xy 102.249954 -231.800581) (xy 102.207333 -231.775974)
			(xy 102.169212 -231.744849) (xy 102.136577 -231.708012) (xy 102.110274 -231.666416) (xy 102.090983 -231.62114)
			(xy 102.079206 -231.573356) (xy 102.075246 -231.524302) (xy 101.747117 -231.524302) (xy 101.742941 -231.574686)
			(xy 101.73053 -231.623697) (xy 101.710221 -231.669996) (xy 101.682568 -231.712322) (xy 101.648326 -231.749519)
			(xy 101.608428 -231.780572) (xy 101.563963 -231.804635) (xy 101.516144 -231.82105) (xy 101.466275 -231.829371)
			(xy 101.440996 -231.829864) (xy 100.500942 -231.829864) (xy 100.475661 -231.82937) (xy 100.425788 -231.821054)
			(xy 100.377964 -231.804642) (xy 100.333495 -231.780582) (xy 100.293592 -231.749529) (xy 100.259345 -231.712332)
			(xy 100.231688 -231.670005) (xy 100.211376 -231.623703) (xy 100.198963 -231.574689) (xy 100.194787 -231.5243)
			(xy 99.865929 -231.5243) (xy 99.865929 -231.548561) (xy 99.858254 -231.596473) (xy 99.843097 -231.642567)
			(xy 99.82084 -231.685683) (xy 99.792044 -231.724736) (xy 99.757432 -231.758742) (xy 99.717877 -231.786846)
			(xy 99.674375 -231.808339) (xy 99.628021 -231.822681) (xy 99.604068 -231.826562) (xy 99.585272 -231.829102)
			(xy 99.56038 -231.857804) (xy 99.56038 -232.12806) (xy 99.559945 -232.138125) (xy 99.552213 -232.156712)
			(xy 99.545394 -232.164128) (xy 99.411282 -232.29824) (xy 99.404433 -232.305637) (xy 99.3967 -232.324236)
			(xy 99.396296 -232.334308) (xy 99.725238 -232.334308) (xy 99.729198 -232.285254) (xy 99.740975 -232.23747)
			(xy 99.760266 -232.192194) (xy 99.786569 -232.150598) (xy 99.819204 -232.113761) (xy 99.857325 -232.082636)
			(xy 99.899946 -232.058029) (xy 99.945962 -232.040577) (xy 99.994181 -232.030733) (xy 100.043356 -232.028752)
			(xy 100.092211 -232.034684) (xy 100.139482 -232.048376) (xy 100.183944 -232.069474) (xy 100.224447 -232.09743)
			(xy 100.25994 -232.131522) (xy 100.289505 -232.170866) (xy 100.312376 -232.214443) (xy 100.32796 -232.261124)
			(xy 100.335855 -232.309701) (xy 100.33635 -232.334308) (xy 100.665292 -232.334308) (xy 100.669252 -232.285254)
			(xy 100.681029 -232.23747) (xy 100.70032 -232.192194) (xy 100.726623 -232.150598) (xy 100.759258 -232.113761)
			(xy 100.797379 -232.082636) (xy 100.84 -232.058029) (xy 100.886016 -232.040577) (xy 100.934235 -232.030733)
			(xy 100.98341 -232.028752) (xy 101.032265 -232.034684) (xy 101.079536 -232.048376) (xy 101.123998 -232.069474)
			(xy 101.164501 -232.09743) (xy 101.199994 -232.131522) (xy 101.229559 -232.170866) (xy 101.25243 -232.214443)
			(xy 101.268014 -232.261124) (xy 101.275909 -232.309701) (xy 101.276404 -232.334308) (xy 101.605346 -232.334308)
			(xy 101.609306 -232.285254) (xy 101.621083 -232.23747) (xy 101.640374 -232.192194) (xy 101.666677 -232.150598)
			(xy 101.699312 -232.113761) (xy 101.737433 -232.082636) (xy 101.780054 -232.058029) (xy 101.82607 -232.040577)
			(xy 101.874289 -232.030733) (xy 101.923464 -232.028752) (xy 101.972319 -232.034684) (xy 102.01959 -232.048376)
			(xy 102.064052 -232.069474) (xy 102.104555 -232.09743) (xy 102.140048 -232.131522) (xy 102.169613 -232.170866)
			(xy 102.192484 -232.214443) (xy 102.208068 -232.261124) (xy 102.215963 -232.309701) (xy 102.216458 -232.334308)
			(xy 102.545146 -232.334308) (xy 102.549106 -232.285254) (xy 102.560883 -232.23747) (xy 102.580174 -232.192194)
			(xy 102.606477 -232.150598) (xy 102.639112 -232.113761) (xy 102.677233 -232.082636) (xy 102.719854 -232.058029)
			(xy 102.76587 -232.040577) (xy 102.814089 -232.030733) (xy 102.863264 -232.028752) (xy 102.912119 -232.034684)
			(xy 102.95939 -232.048376) (xy 103.003852 -232.069474) (xy 103.044355 -232.09743) (xy 103.079848 -232.131522)
			(xy 103.109413 -232.170866) (xy 103.132284 -232.214443) (xy 103.147868 -232.261124) (xy 103.155763 -232.309701)
			(xy 103.156258 -232.334308) (xy 103.4852 -232.334308) (xy 103.48916 -232.285254) (xy 103.500937 -232.23747)
			(xy 103.520228 -232.192194) (xy 103.546531 -232.150598) (xy 103.579166 -232.113761) (xy 103.617287 -232.082636)
			(xy 103.659908 -232.058029) (xy 103.705924 -232.040577) (xy 103.754143 -232.030733) (xy 103.803318 -232.028752)
			(xy 103.852173 -232.034684) (xy 103.899444 -232.048376) (xy 103.943906 -232.069474) (xy 103.984409 -232.09743)
			(xy 104.019902 -232.131522) (xy 104.049467 -232.170866) (xy 104.072338 -232.214443) (xy 104.087922 -232.261124)
			(xy 104.095817 -232.309701) (xy 104.096312 -232.334308) (xy 104.425254 -232.334308) (xy 104.429214 -232.285254)
			(xy 104.440991 -232.23747) (xy 104.460282 -232.192194) (xy 104.486585 -232.150598) (xy 104.51922 -232.113761)
			(xy 104.557341 -232.082636) (xy 104.599962 -232.058029) (xy 104.645978 -232.040577) (xy 104.694197 -232.030733)
			(xy 104.743372 -232.028752) (xy 104.792227 -232.034684) (xy 104.839498 -232.048376) (xy 104.88396 -232.069474)
			(xy 104.924463 -232.09743) (xy 104.959956 -232.131522) (xy 104.989521 -232.170866) (xy 105.012392 -232.214443)
			(xy 105.027976 -232.261124) (xy 105.035871 -232.309701) (xy 105.036366 -232.334308) (xy 105.365308 -232.334308)
			(xy 105.369268 -232.285254) (xy 105.381045 -232.23747) (xy 105.400336 -232.192194) (xy 105.426639 -232.150598)
			(xy 105.459274 -232.113761) (xy 105.497395 -232.082636) (xy 105.540016 -232.058029) (xy 105.586032 -232.040577)
			(xy 105.634251 -232.030733) (xy 105.683426 -232.028752) (xy 105.732281 -232.034684) (xy 105.779552 -232.048376)
			(xy 105.824014 -232.069474) (xy 105.864517 -232.09743) (xy 105.90001 -232.131522) (xy 105.929575 -232.170866)
			(xy 105.952446 -232.214443) (xy 105.96803 -232.261124) (xy 105.975925 -232.309701) (xy 105.97642 -232.334308)
			(xy 106.305362 -232.334308) (xy 106.309322 -232.285254) (xy 106.321099 -232.23747) (xy 106.34039 -232.192194)
			(xy 106.366693 -232.150598) (xy 106.399328 -232.113761) (xy 106.437449 -232.082636) (xy 106.48007 -232.058029)
			(xy 106.526086 -232.040577) (xy 106.574305 -232.030733) (xy 106.62348 -232.028752) (xy 106.672335 -232.034684)
			(xy 106.719606 -232.048376) (xy 106.764068 -232.069474) (xy 106.804571 -232.09743) (xy 106.840064 -232.131522)
			(xy 106.869629 -232.170866) (xy 106.8925 -232.214443) (xy 106.908084 -232.261124) (xy 106.915979 -232.309701)
			(xy 106.916474 -232.334308) (xy 107.245162 -232.334308) (xy 107.249122 -232.285254) (xy 107.260899 -232.23747)
			(xy 107.28019 -232.192194) (xy 107.306493 -232.150598) (xy 107.339128 -232.113761) (xy 107.377249 -232.082636)
			(xy 107.41987 -232.058029) (xy 107.465886 -232.040577) (xy 107.514105 -232.030733) (xy 107.56328 -232.028752)
			(xy 107.612135 -232.034684) (xy 107.659406 -232.048376) (xy 107.703868 -232.069474) (xy 107.744371 -232.09743)
			(xy 107.779864 -232.131522) (xy 107.809429 -232.170866) (xy 107.8323 -232.214443) (xy 107.847884 -232.261124)
			(xy 107.855779 -232.309701) (xy 107.856274 -232.3343) (xy 108.185148 -232.3343) (xy 108.18932 -232.283956)
			(xy 108.201721 -232.234986) (xy 108.222014 -232.188725) (xy 108.249645 -232.146435) (xy 108.28386 -232.10927)
			(xy 108.323725 -232.078244) (xy 108.368154 -232.054203) (xy 108.415934 -232.037803) (xy 108.465762 -232.029491)
			(xy 108.49102 -232.029) (xy 109.431074 -232.029) (xy 109.456334 -232.029475) (xy 109.506165 -232.037786)
			(xy 109.553948 -232.054187) (xy 109.59838 -232.078229) (xy 109.638249 -232.109256) (xy 109.672466 -232.146423)
			(xy 109.700099 -232.188716) (xy 109.720393 -232.23498) (xy 109.732796 -232.283953) (xy 109.736968 -232.3343)
			(xy 109.736967 -232.334308) (xy 110.065324 -232.334308) (xy 110.069284 -232.285254) (xy 110.081061 -232.23747)
			(xy 110.100352 -232.192194) (xy 110.126655 -232.150598) (xy 110.15929 -232.113761) (xy 110.197411 -232.082636)
			(xy 110.240032 -232.058029) (xy 110.286048 -232.040577) (xy 110.334267 -232.030733) (xy 110.383442 -232.028752)
			(xy 110.432297 -232.034684) (xy 110.479568 -232.048376) (xy 110.52403 -232.069474) (xy 110.564533 -232.09743)
			(xy 110.600026 -232.131522) (xy 110.629591 -232.170866) (xy 110.652462 -232.214443) (xy 110.668046 -232.261124)
			(xy 110.675941 -232.309701) (xy 110.676436 -232.334308) (xy 112.878882 -232.334308) (xy 112.882842 -232.285254)
			(xy 112.894619 -232.23747) (xy 112.91391 -232.192194) (xy 112.940213 -232.150598) (xy 112.972848 -232.113761)
			(xy 113.010969 -232.082636) (xy 113.05359 -232.058029) (xy 113.099606 -232.040577) (xy 113.147825 -232.030733)
			(xy 113.197 -232.028752) (xy 113.245855 -232.034684) (xy 113.293126 -232.048376) (xy 113.337588 -232.069474)
			(xy 113.378091 -232.09743) (xy 113.413584 -232.131522) (xy 113.443149 -232.170866) (xy 113.46602 -232.214443)
			(xy 113.481604 -232.261124) (xy 113.489499 -232.309701) (xy 113.489994 -232.334308) (xy 113.818936 -232.334308)
			(xy 113.822896 -232.285254) (xy 113.834673 -232.23747) (xy 113.853964 -232.192194) (xy 113.880267 -232.150598)
			(xy 113.912902 -232.113761) (xy 113.951023 -232.082636) (xy 113.993644 -232.058029) (xy 114.03966 -232.040577)
			(xy 114.087879 -232.030733) (xy 114.137054 -232.028752) (xy 114.185909 -232.034684) (xy 114.23318 -232.048376)
			(xy 114.277642 -232.069474) (xy 114.318145 -232.09743) (xy 114.353638 -232.131522) (xy 114.383203 -232.170866)
			(xy 114.406074 -232.214443) (xy 114.421658 -232.261124) (xy 114.429553 -232.309701) (xy 114.430048 -232.334308)
			(xy 114.75899 -232.334308) (xy 114.76295 -232.285254) (xy 114.774727 -232.23747) (xy 114.794018 -232.192194)
			(xy 114.820321 -232.150598) (xy 114.852956 -232.113761) (xy 114.891077 -232.082636) (xy 114.933698 -232.058029)
			(xy 114.979714 -232.040577) (xy 115.027933 -232.030733) (xy 115.077108 -232.028752) (xy 115.125963 -232.034684)
			(xy 115.173234 -232.048376) (xy 115.217696 -232.069474) (xy 115.258199 -232.09743) (xy 115.293692 -232.131522)
			(xy 115.323257 -232.170866) (xy 115.346128 -232.214443) (xy 115.361712 -232.261124) (xy 115.369607 -232.309701)
			(xy 115.370102 -232.334308) (xy 115.699044 -232.334308) (xy 115.703004 -232.285254) (xy 115.714781 -232.23747)
			(xy 115.734072 -232.192194) (xy 115.760375 -232.150598) (xy 115.79301 -232.113761) (xy 115.831131 -232.082636)
			(xy 115.873752 -232.058029) (xy 115.919768 -232.040577) (xy 115.967987 -232.030733) (xy 116.017162 -232.028752)
			(xy 116.066017 -232.034684) (xy 116.113288 -232.048376) (xy 116.15775 -232.069474) (xy 116.198253 -232.09743)
			(xy 116.233746 -232.131522) (xy 116.263311 -232.170866) (xy 116.286182 -232.214443) (xy 116.301766 -232.261124)
			(xy 116.309661 -232.309701) (xy 116.310156 -232.334308) (xy 116.638844 -232.334308) (xy 116.642804 -232.285254)
			(xy 116.654581 -232.23747) (xy 116.673872 -232.192194) (xy 116.700175 -232.150598) (xy 116.73281 -232.113761)
			(xy 116.770931 -232.082636) (xy 116.813552 -232.058029) (xy 116.859568 -232.040577) (xy 116.907787 -232.030733)
			(xy 116.956962 -232.028752) (xy 117.005817 -232.034684) (xy 117.053088 -232.048376) (xy 117.09755 -232.069474)
			(xy 117.138053 -232.09743) (xy 117.173546 -232.131522) (xy 117.203111 -232.170866) (xy 117.225982 -232.214443)
			(xy 117.241566 -232.261124) (xy 117.249461 -232.309701) (xy 117.249956 -232.334308) (xy 117.578898 -232.334308)
			(xy 117.582858 -232.285254) (xy 117.594635 -232.23747) (xy 117.613926 -232.192194) (xy 117.640229 -232.150598)
			(xy 117.672864 -232.113761) (xy 117.710985 -232.082636) (xy 117.753606 -232.058029) (xy 117.799622 -232.040577)
			(xy 117.847841 -232.030733) (xy 117.897016 -232.028752) (xy 117.945871 -232.034684) (xy 117.993142 -232.048376)
			(xy 118.037604 -232.069474) (xy 118.078107 -232.09743) (xy 118.1136 -232.131522) (xy 118.143165 -232.170866)
			(xy 118.166036 -232.214443) (xy 118.18162 -232.261124) (xy 118.189515 -232.309701) (xy 118.19001 -232.334308)
			(xy 118.518952 -232.334308) (xy 118.522912 -232.285254) (xy 118.534689 -232.23747) (xy 118.55398 -232.192194)
			(xy 118.580283 -232.150598) (xy 118.612918 -232.113761) (xy 118.651039 -232.082636) (xy 118.69366 -232.058029)
			(xy 118.739676 -232.040577) (xy 118.787895 -232.030733) (xy 118.83707 -232.028752) (xy 118.885925 -232.034684)
			(xy 118.933196 -232.048376) (xy 118.977658 -232.069474) (xy 119.018161 -232.09743) (xy 119.053654 -232.131522)
			(xy 119.083219 -232.170866) (xy 119.10609 -232.214443) (xy 119.121674 -232.261124) (xy 119.129569 -232.309701)
			(xy 119.130064 -232.334308) (xy 119.459006 -232.334308) (xy 119.462966 -232.285254) (xy 119.474743 -232.23747)
			(xy 119.494034 -232.192194) (xy 119.520337 -232.150598) (xy 119.552972 -232.113761) (xy 119.591093 -232.082636)
			(xy 119.633714 -232.058029) (xy 119.67973 -232.040577) (xy 119.727949 -232.030733) (xy 119.777124 -232.028752)
			(xy 119.825979 -232.034684) (xy 119.87325 -232.048376) (xy 119.917712 -232.069474) (xy 119.958215 -232.09743)
			(xy 119.993708 -232.131522) (xy 120.023273 -232.170866) (xy 120.046144 -232.214443) (xy 120.061728 -232.261124)
			(xy 120.069623 -232.309701) (xy 120.070118 -232.334308) (xy 120.398806 -232.334308) (xy 120.402766 -232.285254)
			(xy 120.414543 -232.23747) (xy 120.433834 -232.192194) (xy 120.460137 -232.150598) (xy 120.492772 -232.113761)
			(xy 120.530893 -232.082636) (xy 120.573514 -232.058029) (xy 120.61953 -232.040577) (xy 120.667749 -232.030733)
			(xy 120.716924 -232.028752) (xy 120.765779 -232.034684) (xy 120.81305 -232.048376) (xy 120.857512 -232.069474)
			(xy 120.898015 -232.09743) (xy 120.933508 -232.131522) (xy 120.963073 -232.170866) (xy 120.985944 -232.214443)
			(xy 121.001528 -232.261124) (xy 121.009423 -232.309701) (xy 121.009918 -232.334308) (xy 121.33886 -232.334308)
			(xy 121.34282 -232.285254) (xy 121.354597 -232.23747) (xy 121.373888 -232.192194) (xy 121.400191 -232.150598)
			(xy 121.432826 -232.113761) (xy 121.470947 -232.082636) (xy 121.513568 -232.058029) (xy 121.559584 -232.040577)
			(xy 121.607803 -232.030733) (xy 121.656978 -232.028752) (xy 121.705833 -232.034684) (xy 121.753104 -232.048376)
			(xy 121.797566 -232.069474) (xy 121.838069 -232.09743) (xy 121.873562 -232.131522) (xy 121.903127 -232.170866)
			(xy 121.925998 -232.214443) (xy 121.941582 -232.261124) (xy 121.949477 -232.309701) (xy 121.949972 -232.334308)
			(xy 122.278914 -232.334308) (xy 122.282874 -232.285254) (xy 122.294651 -232.23747) (xy 122.313942 -232.192194)
			(xy 122.340245 -232.150598) (xy 122.37288 -232.113761) (xy 122.411001 -232.082636) (xy 122.453622 -232.058029)
			(xy 122.499638 -232.040577) (xy 122.547857 -232.030733) (xy 122.597032 -232.028752) (xy 122.645887 -232.034684)
			(xy 122.693158 -232.048376) (xy 122.73762 -232.069474) (xy 122.778123 -232.09743) (xy 122.813616 -232.131522)
			(xy 122.843181 -232.170866) (xy 122.866052 -232.214443) (xy 122.881636 -232.261124) (xy 122.889531 -232.309701)
			(xy 122.890026 -232.334308) (xy 123.218968 -232.334308) (xy 123.222928 -232.285254) (xy 123.234705 -232.23747)
			(xy 123.253996 -232.192194) (xy 123.280299 -232.150598) (xy 123.312934 -232.113761) (xy 123.351055 -232.082636)
			(xy 123.393676 -232.058029) (xy 123.439692 -232.040577) (xy 123.487911 -232.030733) (xy 123.537086 -232.028752)
			(xy 123.585941 -232.034684) (xy 123.633212 -232.048376) (xy 123.677674 -232.069474) (xy 123.718177 -232.09743)
			(xy 123.75367 -232.131522) (xy 123.783235 -232.170866) (xy 123.806106 -232.214443) (xy 123.82169 -232.261124)
			(xy 123.829585 -232.309701) (xy 123.83008 -232.334308) (xy 124.159022 -232.334308) (xy 124.162982 -232.285254)
			(xy 124.174759 -232.23747) (xy 124.19405 -232.192194) (xy 124.220353 -232.150598) (xy 124.252988 -232.113761)
			(xy 124.291109 -232.082636) (xy 124.33373 -232.058029) (xy 124.379746 -232.040577) (xy 124.427965 -232.030733)
			(xy 124.47714 -232.028752) (xy 124.525995 -232.034684) (xy 124.573266 -232.048376) (xy 124.617728 -232.069474)
			(xy 124.658231 -232.09743) (xy 124.693724 -232.131522) (xy 124.723289 -232.170866) (xy 124.74616 -232.214443)
			(xy 124.761744 -232.261124) (xy 124.769639 -232.309701) (xy 124.770134 -232.334308) (xy 125.098822 -232.334308)
			(xy 125.102782 -232.285254) (xy 125.114559 -232.23747) (xy 125.13385 -232.192194) (xy 125.160153 -232.150598)
			(xy 125.192788 -232.113761) (xy 125.230909 -232.082636) (xy 125.27353 -232.058029) (xy 125.319546 -232.040577)
			(xy 125.367765 -232.030733) (xy 125.41694 -232.028752) (xy 125.465795 -232.034684) (xy 125.513066 -232.048376)
			(xy 125.557528 -232.069474) (xy 125.598031 -232.09743) (xy 125.633524 -232.131522) (xy 125.663089 -232.170866)
			(xy 125.68596 -232.214443) (xy 125.701544 -232.261124) (xy 125.709439 -232.309701) (xy 125.709934 -232.334308)
			(xy 126.038876 -232.334308) (xy 126.042836 -232.285254) (xy 126.054613 -232.23747) (xy 126.073904 -232.192194)
			(xy 126.100207 -232.150598) (xy 126.132842 -232.113761) (xy 126.170963 -232.082636) (xy 126.213584 -232.058029)
			(xy 126.2596 -232.040577) (xy 126.307819 -232.030733) (xy 126.356994 -232.028752) (xy 126.405849 -232.034684)
			(xy 126.45312 -232.048376) (xy 126.497582 -232.069474) (xy 126.538085 -232.09743) (xy 126.573578 -232.131522)
			(xy 126.603143 -232.170866) (xy 126.626014 -232.214443) (xy 126.641598 -232.261124) (xy 126.649493 -232.309701)
			(xy 126.649988 -232.334308) (xy 126.649493 -232.358915) (xy 126.641598 -232.407492) (xy 126.626014 -232.454173)
			(xy 126.603143 -232.49775) (xy 126.573578 -232.537094) (xy 126.538085 -232.571186) (xy 126.497582 -232.599142)
			(xy 126.45312 -232.62024) (xy 126.405849 -232.633932) (xy 126.356994 -232.639864) (xy 126.307819 -232.637883)
			(xy 126.2596 -232.628039) (xy 126.213584 -232.610587) (xy 126.170963 -232.58598) (xy 126.132842 -232.554855)
			(xy 126.100207 -232.518018) (xy 126.073904 -232.476422) (xy 126.054613 -232.431146) (xy 126.042836 -232.383362)
			(xy 126.038876 -232.334308) (xy 125.709934 -232.334308) (xy 125.709439 -232.358915) (xy 125.701544 -232.407492)
			(xy 125.68596 -232.454173) (xy 125.663089 -232.49775) (xy 125.633524 -232.537094) (xy 125.598031 -232.571186)
			(xy 125.557528 -232.599142) (xy 125.513066 -232.62024) (xy 125.465795 -232.633932) (xy 125.41694 -232.639864)
			(xy 125.367765 -232.637883) (xy 125.319546 -232.628039) (xy 125.27353 -232.610587) (xy 125.230909 -232.58598)
			(xy 125.192788 -232.554855) (xy 125.160153 -232.518018) (xy 125.13385 -232.476422) (xy 125.114559 -232.431146)
			(xy 125.102782 -232.383362) (xy 125.098822 -232.334308) (xy 124.770134 -232.334308) (xy 124.769639 -232.358915)
			(xy 124.761744 -232.407492) (xy 124.74616 -232.454173) (xy 124.723289 -232.49775) (xy 124.693724 -232.537094)
			(xy 124.658231 -232.571186) (xy 124.617728 -232.599142) (xy 124.573266 -232.62024) (xy 124.525995 -232.633932)
			(xy 124.47714 -232.639864) (xy 124.427965 -232.637883) (xy 124.379746 -232.628039) (xy 124.33373 -232.610587)
			(xy 124.291109 -232.58598) (xy 124.252988 -232.554855) (xy 124.220353 -232.518018) (xy 124.19405 -232.476422)
			(xy 124.174759 -232.431146) (xy 124.162982 -232.383362) (xy 124.159022 -232.334308) (xy 123.83008 -232.334308)
			(xy 123.829585 -232.358915) (xy 123.82169 -232.407492) (xy 123.806106 -232.454173) (xy 123.783235 -232.49775)
			(xy 123.75367 -232.537094) (xy 123.718177 -232.571186) (xy 123.677674 -232.599142) (xy 123.633212 -232.62024)
			(xy 123.585941 -232.633932) (xy 123.537086 -232.639864) (xy 123.487911 -232.637883) (xy 123.439692 -232.628039)
			(xy 123.393676 -232.610587) (xy 123.351055 -232.58598) (xy 123.312934 -232.554855) (xy 123.280299 -232.518018)
			(xy 123.253996 -232.476422) (xy 123.234705 -232.431146) (xy 123.222928 -232.383362) (xy 123.218968 -232.334308)
			(xy 122.890026 -232.334308) (xy 122.889531 -232.358915) (xy 122.881636 -232.407492) (xy 122.866052 -232.454173)
			(xy 122.843181 -232.49775) (xy 122.813616 -232.537094) (xy 122.778123 -232.571186) (xy 122.73762 -232.599142)
			(xy 122.693158 -232.62024) (xy 122.645887 -232.633932) (xy 122.597032 -232.639864) (xy 122.547857 -232.637883)
			(xy 122.499638 -232.628039) (xy 122.453622 -232.610587) (xy 122.411001 -232.58598) (xy 122.37288 -232.554855)
			(xy 122.340245 -232.518018) (xy 122.313942 -232.476422) (xy 122.294651 -232.431146) (xy 122.282874 -232.383362)
			(xy 122.278914 -232.334308) (xy 121.949972 -232.334308) (xy 121.949477 -232.358915) (xy 121.941582 -232.407492)
			(xy 121.925998 -232.454173) (xy 121.903127 -232.49775) (xy 121.873562 -232.537094) (xy 121.838069 -232.571186)
			(xy 121.797566 -232.599142) (xy 121.753104 -232.62024) (xy 121.705833 -232.633932) (xy 121.656978 -232.639864)
			(xy 121.607803 -232.637883) (xy 121.559584 -232.628039) (xy 121.513568 -232.610587) (xy 121.470947 -232.58598)
			(xy 121.432826 -232.554855) (xy 121.400191 -232.518018) (xy 121.373888 -232.476422) (xy 121.354597 -232.431146)
			(xy 121.34282 -232.383362) (xy 121.33886 -232.334308) (xy 121.009918 -232.334308) (xy 121.009423 -232.358915)
			(xy 121.001528 -232.407492) (xy 120.985944 -232.454173) (xy 120.963073 -232.49775) (xy 120.933508 -232.537094)
			(xy 120.898015 -232.571186) (xy 120.857512 -232.599142) (xy 120.81305 -232.62024) (xy 120.765779 -232.633932)
			(xy 120.716924 -232.639864) (xy 120.667749 -232.637883) (xy 120.61953 -232.628039) (xy 120.573514 -232.610587)
			(xy 120.530893 -232.58598) (xy 120.492772 -232.554855) (xy 120.460137 -232.518018) (xy 120.433834 -232.476422)
			(xy 120.414543 -232.431146) (xy 120.402766 -232.383362) (xy 120.398806 -232.334308) (xy 120.070118 -232.334308)
			(xy 120.069623 -232.358915) (xy 120.061728 -232.407492) (xy 120.046144 -232.454173) (xy 120.023273 -232.49775)
			(xy 119.993708 -232.537094) (xy 119.958215 -232.571186) (xy 119.917712 -232.599142) (xy 119.87325 -232.62024)
			(xy 119.825979 -232.633932) (xy 119.777124 -232.639864) (xy 119.727949 -232.637883) (xy 119.67973 -232.628039)
			(xy 119.633714 -232.610587) (xy 119.591093 -232.58598) (xy 119.552972 -232.554855) (xy 119.520337 -232.518018)
			(xy 119.494034 -232.476422) (xy 119.474743 -232.431146) (xy 119.462966 -232.383362) (xy 119.459006 -232.334308)
			(xy 119.130064 -232.334308) (xy 119.129569 -232.358915) (xy 119.121674 -232.407492) (xy 119.10609 -232.454173)
			(xy 119.083219 -232.49775) (xy 119.053654 -232.537094) (xy 119.018161 -232.571186) (xy 118.977658 -232.599142)
			(xy 118.933196 -232.62024) (xy 118.885925 -232.633932) (xy 118.83707 -232.639864) (xy 118.787895 -232.637883)
			(xy 118.739676 -232.628039) (xy 118.69366 -232.610587) (xy 118.651039 -232.58598) (xy 118.612918 -232.554855)
			(xy 118.580283 -232.518018) (xy 118.55398 -232.476422) (xy 118.534689 -232.431146) (xy 118.522912 -232.383362)
			(xy 118.518952 -232.334308) (xy 118.19001 -232.334308) (xy 118.189515 -232.358915) (xy 118.18162 -232.407492)
			(xy 118.166036 -232.454173) (xy 118.143165 -232.49775) (xy 118.1136 -232.537094) (xy 118.078107 -232.571186)
			(xy 118.037604 -232.599142) (xy 117.993142 -232.62024) (xy 117.945871 -232.633932) (xy 117.897016 -232.639864)
			(xy 117.847841 -232.637883) (xy 117.799622 -232.628039) (xy 117.753606 -232.610587) (xy 117.710985 -232.58598)
			(xy 117.672864 -232.554855) (xy 117.640229 -232.518018) (xy 117.613926 -232.476422) (xy 117.594635 -232.431146)
			(xy 117.582858 -232.383362) (xy 117.578898 -232.334308) (xy 117.249956 -232.334308) (xy 117.249461 -232.358915)
			(xy 117.241566 -232.407492) (xy 117.225982 -232.454173) (xy 117.203111 -232.49775) (xy 117.173546 -232.537094)
			(xy 117.138053 -232.571186) (xy 117.09755 -232.599142) (xy 117.053088 -232.62024) (xy 117.005817 -232.633932)
			(xy 116.956962 -232.639864) (xy 116.907787 -232.637883) (xy 116.859568 -232.628039) (xy 116.813552 -232.610587)
			(xy 116.770931 -232.58598) (xy 116.73281 -232.554855) (xy 116.700175 -232.518018) (xy 116.673872 -232.476422)
			(xy 116.654581 -232.431146) (xy 116.642804 -232.383362) (xy 116.638844 -232.334308) (xy 116.310156 -232.334308)
			(xy 116.309661 -232.358915) (xy 116.301766 -232.407492) (xy 116.286182 -232.454173) (xy 116.263311 -232.49775)
			(xy 116.233746 -232.537094) (xy 116.198253 -232.571186) (xy 116.15775 -232.599142) (xy 116.113288 -232.62024)
			(xy 116.066017 -232.633932) (xy 116.017162 -232.639864) (xy 115.967987 -232.637883) (xy 115.919768 -232.628039)
			(xy 115.873752 -232.610587) (xy 115.831131 -232.58598) (xy 115.79301 -232.554855) (xy 115.760375 -232.518018)
			(xy 115.734072 -232.476422) (xy 115.714781 -232.431146) (xy 115.703004 -232.383362) (xy 115.699044 -232.334308)
			(xy 115.370102 -232.334308) (xy 115.369607 -232.358915) (xy 115.361712 -232.407492) (xy 115.346128 -232.454173)
			(xy 115.323257 -232.49775) (xy 115.293692 -232.537094) (xy 115.258199 -232.571186) (xy 115.217696 -232.599142)
			(xy 115.173234 -232.62024) (xy 115.125963 -232.633932) (xy 115.077108 -232.639864) (xy 115.027933 -232.637883)
			(xy 114.979714 -232.628039) (xy 114.933698 -232.610587) (xy 114.891077 -232.58598) (xy 114.852956 -232.554855)
			(xy 114.820321 -232.518018) (xy 114.794018 -232.476422) (xy 114.774727 -232.431146) (xy 114.76295 -232.383362)
			(xy 114.75899 -232.334308) (xy 114.430048 -232.334308) (xy 114.429553 -232.358915) (xy 114.421658 -232.407492)
			(xy 114.406074 -232.454173) (xy 114.383203 -232.49775) (xy 114.353638 -232.537094) (xy 114.318145 -232.571186)
			(xy 114.277642 -232.599142) (xy 114.23318 -232.62024) (xy 114.185909 -232.633932) (xy 114.137054 -232.639864)
			(xy 114.087879 -232.637883) (xy 114.03966 -232.628039) (xy 113.993644 -232.610587) (xy 113.951023 -232.58598)
			(xy 113.912902 -232.554855) (xy 113.880267 -232.518018) (xy 113.853964 -232.476422) (xy 113.834673 -232.431146)
			(xy 113.822896 -232.383362) (xy 113.818936 -232.334308) (xy 113.489994 -232.334308) (xy 113.489499 -232.358915)
			(xy 113.481604 -232.407492) (xy 113.46602 -232.454173) (xy 113.443149 -232.49775) (xy 113.413584 -232.537094)
			(xy 113.378091 -232.571186) (xy 113.337588 -232.599142) (xy 113.293126 -232.62024) (xy 113.245855 -232.633932)
			(xy 113.197 -232.639864) (xy 113.147825 -232.637883) (xy 113.099606 -232.628039) (xy 113.05359 -232.610587)
			(xy 113.010969 -232.58598) (xy 112.972848 -232.554855) (xy 112.940213 -232.518018) (xy 112.91391 -232.476422)
			(xy 112.894619 -232.431146) (xy 112.882842 -232.383362) (xy 112.878882 -232.334308) (xy 110.676436 -232.334308)
			(xy 110.675941 -232.358915) (xy 110.668046 -232.407492) (xy 110.652462 -232.454173) (xy 110.629591 -232.49775)
			(xy 110.600026 -232.537094) (xy 110.564533 -232.571186) (xy 110.52403 -232.599142) (xy 110.479568 -232.62024)
			(xy 110.432297 -232.633932) (xy 110.383442 -232.639864) (xy 110.334267 -232.637883) (xy 110.286048 -232.628039)
			(xy 110.240032 -232.610587) (xy 110.197411 -232.58598) (xy 110.15929 -232.554855) (xy 110.126655 -232.518018)
			(xy 110.100352 -232.476422) (xy 110.081061 -232.431146) (xy 110.069284 -232.383362) (xy 110.065324 -232.334308)
			(xy 109.736967 -232.334308) (xy 109.732796 -232.384647) (xy 109.720393 -232.43362) (xy 109.700099 -232.479884)
			(xy 109.672466 -232.522177) (xy 109.638249 -232.559344) (xy 109.59838 -232.590371) (xy 109.553948 -232.614413)
			(xy 109.506165 -232.630814) (xy 109.456334 -232.639125) (xy 109.431074 -232.639616) (xy 108.49102 -232.639616)
			(xy 108.465762 -232.639109) (xy 108.415934 -232.630797) (xy 108.368154 -232.614397) (xy 108.323725 -232.590356)
			(xy 108.28386 -232.55933) (xy 108.249645 -232.522165) (xy 108.222014 -232.479875) (xy 108.201721 -232.433614)
			(xy 108.18932 -232.384644) (xy 108.185148 -232.3343) (xy 107.856274 -232.3343) (xy 107.856274 -232.334308)
			(xy 107.855779 -232.358915) (xy 107.847884 -232.407492) (xy 107.8323 -232.454173) (xy 107.809429 -232.49775)
			(xy 107.779864 -232.537094) (xy 107.744371 -232.571186) (xy 107.703868 -232.599142) (xy 107.659406 -232.62024)
			(xy 107.612135 -232.633932) (xy 107.56328 -232.639864) (xy 107.514105 -232.637883) (xy 107.465886 -232.628039)
			(xy 107.41987 -232.610587) (xy 107.377249 -232.58598) (xy 107.339128 -232.554855) (xy 107.306493 -232.518018)
			(xy 107.28019 -232.476422) (xy 107.260899 -232.431146) (xy 107.249122 -232.383362) (xy 107.245162 -232.334308)
			(xy 106.916474 -232.334308) (xy 106.915979 -232.358915) (xy 106.908084 -232.407492) (xy 106.8925 -232.454173)
			(xy 106.869629 -232.49775) (xy 106.840064 -232.537094) (xy 106.804571 -232.571186) (xy 106.764068 -232.599142)
			(xy 106.719606 -232.62024) (xy 106.672335 -232.633932) (xy 106.62348 -232.639864) (xy 106.574305 -232.637883)
			(xy 106.526086 -232.628039) (xy 106.48007 -232.610587) (xy 106.437449 -232.58598) (xy 106.399328 -232.554855)
			(xy 106.366693 -232.518018) (xy 106.34039 -232.476422) (xy 106.321099 -232.431146) (xy 106.309322 -232.383362)
			(xy 106.305362 -232.334308) (xy 105.97642 -232.334308) (xy 105.975925 -232.358915) (xy 105.96803 -232.407492)
			(xy 105.952446 -232.454173) (xy 105.929575 -232.49775) (xy 105.90001 -232.537094) (xy 105.864517 -232.571186)
			(xy 105.824014 -232.599142) (xy 105.779552 -232.62024) (xy 105.732281 -232.633932) (xy 105.683426 -232.639864)
			(xy 105.634251 -232.637883) (xy 105.586032 -232.628039) (xy 105.540016 -232.610587) (xy 105.497395 -232.58598)
			(xy 105.459274 -232.554855) (xy 105.426639 -232.518018) (xy 105.400336 -232.476422) (xy 105.381045 -232.431146)
			(xy 105.369268 -232.383362) (xy 105.365308 -232.334308) (xy 105.036366 -232.334308) (xy 105.035871 -232.358915)
			(xy 105.027976 -232.407492) (xy 105.012392 -232.454173) (xy 104.989521 -232.49775) (xy 104.959956 -232.537094)
			(xy 104.924463 -232.571186) (xy 104.88396 -232.599142) (xy 104.839498 -232.62024) (xy 104.792227 -232.633932)
			(xy 104.743372 -232.639864) (xy 104.694197 -232.637883) (xy 104.645978 -232.628039) (xy 104.599962 -232.610587)
			(xy 104.557341 -232.58598) (xy 104.51922 -232.554855) (xy 104.486585 -232.518018) (xy 104.460282 -232.476422)
			(xy 104.440991 -232.431146) (xy 104.429214 -232.383362) (xy 104.425254 -232.334308) (xy 104.096312 -232.334308)
			(xy 104.095817 -232.358915) (xy 104.087922 -232.407492) (xy 104.072338 -232.454173) (xy 104.049467 -232.49775)
			(xy 104.019902 -232.537094) (xy 103.984409 -232.571186) (xy 103.943906 -232.599142) (xy 103.899444 -232.62024)
			(xy 103.852173 -232.633932) (xy 103.803318 -232.639864) (xy 103.754143 -232.637883) (xy 103.705924 -232.628039)
			(xy 103.659908 -232.610587) (xy 103.617287 -232.58598) (xy 103.579166 -232.554855) (xy 103.546531 -232.518018)
			(xy 103.520228 -232.476422) (xy 103.500937 -232.431146) (xy 103.48916 -232.383362) (xy 103.4852 -232.334308)
			(xy 103.156258 -232.334308) (xy 103.155763 -232.358915) (xy 103.147868 -232.407492) (xy 103.132284 -232.454173)
			(xy 103.109413 -232.49775) (xy 103.079848 -232.537094) (xy 103.044355 -232.571186) (xy 103.003852 -232.599142)
			(xy 102.95939 -232.62024) (xy 102.912119 -232.633932) (xy 102.863264 -232.639864) (xy 102.814089 -232.637883)
			(xy 102.76587 -232.628039) (xy 102.719854 -232.610587) (xy 102.677233 -232.58598) (xy 102.639112 -232.554855)
			(xy 102.606477 -232.518018) (xy 102.580174 -232.476422) (xy 102.560883 -232.431146) (xy 102.549106 -232.383362)
			(xy 102.545146 -232.334308) (xy 102.216458 -232.334308) (xy 102.215963 -232.358915) (xy 102.208068 -232.407492)
			(xy 102.192484 -232.454173) (xy 102.169613 -232.49775) (xy 102.140048 -232.537094) (xy 102.104555 -232.571186)
			(xy 102.064052 -232.599142) (xy 102.01959 -232.62024) (xy 101.972319 -232.633932) (xy 101.923464 -232.639864)
			(xy 101.874289 -232.637883) (xy 101.82607 -232.628039) (xy 101.780054 -232.610587) (xy 101.737433 -232.58598)
			(xy 101.699312 -232.554855) (xy 101.666677 -232.518018) (xy 101.640374 -232.476422) (xy 101.621083 -232.431146)
			(xy 101.609306 -232.383362) (xy 101.605346 -232.334308) (xy 101.276404 -232.334308) (xy 101.275909 -232.358915)
			(xy 101.268014 -232.407492) (xy 101.25243 -232.454173) (xy 101.229559 -232.49775) (xy 101.199994 -232.537094)
			(xy 101.164501 -232.571186) (xy 101.123998 -232.599142) (xy 101.079536 -232.62024) (xy 101.032265 -232.633932)
			(xy 100.98341 -232.639864) (xy 100.934235 -232.637883) (xy 100.886016 -232.628039) (xy 100.84 -232.610587)
			(xy 100.797379 -232.58598) (xy 100.759258 -232.554855) (xy 100.726623 -232.518018) (xy 100.70032 -232.476422)
			(xy 100.681029 -232.431146) (xy 100.669252 -232.383362) (xy 100.665292 -232.334308) (xy 100.33635 -232.334308)
			(xy 100.335855 -232.358915) (xy 100.32796 -232.407492) (xy 100.312376 -232.454173) (xy 100.289505 -232.49775)
			(xy 100.25994 -232.537094) (xy 100.224447 -232.571186) (xy 100.183944 -232.599142) (xy 100.139482 -232.62024)
			(xy 100.092211 -232.633932) (xy 100.043356 -232.639864) (xy 99.994181 -232.637883) (xy 99.945962 -232.628039)
			(xy 99.899946 -232.610587) (xy 99.857325 -232.58598) (xy 99.819204 -232.554855) (xy 99.786569 -232.518018)
			(xy 99.760266 -232.476422) (xy 99.740975 -232.431146) (xy 99.729198 -232.383362) (xy 99.725238 -232.334308)
			(xy 99.396296 -232.334308) (xy 99.395849 -232.3583) (xy 99.388341 -232.405694) (xy 99.373512 -232.45133)
			(xy 99.351726 -232.494084) (xy 99.32352 -232.532904) (xy 99.289589 -232.566833) (xy 99.250767 -232.595037)
			(xy 99.208012 -232.61682) (xy 99.162375 -232.631646) (xy 99.11498 -232.639151) (xy 99.090988 -232.639616)
			(xy 99.080919 -232.640042) (xy 99.062319 -232.647761) (xy 99.05492 -232.654602) (xy 99.036886 -232.672636)
			(xy 99.02949 -232.679487) (xy 99.010891 -232.687226) (xy 99.000818 -232.687622) (xy 97.314258 -232.687622)
			(xy 97.304419 -232.688153) (xy 97.286252 -232.695736) (xy 97.278952 -232.702354) (xy 97.025968 -232.955338)
			(xy 97.02062 -232.961037) (xy 97.013365 -232.974871) (xy 97.011744 -232.982516) (xy 97.010474 -232.989374)
			(xy 97.01276 -233.004868) (xy 97.01657 -233.012742) (xy 97.025982 -233.033473) (xy 97.039254 -233.077022)
			(xy 97.045925 -233.122058) (xy 97.04628 -233.1443) (xy 97.374899 -233.1443) (xy 97.379075 -233.093914)
			(xy 97.391487 -233.044903) (xy 97.411798 -232.998603) (xy 97.439453 -232.956278) (xy 97.473697 -232.919082)
			(xy 97.513597 -232.888031) (xy 97.558064 -232.863971) (xy 97.605885 -232.847559) (xy 97.655755 -232.839242)
			(xy 97.681034 -232.838752) (xy 98.621088 -232.838752) (xy 98.646369 -232.839216) (xy 98.69624 -232.847536)
			(xy 98.744062 -232.863952) (xy 98.78853 -232.888015) (xy 98.828431 -232.91907) (xy 98.862675 -232.956268)
			(xy 98.89033 -232.998596) (xy 98.910641 -233.044898) (xy 98.923053 -233.093912) (xy 98.927229 -233.1443)
			(xy 98.927228 -233.144314) (xy 99.255338 -233.144314) (xy 99.259298 -233.09526) (xy 99.271075 -233.047476)
			(xy 99.290366 -233.0022) (xy 99.316669 -232.960604) (xy 99.349304 -232.923767) (xy 99.387425 -232.892642)
			(xy 99.430046 -232.868035) (xy 99.476062 -232.850583) (xy 99.524281 -232.840739) (xy 99.573456 -232.838758)
			(xy 99.622311 -232.84469) (xy 99.669582 -232.858382) (xy 99.714044 -232.87948) (xy 99.754547 -232.907436)
			(xy 99.79004 -232.941528) (xy 99.819605 -232.980872) (xy 99.842476 -233.024449) (xy 99.85806 -233.07113)
			(xy 99.865955 -233.119707) (xy 99.86645 -233.1443) (xy 100.194799 -233.1443) (xy 100.198975 -233.093913)
			(xy 100.211388 -233.044901) (xy 100.231699 -232.998601) (xy 100.259355 -232.956275) (xy 100.2936 -232.91908)
			(xy 100.333501 -232.888028) (xy 100.377969 -232.863969) (xy 100.425791 -232.847557) (xy 100.475662 -232.839242)
			(xy 100.500942 -232.838752) (xy 101.440996 -232.838752) (xy 101.466276 -232.839217) (xy 101.516147 -232.847538)
			(xy 101.563968 -232.863954) (xy 101.608434 -232.888018) (xy 101.648334 -232.919073) (xy 101.682577 -232.956271)
			(xy 101.710231 -232.998598) (xy 101.730541 -233.044899) (xy 101.742953 -233.093912) (xy 101.747129 -233.1443)
			(xy 101.747128 -233.144314) (xy 102.075246 -233.144314) (xy 102.079206 -233.09526) (xy 102.090983 -233.047476)
			(xy 102.110274 -233.0022) (xy 102.136577 -232.960604) (xy 102.169212 -232.923767) (xy 102.207333 -232.892642)
			(xy 102.249954 -232.868035) (xy 102.29597 -232.850583) (xy 102.344189 -232.840739) (xy 102.393364 -232.838758)
			(xy 102.442219 -232.84469) (xy 102.48949 -232.858382) (xy 102.533952 -232.87948) (xy 102.574455 -232.907436)
			(xy 102.609948 -232.941528) (xy 102.639513 -232.980872) (xy 102.662384 -233.024449) (xy 102.677968 -233.07113)
			(xy 102.685863 -233.119707) (xy 102.686358 -233.1443) (xy 103.014999 -233.1443) (xy 103.019174 -233.093917)
			(xy 103.031585 -233.044909) (xy 103.051893 -232.998611) (xy 103.079545 -232.956288) (xy 103.113785 -232.919093)
			(xy 103.153681 -232.888042) (xy 103.198144 -232.86398) (xy 103.24596 -232.847565) (xy 103.295826 -232.839245)
			(xy 103.321104 -232.838752) (xy 104.261158 -232.838752) (xy 104.28644 -232.839214) (xy 104.336316 -232.84753)
			(xy 104.384142 -232.863943) (xy 104.428614 -232.888005) (xy 104.468519 -232.919059) (xy 104.502768 -232.956258)
			(xy 104.530426 -232.998587) (xy 104.550739 -233.044892) (xy 104.563153 -233.093909) (xy 104.567329 -233.1443)
			(xy 104.567328 -233.144314) (xy 104.895154 -233.144314) (xy 104.899114 -233.09526) (xy 104.910891 -233.047476)
			(xy 104.930182 -233.0022) (xy 104.956485 -232.960604) (xy 104.98912 -232.923767) (xy 105.027241 -232.892642)
			(xy 105.069862 -232.868035) (xy 105.115878 -232.850583) (xy 105.164097 -232.840739) (xy 105.213272 -232.838758)
			(xy 105.262127 -232.84469) (xy 105.309398 -232.858382) (xy 105.35386 -232.87948) (xy 105.394363 -232.907436)
			(xy 105.429856 -232.941528) (xy 105.459421 -232.980872) (xy 105.482292 -233.024449) (xy 105.497876 -233.07113)
			(xy 105.505771 -233.119707) (xy 105.506266 -233.1443) (xy 105.834899 -233.1443) (xy 105.839075 -233.093916)
			(xy 105.851486 -233.044907) (xy 105.871794 -232.998609) (xy 105.899447 -232.956285) (xy 105.933688 -232.91909)
			(xy 105.973585 -232.888039) (xy 106.018049 -232.863978) (xy 106.065867 -232.847564) (xy 106.115734 -232.839244)
			(xy 106.141012 -232.838752) (xy 107.081066 -232.838752) (xy 107.106348 -232.839214) (xy 107.156222 -232.847532)
			(xy 107.204047 -232.863946) (xy 107.248518 -232.888008) (xy 107.288422 -232.919062) (xy 107.32267 -232.956261)
			(xy 107.350327 -232.998589) (xy 107.370639 -233.044893) (xy 107.383053 -233.093909) (xy 107.387229 -233.1443)
			(xy 107.387228 -233.144314) (xy 107.715316 -233.144314) (xy 107.719276 -233.09526) (xy 107.731053 -233.047476)
			(xy 107.750344 -233.0022) (xy 107.776647 -232.960604) (xy 107.809282 -232.923767) (xy 107.847403 -232.892642)
			(xy 107.890024 -232.868035) (xy 107.93604 -232.850583) (xy 107.984259 -232.840739) (xy 108.033434 -232.838758)
			(xy 108.082289 -232.84469) (xy 108.12956 -232.858382) (xy 108.174022 -232.87948) (xy 108.214525 -232.907436)
			(xy 108.250018 -232.941528) (xy 108.279583 -232.980872) (xy 108.302454 -233.024449) (xy 108.318038 -233.07113)
			(xy 108.325933 -233.119707) (xy 108.326428 -233.144314) (xy 108.65537 -233.144314) (xy 108.65933 -233.09526)
			(xy 108.671107 -233.047476) (xy 108.690398 -233.0022) (xy 108.716701 -232.960604) (xy 108.749336 -232.923767)
			(xy 108.787457 -232.892642) (xy 108.830078 -232.868035) (xy 108.876094 -232.850583) (xy 108.924313 -232.840739)
			(xy 108.973488 -232.838758) (xy 109.022343 -232.84469) (xy 109.069614 -232.858382) (xy 109.114076 -232.87948)
			(xy 109.154579 -232.907436) (xy 109.190072 -232.941528) (xy 109.219637 -232.980872) (xy 109.242508 -233.024449)
			(xy 109.258092 -233.07113) (xy 109.265987 -233.119707) (xy 109.266482 -233.144314) (xy 109.59517 -233.144314)
			(xy 109.59913 -233.09526) (xy 109.610907 -233.047476) (xy 109.630198 -233.0022) (xy 109.656501 -232.960604)
			(xy 109.689136 -232.923767) (xy 109.727257 -232.892642) (xy 109.769878 -232.868035) (xy 109.815894 -232.850583)
			(xy 109.864113 -232.840739) (xy 109.913288 -232.838758) (xy 109.962143 -232.84469) (xy 110.009414 -232.858382)
			(xy 110.053876 -232.87948) (xy 110.094379 -232.907436) (xy 110.129872 -232.941528) (xy 110.159437 -232.980872)
			(xy 110.182308 -233.024449) (xy 110.197892 -233.07113) (xy 110.205787 -233.119707) (xy 110.206282 -233.144314)
			(xy 113.349036 -233.144314) (xy 113.352996 -233.09526) (xy 113.364773 -233.047476) (xy 113.384064 -233.0022)
			(xy 113.410367 -232.960604) (xy 113.443002 -232.923767) (xy 113.481123 -232.892642) (xy 113.523744 -232.868035)
			(xy 113.56976 -232.850583) (xy 113.617979 -232.840739) (xy 113.667154 -232.838758) (xy 113.716009 -232.84469)
			(xy 113.76328 -232.858382) (xy 113.807742 -232.87948) (xy 113.848245 -232.907436) (xy 113.883738 -232.941528)
			(xy 113.913303 -232.980872) (xy 113.936174 -233.024449) (xy 113.951758 -233.07113) (xy 113.959653 -233.119707)
			(xy 113.960148 -233.144314) (xy 114.288836 -233.144314) (xy 114.292796 -233.09526) (xy 114.304573 -233.047476)
			(xy 114.323864 -233.0022) (xy 114.350167 -232.960604) (xy 114.382802 -232.923767) (xy 114.420923 -232.892642)
			(xy 114.463544 -232.868035) (xy 114.50956 -232.850583) (xy 114.557779 -232.840739) (xy 114.606954 -232.838758)
			(xy 114.655809 -232.84469) (xy 114.70308 -232.858382) (xy 114.747542 -232.87948) (xy 114.788045 -232.907436)
			(xy 114.823538 -232.941528) (xy 114.853103 -232.980872) (xy 114.875974 -233.024449) (xy 114.891558 -233.07113)
			(xy 114.899453 -233.119707) (xy 114.899948 -233.144314) (xy 115.22889 -233.144314) (xy 115.23285 -233.09526)
			(xy 115.244627 -233.047476) (xy 115.263918 -233.0022) (xy 115.290221 -232.960604) (xy 115.322856 -232.923767)
			(xy 115.360977 -232.892642) (xy 115.403598 -232.868035) (xy 115.449614 -232.850583) (xy 115.497833 -232.840739)
			(xy 115.547008 -232.838758) (xy 115.595863 -232.84469) (xy 115.643134 -232.858382) (xy 115.687596 -232.87948)
			(xy 115.728099 -232.907436) (xy 115.763592 -232.941528) (xy 115.793157 -232.980872) (xy 115.816028 -233.024449)
			(xy 115.831612 -233.07113) (xy 115.839507 -233.119707) (xy 115.840002 -233.144314) (xy 116.168944 -233.144314)
			(xy 116.172904 -233.09526) (xy 116.184681 -233.047476) (xy 116.203972 -233.0022) (xy 116.230275 -232.960604)
			(xy 116.26291 -232.923767) (xy 116.301031 -232.892642) (xy 116.343652 -232.868035) (xy 116.389668 -232.850583)
			(xy 116.437887 -232.840739) (xy 116.487062 -232.838758) (xy 116.535917 -232.84469) (xy 116.583188 -232.858382)
			(xy 116.62765 -232.87948) (xy 116.668153 -232.907436) (xy 116.703646 -232.941528) (xy 116.733211 -232.980872)
			(xy 116.756082 -233.024449) (xy 116.771666 -233.07113) (xy 116.779561 -233.119707) (xy 116.780056 -233.144314)
			(xy 117.108998 -233.144314) (xy 117.112958 -233.09526) (xy 117.124735 -233.047476) (xy 117.144026 -233.0022)
			(xy 117.170329 -232.960604) (xy 117.202964 -232.923767) (xy 117.241085 -232.892642) (xy 117.283706 -232.868035)
			(xy 117.329722 -232.850583) (xy 117.377941 -232.840739) (xy 117.427116 -232.838758) (xy 117.475971 -232.84469)
			(xy 117.523242 -232.858382) (xy 117.567704 -232.87948) (xy 117.608207 -232.907436) (xy 117.6437 -232.941528)
			(xy 117.673265 -232.980872) (xy 117.696136 -233.024449) (xy 117.71172 -233.07113) (xy 117.719615 -233.119707)
			(xy 117.72011 -233.144314) (xy 118.049052 -233.144314) (xy 118.053012 -233.09526) (xy 118.064789 -233.047476)
			(xy 118.08408 -233.0022) (xy 118.110383 -232.960604) (xy 118.143018 -232.923767) (xy 118.181139 -232.892642)
			(xy 118.22376 -232.868035) (xy 118.269776 -232.850583) (xy 118.317995 -232.840739) (xy 118.36717 -232.838758)
			(xy 118.416025 -232.84469) (xy 118.463296 -232.858382) (xy 118.507758 -232.87948) (xy 118.548261 -232.907436)
			(xy 118.583754 -232.941528) (xy 118.613319 -232.980872) (xy 118.63619 -233.024449) (xy 118.651774 -233.07113)
			(xy 118.659669 -233.119707) (xy 118.660164 -233.144314) (xy 118.988852 -233.144314) (xy 118.992812 -233.09526)
			(xy 119.004589 -233.047476) (xy 119.02388 -233.0022) (xy 119.050183 -232.960604) (xy 119.082818 -232.923767)
			(xy 119.120939 -232.892642) (xy 119.16356 -232.868035) (xy 119.209576 -232.850583) (xy 119.257795 -232.840739)
			(xy 119.30697 -232.838758) (xy 119.355825 -232.84469) (xy 119.403096 -232.858382) (xy 119.447558 -232.87948)
			(xy 119.488061 -232.907436) (xy 119.523554 -232.941528) (xy 119.553119 -232.980872) (xy 119.57599 -233.024449)
			(xy 119.591574 -233.07113) (xy 119.599469 -233.119707) (xy 119.599964 -233.144314) (xy 119.928906 -233.144314)
			(xy 119.932866 -233.09526) (xy 119.944643 -233.047476) (xy 119.963934 -233.0022) (xy 119.990237 -232.960604)
			(xy 120.022872 -232.923767) (xy 120.060993 -232.892642) (xy 120.103614 -232.868035) (xy 120.14963 -232.850583)
			(xy 120.197849 -232.840739) (xy 120.247024 -232.838758) (xy 120.295879 -232.84469) (xy 120.34315 -232.858382)
			(xy 120.387612 -232.87948) (xy 120.428115 -232.907436) (xy 120.463608 -232.941528) (xy 120.493173 -232.980872)
			(xy 120.516044 -233.024449) (xy 120.531628 -233.07113) (xy 120.539523 -233.119707) (xy 120.540018 -233.144314)
			(xy 120.86896 -233.144314) (xy 120.87292 -233.09526) (xy 120.884697 -233.047476) (xy 120.903988 -233.0022)
			(xy 120.930291 -232.960604) (xy 120.962926 -232.923767) (xy 121.001047 -232.892642) (xy 121.043668 -232.868035)
			(xy 121.089684 -232.850583) (xy 121.137903 -232.840739) (xy 121.187078 -232.838758) (xy 121.235933 -232.84469)
			(xy 121.283204 -232.858382) (xy 121.327666 -232.87948) (xy 121.368169 -232.907436) (xy 121.403662 -232.941528)
			(xy 121.433227 -232.980872) (xy 121.456098 -233.024449) (xy 121.471682 -233.07113) (xy 121.479577 -233.119707)
			(xy 121.480072 -233.144314) (xy 121.809014 -233.144314) (xy 121.812974 -233.09526) (xy 121.824751 -233.047476)
			(xy 121.844042 -233.0022) (xy 121.870345 -232.960604) (xy 121.90298 -232.923767) (xy 121.941101 -232.892642)
			(xy 121.983722 -232.868035) (xy 122.029738 -232.850583) (xy 122.077957 -232.840739) (xy 122.127132 -232.838758)
			(xy 122.175987 -232.84469) (xy 122.223258 -232.858382) (xy 122.26772 -232.87948) (xy 122.308223 -232.907436)
			(xy 122.343716 -232.941528) (xy 122.373281 -232.980872) (xy 122.396152 -233.024449) (xy 122.411736 -233.07113)
			(xy 122.419631 -233.119707) (xy 122.420126 -233.144314) (xy 122.748814 -233.144314) (xy 122.752774 -233.09526)
			(xy 122.764551 -233.047476) (xy 122.783842 -233.0022) (xy 122.810145 -232.960604) (xy 122.84278 -232.923767)
			(xy 122.880901 -232.892642) (xy 122.923522 -232.868035) (xy 122.969538 -232.850583) (xy 123.017757 -232.840739)
			(xy 123.066932 -232.838758) (xy 123.115787 -232.84469) (xy 123.163058 -232.858382) (xy 123.20752 -232.87948)
			(xy 123.248023 -232.907436) (xy 123.283516 -232.941528) (xy 123.313081 -232.980872) (xy 123.335952 -233.024449)
			(xy 123.351536 -233.07113) (xy 123.359431 -233.119707) (xy 123.359926 -233.144314) (xy 123.688868 -233.144314)
			(xy 123.692828 -233.09526) (xy 123.704605 -233.047476) (xy 123.723896 -233.0022) (xy 123.750199 -232.960604)
			(xy 123.782834 -232.923767) (xy 123.820955 -232.892642) (xy 123.863576 -232.868035) (xy 123.909592 -232.850583)
			(xy 123.957811 -232.840739) (xy 124.006986 -232.838758) (xy 124.055841 -232.84469) (xy 124.103112 -232.858382)
			(xy 124.147574 -232.87948) (xy 124.188077 -232.907436) (xy 124.22357 -232.941528) (xy 124.253135 -232.980872)
			(xy 124.276006 -233.024449) (xy 124.29159 -233.07113) (xy 124.299485 -233.119707) (xy 124.29998 -233.144314)
			(xy 124.628922 -233.144314) (xy 124.632882 -233.09526) (xy 124.644659 -233.047476) (xy 124.66395 -233.0022)
			(xy 124.690253 -232.960604) (xy 124.722888 -232.923767) (xy 124.761009 -232.892642) (xy 124.80363 -232.868035)
			(xy 124.849646 -232.850583) (xy 124.897865 -232.840739) (xy 124.94704 -232.838758) (xy 124.995895 -232.84469)
			(xy 125.043166 -232.858382) (xy 125.087628 -232.87948) (xy 125.128131 -232.907436) (xy 125.163624 -232.941528)
			(xy 125.193189 -232.980872) (xy 125.21606 -233.024449) (xy 125.231644 -233.07113) (xy 125.239539 -233.119707)
			(xy 125.240034 -233.144314) (xy 125.568976 -233.144314) (xy 125.572936 -233.09526) (xy 125.584713 -233.047476)
			(xy 125.604004 -233.0022) (xy 125.630307 -232.960604) (xy 125.662942 -232.923767) (xy 125.701063 -232.892642)
			(xy 125.743684 -232.868035) (xy 125.7897 -232.850583) (xy 125.837919 -232.840739) (xy 125.887094 -232.838758)
			(xy 125.935949 -232.84469) (xy 125.98322 -232.858382) (xy 126.027682 -232.87948) (xy 126.068185 -232.907436)
			(xy 126.103678 -232.941528) (xy 126.133243 -232.980872) (xy 126.156114 -233.024449) (xy 126.171698 -233.07113)
			(xy 126.179593 -233.119707) (xy 126.180088 -233.144314) (xy 126.179593 -233.168921) (xy 126.171698 -233.217498)
			(xy 126.156114 -233.264179) (xy 126.133243 -233.307756) (xy 126.103678 -233.3471) (xy 126.068185 -233.381192)
			(xy 126.027682 -233.409148) (xy 125.98322 -233.430246) (xy 125.935949 -233.443938) (xy 125.887094 -233.44987)
			(xy 125.837919 -233.447889) (xy 125.7897 -233.438045) (xy 125.743684 -233.420593) (xy 125.701063 -233.395986)
			(xy 125.662942 -233.364861) (xy 125.630307 -233.328024) (xy 125.604004 -233.286428) (xy 125.584713 -233.241152)
			(xy 125.572936 -233.193368) (xy 125.568976 -233.144314) (xy 125.240034 -233.144314) (xy 125.239539 -233.168921)
			(xy 125.231644 -233.217498) (xy 125.21606 -233.264179) (xy 125.193189 -233.307756) (xy 125.163624 -233.3471)
			(xy 125.128131 -233.381192) (xy 125.087628 -233.409148) (xy 125.043166 -233.430246) (xy 124.995895 -233.443938)
			(xy 124.94704 -233.44987) (xy 124.897865 -233.447889) (xy 124.849646 -233.438045) (xy 124.80363 -233.420593)
			(xy 124.761009 -233.395986) (xy 124.722888 -233.364861) (xy 124.690253 -233.328024) (xy 124.66395 -233.286428)
			(xy 124.644659 -233.241152) (xy 124.632882 -233.193368) (xy 124.628922 -233.144314) (xy 124.29998 -233.144314)
			(xy 124.299485 -233.168921) (xy 124.29159 -233.217498) (xy 124.276006 -233.264179) (xy 124.253135 -233.307756)
			(xy 124.22357 -233.3471) (xy 124.188077 -233.381192) (xy 124.147574 -233.409148) (xy 124.103112 -233.430246)
			(xy 124.055841 -233.443938) (xy 124.006986 -233.44987) (xy 123.957811 -233.447889) (xy 123.909592 -233.438045)
			(xy 123.863576 -233.420593) (xy 123.820955 -233.395986) (xy 123.782834 -233.364861) (xy 123.750199 -233.328024)
			(xy 123.723896 -233.286428) (xy 123.704605 -233.241152) (xy 123.692828 -233.193368) (xy 123.688868 -233.144314)
			(xy 123.359926 -233.144314) (xy 123.359431 -233.168921) (xy 123.351536 -233.217498) (xy 123.335952 -233.264179)
			(xy 123.313081 -233.307756) (xy 123.283516 -233.3471) (xy 123.248023 -233.381192) (xy 123.20752 -233.409148)
			(xy 123.163058 -233.430246) (xy 123.115787 -233.443938) (xy 123.066932 -233.44987) (xy 123.017757 -233.447889)
			(xy 122.969538 -233.438045) (xy 122.923522 -233.420593) (xy 122.880901 -233.395986) (xy 122.84278 -233.364861)
			(xy 122.810145 -233.328024) (xy 122.783842 -233.286428) (xy 122.764551 -233.241152) (xy 122.752774 -233.193368)
			(xy 122.748814 -233.144314) (xy 122.420126 -233.144314) (xy 122.419631 -233.168921) (xy 122.411736 -233.217498)
			(xy 122.396152 -233.264179) (xy 122.373281 -233.307756) (xy 122.343716 -233.3471) (xy 122.308223 -233.381192)
			(xy 122.26772 -233.409148) (xy 122.223258 -233.430246) (xy 122.175987 -233.443938) (xy 122.127132 -233.44987)
			(xy 122.077957 -233.447889) (xy 122.029738 -233.438045) (xy 121.983722 -233.420593) (xy 121.941101 -233.395986)
			(xy 121.90298 -233.364861) (xy 121.870345 -233.328024) (xy 121.844042 -233.286428) (xy 121.824751 -233.241152)
			(xy 121.812974 -233.193368) (xy 121.809014 -233.144314) (xy 121.480072 -233.144314) (xy 121.479577 -233.168921)
			(xy 121.471682 -233.217498) (xy 121.456098 -233.264179) (xy 121.433227 -233.307756) (xy 121.403662 -233.3471)
			(xy 121.368169 -233.381192) (xy 121.327666 -233.409148) (xy 121.283204 -233.430246) (xy 121.235933 -233.443938)
			(xy 121.187078 -233.44987) (xy 121.137903 -233.447889) (xy 121.089684 -233.438045) (xy 121.043668 -233.420593)
			(xy 121.001047 -233.395986) (xy 120.962926 -233.364861) (xy 120.930291 -233.328024) (xy 120.903988 -233.286428)
			(xy 120.884697 -233.241152) (xy 120.87292 -233.193368) (xy 120.86896 -233.144314) (xy 120.540018 -233.144314)
			(xy 120.539523 -233.168921) (xy 120.531628 -233.217498) (xy 120.516044 -233.264179) (xy 120.493173 -233.307756)
			(xy 120.463608 -233.3471) (xy 120.428115 -233.381192) (xy 120.387612 -233.409148) (xy 120.34315 -233.430246)
			(xy 120.295879 -233.443938) (xy 120.247024 -233.44987) (xy 120.197849 -233.447889) (xy 120.14963 -233.438045)
			(xy 120.103614 -233.420593) (xy 120.060993 -233.395986) (xy 120.022872 -233.364861) (xy 119.990237 -233.328024)
			(xy 119.963934 -233.286428) (xy 119.944643 -233.241152) (xy 119.932866 -233.193368) (xy 119.928906 -233.144314)
			(xy 119.599964 -233.144314) (xy 119.599469 -233.168921) (xy 119.591574 -233.217498) (xy 119.57599 -233.264179)
			(xy 119.553119 -233.307756) (xy 119.523554 -233.3471) (xy 119.488061 -233.381192) (xy 119.447558 -233.409148)
			(xy 119.403096 -233.430246) (xy 119.355825 -233.443938) (xy 119.30697 -233.44987) (xy 119.257795 -233.447889)
			(xy 119.209576 -233.438045) (xy 119.16356 -233.420593) (xy 119.120939 -233.395986) (xy 119.082818 -233.364861)
			(xy 119.050183 -233.328024) (xy 119.02388 -233.286428) (xy 119.004589 -233.241152) (xy 118.992812 -233.193368)
			(xy 118.988852 -233.144314) (xy 118.660164 -233.144314) (xy 118.659669 -233.168921) (xy 118.651774 -233.217498)
			(xy 118.63619 -233.264179) (xy 118.613319 -233.307756) (xy 118.583754 -233.3471) (xy 118.548261 -233.381192)
			(xy 118.507758 -233.409148) (xy 118.463296 -233.430246) (xy 118.416025 -233.443938) (xy 118.36717 -233.44987)
			(xy 118.317995 -233.447889) (xy 118.269776 -233.438045) (xy 118.22376 -233.420593) (xy 118.181139 -233.395986)
			(xy 118.143018 -233.364861) (xy 118.110383 -233.328024) (xy 118.08408 -233.286428) (xy 118.064789 -233.241152)
			(xy 118.053012 -233.193368) (xy 118.049052 -233.144314) (xy 117.72011 -233.144314) (xy 117.719615 -233.168921)
			(xy 117.71172 -233.217498) (xy 117.696136 -233.264179) (xy 117.673265 -233.307756) (xy 117.6437 -233.3471)
			(xy 117.608207 -233.381192) (xy 117.567704 -233.409148) (xy 117.523242 -233.430246) (xy 117.475971 -233.443938)
			(xy 117.427116 -233.44987) (xy 117.377941 -233.447889) (xy 117.329722 -233.438045) (xy 117.283706 -233.420593)
			(xy 117.241085 -233.395986) (xy 117.202964 -233.364861) (xy 117.170329 -233.328024) (xy 117.144026 -233.286428)
			(xy 117.124735 -233.241152) (xy 117.112958 -233.193368) (xy 117.108998 -233.144314) (xy 116.780056 -233.144314)
			(xy 116.779561 -233.168921) (xy 116.771666 -233.217498) (xy 116.756082 -233.264179) (xy 116.733211 -233.307756)
			(xy 116.703646 -233.3471) (xy 116.668153 -233.381192) (xy 116.62765 -233.409148) (xy 116.583188 -233.430246)
			(xy 116.535917 -233.443938) (xy 116.487062 -233.44987) (xy 116.437887 -233.447889) (xy 116.389668 -233.438045)
			(xy 116.343652 -233.420593) (xy 116.301031 -233.395986) (xy 116.26291 -233.364861) (xy 116.230275 -233.328024)
			(xy 116.203972 -233.286428) (xy 116.184681 -233.241152) (xy 116.172904 -233.193368) (xy 116.168944 -233.144314)
			(xy 115.840002 -233.144314) (xy 115.839507 -233.168921) (xy 115.831612 -233.217498) (xy 115.816028 -233.264179)
			(xy 115.793157 -233.307756) (xy 115.763592 -233.3471) (xy 115.728099 -233.381192) (xy 115.687596 -233.409148)
			(xy 115.643134 -233.430246) (xy 115.595863 -233.443938) (xy 115.547008 -233.44987) (xy 115.497833 -233.447889)
			(xy 115.449614 -233.438045) (xy 115.403598 -233.420593) (xy 115.360977 -233.395986) (xy 115.322856 -233.364861)
			(xy 115.290221 -233.328024) (xy 115.263918 -233.286428) (xy 115.244627 -233.241152) (xy 115.23285 -233.193368)
			(xy 115.22889 -233.144314) (xy 114.899948 -233.144314) (xy 114.899453 -233.168921) (xy 114.891558 -233.217498)
			(xy 114.875974 -233.264179) (xy 114.853103 -233.307756) (xy 114.823538 -233.3471) (xy 114.788045 -233.381192)
			(xy 114.747542 -233.409148) (xy 114.70308 -233.430246) (xy 114.655809 -233.443938) (xy 114.606954 -233.44987)
			(xy 114.557779 -233.447889) (xy 114.50956 -233.438045) (xy 114.463544 -233.420593) (xy 114.420923 -233.395986)
			(xy 114.382802 -233.364861) (xy 114.350167 -233.328024) (xy 114.323864 -233.286428) (xy 114.304573 -233.241152)
			(xy 114.292796 -233.193368) (xy 114.288836 -233.144314) (xy 113.960148 -233.144314) (xy 113.959653 -233.168921)
			(xy 113.951758 -233.217498) (xy 113.936174 -233.264179) (xy 113.913303 -233.307756) (xy 113.883738 -233.3471)
			(xy 113.848245 -233.381192) (xy 113.807742 -233.409148) (xy 113.76328 -233.430246) (xy 113.716009 -233.443938)
			(xy 113.667154 -233.44987) (xy 113.617979 -233.447889) (xy 113.56976 -233.438045) (xy 113.523744 -233.420593)
			(xy 113.481123 -233.395986) (xy 113.443002 -233.364861) (xy 113.410367 -233.328024) (xy 113.384064 -233.286428)
			(xy 113.364773 -233.241152) (xy 113.352996 -233.193368) (xy 113.349036 -233.144314) (xy 110.206282 -233.144314)
			(xy 110.205787 -233.168921) (xy 110.197892 -233.217498) (xy 110.182308 -233.264179) (xy 110.159437 -233.307756)
			(xy 110.129872 -233.3471) (xy 110.094379 -233.381192) (xy 110.053876 -233.409148) (xy 110.009414 -233.430246)
			(xy 109.962143 -233.443938) (xy 109.913288 -233.44987) (xy 109.864113 -233.447889) (xy 109.815894 -233.438045)
			(xy 109.769878 -233.420593) (xy 109.727257 -233.395986) (xy 109.689136 -233.364861) (xy 109.656501 -233.328024)
			(xy 109.630198 -233.286428) (xy 109.610907 -233.241152) (xy 109.59913 -233.193368) (xy 109.59517 -233.144314)
			(xy 109.266482 -233.144314) (xy 109.265987 -233.168921) (xy 109.258092 -233.217498) (xy 109.242508 -233.264179)
			(xy 109.219637 -233.307756) (xy 109.190072 -233.3471) (xy 109.154579 -233.381192) (xy 109.114076 -233.409148)
			(xy 109.069614 -233.430246) (xy 109.022343 -233.443938) (xy 108.973488 -233.44987) (xy 108.924313 -233.447889)
			(xy 108.876094 -233.438045) (xy 108.830078 -233.420593) (xy 108.787457 -233.395986) (xy 108.749336 -233.364861)
			(xy 108.716701 -233.328024) (xy 108.690398 -233.286428) (xy 108.671107 -233.241152) (xy 108.65933 -233.193368)
			(xy 108.65537 -233.144314) (xy 108.326428 -233.144314) (xy 108.325933 -233.168921) (xy 108.318038 -233.217498)
			(xy 108.302454 -233.264179) (xy 108.279583 -233.307756) (xy 108.250018 -233.3471) (xy 108.214525 -233.381192)
			(xy 108.174022 -233.409148) (xy 108.12956 -233.430246) (xy 108.082289 -233.443938) (xy 108.033434 -233.44987)
			(xy 107.984259 -233.447889) (xy 107.93604 -233.438045) (xy 107.890024 -233.420593) (xy 107.847403 -233.395986)
			(xy 107.809282 -233.364861) (xy 107.776647 -233.328024) (xy 107.750344 -233.286428) (xy 107.731053 -233.241152)
			(xy 107.719276 -233.193368) (xy 107.715316 -233.144314) (xy 107.387228 -233.144314) (xy 107.383053 -233.194691)
			(xy 107.370639 -233.243707) (xy 107.350327 -233.290011) (xy 107.32267 -233.332339) (xy 107.288422 -233.369538)
			(xy 107.248518 -233.400592) (xy 107.204047 -233.424654) (xy 107.156222 -233.441068) (xy 107.106348 -233.449386)
			(xy 107.081066 -233.449876) (xy 106.141012 -233.449876) (xy 106.115734 -233.449356) (xy 106.065867 -233.441036)
			(xy 106.018049 -233.424622) (xy 105.973585 -233.400561) (xy 105.933688 -233.36951) (xy 105.899447 -233.332315)
			(xy 105.871794 -233.289991) (xy 105.851486 -233.243693) (xy 105.839075 -233.194684) (xy 105.834899 -233.1443)
			(xy 105.506266 -233.1443) (xy 105.506266 -233.144314) (xy 105.505771 -233.168921) (xy 105.497876 -233.217498)
			(xy 105.482292 -233.264179) (xy 105.459421 -233.307756) (xy 105.429856 -233.3471) (xy 105.394363 -233.381192)
			(xy 105.35386 -233.409148) (xy 105.309398 -233.430246) (xy 105.262127 -233.443938) (xy 105.213272 -233.44987)
			(xy 105.164097 -233.447889) (xy 105.115878 -233.438045) (xy 105.069862 -233.420593) (xy 105.027241 -233.395986)
			(xy 104.98912 -233.364861) (xy 104.956485 -233.328024) (xy 104.930182 -233.286428) (xy 104.910891 -233.241152)
			(xy 104.899114 -233.193368) (xy 104.895154 -233.144314) (xy 104.567328 -233.144314) (xy 104.563153 -233.194691)
			(xy 104.550739 -233.243708) (xy 104.530426 -233.290013) (xy 104.502768 -233.332342) (xy 104.468519 -233.369541)
			(xy 104.428614 -233.400595) (xy 104.384142 -233.424657) (xy 104.336316 -233.44107) (xy 104.28644 -233.449386)
			(xy 104.261158 -233.449876) (xy 103.321104 -233.449876) (xy 103.295826 -233.449355) (xy 103.24596 -233.441035)
			(xy 103.198144 -233.42462) (xy 103.153681 -233.400558) (xy 103.113785 -233.369507) (xy 103.079545 -233.332312)
			(xy 103.051893 -233.289989) (xy 103.031585 -233.243691) (xy 103.019174 -233.194683) (xy 103.014999 -233.1443)
			(xy 102.686358 -233.1443) (xy 102.686358 -233.144314) (xy 102.685863 -233.168921) (xy 102.677968 -233.217498)
			(xy 102.662384 -233.264179) (xy 102.639513 -233.307756) (xy 102.609948 -233.3471) (xy 102.574455 -233.381192)
			(xy 102.533952 -233.409148) (xy 102.48949 -233.430246) (xy 102.442219 -233.443938) (xy 102.393364 -233.44987)
			(xy 102.344189 -233.447889) (xy 102.29597 -233.438045) (xy 102.249954 -233.420593) (xy 102.207333 -233.395986)
			(xy 102.169212 -233.364861) (xy 102.136577 -233.328024) (xy 102.110274 -233.286428) (xy 102.090983 -233.241152)
			(xy 102.079206 -233.193368) (xy 102.075246 -233.144314) (xy 101.747128 -233.144314) (xy 101.742953 -233.194688)
			(xy 101.730541 -233.243701) (xy 101.710231 -233.290002) (xy 101.682577 -233.332329) (xy 101.648334 -233.369527)
			(xy 101.608434 -233.400582) (xy 101.563968 -233.424646) (xy 101.516147 -233.441062) (xy 101.466276 -233.449383)
			(xy 101.440996 -233.449876) (xy 100.500942 -233.449876) (xy 100.475662 -233.449358) (xy 100.425791 -233.441043)
			(xy 100.377969 -233.424631) (xy 100.333501 -233.400572) (xy 100.2936 -233.36952) (xy 100.259355 -233.332325)
			(xy 100.231699 -233.289999) (xy 100.211388 -233.243699) (xy 100.198975 -233.194687) (xy 100.194799 -233.1443)
			(xy 99.86645 -233.1443) (xy 99.86645 -233.144314) (xy 99.865955 -233.168921) (xy 99.85806 -233.217498)
			(xy 99.842476 -233.264179) (xy 99.819605 -233.307756) (xy 99.79004 -233.3471) (xy 99.754547 -233.381192)
			(xy 99.714044 -233.409148) (xy 99.669582 -233.430246) (xy 99.622311 -233.443938) (xy 99.573456 -233.44987)
			(xy 99.524281 -233.447889) (xy 99.476062 -233.438045) (xy 99.430046 -233.420593) (xy 99.387425 -233.395986)
			(xy 99.349304 -233.364861) (xy 99.316669 -233.328024) (xy 99.290366 -233.286428) (xy 99.271075 -233.241152)
			(xy 99.259298 -233.193368) (xy 99.255338 -233.144314) (xy 98.927228 -233.144314) (xy 98.923053 -233.194688)
			(xy 98.910641 -233.243702) (xy 98.89033 -233.290004) (xy 98.862675 -233.332332) (xy 98.828431 -233.36953)
			(xy 98.78853 -233.400585) (xy 98.744062 -233.424648) (xy 98.69624 -233.441064) (xy 98.646369 -233.449384)
			(xy 98.621088 -233.449876) (xy 97.681034 -233.449876) (xy 97.655755 -233.449358) (xy 97.605885 -233.441041)
			(xy 97.558064 -233.424629) (xy 97.513597 -233.400569) (xy 97.473697 -233.369518) (xy 97.439453 -233.332322)
			(xy 97.411798 -233.289997) (xy 97.391487 -233.243697) (xy 97.379075 -233.194686) (xy 97.374899 -233.1443)
			(xy 97.04628 -233.1443) (xy 97.046288 -233.144822) (xy 97.046288 -233.149394) (xy 97.045441 -233.17312)
			(xy 97.037309 -233.219892) (xy 97.022034 -233.264841) (xy 96.999984 -233.306883) (xy 96.97169 -233.345004)
			(xy 96.937836 -233.378285) (xy 96.899237 -233.405923) (xy 96.856824 -233.427252) (xy 96.811621 -233.441757)
			(xy 96.764717 -233.449089) (xy 96.74098 -233.449622) (xy 96.740472 -233.449622) (xy 96.717878 -233.449194)
			(xy 96.673189 -233.442487) (xy 96.629981 -233.429254) (xy 96.609408 -233.419904) (xy 96.6089 -233.41965)
			(xy 96.601656 -233.416476) (xy 96.586003 -233.414272) (xy 96.578166 -233.415332) (xy 96.571562 -233.416602)
			(xy 96.557592 -233.423714) (xy 96.4311 -233.550206) (xy 96.42403 -233.557982) (xy 96.416415 -233.577543)
			(xy 96.416368 -233.588052) (xy 96.41967 -233.623358) (xy 96.42348 -233.666284) (xy 96.424141 -233.671903)
			(xy 96.427594 -233.682673) (xy 96.430338 -233.68762) (xy 96.435672 -233.696764) (xy 96.44507 -233.703368)
			(xy 96.464962 -233.717775) (xy 96.500307 -233.751874) (xy 96.529746 -233.791184) (xy 96.552522 -233.834696)
			(xy 96.568049 -233.881288) (xy 96.575929 -233.929764) (xy 96.576388 -233.95432) (xy 98.785184 -233.95432)
			(xy 98.789144 -233.905266) (xy 98.800921 -233.857482) (xy 98.820212 -233.812206) (xy 98.846515 -233.77061)
			(xy 98.87915 -233.733773) (xy 98.917271 -233.702648) (xy 98.959892 -233.678041) (xy 99.005908 -233.660589)
			(xy 99.054127 -233.650745) (xy 99.103302 -233.648764) (xy 99.152157 -233.654696) (xy 99.199428 -233.668388)
			(xy 99.24389 -233.689486) (xy 99.284393 -233.717442) (xy 99.319886 -233.751534) (xy 99.349451 -233.790878)
			(xy 99.372322 -233.834455) (xy 99.387906 -233.881136) (xy 99.395801 -233.929713) (xy 99.396296 -233.95432)
			(xy 101.605346 -233.95432) (xy 101.609306 -233.905266) (xy 101.621083 -233.857482) (xy 101.640374 -233.812206)
			(xy 101.666677 -233.77061) (xy 101.699312 -233.733773) (xy 101.737433 -233.702648) (xy 101.780054 -233.678041)
			(xy 101.82607 -233.660589) (xy 101.874289 -233.650745) (xy 101.923464 -233.648764) (xy 101.972319 -233.654696)
			(xy 102.01959 -233.668388) (xy 102.064052 -233.689486) (xy 102.104555 -233.717442) (xy 102.140048 -233.751534)
			(xy 102.169613 -233.790878) (xy 102.192484 -233.834455) (xy 102.208068 -233.881136) (xy 102.215963 -233.929713)
			(xy 102.216458 -233.95432) (xy 104.425254 -233.95432) (xy 104.429214 -233.905266) (xy 104.440991 -233.857482)
			(xy 104.460282 -233.812206) (xy 104.486585 -233.77061) (xy 104.51922 -233.733773) (xy 104.557341 -233.702648)
			(xy 104.599962 -233.678041) (xy 104.645978 -233.660589) (xy 104.694197 -233.650745) (xy 104.743372 -233.648764)
			(xy 104.792227 -233.654696) (xy 104.839498 -233.668388) (xy 104.88396 -233.689486) (xy 104.924463 -233.717442)
			(xy 104.959956 -233.751534) (xy 104.989521 -233.790878) (xy 105.012392 -233.834455) (xy 105.027976 -233.881136)
			(xy 105.035871 -233.929713) (xy 105.036366 -233.95432) (xy 107.245162 -233.95432) (xy 107.249122 -233.905266)
			(xy 107.260899 -233.857482) (xy 107.28019 -233.812206) (xy 107.306493 -233.77061) (xy 107.339128 -233.733773)
			(xy 107.377249 -233.702648) (xy 107.41987 -233.678041) (xy 107.465886 -233.660589) (xy 107.514105 -233.650745)
			(xy 107.56328 -233.648764) (xy 107.612135 -233.654696) (xy 107.659406 -233.668388) (xy 107.703868 -233.689486)
			(xy 107.744371 -233.717442) (xy 107.779864 -233.751534) (xy 107.809429 -233.790878) (xy 107.8323 -233.834455)
			(xy 107.847884 -233.881136) (xy 107.855779 -233.929713) (xy 107.856274 -233.9543) (xy 108.18516 -233.9543)
			(xy 108.189332 -233.903958) (xy 108.201733 -233.85499) (xy 108.222025 -233.808731) (xy 108.249654 -233.766443)
			(xy 108.283868 -233.729279) (xy 108.323732 -233.698254) (xy 108.368159 -233.674214) (xy 108.415937 -233.657814)
			(xy 108.465763 -233.649503) (xy 108.49102 -233.649012) (xy 109.431074 -233.649012) (xy 109.456335 -233.649463)
			(xy 109.506168 -233.657774) (xy 109.553953 -233.674176) (xy 109.598387 -233.698219) (xy 109.638257 -233.729247)
			(xy 109.672476 -233.766416) (xy 109.70011 -233.80871) (xy 109.720405 -233.854976) (xy 109.732808 -233.903951)
			(xy 109.73698 -233.9543) (xy 109.736978 -233.95432) (xy 110.065324 -233.95432) (xy 110.069284 -233.905266)
			(xy 110.081061 -233.857482) (xy 110.100352 -233.812206) (xy 110.126655 -233.77061) (xy 110.15929 -233.733773)
			(xy 110.197411 -233.702648) (xy 110.240032 -233.678041) (xy 110.286048 -233.660589) (xy 110.334267 -233.650745)
			(xy 110.383442 -233.648764) (xy 110.432297 -233.654696) (xy 110.479568 -233.668388) (xy 110.52403 -233.689486)
			(xy 110.564533 -233.717442) (xy 110.600026 -233.751534) (xy 110.629591 -233.790878) (xy 110.652462 -233.834455)
			(xy 110.668046 -233.881136) (xy 110.675941 -233.929713) (xy 110.676436 -233.95432) (xy 112.878882 -233.95432)
			(xy 112.882842 -233.905266) (xy 112.894619 -233.857482) (xy 112.91391 -233.812206) (xy 112.940213 -233.77061)
			(xy 112.972848 -233.733773) (xy 113.010969 -233.702648) (xy 113.05359 -233.678041) (xy 113.099606 -233.660589)
			(xy 113.147825 -233.650745) (xy 113.197 -233.648764) (xy 113.245855 -233.654696) (xy 113.293126 -233.668388)
			(xy 113.337588 -233.689486) (xy 113.378091 -233.717442) (xy 113.413584 -233.751534) (xy 113.443149 -233.790878)
			(xy 113.46602 -233.834455) (xy 113.481604 -233.881136) (xy 113.489499 -233.929713) (xy 113.489994 -233.95432)
			(xy 113.818936 -233.95432) (xy 113.822896 -233.905266) (xy 113.834673 -233.857482) (xy 113.853964 -233.812206)
			(xy 113.880267 -233.77061) (xy 113.912902 -233.733773) (xy 113.951023 -233.702648) (xy 113.993644 -233.678041)
			(xy 114.03966 -233.660589) (xy 114.087879 -233.650745) (xy 114.137054 -233.648764) (xy 114.185909 -233.654696)
			(xy 114.23318 -233.668388) (xy 114.277642 -233.689486) (xy 114.318145 -233.717442) (xy 114.353638 -233.751534)
			(xy 114.383203 -233.790878) (xy 114.406074 -233.834455) (xy 114.421658 -233.881136) (xy 114.429553 -233.929713)
			(xy 114.430048 -233.95432) (xy 114.75899 -233.95432) (xy 114.76295 -233.905266) (xy 114.774727 -233.857482)
			(xy 114.794018 -233.812206) (xy 114.820321 -233.77061) (xy 114.852956 -233.733773) (xy 114.891077 -233.702648)
			(xy 114.933698 -233.678041) (xy 114.979714 -233.660589) (xy 115.027933 -233.650745) (xy 115.077108 -233.648764)
			(xy 115.125963 -233.654696) (xy 115.173234 -233.668388) (xy 115.217696 -233.689486) (xy 115.258199 -233.717442)
			(xy 115.293692 -233.751534) (xy 115.323257 -233.790878) (xy 115.346128 -233.834455) (xy 115.361712 -233.881136)
			(xy 115.369607 -233.929713) (xy 115.370102 -233.95432) (xy 115.699044 -233.95432) (xy 115.703004 -233.905266)
			(xy 115.714781 -233.857482) (xy 115.734072 -233.812206) (xy 115.760375 -233.77061) (xy 115.79301 -233.733773)
			(xy 115.831131 -233.702648) (xy 115.873752 -233.678041) (xy 115.919768 -233.660589) (xy 115.967987 -233.650745)
			(xy 116.017162 -233.648764) (xy 116.066017 -233.654696) (xy 116.113288 -233.668388) (xy 116.15775 -233.689486)
			(xy 116.198253 -233.717442) (xy 116.233746 -233.751534) (xy 116.263311 -233.790878) (xy 116.286182 -233.834455)
			(xy 116.301766 -233.881136) (xy 116.309661 -233.929713) (xy 116.310156 -233.95432) (xy 118.518952 -233.95432)
			(xy 118.522912 -233.905266) (xy 118.534689 -233.857482) (xy 118.55398 -233.812206) (xy 118.580283 -233.77061)
			(xy 118.612918 -233.733773) (xy 118.651039 -233.702648) (xy 118.69366 -233.678041) (xy 118.739676 -233.660589)
			(xy 118.787895 -233.650745) (xy 118.83707 -233.648764) (xy 118.885925 -233.654696) (xy 118.933196 -233.668388)
			(xy 118.977658 -233.689486) (xy 119.018161 -233.717442) (xy 119.053654 -233.751534) (xy 119.083219 -233.790878)
			(xy 119.10609 -233.834455) (xy 119.121674 -233.881136) (xy 119.129569 -233.929713) (xy 119.130064 -233.95432)
			(xy 121.33886 -233.95432) (xy 121.34282 -233.905266) (xy 121.354597 -233.857482) (xy 121.373888 -233.812206)
			(xy 121.400191 -233.77061) (xy 121.432826 -233.733773) (xy 121.470947 -233.702648) (xy 121.513568 -233.678041)
			(xy 121.559584 -233.660589) (xy 121.607803 -233.650745) (xy 121.656978 -233.648764) (xy 121.705833 -233.654696)
			(xy 121.753104 -233.668388) (xy 121.797566 -233.689486) (xy 121.838069 -233.717442) (xy 121.873562 -233.751534)
			(xy 121.903127 -233.790878) (xy 121.925998 -233.834455) (xy 121.941582 -233.881136) (xy 121.949477 -233.929713)
			(xy 121.949972 -233.95432) (xy 124.159022 -233.95432) (xy 124.162982 -233.905266) (xy 124.174759 -233.857482)
			(xy 124.19405 -233.812206) (xy 124.220353 -233.77061) (xy 124.252988 -233.733773) (xy 124.291109 -233.702648)
			(xy 124.33373 -233.678041) (xy 124.379746 -233.660589) (xy 124.427965 -233.650745) (xy 124.47714 -233.648764)
			(xy 124.525995 -233.654696) (xy 124.573266 -233.668388) (xy 124.617728 -233.689486) (xy 124.658231 -233.717442)
			(xy 124.693724 -233.751534) (xy 124.723289 -233.790878) (xy 124.74616 -233.834455) (xy 124.761744 -233.881136)
			(xy 124.769639 -233.929713) (xy 124.770134 -233.95432) (xy 124.769639 -233.978927) (xy 124.761744 -234.027504)
			(xy 124.74616 -234.074185) (xy 124.723289 -234.117762) (xy 124.693724 -234.157106) (xy 124.658231 -234.191198)
			(xy 124.617728 -234.219154) (xy 124.573266 -234.240252) (xy 124.525995 -234.253944) (xy 124.47714 -234.259876)
			(xy 124.427965 -234.257895) (xy 124.379746 -234.248051) (xy 124.33373 -234.230599) (xy 124.291109 -234.205992)
			(xy 124.252988 -234.174867) (xy 124.220353 -234.13803) (xy 124.19405 -234.096434) (xy 124.174759 -234.051158)
			(xy 124.162982 -234.003374) (xy 124.159022 -233.95432) (xy 121.949972 -233.95432) (xy 121.949477 -233.978927)
			(xy 121.941582 -234.027504) (xy 121.925998 -234.074185) (xy 121.903127 -234.117762) (xy 121.873562 -234.157106)
			(xy 121.838069 -234.191198) (xy 121.797566 -234.219154) (xy 121.753104 -234.240252) (xy 121.705833 -234.253944)
			(xy 121.656978 -234.259876) (xy 121.607803 -234.257895) (xy 121.559584 -234.248051) (xy 121.513568 -234.230599)
			(xy 121.470947 -234.205992) (xy 121.432826 -234.174867) (xy 121.400191 -234.13803) (xy 121.373888 -234.096434)
			(xy 121.354597 -234.051158) (xy 121.34282 -234.003374) (xy 121.33886 -233.95432) (xy 119.130064 -233.95432)
			(xy 119.129569 -233.978927) (xy 119.121674 -234.027504) (xy 119.10609 -234.074185) (xy 119.083219 -234.117762)
			(xy 119.053654 -234.157106) (xy 119.018161 -234.191198) (xy 118.977658 -234.219154) (xy 118.933196 -234.240252)
			(xy 118.885925 -234.253944) (xy 118.83707 -234.259876) (xy 118.787895 -234.257895) (xy 118.739676 -234.248051)
			(xy 118.69366 -234.230599) (xy 118.651039 -234.205992) (xy 118.612918 -234.174867) (xy 118.580283 -234.13803)
			(xy 118.55398 -234.096434) (xy 118.534689 -234.051158) (xy 118.522912 -234.003374) (xy 118.518952 -233.95432)
			(xy 116.310156 -233.95432) (xy 116.309661 -233.978927) (xy 116.301766 -234.027504) (xy 116.286182 -234.074185)
			(xy 116.263311 -234.117762) (xy 116.233746 -234.157106) (xy 116.198253 -234.191198) (xy 116.15775 -234.219154)
			(xy 116.113288 -234.240252) (xy 116.066017 -234.253944) (xy 116.017162 -234.259876) (xy 115.967987 -234.257895)
			(xy 115.919768 -234.248051) (xy 115.873752 -234.230599) (xy 115.831131 -234.205992) (xy 115.79301 -234.174867)
			(xy 115.760375 -234.13803) (xy 115.734072 -234.096434) (xy 115.714781 -234.051158) (xy 115.703004 -234.003374)
			(xy 115.699044 -233.95432) (xy 115.370102 -233.95432) (xy 115.369607 -233.978927) (xy 115.361712 -234.027504)
			(xy 115.346128 -234.074185) (xy 115.323257 -234.117762) (xy 115.293692 -234.157106) (xy 115.258199 -234.191198)
			(xy 115.217696 -234.219154) (xy 115.173234 -234.240252) (xy 115.125963 -234.253944) (xy 115.077108 -234.259876)
			(xy 115.027933 -234.257895) (xy 114.979714 -234.248051) (xy 114.933698 -234.230599) (xy 114.891077 -234.205992)
			(xy 114.852956 -234.174867) (xy 114.820321 -234.13803) (xy 114.794018 -234.096434) (xy 114.774727 -234.051158)
			(xy 114.76295 -234.003374) (xy 114.75899 -233.95432) (xy 114.430048 -233.95432) (xy 114.429553 -233.978927)
			(xy 114.421658 -234.027504) (xy 114.406074 -234.074185) (xy 114.383203 -234.117762) (xy 114.353638 -234.157106)
			(xy 114.318145 -234.191198) (xy 114.277642 -234.219154) (xy 114.23318 -234.240252) (xy 114.185909 -234.253944)
			(xy 114.137054 -234.259876) (xy 114.087879 -234.257895) (xy 114.03966 -234.248051) (xy 113.993644 -234.230599)
			(xy 113.951023 -234.205992) (xy 113.912902 -234.174867) (xy 113.880267 -234.13803) (xy 113.853964 -234.096434)
			(xy 113.834673 -234.051158) (xy 113.822896 -234.003374) (xy 113.818936 -233.95432) (xy 113.489994 -233.95432)
			(xy 113.489499 -233.978927) (xy 113.481604 -234.027504) (xy 113.46602 -234.074185) (xy 113.443149 -234.117762)
			(xy 113.413584 -234.157106) (xy 113.378091 -234.191198) (xy 113.337588 -234.219154) (xy 113.293126 -234.240252)
			(xy 113.245855 -234.253944) (xy 113.197 -234.259876) (xy 113.147825 -234.257895) (xy 113.099606 -234.248051)
			(xy 113.05359 -234.230599) (xy 113.010969 -234.205992) (xy 112.972848 -234.174867) (xy 112.940213 -234.13803)
			(xy 112.91391 -234.096434) (xy 112.894619 -234.051158) (xy 112.882842 -234.003374) (xy 112.878882 -233.95432)
			(xy 110.676436 -233.95432) (xy 110.675941 -233.978927) (xy 110.668046 -234.027504) (xy 110.652462 -234.074185)
			(xy 110.629591 -234.117762) (xy 110.600026 -234.157106) (xy 110.564533 -234.191198) (xy 110.52403 -234.219154)
			(xy 110.479568 -234.240252) (xy 110.432297 -234.253944) (xy 110.383442 -234.259876) (xy 110.334267 -234.257895)
			(xy 110.286048 -234.248051) (xy 110.240032 -234.230599) (xy 110.197411 -234.205992) (xy 110.15929 -234.174867)
			(xy 110.126655 -234.13803) (xy 110.100352 -234.096434) (xy 110.081061 -234.051158) (xy 110.069284 -234.003374)
			(xy 110.065324 -233.95432) (xy 109.736978 -233.95432) (xy 109.732808 -234.004649) (xy 109.720405 -234.053624)
			(xy 109.70011 -234.09989) (xy 109.672476 -234.142184) (xy 109.638257 -234.179353) (xy 109.598387 -234.210381)
			(xy 109.553953 -234.234424) (xy 109.506168 -234.250826) (xy 109.456335 -234.259137) (xy 109.431074 -234.259628)
			(xy 108.49102 -234.259628) (xy 108.465763 -234.259097) (xy 108.415937 -234.250786) (xy 108.368159 -234.234386)
			(xy 108.323732 -234.210346) (xy 108.283868 -234.179321) (xy 108.249654 -234.142157) (xy 108.222025 -234.099869)
			(xy 108.201733 -234.05361) (xy 108.189332 -234.004642) (xy 108.18516 -233.9543) (xy 107.856274 -233.9543)
			(xy 107.856274 -233.95432) (xy 107.855779 -233.978927) (xy 107.847884 -234.027504) (xy 107.8323 -234.074185)
			(xy 107.809429 -234.117762) (xy 107.779864 -234.157106) (xy 107.744371 -234.191198) (xy 107.703868 -234.219154)
			(xy 107.659406 -234.240252) (xy 107.612135 -234.253944) (xy 107.56328 -234.259876) (xy 107.514105 -234.257895)
			(xy 107.465886 -234.248051) (xy 107.41987 -234.230599) (xy 107.377249 -234.205992) (xy 107.339128 -234.174867)
			(xy 107.306493 -234.13803) (xy 107.28019 -234.096434) (xy 107.260899 -234.051158) (xy 107.249122 -234.003374)
			(xy 107.245162 -233.95432) (xy 105.036366 -233.95432) (xy 105.035871 -233.978927) (xy 105.027976 -234.027504)
			(xy 105.012392 -234.074185) (xy 104.989521 -234.117762) (xy 104.959956 -234.157106) (xy 104.924463 -234.191198)
			(xy 104.88396 -234.219154) (xy 104.839498 -234.240252) (xy 104.792227 -234.253944) (xy 104.743372 -234.259876)
			(xy 104.694197 -234.257895) (xy 104.645978 -234.248051) (xy 104.599962 -234.230599) (xy 104.557341 -234.205992)
			(xy 104.51922 -234.174867) (xy 104.486585 -234.13803) (xy 104.460282 -234.096434) (xy 104.440991 -234.051158)
			(xy 104.429214 -234.003374) (xy 104.425254 -233.95432) (xy 102.216458 -233.95432) (xy 102.215963 -233.978927)
			(xy 102.208068 -234.027504) (xy 102.192484 -234.074185) (xy 102.169613 -234.117762) (xy 102.140048 -234.157106)
			(xy 102.104555 -234.191198) (xy 102.064052 -234.219154) (xy 102.01959 -234.240252) (xy 101.972319 -234.253944)
			(xy 101.923464 -234.259876) (xy 101.874289 -234.257895) (xy 101.82607 -234.248051) (xy 101.780054 -234.230599)
			(xy 101.737433 -234.205992) (xy 101.699312 -234.174867) (xy 101.666677 -234.13803) (xy 101.640374 -234.096434)
			(xy 101.621083 -234.051158) (xy 101.609306 -234.003374) (xy 101.605346 -233.95432) (xy 99.396296 -233.95432)
			(xy 99.395801 -233.978927) (xy 99.387906 -234.027504) (xy 99.372322 -234.074185) (xy 99.349451 -234.117762)
			(xy 99.319886 -234.157106) (xy 99.284393 -234.191198) (xy 99.24389 -234.219154) (xy 99.199428 -234.240252)
			(xy 99.152157 -234.253944) (xy 99.103302 -234.259876) (xy 99.054127 -234.257895) (xy 99.005908 -234.248051)
			(xy 98.959892 -234.230599) (xy 98.917271 -234.205992) (xy 98.87915 -234.174867) (xy 98.846515 -234.13803)
			(xy 98.820212 -234.096434) (xy 98.800921 -234.051158) (xy 98.789144 -234.003374) (xy 98.785184 -233.95432)
			(xy 96.576388 -233.95432) (xy 96.57625 -233.967083) (xy 96.57409 -233.992517) (xy 96.57207 -234.00512)
			(xy 96.572324 -234.00512) (xy 96.56789 -234.028626) (xy 96.552683 -234.073976) (xy 96.530596 -234.116404)
			(xy 96.502169 -234.154871) (xy 96.468095 -234.18844) (xy 96.429206 -234.21629) (xy 96.386454 -234.23774)
			(xy 96.340881 -234.252267) (xy 96.317308 -234.256326) (xy 96.3168 -234.256326) (xy 96.316292 -234.25658)
			(xy 96.307527 -234.258242) (xy 96.291904 -234.266828) (xy 96.285812 -234.273344) (xy 96.280224 -234.279694)
			(xy 96.273874 -234.296712) (xy 96.273874 -234.451652) (xy 96.274063 -234.457886) (xy 96.277146 -234.469967)
			(xy 96.27997 -234.475528) (xy 96.284542 -234.483402) (xy 96.295085 -234.502004) (xy 96.313648 -234.540526)
			(xy 96.321626 -234.560364) (xy 96.323658 -234.565444) (xy 96.326452 -234.573064) (xy 96.33712 -234.581446)
			(xy 96.342594 -234.585407) (xy 96.355083 -234.590555) (xy 96.361758 -234.591606) (xy 96.448372 -234.603036)
			(xy 96.455111 -234.60362) (xy 96.468494 -234.601702) (xy 96.474788 -234.599226) (xy 96.48698 -234.594146)
			(xy 96.490536 -234.589574) (xy 96.495616 -234.582716) (xy 96.51012 -234.563888) (xy 96.543977 -234.530536)
			(xy 96.582591 -234.50283) (xy 96.625029 -234.481438) (xy 96.670269 -234.466877) (xy 96.717218 -234.459498)
			(xy 96.74098 -234.459018) (xy 96.766237 -234.459509) (xy 96.816061 -234.46782) (xy 96.863839 -234.484219)
			(xy 96.908265 -234.508259) (xy 96.948128 -234.539283) (xy 96.982341 -234.576446) (xy 97.00997 -234.618734)
			(xy 97.030262 -234.664992) (xy 97.042662 -234.713959) (xy 97.046834 -234.7643) (xy 97.374911 -234.7643)
			(xy 97.379087 -234.713916) (xy 97.391499 -234.664906) (xy 97.411808 -234.618609) (xy 97.439462 -234.576285)
			(xy 97.473705 -234.539091) (xy 97.513603 -234.508041) (xy 97.558069 -234.483982) (xy 97.605888 -234.467571)
			(xy 97.655756 -234.459254) (xy 97.681034 -234.458764) (xy 98.621088 -234.458764) (xy 98.64637 -234.459204)
			(xy 98.696243 -234.467525) (xy 98.744067 -234.483941) (xy 98.788537 -234.508005) (xy 98.828439 -234.539061)
			(xy 98.862685 -234.576261) (xy 98.890341 -234.61859) (xy 98.910652 -234.664894) (xy 98.923065 -234.71391)
			(xy 98.927241 -234.7643) (xy 98.927239 -234.764326) (xy 99.255338 -234.764326) (xy 99.259298 -234.715272)
			(xy 99.271075 -234.667488) (xy 99.290366 -234.622212) (xy 99.316669 -234.580616) (xy 99.349304 -234.543779)
			(xy 99.387425 -234.512654) (xy 99.430046 -234.488047) (xy 99.476062 -234.470595) (xy 99.524281 -234.460751)
			(xy 99.573456 -234.45877) (xy 99.622311 -234.464702) (xy 99.669582 -234.478394) (xy 99.714044 -234.499492)
			(xy 99.754547 -234.527448) (xy 99.79004 -234.56154) (xy 99.819605 -234.600884) (xy 99.842476 -234.644461)
			(xy 99.85806 -234.691142) (xy 99.865955 -234.739719) (xy 99.866449 -234.7643) (xy 100.194811 -234.7643)
			(xy 100.198987 -234.713915) (xy 100.211399 -234.664905) (xy 100.23171 -234.618606) (xy 100.259364 -234.576283)
			(xy 100.293608 -234.539088) (xy 100.333508 -234.508038) (xy 100.377974 -234.48398) (xy 100.425794 -234.467569)
			(xy 100.475663 -234.459254) (xy 100.500942 -234.458764) (xy 101.440996 -234.458764) (xy 101.466277 -234.459205)
			(xy 101.51615 -234.467526) (xy 101.563973 -234.483944) (xy 101.608441 -234.508008) (xy 101.648342 -234.539064)
			(xy 101.682587 -234.576263) (xy 101.710242 -234.618592) (xy 101.730553 -234.664896) (xy 101.742965 -234.713911)
			(xy 101.747141 -234.7643) (xy 101.747139 -234.764326) (xy 102.075246 -234.764326) (xy 102.079206 -234.715272)
			(xy 102.090983 -234.667488) (xy 102.110274 -234.622212) (xy 102.136577 -234.580616) (xy 102.169212 -234.543779)
			(xy 102.207333 -234.512654) (xy 102.249954 -234.488047) (xy 102.29597 -234.470595) (xy 102.344189 -234.460751)
			(xy 102.393364 -234.45877) (xy 102.442219 -234.464702) (xy 102.48949 -234.478394) (xy 102.533952 -234.499492)
			(xy 102.574455 -234.527448) (xy 102.609948 -234.56154) (xy 102.639513 -234.600884) (xy 102.662384 -234.644461)
			(xy 102.677968 -234.691142) (xy 102.685863 -234.739719) (xy 102.686357 -234.7643) (xy 103.015011 -234.7643)
			(xy 103.019186 -234.713919) (xy 103.031596 -234.664912) (xy 103.051904 -234.618617) (xy 103.079554 -234.576295)
			(xy 103.113793 -234.539102) (xy 103.153688 -234.508052) (xy 103.198148 -234.483991) (xy 103.245963 -234.467577)
			(xy 103.295827 -234.459257) (xy 103.321104 -234.458764) (xy 104.261158 -234.458764) (xy 104.286441 -234.459202)
			(xy 104.336319 -234.467519) (xy 104.384147 -234.483932) (xy 104.428621 -234.507995) (xy 104.468527 -234.53905)
			(xy 104.502777 -234.576251) (xy 104.530436 -234.618582) (xy 104.55075 -234.664888) (xy 104.563164 -234.713907)
			(xy 104.567341 -234.7643) (xy 104.567339 -234.764326) (xy 104.895154 -234.764326) (xy 104.899114 -234.715272)
			(xy 104.910891 -234.667488) (xy 104.930182 -234.622212) (xy 104.956485 -234.580616) (xy 104.98912 -234.543779)
			(xy 105.027241 -234.512654) (xy 105.069862 -234.488047) (xy 105.115878 -234.470595) (xy 105.164097 -234.460751)
			(xy 105.213272 -234.45877) (xy 105.262127 -234.464702) (xy 105.309398 -234.478394) (xy 105.35386 -234.499492)
			(xy 105.394363 -234.527448) (xy 105.429856 -234.56154) (xy 105.459421 -234.600884) (xy 105.482292 -234.644461)
			(xy 105.497876 -234.691142) (xy 105.505771 -234.739719) (xy 105.506265 -234.7643) (xy 105.834911 -234.7643)
			(xy 105.839086 -234.713918) (xy 105.851497 -234.664911) (xy 105.871805 -234.618615) (xy 105.899456 -234.576293)
			(xy 105.933697 -234.539099) (xy 105.973592 -234.508049) (xy 106.018054 -234.483989) (xy 106.06587 -234.467575)
			(xy 106.115735 -234.459256) (xy 106.141012 -234.458764) (xy 107.081066 -234.458764) (xy 107.106349 -234.459202)
			(xy 107.156225 -234.46752) (xy 107.204052 -234.483935) (xy 107.248525 -234.507998) (xy 107.28843 -234.539053)
			(xy 107.322679 -234.576253) (xy 107.350337 -234.618584) (xy 107.370651 -234.66489) (xy 107.383065 -234.713907)
			(xy 107.387241 -234.7643) (xy 107.387239 -234.764326) (xy 107.715316 -234.764326) (xy 107.719276 -234.715272)
			(xy 107.731053 -234.667488) (xy 107.750344 -234.622212) (xy 107.776647 -234.580616) (xy 107.809282 -234.543779)
			(xy 107.847403 -234.512654) (xy 107.890024 -234.488047) (xy 107.93604 -234.470595) (xy 107.984259 -234.460751)
			(xy 108.033434 -234.45877) (xy 108.082289 -234.464702) (xy 108.12956 -234.478394) (xy 108.174022 -234.499492)
			(xy 108.214525 -234.527448) (xy 108.250018 -234.56154) (xy 108.279583 -234.600884) (xy 108.302454 -234.644461)
			(xy 108.318038 -234.691142) (xy 108.325933 -234.739719) (xy 108.326428 -234.764326) (xy 115.22889 -234.764326)
			(xy 115.23285 -234.715272) (xy 115.244627 -234.667488) (xy 115.263918 -234.622212) (xy 115.290221 -234.580616)
			(xy 115.322856 -234.543779) (xy 115.360977 -234.512654) (xy 115.403598 -234.488047) (xy 115.449614 -234.470595)
			(xy 115.497833 -234.460751) (xy 115.547008 -234.45877) (xy 115.595863 -234.464702) (xy 115.643134 -234.478394)
			(xy 115.687596 -234.499492) (xy 115.728099 -234.527448) (xy 115.763592 -234.56154) (xy 115.793157 -234.600884)
			(xy 115.816028 -234.644461) (xy 115.831612 -234.691142) (xy 115.839507 -234.739719) (xy 115.840002 -234.764326)
			(xy 116.168944 -234.764326) (xy 116.172904 -234.715272) (xy 116.184681 -234.667488) (xy 116.203972 -234.622212)
			(xy 116.230275 -234.580616) (xy 116.26291 -234.543779) (xy 116.301031 -234.512654) (xy 116.343652 -234.488047)
			(xy 116.389668 -234.470595) (xy 116.437887 -234.460751) (xy 116.487062 -234.45877) (xy 116.535917 -234.464702)
			(xy 116.583188 -234.478394) (xy 116.62765 -234.499492) (xy 116.668153 -234.527448) (xy 116.703646 -234.56154)
			(xy 116.733211 -234.600884) (xy 116.756082 -234.644461) (xy 116.771666 -234.691142) (xy 116.779561 -234.739719)
			(xy 116.780056 -234.764326) (xy 117.108998 -234.764326) (xy 117.112958 -234.715272) (xy 117.124735 -234.667488)
			(xy 117.144026 -234.622212) (xy 117.170329 -234.580616) (xy 117.202964 -234.543779) (xy 117.241085 -234.512654)
			(xy 117.283706 -234.488047) (xy 117.329722 -234.470595) (xy 117.377941 -234.460751) (xy 117.427116 -234.45877)
			(xy 117.475971 -234.464702) (xy 117.523242 -234.478394) (xy 117.567704 -234.499492) (xy 117.608207 -234.527448)
			(xy 117.6437 -234.56154) (xy 117.673265 -234.600884) (xy 117.696136 -234.644461) (xy 117.71172 -234.691142)
			(xy 117.719615 -234.739719) (xy 117.72011 -234.764326) (xy 118.049052 -234.764326) (xy 118.053012 -234.715272)
			(xy 118.064789 -234.667488) (xy 118.08408 -234.622212) (xy 118.110383 -234.580616) (xy 118.143018 -234.543779)
			(xy 118.181139 -234.512654) (xy 118.22376 -234.488047) (xy 118.269776 -234.470595) (xy 118.317995 -234.460751)
			(xy 118.36717 -234.45877) (xy 118.416025 -234.464702) (xy 118.463296 -234.478394) (xy 118.507758 -234.499492)
			(xy 118.548261 -234.527448) (xy 118.583754 -234.56154) (xy 118.613319 -234.600884) (xy 118.63619 -234.644461)
			(xy 118.651774 -234.691142) (xy 118.659669 -234.739719) (xy 118.660164 -234.764326) (xy 118.988852 -234.764326)
			(xy 118.992812 -234.715272) (xy 119.004589 -234.667488) (xy 119.02388 -234.622212) (xy 119.050183 -234.580616)
			(xy 119.082818 -234.543779) (xy 119.120939 -234.512654) (xy 119.16356 -234.488047) (xy 119.209576 -234.470595)
			(xy 119.257795 -234.460751) (xy 119.30697 -234.45877) (xy 119.355825 -234.464702) (xy 119.403096 -234.478394)
			(xy 119.447558 -234.499492) (xy 119.488061 -234.527448) (xy 119.523554 -234.56154) (xy 119.553119 -234.600884)
			(xy 119.57599 -234.644461) (xy 119.591574 -234.691142) (xy 119.599469 -234.739719) (xy 119.599964 -234.764326)
			(xy 119.928906 -234.764326) (xy 119.932866 -234.715272) (xy 119.944643 -234.667488) (xy 119.963934 -234.622212)
			(xy 119.990237 -234.580616) (xy 120.022872 -234.543779) (xy 120.060993 -234.512654) (xy 120.103614 -234.488047)
			(xy 120.14963 -234.470595) (xy 120.197849 -234.460751) (xy 120.247024 -234.45877) (xy 120.295879 -234.464702)
			(xy 120.34315 -234.478394) (xy 120.387612 -234.499492) (xy 120.428115 -234.527448) (xy 120.463608 -234.56154)
			(xy 120.493173 -234.600884) (xy 120.516044 -234.644461) (xy 120.531628 -234.691142) (xy 120.539523 -234.739719)
			(xy 120.540018 -234.764326) (xy 120.86896 -234.764326) (xy 120.87292 -234.715272) (xy 120.884697 -234.667488)
			(xy 120.903988 -234.622212) (xy 120.930291 -234.580616) (xy 120.962926 -234.543779) (xy 121.001047 -234.512654)
			(xy 121.043668 -234.488047) (xy 121.089684 -234.470595) (xy 121.137903 -234.460751) (xy 121.187078 -234.45877)
			(xy 121.235933 -234.464702) (xy 121.283204 -234.478394) (xy 121.327666 -234.499492) (xy 121.368169 -234.527448)
			(xy 121.403662 -234.56154) (xy 121.433227 -234.600884) (xy 121.456098 -234.644461) (xy 121.471682 -234.691142)
			(xy 121.479577 -234.739719) (xy 121.480072 -234.764326) (xy 121.809014 -234.764326) (xy 121.812974 -234.715272)
			(xy 121.824751 -234.667488) (xy 121.844042 -234.622212) (xy 121.870345 -234.580616) (xy 121.90298 -234.543779)
			(xy 121.941101 -234.512654) (xy 121.983722 -234.488047) (xy 122.029738 -234.470595) (xy 122.077957 -234.460751)
			(xy 122.127132 -234.45877) (xy 122.175987 -234.464702) (xy 122.223258 -234.478394) (xy 122.26772 -234.499492)
			(xy 122.308223 -234.527448) (xy 122.343716 -234.56154) (xy 122.373281 -234.600884) (xy 122.396152 -234.644461)
			(xy 122.411736 -234.691142) (xy 122.419631 -234.739719) (xy 122.420126 -234.764326) (xy 122.748814 -234.764326)
			(xy 122.752774 -234.715272) (xy 122.764551 -234.667488) (xy 122.783842 -234.622212) (xy 122.810145 -234.580616)
			(xy 122.84278 -234.543779) (xy 122.880901 -234.512654) (xy 122.923522 -234.488047) (xy 122.969538 -234.470595)
			(xy 123.017757 -234.460751) (xy 123.066932 -234.45877) (xy 123.115787 -234.464702) (xy 123.163058 -234.478394)
			(xy 123.20752 -234.499492) (xy 123.248023 -234.527448) (xy 123.283516 -234.56154) (xy 123.313081 -234.600884)
			(xy 123.335952 -234.644461) (xy 123.351536 -234.691142) (xy 123.359431 -234.739719) (xy 123.359926 -234.764326)
			(xy 123.688868 -234.764326) (xy 123.692828 -234.715272) (xy 123.704605 -234.667488) (xy 123.723896 -234.622212)
			(xy 123.750199 -234.580616) (xy 123.782834 -234.543779) (xy 123.820955 -234.512654) (xy 123.863576 -234.488047)
			(xy 123.909592 -234.470595) (xy 123.957811 -234.460751) (xy 124.006986 -234.45877) (xy 124.055841 -234.464702)
			(xy 124.103112 -234.478394) (xy 124.147574 -234.499492) (xy 124.188077 -234.527448) (xy 124.22357 -234.56154)
			(xy 124.253135 -234.600884) (xy 124.276006 -234.644461) (xy 124.29159 -234.691142) (xy 124.299485 -234.739719)
			(xy 124.29998 -234.764326) (xy 124.628922 -234.764326) (xy 124.632882 -234.715272) (xy 124.644659 -234.667488)
			(xy 124.66395 -234.622212) (xy 124.690253 -234.580616) (xy 124.722888 -234.543779) (xy 124.761009 -234.512654)
			(xy 124.80363 -234.488047) (xy 124.849646 -234.470595) (xy 124.897865 -234.460751) (xy 124.94704 -234.45877)
			(xy 124.995895 -234.464702) (xy 125.043166 -234.478394) (xy 125.087628 -234.499492) (xy 125.128131 -234.527448)
			(xy 125.163624 -234.56154) (xy 125.193189 -234.600884) (xy 125.21606 -234.644461) (xy 125.231644 -234.691142)
			(xy 125.239539 -234.739719) (xy 125.240034 -234.764326) (xy 125.568976 -234.764326) (xy 125.572936 -234.715272)
			(xy 125.584713 -234.667488) (xy 125.604004 -234.622212) (xy 125.630307 -234.580616) (xy 125.662942 -234.543779)
			(xy 125.701063 -234.512654) (xy 125.743684 -234.488047) (xy 125.7897 -234.470595) (xy 125.837919 -234.460751)
			(xy 125.887094 -234.45877) (xy 125.935949 -234.464702) (xy 125.98322 -234.478394) (xy 126.027682 -234.499492)
			(xy 126.068185 -234.527448) (xy 126.103678 -234.56154) (xy 126.133243 -234.600884) (xy 126.156114 -234.644461)
			(xy 126.171698 -234.691142) (xy 126.179593 -234.739719) (xy 126.180088 -234.764326) (xy 126.179593 -234.788933)
			(xy 126.171698 -234.83751) (xy 126.156114 -234.884191) (xy 126.133243 -234.927768) (xy 126.103678 -234.967112)
			(xy 126.068185 -235.001204) (xy 126.027682 -235.02916) (xy 125.98322 -235.050258) (xy 125.935949 -235.06395)
			(xy 125.887094 -235.069882) (xy 125.837919 -235.067901) (xy 125.7897 -235.058057) (xy 125.743684 -235.040605)
			(xy 125.701063 -235.015998) (xy 125.662942 -234.984873) (xy 125.630307 -234.948036) (xy 125.604004 -234.90644)
			(xy 125.584713 -234.861164) (xy 125.572936 -234.81338) (xy 125.568976 -234.764326) (xy 125.240034 -234.764326)
			(xy 125.239539 -234.788933) (xy 125.231644 -234.83751) (xy 125.21606 -234.884191) (xy 125.193189 -234.927768)
			(xy 125.163624 -234.967112) (xy 125.128131 -235.001204) (xy 125.087628 -235.02916) (xy 125.043166 -235.050258)
			(xy 124.995895 -235.06395) (xy 124.94704 -235.069882) (xy 124.897865 -235.067901) (xy 124.849646 -235.058057)
			(xy 124.80363 -235.040605) (xy 124.761009 -235.015998) (xy 124.722888 -234.984873) (xy 124.690253 -234.948036)
			(xy 124.66395 -234.90644) (xy 124.644659 -234.861164) (xy 124.632882 -234.81338) (xy 124.628922 -234.764326)
			(xy 124.29998 -234.764326) (xy 124.299485 -234.788933) (xy 124.29159 -234.83751) (xy 124.276006 -234.884191)
			(xy 124.253135 -234.927768) (xy 124.22357 -234.967112) (xy 124.188077 -235.001204) (xy 124.147574 -235.02916)
			(xy 124.103112 -235.050258) (xy 124.055841 -235.06395) (xy 124.006986 -235.069882) (xy 123.957811 -235.067901)
			(xy 123.909592 -235.058057) (xy 123.863576 -235.040605) (xy 123.820955 -235.015998) (xy 123.782834 -234.984873)
			(xy 123.750199 -234.948036) (xy 123.723896 -234.90644) (xy 123.704605 -234.861164) (xy 123.692828 -234.81338)
			(xy 123.688868 -234.764326) (xy 123.359926 -234.764326) (xy 123.359431 -234.788933) (xy 123.351536 -234.83751)
			(xy 123.335952 -234.884191) (xy 123.313081 -234.927768) (xy 123.283516 -234.967112) (xy 123.248023 -235.001204)
			(xy 123.20752 -235.02916) (xy 123.163058 -235.050258) (xy 123.115787 -235.06395) (xy 123.066932 -235.069882)
			(xy 123.017757 -235.067901) (xy 122.969538 -235.058057) (xy 122.923522 -235.040605) (xy 122.880901 -235.015998)
			(xy 122.84278 -234.984873) (xy 122.810145 -234.948036) (xy 122.783842 -234.90644) (xy 122.764551 -234.861164)
			(xy 122.752774 -234.81338) (xy 122.748814 -234.764326) (xy 122.420126 -234.764326) (xy 122.419631 -234.788933)
			(xy 122.411736 -234.83751) (xy 122.396152 -234.884191) (xy 122.373281 -234.927768) (xy 122.343716 -234.967112)
			(xy 122.308223 -235.001204) (xy 122.26772 -235.02916) (xy 122.223258 -235.050258) (xy 122.175987 -235.06395)
			(xy 122.127132 -235.069882) (xy 122.077957 -235.067901) (xy 122.029738 -235.058057) (xy 121.983722 -235.040605)
			(xy 121.941101 -235.015998) (xy 121.90298 -234.984873) (xy 121.870345 -234.948036) (xy 121.844042 -234.90644)
			(xy 121.824751 -234.861164) (xy 121.812974 -234.81338) (xy 121.809014 -234.764326) (xy 121.480072 -234.764326)
			(xy 121.479577 -234.788933) (xy 121.471682 -234.83751) (xy 121.456098 -234.884191) (xy 121.433227 -234.927768)
			(xy 121.403662 -234.967112) (xy 121.368169 -235.001204) (xy 121.327666 -235.02916) (xy 121.283204 -235.050258)
			(xy 121.235933 -235.06395) (xy 121.187078 -235.069882) (xy 121.137903 -235.067901) (xy 121.089684 -235.058057)
			(xy 121.043668 -235.040605) (xy 121.001047 -235.015998) (xy 120.962926 -234.984873) (xy 120.930291 -234.948036)
			(xy 120.903988 -234.90644) (xy 120.884697 -234.861164) (xy 120.87292 -234.81338) (xy 120.86896 -234.764326)
			(xy 120.540018 -234.764326) (xy 120.539523 -234.788933) (xy 120.531628 -234.83751) (xy 120.516044 -234.884191)
			(xy 120.493173 -234.927768) (xy 120.463608 -234.967112) (xy 120.428115 -235.001204) (xy 120.387612 -235.02916)
			(xy 120.34315 -235.050258) (xy 120.295879 -235.06395) (xy 120.247024 -235.069882) (xy 120.197849 -235.067901)
			(xy 120.14963 -235.058057) (xy 120.103614 -235.040605) (xy 120.060993 -235.015998) (xy 120.022872 -234.984873)
			(xy 119.990237 -234.948036) (xy 119.963934 -234.90644) (xy 119.944643 -234.861164) (xy 119.932866 -234.81338)
			(xy 119.928906 -234.764326) (xy 119.599964 -234.764326) (xy 119.599469 -234.788933) (xy 119.591574 -234.83751)
			(xy 119.57599 -234.884191) (xy 119.553119 -234.927768) (xy 119.523554 -234.967112) (xy 119.488061 -235.001204)
			(xy 119.447558 -235.02916) (xy 119.403096 -235.050258) (xy 119.355825 -235.06395) (xy 119.30697 -235.069882)
			(xy 119.257795 -235.067901) (xy 119.209576 -235.058057) (xy 119.16356 -235.040605) (xy 119.120939 -235.015998)
			(xy 119.082818 -234.984873) (xy 119.050183 -234.948036) (xy 119.02388 -234.90644) (xy 119.004589 -234.861164)
			(xy 118.992812 -234.81338) (xy 118.988852 -234.764326) (xy 118.660164 -234.764326) (xy 118.659669 -234.788933)
			(xy 118.651774 -234.83751) (xy 118.63619 -234.884191) (xy 118.613319 -234.927768) (xy 118.583754 -234.967112)
			(xy 118.548261 -235.001204) (xy 118.507758 -235.02916) (xy 118.463296 -235.050258) (xy 118.416025 -235.06395)
			(xy 118.36717 -235.069882) (xy 118.317995 -235.067901) (xy 118.269776 -235.058057) (xy 118.22376 -235.040605)
			(xy 118.181139 -235.015998) (xy 118.143018 -234.984873) (xy 118.110383 -234.948036) (xy 118.08408 -234.90644)
			(xy 118.064789 -234.861164) (xy 118.053012 -234.81338) (xy 118.049052 -234.764326) (xy 117.72011 -234.764326)
			(xy 117.719615 -234.788933) (xy 117.71172 -234.83751) (xy 117.696136 -234.884191) (xy 117.673265 -234.927768)
			(xy 117.6437 -234.967112) (xy 117.608207 -235.001204) (xy 117.567704 -235.02916) (xy 117.523242 -235.050258)
			(xy 117.475971 -235.06395) (xy 117.427116 -235.069882) (xy 117.377941 -235.067901) (xy 117.329722 -235.058057)
			(xy 117.283706 -235.040605) (xy 117.241085 -235.015998) (xy 117.202964 -234.984873) (xy 117.170329 -234.948036)
			(xy 117.144026 -234.90644) (xy 117.124735 -234.861164) (xy 117.112958 -234.81338) (xy 117.108998 -234.764326)
			(xy 116.780056 -234.764326) (xy 116.779561 -234.788933) (xy 116.771666 -234.83751) (xy 116.756082 -234.884191)
			(xy 116.733211 -234.927768) (xy 116.703646 -234.967112) (xy 116.668153 -235.001204) (xy 116.62765 -235.02916)
			(xy 116.583188 -235.050258) (xy 116.535917 -235.06395) (xy 116.487062 -235.069882) (xy 116.437887 -235.067901)
			(xy 116.389668 -235.058057) (xy 116.343652 -235.040605) (xy 116.301031 -235.015998) (xy 116.26291 -234.984873)
			(xy 116.230275 -234.948036) (xy 116.203972 -234.90644) (xy 116.184681 -234.861164) (xy 116.172904 -234.81338)
			(xy 116.168944 -234.764326) (xy 115.840002 -234.764326) (xy 115.839507 -234.788933) (xy 115.831612 -234.83751)
			(xy 115.816028 -234.884191) (xy 115.793157 -234.927768) (xy 115.763592 -234.967112) (xy 115.728099 -235.001204)
			(xy 115.687596 -235.02916) (xy 115.643134 -235.050258) (xy 115.595863 -235.06395) (xy 115.547008 -235.069882)
			(xy 115.497833 -235.067901) (xy 115.449614 -235.058057) (xy 115.403598 -235.040605) (xy 115.360977 -235.015998)
			(xy 115.322856 -234.984873) (xy 115.290221 -234.948036) (xy 115.263918 -234.90644) (xy 115.244627 -234.861164)
			(xy 115.23285 -234.81338) (xy 115.22889 -234.764326) (xy 108.326428 -234.764326) (xy 108.325933 -234.788933)
			(xy 108.318038 -234.83751) (xy 108.302454 -234.884191) (xy 108.279583 -234.927768) (xy 108.250018 -234.967112)
			(xy 108.214525 -235.001204) (xy 108.174022 -235.02916) (xy 108.12956 -235.050258) (xy 108.082289 -235.06395)
			(xy 108.033434 -235.069882) (xy 107.984259 -235.067901) (xy 107.93604 -235.058057) (xy 107.890024 -235.040605)
			(xy 107.847403 -235.015998) (xy 107.809282 -234.984873) (xy 107.776647 -234.948036) (xy 107.750344 -234.90644)
			(xy 107.731053 -234.861164) (xy 107.719276 -234.81338) (xy 107.715316 -234.764326) (xy 107.387239 -234.764326)
			(xy 107.383065 -234.814693) (xy 107.370651 -234.86371) (xy 107.350337 -234.910016) (xy 107.322679 -234.952347)
			(xy 107.28843 -234.989547) (xy 107.248525 -235.020602) (xy 107.204052 -235.044665) (xy 107.156225 -235.06108)
			(xy 107.106349 -235.069398) (xy 107.081066 -235.069888) (xy 106.141012 -235.069888) (xy 106.115735 -235.069344)
			(xy 106.06587 -235.061025) (xy 106.018054 -235.044611) (xy 105.973592 -235.020551) (xy 105.933697 -234.989501)
			(xy 105.899456 -234.952307) (xy 105.871805 -234.909985) (xy 105.851497 -234.863689) (xy 105.839086 -234.814682)
			(xy 105.834911 -234.7643) (xy 105.506265 -234.7643) (xy 105.506266 -234.764326) (xy 105.505771 -234.788933)
			(xy 105.497876 -234.83751) (xy 105.482292 -234.884191) (xy 105.459421 -234.927768) (xy 105.429856 -234.967112)
			(xy 105.394363 -235.001204) (xy 105.35386 -235.02916) (xy 105.309398 -235.050258) (xy 105.262127 -235.06395)
			(xy 105.213272 -235.069882) (xy 105.164097 -235.067901) (xy 105.115878 -235.058057) (xy 105.069862 -235.040605)
			(xy 105.027241 -235.015998) (xy 104.98912 -234.984873) (xy 104.956485 -234.948036) (xy 104.930182 -234.90644)
			(xy 104.910891 -234.861164) (xy 104.899114 -234.81338) (xy 104.895154 -234.764326) (xy 104.567339 -234.764326)
			(xy 104.563164 -234.814693) (xy 104.55075 -234.863712) (xy 104.530436 -234.910018) (xy 104.502777 -234.952349)
			(xy 104.468527 -234.98955) (xy 104.428621 -235.020605) (xy 104.384147 -235.044668) (xy 104.336319 -235.061081)
			(xy 104.286441 -235.069398) (xy 104.261158 -235.069888) (xy 103.321104 -235.069888) (xy 103.295827 -235.069343)
			(xy 103.245963 -235.061023) (xy 103.198148 -235.044609) (xy 103.153688 -235.020548) (xy 103.113793 -234.989498)
			(xy 103.079554 -234.952305) (xy 103.051904 -234.909983) (xy 103.031596 -234.863688) (xy 103.019186 -234.814681)
			(xy 103.015011 -234.7643) (xy 102.686357 -234.7643) (xy 102.686358 -234.764326) (xy 102.685863 -234.788933)
			(xy 102.677968 -234.83751) (xy 102.662384 -234.884191) (xy 102.639513 -234.927768) (xy 102.609948 -234.967112)
			(xy 102.574455 -235.001204) (xy 102.533952 -235.02916) (xy 102.48949 -235.050258) (xy 102.442219 -235.06395)
			(xy 102.393364 -235.069882) (xy 102.344189 -235.067901) (xy 102.29597 -235.058057) (xy 102.249954 -235.040605)
			(xy 102.207333 -235.015998) (xy 102.169212 -234.984873) (xy 102.136577 -234.948036) (xy 102.110274 -234.90644)
			(xy 102.090983 -234.861164) (xy 102.079206 -234.81338) (xy 102.075246 -234.764326) (xy 101.747139 -234.764326)
			(xy 101.742965 -234.814689) (xy 101.730553 -234.863704) (xy 101.710242 -234.910008) (xy 101.682587 -234.952337)
			(xy 101.648342 -234.989536) (xy 101.608441 -235.020592) (xy 101.563973 -235.044656) (xy 101.51615 -235.061074)
			(xy 101.466277 -235.069395) (xy 101.440996 -235.069888) (xy 100.500942 -235.069888) (xy 100.475663 -235.069346)
			(xy 100.425794 -235.061031) (xy 100.377974 -235.04462) (xy 100.333508 -235.020562) (xy 100.293608 -234.989512)
			(xy 100.259364 -234.952317) (xy 100.23171 -234.909994) (xy 100.211399 -234.863695) (xy 100.198987 -234.814685)
			(xy 100.194811 -234.7643) (xy 99.866449 -234.7643) (xy 99.86645 -234.764326) (xy 99.865955 -234.788933)
			(xy 99.85806 -234.83751) (xy 99.842476 -234.884191) (xy 99.819605 -234.927768) (xy 99.79004 -234.967112)
			(xy 99.754547 -235.001204) (xy 99.714044 -235.02916) (xy 99.669582 -235.050258) (xy 99.622311 -235.06395)
			(xy 99.573456 -235.069882) (xy 99.524281 -235.067901) (xy 99.476062 -235.058057) (xy 99.430046 -235.040605)
			(xy 99.387425 -235.015998) (xy 99.349304 -234.984873) (xy 99.316669 -234.948036) (xy 99.290366 -234.90644)
			(xy 99.271075 -234.861164) (xy 99.259298 -234.81338) (xy 99.255338 -234.764326) (xy 98.927239 -234.764326)
			(xy 98.923065 -234.81469) (xy 98.910652 -234.863706) (xy 98.890341 -234.91001) (xy 98.862685 -234.952339)
			(xy 98.828439 -234.989539) (xy 98.788537 -235.020595) (xy 98.744067 -235.044659) (xy 98.696243 -235.061075)
			(xy 98.64637 -235.069396) (xy 98.621088 -235.069888) (xy 97.681034 -235.069888) (xy 97.655756 -235.069346)
			(xy 97.605888 -235.061029) (xy 97.558069 -235.044618) (xy 97.513603 -235.020559) (xy 97.473705 -234.989509)
			(xy 97.439462 -234.952315) (xy 97.411808 -234.909991) (xy 97.391499 -234.863694) (xy 97.379087 -234.814684)
			(xy 97.374911 -234.7643) (xy 97.046834 -234.7643) (xy 97.042662 -234.814641) (xy 97.030262 -234.863608)
			(xy 97.00997 -234.909866) (xy 96.982341 -234.952154) (xy 96.948128 -234.989317) (xy 96.908265 -235.020341)
			(xy 96.863839 -235.044381) (xy 96.816061 -235.06078) (xy 96.766237 -235.069091) (xy 96.74098 -235.069634)
			(xy 96.717213 -235.069187) (xy 96.670252 -235.061828) (xy 96.625 -235.047276) (xy 96.582552 -235.025883)
			(xy 96.543935 -234.998166) (xy 96.510084 -234.964797) (xy 96.495616 -234.945936) (xy 96.490536 -234.939078)
			(xy 96.48698 -234.934506) (xy 96.474788 -234.929426) (xy 96.468505 -234.926903) (xy 96.455111 -234.924963)
			(xy 96.448372 -234.925616) (xy 96.361758 -234.937046) (xy 96.355082 -234.938096) (xy 96.342588 -234.943236)
			(xy 96.33712 -234.947206) (xy 96.326452 -234.955588) (xy 96.323658 -234.963208) (xy 96.321626 -234.968288)
			(xy 96.308164 -234.99953) (xy 96.302018 -235.012656) (xy 96.288552 -235.038324) (xy 96.28124 -235.050838)
			(xy 96.280986 -235.051092) (xy 96.27743 -235.057188) (xy 96.275652 -235.063284) (xy 96.273874 -235.076746)
			(xy 96.273874 -235.222542) (xy 96.274244 -235.231648) (xy 96.280615 -235.248709) (xy 96.28632 -235.255816)
			(xy 96.291908 -235.262166) (xy 96.307402 -235.270802) (xy 96.317054 -235.272326) (xy 96.340803 -235.276421)
			(xy 96.386703 -235.291101) (xy 96.429731 -235.312803) (xy 96.468818 -235.340989) (xy 96.502998 -235.37496)
			(xy 96.531422 -235.413875) (xy 96.553387 -235.45677) (xy 96.568346 -235.502579) (xy 96.575931 -235.550169)
			(xy 96.575942 -235.574332) (xy 96.90533 -235.574332) (xy 96.90929 -235.525278) (xy 96.921067 -235.477494)
			(xy 96.940358 -235.432218) (xy 96.966661 -235.390622) (xy 96.999296 -235.353785) (xy 97.037417 -235.32266)
			(xy 97.080038 -235.298053) (xy 97.126054 -235.280601) (xy 97.174273 -235.270757) (xy 97.223448 -235.268776)
			(xy 97.272303 -235.274708) (xy 97.319574 -235.2884) (xy 97.364036 -235.309498) (xy 97.404539 -235.337454)
			(xy 97.440032 -235.371546) (xy 97.469597 -235.41089) (xy 97.492468 -235.454467) (xy 97.508052 -235.501148)
			(xy 97.515947 -235.549725) (xy 97.516442 -235.574332) (xy 97.84513 -235.574332) (xy 97.84909 -235.525278)
			(xy 97.860867 -235.477494) (xy 97.880158 -235.432218) (xy 97.906461 -235.390622) (xy 97.939096 -235.353785)
			(xy 97.977217 -235.32266) (xy 98.019838 -235.298053) (xy 98.065854 -235.280601) (xy 98.114073 -235.270757)
			(xy 98.163248 -235.268776) (xy 98.212103 -235.274708) (xy 98.259374 -235.2884) (xy 98.303836 -235.309498)
			(xy 98.344339 -235.337454) (xy 98.379832 -235.371546) (xy 98.409397 -235.41089) (xy 98.432268 -235.454467)
			(xy 98.447852 -235.501148) (xy 98.455747 -235.549725) (xy 98.456242 -235.574332) (xy 98.785184 -235.574332)
			(xy 98.789144 -235.525278) (xy 98.800921 -235.477494) (xy 98.820212 -235.432218) (xy 98.846515 -235.390622)
			(xy 98.87915 -235.353785) (xy 98.917271 -235.32266) (xy 98.959892 -235.298053) (xy 99.005908 -235.280601)
			(xy 99.054127 -235.270757) (xy 99.103302 -235.268776) (xy 99.152157 -235.274708) (xy 99.199428 -235.2884)
			(xy 99.24389 -235.309498) (xy 99.284393 -235.337454) (xy 99.319886 -235.371546) (xy 99.349451 -235.41089)
			(xy 99.372322 -235.454467) (xy 99.387906 -235.501148) (xy 99.395801 -235.549725) (xy 99.396296 -235.574332)
			(xy 99.725238 -235.574332) (xy 99.729198 -235.525278) (xy 99.740975 -235.477494) (xy 99.760266 -235.432218)
			(xy 99.786569 -235.390622) (xy 99.819204 -235.353785) (xy 99.857325 -235.32266) (xy 99.899946 -235.298053)
			(xy 99.945962 -235.280601) (xy 99.994181 -235.270757) (xy 100.043356 -235.268776) (xy 100.092211 -235.274708)
			(xy 100.139482 -235.2884) (xy 100.183944 -235.309498) (xy 100.224447 -235.337454) (xy 100.25994 -235.371546)
			(xy 100.289505 -235.41089) (xy 100.312376 -235.454467) (xy 100.32796 -235.501148) (xy 100.335855 -235.549725)
			(xy 100.33635 -235.574332) (xy 100.665292 -235.574332) (xy 100.669252 -235.525278) (xy 100.681029 -235.477494)
			(xy 100.70032 -235.432218) (xy 100.726623 -235.390622) (xy 100.759258 -235.353785) (xy 100.797379 -235.32266)
			(xy 100.84 -235.298053) (xy 100.886016 -235.280601) (xy 100.934235 -235.270757) (xy 100.98341 -235.268776)
			(xy 101.032265 -235.274708) (xy 101.079536 -235.2884) (xy 101.123998 -235.309498) (xy 101.164501 -235.337454)
			(xy 101.199994 -235.371546) (xy 101.229559 -235.41089) (xy 101.25243 -235.454467) (xy 101.268014 -235.501148)
			(xy 101.275909 -235.549725) (xy 101.276404 -235.574332) (xy 101.605346 -235.574332) (xy 101.609306 -235.525278)
			(xy 101.621083 -235.477494) (xy 101.640374 -235.432218) (xy 101.666677 -235.390622) (xy 101.699312 -235.353785)
			(xy 101.737433 -235.32266) (xy 101.780054 -235.298053) (xy 101.82607 -235.280601) (xy 101.874289 -235.270757)
			(xy 101.923464 -235.268776) (xy 101.972319 -235.274708) (xy 102.01959 -235.2884) (xy 102.064052 -235.309498)
			(xy 102.104555 -235.337454) (xy 102.140048 -235.371546) (xy 102.169613 -235.41089) (xy 102.192484 -235.454467)
			(xy 102.208068 -235.501148) (xy 102.215963 -235.549725) (xy 102.216458 -235.574332) (xy 102.545146 -235.574332)
			(xy 102.549106 -235.525278) (xy 102.560883 -235.477494) (xy 102.580174 -235.432218) (xy 102.606477 -235.390622)
			(xy 102.639112 -235.353785) (xy 102.677233 -235.32266) (xy 102.719854 -235.298053) (xy 102.76587 -235.280601)
			(xy 102.814089 -235.270757) (xy 102.863264 -235.268776) (xy 102.912119 -235.274708) (xy 102.95939 -235.2884)
			(xy 103.003852 -235.309498) (xy 103.044355 -235.337454) (xy 103.079848 -235.371546) (xy 103.109413 -235.41089)
			(xy 103.132284 -235.454467) (xy 103.147868 -235.501148) (xy 103.155763 -235.549725) (xy 103.156258 -235.574332)
			(xy 103.4852 -235.574332) (xy 103.48916 -235.525278) (xy 103.500937 -235.477494) (xy 103.520228 -235.432218)
			(xy 103.546531 -235.390622) (xy 103.579166 -235.353785) (xy 103.617287 -235.32266) (xy 103.659908 -235.298053)
			(xy 103.705924 -235.280601) (xy 103.754143 -235.270757) (xy 103.803318 -235.268776) (xy 103.852173 -235.274708)
			(xy 103.899444 -235.2884) (xy 103.943906 -235.309498) (xy 103.984409 -235.337454) (xy 104.019902 -235.371546)
			(xy 104.049467 -235.41089) (xy 104.072338 -235.454467) (xy 104.087922 -235.501148) (xy 104.095817 -235.549725)
			(xy 104.096312 -235.574332) (xy 104.425254 -235.574332) (xy 104.429214 -235.525278) (xy 104.440991 -235.477494)
			(xy 104.460282 -235.432218) (xy 104.486585 -235.390622) (xy 104.51922 -235.353785) (xy 104.557341 -235.32266)
			(xy 104.599962 -235.298053) (xy 104.645978 -235.280601) (xy 104.694197 -235.270757) (xy 104.743372 -235.268776)
			(xy 104.792227 -235.274708) (xy 104.839498 -235.2884) (xy 104.88396 -235.309498) (xy 104.924463 -235.337454)
			(xy 104.959956 -235.371546) (xy 104.989521 -235.41089) (xy 105.012392 -235.454467) (xy 105.027976 -235.501148)
			(xy 105.035871 -235.549725) (xy 105.036366 -235.574332) (xy 105.365308 -235.574332) (xy 105.369268 -235.525278)
			(xy 105.381045 -235.477494) (xy 105.400336 -235.432218) (xy 105.426639 -235.390622) (xy 105.459274 -235.353785)
			(xy 105.497395 -235.32266) (xy 105.540016 -235.298053) (xy 105.586032 -235.280601) (xy 105.634251 -235.270757)
			(xy 105.683426 -235.268776) (xy 105.732281 -235.274708) (xy 105.779552 -235.2884) (xy 105.824014 -235.309498)
			(xy 105.864517 -235.337454) (xy 105.90001 -235.371546) (xy 105.929575 -235.41089) (xy 105.952446 -235.454467)
			(xy 105.96803 -235.501148) (xy 105.975925 -235.549725) (xy 105.97642 -235.574332) (xy 106.305362 -235.574332)
			(xy 106.309322 -235.525278) (xy 106.321099 -235.477494) (xy 106.34039 -235.432218) (xy 106.366693 -235.390622)
			(xy 106.399328 -235.353785) (xy 106.437449 -235.32266) (xy 106.48007 -235.298053) (xy 106.526086 -235.280601)
			(xy 106.574305 -235.270757) (xy 106.62348 -235.268776) (xy 106.672335 -235.274708) (xy 106.719606 -235.2884)
			(xy 106.764068 -235.309498) (xy 106.804571 -235.337454) (xy 106.840064 -235.371546) (xy 106.869629 -235.41089)
			(xy 106.8925 -235.454467) (xy 106.908084 -235.501148) (xy 106.915979 -235.549725) (xy 106.916474 -235.574332)
			(xy 107.245162 -235.574332) (xy 107.249122 -235.525278) (xy 107.260899 -235.477494) (xy 107.28019 -235.432218)
			(xy 107.306493 -235.390622) (xy 107.339128 -235.353785) (xy 107.377249 -235.32266) (xy 107.41987 -235.298053)
			(xy 107.465886 -235.280601) (xy 107.514105 -235.270757) (xy 107.56328 -235.268776) (xy 107.612135 -235.274708)
			(xy 107.659406 -235.2884) (xy 107.703868 -235.309498) (xy 107.744371 -235.337454) (xy 107.779864 -235.371546)
			(xy 107.809429 -235.41089) (xy 107.8323 -235.454467) (xy 107.847884 -235.501148) (xy 107.855779 -235.549725)
			(xy 107.856273 -235.5743) (xy 108.185172 -235.5743) (xy 108.189343 -235.52396) (xy 108.201744 -235.474994)
			(xy 108.222035 -235.428736) (xy 108.249664 -235.38645) (xy 108.283876 -235.349288) (xy 108.323739 -235.318264)
			(xy 108.368164 -235.294225) (xy 108.41594 -235.277826) (xy 108.465764 -235.269515) (xy 108.49102 -235.269024)
			(xy 109.431074 -235.269024) (xy 109.456336 -235.269451) (xy 109.506171 -235.277763) (xy 109.553958 -235.294165)
			(xy 109.598393 -235.318208) (xy 109.638265 -235.349239) (xy 109.672485 -235.386409) (xy 109.70012 -235.428704)
			(xy 109.720416 -235.474972) (xy 109.73282 -235.523949) (xy 109.736992 -235.5743) (xy 109.736989 -235.574332)
			(xy 110.065324 -235.574332) (xy 110.069284 -235.525278) (xy 110.081061 -235.477494) (xy 110.100352 -235.432218)
			(xy 110.126655 -235.390622) (xy 110.15929 -235.353785) (xy 110.197411 -235.32266) (xy 110.240032 -235.298053)
			(xy 110.286048 -235.280601) (xy 110.334267 -235.270757) (xy 110.383442 -235.268776) (xy 110.432297 -235.274708)
			(xy 110.479568 -235.2884) (xy 110.52403 -235.309498) (xy 110.564533 -235.337454) (xy 110.600026 -235.371546)
			(xy 110.629591 -235.41089) (xy 110.652462 -235.454467) (xy 110.668046 -235.501148) (xy 110.675941 -235.549725)
			(xy 110.676436 -235.574332) (xy 112.878882 -235.574332) (xy 112.882842 -235.525278) (xy 112.894619 -235.477494)
			(xy 112.91391 -235.432218) (xy 112.940213 -235.390622) (xy 112.972848 -235.353785) (xy 113.010969 -235.32266)
			(xy 113.05359 -235.298053) (xy 113.099606 -235.280601) (xy 113.147825 -235.270757) (xy 113.197 -235.268776)
			(xy 113.245855 -235.274708) (xy 113.293126 -235.2884) (xy 113.337588 -235.309498) (xy 113.378091 -235.337454)
			(xy 113.413584 -235.371546) (xy 113.443149 -235.41089) (xy 113.46602 -235.454467) (xy 113.481604 -235.501148)
			(xy 113.489499 -235.549725) (xy 113.489994 -235.574332) (xy 113.818936 -235.574332) (xy 113.822896 -235.525278)
			(xy 113.834673 -235.477494) (xy 113.853964 -235.432218) (xy 113.880267 -235.390622) (xy 113.912902 -235.353785)
			(xy 113.951023 -235.32266) (xy 113.993644 -235.298053) (xy 114.03966 -235.280601) (xy 114.087879 -235.270757)
			(xy 114.137054 -235.268776) (xy 114.185909 -235.274708) (xy 114.23318 -235.2884) (xy 114.277642 -235.309498)
			(xy 114.318145 -235.337454) (xy 114.353638 -235.371546) (xy 114.383203 -235.41089) (xy 114.406074 -235.454467)
			(xy 114.421658 -235.501148) (xy 114.429553 -235.549725) (xy 114.430048 -235.574332) (xy 114.75899 -235.574332)
			(xy 114.76295 -235.525278) (xy 114.774727 -235.477494) (xy 114.794018 -235.432218) (xy 114.820321 -235.390622)
			(xy 114.852956 -235.353785) (xy 114.891077 -235.32266) (xy 114.933698 -235.298053) (xy 114.979714 -235.280601)
			(xy 115.027933 -235.270757) (xy 115.077108 -235.268776) (xy 115.125963 -235.274708) (xy 115.173234 -235.2884)
			(xy 115.217696 -235.309498) (xy 115.258199 -235.337454) (xy 115.293692 -235.371546) (xy 115.323257 -235.41089)
			(xy 115.346128 -235.454467) (xy 115.361712 -235.501148) (xy 115.369607 -235.549725) (xy 115.370102 -235.574332)
			(xy 115.699044 -235.574332) (xy 115.703004 -235.525278) (xy 115.714781 -235.477494) (xy 115.734072 -235.432218)
			(xy 115.760375 -235.390622) (xy 115.79301 -235.353785) (xy 115.831131 -235.32266) (xy 115.873752 -235.298053)
			(xy 115.919768 -235.280601) (xy 115.967987 -235.270757) (xy 116.017162 -235.268776) (xy 116.066017 -235.274708)
			(xy 116.113288 -235.2884) (xy 116.15775 -235.309498) (xy 116.198253 -235.337454) (xy 116.233746 -235.371546)
			(xy 116.263311 -235.41089) (xy 116.286182 -235.454467) (xy 116.301766 -235.501148) (xy 116.309661 -235.549725)
			(xy 116.310156 -235.574332) (xy 116.638844 -235.574332) (xy 116.642804 -235.525278) (xy 116.654581 -235.477494)
			(xy 116.673872 -235.432218) (xy 116.700175 -235.390622) (xy 116.73281 -235.353785) (xy 116.770931 -235.32266)
			(xy 116.813552 -235.298053) (xy 116.859568 -235.280601) (xy 116.907787 -235.270757) (xy 116.956962 -235.268776)
			(xy 117.005817 -235.274708) (xy 117.053088 -235.2884) (xy 117.09755 -235.309498) (xy 117.138053 -235.337454)
			(xy 117.173546 -235.371546) (xy 117.203111 -235.41089) (xy 117.225982 -235.454467) (xy 117.241566 -235.501148)
			(xy 117.249461 -235.549725) (xy 117.249956 -235.574332) (xy 117.578898 -235.574332) (xy 117.582858 -235.525278)
			(xy 117.594635 -235.477494) (xy 117.613926 -235.432218) (xy 117.640229 -235.390622) (xy 117.672864 -235.353785)
			(xy 117.710985 -235.32266) (xy 117.753606 -235.298053) (xy 117.799622 -235.280601) (xy 117.847841 -235.270757)
			(xy 117.897016 -235.268776) (xy 117.945871 -235.274708) (xy 117.993142 -235.2884) (xy 118.037604 -235.309498)
			(xy 118.078107 -235.337454) (xy 118.1136 -235.371546) (xy 118.143165 -235.41089) (xy 118.166036 -235.454467)
			(xy 118.18162 -235.501148) (xy 118.189515 -235.549725) (xy 118.19001 -235.574332) (xy 118.518952 -235.574332)
			(xy 118.522912 -235.525278) (xy 118.534689 -235.477494) (xy 118.55398 -235.432218) (xy 118.580283 -235.390622)
			(xy 118.612918 -235.353785) (xy 118.651039 -235.32266) (xy 118.69366 -235.298053) (xy 118.739676 -235.280601)
			(xy 118.787895 -235.270757) (xy 118.83707 -235.268776) (xy 118.885925 -235.274708) (xy 118.933196 -235.2884)
			(xy 118.977658 -235.309498) (xy 119.018161 -235.337454) (xy 119.053654 -235.371546) (xy 119.083219 -235.41089)
			(xy 119.10609 -235.454467) (xy 119.121674 -235.501148) (xy 119.129569 -235.549725) (xy 119.130064 -235.574332)
			(xy 119.459006 -235.574332) (xy 119.462966 -235.525278) (xy 119.474743 -235.477494) (xy 119.494034 -235.432218)
			(xy 119.520337 -235.390622) (xy 119.552972 -235.353785) (xy 119.591093 -235.32266) (xy 119.633714 -235.298053)
			(xy 119.67973 -235.280601) (xy 119.727949 -235.270757) (xy 119.777124 -235.268776) (xy 119.825979 -235.274708)
			(xy 119.87325 -235.2884) (xy 119.917712 -235.309498) (xy 119.958215 -235.337454) (xy 119.993708 -235.371546)
			(xy 120.023273 -235.41089) (xy 120.046144 -235.454467) (xy 120.061728 -235.501148) (xy 120.069623 -235.549725)
			(xy 120.070118 -235.574332) (xy 120.398806 -235.574332) (xy 120.402766 -235.525278) (xy 120.414543 -235.477494)
			(xy 120.433834 -235.432218) (xy 120.460137 -235.390622) (xy 120.492772 -235.353785) (xy 120.530893 -235.32266)
			(xy 120.573514 -235.298053) (xy 120.61953 -235.280601) (xy 120.667749 -235.270757) (xy 120.716924 -235.268776)
			(xy 120.765779 -235.274708) (xy 120.81305 -235.2884) (xy 120.857512 -235.309498) (xy 120.898015 -235.337454)
			(xy 120.933508 -235.371546) (xy 120.963073 -235.41089) (xy 120.985944 -235.454467) (xy 121.001528 -235.501148)
			(xy 121.009423 -235.549725) (xy 121.009918 -235.574332) (xy 121.33886 -235.574332) (xy 121.34282 -235.525278)
			(xy 121.354597 -235.477494) (xy 121.373888 -235.432218) (xy 121.400191 -235.390622) (xy 121.432826 -235.353785)
			(xy 121.470947 -235.32266) (xy 121.513568 -235.298053) (xy 121.559584 -235.280601) (xy 121.607803 -235.270757)
			(xy 121.656978 -235.268776) (xy 121.705833 -235.274708) (xy 121.753104 -235.2884) (xy 121.797566 -235.309498)
			(xy 121.838069 -235.337454) (xy 121.873562 -235.371546) (xy 121.903127 -235.41089) (xy 121.925998 -235.454467)
			(xy 121.941582 -235.501148) (xy 121.949477 -235.549725) (xy 121.949972 -235.574332) (xy 122.278914 -235.574332)
			(xy 122.282874 -235.525278) (xy 122.294651 -235.477494) (xy 122.313942 -235.432218) (xy 122.340245 -235.390622)
			(xy 122.37288 -235.353785) (xy 122.411001 -235.32266) (xy 122.453622 -235.298053) (xy 122.499638 -235.280601)
			(xy 122.547857 -235.270757) (xy 122.597032 -235.268776) (xy 122.645887 -235.274708) (xy 122.693158 -235.2884)
			(xy 122.73762 -235.309498) (xy 122.778123 -235.337454) (xy 122.813616 -235.371546) (xy 122.843181 -235.41089)
			(xy 122.866052 -235.454467) (xy 122.881636 -235.501148) (xy 122.889531 -235.549725) (xy 122.890026 -235.574332)
			(xy 123.218968 -235.574332) (xy 123.222928 -235.525278) (xy 123.234705 -235.477494) (xy 123.253996 -235.432218)
			(xy 123.280299 -235.390622) (xy 123.312934 -235.353785) (xy 123.351055 -235.32266) (xy 123.393676 -235.298053)
			(xy 123.439692 -235.280601) (xy 123.487911 -235.270757) (xy 123.537086 -235.268776) (xy 123.585941 -235.274708)
			(xy 123.633212 -235.2884) (xy 123.677674 -235.309498) (xy 123.718177 -235.337454) (xy 123.75367 -235.371546)
			(xy 123.783235 -235.41089) (xy 123.806106 -235.454467) (xy 123.82169 -235.501148) (xy 123.829585 -235.549725)
			(xy 123.83008 -235.574332) (xy 124.159022 -235.574332) (xy 124.162982 -235.525278) (xy 124.174759 -235.477494)
			(xy 124.19405 -235.432218) (xy 124.220353 -235.390622) (xy 124.252988 -235.353785) (xy 124.291109 -235.32266)
			(xy 124.33373 -235.298053) (xy 124.379746 -235.280601) (xy 124.427965 -235.270757) (xy 124.47714 -235.268776)
			(xy 124.525995 -235.274708) (xy 124.573266 -235.2884) (xy 124.617728 -235.309498) (xy 124.658231 -235.337454)
			(xy 124.693724 -235.371546) (xy 124.723289 -235.41089) (xy 124.74616 -235.454467) (xy 124.761744 -235.501148)
			(xy 124.769639 -235.549725) (xy 124.770134 -235.574332) (xy 125.098822 -235.574332) (xy 125.102782 -235.525278)
			(xy 125.114559 -235.477494) (xy 125.13385 -235.432218) (xy 125.160153 -235.390622) (xy 125.192788 -235.353785)
			(xy 125.230909 -235.32266) (xy 125.27353 -235.298053) (xy 125.319546 -235.280601) (xy 125.367765 -235.270757)
			(xy 125.41694 -235.268776) (xy 125.465795 -235.274708) (xy 125.513066 -235.2884) (xy 125.557528 -235.309498)
			(xy 125.598031 -235.337454) (xy 125.633524 -235.371546) (xy 125.663089 -235.41089) (xy 125.68596 -235.454467)
			(xy 125.701544 -235.501148) (xy 125.709439 -235.549725) (xy 125.709934 -235.574332) (xy 126.038876 -235.574332)
			(xy 126.042836 -235.525278) (xy 126.054613 -235.477494) (xy 126.073904 -235.432218) (xy 126.100207 -235.390622)
			(xy 126.132842 -235.353785) (xy 126.170963 -235.32266) (xy 126.213584 -235.298053) (xy 126.2596 -235.280601)
			(xy 126.307819 -235.270757) (xy 126.356994 -235.268776) (xy 126.405849 -235.274708) (xy 126.45312 -235.2884)
			(xy 126.497582 -235.309498) (xy 126.538085 -235.337454) (xy 126.573578 -235.371546) (xy 126.603143 -235.41089)
			(xy 126.626014 -235.454467) (xy 126.641598 -235.501148) (xy 126.649493 -235.549725) (xy 126.649988 -235.574332)
			(xy 126.649493 -235.598939) (xy 126.641598 -235.647516) (xy 126.626014 -235.694197) (xy 126.603143 -235.737774)
			(xy 126.573578 -235.777118) (xy 126.538085 -235.81121) (xy 126.497582 -235.839166) (xy 126.45312 -235.860264)
			(xy 126.405849 -235.873956) (xy 126.356994 -235.879888) (xy 126.307819 -235.877907) (xy 126.2596 -235.868063)
			(xy 126.213584 -235.850611) (xy 126.170963 -235.826004) (xy 126.132842 -235.794879) (xy 126.100207 -235.758042)
			(xy 126.073904 -235.716446) (xy 126.054613 -235.67117) (xy 126.042836 -235.623386) (xy 126.038876 -235.574332)
			(xy 125.709934 -235.574332) (xy 125.709439 -235.598939) (xy 125.701544 -235.647516) (xy 125.68596 -235.694197)
			(xy 125.663089 -235.737774) (xy 125.633524 -235.777118) (xy 125.598031 -235.81121) (xy 125.557528 -235.839166)
			(xy 125.513066 -235.860264) (xy 125.465795 -235.873956) (xy 125.41694 -235.879888) (xy 125.367765 -235.877907)
			(xy 125.319546 -235.868063) (xy 125.27353 -235.850611) (xy 125.230909 -235.826004) (xy 125.192788 -235.794879)
			(xy 125.160153 -235.758042) (xy 125.13385 -235.716446) (xy 125.114559 -235.67117) (xy 125.102782 -235.623386)
			(xy 125.098822 -235.574332) (xy 124.770134 -235.574332) (xy 124.769639 -235.598939) (xy 124.761744 -235.647516)
			(xy 124.74616 -235.694197) (xy 124.723289 -235.737774) (xy 124.693724 -235.777118) (xy 124.658231 -235.81121)
			(xy 124.617728 -235.839166) (xy 124.573266 -235.860264) (xy 124.525995 -235.873956) (xy 124.47714 -235.879888)
			(xy 124.427965 -235.877907) (xy 124.379746 -235.868063) (xy 124.33373 -235.850611) (xy 124.291109 -235.826004)
			(xy 124.252988 -235.794879) (xy 124.220353 -235.758042) (xy 124.19405 -235.716446) (xy 124.174759 -235.67117)
			(xy 124.162982 -235.623386) (xy 124.159022 -235.574332) (xy 123.83008 -235.574332) (xy 123.829585 -235.598939)
			(xy 123.82169 -235.647516) (xy 123.806106 -235.694197) (xy 123.783235 -235.737774) (xy 123.75367 -235.777118)
			(xy 123.718177 -235.81121) (xy 123.677674 -235.839166) (xy 123.633212 -235.860264) (xy 123.585941 -235.873956)
			(xy 123.537086 -235.879888) (xy 123.487911 -235.877907) (xy 123.439692 -235.868063) (xy 123.393676 -235.850611)
			(xy 123.351055 -235.826004) (xy 123.312934 -235.794879) (xy 123.280299 -235.758042) (xy 123.253996 -235.716446)
			(xy 123.234705 -235.67117) (xy 123.222928 -235.623386) (xy 123.218968 -235.574332) (xy 122.890026 -235.574332)
			(xy 122.889531 -235.598939) (xy 122.881636 -235.647516) (xy 122.866052 -235.694197) (xy 122.843181 -235.737774)
			(xy 122.813616 -235.777118) (xy 122.778123 -235.81121) (xy 122.73762 -235.839166) (xy 122.693158 -235.860264)
			(xy 122.645887 -235.873956) (xy 122.597032 -235.879888) (xy 122.547857 -235.877907) (xy 122.499638 -235.868063)
			(xy 122.453622 -235.850611) (xy 122.411001 -235.826004) (xy 122.37288 -235.794879) (xy 122.340245 -235.758042)
			(xy 122.313942 -235.716446) (xy 122.294651 -235.67117) (xy 122.282874 -235.623386) (xy 122.278914 -235.574332)
			(xy 121.949972 -235.574332) (xy 121.949477 -235.598939) (xy 121.941582 -235.647516) (xy 121.925998 -235.694197)
			(xy 121.903127 -235.737774) (xy 121.873562 -235.777118) (xy 121.838069 -235.81121) (xy 121.797566 -235.839166)
			(xy 121.753104 -235.860264) (xy 121.705833 -235.873956) (xy 121.656978 -235.879888) (xy 121.607803 -235.877907)
			(xy 121.559584 -235.868063) (xy 121.513568 -235.850611) (xy 121.470947 -235.826004) (xy 121.432826 -235.794879)
			(xy 121.400191 -235.758042) (xy 121.373888 -235.716446) (xy 121.354597 -235.67117) (xy 121.34282 -235.623386)
			(xy 121.33886 -235.574332) (xy 121.009918 -235.574332) (xy 121.009423 -235.598939) (xy 121.001528 -235.647516)
			(xy 120.985944 -235.694197) (xy 120.963073 -235.737774) (xy 120.933508 -235.777118) (xy 120.898015 -235.81121)
			(xy 120.857512 -235.839166) (xy 120.81305 -235.860264) (xy 120.765779 -235.873956) (xy 120.716924 -235.879888)
			(xy 120.667749 -235.877907) (xy 120.61953 -235.868063) (xy 120.573514 -235.850611) (xy 120.530893 -235.826004)
			(xy 120.492772 -235.794879) (xy 120.460137 -235.758042) (xy 120.433834 -235.716446) (xy 120.414543 -235.67117)
			(xy 120.402766 -235.623386) (xy 120.398806 -235.574332) (xy 120.070118 -235.574332) (xy 120.069623 -235.598939)
			(xy 120.061728 -235.647516) (xy 120.046144 -235.694197) (xy 120.023273 -235.737774) (xy 119.993708 -235.777118)
			(xy 119.958215 -235.81121) (xy 119.917712 -235.839166) (xy 119.87325 -235.860264) (xy 119.825979 -235.873956)
			(xy 119.777124 -235.879888) (xy 119.727949 -235.877907) (xy 119.67973 -235.868063) (xy 119.633714 -235.850611)
			(xy 119.591093 -235.826004) (xy 119.552972 -235.794879) (xy 119.520337 -235.758042) (xy 119.494034 -235.716446)
			(xy 119.474743 -235.67117) (xy 119.462966 -235.623386) (xy 119.459006 -235.574332) (xy 119.130064 -235.574332)
			(xy 119.129569 -235.598939) (xy 119.121674 -235.647516) (xy 119.10609 -235.694197) (xy 119.083219 -235.737774)
			(xy 119.053654 -235.777118) (xy 119.018161 -235.81121) (xy 118.977658 -235.839166) (xy 118.933196 -235.860264)
			(xy 118.885925 -235.873956) (xy 118.83707 -235.879888) (xy 118.787895 -235.877907) (xy 118.739676 -235.868063)
			(xy 118.69366 -235.850611) (xy 118.651039 -235.826004) (xy 118.612918 -235.794879) (xy 118.580283 -235.758042)
			(xy 118.55398 -235.716446) (xy 118.534689 -235.67117) (xy 118.522912 -235.623386) (xy 118.518952 -235.574332)
			(xy 118.19001 -235.574332) (xy 118.189515 -235.598939) (xy 118.18162 -235.647516) (xy 118.166036 -235.694197)
			(xy 118.143165 -235.737774) (xy 118.1136 -235.777118) (xy 118.078107 -235.81121) (xy 118.037604 -235.839166)
			(xy 117.993142 -235.860264) (xy 117.945871 -235.873956) (xy 117.897016 -235.879888) (xy 117.847841 -235.877907)
			(xy 117.799622 -235.868063) (xy 117.753606 -235.850611) (xy 117.710985 -235.826004) (xy 117.672864 -235.794879)
			(xy 117.640229 -235.758042) (xy 117.613926 -235.716446) (xy 117.594635 -235.67117) (xy 117.582858 -235.623386)
			(xy 117.578898 -235.574332) (xy 117.249956 -235.574332) (xy 117.249461 -235.598939) (xy 117.241566 -235.647516)
			(xy 117.225982 -235.694197) (xy 117.203111 -235.737774) (xy 117.173546 -235.777118) (xy 117.138053 -235.81121)
			(xy 117.09755 -235.839166) (xy 117.053088 -235.860264) (xy 117.005817 -235.873956) (xy 116.956962 -235.879888)
			(xy 116.907787 -235.877907) (xy 116.859568 -235.868063) (xy 116.813552 -235.850611) (xy 116.770931 -235.826004)
			(xy 116.73281 -235.794879) (xy 116.700175 -235.758042) (xy 116.673872 -235.716446) (xy 116.654581 -235.67117)
			(xy 116.642804 -235.623386) (xy 116.638844 -235.574332) (xy 116.310156 -235.574332) (xy 116.309661 -235.598939)
			(xy 116.301766 -235.647516) (xy 116.286182 -235.694197) (xy 116.263311 -235.737774) (xy 116.233746 -235.777118)
			(xy 116.198253 -235.81121) (xy 116.15775 -235.839166) (xy 116.113288 -235.860264) (xy 116.066017 -235.873956)
			(xy 116.017162 -235.879888) (xy 115.967987 -235.877907) (xy 115.919768 -235.868063) (xy 115.873752 -235.850611)
			(xy 115.831131 -235.826004) (xy 115.79301 -235.794879) (xy 115.760375 -235.758042) (xy 115.734072 -235.716446)
			(xy 115.714781 -235.67117) (xy 115.703004 -235.623386) (xy 115.699044 -235.574332) (xy 115.370102 -235.574332)
			(xy 115.369607 -235.598939) (xy 115.361712 -235.647516) (xy 115.346128 -235.694197) (xy 115.323257 -235.737774)
			(xy 115.293692 -235.777118) (xy 115.258199 -235.81121) (xy 115.217696 -235.839166) (xy 115.173234 -235.860264)
			(xy 115.125963 -235.873956) (xy 115.077108 -235.879888) (xy 115.027933 -235.877907) (xy 114.979714 -235.868063)
			(xy 114.933698 -235.850611) (xy 114.891077 -235.826004) (xy 114.852956 -235.794879) (xy 114.820321 -235.758042)
			(xy 114.794018 -235.716446) (xy 114.774727 -235.67117) (xy 114.76295 -235.623386) (xy 114.75899 -235.574332)
			(xy 114.430048 -235.574332) (xy 114.429553 -235.598939) (xy 114.421658 -235.647516) (xy 114.406074 -235.694197)
			(xy 114.383203 -235.737774) (xy 114.353638 -235.777118) (xy 114.318145 -235.81121) (xy 114.277642 -235.839166)
			(xy 114.23318 -235.860264) (xy 114.185909 -235.873956) (xy 114.137054 -235.879888) (xy 114.087879 -235.877907)
			(xy 114.03966 -235.868063) (xy 113.993644 -235.850611) (xy 113.951023 -235.826004) (xy 113.912902 -235.794879)
			(xy 113.880267 -235.758042) (xy 113.853964 -235.716446) (xy 113.834673 -235.67117) (xy 113.822896 -235.623386)
			(xy 113.818936 -235.574332) (xy 113.489994 -235.574332) (xy 113.489499 -235.598939) (xy 113.481604 -235.647516)
			(xy 113.46602 -235.694197) (xy 113.443149 -235.737774) (xy 113.413584 -235.777118) (xy 113.378091 -235.81121)
			(xy 113.337588 -235.839166) (xy 113.293126 -235.860264) (xy 113.245855 -235.873956) (xy 113.197 -235.879888)
			(xy 113.147825 -235.877907) (xy 113.099606 -235.868063) (xy 113.05359 -235.850611) (xy 113.010969 -235.826004)
			(xy 112.972848 -235.794879) (xy 112.940213 -235.758042) (xy 112.91391 -235.716446) (xy 112.894619 -235.67117)
			(xy 112.882842 -235.623386) (xy 112.878882 -235.574332) (xy 110.676436 -235.574332) (xy 110.675941 -235.598939)
			(xy 110.668046 -235.647516) (xy 110.652462 -235.694197) (xy 110.629591 -235.737774) (xy 110.600026 -235.777118)
			(xy 110.564533 -235.81121) (xy 110.52403 -235.839166) (xy 110.479568 -235.860264) (xy 110.432297 -235.873956)
			(xy 110.383442 -235.879888) (xy 110.334267 -235.877907) (xy 110.286048 -235.868063) (xy 110.240032 -235.850611)
			(xy 110.197411 -235.826004) (xy 110.15929 -235.794879) (xy 110.126655 -235.758042) (xy 110.100352 -235.716446)
			(xy 110.081061 -235.67117) (xy 110.069284 -235.623386) (xy 110.065324 -235.574332) (xy 109.736989 -235.574332)
			(xy 109.73282 -235.624651) (xy 109.720416 -235.673628) (xy 109.70012 -235.719896) (xy 109.672485 -235.762191)
			(xy 109.638265 -235.799361) (xy 109.598393 -235.830392) (xy 109.553958 -235.854435) (xy 109.506171 -235.870837)
			(xy 109.456336 -235.879149) (xy 109.431074 -235.87964) (xy 108.49102 -235.87964) (xy 108.465764 -235.879085)
			(xy 108.41594 -235.870774) (xy 108.368164 -235.854375) (xy 108.323739 -235.830336) (xy 108.283876 -235.799312)
			(xy 108.249664 -235.76215) (xy 108.222035 -235.719864) (xy 108.201744 -235.673606) (xy 108.189343 -235.62464)
			(xy 108.185172 -235.5743) (xy 107.856273 -235.5743) (xy 107.856274 -235.574332) (xy 107.855779 -235.598939)
			(xy 107.847884 -235.647516) (xy 107.8323 -235.694197) (xy 107.809429 -235.737774) (xy 107.779864 -235.777118)
			(xy 107.744371 -235.81121) (xy 107.703868 -235.839166) (xy 107.659406 -235.860264) (xy 107.612135 -235.873956)
			(xy 107.56328 -235.879888) (xy 107.514105 -235.877907) (xy 107.465886 -235.868063) (xy 107.41987 -235.850611)
			(xy 107.377249 -235.826004) (xy 107.339128 -235.794879) (xy 107.306493 -235.758042) (xy 107.28019 -235.716446)
			(xy 107.260899 -235.67117) (xy 107.249122 -235.623386) (xy 107.245162 -235.574332) (xy 106.916474 -235.574332)
			(xy 106.915979 -235.598939) (xy 106.908084 -235.647516) (xy 106.8925 -235.694197) (xy 106.869629 -235.737774)
			(xy 106.840064 -235.777118) (xy 106.804571 -235.81121) (xy 106.764068 -235.839166) (xy 106.719606 -235.860264)
			(xy 106.672335 -235.873956) (xy 106.62348 -235.879888) (xy 106.574305 -235.877907) (xy 106.526086 -235.868063)
			(xy 106.48007 -235.850611) (xy 106.437449 -235.826004) (xy 106.399328 -235.794879) (xy 106.366693 -235.758042)
			(xy 106.34039 -235.716446) (xy 106.321099 -235.67117) (xy 106.309322 -235.623386) (xy 106.305362 -235.574332)
			(xy 105.97642 -235.574332) (xy 105.975925 -235.598939) (xy 105.96803 -235.647516) (xy 105.952446 -235.694197)
			(xy 105.929575 -235.737774) (xy 105.90001 -235.777118) (xy 105.864517 -235.81121) (xy 105.824014 -235.839166)
			(xy 105.779552 -235.860264) (xy 105.732281 -235.873956) (xy 105.683426 -235.879888) (xy 105.634251 -235.877907)
			(xy 105.586032 -235.868063) (xy 105.540016 -235.850611) (xy 105.497395 -235.826004) (xy 105.459274 -235.794879)
			(xy 105.426639 -235.758042) (xy 105.400336 -235.716446) (xy 105.381045 -235.67117) (xy 105.369268 -235.623386)
			(xy 105.365308 -235.574332) (xy 105.036366 -235.574332) (xy 105.035871 -235.598939) (xy 105.027976 -235.647516)
			(xy 105.012392 -235.694197) (xy 104.989521 -235.737774) (xy 104.959956 -235.777118) (xy 104.924463 -235.81121)
			(xy 104.88396 -235.839166) (xy 104.839498 -235.860264) (xy 104.792227 -235.873956) (xy 104.743372 -235.879888)
			(xy 104.694197 -235.877907) (xy 104.645978 -235.868063) (xy 104.599962 -235.850611) (xy 104.557341 -235.826004)
			(xy 104.51922 -235.794879) (xy 104.486585 -235.758042) (xy 104.460282 -235.716446) (xy 104.440991 -235.67117)
			(xy 104.429214 -235.623386) (xy 104.425254 -235.574332) (xy 104.096312 -235.574332) (xy 104.095817 -235.598939)
			(xy 104.087922 -235.647516) (xy 104.072338 -235.694197) (xy 104.049467 -235.737774) (xy 104.019902 -235.777118)
			(xy 103.984409 -235.81121) (xy 103.943906 -235.839166) (xy 103.899444 -235.860264) (xy 103.852173 -235.873956)
			(xy 103.803318 -235.879888) (xy 103.754143 -235.877907) (xy 103.705924 -235.868063) (xy 103.659908 -235.850611)
			(xy 103.617287 -235.826004) (xy 103.579166 -235.794879) (xy 103.546531 -235.758042) (xy 103.520228 -235.716446)
			(xy 103.500937 -235.67117) (xy 103.48916 -235.623386) (xy 103.4852 -235.574332) (xy 103.156258 -235.574332)
			(xy 103.155763 -235.598939) (xy 103.147868 -235.647516) (xy 103.132284 -235.694197) (xy 103.109413 -235.737774)
			(xy 103.079848 -235.777118) (xy 103.044355 -235.81121) (xy 103.003852 -235.839166) (xy 102.95939 -235.860264)
			(xy 102.912119 -235.873956) (xy 102.863264 -235.879888) (xy 102.814089 -235.877907) (xy 102.76587 -235.868063)
			(xy 102.719854 -235.850611) (xy 102.677233 -235.826004) (xy 102.639112 -235.794879) (xy 102.606477 -235.758042)
			(xy 102.580174 -235.716446) (xy 102.560883 -235.67117) (xy 102.549106 -235.623386) (xy 102.545146 -235.574332)
			(xy 102.216458 -235.574332) (xy 102.215963 -235.598939) (xy 102.208068 -235.647516) (xy 102.192484 -235.694197)
			(xy 102.169613 -235.737774) (xy 102.140048 -235.777118) (xy 102.104555 -235.81121) (xy 102.064052 -235.839166)
			(xy 102.01959 -235.860264) (xy 101.972319 -235.873956) (xy 101.923464 -235.879888) (xy 101.874289 -235.877907)
			(xy 101.82607 -235.868063) (xy 101.780054 -235.850611) (xy 101.737433 -235.826004) (xy 101.699312 -235.794879)
			(xy 101.666677 -235.758042) (xy 101.640374 -235.716446) (xy 101.621083 -235.67117) (xy 101.609306 -235.623386)
			(xy 101.605346 -235.574332) (xy 101.276404 -235.574332) (xy 101.275909 -235.598939) (xy 101.268014 -235.647516)
			(xy 101.25243 -235.694197) (xy 101.229559 -235.737774) (xy 101.199994 -235.777118) (xy 101.164501 -235.81121)
			(xy 101.123998 -235.839166) (xy 101.079536 -235.860264) (xy 101.032265 -235.873956) (xy 100.98341 -235.879888)
			(xy 100.934235 -235.877907) (xy 100.886016 -235.868063) (xy 100.84 -235.850611) (xy 100.797379 -235.826004)
			(xy 100.759258 -235.794879) (xy 100.726623 -235.758042) (xy 100.70032 -235.716446) (xy 100.681029 -235.67117)
			(xy 100.669252 -235.623386) (xy 100.665292 -235.574332) (xy 100.33635 -235.574332) (xy 100.335855 -235.598939)
			(xy 100.32796 -235.647516) (xy 100.312376 -235.694197) (xy 100.289505 -235.737774) (xy 100.25994 -235.777118)
			(xy 100.224447 -235.81121) (xy 100.183944 -235.839166) (xy 100.139482 -235.860264) (xy 100.092211 -235.873956)
			(xy 100.043356 -235.879888) (xy 99.994181 -235.877907) (xy 99.945962 -235.868063) (xy 99.899946 -235.850611)
			(xy 99.857325 -235.826004) (xy 99.819204 -235.794879) (xy 99.786569 -235.758042) (xy 99.760266 -235.716446)
			(xy 99.740975 -235.67117) (xy 99.729198 -235.623386) (xy 99.725238 -235.574332) (xy 99.396296 -235.574332)
			(xy 99.395801 -235.598939) (xy 99.387906 -235.647516) (xy 99.372322 -235.694197) (xy 99.349451 -235.737774)
			(xy 99.319886 -235.777118) (xy 99.284393 -235.81121) (xy 99.24389 -235.839166) (xy 99.199428 -235.860264)
			(xy 99.152157 -235.873956) (xy 99.103302 -235.879888) (xy 99.054127 -235.877907) (xy 99.005908 -235.868063)
			(xy 98.959892 -235.850611) (xy 98.917271 -235.826004) (xy 98.87915 -235.794879) (xy 98.846515 -235.758042)
			(xy 98.820212 -235.716446) (xy 98.800921 -235.67117) (xy 98.789144 -235.623386) (xy 98.785184 -235.574332)
			(xy 98.456242 -235.574332) (xy 98.455747 -235.598939) (xy 98.447852 -235.647516) (xy 98.432268 -235.694197)
			(xy 98.409397 -235.737774) (xy 98.379832 -235.777118) (xy 98.344339 -235.81121) (xy 98.303836 -235.839166)
			(xy 98.259374 -235.860264) (xy 98.212103 -235.873956) (xy 98.163248 -235.879888) (xy 98.114073 -235.877907)
			(xy 98.065854 -235.868063) (xy 98.019838 -235.850611) (xy 97.977217 -235.826004) (xy 97.939096 -235.794879)
			(xy 97.906461 -235.758042) (xy 97.880158 -235.716446) (xy 97.860867 -235.67117) (xy 97.84909 -235.623386)
			(xy 97.84513 -235.574332) (xy 97.516442 -235.574332) (xy 97.515947 -235.598939) (xy 97.508052 -235.647516)
			(xy 97.492468 -235.694197) (xy 97.469597 -235.737774) (xy 97.440032 -235.777118) (xy 97.404539 -235.81121)
			(xy 97.364036 -235.839166) (xy 97.319574 -235.860264) (xy 97.272303 -235.873956) (xy 97.223448 -235.879888)
			(xy 97.174273 -235.877907) (xy 97.126054 -235.868063) (xy 97.080038 -235.850611) (xy 97.037417 -235.826004)
			(xy 96.999296 -235.794879) (xy 96.966661 -235.758042) (xy 96.940358 -235.716446) (xy 96.921067 -235.67117)
			(xy 96.90929 -235.623386) (xy 96.90533 -235.574332) (xy 96.575942 -235.574332) (xy 96.575953 -235.59836)
			(xy 96.56841 -235.645956) (xy 96.553491 -235.691779) (xy 96.531565 -235.734693) (xy 96.503175 -235.773633)
			(xy 96.469026 -235.807635) (xy 96.429963 -235.835856) (xy 96.386955 -235.857596) (xy 96.341068 -235.872317)
			(xy 96.317308 -235.876338) (xy 96.3168 -235.876338) (xy 96.316292 -235.876592) (xy 96.307528 -235.878255)
			(xy 96.291905 -235.886841) (xy 96.285812 -235.893356) (xy 96.280224 -235.899706) (xy 96.273874 -235.916724)
			(xy 96.273874 -236.071664) (xy 96.274064 -236.077898) (xy 96.27715 -236.089977) (xy 96.27997 -236.09554)
			(xy 96.284542 -236.103414) (xy 96.295085 -236.122016) (xy 96.313647 -236.160539) (xy 96.321626 -236.180376)
			(xy 96.323658 -236.185456) (xy 96.326452 -236.193076) (xy 96.33712 -236.201458) (xy 96.342595 -236.205418)
			(xy 96.355083 -236.210565) (xy 96.361758 -236.211618) (xy 96.448372 -236.223048) (xy 96.455111 -236.223632)
			(xy 96.468495 -236.221714) (xy 96.474788 -236.219238) (xy 96.48698 -236.214158) (xy 96.490536 -236.209586)
			(xy 96.495616 -236.202728) (xy 96.51012 -236.1839) (xy 96.543976 -236.150546) (xy 96.582589 -236.122839)
			(xy 96.625028 -236.101446) (xy 96.670268 -236.086884) (xy 96.717217 -236.079505) (xy 96.74098 -236.07903)
			(xy 96.766236 -236.079521) (xy 96.816059 -236.087832) (xy 96.863834 -236.10423) (xy 96.908258 -236.128269)
			(xy 96.94812 -236.159292) (xy 96.982331 -236.196454) (xy 97.009959 -236.238739) (xy 97.03025 -236.284996)
			(xy 97.042651 -236.333961) (xy 97.046822 -236.3843) (xy 97.374923 -236.3843) (xy 97.379099 -236.333918)
			(xy 97.39151 -236.28491) (xy 97.411819 -236.238614) (xy 97.439471 -236.196293) (xy 97.473713 -236.1591)
			(xy 97.51361 -236.128051) (xy 97.558073 -236.103993) (xy 97.60589 -236.087582) (xy 97.655757 -236.079266)
			(xy 97.681034 -236.078776) (xy 98.621088 -236.078776) (xy 98.646371 -236.079192) (xy 98.696246 -236.087513)
			(xy 98.744072 -236.10393) (xy 98.788543 -236.127995) (xy 98.828447 -236.159052) (xy 98.862694 -236.196253)
			(xy 98.890351 -236.238584) (xy 98.910663 -236.28489) (xy 98.923077 -236.333908) (xy 98.927253 -236.3843)
			(xy 98.92725 -236.384338) (xy 99.255338 -236.384338) (xy 99.259298 -236.335284) (xy 99.271075 -236.2875)
			(xy 99.290366 -236.242224) (xy 99.316669 -236.200628) (xy 99.349304 -236.163791) (xy 99.387425 -236.132666)
			(xy 99.430046 -236.108059) (xy 99.476062 -236.090607) (xy 99.524281 -236.080763) (xy 99.573456 -236.078782)
			(xy 99.622311 -236.084714) (xy 99.669582 -236.098406) (xy 99.714044 -236.119504) (xy 99.754547 -236.14746)
			(xy 99.79004 -236.181552) (xy 99.819605 -236.220896) (xy 99.842476 -236.264473) (xy 99.85806 -236.311154)
			(xy 99.865955 -236.359731) (xy 99.866449 -236.3843) (xy 100.194823 -236.3843) (xy 100.198999 -236.333917)
			(xy 100.21141 -236.284909) (xy 100.23172 -236.238612) (xy 100.259374 -236.19629) (xy 100.293616 -236.159097)
			(xy 100.333514 -236.128048) (xy 100.377979 -236.103991) (xy 100.425797 -236.087581) (xy 100.475664 -236.079266)
			(xy 100.500942 -236.078776) (xy 101.440996 -236.078776) (xy 101.466278 -236.079193) (xy 101.516153 -236.087515)
			(xy 101.563977 -236.103933) (xy 101.608447 -236.127998) (xy 101.64835 -236.159055) (xy 101.682596 -236.196256)
			(xy 101.710252 -236.238586) (xy 101.730564 -236.284892) (xy 101.742977 -236.333909) (xy 101.747153 -236.3843)
			(xy 101.74715 -236.384338) (xy 102.075246 -236.384338) (xy 102.079206 -236.335284) (xy 102.090983 -236.2875)
			(xy 102.110274 -236.242224) (xy 102.136577 -236.200628) (xy 102.169212 -236.163791) (xy 102.207333 -236.132666)
			(xy 102.249954 -236.108059) (xy 102.29597 -236.090607) (xy 102.344189 -236.080763) (xy 102.393364 -236.078782)
			(xy 102.442219 -236.084714) (xy 102.48949 -236.098406) (xy 102.533952 -236.119504) (xy 102.574455 -236.14746)
			(xy 102.609948 -236.181552) (xy 102.639513 -236.220896) (xy 102.662384 -236.264473) (xy 102.677968 -236.311154)
			(xy 102.685863 -236.359731) (xy 102.686358 -236.384338) (xy 104.895154 -236.384338) (xy 104.899114 -236.335284)
			(xy 104.910891 -236.2875) (xy 104.930182 -236.242224) (xy 104.956485 -236.200628) (xy 104.98912 -236.163791)
			(xy 105.027241 -236.132666) (xy 105.069862 -236.108059) (xy 105.115878 -236.090607) (xy 105.164097 -236.080763)
			(xy 105.213272 -236.078782) (xy 105.262127 -236.084714) (xy 105.309398 -236.098406) (xy 105.35386 -236.119504)
			(xy 105.394363 -236.14746) (xy 105.429856 -236.181552) (xy 105.459421 -236.220896) (xy 105.482292 -236.264473)
			(xy 105.497876 -236.311154) (xy 105.505771 -236.359731) (xy 105.506266 -236.384338) (xy 107.715316 -236.384338)
			(xy 107.719276 -236.335284) (xy 107.731053 -236.2875) (xy 107.750344 -236.242224) (xy 107.776647 -236.200628)
			(xy 107.809282 -236.163791) (xy 107.847403 -236.132666) (xy 107.890024 -236.108059) (xy 107.93604 -236.090607)
			(xy 107.984259 -236.080763) (xy 108.033434 -236.078782) (xy 108.082289 -236.084714) (xy 108.12956 -236.098406)
			(xy 108.174022 -236.119504) (xy 108.214525 -236.14746) (xy 108.250018 -236.181552) (xy 108.279583 -236.220896)
			(xy 108.302454 -236.264473) (xy 108.318038 -236.311154) (xy 108.325933 -236.359731) (xy 108.326428 -236.384338)
			(xy 108.65537 -236.384338) (xy 108.65933 -236.335284) (xy 108.671107 -236.2875) (xy 108.690398 -236.242224)
			(xy 108.716701 -236.200628) (xy 108.749336 -236.163791) (xy 108.787457 -236.132666) (xy 108.830078 -236.108059)
			(xy 108.876094 -236.090607) (xy 108.924313 -236.080763) (xy 108.973488 -236.078782) (xy 109.022343 -236.084714)
			(xy 109.069614 -236.098406) (xy 109.114076 -236.119504) (xy 109.154579 -236.14746) (xy 109.190072 -236.181552)
			(xy 109.219637 -236.220896) (xy 109.242508 -236.264473) (xy 109.258092 -236.311154) (xy 109.265987 -236.359731)
			(xy 109.266482 -236.384338) (xy 109.59517 -236.384338) (xy 109.59913 -236.335284) (xy 109.610907 -236.2875)
			(xy 109.630198 -236.242224) (xy 109.656501 -236.200628) (xy 109.689136 -236.163791) (xy 109.727257 -236.132666)
			(xy 109.769878 -236.108059) (xy 109.815894 -236.090607) (xy 109.864113 -236.080763) (xy 109.913288 -236.078782)
			(xy 109.962143 -236.084714) (xy 110.009414 -236.098406) (xy 110.053876 -236.119504) (xy 110.094379 -236.14746)
			(xy 110.129872 -236.181552) (xy 110.159437 -236.220896) (xy 110.182308 -236.264473) (xy 110.197892 -236.311154)
			(xy 110.205787 -236.359731) (xy 110.206282 -236.384338) (xy 113.349036 -236.384338) (xy 113.352996 -236.335284)
			(xy 113.364773 -236.2875) (xy 113.384064 -236.242224) (xy 113.410367 -236.200628) (xy 113.443002 -236.163791)
			(xy 113.481123 -236.132666) (xy 113.523744 -236.108059) (xy 113.56976 -236.090607) (xy 113.617979 -236.080763)
			(xy 113.667154 -236.078782) (xy 113.716009 -236.084714) (xy 113.76328 -236.098406) (xy 113.807742 -236.119504)
			(xy 113.848245 -236.14746) (xy 113.883738 -236.181552) (xy 113.913303 -236.220896) (xy 113.936174 -236.264473)
			(xy 113.951758 -236.311154) (xy 113.959653 -236.359731) (xy 113.960148 -236.384338) (xy 114.288836 -236.384338)
			(xy 114.292796 -236.335284) (xy 114.304573 -236.2875) (xy 114.323864 -236.242224) (xy 114.350167 -236.200628)
			(xy 114.382802 -236.163791) (xy 114.420923 -236.132666) (xy 114.463544 -236.108059) (xy 114.50956 -236.090607)
			(xy 114.557779 -236.080763) (xy 114.606954 -236.078782) (xy 114.655809 -236.084714) (xy 114.70308 -236.098406)
			(xy 114.747542 -236.119504) (xy 114.788045 -236.14746) (xy 114.823538 -236.181552) (xy 114.853103 -236.220896)
			(xy 114.875974 -236.264473) (xy 114.891558 -236.311154) (xy 114.899453 -236.359731) (xy 114.899948 -236.384338)
			(xy 115.22889 -236.384338) (xy 115.23285 -236.335284) (xy 115.244627 -236.2875) (xy 115.263918 -236.242224)
			(xy 115.290221 -236.200628) (xy 115.322856 -236.163791) (xy 115.360977 -236.132666) (xy 115.403598 -236.108059)
			(xy 115.449614 -236.090607) (xy 115.497833 -236.080763) (xy 115.547008 -236.078782) (xy 115.595863 -236.084714)
			(xy 115.643134 -236.098406) (xy 115.687596 -236.119504) (xy 115.728099 -236.14746) (xy 115.763592 -236.181552)
			(xy 115.793157 -236.220896) (xy 115.816028 -236.264473) (xy 115.831612 -236.311154) (xy 115.839507 -236.359731)
			(xy 115.840002 -236.384338) (xy 118.049052 -236.384338) (xy 118.053012 -236.335284) (xy 118.064789 -236.2875)
			(xy 118.08408 -236.242224) (xy 118.110383 -236.200628) (xy 118.143018 -236.163791) (xy 118.181139 -236.132666)
			(xy 118.22376 -236.108059) (xy 118.269776 -236.090607) (xy 118.317995 -236.080763) (xy 118.36717 -236.078782)
			(xy 118.416025 -236.084714) (xy 118.463296 -236.098406) (xy 118.507758 -236.119504) (xy 118.548261 -236.14746)
			(xy 118.583754 -236.181552) (xy 118.613319 -236.220896) (xy 118.63619 -236.264473) (xy 118.651774 -236.311154)
			(xy 118.659669 -236.359731) (xy 118.660164 -236.384338) (xy 120.86896 -236.384338) (xy 120.87292 -236.335284)
			(xy 120.884697 -236.2875) (xy 120.903988 -236.242224) (xy 120.930291 -236.200628) (xy 120.962926 -236.163791)
			(xy 121.001047 -236.132666) (xy 121.043668 -236.108059) (xy 121.089684 -236.090607) (xy 121.137903 -236.080763)
			(xy 121.187078 -236.078782) (xy 121.235933 -236.084714) (xy 121.283204 -236.098406) (xy 121.327666 -236.119504)
			(xy 121.368169 -236.14746) (xy 121.403662 -236.181552) (xy 121.433227 -236.220896) (xy 121.456098 -236.264473)
			(xy 121.471682 -236.311154) (xy 121.479577 -236.359731) (xy 121.480072 -236.384338) (xy 121.809014 -236.384338)
			(xy 121.812974 -236.335284) (xy 121.824751 -236.2875) (xy 121.844042 -236.242224) (xy 121.870345 -236.200628)
			(xy 121.90298 -236.163791) (xy 121.941101 -236.132666) (xy 121.983722 -236.108059) (xy 122.029738 -236.090607)
			(xy 122.077957 -236.080763) (xy 122.127132 -236.078782) (xy 122.175987 -236.084714) (xy 122.223258 -236.098406)
			(xy 122.26772 -236.119504) (xy 122.308223 -236.14746) (xy 122.343716 -236.181552) (xy 122.373281 -236.220896)
			(xy 122.396152 -236.264473) (xy 122.411736 -236.311154) (xy 122.419631 -236.359731) (xy 122.420126 -236.384338)
			(xy 122.748814 -236.384338) (xy 122.752774 -236.335284) (xy 122.764551 -236.2875) (xy 122.783842 -236.242224)
			(xy 122.810145 -236.200628) (xy 122.84278 -236.163791) (xy 122.880901 -236.132666) (xy 122.923522 -236.108059)
			(xy 122.969538 -236.090607) (xy 123.017757 -236.080763) (xy 123.066932 -236.078782) (xy 123.115787 -236.084714)
			(xy 123.163058 -236.098406) (xy 123.20752 -236.119504) (xy 123.248023 -236.14746) (xy 123.283516 -236.181552)
			(xy 123.313081 -236.220896) (xy 123.335952 -236.264473) (xy 123.351536 -236.311154) (xy 123.359431 -236.359731)
			(xy 123.359926 -236.384338) (xy 123.688868 -236.384338) (xy 123.692828 -236.335284) (xy 123.704605 -236.2875)
			(xy 123.723896 -236.242224) (xy 123.750199 -236.200628) (xy 123.782834 -236.163791) (xy 123.820955 -236.132666)
			(xy 123.863576 -236.108059) (xy 123.909592 -236.090607) (xy 123.957811 -236.080763) (xy 124.006986 -236.078782)
			(xy 124.055841 -236.084714) (xy 124.103112 -236.098406) (xy 124.147574 -236.119504) (xy 124.188077 -236.14746)
			(xy 124.22357 -236.181552) (xy 124.253135 -236.220896) (xy 124.276006 -236.264473) (xy 124.29159 -236.311154)
			(xy 124.299485 -236.359731) (xy 124.29998 -236.384338) (xy 124.628922 -236.384338) (xy 124.632882 -236.335284)
			(xy 124.644659 -236.2875) (xy 124.66395 -236.242224) (xy 124.690253 -236.200628) (xy 124.722888 -236.163791)
			(xy 124.761009 -236.132666) (xy 124.80363 -236.108059) (xy 124.849646 -236.090607) (xy 124.897865 -236.080763)
			(xy 124.94704 -236.078782) (xy 124.995895 -236.084714) (xy 125.043166 -236.098406) (xy 125.087628 -236.119504)
			(xy 125.128131 -236.14746) (xy 125.163624 -236.181552) (xy 125.193189 -236.220896) (xy 125.21606 -236.264473)
			(xy 125.231644 -236.311154) (xy 125.239539 -236.359731) (xy 125.240034 -236.384338) (xy 125.568976 -236.384338)
			(xy 125.572936 -236.335284) (xy 125.584713 -236.2875) (xy 125.604004 -236.242224) (xy 125.630307 -236.200628)
			(xy 125.662942 -236.163791) (xy 125.701063 -236.132666) (xy 125.743684 -236.108059) (xy 125.7897 -236.090607)
			(xy 125.837919 -236.080763) (xy 125.887094 -236.078782) (xy 125.935949 -236.084714) (xy 125.98322 -236.098406)
			(xy 126.027682 -236.119504) (xy 126.068185 -236.14746) (xy 126.103678 -236.181552) (xy 126.133243 -236.220896)
			(xy 126.156114 -236.264473) (xy 126.171698 -236.311154) (xy 126.179593 -236.359731) (xy 126.180088 -236.384338)
			(xy 126.179593 -236.408945) (xy 126.171698 -236.457522) (xy 126.156114 -236.504203) (xy 126.133243 -236.54778)
			(xy 126.103678 -236.587124) (xy 126.068185 -236.621216) (xy 126.027682 -236.649172) (xy 125.98322 -236.67027)
			(xy 125.935949 -236.683962) (xy 125.887094 -236.689894) (xy 125.837919 -236.687913) (xy 125.7897 -236.678069)
			(xy 125.743684 -236.660617) (xy 125.701063 -236.63601) (xy 125.662942 -236.604885) (xy 125.630307 -236.568048)
			(xy 125.604004 -236.526452) (xy 125.584713 -236.481176) (xy 125.572936 -236.433392) (xy 125.568976 -236.384338)
			(xy 125.240034 -236.384338) (xy 125.239539 -236.408945) (xy 125.231644 -236.457522) (xy 125.21606 -236.504203)
			(xy 125.193189 -236.54778) (xy 125.163624 -236.587124) (xy 125.128131 -236.621216) (xy 125.087628 -236.649172)
			(xy 125.043166 -236.67027) (xy 124.995895 -236.683962) (xy 124.94704 -236.689894) (xy 124.897865 -236.687913)
			(xy 124.849646 -236.678069) (xy 124.80363 -236.660617) (xy 124.761009 -236.63601) (xy 124.722888 -236.604885)
			(xy 124.690253 -236.568048) (xy 124.66395 -236.526452) (xy 124.644659 -236.481176) (xy 124.632882 -236.433392)
			(xy 124.628922 -236.384338) (xy 124.29998 -236.384338) (xy 124.299485 -236.408945) (xy 124.29159 -236.457522)
			(xy 124.276006 -236.504203) (xy 124.253135 -236.54778) (xy 124.22357 -236.587124) (xy 124.188077 -236.621216)
			(xy 124.147574 -236.649172) (xy 124.103112 -236.67027) (xy 124.055841 -236.683962) (xy 124.006986 -236.689894)
			(xy 123.957811 -236.687913) (xy 123.909592 -236.678069) (xy 123.863576 -236.660617) (xy 123.820955 -236.63601)
			(xy 123.782834 -236.604885) (xy 123.750199 -236.568048) (xy 123.723896 -236.526452) (xy 123.704605 -236.481176)
			(xy 123.692828 -236.433392) (xy 123.688868 -236.384338) (xy 123.359926 -236.384338) (xy 123.359431 -236.408945)
			(xy 123.351536 -236.457522) (xy 123.335952 -236.504203) (xy 123.313081 -236.54778) (xy 123.283516 -236.587124)
			(xy 123.248023 -236.621216) (xy 123.20752 -236.649172) (xy 123.163058 -236.67027) (xy 123.115787 -236.683962)
			(xy 123.066932 -236.689894) (xy 123.017757 -236.687913) (xy 122.969538 -236.678069) (xy 122.923522 -236.660617)
			(xy 122.880901 -236.63601) (xy 122.84278 -236.604885) (xy 122.810145 -236.568048) (xy 122.783842 -236.526452)
			(xy 122.764551 -236.481176) (xy 122.752774 -236.433392) (xy 122.748814 -236.384338) (xy 122.420126 -236.384338)
			(xy 122.419631 -236.408945) (xy 122.411736 -236.457522) (xy 122.396152 -236.504203) (xy 122.373281 -236.54778)
			(xy 122.343716 -236.587124) (xy 122.308223 -236.621216) (xy 122.26772 -236.649172) (xy 122.223258 -236.67027)
			(xy 122.175987 -236.683962) (xy 122.127132 -236.689894) (xy 122.077957 -236.687913) (xy 122.029738 -236.678069)
			(xy 121.983722 -236.660617) (xy 121.941101 -236.63601) (xy 121.90298 -236.604885) (xy 121.870345 -236.568048)
			(xy 121.844042 -236.526452) (xy 121.824751 -236.481176) (xy 121.812974 -236.433392) (xy 121.809014 -236.384338)
			(xy 121.480072 -236.384338) (xy 121.479577 -236.408945) (xy 121.471682 -236.457522) (xy 121.456098 -236.504203)
			(xy 121.433227 -236.54778) (xy 121.403662 -236.587124) (xy 121.368169 -236.621216) (xy 121.327666 -236.649172)
			(xy 121.283204 -236.67027) (xy 121.235933 -236.683962) (xy 121.187078 -236.689894) (xy 121.137903 -236.687913)
			(xy 121.089684 -236.678069) (xy 121.043668 -236.660617) (xy 121.001047 -236.63601) (xy 120.962926 -236.604885)
			(xy 120.930291 -236.568048) (xy 120.903988 -236.526452) (xy 120.884697 -236.481176) (xy 120.87292 -236.433392)
			(xy 120.86896 -236.384338) (xy 118.660164 -236.384338) (xy 118.659669 -236.408945) (xy 118.651774 -236.457522)
			(xy 118.63619 -236.504203) (xy 118.613319 -236.54778) (xy 118.583754 -236.587124) (xy 118.548261 -236.621216)
			(xy 118.507758 -236.649172) (xy 118.463296 -236.67027) (xy 118.416025 -236.683962) (xy 118.36717 -236.689894)
			(xy 118.317995 -236.687913) (xy 118.269776 -236.678069) (xy 118.22376 -236.660617) (xy 118.181139 -236.63601)
			(xy 118.143018 -236.604885) (xy 118.110383 -236.568048) (xy 118.08408 -236.526452) (xy 118.064789 -236.481176)
			(xy 118.053012 -236.433392) (xy 118.049052 -236.384338) (xy 115.840002 -236.384338) (xy 115.839507 -236.408945)
			(xy 115.831612 -236.457522) (xy 115.816028 -236.504203) (xy 115.793157 -236.54778) (xy 115.763592 -236.587124)
			(xy 115.728099 -236.621216) (xy 115.687596 -236.649172) (xy 115.643134 -236.67027) (xy 115.595863 -236.683962)
			(xy 115.547008 -236.689894) (xy 115.497833 -236.687913) (xy 115.449614 -236.678069) (xy 115.403598 -236.660617)
			(xy 115.360977 -236.63601) (xy 115.322856 -236.604885) (xy 115.290221 -236.568048) (xy 115.263918 -236.526452)
			(xy 115.244627 -236.481176) (xy 115.23285 -236.433392) (xy 115.22889 -236.384338) (xy 114.899948 -236.384338)
			(xy 114.899453 -236.408945) (xy 114.891558 -236.457522) (xy 114.875974 -236.504203) (xy 114.853103 -236.54778)
			(xy 114.823538 -236.587124) (xy 114.788045 -236.621216) (xy 114.747542 -236.649172) (xy 114.70308 -236.67027)
			(xy 114.655809 -236.683962) (xy 114.606954 -236.689894) (xy 114.557779 -236.687913) (xy 114.50956 -236.678069)
			(xy 114.463544 -236.660617) (xy 114.420923 -236.63601) (xy 114.382802 -236.604885) (xy 114.350167 -236.568048)
			(xy 114.323864 -236.526452) (xy 114.304573 -236.481176) (xy 114.292796 -236.433392) (xy 114.288836 -236.384338)
			(xy 113.960148 -236.384338) (xy 113.959653 -236.408945) (xy 113.951758 -236.457522) (xy 113.936174 -236.504203)
			(xy 113.913303 -236.54778) (xy 113.883738 -236.587124) (xy 113.848245 -236.621216) (xy 113.807742 -236.649172)
			(xy 113.76328 -236.67027) (xy 113.716009 -236.683962) (xy 113.667154 -236.689894) (xy 113.617979 -236.687913)
			(xy 113.56976 -236.678069) (xy 113.523744 -236.660617) (xy 113.481123 -236.63601) (xy 113.443002 -236.604885)
			(xy 113.410367 -236.568048) (xy 113.384064 -236.526452) (xy 113.364773 -236.481176) (xy 113.352996 -236.433392)
			(xy 113.349036 -236.384338) (xy 110.206282 -236.384338) (xy 110.205787 -236.408945) (xy 110.197892 -236.457522)
			(xy 110.182308 -236.504203) (xy 110.159437 -236.54778) (xy 110.129872 -236.587124) (xy 110.094379 -236.621216)
			(xy 110.053876 -236.649172) (xy 110.009414 -236.67027) (xy 109.962143 -236.683962) (xy 109.913288 -236.689894)
			(xy 109.864113 -236.687913) (xy 109.815894 -236.678069) (xy 109.769878 -236.660617) (xy 109.727257 -236.63601)
			(xy 109.689136 -236.604885) (xy 109.656501 -236.568048) (xy 109.630198 -236.526452) (xy 109.610907 -236.481176)
			(xy 109.59913 -236.433392) (xy 109.59517 -236.384338) (xy 109.266482 -236.384338) (xy 109.265987 -236.408945)
			(xy 109.258092 -236.457522) (xy 109.242508 -236.504203) (xy 109.219637 -236.54778) (xy 109.190072 -236.587124)
			(xy 109.154579 -236.621216) (xy 109.114076 -236.649172) (xy 109.069614 -236.67027) (xy 109.022343 -236.683962)
			(xy 108.973488 -236.689894) (xy 108.924313 -236.687913) (xy 108.876094 -236.678069) (xy 108.830078 -236.660617)
			(xy 108.787457 -236.63601) (xy 108.749336 -236.604885) (xy 108.716701 -236.568048) (xy 108.690398 -236.526452)
			(xy 108.671107 -236.481176) (xy 108.65933 -236.433392) (xy 108.65537 -236.384338) (xy 108.326428 -236.384338)
			(xy 108.325933 -236.408945) (xy 108.318038 -236.457522) (xy 108.302454 -236.504203) (xy 108.279583 -236.54778)
			(xy 108.250018 -236.587124) (xy 108.214525 -236.621216) (xy 108.174022 -236.649172) (xy 108.12956 -236.67027)
			(xy 108.082289 -236.683962) (xy 108.033434 -236.689894) (xy 107.984259 -236.687913) (xy 107.93604 -236.678069)
			(xy 107.890024 -236.660617) (xy 107.847403 -236.63601) (xy 107.809282 -236.604885) (xy 107.776647 -236.568048)
			(xy 107.750344 -236.526452) (xy 107.731053 -236.481176) (xy 107.719276 -236.433392) (xy 107.715316 -236.384338)
			(xy 105.506266 -236.384338) (xy 105.505771 -236.408945) (xy 105.497876 -236.457522) (xy 105.482292 -236.504203)
			(xy 105.459421 -236.54778) (xy 105.429856 -236.587124) (xy 105.394363 -236.621216) (xy 105.35386 -236.649172)
			(xy 105.309398 -236.67027) (xy 105.262127 -236.683962) (xy 105.213272 -236.689894) (xy 105.164097 -236.687913)
			(xy 105.115878 -236.678069) (xy 105.069862 -236.660617) (xy 105.027241 -236.63601) (xy 104.98912 -236.604885)
			(xy 104.956485 -236.568048) (xy 104.930182 -236.526452) (xy 104.910891 -236.481176) (xy 104.899114 -236.433392)
			(xy 104.895154 -236.384338) (xy 102.686358 -236.384338) (xy 102.685863 -236.408945) (xy 102.677968 -236.457522)
			(xy 102.662384 -236.504203) (xy 102.639513 -236.54778) (xy 102.609948 -236.587124) (xy 102.574455 -236.621216)
			(xy 102.533952 -236.649172) (xy 102.48949 -236.67027) (xy 102.442219 -236.683962) (xy 102.393364 -236.689894)
			(xy 102.344189 -236.687913) (xy 102.29597 -236.678069) (xy 102.249954 -236.660617) (xy 102.207333 -236.63601)
			(xy 102.169212 -236.604885) (xy 102.136577 -236.568048) (xy 102.110274 -236.526452) (xy 102.090983 -236.481176)
			(xy 102.079206 -236.433392) (xy 102.075246 -236.384338) (xy 101.74715 -236.384338) (xy 101.742977 -236.434691)
			(xy 101.730564 -236.483708) (xy 101.710252 -236.530014) (xy 101.682596 -236.572344) (xy 101.64835 -236.609545)
			(xy 101.608447 -236.640602) (xy 101.563977 -236.664667) (xy 101.516153 -236.681085) (xy 101.466278 -236.689407)
			(xy 101.440996 -236.6899) (xy 100.500942 -236.6899) (xy 100.475664 -236.689334) (xy 100.425797 -236.681019)
			(xy 100.377979 -236.664609) (xy 100.333514 -236.640552) (xy 100.293616 -236.609503) (xy 100.259374 -236.57231)
			(xy 100.23172 -236.529988) (xy 100.21141 -236.483691) (xy 100.198999 -236.434683) (xy 100.194823 -236.3843)
			(xy 99.866449 -236.3843) (xy 99.86645 -236.384338) (xy 99.865955 -236.408945) (xy 99.85806 -236.457522)
			(xy 99.842476 -236.504203) (xy 99.819605 -236.54778) (xy 99.79004 -236.587124) (xy 99.754547 -236.621216)
			(xy 99.714044 -236.649172) (xy 99.669582 -236.67027) (xy 99.622311 -236.683962) (xy 99.573456 -236.689894)
			(xy 99.524281 -236.687913) (xy 99.476062 -236.678069) (xy 99.430046 -236.660617) (xy 99.387425 -236.63601)
			(xy 99.349304 -236.604885) (xy 99.316669 -236.568048) (xy 99.290366 -236.526452) (xy 99.271075 -236.481176)
			(xy 99.259298 -236.433392) (xy 99.255338 -236.384338) (xy 98.92725 -236.384338) (xy 98.923077 -236.434692)
			(xy 98.910663 -236.48371) (xy 98.890351 -236.530016) (xy 98.862694 -236.572347) (xy 98.828447 -236.609548)
			(xy 98.788543 -236.640605) (xy 98.744072 -236.66467) (xy 98.696246 -236.681087) (xy 98.646371 -236.689408)
			(xy 98.621088 -236.6899) (xy 97.681034 -236.6899) (xy 97.655757 -236.689334) (xy 97.60589 -236.681018)
			(xy 97.558073 -236.664607) (xy 97.51361 -236.640549) (xy 97.473713 -236.6095) (xy 97.439471 -236.572307)
			(xy 97.411819 -236.529986) (xy 97.39151 -236.48369) (xy 97.379099 -236.434682) (xy 97.374923 -236.3843)
			(xy 97.046822 -236.3843) (xy 97.042651 -236.434639) (xy 97.03025 -236.483604) (xy 97.009959 -236.529861)
			(xy 96.982331 -236.572146) (xy 96.94812 -236.609308) (xy 96.908258 -236.640331) (xy 96.863834 -236.66437)
			(xy 96.816059 -236.680768) (xy 96.766236 -236.689079) (xy 96.74098 -236.689646) (xy 96.717214 -236.689198)
			(xy 96.670255 -236.681838) (xy 96.625006 -236.667283) (xy 96.582563 -236.645886) (xy 96.543952 -236.618165)
			(xy 96.510108 -236.58479) (xy 96.495616 -236.565948) (xy 96.490536 -236.55909) (xy 96.48698 -236.554518)
			(xy 96.474788 -236.549438) (xy 96.468505 -236.546915) (xy 96.455111 -236.544974) (xy 96.448372 -236.545628)
			(xy 96.361758 -236.557058) (xy 96.355082 -236.558109) (xy 96.342589 -236.563249) (xy 96.33712 -236.567218)
			(xy 96.326452 -236.5756) (xy 96.323658 -236.58322) (xy 96.321626 -236.5883) (xy 96.308164 -236.619542)
			(xy 96.302017 -236.632668) (xy 96.288551 -236.658336) (xy 96.28124 -236.67085) (xy 96.280986 -236.671104)
			(xy 96.27743 -236.6772) (xy 96.275652 -236.683296) (xy 96.273874 -236.696758) (xy 96.273874 -236.842554)
			(xy 96.274246 -236.85166) (xy 96.28062 -236.868718) (xy 96.28632 -236.875828) (xy 96.291908 -236.882178)
			(xy 96.307402 -236.890814) (xy 96.317054 -236.892338) (xy 96.340802 -236.896433) (xy 96.3867 -236.911112)
			(xy 96.429726 -236.932814) (xy 96.468812 -236.960999) (xy 96.50299 -236.994969) (xy 96.531413 -237.033883)
			(xy 96.553376 -237.076776) (xy 96.568335 -237.122584) (xy 96.575919 -237.170172) (xy 96.57593 -237.194344)
			(xy 96.90533 -237.194344) (xy 96.90929 -237.14529) (xy 96.921067 -237.097506) (xy 96.940358 -237.05223)
			(xy 96.966661 -237.010634) (xy 96.999296 -236.973797) (xy 97.037417 -236.942672) (xy 97.080038 -236.918065)
			(xy 97.126054 -236.900613) (xy 97.174273 -236.890769) (xy 97.223448 -236.888788) (xy 97.272303 -236.89472)
			(xy 97.319574 -236.908412) (xy 97.364036 -236.92951) (xy 97.404539 -236.957466) (xy 97.440032 -236.991558)
			(xy 97.469597 -237.030902) (xy 97.492468 -237.074479) (xy 97.508052 -237.12116) (xy 97.515947 -237.169737)
			(xy 97.516442 -237.194344) (xy 97.84513 -237.194344) (xy 97.84909 -237.14529) (xy 97.860867 -237.097506)
			(xy 97.880158 -237.05223) (xy 97.906461 -237.010634) (xy 97.939096 -236.973797) (xy 97.977217 -236.942672)
			(xy 98.019838 -236.918065) (xy 98.065854 -236.900613) (xy 98.114073 -236.890769) (xy 98.163248 -236.888788)
			(xy 98.212103 -236.89472) (xy 98.259374 -236.908412) (xy 98.303836 -236.92951) (xy 98.344339 -236.957466)
			(xy 98.379832 -236.991558) (xy 98.409397 -237.030902) (xy 98.432268 -237.074479) (xy 98.447852 -237.12116)
			(xy 98.455747 -237.169737) (xy 98.456242 -237.194344) (xy 98.785184 -237.194344) (xy 98.789144 -237.14529)
			(xy 98.800921 -237.097506) (xy 98.820212 -237.05223) (xy 98.846515 -237.010634) (xy 98.87915 -236.973797)
			(xy 98.917271 -236.942672) (xy 98.959892 -236.918065) (xy 99.005908 -236.900613) (xy 99.054127 -236.890769)
			(xy 99.103302 -236.888788) (xy 99.152157 -236.89472) (xy 99.199428 -236.908412) (xy 99.24389 -236.92951)
			(xy 99.284393 -236.957466) (xy 99.319886 -236.991558) (xy 99.349451 -237.030902) (xy 99.372322 -237.074479)
			(xy 99.387906 -237.12116) (xy 99.395801 -237.169737) (xy 99.396296 -237.194344) (xy 99.725238 -237.194344)
			(xy 99.729198 -237.14529) (xy 99.740975 -237.097506) (xy 99.760266 -237.05223) (xy 99.786569 -237.010634)
			(xy 99.819204 -236.973797) (xy 99.857325 -236.942672) (xy 99.899946 -236.918065) (xy 99.945962 -236.900613)
			(xy 99.994181 -236.890769) (xy 100.043356 -236.888788) (xy 100.092211 -236.89472) (xy 100.139482 -236.908412)
			(xy 100.183944 -236.92951) (xy 100.224447 -236.957466) (xy 100.25994 -236.991558) (xy 100.289505 -237.030902)
			(xy 100.312376 -237.074479) (xy 100.32796 -237.12116) (xy 100.335855 -237.169737) (xy 100.33635 -237.194344)
			(xy 100.665292 -237.194344) (xy 100.669252 -237.14529) (xy 100.681029 -237.097506) (xy 100.70032 -237.05223)
			(xy 100.726623 -237.010634) (xy 100.759258 -236.973797) (xy 100.797379 -236.942672) (xy 100.84 -236.918065)
			(xy 100.886016 -236.900613) (xy 100.934235 -236.890769) (xy 100.98341 -236.888788) (xy 101.032265 -236.89472)
			(xy 101.079536 -236.908412) (xy 101.123998 -236.92951) (xy 101.164501 -236.957466) (xy 101.199994 -236.991558)
			(xy 101.229559 -237.030902) (xy 101.25243 -237.074479) (xy 101.268014 -237.12116) (xy 101.275909 -237.169737)
			(xy 101.276404 -237.194344) (xy 101.605346 -237.194344) (xy 101.609306 -237.14529) (xy 101.621083 -237.097506)
			(xy 101.640374 -237.05223) (xy 101.666677 -237.010634) (xy 101.699312 -236.973797) (xy 101.737433 -236.942672)
			(xy 101.780054 -236.918065) (xy 101.82607 -236.900613) (xy 101.874289 -236.890769) (xy 101.923464 -236.888788)
			(xy 101.972319 -236.89472) (xy 102.01959 -236.908412) (xy 102.064052 -236.92951) (xy 102.104555 -236.957466)
			(xy 102.140048 -236.991558) (xy 102.169613 -237.030902) (xy 102.192484 -237.074479) (xy 102.208068 -237.12116)
			(xy 102.215963 -237.169737) (xy 102.216458 -237.194344) (xy 102.545146 -237.194344) (xy 102.549106 -237.14529)
			(xy 102.560883 -237.097506) (xy 102.580174 -237.05223) (xy 102.606477 -237.010634) (xy 102.639112 -236.973797)
			(xy 102.677233 -236.942672) (xy 102.719854 -236.918065) (xy 102.76587 -236.900613) (xy 102.814089 -236.890769)
			(xy 102.863264 -236.888788) (xy 102.912119 -236.89472) (xy 102.95939 -236.908412) (xy 103.003852 -236.92951)
			(xy 103.044355 -236.957466) (xy 103.079848 -236.991558) (xy 103.109413 -237.030902) (xy 103.132284 -237.074479)
			(xy 103.147868 -237.12116) (xy 103.155763 -237.169737) (xy 103.156258 -237.194344) (xy 103.4852 -237.194344)
			(xy 103.48916 -237.14529) (xy 103.500937 -237.097506) (xy 103.520228 -237.05223) (xy 103.546531 -237.010634)
			(xy 103.579166 -236.973797) (xy 103.617287 -236.942672) (xy 103.659908 -236.918065) (xy 103.705924 -236.900613)
			(xy 103.754143 -236.890769) (xy 103.803318 -236.888788) (xy 103.852173 -236.89472) (xy 103.899444 -236.908412)
			(xy 103.943906 -236.92951) (xy 103.984409 -236.957466) (xy 104.019902 -236.991558) (xy 104.049467 -237.030902)
			(xy 104.072338 -237.074479) (xy 104.087922 -237.12116) (xy 104.095817 -237.169737) (xy 104.096312 -237.194344)
			(xy 104.425254 -237.194344) (xy 104.429214 -237.14529) (xy 104.440991 -237.097506) (xy 104.460282 -237.05223)
			(xy 104.486585 -237.010634) (xy 104.51922 -236.973797) (xy 104.557341 -236.942672) (xy 104.599962 -236.918065)
			(xy 104.645978 -236.900613) (xy 104.694197 -236.890769) (xy 104.743372 -236.888788) (xy 104.792227 -236.89472)
			(xy 104.839498 -236.908412) (xy 104.88396 -236.92951) (xy 104.924463 -236.957466) (xy 104.959956 -236.991558)
			(xy 104.989521 -237.030902) (xy 105.012392 -237.074479) (xy 105.027976 -237.12116) (xy 105.035871 -237.169737)
			(xy 105.036366 -237.194344) (xy 105.365308 -237.194344) (xy 105.369268 -237.14529) (xy 105.381045 -237.097506)
			(xy 105.400336 -237.05223) (xy 105.426639 -237.010634) (xy 105.459274 -236.973797) (xy 105.497395 -236.942672)
			(xy 105.540016 -236.918065) (xy 105.586032 -236.900613) (xy 105.634251 -236.890769) (xy 105.683426 -236.888788)
			(xy 105.732281 -236.89472) (xy 105.779552 -236.908412) (xy 105.824014 -236.92951) (xy 105.864517 -236.957466)
			(xy 105.90001 -236.991558) (xy 105.929575 -237.030902) (xy 105.952446 -237.074479) (xy 105.96803 -237.12116)
			(xy 105.975925 -237.169737) (xy 105.97642 -237.194344) (xy 106.305362 -237.194344) (xy 106.309322 -237.14529)
			(xy 106.321099 -237.097506) (xy 106.34039 -237.05223) (xy 106.366693 -237.010634) (xy 106.399328 -236.973797)
			(xy 106.437449 -236.942672) (xy 106.48007 -236.918065) (xy 106.526086 -236.900613) (xy 106.574305 -236.890769)
			(xy 106.62348 -236.888788) (xy 106.672335 -236.89472) (xy 106.719606 -236.908412) (xy 106.764068 -236.92951)
			(xy 106.804571 -236.957466) (xy 106.840064 -236.991558) (xy 106.869629 -237.030902) (xy 106.8925 -237.074479)
			(xy 106.908084 -237.12116) (xy 106.915979 -237.169737) (xy 106.916474 -237.194344) (xy 107.245162 -237.194344)
			(xy 107.249122 -237.14529) (xy 107.260899 -237.097506) (xy 107.28019 -237.05223) (xy 107.306493 -237.010634)
			(xy 107.339128 -236.973797) (xy 107.377249 -236.942672) (xy 107.41987 -236.918065) (xy 107.465886 -236.900613)
			(xy 107.514105 -236.890769) (xy 107.56328 -236.888788) (xy 107.612135 -236.89472) (xy 107.659406 -236.908412)
			(xy 107.703868 -236.92951) (xy 107.744371 -236.957466) (xy 107.779864 -236.991558) (xy 107.809429 -237.030902)
			(xy 107.8323 -237.074479) (xy 107.847884 -237.12116) (xy 107.855779 -237.169737) (xy 107.856274 -237.194344)
			(xy 110.065324 -237.194344) (xy 110.069284 -237.14529) (xy 110.081061 -237.097506) (xy 110.100352 -237.05223)
			(xy 110.126655 -237.010634) (xy 110.15929 -236.973797) (xy 110.197411 -236.942672) (xy 110.240032 -236.918065)
			(xy 110.286048 -236.900613) (xy 110.334267 -236.890769) (xy 110.383442 -236.888788) (xy 110.432297 -236.89472)
			(xy 110.479568 -236.908412) (xy 110.52403 -236.92951) (xy 110.564533 -236.957466) (xy 110.600026 -236.991558)
			(xy 110.629591 -237.030902) (xy 110.652462 -237.074479) (xy 110.668046 -237.12116) (xy 110.675941 -237.169737)
			(xy 110.676436 -237.194344) (xy 112.878882 -237.194344) (xy 112.882842 -237.14529) (xy 112.894619 -237.097506)
			(xy 112.91391 -237.05223) (xy 112.940213 -237.010634) (xy 112.972848 -236.973797) (xy 113.010969 -236.942672)
			(xy 113.05359 -236.918065) (xy 113.099606 -236.900613) (xy 113.147825 -236.890769) (xy 113.197 -236.888788)
			(xy 113.245855 -236.89472) (xy 113.293126 -236.908412) (xy 113.337588 -236.92951) (xy 113.378091 -236.957466)
			(xy 113.413584 -236.991558) (xy 113.443149 -237.030902) (xy 113.46602 -237.074479) (xy 113.481604 -237.12116)
			(xy 113.489499 -237.169737) (xy 113.489994 -237.194344) (xy 115.699044 -237.194344) (xy 115.703004 -237.14529)
			(xy 115.714781 -237.097506) (xy 115.734072 -237.05223) (xy 115.760375 -237.010634) (xy 115.79301 -236.973797)
			(xy 115.831131 -236.942672) (xy 115.873752 -236.918065) (xy 115.919768 -236.900613) (xy 115.967987 -236.890769)
			(xy 116.017162 -236.888788) (xy 116.066017 -236.89472) (xy 116.113288 -236.908412) (xy 116.15775 -236.92951)
			(xy 116.198253 -236.957466) (xy 116.233746 -236.991558) (xy 116.263311 -237.030902) (xy 116.286182 -237.074479)
			(xy 116.301766 -237.12116) (xy 116.309661 -237.169737) (xy 116.310156 -237.194344) (xy 116.638844 -237.194344)
			(xy 116.642804 -237.14529) (xy 116.654581 -237.097506) (xy 116.673872 -237.05223) (xy 116.700175 -237.010634)
			(xy 116.73281 -236.973797) (xy 116.770931 -236.942672) (xy 116.813552 -236.918065) (xy 116.859568 -236.900613)
			(xy 116.907787 -236.890769) (xy 116.956962 -236.888788) (xy 117.005817 -236.89472) (xy 117.053088 -236.908412)
			(xy 117.09755 -236.92951) (xy 117.138053 -236.957466) (xy 117.173546 -236.991558) (xy 117.203111 -237.030902)
			(xy 117.225982 -237.074479) (xy 117.241566 -237.12116) (xy 117.249461 -237.169737) (xy 117.249956 -237.194344)
			(xy 117.578898 -237.194344) (xy 117.582858 -237.14529) (xy 117.594635 -237.097506) (xy 117.613926 -237.05223)
			(xy 117.640229 -237.010634) (xy 117.672864 -236.973797) (xy 117.710985 -236.942672) (xy 117.753606 -236.918065)
			(xy 117.799622 -236.900613) (xy 117.847841 -236.890769) (xy 117.897016 -236.888788) (xy 117.945871 -236.89472)
			(xy 117.993142 -236.908412) (xy 118.037604 -236.92951) (xy 118.078107 -236.957466) (xy 118.1136 -236.991558)
			(xy 118.143165 -237.030902) (xy 118.166036 -237.074479) (xy 118.18162 -237.12116) (xy 118.189515 -237.169737)
			(xy 118.19001 -237.194344) (xy 118.518952 -237.194344) (xy 118.522912 -237.14529) (xy 118.534689 -237.097506)
			(xy 118.55398 -237.05223) (xy 118.580283 -237.010634) (xy 118.612918 -236.973797) (xy 118.651039 -236.942672)
			(xy 118.69366 -236.918065) (xy 118.739676 -236.900613) (xy 118.787895 -236.890769) (xy 118.83707 -236.888788)
			(xy 118.885925 -236.89472) (xy 118.933196 -236.908412) (xy 118.977658 -236.92951) (xy 119.018161 -236.957466)
			(xy 119.053654 -236.991558) (xy 119.083219 -237.030902) (xy 119.10609 -237.074479) (xy 119.121674 -237.12116)
			(xy 119.129569 -237.169737) (xy 119.130064 -237.194344) (xy 119.459006 -237.194344) (xy 119.462966 -237.14529)
			(xy 119.474743 -237.097506) (xy 119.494034 -237.05223) (xy 119.520337 -237.010634) (xy 119.552972 -236.973797)
			(xy 119.591093 -236.942672) (xy 119.633714 -236.918065) (xy 119.67973 -236.900613) (xy 119.727949 -236.890769)
			(xy 119.777124 -236.888788) (xy 119.825979 -236.89472) (xy 119.87325 -236.908412) (xy 119.917712 -236.92951)
			(xy 119.958215 -236.957466) (xy 119.993708 -236.991558) (xy 120.023273 -237.030902) (xy 120.046144 -237.074479)
			(xy 120.061728 -237.12116) (xy 120.069623 -237.169737) (xy 120.070118 -237.194344) (xy 120.398806 -237.194344)
			(xy 120.402766 -237.14529) (xy 120.414543 -237.097506) (xy 120.433834 -237.05223) (xy 120.460137 -237.010634)
			(xy 120.492772 -236.973797) (xy 120.530893 -236.942672) (xy 120.573514 -236.918065) (xy 120.61953 -236.900613)
			(xy 120.667749 -236.890769) (xy 120.716924 -236.888788) (xy 120.765779 -236.89472) (xy 120.81305 -236.908412)
			(xy 120.857512 -236.92951) (xy 120.898015 -236.957466) (xy 120.933508 -236.991558) (xy 120.963073 -237.030902)
			(xy 120.985944 -237.074479) (xy 121.001528 -237.12116) (xy 121.009423 -237.169737) (xy 121.009918 -237.194344)
			(xy 121.33886 -237.194344) (xy 121.34282 -237.14529) (xy 121.354597 -237.097506) (xy 121.373888 -237.05223)
			(xy 121.400191 -237.010634) (xy 121.432826 -236.973797) (xy 121.470947 -236.942672) (xy 121.513568 -236.918065)
			(xy 121.559584 -236.900613) (xy 121.607803 -236.890769) (xy 121.656978 -236.888788) (xy 121.705833 -236.89472)
			(xy 121.753104 -236.908412) (xy 121.797566 -236.92951) (xy 121.838069 -236.957466) (xy 121.873562 -236.991558)
			(xy 121.903127 -237.030902) (xy 121.925998 -237.074479) (xy 121.941582 -237.12116) (xy 121.949477 -237.169737)
			(xy 121.949972 -237.194344) (xy 122.278914 -237.194344) (xy 122.282874 -237.14529) (xy 122.294651 -237.097506)
			(xy 122.313942 -237.05223) (xy 122.340245 -237.010634) (xy 122.37288 -236.973797) (xy 122.411001 -236.942672)
			(xy 122.453622 -236.918065) (xy 122.499638 -236.900613) (xy 122.547857 -236.890769) (xy 122.597032 -236.888788)
			(xy 122.645887 -236.89472) (xy 122.693158 -236.908412) (xy 122.73762 -236.92951) (xy 122.778123 -236.957466)
			(xy 122.813616 -236.991558) (xy 122.843181 -237.030902) (xy 122.866052 -237.074479) (xy 122.881636 -237.12116)
			(xy 122.889531 -237.169737) (xy 122.890026 -237.194344) (xy 123.218968 -237.194344) (xy 123.222928 -237.14529)
			(xy 123.234705 -237.097506) (xy 123.253996 -237.05223) (xy 123.280299 -237.010634) (xy 123.312934 -236.973797)
			(xy 123.351055 -236.942672) (xy 123.393676 -236.918065) (xy 123.439692 -236.900613) (xy 123.487911 -236.890769)
			(xy 123.537086 -236.888788) (xy 123.585941 -236.89472) (xy 123.633212 -236.908412) (xy 123.677674 -236.92951)
			(xy 123.718177 -236.957466) (xy 123.75367 -236.991558) (xy 123.783235 -237.030902) (xy 123.806106 -237.074479)
			(xy 123.82169 -237.12116) (xy 123.829585 -237.169737) (xy 123.83008 -237.194344) (xy 124.159022 -237.194344)
			(xy 124.162982 -237.14529) (xy 124.174759 -237.097506) (xy 124.19405 -237.05223) (xy 124.220353 -237.010634)
			(xy 124.252988 -236.973797) (xy 124.291109 -236.942672) (xy 124.33373 -236.918065) (xy 124.379746 -236.900613)
			(xy 124.427965 -236.890769) (xy 124.47714 -236.888788) (xy 124.525995 -236.89472) (xy 124.573266 -236.908412)
			(xy 124.617728 -236.92951) (xy 124.658231 -236.957466) (xy 124.693724 -236.991558) (xy 124.723289 -237.030902)
			(xy 124.74616 -237.074479) (xy 124.761744 -237.12116) (xy 124.769639 -237.169737) (xy 124.770134 -237.194344)
			(xy 125.098822 -237.194344) (xy 125.102782 -237.14529) (xy 125.114559 -237.097506) (xy 125.13385 -237.05223)
			(xy 125.160153 -237.010634) (xy 125.192788 -236.973797) (xy 125.230909 -236.942672) (xy 125.27353 -236.918065)
			(xy 125.319546 -236.900613) (xy 125.367765 -236.890769) (xy 125.41694 -236.888788) (xy 125.465795 -236.89472)
			(xy 125.513066 -236.908412) (xy 125.557528 -236.92951) (xy 125.598031 -236.957466) (xy 125.633524 -236.991558)
			(xy 125.663089 -237.030902) (xy 125.68596 -237.074479) (xy 125.701544 -237.12116) (xy 125.709439 -237.169737)
			(xy 125.709934 -237.194344) (xy 126.038876 -237.194344) (xy 126.042836 -237.14529) (xy 126.054613 -237.097506)
			(xy 126.073904 -237.05223) (xy 126.100207 -237.010634) (xy 126.132842 -236.973797) (xy 126.170963 -236.942672)
			(xy 126.213584 -236.918065) (xy 126.2596 -236.900613) (xy 126.307819 -236.890769) (xy 126.356994 -236.888788)
			(xy 126.405849 -236.89472) (xy 126.45312 -236.908412) (xy 126.497582 -236.92951) (xy 126.538085 -236.957466)
			(xy 126.573578 -236.991558) (xy 126.603143 -237.030902) (xy 126.626014 -237.074479) (xy 126.641598 -237.12116)
			(xy 126.649493 -237.169737) (xy 126.649988 -237.194344) (xy 126.649493 -237.218951) (xy 126.641598 -237.267528)
			(xy 126.626014 -237.314209) (xy 126.603143 -237.357786) (xy 126.573578 -237.39713) (xy 126.538085 -237.431222)
			(xy 126.497582 -237.459178) (xy 126.45312 -237.480276) (xy 126.405849 -237.493968) (xy 126.356994 -237.4999)
			(xy 126.307819 -237.497919) (xy 126.2596 -237.488075) (xy 126.213584 -237.470623) (xy 126.170963 -237.446016)
			(xy 126.132842 -237.414891) (xy 126.100207 -237.378054) (xy 126.073904 -237.336458) (xy 126.054613 -237.291182)
			(xy 126.042836 -237.243398) (xy 126.038876 -237.194344) (xy 125.709934 -237.194344) (xy 125.709439 -237.218951)
			(xy 125.701544 -237.267528) (xy 125.68596 -237.314209) (xy 125.663089 -237.357786) (xy 125.633524 -237.39713)
			(xy 125.598031 -237.431222) (xy 125.557528 -237.459178) (xy 125.513066 -237.480276) (xy 125.465795 -237.493968)
			(xy 125.41694 -237.4999) (xy 125.367765 -237.497919) (xy 125.319546 -237.488075) (xy 125.27353 -237.470623)
			(xy 125.230909 -237.446016) (xy 125.192788 -237.414891) (xy 125.160153 -237.378054) (xy 125.13385 -237.336458)
			(xy 125.114559 -237.291182) (xy 125.102782 -237.243398) (xy 125.098822 -237.194344) (xy 124.770134 -237.194344)
			(xy 124.769639 -237.218951) (xy 124.761744 -237.267528) (xy 124.74616 -237.314209) (xy 124.723289 -237.357786)
			(xy 124.693724 -237.39713) (xy 124.658231 -237.431222) (xy 124.617728 -237.459178) (xy 124.573266 -237.480276)
			(xy 124.525995 -237.493968) (xy 124.47714 -237.4999) (xy 124.427965 -237.497919) (xy 124.379746 -237.488075)
			(xy 124.33373 -237.470623) (xy 124.291109 -237.446016) (xy 124.252988 -237.414891) (xy 124.220353 -237.378054)
			(xy 124.19405 -237.336458) (xy 124.174759 -237.291182) (xy 124.162982 -237.243398) (xy 124.159022 -237.194344)
			(xy 123.83008 -237.194344) (xy 123.829585 -237.218951) (xy 123.82169 -237.267528) (xy 123.806106 -237.314209)
			(xy 123.783235 -237.357786) (xy 123.75367 -237.39713) (xy 123.718177 -237.431222) (xy 123.677674 -237.459178)
			(xy 123.633212 -237.480276) (xy 123.585941 -237.493968) (xy 123.537086 -237.4999) (xy 123.487911 -237.497919)
			(xy 123.439692 -237.488075) (xy 123.393676 -237.470623) (xy 123.351055 -237.446016) (xy 123.312934 -237.414891)
			(xy 123.280299 -237.378054) (xy 123.253996 -237.336458) (xy 123.234705 -237.291182) (xy 123.222928 -237.243398)
			(xy 123.218968 -237.194344) (xy 122.890026 -237.194344) (xy 122.889531 -237.218951) (xy 122.881636 -237.267528)
			(xy 122.866052 -237.314209) (xy 122.843181 -237.357786) (xy 122.813616 -237.39713) (xy 122.778123 -237.431222)
			(xy 122.73762 -237.459178) (xy 122.693158 -237.480276) (xy 122.645887 -237.493968) (xy 122.597032 -237.4999)
			(xy 122.547857 -237.497919) (xy 122.499638 -237.488075) (xy 122.453622 -237.470623) (xy 122.411001 -237.446016)
			(xy 122.37288 -237.414891) (xy 122.340245 -237.378054) (xy 122.313942 -237.336458) (xy 122.294651 -237.291182)
			(xy 122.282874 -237.243398) (xy 122.278914 -237.194344) (xy 121.949972 -237.194344) (xy 121.949477 -237.218951)
			(xy 121.941582 -237.267528) (xy 121.925998 -237.314209) (xy 121.903127 -237.357786) (xy 121.873562 -237.39713)
			(xy 121.838069 -237.431222) (xy 121.797566 -237.459178) (xy 121.753104 -237.480276) (xy 121.705833 -237.493968)
			(xy 121.656978 -237.4999) (xy 121.607803 -237.497919) (xy 121.559584 -237.488075) (xy 121.513568 -237.470623)
			(xy 121.470947 -237.446016) (xy 121.432826 -237.414891) (xy 121.400191 -237.378054) (xy 121.373888 -237.336458)
			(xy 121.354597 -237.291182) (xy 121.34282 -237.243398) (xy 121.33886 -237.194344) (xy 121.009918 -237.194344)
			(xy 121.009423 -237.218951) (xy 121.001528 -237.267528) (xy 120.985944 -237.314209) (xy 120.963073 -237.357786)
			(xy 120.933508 -237.39713) (xy 120.898015 -237.431222) (xy 120.857512 -237.459178) (xy 120.81305 -237.480276)
			(xy 120.765779 -237.493968) (xy 120.716924 -237.4999) (xy 120.667749 -237.497919) (xy 120.61953 -237.488075)
			(xy 120.573514 -237.470623) (xy 120.530893 -237.446016) (xy 120.492772 -237.414891) (xy 120.460137 -237.378054)
			(xy 120.433834 -237.336458) (xy 120.414543 -237.291182) (xy 120.402766 -237.243398) (xy 120.398806 -237.194344)
			(xy 120.070118 -237.194344) (xy 120.069623 -237.218951) (xy 120.061728 -237.267528) (xy 120.046144 -237.314209)
			(xy 120.023273 -237.357786) (xy 119.993708 -237.39713) (xy 119.958215 -237.431222) (xy 119.917712 -237.459178)
			(xy 119.87325 -237.480276) (xy 119.825979 -237.493968) (xy 119.777124 -237.4999) (xy 119.727949 -237.497919)
			(xy 119.67973 -237.488075) (xy 119.633714 -237.470623) (xy 119.591093 -237.446016) (xy 119.552972 -237.414891)
			(xy 119.520337 -237.378054) (xy 119.494034 -237.336458) (xy 119.474743 -237.291182) (xy 119.462966 -237.243398)
			(xy 119.459006 -237.194344) (xy 119.130064 -237.194344) (xy 119.129569 -237.218951) (xy 119.121674 -237.267528)
			(xy 119.10609 -237.314209) (xy 119.083219 -237.357786) (xy 119.053654 -237.39713) (xy 119.018161 -237.431222)
			(xy 118.977658 -237.459178) (xy 118.933196 -237.480276) (xy 118.885925 -237.493968) (xy 118.83707 -237.4999)
			(xy 118.787895 -237.497919) (xy 118.739676 -237.488075) (xy 118.69366 -237.470623) (xy 118.651039 -237.446016)
			(xy 118.612918 -237.414891) (xy 118.580283 -237.378054) (xy 118.55398 -237.336458) (xy 118.534689 -237.291182)
			(xy 118.522912 -237.243398) (xy 118.518952 -237.194344) (xy 118.19001 -237.194344) (xy 118.189515 -237.218951)
			(xy 118.18162 -237.267528) (xy 118.166036 -237.314209) (xy 118.143165 -237.357786) (xy 118.1136 -237.39713)
			(xy 118.078107 -237.431222) (xy 118.037604 -237.459178) (xy 117.993142 -237.480276) (xy 117.945871 -237.493968)
			(xy 117.897016 -237.4999) (xy 117.847841 -237.497919) (xy 117.799622 -237.488075) (xy 117.753606 -237.470623)
			(xy 117.710985 -237.446016) (xy 117.672864 -237.414891) (xy 117.640229 -237.378054) (xy 117.613926 -237.336458)
			(xy 117.594635 -237.291182) (xy 117.582858 -237.243398) (xy 117.578898 -237.194344) (xy 117.249956 -237.194344)
			(xy 117.249461 -237.218951) (xy 117.241566 -237.267528) (xy 117.225982 -237.314209) (xy 117.203111 -237.357786)
			(xy 117.173546 -237.39713) (xy 117.138053 -237.431222) (xy 117.09755 -237.459178) (xy 117.053088 -237.480276)
			(xy 117.005817 -237.493968) (xy 116.956962 -237.4999) (xy 116.907787 -237.497919) (xy 116.859568 -237.488075)
			(xy 116.813552 -237.470623) (xy 116.770931 -237.446016) (xy 116.73281 -237.414891) (xy 116.700175 -237.378054)
			(xy 116.673872 -237.336458) (xy 116.654581 -237.291182) (xy 116.642804 -237.243398) (xy 116.638844 -237.194344)
			(xy 116.310156 -237.194344) (xy 116.309661 -237.218951) (xy 116.301766 -237.267528) (xy 116.286182 -237.314209)
			(xy 116.263311 -237.357786) (xy 116.233746 -237.39713) (xy 116.198253 -237.431222) (xy 116.15775 -237.459178)
			(xy 116.113288 -237.480276) (xy 116.066017 -237.493968) (xy 116.017162 -237.4999) (xy 115.967987 -237.497919)
			(xy 115.919768 -237.488075) (xy 115.873752 -237.470623) (xy 115.831131 -237.446016) (xy 115.79301 -237.414891)
			(xy 115.760375 -237.378054) (xy 115.734072 -237.336458) (xy 115.714781 -237.291182) (xy 115.703004 -237.243398)
			(xy 115.699044 -237.194344) (xy 113.489994 -237.194344) (xy 113.489499 -237.218951) (xy 113.481604 -237.267528)
			(xy 113.46602 -237.314209) (xy 113.443149 -237.357786) (xy 113.413584 -237.39713) (xy 113.378091 -237.431222)
			(xy 113.337588 -237.459178) (xy 113.293126 -237.480276) (xy 113.245855 -237.493968) (xy 113.197 -237.4999)
			(xy 113.147825 -237.497919) (xy 113.099606 -237.488075) (xy 113.05359 -237.470623) (xy 113.010969 -237.446016)
			(xy 112.972848 -237.414891) (xy 112.940213 -237.378054) (xy 112.91391 -237.336458) (xy 112.894619 -237.291182)
			(xy 112.882842 -237.243398) (xy 112.878882 -237.194344) (xy 110.676436 -237.194344) (xy 110.675941 -237.218951)
			(xy 110.668046 -237.267528) (xy 110.652462 -237.314209) (xy 110.629591 -237.357786) (xy 110.600026 -237.39713)
			(xy 110.564533 -237.431222) (xy 110.52403 -237.459178) (xy 110.479568 -237.480276) (xy 110.432297 -237.493968)
			(xy 110.383442 -237.4999) (xy 110.334267 -237.497919) (xy 110.286048 -237.488075) (xy 110.240032 -237.470623)
			(xy 110.197411 -237.446016) (xy 110.15929 -237.414891) (xy 110.126655 -237.378054) (xy 110.100352 -237.336458)
			(xy 110.081061 -237.291182) (xy 110.069284 -237.243398) (xy 110.065324 -237.194344) (xy 107.856274 -237.194344)
			(xy 107.855779 -237.218951) (xy 107.847884 -237.267528) (xy 107.8323 -237.314209) (xy 107.809429 -237.357786)
			(xy 107.779864 -237.39713) (xy 107.744371 -237.431222) (xy 107.703868 -237.459178) (xy 107.659406 -237.480276)
			(xy 107.612135 -237.493968) (xy 107.56328 -237.4999) (xy 107.514105 -237.497919) (xy 107.465886 -237.488075)
			(xy 107.41987 -237.470623) (xy 107.377249 -237.446016) (xy 107.339128 -237.414891) (xy 107.306493 -237.378054)
			(xy 107.28019 -237.336458) (xy 107.260899 -237.291182) (xy 107.249122 -237.243398) (xy 107.245162 -237.194344)
			(xy 106.916474 -237.194344) (xy 106.915979 -237.218951) (xy 106.908084 -237.267528) (xy 106.8925 -237.314209)
			(xy 106.869629 -237.357786) (xy 106.840064 -237.39713) (xy 106.804571 -237.431222) (xy 106.764068 -237.459178)
			(xy 106.719606 -237.480276) (xy 106.672335 -237.493968) (xy 106.62348 -237.4999) (xy 106.574305 -237.497919)
			(xy 106.526086 -237.488075) (xy 106.48007 -237.470623) (xy 106.437449 -237.446016) (xy 106.399328 -237.414891)
			(xy 106.366693 -237.378054) (xy 106.34039 -237.336458) (xy 106.321099 -237.291182) (xy 106.309322 -237.243398)
			(xy 106.305362 -237.194344) (xy 105.97642 -237.194344) (xy 105.975925 -237.218951) (xy 105.96803 -237.267528)
			(xy 105.952446 -237.314209) (xy 105.929575 -237.357786) (xy 105.90001 -237.39713) (xy 105.864517 -237.431222)
			(xy 105.824014 -237.459178) (xy 105.779552 -237.480276) (xy 105.732281 -237.493968) (xy 105.683426 -237.4999)
			(xy 105.634251 -237.497919) (xy 105.586032 -237.488075) (xy 105.540016 -237.470623) (xy 105.497395 -237.446016)
			(xy 105.459274 -237.414891) (xy 105.426639 -237.378054) (xy 105.400336 -237.336458) (xy 105.381045 -237.291182)
			(xy 105.369268 -237.243398) (xy 105.365308 -237.194344) (xy 105.036366 -237.194344) (xy 105.035871 -237.218951)
			(xy 105.027976 -237.267528) (xy 105.012392 -237.314209) (xy 104.989521 -237.357786) (xy 104.959956 -237.39713)
			(xy 104.924463 -237.431222) (xy 104.88396 -237.459178) (xy 104.839498 -237.480276) (xy 104.792227 -237.493968)
			(xy 104.743372 -237.4999) (xy 104.694197 -237.497919) (xy 104.645978 -237.488075) (xy 104.599962 -237.470623)
			(xy 104.557341 -237.446016) (xy 104.51922 -237.414891) (xy 104.486585 -237.378054) (xy 104.460282 -237.336458)
			(xy 104.440991 -237.291182) (xy 104.429214 -237.243398) (xy 104.425254 -237.194344) (xy 104.096312 -237.194344)
			(xy 104.095817 -237.218951) (xy 104.087922 -237.267528) (xy 104.072338 -237.314209) (xy 104.049467 -237.357786)
			(xy 104.019902 -237.39713) (xy 103.984409 -237.431222) (xy 103.943906 -237.459178) (xy 103.899444 -237.480276)
			(xy 103.852173 -237.493968) (xy 103.803318 -237.4999) (xy 103.754143 -237.497919) (xy 103.705924 -237.488075)
			(xy 103.659908 -237.470623) (xy 103.617287 -237.446016) (xy 103.579166 -237.414891) (xy 103.546531 -237.378054)
			(xy 103.520228 -237.336458) (xy 103.500937 -237.291182) (xy 103.48916 -237.243398) (xy 103.4852 -237.194344)
			(xy 103.156258 -237.194344) (xy 103.155763 -237.218951) (xy 103.147868 -237.267528) (xy 103.132284 -237.314209)
			(xy 103.109413 -237.357786) (xy 103.079848 -237.39713) (xy 103.044355 -237.431222) (xy 103.003852 -237.459178)
			(xy 102.95939 -237.480276) (xy 102.912119 -237.493968) (xy 102.863264 -237.4999) (xy 102.814089 -237.497919)
			(xy 102.76587 -237.488075) (xy 102.719854 -237.470623) (xy 102.677233 -237.446016) (xy 102.639112 -237.414891)
			(xy 102.606477 -237.378054) (xy 102.580174 -237.336458) (xy 102.560883 -237.291182) (xy 102.549106 -237.243398)
			(xy 102.545146 -237.194344) (xy 102.216458 -237.194344) (xy 102.215963 -237.218951) (xy 102.208068 -237.267528)
			(xy 102.192484 -237.314209) (xy 102.169613 -237.357786) (xy 102.140048 -237.39713) (xy 102.104555 -237.431222)
			(xy 102.064052 -237.459178) (xy 102.01959 -237.480276) (xy 101.972319 -237.493968) (xy 101.923464 -237.4999)
			(xy 101.874289 -237.497919) (xy 101.82607 -237.488075) (xy 101.780054 -237.470623) (xy 101.737433 -237.446016)
			(xy 101.699312 -237.414891) (xy 101.666677 -237.378054) (xy 101.640374 -237.336458) (xy 101.621083 -237.291182)
			(xy 101.609306 -237.243398) (xy 101.605346 -237.194344) (xy 101.276404 -237.194344) (xy 101.275909 -237.218951)
			(xy 101.268014 -237.267528) (xy 101.25243 -237.314209) (xy 101.229559 -237.357786) (xy 101.199994 -237.39713)
			(xy 101.164501 -237.431222) (xy 101.123998 -237.459178) (xy 101.079536 -237.480276) (xy 101.032265 -237.493968)
			(xy 100.98341 -237.4999) (xy 100.934235 -237.497919) (xy 100.886016 -237.488075) (xy 100.84 -237.470623)
			(xy 100.797379 -237.446016) (xy 100.759258 -237.414891) (xy 100.726623 -237.378054) (xy 100.70032 -237.336458)
			(xy 100.681029 -237.291182) (xy 100.669252 -237.243398) (xy 100.665292 -237.194344) (xy 100.33635 -237.194344)
			(xy 100.335855 -237.218951) (xy 100.32796 -237.267528) (xy 100.312376 -237.314209) (xy 100.289505 -237.357786)
			(xy 100.25994 -237.39713) (xy 100.224447 -237.431222) (xy 100.183944 -237.459178) (xy 100.139482 -237.480276)
			(xy 100.092211 -237.493968) (xy 100.043356 -237.4999) (xy 99.994181 -237.497919) (xy 99.945962 -237.488075)
			(xy 99.899946 -237.470623) (xy 99.857325 -237.446016) (xy 99.819204 -237.414891) (xy 99.786569 -237.378054)
			(xy 99.760266 -237.336458) (xy 99.740975 -237.291182) (xy 99.729198 -237.243398) (xy 99.725238 -237.194344)
			(xy 99.396296 -237.194344) (xy 99.395801 -237.218951) (xy 99.387906 -237.267528) (xy 99.372322 -237.314209)
			(xy 99.349451 -237.357786) (xy 99.319886 -237.39713) (xy 99.284393 -237.431222) (xy 99.24389 -237.459178)
			(xy 99.199428 -237.480276) (xy 99.152157 -237.493968) (xy 99.103302 -237.4999) (xy 99.054127 -237.497919)
			(xy 99.005908 -237.488075) (xy 98.959892 -237.470623) (xy 98.917271 -237.446016) (xy 98.87915 -237.414891)
			(xy 98.846515 -237.378054) (xy 98.820212 -237.336458) (xy 98.800921 -237.291182) (xy 98.789144 -237.243398)
			(xy 98.785184 -237.194344) (xy 98.456242 -237.194344) (xy 98.455747 -237.218951) (xy 98.447852 -237.267528)
			(xy 98.432268 -237.314209) (xy 98.409397 -237.357786) (xy 98.379832 -237.39713) (xy 98.344339 -237.431222)
			(xy 98.303836 -237.459178) (xy 98.259374 -237.480276) (xy 98.212103 -237.493968) (xy 98.163248 -237.4999)
			(xy 98.114073 -237.497919) (xy 98.065854 -237.488075) (xy 98.019838 -237.470623) (xy 97.977217 -237.446016)
			(xy 97.939096 -237.414891) (xy 97.906461 -237.378054) (xy 97.880158 -237.336458) (xy 97.860867 -237.291182)
			(xy 97.84909 -237.243398) (xy 97.84513 -237.194344) (xy 97.516442 -237.194344) (xy 97.515947 -237.218951)
			(xy 97.508052 -237.267528) (xy 97.492468 -237.314209) (xy 97.469597 -237.357786) (xy 97.440032 -237.39713)
			(xy 97.404539 -237.431222) (xy 97.364036 -237.459178) (xy 97.319574 -237.480276) (xy 97.272303 -237.493968)
			(xy 97.223448 -237.4999) (xy 97.174273 -237.497919) (xy 97.126054 -237.488075) (xy 97.080038 -237.470623)
			(xy 97.037417 -237.446016) (xy 96.999296 -237.414891) (xy 96.966661 -237.378054) (xy 96.940358 -237.336458)
			(xy 96.921067 -237.291182) (xy 96.90929 -237.243398) (xy 96.90533 -237.194344) (xy 96.57593 -237.194344)
			(xy 96.575941 -237.21836) (xy 96.568398 -237.265955) (xy 96.553479 -237.311776) (xy 96.531554 -237.354688)
			(xy 96.503165 -237.393627) (xy 96.469017 -237.427627) (xy 96.429955 -237.455847) (xy 96.386949 -237.477586)
			(xy 96.341064 -237.492306) (xy 96.317308 -237.49635) (xy 96.3168 -237.49635) (xy 96.316292 -237.496604)
			(xy 96.307528 -237.498267) (xy 96.291907 -237.506855) (xy 96.285812 -237.513368) (xy 96.280224 -237.519718)
			(xy 96.273874 -237.536736) (xy 96.273874 -237.691676) (xy 96.274065 -237.697909) (xy 96.277154 -237.709987)
			(xy 96.27997 -237.715552) (xy 96.284542 -237.723426) (xy 96.295085 -237.742028) (xy 96.313646 -237.780551)
			(xy 96.321626 -237.800388) (xy 96.323658 -237.805468) (xy 96.326452 -237.813088) (xy 96.33712 -237.82147)
			(xy 96.342595 -237.82543) (xy 96.355084 -237.830575) (xy 96.361758 -237.83163) (xy 96.448372 -237.84306)
			(xy 96.45511 -237.843644) (xy 96.468493 -237.841723) (xy 96.474788 -237.83925) (xy 96.48698 -237.83417)
			(xy 96.490536 -237.829598) (xy 96.495616 -237.82274) (xy 96.51012 -237.803911) (xy 96.543975 -237.770556)
			(xy 96.582588 -237.742848) (xy 96.625027 -237.721454) (xy 96.670267 -237.706892) (xy 96.717217 -237.699512)
			(xy 96.74098 -237.699042) (xy 96.766235 -237.699533) (xy 96.816056 -237.707844) (xy 96.863829 -237.724241)
			(xy 96.908252 -237.748279) (xy 96.948112 -237.779301) (xy 96.982322 -237.816461) (xy 97.009949 -237.858745)
			(xy 97.030239 -237.905) (xy 97.042639 -237.953963) (xy 97.04681 -238.0043) (xy 97.046806 -238.00435)
			(xy 97.37523 -238.00435) (xy 97.37919 -237.955296) (xy 97.390967 -237.907512) (xy 97.410258 -237.862236)
			(xy 97.436561 -237.82064) (xy 97.469196 -237.783803) (xy 97.507317 -237.752678) (xy 97.549938 -237.728071)
			(xy 97.595954 -237.710619) (xy 97.644173 -237.700775) (xy 97.693348 -237.698794) (xy 97.742203 -237.704726)
			(xy 97.789474 -237.718418) (xy 97.833936 -237.739516) (xy 97.874439 -237.767472) (xy 97.909932 -237.801564)
			(xy 97.939497 -237.840908) (xy 97.962368 -237.884485) (xy 97.977952 -237.931166) (xy 97.985847 -237.979743)
			(xy 97.986342 -238.00435) (xy 98.315284 -238.00435) (xy 98.319244 -237.955296) (xy 98.331021 -237.907512)
			(xy 98.350312 -237.862236) (xy 98.376615 -237.82064) (xy 98.40925 -237.783803) (xy 98.447371 -237.752678)
			(xy 98.489992 -237.728071) (xy 98.536008 -237.710619) (xy 98.584227 -237.700775) (xy 98.633402 -237.698794)
			(xy 98.682257 -237.704726) (xy 98.729528 -237.718418) (xy 98.77399 -237.739516) (xy 98.814493 -237.767472)
			(xy 98.849986 -237.801564) (xy 98.879551 -237.840908) (xy 98.902422 -237.884485) (xy 98.918006 -237.931166)
			(xy 98.925901 -237.979743) (xy 98.926396 -238.00435) (xy 99.255338 -238.00435) (xy 99.259298 -237.955296)
			(xy 99.271075 -237.907512) (xy 99.290366 -237.862236) (xy 99.316669 -237.82064) (xy 99.349304 -237.783803)
			(xy 99.387425 -237.752678) (xy 99.430046 -237.728071) (xy 99.476062 -237.710619) (xy 99.524281 -237.700775)
			(xy 99.573456 -237.698794) (xy 99.622311 -237.704726) (xy 99.669582 -237.718418) (xy 99.714044 -237.739516)
			(xy 99.754547 -237.767472) (xy 99.79004 -237.801564) (xy 99.819605 -237.840908) (xy 99.842476 -237.884485)
			(xy 99.85806 -237.931166) (xy 99.865955 -237.979743) (xy 99.86645 -238.00435) (xy 100.195138 -238.00435)
			(xy 100.199098 -237.955296) (xy 100.210875 -237.907512) (xy 100.230166 -237.862236) (xy 100.256469 -237.82064)
			(xy 100.289104 -237.783803) (xy 100.327225 -237.752678) (xy 100.369846 -237.728071) (xy 100.415862 -237.710619)
			(xy 100.464081 -237.700775) (xy 100.513256 -237.698794) (xy 100.562111 -237.704726) (xy 100.609382 -237.718418)
			(xy 100.653844 -237.739516) (xy 100.694347 -237.767472) (xy 100.72984 -237.801564) (xy 100.759405 -237.840908)
			(xy 100.782276 -237.884485) (xy 100.79786 -237.931166) (xy 100.805755 -237.979743) (xy 100.80625 -238.00435)
			(xy 101.135192 -238.00435) (xy 101.139152 -237.955296) (xy 101.150929 -237.907512) (xy 101.17022 -237.862236)
			(xy 101.196523 -237.82064) (xy 101.229158 -237.783803) (xy 101.267279 -237.752678) (xy 101.3099 -237.728071)
			(xy 101.355916 -237.710619) (xy 101.404135 -237.700775) (xy 101.45331 -237.698794) (xy 101.502165 -237.704726)
			(xy 101.549436 -237.718418) (xy 101.593898 -237.739516) (xy 101.634401 -237.767472) (xy 101.669894 -237.801564)
			(xy 101.699459 -237.840908) (xy 101.72233 -237.884485) (xy 101.737914 -237.931166) (xy 101.745809 -237.979743)
			(xy 101.746304 -238.00435) (xy 102.075246 -238.00435) (xy 102.079206 -237.955296) (xy 102.090983 -237.907512)
			(xy 102.110274 -237.862236) (xy 102.136577 -237.82064) (xy 102.169212 -237.783803) (xy 102.207333 -237.752678)
			(xy 102.249954 -237.728071) (xy 102.29597 -237.710619) (xy 102.344189 -237.700775) (xy 102.393364 -237.698794)
			(xy 102.442219 -237.704726) (xy 102.48949 -237.718418) (xy 102.533952 -237.739516) (xy 102.574455 -237.767472)
			(xy 102.609948 -237.801564) (xy 102.639513 -237.840908) (xy 102.662384 -237.884485) (xy 102.677968 -237.931166)
			(xy 102.685863 -237.979743) (xy 102.686358 -238.00435) (xy 103.0153 -238.00435) (xy 103.01926 -237.955296)
			(xy 103.031037 -237.907512) (xy 103.050328 -237.862236) (xy 103.076631 -237.82064) (xy 103.109266 -237.783803)
			(xy 103.147387 -237.752678) (xy 103.190008 -237.728071) (xy 103.236024 -237.710619) (xy 103.284243 -237.700775)
			(xy 103.333418 -237.698794) (xy 103.382273 -237.704726) (xy 103.429544 -237.718418) (xy 103.474006 -237.739516)
			(xy 103.514509 -237.767472) (xy 103.550002 -237.801564) (xy 103.579567 -237.840908) (xy 103.602438 -237.884485)
			(xy 103.618022 -237.931166) (xy 103.625917 -237.979743) (xy 103.626412 -238.00435) (xy 103.955354 -238.00435)
			(xy 103.959314 -237.955296) (xy 103.971091 -237.907512) (xy 103.990382 -237.862236) (xy 104.016685 -237.82064)
			(xy 104.04932 -237.783803) (xy 104.087441 -237.752678) (xy 104.130062 -237.728071) (xy 104.176078 -237.710619)
			(xy 104.224297 -237.700775) (xy 104.273472 -237.698794) (xy 104.322327 -237.704726) (xy 104.369598 -237.718418)
			(xy 104.41406 -237.739516) (xy 104.454563 -237.767472) (xy 104.490056 -237.801564) (xy 104.519621 -237.840908)
			(xy 104.542492 -237.884485) (xy 104.558076 -237.931166) (xy 104.565971 -237.979743) (xy 104.566466 -238.00435)
			(xy 104.895154 -238.00435) (xy 104.899114 -237.955296) (xy 104.910891 -237.907512) (xy 104.930182 -237.862236)
			(xy 104.956485 -237.82064) (xy 104.98912 -237.783803) (xy 105.027241 -237.752678) (xy 105.069862 -237.728071)
			(xy 105.115878 -237.710619) (xy 105.164097 -237.700775) (xy 105.213272 -237.698794) (xy 105.262127 -237.704726)
			(xy 105.309398 -237.718418) (xy 105.35386 -237.739516) (xy 105.394363 -237.767472) (xy 105.429856 -237.801564)
			(xy 105.459421 -237.840908) (xy 105.482292 -237.884485) (xy 105.497876 -237.931166) (xy 105.505771 -237.979743)
			(xy 105.506266 -238.00435) (xy 105.835208 -238.00435) (xy 105.839168 -237.955296) (xy 105.850945 -237.907512)
			(xy 105.870236 -237.862236) (xy 105.896539 -237.82064) (xy 105.929174 -237.783803) (xy 105.967295 -237.752678)
			(xy 106.009916 -237.728071) (xy 106.055932 -237.710619) (xy 106.104151 -237.700775) (xy 106.153326 -237.698794)
			(xy 106.202181 -237.704726) (xy 106.249452 -237.718418) (xy 106.293914 -237.739516) (xy 106.334417 -237.767472)
			(xy 106.36991 -237.801564) (xy 106.399475 -237.840908) (xy 106.422346 -237.884485) (xy 106.43793 -237.931166)
			(xy 106.445825 -237.979743) (xy 106.44632 -238.00435) (xy 106.775262 -238.00435) (xy 106.779222 -237.955296)
			(xy 106.790999 -237.907512) (xy 106.81029 -237.862236) (xy 106.836593 -237.82064) (xy 106.869228 -237.783803)
			(xy 106.907349 -237.752678) (xy 106.94997 -237.728071) (xy 106.995986 -237.710619) (xy 107.044205 -237.700775)
			(xy 107.09338 -237.698794) (xy 107.142235 -237.704726) (xy 107.189506 -237.718418) (xy 107.233968 -237.739516)
			(xy 107.274471 -237.767472) (xy 107.309964 -237.801564) (xy 107.339529 -237.840908) (xy 107.3624 -237.884485)
			(xy 107.377984 -237.931166) (xy 107.385879 -237.979743) (xy 107.386374 -238.00435) (xy 107.715316 -238.00435)
			(xy 107.719276 -237.955296) (xy 107.731053 -237.907512) (xy 107.750344 -237.862236) (xy 107.776647 -237.82064)
			(xy 107.809282 -237.783803) (xy 107.847403 -237.752678) (xy 107.890024 -237.728071) (xy 107.93604 -237.710619)
			(xy 107.984259 -237.700775) (xy 108.033434 -237.698794) (xy 108.082289 -237.704726) (xy 108.12956 -237.718418)
			(xy 108.174022 -237.739516) (xy 108.214525 -237.767472) (xy 108.250018 -237.801564) (xy 108.279583 -237.840908)
			(xy 108.302454 -237.884485) (xy 108.318038 -237.931166) (xy 108.325933 -237.979743) (xy 108.326428 -238.00435)
			(xy 108.65537 -238.00435) (xy 108.65933 -237.955296) (xy 108.671107 -237.907512) (xy 108.690398 -237.862236)
			(xy 108.716701 -237.82064) (xy 108.749336 -237.783803) (xy 108.787457 -237.752678) (xy 108.830078 -237.728071)
			(xy 108.876094 -237.710619) (xy 108.924313 -237.700775) (xy 108.973488 -237.698794) (xy 109.022343 -237.704726)
			(xy 109.069614 -237.718418) (xy 109.114076 -237.739516) (xy 109.154579 -237.767472) (xy 109.190072 -237.801564)
			(xy 109.219637 -237.840908) (xy 109.242508 -237.884485) (xy 109.258092 -237.931166) (xy 109.265987 -237.979743)
			(xy 109.266482 -238.00435) (xy 109.59517 -238.00435) (xy 109.59913 -237.955296) (xy 109.610907 -237.907512)
			(xy 109.630198 -237.862236) (xy 109.656501 -237.82064) (xy 109.689136 -237.783803) (xy 109.727257 -237.752678)
			(xy 109.769878 -237.728071) (xy 109.815894 -237.710619) (xy 109.864113 -237.700775) (xy 109.913288 -237.698794)
			(xy 109.962143 -237.704726) (xy 110.009414 -237.718418) (xy 110.053876 -237.739516) (xy 110.094379 -237.767472)
			(xy 110.129872 -237.801564) (xy 110.159437 -237.840908) (xy 110.182308 -237.884485) (xy 110.197892 -237.931166)
			(xy 110.205787 -237.979743) (xy 110.206282 -238.00435) (xy 113.349036 -238.00435) (xy 113.352996 -237.955296)
			(xy 113.364773 -237.907512) (xy 113.384064 -237.862236) (xy 113.410367 -237.82064) (xy 113.443002 -237.783803)
			(xy 113.481123 -237.752678) (xy 113.523744 -237.728071) (xy 113.56976 -237.710619) (xy 113.617979 -237.700775)
			(xy 113.667154 -237.698794) (xy 113.716009 -237.704726) (xy 113.76328 -237.718418) (xy 113.807742 -237.739516)
			(xy 113.848245 -237.767472) (xy 113.883738 -237.801564) (xy 113.913303 -237.840908) (xy 113.936174 -237.884485)
			(xy 113.951758 -237.931166) (xy 113.959653 -237.979743) (xy 113.960148 -238.00435) (xy 114.288836 -238.00435)
			(xy 114.292796 -237.955296) (xy 114.304573 -237.907512) (xy 114.323864 -237.862236) (xy 114.350167 -237.82064)
			(xy 114.382802 -237.783803) (xy 114.420923 -237.752678) (xy 114.463544 -237.728071) (xy 114.50956 -237.710619)
			(xy 114.557779 -237.700775) (xy 114.606954 -237.698794) (xy 114.655809 -237.704726) (xy 114.70308 -237.718418)
			(xy 114.747542 -237.739516) (xy 114.788045 -237.767472) (xy 114.823538 -237.801564) (xy 114.853103 -237.840908)
			(xy 114.875974 -237.884485) (xy 114.891558 -237.931166) (xy 114.899453 -237.979743) (xy 114.899948 -238.00435)
			(xy 115.22889 -238.00435) (xy 115.23285 -237.955296) (xy 115.244627 -237.907512) (xy 115.263918 -237.862236)
			(xy 115.290221 -237.82064) (xy 115.322856 -237.783803) (xy 115.360977 -237.752678) (xy 115.403598 -237.728071)
			(xy 115.449614 -237.710619) (xy 115.497833 -237.700775) (xy 115.547008 -237.698794) (xy 115.595863 -237.704726)
			(xy 115.643134 -237.718418) (xy 115.687596 -237.739516) (xy 115.728099 -237.767472) (xy 115.763592 -237.801564)
			(xy 115.793157 -237.840908) (xy 115.816028 -237.884485) (xy 115.831612 -237.931166) (xy 115.839507 -237.979743)
			(xy 115.840002 -238.00435) (xy 116.168944 -238.00435) (xy 116.172904 -237.955296) (xy 116.184681 -237.907512)
			(xy 116.203972 -237.862236) (xy 116.230275 -237.82064) (xy 116.26291 -237.783803) (xy 116.301031 -237.752678)
			(xy 116.343652 -237.728071) (xy 116.389668 -237.710619) (xy 116.437887 -237.700775) (xy 116.487062 -237.698794)
			(xy 116.535917 -237.704726) (xy 116.583188 -237.718418) (xy 116.62765 -237.739516) (xy 116.668153 -237.767472)
			(xy 116.703646 -237.801564) (xy 116.733211 -237.840908) (xy 116.756082 -237.884485) (xy 116.771666 -237.931166)
			(xy 116.779561 -237.979743) (xy 116.780056 -238.00435) (xy 117.108998 -238.00435) (xy 117.112958 -237.955296)
			(xy 117.124735 -237.907512) (xy 117.144026 -237.862236) (xy 117.170329 -237.82064) (xy 117.202964 -237.783803)
			(xy 117.241085 -237.752678) (xy 117.283706 -237.728071) (xy 117.329722 -237.710619) (xy 117.377941 -237.700775)
			(xy 117.427116 -237.698794) (xy 117.475971 -237.704726) (xy 117.523242 -237.718418) (xy 117.567704 -237.739516)
			(xy 117.608207 -237.767472) (xy 117.6437 -237.801564) (xy 117.673265 -237.840908) (xy 117.696136 -237.884485)
			(xy 117.71172 -237.931166) (xy 117.719615 -237.979743) (xy 117.72011 -238.00435) (xy 118.049052 -238.00435)
			(xy 118.053012 -237.955296) (xy 118.064789 -237.907512) (xy 118.08408 -237.862236) (xy 118.110383 -237.82064)
			(xy 118.143018 -237.783803) (xy 118.181139 -237.752678) (xy 118.22376 -237.728071) (xy 118.269776 -237.710619)
			(xy 118.317995 -237.700775) (xy 118.36717 -237.698794) (xy 118.416025 -237.704726) (xy 118.463296 -237.718418)
			(xy 118.507758 -237.739516) (xy 118.548261 -237.767472) (xy 118.583754 -237.801564) (xy 118.613319 -237.840908)
			(xy 118.63619 -237.884485) (xy 118.651774 -237.931166) (xy 118.659669 -237.979743) (xy 118.660164 -238.00435)
			(xy 118.988852 -238.00435) (xy 118.992812 -237.955296) (xy 119.004589 -237.907512) (xy 119.02388 -237.862236)
			(xy 119.050183 -237.82064) (xy 119.082818 -237.783803) (xy 119.120939 -237.752678) (xy 119.16356 -237.728071)
			(xy 119.209576 -237.710619) (xy 119.257795 -237.700775) (xy 119.30697 -237.698794) (xy 119.355825 -237.704726)
			(xy 119.403096 -237.718418) (xy 119.447558 -237.739516) (xy 119.488061 -237.767472) (xy 119.523554 -237.801564)
			(xy 119.553119 -237.840908) (xy 119.57599 -237.884485) (xy 119.591574 -237.931166) (xy 119.599469 -237.979743)
			(xy 119.599964 -238.00435) (xy 119.928906 -238.00435) (xy 119.932866 -237.955296) (xy 119.944643 -237.907512)
			(xy 119.963934 -237.862236) (xy 119.990237 -237.82064) (xy 120.022872 -237.783803) (xy 120.060993 -237.752678)
			(xy 120.103614 -237.728071) (xy 120.14963 -237.710619) (xy 120.197849 -237.700775) (xy 120.247024 -237.698794)
			(xy 120.295879 -237.704726) (xy 120.34315 -237.718418) (xy 120.387612 -237.739516) (xy 120.428115 -237.767472)
			(xy 120.463608 -237.801564) (xy 120.493173 -237.840908) (xy 120.516044 -237.884485) (xy 120.531628 -237.931166)
			(xy 120.539523 -237.979743) (xy 120.540018 -238.00435) (xy 120.86896 -238.00435) (xy 120.87292 -237.955296)
			(xy 120.884697 -237.907512) (xy 120.903988 -237.862236) (xy 120.930291 -237.82064) (xy 120.962926 -237.783803)
			(xy 121.001047 -237.752678) (xy 121.043668 -237.728071) (xy 121.089684 -237.710619) (xy 121.137903 -237.700775)
			(xy 121.187078 -237.698794) (xy 121.235933 -237.704726) (xy 121.283204 -237.718418) (xy 121.327666 -237.739516)
			(xy 121.368169 -237.767472) (xy 121.403662 -237.801564) (xy 121.433227 -237.840908) (xy 121.456098 -237.884485)
			(xy 121.471682 -237.931166) (xy 121.479577 -237.979743) (xy 121.480072 -238.00435) (xy 121.809014 -238.00435)
			(xy 121.812974 -237.955296) (xy 121.824751 -237.907512) (xy 121.844042 -237.862236) (xy 121.870345 -237.82064)
			(xy 121.90298 -237.783803) (xy 121.941101 -237.752678) (xy 121.983722 -237.728071) (xy 122.029738 -237.710619)
			(xy 122.077957 -237.700775) (xy 122.127132 -237.698794) (xy 122.175987 -237.704726) (xy 122.223258 -237.718418)
			(xy 122.26772 -237.739516) (xy 122.308223 -237.767472) (xy 122.343716 -237.801564) (xy 122.373281 -237.840908)
			(xy 122.396152 -237.884485) (xy 122.411736 -237.931166) (xy 122.419631 -237.979743) (xy 122.420126 -238.00435)
			(xy 122.748814 -238.00435) (xy 122.752774 -237.955296) (xy 122.764551 -237.907512) (xy 122.783842 -237.862236)
			(xy 122.810145 -237.82064) (xy 122.84278 -237.783803) (xy 122.880901 -237.752678) (xy 122.923522 -237.728071)
			(xy 122.969538 -237.710619) (xy 123.017757 -237.700775) (xy 123.066932 -237.698794) (xy 123.115787 -237.704726)
			(xy 123.163058 -237.718418) (xy 123.20752 -237.739516) (xy 123.248023 -237.767472) (xy 123.283516 -237.801564)
			(xy 123.313081 -237.840908) (xy 123.335952 -237.884485) (xy 123.351536 -237.931166) (xy 123.359431 -237.979743)
			(xy 123.359926 -238.00435) (xy 123.688868 -238.00435) (xy 123.692828 -237.955296) (xy 123.704605 -237.907512)
			(xy 123.723896 -237.862236) (xy 123.750199 -237.82064) (xy 123.782834 -237.783803) (xy 123.820955 -237.752678)
			(xy 123.863576 -237.728071) (xy 123.909592 -237.710619) (xy 123.957811 -237.700775) (xy 124.006986 -237.698794)
			(xy 124.055841 -237.704726) (xy 124.103112 -237.718418) (xy 124.147574 -237.739516) (xy 124.188077 -237.767472)
			(xy 124.22357 -237.801564) (xy 124.253135 -237.840908) (xy 124.276006 -237.884485) (xy 124.29159 -237.931166)
			(xy 124.299485 -237.979743) (xy 124.29998 -238.00435) (xy 124.628922 -238.00435) (xy 124.632882 -237.955296)
			(xy 124.644659 -237.907512) (xy 124.66395 -237.862236) (xy 124.690253 -237.82064) (xy 124.722888 -237.783803)
			(xy 124.761009 -237.752678) (xy 124.80363 -237.728071) (xy 124.849646 -237.710619) (xy 124.897865 -237.700775)
			(xy 124.94704 -237.698794) (xy 124.995895 -237.704726) (xy 125.043166 -237.718418) (xy 125.087628 -237.739516)
			(xy 125.128131 -237.767472) (xy 125.163624 -237.801564) (xy 125.193189 -237.840908) (xy 125.21606 -237.884485)
			(xy 125.231644 -237.931166) (xy 125.239539 -237.979743) (xy 125.240034 -238.00435) (xy 125.568976 -238.00435)
			(xy 125.572936 -237.955296) (xy 125.584713 -237.907512) (xy 125.604004 -237.862236) (xy 125.630307 -237.82064)
			(xy 125.662942 -237.783803) (xy 125.701063 -237.752678) (xy 125.743684 -237.728071) (xy 125.7897 -237.710619)
			(xy 125.837919 -237.700775) (xy 125.887094 -237.698794) (xy 125.935949 -237.704726) (xy 125.98322 -237.718418)
			(xy 126.027682 -237.739516) (xy 126.068185 -237.767472) (xy 126.103678 -237.801564) (xy 126.133243 -237.840908)
			(xy 126.156114 -237.884485) (xy 126.171698 -237.931166) (xy 126.179593 -237.979743) (xy 126.180088 -238.00435)
			(xy 126.179593 -238.028957) (xy 126.171698 -238.077534) (xy 126.156114 -238.124215) (xy 126.133243 -238.167792)
			(xy 126.103678 -238.207136) (xy 126.068185 -238.241228) (xy 126.027682 -238.269184) (xy 125.98322 -238.290282)
			(xy 125.935949 -238.303974) (xy 125.887094 -238.309906) (xy 125.837919 -238.307925) (xy 125.7897 -238.298081)
			(xy 125.743684 -238.280629) (xy 125.701063 -238.256022) (xy 125.662942 -238.224897) (xy 125.630307 -238.18806)
			(xy 125.604004 -238.146464) (xy 125.584713 -238.101188) (xy 125.572936 -238.053404) (xy 125.568976 -238.00435)
			(xy 125.240034 -238.00435) (xy 125.239539 -238.028957) (xy 125.231644 -238.077534) (xy 125.21606 -238.124215)
			(xy 125.193189 -238.167792) (xy 125.163624 -238.207136) (xy 125.128131 -238.241228) (xy 125.087628 -238.269184)
			(xy 125.043166 -238.290282) (xy 124.995895 -238.303974) (xy 124.94704 -238.309906) (xy 124.897865 -238.307925)
			(xy 124.849646 -238.298081) (xy 124.80363 -238.280629) (xy 124.761009 -238.256022) (xy 124.722888 -238.224897)
			(xy 124.690253 -238.18806) (xy 124.66395 -238.146464) (xy 124.644659 -238.101188) (xy 124.632882 -238.053404)
			(xy 124.628922 -238.00435) (xy 124.29998 -238.00435) (xy 124.299485 -238.028957) (xy 124.29159 -238.077534)
			(xy 124.276006 -238.124215) (xy 124.253135 -238.167792) (xy 124.22357 -238.207136) (xy 124.188077 -238.241228)
			(xy 124.147574 -238.269184) (xy 124.103112 -238.290282) (xy 124.055841 -238.303974) (xy 124.006986 -238.309906)
			(xy 123.957811 -238.307925) (xy 123.909592 -238.298081) (xy 123.863576 -238.280629) (xy 123.820955 -238.256022)
			(xy 123.782834 -238.224897) (xy 123.750199 -238.18806) (xy 123.723896 -238.146464) (xy 123.704605 -238.101188)
			(xy 123.692828 -238.053404) (xy 123.688868 -238.00435) (xy 123.359926 -238.00435) (xy 123.359431 -238.028957)
			(xy 123.351536 -238.077534) (xy 123.335952 -238.124215) (xy 123.313081 -238.167792) (xy 123.283516 -238.207136)
			(xy 123.248023 -238.241228) (xy 123.20752 -238.269184) (xy 123.163058 -238.290282) (xy 123.115787 -238.303974)
			(xy 123.066932 -238.309906) (xy 123.017757 -238.307925) (xy 122.969538 -238.298081) (xy 122.923522 -238.280629)
			(xy 122.880901 -238.256022) (xy 122.84278 -238.224897) (xy 122.810145 -238.18806) (xy 122.783842 -238.146464)
			(xy 122.764551 -238.101188) (xy 122.752774 -238.053404) (xy 122.748814 -238.00435) (xy 122.420126 -238.00435)
			(xy 122.419631 -238.028957) (xy 122.411736 -238.077534) (xy 122.396152 -238.124215) (xy 122.373281 -238.167792)
			(xy 122.343716 -238.207136) (xy 122.308223 -238.241228) (xy 122.26772 -238.269184) (xy 122.223258 -238.290282)
			(xy 122.175987 -238.303974) (xy 122.127132 -238.309906) (xy 122.077957 -238.307925) (xy 122.029738 -238.298081)
			(xy 121.983722 -238.280629) (xy 121.941101 -238.256022) (xy 121.90298 -238.224897) (xy 121.870345 -238.18806)
			(xy 121.844042 -238.146464) (xy 121.824751 -238.101188) (xy 121.812974 -238.053404) (xy 121.809014 -238.00435)
			(xy 121.480072 -238.00435) (xy 121.479577 -238.028957) (xy 121.471682 -238.077534) (xy 121.456098 -238.124215)
			(xy 121.433227 -238.167792) (xy 121.403662 -238.207136) (xy 121.368169 -238.241228) (xy 121.327666 -238.269184)
			(xy 121.283204 -238.290282) (xy 121.235933 -238.303974) (xy 121.187078 -238.309906) (xy 121.137903 -238.307925)
			(xy 121.089684 -238.298081) (xy 121.043668 -238.280629) (xy 121.001047 -238.256022) (xy 120.962926 -238.224897)
			(xy 120.930291 -238.18806) (xy 120.903988 -238.146464) (xy 120.884697 -238.101188) (xy 120.87292 -238.053404)
			(xy 120.86896 -238.00435) (xy 120.540018 -238.00435) (xy 120.539523 -238.028957) (xy 120.531628 -238.077534)
			(xy 120.516044 -238.124215) (xy 120.493173 -238.167792) (xy 120.463608 -238.207136) (xy 120.428115 -238.241228)
			(xy 120.387612 -238.269184) (xy 120.34315 -238.290282) (xy 120.295879 -238.303974) (xy 120.247024 -238.309906)
			(xy 120.197849 -238.307925) (xy 120.14963 -238.298081) (xy 120.103614 -238.280629) (xy 120.060993 -238.256022)
			(xy 120.022872 -238.224897) (xy 119.990237 -238.18806) (xy 119.963934 -238.146464) (xy 119.944643 -238.101188)
			(xy 119.932866 -238.053404) (xy 119.928906 -238.00435) (xy 119.599964 -238.00435) (xy 119.599469 -238.028957)
			(xy 119.591574 -238.077534) (xy 119.57599 -238.124215) (xy 119.553119 -238.167792) (xy 119.523554 -238.207136)
			(xy 119.488061 -238.241228) (xy 119.447558 -238.269184) (xy 119.403096 -238.290282) (xy 119.355825 -238.303974)
			(xy 119.30697 -238.309906) (xy 119.257795 -238.307925) (xy 119.209576 -238.298081) (xy 119.16356 -238.280629)
			(xy 119.120939 -238.256022) (xy 119.082818 -238.224897) (xy 119.050183 -238.18806) (xy 119.02388 -238.146464)
			(xy 119.004589 -238.101188) (xy 118.992812 -238.053404) (xy 118.988852 -238.00435) (xy 118.660164 -238.00435)
			(xy 118.659669 -238.028957) (xy 118.651774 -238.077534) (xy 118.63619 -238.124215) (xy 118.613319 -238.167792)
			(xy 118.583754 -238.207136) (xy 118.548261 -238.241228) (xy 118.507758 -238.269184) (xy 118.463296 -238.290282)
			(xy 118.416025 -238.303974) (xy 118.36717 -238.309906) (xy 118.317995 -238.307925) (xy 118.269776 -238.298081)
			(xy 118.22376 -238.280629) (xy 118.181139 -238.256022) (xy 118.143018 -238.224897) (xy 118.110383 -238.18806)
			(xy 118.08408 -238.146464) (xy 118.064789 -238.101188) (xy 118.053012 -238.053404) (xy 118.049052 -238.00435)
			(xy 117.72011 -238.00435) (xy 117.719615 -238.028957) (xy 117.71172 -238.077534) (xy 117.696136 -238.124215)
			(xy 117.673265 -238.167792) (xy 117.6437 -238.207136) (xy 117.608207 -238.241228) (xy 117.567704 -238.269184)
			(xy 117.523242 -238.290282) (xy 117.475971 -238.303974) (xy 117.427116 -238.309906) (xy 117.377941 -238.307925)
			(xy 117.329722 -238.298081) (xy 117.283706 -238.280629) (xy 117.241085 -238.256022) (xy 117.202964 -238.224897)
			(xy 117.170329 -238.18806) (xy 117.144026 -238.146464) (xy 117.124735 -238.101188) (xy 117.112958 -238.053404)
			(xy 117.108998 -238.00435) (xy 116.780056 -238.00435) (xy 116.779561 -238.028957) (xy 116.771666 -238.077534)
			(xy 116.756082 -238.124215) (xy 116.733211 -238.167792) (xy 116.703646 -238.207136) (xy 116.668153 -238.241228)
			(xy 116.62765 -238.269184) (xy 116.583188 -238.290282) (xy 116.535917 -238.303974) (xy 116.487062 -238.309906)
			(xy 116.437887 -238.307925) (xy 116.389668 -238.298081) (xy 116.343652 -238.280629) (xy 116.301031 -238.256022)
			(xy 116.26291 -238.224897) (xy 116.230275 -238.18806) (xy 116.203972 -238.146464) (xy 116.184681 -238.101188)
			(xy 116.172904 -238.053404) (xy 116.168944 -238.00435) (xy 115.840002 -238.00435) (xy 115.839507 -238.028957)
			(xy 115.831612 -238.077534) (xy 115.816028 -238.124215) (xy 115.793157 -238.167792) (xy 115.763592 -238.207136)
			(xy 115.728099 -238.241228) (xy 115.687596 -238.269184) (xy 115.643134 -238.290282) (xy 115.595863 -238.303974)
			(xy 115.547008 -238.309906) (xy 115.497833 -238.307925) (xy 115.449614 -238.298081) (xy 115.403598 -238.280629)
			(xy 115.360977 -238.256022) (xy 115.322856 -238.224897) (xy 115.290221 -238.18806) (xy 115.263918 -238.146464)
			(xy 115.244627 -238.101188) (xy 115.23285 -238.053404) (xy 115.22889 -238.00435) (xy 114.899948 -238.00435)
			(xy 114.899453 -238.028957) (xy 114.891558 -238.077534) (xy 114.875974 -238.124215) (xy 114.853103 -238.167792)
			(xy 114.823538 -238.207136) (xy 114.788045 -238.241228) (xy 114.747542 -238.269184) (xy 114.70308 -238.290282)
			(xy 114.655809 -238.303974) (xy 114.606954 -238.309906) (xy 114.557779 -238.307925) (xy 114.50956 -238.298081)
			(xy 114.463544 -238.280629) (xy 114.420923 -238.256022) (xy 114.382802 -238.224897) (xy 114.350167 -238.18806)
			(xy 114.323864 -238.146464) (xy 114.304573 -238.101188) (xy 114.292796 -238.053404) (xy 114.288836 -238.00435)
			(xy 113.960148 -238.00435) (xy 113.959653 -238.028957) (xy 113.951758 -238.077534) (xy 113.936174 -238.124215)
			(xy 113.913303 -238.167792) (xy 113.883738 -238.207136) (xy 113.848245 -238.241228) (xy 113.807742 -238.269184)
			(xy 113.76328 -238.290282) (xy 113.716009 -238.303974) (xy 113.667154 -238.309906) (xy 113.617979 -238.307925)
			(xy 113.56976 -238.298081) (xy 113.523744 -238.280629) (xy 113.481123 -238.256022) (xy 113.443002 -238.224897)
			(xy 113.410367 -238.18806) (xy 113.384064 -238.146464) (xy 113.364773 -238.101188) (xy 113.352996 -238.053404)
			(xy 113.349036 -238.00435) (xy 110.206282 -238.00435) (xy 110.205787 -238.028957) (xy 110.197892 -238.077534)
			(xy 110.182308 -238.124215) (xy 110.159437 -238.167792) (xy 110.129872 -238.207136) (xy 110.094379 -238.241228)
			(xy 110.053876 -238.269184) (xy 110.009414 -238.290282) (xy 109.962143 -238.303974) (xy 109.913288 -238.309906)
			(xy 109.864113 -238.307925) (xy 109.815894 -238.298081) (xy 109.769878 -238.280629) (xy 109.727257 -238.256022)
			(xy 109.689136 -238.224897) (xy 109.656501 -238.18806) (xy 109.630198 -238.146464) (xy 109.610907 -238.101188)
			(xy 109.59913 -238.053404) (xy 109.59517 -238.00435) (xy 109.266482 -238.00435) (xy 109.265987 -238.028957)
			(xy 109.258092 -238.077534) (xy 109.242508 -238.124215) (xy 109.219637 -238.167792) (xy 109.190072 -238.207136)
			(xy 109.154579 -238.241228) (xy 109.114076 -238.269184) (xy 109.069614 -238.290282) (xy 109.022343 -238.303974)
			(xy 108.973488 -238.309906) (xy 108.924313 -238.307925) (xy 108.876094 -238.298081) (xy 108.830078 -238.280629)
			(xy 108.787457 -238.256022) (xy 108.749336 -238.224897) (xy 108.716701 -238.18806) (xy 108.690398 -238.146464)
			(xy 108.671107 -238.101188) (xy 108.65933 -238.053404) (xy 108.65537 -238.00435) (xy 108.326428 -238.00435)
			(xy 108.325933 -238.028957) (xy 108.318038 -238.077534) (xy 108.302454 -238.124215) (xy 108.279583 -238.167792)
			(xy 108.250018 -238.207136) (xy 108.214525 -238.241228) (xy 108.174022 -238.269184) (xy 108.12956 -238.290282)
			(xy 108.082289 -238.303974) (xy 108.033434 -238.309906) (xy 107.984259 -238.307925) (xy 107.93604 -238.298081)
			(xy 107.890024 -238.280629) (xy 107.847403 -238.256022) (xy 107.809282 -238.224897) (xy 107.776647 -238.18806)
			(xy 107.750344 -238.146464) (xy 107.731053 -238.101188) (xy 107.719276 -238.053404) (xy 107.715316 -238.00435)
			(xy 107.386374 -238.00435) (xy 107.385879 -238.028957) (xy 107.377984 -238.077534) (xy 107.3624 -238.124215)
			(xy 107.339529 -238.167792) (xy 107.309964 -238.207136) (xy 107.274471 -238.241228) (xy 107.233968 -238.269184)
			(xy 107.189506 -238.290282) (xy 107.142235 -238.303974) (xy 107.09338 -238.309906) (xy 107.044205 -238.307925)
			(xy 106.995986 -238.298081) (xy 106.94997 -238.280629) (xy 106.907349 -238.256022) (xy 106.869228 -238.224897)
			(xy 106.836593 -238.18806) (xy 106.81029 -238.146464) (xy 106.790999 -238.101188) (xy 106.779222 -238.053404)
			(xy 106.775262 -238.00435) (xy 106.44632 -238.00435) (xy 106.445825 -238.028957) (xy 106.43793 -238.077534)
			(xy 106.422346 -238.124215) (xy 106.399475 -238.167792) (xy 106.36991 -238.207136) (xy 106.334417 -238.241228)
			(xy 106.293914 -238.269184) (xy 106.249452 -238.290282) (xy 106.202181 -238.303974) (xy 106.153326 -238.309906)
			(xy 106.104151 -238.307925) (xy 106.055932 -238.298081) (xy 106.009916 -238.280629) (xy 105.967295 -238.256022)
			(xy 105.929174 -238.224897) (xy 105.896539 -238.18806) (xy 105.870236 -238.146464) (xy 105.850945 -238.101188)
			(xy 105.839168 -238.053404) (xy 105.835208 -238.00435) (xy 105.506266 -238.00435) (xy 105.505771 -238.028957)
			(xy 105.497876 -238.077534) (xy 105.482292 -238.124215) (xy 105.459421 -238.167792) (xy 105.429856 -238.207136)
			(xy 105.394363 -238.241228) (xy 105.35386 -238.269184) (xy 105.309398 -238.290282) (xy 105.262127 -238.303974)
			(xy 105.213272 -238.309906) (xy 105.164097 -238.307925) (xy 105.115878 -238.298081) (xy 105.069862 -238.280629)
			(xy 105.027241 -238.256022) (xy 104.98912 -238.224897) (xy 104.956485 -238.18806) (xy 104.930182 -238.146464)
			(xy 104.910891 -238.101188) (xy 104.899114 -238.053404) (xy 104.895154 -238.00435) (xy 104.566466 -238.00435)
			(xy 104.565971 -238.028957) (xy 104.558076 -238.077534) (xy 104.542492 -238.124215) (xy 104.519621 -238.167792)
			(xy 104.490056 -238.207136) (xy 104.454563 -238.241228) (xy 104.41406 -238.269184) (xy 104.369598 -238.290282)
			(xy 104.322327 -238.303974) (xy 104.273472 -238.309906) (xy 104.224297 -238.307925) (xy 104.176078 -238.298081)
			(xy 104.130062 -238.280629) (xy 104.087441 -238.256022) (xy 104.04932 -238.224897) (xy 104.016685 -238.18806)
			(xy 103.990382 -238.146464) (xy 103.971091 -238.101188) (xy 103.959314 -238.053404) (xy 103.955354 -238.00435)
			(xy 103.626412 -238.00435) (xy 103.625917 -238.028957) (xy 103.618022 -238.077534) (xy 103.602438 -238.124215)
			(xy 103.579567 -238.167792) (xy 103.550002 -238.207136) (xy 103.514509 -238.241228) (xy 103.474006 -238.269184)
			(xy 103.429544 -238.290282) (xy 103.382273 -238.303974) (xy 103.333418 -238.309906) (xy 103.284243 -238.307925)
			(xy 103.236024 -238.298081) (xy 103.190008 -238.280629) (xy 103.147387 -238.256022) (xy 103.109266 -238.224897)
			(xy 103.076631 -238.18806) (xy 103.050328 -238.146464) (xy 103.031037 -238.101188) (xy 103.01926 -238.053404)
			(xy 103.0153 -238.00435) (xy 102.686358 -238.00435) (xy 102.685863 -238.028957) (xy 102.677968 -238.077534)
			(xy 102.662384 -238.124215) (xy 102.639513 -238.167792) (xy 102.609948 -238.207136) (xy 102.574455 -238.241228)
			(xy 102.533952 -238.269184) (xy 102.48949 -238.290282) (xy 102.442219 -238.303974) (xy 102.393364 -238.309906)
			(xy 102.344189 -238.307925) (xy 102.29597 -238.298081) (xy 102.249954 -238.280629) (xy 102.207333 -238.256022)
			(xy 102.169212 -238.224897) (xy 102.136577 -238.18806) (xy 102.110274 -238.146464) (xy 102.090983 -238.101188)
			(xy 102.079206 -238.053404) (xy 102.075246 -238.00435) (xy 101.746304 -238.00435) (xy 101.745809 -238.028957)
			(xy 101.737914 -238.077534) (xy 101.72233 -238.124215) (xy 101.699459 -238.167792) (xy 101.669894 -238.207136)
			(xy 101.634401 -238.241228) (xy 101.593898 -238.269184) (xy 101.549436 -238.290282) (xy 101.502165 -238.303974)
			(xy 101.45331 -238.309906) (xy 101.404135 -238.307925) (xy 101.355916 -238.298081) (xy 101.3099 -238.280629)
			(xy 101.267279 -238.256022) (xy 101.229158 -238.224897) (xy 101.196523 -238.18806) (xy 101.17022 -238.146464)
			(xy 101.150929 -238.101188) (xy 101.139152 -238.053404) (xy 101.135192 -238.00435) (xy 100.80625 -238.00435)
			(xy 100.805755 -238.028957) (xy 100.79786 -238.077534) (xy 100.782276 -238.124215) (xy 100.759405 -238.167792)
			(xy 100.72984 -238.207136) (xy 100.694347 -238.241228) (xy 100.653844 -238.269184) (xy 100.609382 -238.290282)
			(xy 100.562111 -238.303974) (xy 100.513256 -238.309906) (xy 100.464081 -238.307925) (xy 100.415862 -238.298081)
			(xy 100.369846 -238.280629) (xy 100.327225 -238.256022) (xy 100.289104 -238.224897) (xy 100.256469 -238.18806)
			(xy 100.230166 -238.146464) (xy 100.210875 -238.101188) (xy 100.199098 -238.053404) (xy 100.195138 -238.00435)
			(xy 99.86645 -238.00435) (xy 99.865955 -238.028957) (xy 99.85806 -238.077534) (xy 99.842476 -238.124215)
			(xy 99.819605 -238.167792) (xy 99.79004 -238.207136) (xy 99.754547 -238.241228) (xy 99.714044 -238.269184)
			(xy 99.669582 -238.290282) (xy 99.622311 -238.303974) (xy 99.573456 -238.309906) (xy 99.524281 -238.307925)
			(xy 99.476062 -238.298081) (xy 99.430046 -238.280629) (xy 99.387425 -238.256022) (xy 99.349304 -238.224897)
			(xy 99.316669 -238.18806) (xy 99.290366 -238.146464) (xy 99.271075 -238.101188) (xy 99.259298 -238.053404)
			(xy 99.255338 -238.00435) (xy 98.926396 -238.00435) (xy 98.925901 -238.028957) (xy 98.918006 -238.077534)
			(xy 98.902422 -238.124215) (xy 98.879551 -238.167792) (xy 98.849986 -238.207136) (xy 98.814493 -238.241228)
			(xy 98.77399 -238.269184) (xy 98.729528 -238.290282) (xy 98.682257 -238.303974) (xy 98.633402 -238.309906)
			(xy 98.584227 -238.307925) (xy 98.536008 -238.298081) (xy 98.489992 -238.280629) (xy 98.447371 -238.256022)
			(xy 98.40925 -238.224897) (xy 98.376615 -238.18806) (xy 98.350312 -238.146464) (xy 98.331021 -238.101188)
			(xy 98.319244 -238.053404) (xy 98.315284 -238.00435) (xy 97.986342 -238.00435) (xy 97.985847 -238.028957)
			(xy 97.977952 -238.077534) (xy 97.962368 -238.124215) (xy 97.939497 -238.167792) (xy 97.909932 -238.207136)
			(xy 97.874439 -238.241228) (xy 97.833936 -238.269184) (xy 97.789474 -238.290282) (xy 97.742203 -238.303974)
			(xy 97.693348 -238.309906) (xy 97.644173 -238.307925) (xy 97.595954 -238.298081) (xy 97.549938 -238.280629)
			(xy 97.507317 -238.256022) (xy 97.469196 -238.224897) (xy 97.436561 -238.18806) (xy 97.410258 -238.146464)
			(xy 97.390967 -238.101188) (xy 97.37919 -238.053404) (xy 97.37523 -238.00435) (xy 97.046806 -238.00435)
			(xy 97.042639 -238.054637) (xy 97.030239 -238.1036) (xy 97.009949 -238.149855) (xy 96.982322 -238.192139)
			(xy 96.948112 -238.229299) (xy 96.908252 -238.260321) (xy 96.863829 -238.284359) (xy 96.816056 -238.300756)
			(xy 96.766235 -238.309067) (xy 96.74098 -238.309658) (xy 96.717214 -238.30921) (xy 96.670255 -238.30185)
			(xy 96.625006 -238.287296) (xy 96.582562 -238.265899) (xy 96.54395 -238.238178) (xy 96.510105 -238.204804)
			(xy 96.495616 -238.18596) (xy 96.490536 -238.179102) (xy 96.48698 -238.17453) (xy 96.474788 -238.16945)
			(xy 96.468505 -238.166926) (xy 96.455111 -238.164985) (xy 96.448372 -238.16564) (xy 96.361758 -238.17707)
			(xy 96.355082 -238.178121) (xy 96.34259 -238.183262) (xy 96.33712 -238.18723) (xy 96.326452 -238.195612)
			(xy 96.323658 -238.203232) (xy 96.321626 -238.208312) (xy 96.308164 -238.239554) (xy 96.302017 -238.252679)
			(xy 96.28855 -238.278347) (xy 96.28124 -238.290862) (xy 96.280986 -238.291116) (xy 96.27743 -238.297212)
			(xy 96.275652 -238.303308) (xy 96.273874 -238.31677) (xy 96.273874 -238.462566) (xy 96.274248 -238.471671)
			(xy 96.280625 -238.488726) (xy 96.28632 -238.49584) (xy 96.291908 -238.50219) (xy 96.307402 -238.510826)
			(xy 96.317054 -238.51235) (xy 96.340801 -238.516445) (xy 96.386698 -238.531124) (xy 96.429721 -238.552825)
			(xy 96.468806 -238.581009) (xy 96.502983 -238.614979) (xy 96.531404 -238.653891) (xy 96.553366 -238.696782)
			(xy 96.568324 -238.742588) (xy 96.575908 -238.790175) (xy 96.575919 -238.814356) (xy 98.785184 -238.814356)
			(xy 98.789144 -238.765302) (xy 98.800921 -238.717518) (xy 98.820212 -238.672242) (xy 98.846515 -238.630646)
			(xy 98.87915 -238.593809) (xy 98.917271 -238.562684) (xy 98.959892 -238.538077) (xy 99.005908 -238.520625)
			(xy 99.054127 -238.510781) (xy 99.103302 -238.5088) (xy 99.152157 -238.514732) (xy 99.199428 -238.528424)
			(xy 99.24389 -238.549522) (xy 99.284393 -238.577478) (xy 99.319886 -238.61157) (xy 99.349451 -238.650914)
			(xy 99.372322 -238.694491) (xy 99.387906 -238.741172) (xy 99.395801 -238.789749) (xy 99.396296 -238.814356)
			(xy 101.605346 -238.814356) (xy 101.609306 -238.765302) (xy 101.621083 -238.717518) (xy 101.640374 -238.672242)
			(xy 101.666677 -238.630646) (xy 101.699312 -238.593809) (xy 101.737433 -238.562684) (xy 101.780054 -238.538077)
			(xy 101.82607 -238.520625) (xy 101.874289 -238.510781) (xy 101.923464 -238.5088) (xy 101.972319 -238.514732)
			(xy 102.01959 -238.528424) (xy 102.064052 -238.549522) (xy 102.104555 -238.577478) (xy 102.140048 -238.61157)
			(xy 102.169613 -238.650914) (xy 102.192484 -238.694491) (xy 102.208068 -238.741172) (xy 102.215963 -238.789749)
			(xy 102.216458 -238.814356) (xy 104.425254 -238.814356) (xy 104.429214 -238.765302) (xy 104.440991 -238.717518)
			(xy 104.460282 -238.672242) (xy 104.486585 -238.630646) (xy 104.51922 -238.593809) (xy 104.557341 -238.562684)
			(xy 104.599962 -238.538077) (xy 104.645978 -238.520625) (xy 104.694197 -238.510781) (xy 104.743372 -238.5088)
			(xy 104.792227 -238.514732) (xy 104.839498 -238.528424) (xy 104.88396 -238.549522) (xy 104.924463 -238.577478)
			(xy 104.959956 -238.61157) (xy 104.989521 -238.650914) (xy 105.012392 -238.694491) (xy 105.027976 -238.741172)
			(xy 105.035871 -238.789749) (xy 105.036366 -238.814356) (xy 107.245162 -238.814356) (xy 107.249122 -238.765302)
			(xy 107.260899 -238.717518) (xy 107.28019 -238.672242) (xy 107.306493 -238.630646) (xy 107.339128 -238.593809)
			(xy 107.377249 -238.562684) (xy 107.41987 -238.538077) (xy 107.465886 -238.520625) (xy 107.514105 -238.510781)
			(xy 107.56328 -238.5088) (xy 107.612135 -238.514732) (xy 107.659406 -238.528424) (xy 107.703868 -238.549522)
			(xy 107.744371 -238.577478) (xy 107.779864 -238.61157) (xy 107.809429 -238.650914) (xy 107.8323 -238.694491)
			(xy 107.847884 -238.741172) (xy 107.855779 -238.789749) (xy 107.856274 -238.814356) (xy 108.185216 -238.814356)
			(xy 108.189176 -238.765302) (xy 108.200953 -238.717518) (xy 108.220244 -238.672242) (xy 108.246547 -238.630646)
			(xy 108.279182 -238.593809) (xy 108.317303 -238.562684) (xy 108.359924 -238.538077) (xy 108.40594 -238.520625)
			(xy 108.454159 -238.510781) (xy 108.503334 -238.5088) (xy 108.552189 -238.514732) (xy 108.59946 -238.528424)
			(xy 108.643922 -238.549522) (xy 108.684425 -238.577478) (xy 108.719918 -238.61157) (xy 108.749483 -238.650914)
			(xy 108.772354 -238.694491) (xy 108.787938 -238.741172) (xy 108.795833 -238.789749) (xy 108.796328 -238.814356)
			(xy 109.12527 -238.814356) (xy 109.12923 -238.765302) (xy 109.141007 -238.717518) (xy 109.160298 -238.672242)
			(xy 109.186601 -238.630646) (xy 109.219236 -238.593809) (xy 109.257357 -238.562684) (xy 109.299978 -238.538077)
			(xy 109.345994 -238.520625) (xy 109.394213 -238.510781) (xy 109.443388 -238.5088) (xy 109.492243 -238.514732)
			(xy 109.539514 -238.528424) (xy 109.583976 -238.549522) (xy 109.624479 -238.577478) (xy 109.659972 -238.61157)
			(xy 109.689537 -238.650914) (xy 109.712408 -238.694491) (xy 109.727992 -238.741172) (xy 109.735887 -238.789749)
			(xy 109.736382 -238.814356) (xy 110.065324 -238.814356) (xy 110.069284 -238.765302) (xy 110.081061 -238.717518)
			(xy 110.100352 -238.672242) (xy 110.126655 -238.630646) (xy 110.15929 -238.593809) (xy 110.197411 -238.562684)
			(xy 110.240032 -238.538077) (xy 110.286048 -238.520625) (xy 110.334267 -238.510781) (xy 110.383442 -238.5088)
			(xy 110.432297 -238.514732) (xy 110.479568 -238.528424) (xy 110.52403 -238.549522) (xy 110.564533 -238.577478)
			(xy 110.600026 -238.61157) (xy 110.629591 -238.650914) (xy 110.652462 -238.694491) (xy 110.668046 -238.741172)
			(xy 110.675941 -238.789749) (xy 110.676436 -238.814356) (xy 112.878882 -238.814356) (xy 112.882842 -238.765302)
			(xy 112.894619 -238.717518) (xy 112.91391 -238.672242) (xy 112.940213 -238.630646) (xy 112.972848 -238.593809)
			(xy 113.010969 -238.562684) (xy 113.05359 -238.538077) (xy 113.099606 -238.520625) (xy 113.147825 -238.510781)
			(xy 113.197 -238.5088) (xy 113.245855 -238.514732) (xy 113.293126 -238.528424) (xy 113.337588 -238.549522)
			(xy 113.378091 -238.577478) (xy 113.413584 -238.61157) (xy 113.443149 -238.650914) (xy 113.46602 -238.694491)
			(xy 113.481604 -238.741172) (xy 113.489499 -238.789749) (xy 113.489994 -238.814356) (xy 113.818936 -238.814356)
			(xy 113.822896 -238.765302) (xy 113.834673 -238.717518) (xy 113.853964 -238.672242) (xy 113.880267 -238.630646)
			(xy 113.912902 -238.593809) (xy 113.951023 -238.562684) (xy 113.993644 -238.538077) (xy 114.03966 -238.520625)
			(xy 114.087879 -238.510781) (xy 114.137054 -238.5088) (xy 114.185909 -238.514732) (xy 114.23318 -238.528424)
			(xy 114.277642 -238.549522) (xy 114.318145 -238.577478) (xy 114.353638 -238.61157) (xy 114.383203 -238.650914)
			(xy 114.406074 -238.694491) (xy 114.421658 -238.741172) (xy 114.429553 -238.789749) (xy 114.430048 -238.814356)
			(xy 114.75899 -238.814356) (xy 114.76295 -238.765302) (xy 114.774727 -238.717518) (xy 114.794018 -238.672242)
			(xy 114.820321 -238.630646) (xy 114.852956 -238.593809) (xy 114.891077 -238.562684) (xy 114.933698 -238.538077)
			(xy 114.979714 -238.520625) (xy 115.027933 -238.510781) (xy 115.077108 -238.5088) (xy 115.125963 -238.514732)
			(xy 115.173234 -238.528424) (xy 115.217696 -238.549522) (xy 115.258199 -238.577478) (xy 115.293692 -238.61157)
			(xy 115.323257 -238.650914) (xy 115.346128 -238.694491) (xy 115.361712 -238.741172) (xy 115.369607 -238.789749)
			(xy 115.370102 -238.814356) (xy 115.699044 -238.814356) (xy 115.703004 -238.765302) (xy 115.714781 -238.717518)
			(xy 115.734072 -238.672242) (xy 115.760375 -238.630646) (xy 115.79301 -238.593809) (xy 115.831131 -238.562684)
			(xy 115.873752 -238.538077) (xy 115.919768 -238.520625) (xy 115.967987 -238.510781) (xy 116.017162 -238.5088)
			(xy 116.066017 -238.514732) (xy 116.113288 -238.528424) (xy 116.15775 -238.549522) (xy 116.198253 -238.577478)
			(xy 116.233746 -238.61157) (xy 116.263311 -238.650914) (xy 116.286182 -238.694491) (xy 116.301766 -238.741172)
			(xy 116.309661 -238.789749) (xy 116.310156 -238.814356) (xy 118.518952 -238.814356) (xy 118.522912 -238.765302)
			(xy 118.534689 -238.717518) (xy 118.55398 -238.672242) (xy 118.580283 -238.630646) (xy 118.612918 -238.593809)
			(xy 118.651039 -238.562684) (xy 118.69366 -238.538077) (xy 118.739676 -238.520625) (xy 118.787895 -238.510781)
			(xy 118.83707 -238.5088) (xy 118.885925 -238.514732) (xy 118.933196 -238.528424) (xy 118.977658 -238.549522)
			(xy 119.018161 -238.577478) (xy 119.053654 -238.61157) (xy 119.083219 -238.650914) (xy 119.10609 -238.694491)
			(xy 119.121674 -238.741172) (xy 119.129569 -238.789749) (xy 119.130064 -238.814356) (xy 121.33886 -238.814356)
			(xy 121.34282 -238.765302) (xy 121.354597 -238.717518) (xy 121.373888 -238.672242) (xy 121.400191 -238.630646)
			(xy 121.432826 -238.593809) (xy 121.470947 -238.562684) (xy 121.513568 -238.538077) (xy 121.559584 -238.520625)
			(xy 121.607803 -238.510781) (xy 121.656978 -238.5088) (xy 121.705833 -238.514732) (xy 121.753104 -238.528424)
			(xy 121.797566 -238.549522) (xy 121.838069 -238.577478) (xy 121.873562 -238.61157) (xy 121.903127 -238.650914)
			(xy 121.925998 -238.694491) (xy 121.941582 -238.741172) (xy 121.949477 -238.789749) (xy 121.949972 -238.814356)
			(xy 124.159022 -238.814356) (xy 124.162982 -238.765302) (xy 124.174759 -238.717518) (xy 124.19405 -238.672242)
			(xy 124.220353 -238.630646) (xy 124.252988 -238.593809) (xy 124.291109 -238.562684) (xy 124.33373 -238.538077)
			(xy 124.379746 -238.520625) (xy 124.427965 -238.510781) (xy 124.47714 -238.5088) (xy 124.525995 -238.514732)
			(xy 124.573266 -238.528424) (xy 124.617728 -238.549522) (xy 124.658231 -238.577478) (xy 124.693724 -238.61157)
			(xy 124.723289 -238.650914) (xy 124.74616 -238.694491) (xy 124.761744 -238.741172) (xy 124.769639 -238.789749)
			(xy 124.770134 -238.814356) (xy 124.769639 -238.838963) (xy 124.761744 -238.88754) (xy 124.74616 -238.934221)
			(xy 124.723289 -238.977798) (xy 124.693724 -239.017142) (xy 124.658231 -239.051234) (xy 124.617728 -239.07919)
			(xy 124.573266 -239.100288) (xy 124.525995 -239.11398) (xy 124.47714 -239.119912) (xy 124.427965 -239.117931)
			(xy 124.379746 -239.108087) (xy 124.33373 -239.090635) (xy 124.291109 -239.066028) (xy 124.252988 -239.034903)
			(xy 124.220353 -238.998066) (xy 124.19405 -238.95647) (xy 124.174759 -238.911194) (xy 124.162982 -238.86341)
			(xy 124.159022 -238.814356) (xy 121.949972 -238.814356) (xy 121.949477 -238.838963) (xy 121.941582 -238.88754)
			(xy 121.925998 -238.934221) (xy 121.903127 -238.977798) (xy 121.873562 -239.017142) (xy 121.838069 -239.051234)
			(xy 121.797566 -239.07919) (xy 121.753104 -239.100288) (xy 121.705833 -239.11398) (xy 121.656978 -239.119912)
			(xy 121.607803 -239.117931) (xy 121.559584 -239.108087) (xy 121.513568 -239.090635) (xy 121.470947 -239.066028)
			(xy 121.432826 -239.034903) (xy 121.400191 -238.998066) (xy 121.373888 -238.95647) (xy 121.354597 -238.911194)
			(xy 121.34282 -238.86341) (xy 121.33886 -238.814356) (xy 119.130064 -238.814356) (xy 119.129569 -238.838963)
			(xy 119.121674 -238.88754) (xy 119.10609 -238.934221) (xy 119.083219 -238.977798) (xy 119.053654 -239.017142)
			(xy 119.018161 -239.051234) (xy 118.977658 -239.07919) (xy 118.933196 -239.100288) (xy 118.885925 -239.11398)
			(xy 118.83707 -239.119912) (xy 118.787895 -239.117931) (xy 118.739676 -239.108087) (xy 118.69366 -239.090635)
			(xy 118.651039 -239.066028) (xy 118.612918 -239.034903) (xy 118.580283 -238.998066) (xy 118.55398 -238.95647)
			(xy 118.534689 -238.911194) (xy 118.522912 -238.86341) (xy 118.518952 -238.814356) (xy 116.310156 -238.814356)
			(xy 116.309661 -238.838963) (xy 116.301766 -238.88754) (xy 116.286182 -238.934221) (xy 116.263311 -238.977798)
			(xy 116.233746 -239.017142) (xy 116.198253 -239.051234) (xy 116.15775 -239.07919) (xy 116.113288 -239.100288)
			(xy 116.066017 -239.11398) (xy 116.017162 -239.119912) (xy 115.967987 -239.117931) (xy 115.919768 -239.108087)
			(xy 115.873752 -239.090635) (xy 115.831131 -239.066028) (xy 115.79301 -239.034903) (xy 115.760375 -238.998066)
			(xy 115.734072 -238.95647) (xy 115.714781 -238.911194) (xy 115.703004 -238.86341) (xy 115.699044 -238.814356)
			(xy 115.370102 -238.814356) (xy 115.369607 -238.838963) (xy 115.361712 -238.88754) (xy 115.346128 -238.934221)
			(xy 115.323257 -238.977798) (xy 115.293692 -239.017142) (xy 115.258199 -239.051234) (xy 115.217696 -239.07919)
			(xy 115.173234 -239.100288) (xy 115.125963 -239.11398) (xy 115.077108 -239.119912) (xy 115.027933 -239.117931)
			(xy 114.979714 -239.108087) (xy 114.933698 -239.090635) (xy 114.891077 -239.066028) (xy 114.852956 -239.034903)
			(xy 114.820321 -238.998066) (xy 114.794018 -238.95647) (xy 114.774727 -238.911194) (xy 114.76295 -238.86341)
			(xy 114.75899 -238.814356) (xy 114.430048 -238.814356) (xy 114.429553 -238.838963) (xy 114.421658 -238.88754)
			(xy 114.406074 -238.934221) (xy 114.383203 -238.977798) (xy 114.353638 -239.017142) (xy 114.318145 -239.051234)
			(xy 114.277642 -239.07919) (xy 114.23318 -239.100288) (xy 114.185909 -239.11398) (xy 114.137054 -239.119912)
			(xy 114.087879 -239.117931) (xy 114.03966 -239.108087) (xy 113.993644 -239.090635) (xy 113.951023 -239.066028)
			(xy 113.912902 -239.034903) (xy 113.880267 -238.998066) (xy 113.853964 -238.95647) (xy 113.834673 -238.911194)
			(xy 113.822896 -238.86341) (xy 113.818936 -238.814356) (xy 113.489994 -238.814356) (xy 113.489499 -238.838963)
			(xy 113.481604 -238.88754) (xy 113.46602 -238.934221) (xy 113.443149 -238.977798) (xy 113.413584 -239.017142)
			(xy 113.378091 -239.051234) (xy 113.337588 -239.07919) (xy 113.293126 -239.100288) (xy 113.245855 -239.11398)
			(xy 113.197 -239.119912) (xy 113.147825 -239.117931) (xy 113.099606 -239.108087) (xy 113.05359 -239.090635)
			(xy 113.010969 -239.066028) (xy 112.972848 -239.034903) (xy 112.940213 -238.998066) (xy 112.91391 -238.95647)
			(xy 112.894619 -238.911194) (xy 112.882842 -238.86341) (xy 112.878882 -238.814356) (xy 110.676436 -238.814356)
			(xy 110.675941 -238.838963) (xy 110.668046 -238.88754) (xy 110.652462 -238.934221) (xy 110.629591 -238.977798)
			(xy 110.600026 -239.017142) (xy 110.564533 -239.051234) (xy 110.52403 -239.07919) (xy 110.479568 -239.100288)
			(xy 110.432297 -239.11398) (xy 110.383442 -239.119912) (xy 110.334267 -239.117931) (xy 110.286048 -239.108087)
			(xy 110.240032 -239.090635) (xy 110.197411 -239.066028) (xy 110.15929 -239.034903) (xy 110.126655 -238.998066)
			(xy 110.100352 -238.95647) (xy 110.081061 -238.911194) (xy 110.069284 -238.86341) (xy 110.065324 -238.814356)
			(xy 109.736382 -238.814356) (xy 109.735887 -238.838963) (xy 109.727992 -238.88754) (xy 109.712408 -238.934221)
			(xy 109.689537 -238.977798) (xy 109.659972 -239.017142) (xy 109.624479 -239.051234) (xy 109.583976 -239.07919)
			(xy 109.539514 -239.100288) (xy 109.492243 -239.11398) (xy 109.443388 -239.119912) (xy 109.394213 -239.117931)
			(xy 109.345994 -239.108087) (xy 109.299978 -239.090635) (xy 109.257357 -239.066028) (xy 109.219236 -239.034903)
			(xy 109.186601 -238.998066) (xy 109.160298 -238.95647) (xy 109.141007 -238.911194) (xy 109.12923 -238.86341)
			(xy 109.12527 -238.814356) (xy 108.796328 -238.814356) (xy 108.795833 -238.838963) (xy 108.787938 -238.88754)
			(xy 108.772354 -238.934221) (xy 108.749483 -238.977798) (xy 108.719918 -239.017142) (xy 108.684425 -239.051234)
			(xy 108.643922 -239.07919) (xy 108.59946 -239.100288) (xy 108.552189 -239.11398) (xy 108.503334 -239.119912)
			(xy 108.454159 -239.117931) (xy 108.40594 -239.108087) (xy 108.359924 -239.090635) (xy 108.317303 -239.066028)
			(xy 108.279182 -239.034903) (xy 108.246547 -238.998066) (xy 108.220244 -238.95647) (xy 108.200953 -238.911194)
			(xy 108.189176 -238.86341) (xy 108.185216 -238.814356) (xy 107.856274 -238.814356) (xy 107.855779 -238.838963)
			(xy 107.847884 -238.88754) (xy 107.8323 -238.934221) (xy 107.809429 -238.977798) (xy 107.779864 -239.017142)
			(xy 107.744371 -239.051234) (xy 107.703868 -239.07919) (xy 107.659406 -239.100288) (xy 107.612135 -239.11398)
			(xy 107.56328 -239.119912) (xy 107.514105 -239.117931) (xy 107.465886 -239.108087) (xy 107.41987 -239.090635)
			(xy 107.377249 -239.066028) (xy 107.339128 -239.034903) (xy 107.306493 -238.998066) (xy 107.28019 -238.95647)
			(xy 107.260899 -238.911194) (xy 107.249122 -238.86341) (xy 107.245162 -238.814356) (xy 105.036366 -238.814356)
			(xy 105.035871 -238.838963) (xy 105.027976 -238.88754) (xy 105.012392 -238.934221) (xy 104.989521 -238.977798)
			(xy 104.959956 -239.017142) (xy 104.924463 -239.051234) (xy 104.88396 -239.07919) (xy 104.839498 -239.100288)
			(xy 104.792227 -239.11398) (xy 104.743372 -239.119912) (xy 104.694197 -239.117931) (xy 104.645978 -239.108087)
			(xy 104.599962 -239.090635) (xy 104.557341 -239.066028) (xy 104.51922 -239.034903) (xy 104.486585 -238.998066)
			(xy 104.460282 -238.95647) (xy 104.440991 -238.911194) (xy 104.429214 -238.86341) (xy 104.425254 -238.814356)
			(xy 102.216458 -238.814356) (xy 102.215963 -238.838963) (xy 102.208068 -238.88754) (xy 102.192484 -238.934221)
			(xy 102.169613 -238.977798) (xy 102.140048 -239.017142) (xy 102.104555 -239.051234) (xy 102.064052 -239.07919)
			(xy 102.01959 -239.100288) (xy 101.972319 -239.11398) (xy 101.923464 -239.119912) (xy 101.874289 -239.117931)
			(xy 101.82607 -239.108087) (xy 101.780054 -239.090635) (xy 101.737433 -239.066028) (xy 101.699312 -239.034903)
			(xy 101.666677 -238.998066) (xy 101.640374 -238.95647) (xy 101.621083 -238.911194) (xy 101.609306 -238.86341)
			(xy 101.605346 -238.814356) (xy 99.396296 -238.814356) (xy 99.395801 -238.838963) (xy 99.387906 -238.88754)
			(xy 99.372322 -238.934221) (xy 99.349451 -238.977798) (xy 99.319886 -239.017142) (xy 99.284393 -239.051234)
			(xy 99.24389 -239.07919) (xy 99.199428 -239.100288) (xy 99.152157 -239.11398) (xy 99.103302 -239.119912)
			(xy 99.054127 -239.117931) (xy 99.005908 -239.108087) (xy 98.959892 -239.090635) (xy 98.917271 -239.066028)
			(xy 98.87915 -239.034903) (xy 98.846515 -238.998066) (xy 98.820212 -238.95647) (xy 98.800921 -238.911194)
			(xy 98.789144 -238.86341) (xy 98.785184 -238.814356) (xy 96.575919 -238.814356) (xy 96.575929 -238.838361)
			(xy 96.568386 -238.885954) (xy 96.553468 -238.931773) (xy 96.531543 -238.974683) (xy 96.503155 -239.01362)
			(xy 96.469008 -239.047619) (xy 96.429948 -239.075838) (xy 96.386943 -239.097576) (xy 96.341059 -239.112295)
			(xy 96.317308 -239.116362) (xy 96.3168 -239.116362) (xy 96.316292 -239.116616) (xy 96.307528 -239.118279)
			(xy 96.291909 -239.126869) (xy 96.285812 -239.13338) (xy 96.280224 -239.13973) (xy 96.273874 -239.156748)
			(xy 96.273874 -239.311688) (xy 96.274067 -239.317921) (xy 96.277158 -239.329997) (xy 96.27997 -239.335564)
			(xy 96.284542 -239.343438) (xy 96.295087 -239.362039) (xy 96.313654 -239.40056) (xy 96.321626 -239.4204)
			(xy 96.323658 -239.42548) (xy 96.326452 -239.4331) (xy 96.33712 -239.441482) (xy 96.342595 -239.445441)
			(xy 96.355084 -239.450585) (xy 96.361758 -239.451642) (xy 96.448372 -239.463072) (xy 96.45511 -239.463656)
			(xy 96.468494 -239.461736) (xy 96.474788 -239.459262) (xy 96.48698 -239.454182) (xy 96.490536 -239.44961)
			(xy 96.495616 -239.442752) (xy 96.51012 -239.423923) (xy 96.543974 -239.390567) (xy 96.582587 -239.362857)
			(xy 96.625026 -239.341463) (xy 96.670267 -239.3269) (xy 96.717217 -239.31952) (xy 96.74098 -239.319054)
			(xy 96.766242 -239.319545) (xy 96.816077 -239.327858) (xy 96.863864 -239.344261) (xy 96.9083 -239.368306)
			(xy 96.948171 -239.399336) (xy 96.982391 -239.436507) (xy 97.010026 -239.478803) (xy 97.030322 -239.525071)
			(xy 97.042726 -239.574049) (xy 97.046895 -239.624362) (xy 97.37523 -239.624362) (xy 97.37919 -239.575308)
			(xy 97.390967 -239.527524) (xy 97.410258 -239.482248) (xy 97.436561 -239.440652) (xy 97.469196 -239.403815)
			(xy 97.507317 -239.37269) (xy 97.549938 -239.348083) (xy 97.595954 -239.330631) (xy 97.644173 -239.320787)
			(xy 97.693348 -239.318806) (xy 97.742203 -239.324738) (xy 97.789474 -239.33843) (xy 97.833936 -239.359528)
			(xy 97.874439 -239.387484) (xy 97.909932 -239.421576) (xy 97.939497 -239.46092) (xy 97.962368 -239.504497)
			(xy 97.977952 -239.551178) (xy 97.985847 -239.599755) (xy 97.986342 -239.624362) (xy 98.315284 -239.624362)
			(xy 98.319244 -239.575308) (xy 98.331021 -239.527524) (xy 98.350312 -239.482248) (xy 98.376615 -239.440652)
			(xy 98.40925 -239.403815) (xy 98.447371 -239.37269) (xy 98.489992 -239.348083) (xy 98.536008 -239.330631)
			(xy 98.584227 -239.320787) (xy 98.633402 -239.318806) (xy 98.682257 -239.324738) (xy 98.729528 -239.33843)
			(xy 98.77399 -239.359528) (xy 98.814493 -239.387484) (xy 98.849986 -239.421576) (xy 98.879551 -239.46092)
			(xy 98.902422 -239.504497) (xy 98.918006 -239.551178) (xy 98.925901 -239.599755) (xy 98.926396 -239.624362)
			(xy 99.255338 -239.624362) (xy 99.259298 -239.575308) (xy 99.271075 -239.527524) (xy 99.290366 -239.482248)
			(xy 99.316669 -239.440652) (xy 99.349304 -239.403815) (xy 99.387425 -239.37269) (xy 99.430046 -239.348083)
			(xy 99.476062 -239.330631) (xy 99.524281 -239.320787) (xy 99.573456 -239.318806) (xy 99.622311 -239.324738)
			(xy 99.669582 -239.33843) (xy 99.714044 -239.359528) (xy 99.754547 -239.387484) (xy 99.79004 -239.421576)
			(xy 99.819605 -239.46092) (xy 99.842476 -239.504497) (xy 99.85806 -239.551178) (xy 99.865955 -239.599755)
			(xy 99.86645 -239.624362) (xy 100.195138 -239.624362) (xy 100.199098 -239.575308) (xy 100.210875 -239.527524)
			(xy 100.230166 -239.482248) (xy 100.256469 -239.440652) (xy 100.289104 -239.403815) (xy 100.327225 -239.37269)
			(xy 100.369846 -239.348083) (xy 100.415862 -239.330631) (xy 100.464081 -239.320787) (xy 100.513256 -239.318806)
			(xy 100.562111 -239.324738) (xy 100.609382 -239.33843) (xy 100.653844 -239.359528) (xy 100.694347 -239.387484)
			(xy 100.72984 -239.421576) (xy 100.759405 -239.46092) (xy 100.782276 -239.504497) (xy 100.79786 -239.551178)
			(xy 100.805755 -239.599755) (xy 100.80625 -239.624362) (xy 101.135192 -239.624362) (xy 101.139152 -239.575308)
			(xy 101.150929 -239.527524) (xy 101.17022 -239.482248) (xy 101.196523 -239.440652) (xy 101.229158 -239.403815)
			(xy 101.267279 -239.37269) (xy 101.3099 -239.348083) (xy 101.355916 -239.330631) (xy 101.404135 -239.320787)
			(xy 101.45331 -239.318806) (xy 101.502165 -239.324738) (xy 101.549436 -239.33843) (xy 101.593898 -239.359528)
			(xy 101.634401 -239.387484) (xy 101.669894 -239.421576) (xy 101.699459 -239.46092) (xy 101.72233 -239.504497)
			(xy 101.737914 -239.551178) (xy 101.745809 -239.599755) (xy 101.746304 -239.624362) (xy 102.075246 -239.624362)
			(xy 102.079206 -239.575308) (xy 102.090983 -239.527524) (xy 102.110274 -239.482248) (xy 102.136577 -239.440652)
			(xy 102.169212 -239.403815) (xy 102.207333 -239.37269) (xy 102.249954 -239.348083) (xy 102.29597 -239.330631)
			(xy 102.344189 -239.320787) (xy 102.393364 -239.318806) (xy 102.442219 -239.324738) (xy 102.48949 -239.33843)
			(xy 102.533952 -239.359528) (xy 102.574455 -239.387484) (xy 102.609948 -239.421576) (xy 102.639513 -239.46092)
			(xy 102.662384 -239.504497) (xy 102.677968 -239.551178) (xy 102.685863 -239.599755) (xy 102.686358 -239.624362)
			(xy 103.0153 -239.624362) (xy 103.01926 -239.575308) (xy 103.031037 -239.527524) (xy 103.050328 -239.482248)
			(xy 103.076631 -239.440652) (xy 103.109266 -239.403815) (xy 103.147387 -239.37269) (xy 103.190008 -239.348083)
			(xy 103.236024 -239.330631) (xy 103.284243 -239.320787) (xy 103.333418 -239.318806) (xy 103.382273 -239.324738)
			(xy 103.429544 -239.33843) (xy 103.474006 -239.359528) (xy 103.514509 -239.387484) (xy 103.550002 -239.421576)
			(xy 103.579567 -239.46092) (xy 103.602438 -239.504497) (xy 103.618022 -239.551178) (xy 103.625917 -239.599755)
			(xy 103.626412 -239.624362) (xy 103.955354 -239.624362) (xy 103.959314 -239.575308) (xy 103.971091 -239.527524)
			(xy 103.990382 -239.482248) (xy 104.016685 -239.440652) (xy 104.04932 -239.403815) (xy 104.087441 -239.37269)
			(xy 104.130062 -239.348083) (xy 104.176078 -239.330631) (xy 104.224297 -239.320787) (xy 104.273472 -239.318806)
			(xy 104.322327 -239.324738) (xy 104.369598 -239.33843) (xy 104.41406 -239.359528) (xy 104.454563 -239.387484)
			(xy 104.490056 -239.421576) (xy 104.519621 -239.46092) (xy 104.542492 -239.504497) (xy 104.558076 -239.551178)
			(xy 104.565971 -239.599755) (xy 104.566466 -239.624362) (xy 104.895154 -239.624362) (xy 104.899114 -239.575308)
			(xy 104.910891 -239.527524) (xy 104.930182 -239.482248) (xy 104.956485 -239.440652) (xy 104.98912 -239.403815)
			(xy 105.027241 -239.37269) (xy 105.069862 -239.348083) (xy 105.115878 -239.330631) (xy 105.164097 -239.320787)
			(xy 105.213272 -239.318806) (xy 105.262127 -239.324738) (xy 105.309398 -239.33843) (xy 105.35386 -239.359528)
			(xy 105.394363 -239.387484) (xy 105.429856 -239.421576) (xy 105.459421 -239.46092) (xy 105.482292 -239.504497)
			(xy 105.497876 -239.551178) (xy 105.505771 -239.599755) (xy 105.506266 -239.624362) (xy 105.835208 -239.624362)
			(xy 105.839168 -239.575308) (xy 105.850945 -239.527524) (xy 105.870236 -239.482248) (xy 105.896539 -239.440652)
			(xy 105.929174 -239.403815) (xy 105.967295 -239.37269) (xy 106.009916 -239.348083) (xy 106.055932 -239.330631)
			(xy 106.104151 -239.320787) (xy 106.153326 -239.318806) (xy 106.202181 -239.324738) (xy 106.249452 -239.33843)
			(xy 106.293914 -239.359528) (xy 106.334417 -239.387484) (xy 106.36991 -239.421576) (xy 106.399475 -239.46092)
			(xy 106.422346 -239.504497) (xy 106.43793 -239.551178) (xy 106.445825 -239.599755) (xy 106.44632 -239.624362)
			(xy 106.775262 -239.624362) (xy 106.779222 -239.575308) (xy 106.790999 -239.527524) (xy 106.81029 -239.482248)
			(xy 106.836593 -239.440652) (xy 106.869228 -239.403815) (xy 106.907349 -239.37269) (xy 106.94997 -239.348083)
			(xy 106.995986 -239.330631) (xy 107.044205 -239.320787) (xy 107.09338 -239.318806) (xy 107.142235 -239.324738)
			(xy 107.189506 -239.33843) (xy 107.233968 -239.359528) (xy 107.274471 -239.387484) (xy 107.309964 -239.421576)
			(xy 107.339529 -239.46092) (xy 107.3624 -239.504497) (xy 107.377984 -239.551178) (xy 107.385879 -239.599755)
			(xy 107.386374 -239.624362) (xy 107.715316 -239.624362) (xy 107.719276 -239.575308) (xy 107.731053 -239.527524)
			(xy 107.750344 -239.482248) (xy 107.776647 -239.440652) (xy 107.809282 -239.403815) (xy 107.847403 -239.37269)
			(xy 107.890024 -239.348083) (xy 107.93604 -239.330631) (xy 107.984259 -239.320787) (xy 108.033434 -239.318806)
			(xy 108.082289 -239.324738) (xy 108.12956 -239.33843) (xy 108.174022 -239.359528) (xy 108.214525 -239.387484)
			(xy 108.250018 -239.421576) (xy 108.279583 -239.46092) (xy 108.302454 -239.504497) (xy 108.318038 -239.551178)
			(xy 108.325933 -239.599755) (xy 108.326428 -239.624362) (xy 115.22889 -239.624362) (xy 115.23285 -239.575308)
			(xy 115.244627 -239.527524) (xy 115.263918 -239.482248) (xy 115.290221 -239.440652) (xy 115.322856 -239.403815)
			(xy 115.360977 -239.37269) (xy 115.403598 -239.348083) (xy 115.449614 -239.330631) (xy 115.497833 -239.320787)
			(xy 115.547008 -239.318806) (xy 115.595863 -239.324738) (xy 115.643134 -239.33843) (xy 115.687596 -239.359528)
			(xy 115.728099 -239.387484) (xy 115.763592 -239.421576) (xy 115.793157 -239.46092) (xy 115.816028 -239.504497)
			(xy 115.831612 -239.551178) (xy 115.839507 -239.599755) (xy 115.840002 -239.624362) (xy 116.168944 -239.624362)
			(xy 116.172904 -239.575308) (xy 116.184681 -239.527524) (xy 116.203972 -239.482248) (xy 116.230275 -239.440652)
			(xy 116.26291 -239.403815) (xy 116.301031 -239.37269) (xy 116.343652 -239.348083) (xy 116.389668 -239.330631)
			(xy 116.437887 -239.320787) (xy 116.487062 -239.318806) (xy 116.535917 -239.324738) (xy 116.583188 -239.33843)
			(xy 116.62765 -239.359528) (xy 116.668153 -239.387484) (xy 116.703646 -239.421576) (xy 116.733211 -239.46092)
			(xy 116.756082 -239.504497) (xy 116.771666 -239.551178) (xy 116.779561 -239.599755) (xy 116.780056 -239.624362)
			(xy 117.108998 -239.624362) (xy 117.112958 -239.575308) (xy 117.124735 -239.527524) (xy 117.144026 -239.482248)
			(xy 117.170329 -239.440652) (xy 117.202964 -239.403815) (xy 117.241085 -239.37269) (xy 117.283706 -239.348083)
			(xy 117.329722 -239.330631) (xy 117.377941 -239.320787) (xy 117.427116 -239.318806) (xy 117.475971 -239.324738)
			(xy 117.523242 -239.33843) (xy 117.567704 -239.359528) (xy 117.608207 -239.387484) (xy 117.6437 -239.421576)
			(xy 117.673265 -239.46092) (xy 117.696136 -239.504497) (xy 117.71172 -239.551178) (xy 117.719615 -239.599755)
			(xy 117.72011 -239.624362) (xy 118.049052 -239.624362) (xy 118.053012 -239.575308) (xy 118.064789 -239.527524)
			(xy 118.08408 -239.482248) (xy 118.110383 -239.440652) (xy 118.143018 -239.403815) (xy 118.181139 -239.37269)
			(xy 118.22376 -239.348083) (xy 118.269776 -239.330631) (xy 118.317995 -239.320787) (xy 118.36717 -239.318806)
			(xy 118.416025 -239.324738) (xy 118.463296 -239.33843) (xy 118.507758 -239.359528) (xy 118.548261 -239.387484)
			(xy 118.583754 -239.421576) (xy 118.613319 -239.46092) (xy 118.63619 -239.504497) (xy 118.651774 -239.551178)
			(xy 118.659669 -239.599755) (xy 118.660164 -239.624362) (xy 118.988852 -239.624362) (xy 118.992812 -239.575308)
			(xy 119.004589 -239.527524) (xy 119.02388 -239.482248) (xy 119.050183 -239.440652) (xy 119.082818 -239.403815)
			(xy 119.120939 -239.37269) (xy 119.16356 -239.348083) (xy 119.209576 -239.330631) (xy 119.257795 -239.320787)
			(xy 119.30697 -239.318806) (xy 119.355825 -239.324738) (xy 119.403096 -239.33843) (xy 119.447558 -239.359528)
			(xy 119.488061 -239.387484) (xy 119.523554 -239.421576) (xy 119.553119 -239.46092) (xy 119.57599 -239.504497)
			(xy 119.591574 -239.551178) (xy 119.599469 -239.599755) (xy 119.599964 -239.624362) (xy 119.928906 -239.624362)
			(xy 119.932866 -239.575308) (xy 119.944643 -239.527524) (xy 119.963934 -239.482248) (xy 119.990237 -239.440652)
			(xy 120.022872 -239.403815) (xy 120.060993 -239.37269) (xy 120.103614 -239.348083) (xy 120.14963 -239.330631)
			(xy 120.197849 -239.320787) (xy 120.247024 -239.318806) (xy 120.295879 -239.324738) (xy 120.34315 -239.33843)
			(xy 120.387612 -239.359528) (xy 120.428115 -239.387484) (xy 120.463608 -239.421576) (xy 120.493173 -239.46092)
			(xy 120.516044 -239.504497) (xy 120.531628 -239.551178) (xy 120.539523 -239.599755) (xy 120.540018 -239.624362)
			(xy 120.86896 -239.624362) (xy 120.87292 -239.575308) (xy 120.884697 -239.527524) (xy 120.903988 -239.482248)
			(xy 120.930291 -239.440652) (xy 120.962926 -239.403815) (xy 121.001047 -239.37269) (xy 121.043668 -239.348083)
			(xy 121.089684 -239.330631) (xy 121.137903 -239.320787) (xy 121.187078 -239.318806) (xy 121.235933 -239.324738)
			(xy 121.283204 -239.33843) (xy 121.327666 -239.359528) (xy 121.368169 -239.387484) (xy 121.403662 -239.421576)
			(xy 121.433227 -239.46092) (xy 121.456098 -239.504497) (xy 121.471682 -239.551178) (xy 121.479577 -239.599755)
			(xy 121.480072 -239.624362) (xy 121.809014 -239.624362) (xy 121.812974 -239.575308) (xy 121.824751 -239.527524)
			(xy 121.844042 -239.482248) (xy 121.870345 -239.440652) (xy 121.90298 -239.403815) (xy 121.941101 -239.37269)
			(xy 121.983722 -239.348083) (xy 122.029738 -239.330631) (xy 122.077957 -239.320787) (xy 122.127132 -239.318806)
			(xy 122.175987 -239.324738) (xy 122.223258 -239.33843) (xy 122.26772 -239.359528) (xy 122.308223 -239.387484)
			(xy 122.343716 -239.421576) (xy 122.373281 -239.46092) (xy 122.396152 -239.504497) (xy 122.411736 -239.551178)
			(xy 122.419631 -239.599755) (xy 122.420126 -239.624362) (xy 122.748814 -239.624362) (xy 122.752774 -239.575308)
			(xy 122.764551 -239.527524) (xy 122.783842 -239.482248) (xy 122.810145 -239.440652) (xy 122.84278 -239.403815)
			(xy 122.880901 -239.37269) (xy 122.923522 -239.348083) (xy 122.969538 -239.330631) (xy 123.017757 -239.320787)
			(xy 123.066932 -239.318806) (xy 123.115787 -239.324738) (xy 123.163058 -239.33843) (xy 123.20752 -239.359528)
			(xy 123.248023 -239.387484) (xy 123.283516 -239.421576) (xy 123.313081 -239.46092) (xy 123.335952 -239.504497)
			(xy 123.351536 -239.551178) (xy 123.359431 -239.599755) (xy 123.359926 -239.624362) (xy 123.688868 -239.624362)
			(xy 123.692828 -239.575308) (xy 123.704605 -239.527524) (xy 123.723896 -239.482248) (xy 123.750199 -239.440652)
			(xy 123.782834 -239.403815) (xy 123.820955 -239.37269) (xy 123.863576 -239.348083) (xy 123.909592 -239.330631)
			(xy 123.957811 -239.320787) (xy 124.006986 -239.318806) (xy 124.055841 -239.324738) (xy 124.103112 -239.33843)
			(xy 124.147574 -239.359528) (xy 124.188077 -239.387484) (xy 124.22357 -239.421576) (xy 124.253135 -239.46092)
			(xy 124.276006 -239.504497) (xy 124.29159 -239.551178) (xy 124.299485 -239.599755) (xy 124.29998 -239.624362)
			(xy 124.628922 -239.624362) (xy 124.632882 -239.575308) (xy 124.644659 -239.527524) (xy 124.66395 -239.482248)
			(xy 124.690253 -239.440652) (xy 124.722888 -239.403815) (xy 124.761009 -239.37269) (xy 124.80363 -239.348083)
			(xy 124.849646 -239.330631) (xy 124.897865 -239.320787) (xy 124.94704 -239.318806) (xy 124.995895 -239.324738)
			(xy 125.043166 -239.33843) (xy 125.087628 -239.359528) (xy 125.128131 -239.387484) (xy 125.163624 -239.421576)
			(xy 125.193189 -239.46092) (xy 125.21606 -239.504497) (xy 125.231644 -239.551178) (xy 125.239539 -239.599755)
			(xy 125.240034 -239.624362) (xy 125.568976 -239.624362) (xy 125.572936 -239.575308) (xy 125.584713 -239.527524)
			(xy 125.604004 -239.482248) (xy 125.630307 -239.440652) (xy 125.662942 -239.403815) (xy 125.701063 -239.37269)
			(xy 125.743684 -239.348083) (xy 125.7897 -239.330631) (xy 125.837919 -239.320787) (xy 125.887094 -239.318806)
			(xy 125.935949 -239.324738) (xy 125.98322 -239.33843) (xy 126.027682 -239.359528) (xy 126.068185 -239.387484)
			(xy 126.103678 -239.421576) (xy 126.133243 -239.46092) (xy 126.156114 -239.504497) (xy 126.171698 -239.551178)
			(xy 126.179593 -239.599755) (xy 126.180088 -239.624362) (xy 126.179593 -239.648969) (xy 126.171698 -239.697546)
			(xy 126.156114 -239.744227) (xy 126.133243 -239.787804) (xy 126.103678 -239.827148) (xy 126.068185 -239.86124)
			(xy 126.027682 -239.889196) (xy 125.98322 -239.910294) (xy 125.935949 -239.923986) (xy 125.887094 -239.929918)
			(xy 125.837919 -239.927937) (xy 125.7897 -239.918093) (xy 125.743684 -239.900641) (xy 125.701063 -239.876034)
			(xy 125.662942 -239.844909) (xy 125.630307 -239.808072) (xy 125.604004 -239.766476) (xy 125.584713 -239.7212)
			(xy 125.572936 -239.673416) (xy 125.568976 -239.624362) (xy 125.240034 -239.624362) (xy 125.239539 -239.648969)
			(xy 125.231644 -239.697546) (xy 125.21606 -239.744227) (xy 125.193189 -239.787804) (xy 125.163624 -239.827148)
			(xy 125.128131 -239.86124) (xy 125.087628 -239.889196) (xy 125.043166 -239.910294) (xy 124.995895 -239.923986)
			(xy 124.94704 -239.929918) (xy 124.897865 -239.927937) (xy 124.849646 -239.918093) (xy 124.80363 -239.900641)
			(xy 124.761009 -239.876034) (xy 124.722888 -239.844909) (xy 124.690253 -239.808072) (xy 124.66395 -239.766476)
			(xy 124.644659 -239.7212) (xy 124.632882 -239.673416) (xy 124.628922 -239.624362) (xy 124.29998 -239.624362)
			(xy 124.299485 -239.648969) (xy 124.29159 -239.697546) (xy 124.276006 -239.744227) (xy 124.253135 -239.787804)
			(xy 124.22357 -239.827148) (xy 124.188077 -239.86124) (xy 124.147574 -239.889196) (xy 124.103112 -239.910294)
			(xy 124.055841 -239.923986) (xy 124.006986 -239.929918) (xy 123.957811 -239.927937) (xy 123.909592 -239.918093)
			(xy 123.863576 -239.900641) (xy 123.820955 -239.876034) (xy 123.782834 -239.844909) (xy 123.750199 -239.808072)
			(xy 123.723896 -239.766476) (xy 123.704605 -239.7212) (xy 123.692828 -239.673416) (xy 123.688868 -239.624362)
			(xy 123.359926 -239.624362) (xy 123.359431 -239.648969) (xy 123.351536 -239.697546) (xy 123.335952 -239.744227)
			(xy 123.313081 -239.787804) (xy 123.283516 -239.827148) (xy 123.248023 -239.86124) (xy 123.20752 -239.889196)
			(xy 123.163058 -239.910294) (xy 123.115787 -239.923986) (xy 123.066932 -239.929918) (xy 123.017757 -239.927937)
			(xy 122.969538 -239.918093) (xy 122.923522 -239.900641) (xy 122.880901 -239.876034) (xy 122.84278 -239.844909)
			(xy 122.810145 -239.808072) (xy 122.783842 -239.766476) (xy 122.764551 -239.7212) (xy 122.752774 -239.673416)
			(xy 122.748814 -239.624362) (xy 122.420126 -239.624362) (xy 122.419631 -239.648969) (xy 122.411736 -239.697546)
			(xy 122.396152 -239.744227) (xy 122.373281 -239.787804) (xy 122.343716 -239.827148) (xy 122.308223 -239.86124)
			(xy 122.26772 -239.889196) (xy 122.223258 -239.910294) (xy 122.175987 -239.923986) (xy 122.127132 -239.929918)
			(xy 122.077957 -239.927937) (xy 122.029738 -239.918093) (xy 121.983722 -239.900641) (xy 121.941101 -239.876034)
			(xy 121.90298 -239.844909) (xy 121.870345 -239.808072) (xy 121.844042 -239.766476) (xy 121.824751 -239.7212)
			(xy 121.812974 -239.673416) (xy 121.809014 -239.624362) (xy 121.480072 -239.624362) (xy 121.479577 -239.648969)
			(xy 121.471682 -239.697546) (xy 121.456098 -239.744227) (xy 121.433227 -239.787804) (xy 121.403662 -239.827148)
			(xy 121.368169 -239.86124) (xy 121.327666 -239.889196) (xy 121.283204 -239.910294) (xy 121.235933 -239.923986)
			(xy 121.187078 -239.929918) (xy 121.137903 -239.927937) (xy 121.089684 -239.918093) (xy 121.043668 -239.900641)
			(xy 121.001047 -239.876034) (xy 120.962926 -239.844909) (xy 120.930291 -239.808072) (xy 120.903988 -239.766476)
			(xy 120.884697 -239.7212) (xy 120.87292 -239.673416) (xy 120.86896 -239.624362) (xy 120.540018 -239.624362)
			(xy 120.539523 -239.648969) (xy 120.531628 -239.697546) (xy 120.516044 -239.744227) (xy 120.493173 -239.787804)
			(xy 120.463608 -239.827148) (xy 120.428115 -239.86124) (xy 120.387612 -239.889196) (xy 120.34315 -239.910294)
			(xy 120.295879 -239.923986) (xy 120.247024 -239.929918) (xy 120.197849 -239.927937) (xy 120.14963 -239.918093)
			(xy 120.103614 -239.900641) (xy 120.060993 -239.876034) (xy 120.022872 -239.844909) (xy 119.990237 -239.808072)
			(xy 119.963934 -239.766476) (xy 119.944643 -239.7212) (xy 119.932866 -239.673416) (xy 119.928906 -239.624362)
			(xy 119.599964 -239.624362) (xy 119.599469 -239.648969) (xy 119.591574 -239.697546) (xy 119.57599 -239.744227)
			(xy 119.553119 -239.787804) (xy 119.523554 -239.827148) (xy 119.488061 -239.86124) (xy 119.447558 -239.889196)
			(xy 119.403096 -239.910294) (xy 119.355825 -239.923986) (xy 119.30697 -239.929918) (xy 119.257795 -239.927937)
			(xy 119.209576 -239.918093) (xy 119.16356 -239.900641) (xy 119.120939 -239.876034) (xy 119.082818 -239.844909)
			(xy 119.050183 -239.808072) (xy 119.02388 -239.766476) (xy 119.004589 -239.7212) (xy 118.992812 -239.673416)
			(xy 118.988852 -239.624362) (xy 118.660164 -239.624362) (xy 118.659669 -239.648969) (xy 118.651774 -239.697546)
			(xy 118.63619 -239.744227) (xy 118.613319 -239.787804) (xy 118.583754 -239.827148) (xy 118.548261 -239.86124)
			(xy 118.507758 -239.889196) (xy 118.463296 -239.910294) (xy 118.416025 -239.923986) (xy 118.36717 -239.929918)
			(xy 118.317995 -239.927937) (xy 118.269776 -239.918093) (xy 118.22376 -239.900641) (xy 118.181139 -239.876034)
			(xy 118.143018 -239.844909) (xy 118.110383 -239.808072) (xy 118.08408 -239.766476) (xy 118.064789 -239.7212)
			(xy 118.053012 -239.673416) (xy 118.049052 -239.624362) (xy 117.72011 -239.624362) (xy 117.719615 -239.648969)
			(xy 117.71172 -239.697546) (xy 117.696136 -239.744227) (xy 117.673265 -239.787804) (xy 117.6437 -239.827148)
			(xy 117.608207 -239.86124) (xy 117.567704 -239.889196) (xy 117.523242 -239.910294) (xy 117.475971 -239.923986)
			(xy 117.427116 -239.929918) (xy 117.377941 -239.927937) (xy 117.329722 -239.918093) (xy 117.283706 -239.900641)
			(xy 117.241085 -239.876034) (xy 117.202964 -239.844909) (xy 117.170329 -239.808072) (xy 117.144026 -239.766476)
			(xy 117.124735 -239.7212) (xy 117.112958 -239.673416) (xy 117.108998 -239.624362) (xy 116.780056 -239.624362)
			(xy 116.779561 -239.648969) (xy 116.771666 -239.697546) (xy 116.756082 -239.744227) (xy 116.733211 -239.787804)
			(xy 116.703646 -239.827148) (xy 116.668153 -239.86124) (xy 116.62765 -239.889196) (xy 116.583188 -239.910294)
			(xy 116.535917 -239.923986) (xy 116.487062 -239.929918) (xy 116.437887 -239.927937) (xy 116.389668 -239.918093)
			(xy 116.343652 -239.900641) (xy 116.301031 -239.876034) (xy 116.26291 -239.844909) (xy 116.230275 -239.808072)
			(xy 116.203972 -239.766476) (xy 116.184681 -239.7212) (xy 116.172904 -239.673416) (xy 116.168944 -239.624362)
			(xy 115.840002 -239.624362) (xy 115.839507 -239.648969) (xy 115.831612 -239.697546) (xy 115.816028 -239.744227)
			(xy 115.793157 -239.787804) (xy 115.763592 -239.827148) (xy 115.728099 -239.86124) (xy 115.687596 -239.889196)
			(xy 115.643134 -239.910294) (xy 115.595863 -239.923986) (xy 115.547008 -239.929918) (xy 115.497833 -239.927937)
			(xy 115.449614 -239.918093) (xy 115.403598 -239.900641) (xy 115.360977 -239.876034) (xy 115.322856 -239.844909)
			(xy 115.290221 -239.808072) (xy 115.263918 -239.766476) (xy 115.244627 -239.7212) (xy 115.23285 -239.673416)
			(xy 115.22889 -239.624362) (xy 108.326428 -239.624362) (xy 108.325933 -239.648969) (xy 108.318038 -239.697546)
			(xy 108.302454 -239.744227) (xy 108.279583 -239.787804) (xy 108.250018 -239.827148) (xy 108.214525 -239.86124)
			(xy 108.174022 -239.889196) (xy 108.12956 -239.910294) (xy 108.082289 -239.923986) (xy 108.033434 -239.929918)
			(xy 107.984259 -239.927937) (xy 107.93604 -239.918093) (xy 107.890024 -239.900641) (xy 107.847403 -239.876034)
			(xy 107.809282 -239.844909) (xy 107.776647 -239.808072) (xy 107.750344 -239.766476) (xy 107.731053 -239.7212)
			(xy 107.719276 -239.673416) (xy 107.715316 -239.624362) (xy 107.386374 -239.624362) (xy 107.385879 -239.648969)
			(xy 107.377984 -239.697546) (xy 107.3624 -239.744227) (xy 107.339529 -239.787804) (xy 107.309964 -239.827148)
			(xy 107.274471 -239.86124) (xy 107.233968 -239.889196) (xy 107.189506 -239.910294) (xy 107.142235 -239.923986)
			(xy 107.09338 -239.929918) (xy 107.044205 -239.927937) (xy 106.995986 -239.918093) (xy 106.94997 -239.900641)
			(xy 106.907349 -239.876034) (xy 106.869228 -239.844909) (xy 106.836593 -239.808072) (xy 106.81029 -239.766476)
			(xy 106.790999 -239.7212) (xy 106.779222 -239.673416) (xy 106.775262 -239.624362) (xy 106.44632 -239.624362)
			(xy 106.445825 -239.648969) (xy 106.43793 -239.697546) (xy 106.422346 -239.744227) (xy 106.399475 -239.787804)
			(xy 106.36991 -239.827148) (xy 106.334417 -239.86124) (xy 106.293914 -239.889196) (xy 106.249452 -239.910294)
			(xy 106.202181 -239.923986) (xy 106.153326 -239.929918) (xy 106.104151 -239.927937) (xy 106.055932 -239.918093)
			(xy 106.009916 -239.900641) (xy 105.967295 -239.876034) (xy 105.929174 -239.844909) (xy 105.896539 -239.808072)
			(xy 105.870236 -239.766476) (xy 105.850945 -239.7212) (xy 105.839168 -239.673416) (xy 105.835208 -239.624362)
			(xy 105.506266 -239.624362) (xy 105.505771 -239.648969) (xy 105.497876 -239.697546) (xy 105.482292 -239.744227)
			(xy 105.459421 -239.787804) (xy 105.429856 -239.827148) (xy 105.394363 -239.86124) (xy 105.35386 -239.889196)
			(xy 105.309398 -239.910294) (xy 105.262127 -239.923986) (xy 105.213272 -239.929918) (xy 105.164097 -239.927937)
			(xy 105.115878 -239.918093) (xy 105.069862 -239.900641) (xy 105.027241 -239.876034) (xy 104.98912 -239.844909)
			(xy 104.956485 -239.808072) (xy 104.930182 -239.766476) (xy 104.910891 -239.7212) (xy 104.899114 -239.673416)
			(xy 104.895154 -239.624362) (xy 104.566466 -239.624362) (xy 104.565971 -239.648969) (xy 104.558076 -239.697546)
			(xy 104.542492 -239.744227) (xy 104.519621 -239.787804) (xy 104.490056 -239.827148) (xy 104.454563 -239.86124)
			(xy 104.41406 -239.889196) (xy 104.369598 -239.910294) (xy 104.322327 -239.923986) (xy 104.273472 -239.929918)
			(xy 104.224297 -239.927937) (xy 104.176078 -239.918093) (xy 104.130062 -239.900641) (xy 104.087441 -239.876034)
			(xy 104.04932 -239.844909) (xy 104.016685 -239.808072) (xy 103.990382 -239.766476) (xy 103.971091 -239.7212)
			(xy 103.959314 -239.673416) (xy 103.955354 -239.624362) (xy 103.626412 -239.624362) (xy 103.625917 -239.648969)
			(xy 103.618022 -239.697546) (xy 103.602438 -239.744227) (xy 103.579567 -239.787804) (xy 103.550002 -239.827148)
			(xy 103.514509 -239.86124) (xy 103.474006 -239.889196) (xy 103.429544 -239.910294) (xy 103.382273 -239.923986)
			(xy 103.333418 -239.929918) (xy 103.284243 -239.927937) (xy 103.236024 -239.918093) (xy 103.190008 -239.900641)
			(xy 103.147387 -239.876034) (xy 103.109266 -239.844909) (xy 103.076631 -239.808072) (xy 103.050328 -239.766476)
			(xy 103.031037 -239.7212) (xy 103.01926 -239.673416) (xy 103.0153 -239.624362) (xy 102.686358 -239.624362)
			(xy 102.685863 -239.648969) (xy 102.677968 -239.697546) (xy 102.662384 -239.744227) (xy 102.639513 -239.787804)
			(xy 102.609948 -239.827148) (xy 102.574455 -239.86124) (xy 102.533952 -239.889196) (xy 102.48949 -239.910294)
			(xy 102.442219 -239.923986) (xy 102.393364 -239.929918) (xy 102.344189 -239.927937) (xy 102.29597 -239.918093)
			(xy 102.249954 -239.900641) (xy 102.207333 -239.876034) (xy 102.169212 -239.844909) (xy 102.136577 -239.808072)
			(xy 102.110274 -239.766476) (xy 102.090983 -239.7212) (xy 102.079206 -239.673416) (xy 102.075246 -239.624362)
			(xy 101.746304 -239.624362) (xy 101.745809 -239.648969) (xy 101.737914 -239.697546) (xy 101.72233 -239.744227)
			(xy 101.699459 -239.787804) (xy 101.669894 -239.827148) (xy 101.634401 -239.86124) (xy 101.593898 -239.889196)
			(xy 101.549436 -239.910294) (xy 101.502165 -239.923986) (xy 101.45331 -239.929918) (xy 101.404135 -239.927937)
			(xy 101.355916 -239.918093) (xy 101.3099 -239.900641) (xy 101.267279 -239.876034) (xy 101.229158 -239.844909)
			(xy 101.196523 -239.808072) (xy 101.17022 -239.766476) (xy 101.150929 -239.7212) (xy 101.139152 -239.673416)
			(xy 101.135192 -239.624362) (xy 100.80625 -239.624362) (xy 100.805755 -239.648969) (xy 100.79786 -239.697546)
			(xy 100.782276 -239.744227) (xy 100.759405 -239.787804) (xy 100.72984 -239.827148) (xy 100.694347 -239.86124)
			(xy 100.653844 -239.889196) (xy 100.609382 -239.910294) (xy 100.562111 -239.923986) (xy 100.513256 -239.929918)
			(xy 100.464081 -239.927937) (xy 100.415862 -239.918093) (xy 100.369846 -239.900641) (xy 100.327225 -239.876034)
			(xy 100.289104 -239.844909) (xy 100.256469 -239.808072) (xy 100.230166 -239.766476) (xy 100.210875 -239.7212)
			(xy 100.199098 -239.673416) (xy 100.195138 -239.624362) (xy 99.86645 -239.624362) (xy 99.865955 -239.648969)
			(xy 99.85806 -239.697546) (xy 99.842476 -239.744227) (xy 99.819605 -239.787804) (xy 99.79004 -239.827148)
			(xy 99.754547 -239.86124) (xy 99.714044 -239.889196) (xy 99.669582 -239.910294) (xy 99.622311 -239.923986)
			(xy 99.573456 -239.929918) (xy 99.524281 -239.927937) (xy 99.476062 -239.918093) (xy 99.430046 -239.900641)
			(xy 99.387425 -239.876034) (xy 99.349304 -239.844909) (xy 99.316669 -239.808072) (xy 99.290366 -239.766476)
			(xy 99.271075 -239.7212) (xy 99.259298 -239.673416) (xy 99.255338 -239.624362) (xy 98.926396 -239.624362)
			(xy 98.925901 -239.648969) (xy 98.918006 -239.697546) (xy 98.902422 -239.744227) (xy 98.879551 -239.787804)
			(xy 98.849986 -239.827148) (xy 98.814493 -239.86124) (xy 98.77399 -239.889196) (xy 98.729528 -239.910294)
			(xy 98.682257 -239.923986) (xy 98.633402 -239.929918) (xy 98.584227 -239.927937) (xy 98.536008 -239.918093)
			(xy 98.489992 -239.900641) (xy 98.447371 -239.876034) (xy 98.40925 -239.844909) (xy 98.376615 -239.808072)
			(xy 98.350312 -239.766476) (xy 98.331021 -239.7212) (xy 98.319244 -239.673416) (xy 98.315284 -239.624362)
			(xy 97.986342 -239.624362) (xy 97.985847 -239.648969) (xy 97.977952 -239.697546) (xy 97.962368 -239.744227)
			(xy 97.939497 -239.787804) (xy 97.909932 -239.827148) (xy 97.874439 -239.86124) (xy 97.833936 -239.889196)
			(xy 97.789474 -239.910294) (xy 97.742203 -239.923986) (xy 97.693348 -239.929918) (xy 97.644173 -239.927937)
			(xy 97.595954 -239.918093) (xy 97.549938 -239.900641) (xy 97.507317 -239.876034) (xy 97.469196 -239.844909)
			(xy 97.436561 -239.808072) (xy 97.410258 -239.766476) (xy 97.390967 -239.7212) (xy 97.37919 -239.673416)
			(xy 97.37523 -239.624362) (xy 97.046895 -239.624362) (xy 97.046898 -239.6244) (xy 97.042726 -239.674751)
			(xy 97.030322 -239.723729) (xy 97.010026 -239.769997) (xy 96.982391 -239.812293) (xy 96.948171 -239.849464)
			(xy 96.9083 -239.880494) (xy 96.863864 -239.904539) (xy 96.816077 -239.920942) (xy 96.766242 -239.929255)
			(xy 96.74098 -239.92967) (xy 96.717214 -239.929222) (xy 96.670254 -239.921862) (xy 96.625005 -239.907308)
			(xy 96.58256 -239.885912) (xy 96.543947 -239.858192) (xy 96.510101 -239.824819) (xy 96.495616 -239.805972)
			(xy 96.490536 -239.799114) (xy 96.48698 -239.794542) (xy 96.474788 -239.789462) (xy 96.468505 -239.786938)
			(xy 96.455111 -239.784996) (xy 96.448372 -239.785652) (xy 96.361758 -239.797082) (xy 96.355083 -239.798133)
			(xy 96.342591 -239.803275) (xy 96.33712 -239.807242) (xy 96.326452 -239.815624) (xy 96.323658 -239.823244)
			(xy 96.321626 -239.828324) (xy 96.308164 -239.859566) (xy 96.302017 -239.872691) (xy 96.288549 -239.898359)
			(xy 96.28124 -239.910874) (xy 96.280986 -239.911128) (xy 96.27743 -239.917224) (xy 96.275652 -239.92332)
			(xy 96.273874 -239.936782) (xy 96.273874 -240.082578) (xy 96.27425 -240.091682) (xy 96.28063 -240.108735)
			(xy 96.28632 -240.115852) (xy 96.291908 -240.122202) (xy 96.307402 -240.130838) (xy 96.317054 -240.132362)
			(xy 96.3408 -240.136457) (xy 96.386695 -240.151136) (xy 96.429717 -240.172836) (xy 96.4688 -240.201019)
			(xy 96.502975 -240.234988) (xy 96.531395 -240.273899) (xy 96.553356 -240.316788) (xy 96.568313 -240.362593)
			(xy 96.575896 -240.410177) (xy 96.575907 -240.434368) (xy 96.90533 -240.434368) (xy 96.90929 -240.385314)
			(xy 96.921067 -240.33753) (xy 96.940358 -240.292254) (xy 96.966661 -240.250658) (xy 96.999296 -240.213821)
			(xy 97.037417 -240.182696) (xy 97.080038 -240.158089) (xy 97.126054 -240.140637) (xy 97.174273 -240.130793)
			(xy 97.223448 -240.128812) (xy 97.272303 -240.134744) (xy 97.319574 -240.148436) (xy 97.364036 -240.169534)
			(xy 97.404539 -240.19749) (xy 97.440032 -240.231582) (xy 97.469597 -240.270926) (xy 97.492468 -240.314503)
			(xy 97.508052 -240.361184) (xy 97.515947 -240.409761) (xy 97.516442 -240.434368) (xy 97.84513 -240.434368)
			(xy 97.84909 -240.385314) (xy 97.860867 -240.33753) (xy 97.880158 -240.292254) (xy 97.906461 -240.250658)
			(xy 97.939096 -240.213821) (xy 97.977217 -240.182696) (xy 98.019838 -240.158089) (xy 98.065854 -240.140637)
			(xy 98.114073 -240.130793) (xy 98.163248 -240.128812) (xy 98.212103 -240.134744) (xy 98.259374 -240.148436)
			(xy 98.303836 -240.169534) (xy 98.344339 -240.19749) (xy 98.379832 -240.231582) (xy 98.409397 -240.270926)
			(xy 98.432268 -240.314503) (xy 98.447852 -240.361184) (xy 98.455747 -240.409761) (xy 98.456242 -240.434368)
			(xy 98.785184 -240.434368) (xy 98.789144 -240.385314) (xy 98.800921 -240.33753) (xy 98.820212 -240.292254)
			(xy 98.846515 -240.250658) (xy 98.87915 -240.213821) (xy 98.917271 -240.182696) (xy 98.959892 -240.158089)
			(xy 99.005908 -240.140637) (xy 99.054127 -240.130793) (xy 99.103302 -240.128812) (xy 99.152157 -240.134744)
			(xy 99.199428 -240.148436) (xy 99.24389 -240.169534) (xy 99.284393 -240.19749) (xy 99.319886 -240.231582)
			(xy 99.349451 -240.270926) (xy 99.372322 -240.314503) (xy 99.387906 -240.361184) (xy 99.395801 -240.409761)
			(xy 99.396296 -240.434368) (xy 99.725238 -240.434368) (xy 99.729198 -240.385314) (xy 99.740975 -240.33753)
			(xy 99.760266 -240.292254) (xy 99.786569 -240.250658) (xy 99.819204 -240.213821) (xy 99.857325 -240.182696)
			(xy 99.899946 -240.158089) (xy 99.945962 -240.140637) (xy 99.994181 -240.130793) (xy 100.043356 -240.128812)
			(xy 100.092211 -240.134744) (xy 100.139482 -240.148436) (xy 100.183944 -240.169534) (xy 100.224447 -240.19749)
			(xy 100.25994 -240.231582) (xy 100.289505 -240.270926) (xy 100.312376 -240.314503) (xy 100.32796 -240.361184)
			(xy 100.335855 -240.409761) (xy 100.33635 -240.434368) (xy 100.665292 -240.434368) (xy 100.669252 -240.385314)
			(xy 100.681029 -240.33753) (xy 100.70032 -240.292254) (xy 100.726623 -240.250658) (xy 100.759258 -240.213821)
			(xy 100.797379 -240.182696) (xy 100.84 -240.158089) (xy 100.886016 -240.140637) (xy 100.934235 -240.130793)
			(xy 100.98341 -240.128812) (xy 101.032265 -240.134744) (xy 101.079536 -240.148436) (xy 101.123998 -240.169534)
			(xy 101.164501 -240.19749) (xy 101.199994 -240.231582) (xy 101.229559 -240.270926) (xy 101.25243 -240.314503)
			(xy 101.268014 -240.361184) (xy 101.275909 -240.409761) (xy 101.276404 -240.434368) (xy 101.605346 -240.434368)
			(xy 101.609306 -240.385314) (xy 101.621083 -240.33753) (xy 101.640374 -240.292254) (xy 101.666677 -240.250658)
			(xy 101.699312 -240.213821) (xy 101.737433 -240.182696) (xy 101.780054 -240.158089) (xy 101.82607 -240.140637)
			(xy 101.874289 -240.130793) (xy 101.923464 -240.128812) (xy 101.972319 -240.134744) (xy 102.01959 -240.148436)
			(xy 102.064052 -240.169534) (xy 102.104555 -240.19749) (xy 102.140048 -240.231582) (xy 102.169613 -240.270926)
			(xy 102.192484 -240.314503) (xy 102.208068 -240.361184) (xy 102.215963 -240.409761) (xy 102.216458 -240.434368)
			(xy 102.545146 -240.434368) (xy 102.549106 -240.385314) (xy 102.560883 -240.33753) (xy 102.580174 -240.292254)
			(xy 102.606477 -240.250658) (xy 102.639112 -240.213821) (xy 102.677233 -240.182696) (xy 102.719854 -240.158089)
			(xy 102.76587 -240.140637) (xy 102.814089 -240.130793) (xy 102.863264 -240.128812) (xy 102.912119 -240.134744)
			(xy 102.95939 -240.148436) (xy 103.003852 -240.169534) (xy 103.044355 -240.19749) (xy 103.079848 -240.231582)
			(xy 103.109413 -240.270926) (xy 103.132284 -240.314503) (xy 103.147868 -240.361184) (xy 103.155763 -240.409761)
			(xy 103.156258 -240.434368) (xy 103.4852 -240.434368) (xy 103.48916 -240.385314) (xy 103.500937 -240.33753)
			(xy 103.520228 -240.292254) (xy 103.546531 -240.250658) (xy 103.579166 -240.213821) (xy 103.617287 -240.182696)
			(xy 103.659908 -240.158089) (xy 103.705924 -240.140637) (xy 103.754143 -240.130793) (xy 103.803318 -240.128812)
			(xy 103.852173 -240.134744) (xy 103.899444 -240.148436) (xy 103.943906 -240.169534) (xy 103.984409 -240.19749)
			(xy 104.019902 -240.231582) (xy 104.049467 -240.270926) (xy 104.072338 -240.314503) (xy 104.087922 -240.361184)
			(xy 104.095817 -240.409761) (xy 104.096312 -240.434368) (xy 104.425254 -240.434368) (xy 104.429214 -240.385314)
			(xy 104.440991 -240.33753) (xy 104.460282 -240.292254) (xy 104.486585 -240.250658) (xy 104.51922 -240.213821)
			(xy 104.557341 -240.182696) (xy 104.599962 -240.158089) (xy 104.645978 -240.140637) (xy 104.694197 -240.130793)
			(xy 104.743372 -240.128812) (xy 104.792227 -240.134744) (xy 104.839498 -240.148436) (xy 104.88396 -240.169534)
			(xy 104.924463 -240.19749) (xy 104.959956 -240.231582) (xy 104.989521 -240.270926) (xy 105.012392 -240.314503)
			(xy 105.027976 -240.361184) (xy 105.035871 -240.409761) (xy 105.036366 -240.434368) (xy 105.365308 -240.434368)
			(xy 105.369268 -240.385314) (xy 105.381045 -240.33753) (xy 105.400336 -240.292254) (xy 105.426639 -240.250658)
			(xy 105.459274 -240.213821) (xy 105.497395 -240.182696) (xy 105.540016 -240.158089) (xy 105.586032 -240.140637)
			(xy 105.634251 -240.130793) (xy 105.683426 -240.128812) (xy 105.732281 -240.134744) (xy 105.779552 -240.148436)
			(xy 105.824014 -240.169534) (xy 105.864517 -240.19749) (xy 105.90001 -240.231582) (xy 105.929575 -240.270926)
			(xy 105.952446 -240.314503) (xy 105.96803 -240.361184) (xy 105.975925 -240.409761) (xy 105.97642 -240.434368)
			(xy 106.305362 -240.434368) (xy 106.309322 -240.385314) (xy 106.321099 -240.33753) (xy 106.34039 -240.292254)
			(xy 106.366693 -240.250658) (xy 106.399328 -240.213821) (xy 106.437449 -240.182696) (xy 106.48007 -240.158089)
			(xy 106.526086 -240.140637) (xy 106.574305 -240.130793) (xy 106.62348 -240.128812) (xy 106.672335 -240.134744)
			(xy 106.719606 -240.148436) (xy 106.764068 -240.169534) (xy 106.804571 -240.19749) (xy 106.840064 -240.231582)
			(xy 106.869629 -240.270926) (xy 106.8925 -240.314503) (xy 106.908084 -240.361184) (xy 106.915979 -240.409761)
			(xy 106.916474 -240.434368) (xy 107.245162 -240.434368) (xy 107.249122 -240.385314) (xy 107.260899 -240.33753)
			(xy 107.28019 -240.292254) (xy 107.306493 -240.250658) (xy 107.339128 -240.213821) (xy 107.377249 -240.182696)
			(xy 107.41987 -240.158089) (xy 107.465886 -240.140637) (xy 107.514105 -240.130793) (xy 107.56328 -240.128812)
			(xy 107.612135 -240.134744) (xy 107.659406 -240.148436) (xy 107.703868 -240.169534) (xy 107.744371 -240.19749)
			(xy 107.779864 -240.231582) (xy 107.809429 -240.270926) (xy 107.8323 -240.314503) (xy 107.847884 -240.361184)
			(xy 107.855779 -240.409761) (xy 107.856274 -240.434368) (xy 108.185216 -240.434368) (xy 108.189176 -240.385314)
			(xy 108.200953 -240.33753) (xy 108.220244 -240.292254) (xy 108.246547 -240.250658) (xy 108.279182 -240.213821)
			(xy 108.317303 -240.182696) (xy 108.359924 -240.158089) (xy 108.40594 -240.140637) (xy 108.454159 -240.130793)
			(xy 108.503334 -240.128812) (xy 108.552189 -240.134744) (xy 108.59946 -240.148436) (xy 108.643922 -240.169534)
			(xy 108.684425 -240.19749) (xy 108.719918 -240.231582) (xy 108.749483 -240.270926) (xy 108.772354 -240.314503)
			(xy 108.787938 -240.361184) (xy 108.795833 -240.409761) (xy 108.796328 -240.434368) (xy 109.12527 -240.434368)
			(xy 109.12923 -240.385314) (xy 109.141007 -240.33753) (xy 109.160298 -240.292254) (xy 109.186601 -240.250658)
			(xy 109.219236 -240.213821) (xy 109.257357 -240.182696) (xy 109.299978 -240.158089) (xy 109.345994 -240.140637)
			(xy 109.394213 -240.130793) (xy 109.443388 -240.128812) (xy 109.492243 -240.134744) (xy 109.539514 -240.148436)
			(xy 109.583976 -240.169534) (xy 109.624479 -240.19749) (xy 109.659972 -240.231582) (xy 109.689537 -240.270926)
			(xy 109.712408 -240.314503) (xy 109.727992 -240.361184) (xy 109.735887 -240.409761) (xy 109.736382 -240.434368)
			(xy 110.065324 -240.434368) (xy 110.069284 -240.385314) (xy 110.081061 -240.33753) (xy 110.100352 -240.292254)
			(xy 110.126655 -240.250658) (xy 110.15929 -240.213821) (xy 110.197411 -240.182696) (xy 110.240032 -240.158089)
			(xy 110.286048 -240.140637) (xy 110.334267 -240.130793) (xy 110.383442 -240.128812) (xy 110.432297 -240.134744)
			(xy 110.479568 -240.148436) (xy 110.52403 -240.169534) (xy 110.564533 -240.19749) (xy 110.600026 -240.231582)
			(xy 110.629591 -240.270926) (xy 110.652462 -240.314503) (xy 110.668046 -240.361184) (xy 110.675941 -240.409761)
			(xy 110.676436 -240.434368) (xy 112.878882 -240.434368) (xy 112.882842 -240.385314) (xy 112.894619 -240.33753)
			(xy 112.91391 -240.292254) (xy 112.940213 -240.250658) (xy 112.972848 -240.213821) (xy 113.010969 -240.182696)
			(xy 113.05359 -240.158089) (xy 113.099606 -240.140637) (xy 113.147825 -240.130793) (xy 113.197 -240.128812)
			(xy 113.245855 -240.134744) (xy 113.293126 -240.148436) (xy 113.337588 -240.169534) (xy 113.378091 -240.19749)
			(xy 113.413584 -240.231582) (xy 113.443149 -240.270926) (xy 113.46602 -240.314503) (xy 113.481604 -240.361184)
			(xy 113.489499 -240.409761) (xy 113.489994 -240.434368) (xy 113.818936 -240.434368) (xy 113.822896 -240.385314)
			(xy 113.834673 -240.33753) (xy 113.853964 -240.292254) (xy 113.880267 -240.250658) (xy 113.912902 -240.213821)
			(xy 113.951023 -240.182696) (xy 113.993644 -240.158089) (xy 114.03966 -240.140637) (xy 114.087879 -240.130793)
			(xy 114.137054 -240.128812) (xy 114.185909 -240.134744) (xy 114.23318 -240.148436) (xy 114.277642 -240.169534)
			(xy 114.318145 -240.19749) (xy 114.353638 -240.231582) (xy 114.383203 -240.270926) (xy 114.406074 -240.314503)
			(xy 114.421658 -240.361184) (xy 114.429553 -240.409761) (xy 114.430048 -240.434368) (xy 114.75899 -240.434368)
			(xy 114.76295 -240.385314) (xy 114.774727 -240.33753) (xy 114.794018 -240.292254) (xy 114.820321 -240.250658)
			(xy 114.852956 -240.213821) (xy 114.891077 -240.182696) (xy 114.933698 -240.158089) (xy 114.979714 -240.140637)
			(xy 115.027933 -240.130793) (xy 115.077108 -240.128812) (xy 115.125963 -240.134744) (xy 115.173234 -240.148436)
			(xy 115.217696 -240.169534) (xy 115.258199 -240.19749) (xy 115.293692 -240.231582) (xy 115.323257 -240.270926)
			(xy 115.346128 -240.314503) (xy 115.361712 -240.361184) (xy 115.369607 -240.409761) (xy 115.370102 -240.434368)
			(xy 115.699044 -240.434368) (xy 115.703004 -240.385314) (xy 115.714781 -240.33753) (xy 115.734072 -240.292254)
			(xy 115.760375 -240.250658) (xy 115.79301 -240.213821) (xy 115.831131 -240.182696) (xy 115.873752 -240.158089)
			(xy 115.919768 -240.140637) (xy 115.967987 -240.130793) (xy 116.017162 -240.128812) (xy 116.066017 -240.134744)
			(xy 116.113288 -240.148436) (xy 116.15775 -240.169534) (xy 116.198253 -240.19749) (xy 116.233746 -240.231582)
			(xy 116.263311 -240.270926) (xy 116.286182 -240.314503) (xy 116.301766 -240.361184) (xy 116.309661 -240.409761)
			(xy 116.310156 -240.434368) (xy 116.638844 -240.434368) (xy 116.642804 -240.385314) (xy 116.654581 -240.33753)
			(xy 116.673872 -240.292254) (xy 116.700175 -240.250658) (xy 116.73281 -240.213821) (xy 116.770931 -240.182696)
			(xy 116.813552 -240.158089) (xy 116.859568 -240.140637) (xy 116.907787 -240.130793) (xy 116.956962 -240.128812)
			(xy 117.005817 -240.134744) (xy 117.053088 -240.148436) (xy 117.09755 -240.169534) (xy 117.138053 -240.19749)
			(xy 117.173546 -240.231582) (xy 117.203111 -240.270926) (xy 117.225982 -240.314503) (xy 117.241566 -240.361184)
			(xy 117.249461 -240.409761) (xy 117.249956 -240.434368) (xy 117.578898 -240.434368) (xy 117.582858 -240.385314)
			(xy 117.594635 -240.33753) (xy 117.613926 -240.292254) (xy 117.640229 -240.250658) (xy 117.672864 -240.213821)
			(xy 117.710985 -240.182696) (xy 117.753606 -240.158089) (xy 117.799622 -240.140637) (xy 117.847841 -240.130793)
			(xy 117.897016 -240.128812) (xy 117.945871 -240.134744) (xy 117.993142 -240.148436) (xy 118.037604 -240.169534)
			(xy 118.078107 -240.19749) (xy 118.1136 -240.231582) (xy 118.143165 -240.270926) (xy 118.166036 -240.314503)
			(xy 118.18162 -240.361184) (xy 118.189515 -240.409761) (xy 118.19001 -240.434368) (xy 118.518952 -240.434368)
			(xy 118.522912 -240.385314) (xy 118.534689 -240.33753) (xy 118.55398 -240.292254) (xy 118.580283 -240.250658)
			(xy 118.612918 -240.213821) (xy 118.651039 -240.182696) (xy 118.69366 -240.158089) (xy 118.739676 -240.140637)
			(xy 118.787895 -240.130793) (xy 118.83707 -240.128812) (xy 118.885925 -240.134744) (xy 118.933196 -240.148436)
			(xy 118.977658 -240.169534) (xy 119.018161 -240.19749) (xy 119.053654 -240.231582) (xy 119.083219 -240.270926)
			(xy 119.10609 -240.314503) (xy 119.121674 -240.361184) (xy 119.129569 -240.409761) (xy 119.130064 -240.434368)
			(xy 119.459006 -240.434368) (xy 119.462966 -240.385314) (xy 119.474743 -240.33753) (xy 119.494034 -240.292254)
			(xy 119.520337 -240.250658) (xy 119.552972 -240.213821) (xy 119.591093 -240.182696) (xy 119.633714 -240.158089)
			(xy 119.67973 -240.140637) (xy 119.727949 -240.130793) (xy 119.777124 -240.128812) (xy 119.825979 -240.134744)
			(xy 119.87325 -240.148436) (xy 119.917712 -240.169534) (xy 119.958215 -240.19749) (xy 119.993708 -240.231582)
			(xy 120.023273 -240.270926) (xy 120.046144 -240.314503) (xy 120.061728 -240.361184) (xy 120.069623 -240.409761)
			(xy 120.070118 -240.434368) (xy 120.398806 -240.434368) (xy 120.402766 -240.385314) (xy 120.414543 -240.33753)
			(xy 120.433834 -240.292254) (xy 120.460137 -240.250658) (xy 120.492772 -240.213821) (xy 120.530893 -240.182696)
			(xy 120.573514 -240.158089) (xy 120.61953 -240.140637) (xy 120.667749 -240.130793) (xy 120.716924 -240.128812)
			(xy 120.765779 -240.134744) (xy 120.81305 -240.148436) (xy 120.857512 -240.169534) (xy 120.898015 -240.19749)
			(xy 120.933508 -240.231582) (xy 120.963073 -240.270926) (xy 120.985944 -240.314503) (xy 121.001528 -240.361184)
			(xy 121.009423 -240.409761) (xy 121.009918 -240.434368) (xy 121.33886 -240.434368) (xy 121.34282 -240.385314)
			(xy 121.354597 -240.33753) (xy 121.373888 -240.292254) (xy 121.400191 -240.250658) (xy 121.432826 -240.213821)
			(xy 121.470947 -240.182696) (xy 121.513568 -240.158089) (xy 121.559584 -240.140637) (xy 121.607803 -240.130793)
			(xy 121.656978 -240.128812) (xy 121.705833 -240.134744) (xy 121.753104 -240.148436) (xy 121.797566 -240.169534)
			(xy 121.838069 -240.19749) (xy 121.873562 -240.231582) (xy 121.903127 -240.270926) (xy 121.925998 -240.314503)
			(xy 121.941582 -240.361184) (xy 121.949477 -240.409761) (xy 121.949972 -240.434368) (xy 122.278914 -240.434368)
			(xy 122.282874 -240.385314) (xy 122.294651 -240.33753) (xy 122.313942 -240.292254) (xy 122.340245 -240.250658)
			(xy 122.37288 -240.213821) (xy 122.411001 -240.182696) (xy 122.453622 -240.158089) (xy 122.499638 -240.140637)
			(xy 122.547857 -240.130793) (xy 122.597032 -240.128812) (xy 122.645887 -240.134744) (xy 122.693158 -240.148436)
			(xy 122.73762 -240.169534) (xy 122.778123 -240.19749) (xy 122.813616 -240.231582) (xy 122.843181 -240.270926)
			(xy 122.866052 -240.314503) (xy 122.881636 -240.361184) (xy 122.889531 -240.409761) (xy 122.890026 -240.434368)
			(xy 123.218968 -240.434368) (xy 123.222928 -240.385314) (xy 123.234705 -240.33753) (xy 123.253996 -240.292254)
			(xy 123.280299 -240.250658) (xy 123.312934 -240.213821) (xy 123.351055 -240.182696) (xy 123.393676 -240.158089)
			(xy 123.439692 -240.140637) (xy 123.487911 -240.130793) (xy 123.537086 -240.128812) (xy 123.585941 -240.134744)
			(xy 123.633212 -240.148436) (xy 123.677674 -240.169534) (xy 123.718177 -240.19749) (xy 123.75367 -240.231582)
			(xy 123.783235 -240.270926) (xy 123.806106 -240.314503) (xy 123.82169 -240.361184) (xy 123.829585 -240.409761)
			(xy 123.83008 -240.434368) (xy 124.159022 -240.434368) (xy 124.162982 -240.385314) (xy 124.174759 -240.33753)
			(xy 124.19405 -240.292254) (xy 124.220353 -240.250658) (xy 124.252988 -240.213821) (xy 124.291109 -240.182696)
			(xy 124.33373 -240.158089) (xy 124.379746 -240.140637) (xy 124.427965 -240.130793) (xy 124.47714 -240.128812)
			(xy 124.525995 -240.134744) (xy 124.573266 -240.148436) (xy 124.617728 -240.169534) (xy 124.658231 -240.19749)
			(xy 124.693724 -240.231582) (xy 124.723289 -240.270926) (xy 124.74616 -240.314503) (xy 124.761744 -240.361184)
			(xy 124.769639 -240.409761) (xy 124.770134 -240.434368) (xy 125.098822 -240.434368) (xy 125.102782 -240.385314)
			(xy 125.114559 -240.33753) (xy 125.13385 -240.292254) (xy 125.160153 -240.250658) (xy 125.192788 -240.213821)
			(xy 125.230909 -240.182696) (xy 125.27353 -240.158089) (xy 125.319546 -240.140637) (xy 125.367765 -240.130793)
			(xy 125.41694 -240.128812) (xy 125.465795 -240.134744) (xy 125.513066 -240.148436) (xy 125.557528 -240.169534)
			(xy 125.598031 -240.19749) (xy 125.633524 -240.231582) (xy 125.663089 -240.270926) (xy 125.68596 -240.314503)
			(xy 125.701544 -240.361184) (xy 125.709439 -240.409761) (xy 125.709934 -240.434368) (xy 126.038876 -240.434368)
			(xy 126.042836 -240.385314) (xy 126.054613 -240.33753) (xy 126.073904 -240.292254) (xy 126.100207 -240.250658)
			(xy 126.132842 -240.213821) (xy 126.170963 -240.182696) (xy 126.213584 -240.158089) (xy 126.2596 -240.140637)
			(xy 126.307819 -240.130793) (xy 126.356994 -240.128812) (xy 126.405849 -240.134744) (xy 126.45312 -240.148436)
			(xy 126.497582 -240.169534) (xy 126.538085 -240.19749) (xy 126.573578 -240.231582) (xy 126.603143 -240.270926)
			(xy 126.626014 -240.314503) (xy 126.641598 -240.361184) (xy 126.649493 -240.409761) (xy 126.649988 -240.434368)
			(xy 126.649493 -240.458975) (xy 126.641598 -240.507552) (xy 126.626014 -240.554233) (xy 126.603143 -240.59781)
			(xy 126.573578 -240.637154) (xy 126.538085 -240.671246) (xy 126.497582 -240.699202) (xy 126.45312 -240.7203)
			(xy 126.405849 -240.733992) (xy 126.356994 -240.739924) (xy 126.307819 -240.737943) (xy 126.2596 -240.728099)
			(xy 126.213584 -240.710647) (xy 126.170963 -240.68604) (xy 126.132842 -240.654915) (xy 126.100207 -240.618078)
			(xy 126.073904 -240.576482) (xy 126.054613 -240.531206) (xy 126.042836 -240.483422) (xy 126.038876 -240.434368)
			(xy 125.709934 -240.434368) (xy 125.709439 -240.458975) (xy 125.701544 -240.507552) (xy 125.68596 -240.554233)
			(xy 125.663089 -240.59781) (xy 125.633524 -240.637154) (xy 125.598031 -240.671246) (xy 125.557528 -240.699202)
			(xy 125.513066 -240.7203) (xy 125.465795 -240.733992) (xy 125.41694 -240.739924) (xy 125.367765 -240.737943)
			(xy 125.319546 -240.728099) (xy 125.27353 -240.710647) (xy 125.230909 -240.68604) (xy 125.192788 -240.654915)
			(xy 125.160153 -240.618078) (xy 125.13385 -240.576482) (xy 125.114559 -240.531206) (xy 125.102782 -240.483422)
			(xy 125.098822 -240.434368) (xy 124.770134 -240.434368) (xy 124.769639 -240.458975) (xy 124.761744 -240.507552)
			(xy 124.74616 -240.554233) (xy 124.723289 -240.59781) (xy 124.693724 -240.637154) (xy 124.658231 -240.671246)
			(xy 124.617728 -240.699202) (xy 124.573266 -240.7203) (xy 124.525995 -240.733992) (xy 124.47714 -240.739924)
			(xy 124.427965 -240.737943) (xy 124.379746 -240.728099) (xy 124.33373 -240.710647) (xy 124.291109 -240.68604)
			(xy 124.252988 -240.654915) (xy 124.220353 -240.618078) (xy 124.19405 -240.576482) (xy 124.174759 -240.531206)
			(xy 124.162982 -240.483422) (xy 124.159022 -240.434368) (xy 123.83008 -240.434368) (xy 123.829585 -240.458975)
			(xy 123.82169 -240.507552) (xy 123.806106 -240.554233) (xy 123.783235 -240.59781) (xy 123.75367 -240.637154)
			(xy 123.718177 -240.671246) (xy 123.677674 -240.699202) (xy 123.633212 -240.7203) (xy 123.585941 -240.733992)
			(xy 123.537086 -240.739924) (xy 123.487911 -240.737943) (xy 123.439692 -240.728099) (xy 123.393676 -240.710647)
			(xy 123.351055 -240.68604) (xy 123.312934 -240.654915) (xy 123.280299 -240.618078) (xy 123.253996 -240.576482)
			(xy 123.234705 -240.531206) (xy 123.222928 -240.483422) (xy 123.218968 -240.434368) (xy 122.890026 -240.434368)
			(xy 122.889531 -240.458975) (xy 122.881636 -240.507552) (xy 122.866052 -240.554233) (xy 122.843181 -240.59781)
			(xy 122.813616 -240.637154) (xy 122.778123 -240.671246) (xy 122.73762 -240.699202) (xy 122.693158 -240.7203)
			(xy 122.645887 -240.733992) (xy 122.597032 -240.739924) (xy 122.547857 -240.737943) (xy 122.499638 -240.728099)
			(xy 122.453622 -240.710647) (xy 122.411001 -240.68604) (xy 122.37288 -240.654915) (xy 122.340245 -240.618078)
			(xy 122.313942 -240.576482) (xy 122.294651 -240.531206) (xy 122.282874 -240.483422) (xy 122.278914 -240.434368)
			(xy 121.949972 -240.434368) (xy 121.949477 -240.458975) (xy 121.941582 -240.507552) (xy 121.925998 -240.554233)
			(xy 121.903127 -240.59781) (xy 121.873562 -240.637154) (xy 121.838069 -240.671246) (xy 121.797566 -240.699202)
			(xy 121.753104 -240.7203) (xy 121.705833 -240.733992) (xy 121.656978 -240.739924) (xy 121.607803 -240.737943)
			(xy 121.559584 -240.728099) (xy 121.513568 -240.710647) (xy 121.470947 -240.68604) (xy 121.432826 -240.654915)
			(xy 121.400191 -240.618078) (xy 121.373888 -240.576482) (xy 121.354597 -240.531206) (xy 121.34282 -240.483422)
			(xy 121.33886 -240.434368) (xy 121.009918 -240.434368) (xy 121.009423 -240.458975) (xy 121.001528 -240.507552)
			(xy 120.985944 -240.554233) (xy 120.963073 -240.59781) (xy 120.933508 -240.637154) (xy 120.898015 -240.671246)
			(xy 120.857512 -240.699202) (xy 120.81305 -240.7203) (xy 120.765779 -240.733992) (xy 120.716924 -240.739924)
			(xy 120.667749 -240.737943) (xy 120.61953 -240.728099) (xy 120.573514 -240.710647) (xy 120.530893 -240.68604)
			(xy 120.492772 -240.654915) (xy 120.460137 -240.618078) (xy 120.433834 -240.576482) (xy 120.414543 -240.531206)
			(xy 120.402766 -240.483422) (xy 120.398806 -240.434368) (xy 120.070118 -240.434368) (xy 120.069623 -240.458975)
			(xy 120.061728 -240.507552) (xy 120.046144 -240.554233) (xy 120.023273 -240.59781) (xy 119.993708 -240.637154)
			(xy 119.958215 -240.671246) (xy 119.917712 -240.699202) (xy 119.87325 -240.7203) (xy 119.825979 -240.733992)
			(xy 119.777124 -240.739924) (xy 119.727949 -240.737943) (xy 119.67973 -240.728099) (xy 119.633714 -240.710647)
			(xy 119.591093 -240.68604) (xy 119.552972 -240.654915) (xy 119.520337 -240.618078) (xy 119.494034 -240.576482)
			(xy 119.474743 -240.531206) (xy 119.462966 -240.483422) (xy 119.459006 -240.434368) (xy 119.130064 -240.434368)
			(xy 119.129569 -240.458975) (xy 119.121674 -240.507552) (xy 119.10609 -240.554233) (xy 119.083219 -240.59781)
			(xy 119.053654 -240.637154) (xy 119.018161 -240.671246) (xy 118.977658 -240.699202) (xy 118.933196 -240.7203)
			(xy 118.885925 -240.733992) (xy 118.83707 -240.739924) (xy 118.787895 -240.737943) (xy 118.739676 -240.728099)
			(xy 118.69366 -240.710647) (xy 118.651039 -240.68604) (xy 118.612918 -240.654915) (xy 118.580283 -240.618078)
			(xy 118.55398 -240.576482) (xy 118.534689 -240.531206) (xy 118.522912 -240.483422) (xy 118.518952 -240.434368)
			(xy 118.19001 -240.434368) (xy 118.189515 -240.458975) (xy 118.18162 -240.507552) (xy 118.166036 -240.554233)
			(xy 118.143165 -240.59781) (xy 118.1136 -240.637154) (xy 118.078107 -240.671246) (xy 118.037604 -240.699202)
			(xy 117.993142 -240.7203) (xy 117.945871 -240.733992) (xy 117.897016 -240.739924) (xy 117.847841 -240.737943)
			(xy 117.799622 -240.728099) (xy 117.753606 -240.710647) (xy 117.710985 -240.68604) (xy 117.672864 -240.654915)
			(xy 117.640229 -240.618078) (xy 117.613926 -240.576482) (xy 117.594635 -240.531206) (xy 117.582858 -240.483422)
			(xy 117.578898 -240.434368) (xy 117.249956 -240.434368) (xy 117.249461 -240.458975) (xy 117.241566 -240.507552)
			(xy 117.225982 -240.554233) (xy 117.203111 -240.59781) (xy 117.173546 -240.637154) (xy 117.138053 -240.671246)
			(xy 117.09755 -240.699202) (xy 117.053088 -240.7203) (xy 117.005817 -240.733992) (xy 116.956962 -240.739924)
			(xy 116.907787 -240.737943) (xy 116.859568 -240.728099) (xy 116.813552 -240.710647) (xy 116.770931 -240.68604)
			(xy 116.73281 -240.654915) (xy 116.700175 -240.618078) (xy 116.673872 -240.576482) (xy 116.654581 -240.531206)
			(xy 116.642804 -240.483422) (xy 116.638844 -240.434368) (xy 116.310156 -240.434368) (xy 116.309661 -240.458975)
			(xy 116.301766 -240.507552) (xy 116.286182 -240.554233) (xy 116.263311 -240.59781) (xy 116.233746 -240.637154)
			(xy 116.198253 -240.671246) (xy 116.15775 -240.699202) (xy 116.113288 -240.7203) (xy 116.066017 -240.733992)
			(xy 116.017162 -240.739924) (xy 115.967987 -240.737943) (xy 115.919768 -240.728099) (xy 115.873752 -240.710647)
			(xy 115.831131 -240.68604) (xy 115.79301 -240.654915) (xy 115.760375 -240.618078) (xy 115.734072 -240.576482)
			(xy 115.714781 -240.531206) (xy 115.703004 -240.483422) (xy 115.699044 -240.434368) (xy 115.370102 -240.434368)
			(xy 115.369607 -240.458975) (xy 115.361712 -240.507552) (xy 115.346128 -240.554233) (xy 115.323257 -240.59781)
			(xy 115.293692 -240.637154) (xy 115.258199 -240.671246) (xy 115.217696 -240.699202) (xy 115.173234 -240.7203)
			(xy 115.125963 -240.733992) (xy 115.077108 -240.739924) (xy 115.027933 -240.737943) (xy 114.979714 -240.728099)
			(xy 114.933698 -240.710647) (xy 114.891077 -240.68604) (xy 114.852956 -240.654915) (xy 114.820321 -240.618078)
			(xy 114.794018 -240.576482) (xy 114.774727 -240.531206) (xy 114.76295 -240.483422) (xy 114.75899 -240.434368)
			(xy 114.430048 -240.434368) (xy 114.429553 -240.458975) (xy 114.421658 -240.507552) (xy 114.406074 -240.554233)
			(xy 114.383203 -240.59781) (xy 114.353638 -240.637154) (xy 114.318145 -240.671246) (xy 114.277642 -240.699202)
			(xy 114.23318 -240.7203) (xy 114.185909 -240.733992) (xy 114.137054 -240.739924) (xy 114.087879 -240.737943)
			(xy 114.03966 -240.728099) (xy 113.993644 -240.710647) (xy 113.951023 -240.68604) (xy 113.912902 -240.654915)
			(xy 113.880267 -240.618078) (xy 113.853964 -240.576482) (xy 113.834673 -240.531206) (xy 113.822896 -240.483422)
			(xy 113.818936 -240.434368) (xy 113.489994 -240.434368) (xy 113.489499 -240.458975) (xy 113.481604 -240.507552)
			(xy 113.46602 -240.554233) (xy 113.443149 -240.59781) (xy 113.413584 -240.637154) (xy 113.378091 -240.671246)
			(xy 113.337588 -240.699202) (xy 113.293126 -240.7203) (xy 113.245855 -240.733992) (xy 113.197 -240.739924)
			(xy 113.147825 -240.737943) (xy 113.099606 -240.728099) (xy 113.05359 -240.710647) (xy 113.010969 -240.68604)
			(xy 112.972848 -240.654915) (xy 112.940213 -240.618078) (xy 112.91391 -240.576482) (xy 112.894619 -240.531206)
			(xy 112.882842 -240.483422) (xy 112.878882 -240.434368) (xy 110.676436 -240.434368) (xy 110.675941 -240.458975)
			(xy 110.668046 -240.507552) (xy 110.652462 -240.554233) (xy 110.629591 -240.59781) (xy 110.600026 -240.637154)
			(xy 110.564533 -240.671246) (xy 110.52403 -240.699202) (xy 110.479568 -240.7203) (xy 110.432297 -240.733992)
			(xy 110.383442 -240.739924) (xy 110.334267 -240.737943) (xy 110.286048 -240.728099) (xy 110.240032 -240.710647)
			(xy 110.197411 -240.68604) (xy 110.15929 -240.654915) (xy 110.126655 -240.618078) (xy 110.100352 -240.576482)
			(xy 110.081061 -240.531206) (xy 110.069284 -240.483422) (xy 110.065324 -240.434368) (xy 109.736382 -240.434368)
			(xy 109.735887 -240.458975) (xy 109.727992 -240.507552) (xy 109.712408 -240.554233) (xy 109.689537 -240.59781)
			(xy 109.659972 -240.637154) (xy 109.624479 -240.671246) (xy 109.583976 -240.699202) (xy 109.539514 -240.7203)
			(xy 109.492243 -240.733992) (xy 109.443388 -240.739924) (xy 109.394213 -240.737943) (xy 109.345994 -240.728099)
			(xy 109.299978 -240.710647) (xy 109.257357 -240.68604) (xy 109.219236 -240.654915) (xy 109.186601 -240.618078)
			(xy 109.160298 -240.576482) (xy 109.141007 -240.531206) (xy 109.12923 -240.483422) (xy 109.12527 -240.434368)
			(xy 108.796328 -240.434368) (xy 108.795833 -240.458975) (xy 108.787938 -240.507552) (xy 108.772354 -240.554233)
			(xy 108.749483 -240.59781) (xy 108.719918 -240.637154) (xy 108.684425 -240.671246) (xy 108.643922 -240.699202)
			(xy 108.59946 -240.7203) (xy 108.552189 -240.733992) (xy 108.503334 -240.739924) (xy 108.454159 -240.737943)
			(xy 108.40594 -240.728099) (xy 108.359924 -240.710647) (xy 108.317303 -240.68604) (xy 108.279182 -240.654915)
			(xy 108.246547 -240.618078) (xy 108.220244 -240.576482) (xy 108.200953 -240.531206) (xy 108.189176 -240.483422)
			(xy 108.185216 -240.434368) (xy 107.856274 -240.434368) (xy 107.855779 -240.458975) (xy 107.847884 -240.507552)
			(xy 107.8323 -240.554233) (xy 107.809429 -240.59781) (xy 107.779864 -240.637154) (xy 107.744371 -240.671246)
			(xy 107.703868 -240.699202) (xy 107.659406 -240.7203) (xy 107.612135 -240.733992) (xy 107.56328 -240.739924)
			(xy 107.514105 -240.737943) (xy 107.465886 -240.728099) (xy 107.41987 -240.710647) (xy 107.377249 -240.68604)
			(xy 107.339128 -240.654915) (xy 107.306493 -240.618078) (xy 107.28019 -240.576482) (xy 107.260899 -240.531206)
			(xy 107.249122 -240.483422) (xy 107.245162 -240.434368) (xy 106.916474 -240.434368) (xy 106.915979 -240.458975)
			(xy 106.908084 -240.507552) (xy 106.8925 -240.554233) (xy 106.869629 -240.59781) (xy 106.840064 -240.637154)
			(xy 106.804571 -240.671246) (xy 106.764068 -240.699202) (xy 106.719606 -240.7203) (xy 106.672335 -240.733992)
			(xy 106.62348 -240.739924) (xy 106.574305 -240.737943) (xy 106.526086 -240.728099) (xy 106.48007 -240.710647)
			(xy 106.437449 -240.68604) (xy 106.399328 -240.654915) (xy 106.366693 -240.618078) (xy 106.34039 -240.576482)
			(xy 106.321099 -240.531206) (xy 106.309322 -240.483422) (xy 106.305362 -240.434368) (xy 105.97642 -240.434368)
			(xy 105.975925 -240.458975) (xy 105.96803 -240.507552) (xy 105.952446 -240.554233) (xy 105.929575 -240.59781)
			(xy 105.90001 -240.637154) (xy 105.864517 -240.671246) (xy 105.824014 -240.699202) (xy 105.779552 -240.7203)
			(xy 105.732281 -240.733992) (xy 105.683426 -240.739924) (xy 105.634251 -240.737943) (xy 105.586032 -240.728099)
			(xy 105.540016 -240.710647) (xy 105.497395 -240.68604) (xy 105.459274 -240.654915) (xy 105.426639 -240.618078)
			(xy 105.400336 -240.576482) (xy 105.381045 -240.531206) (xy 105.369268 -240.483422) (xy 105.365308 -240.434368)
			(xy 105.036366 -240.434368) (xy 105.035871 -240.458975) (xy 105.027976 -240.507552) (xy 105.012392 -240.554233)
			(xy 104.989521 -240.59781) (xy 104.959956 -240.637154) (xy 104.924463 -240.671246) (xy 104.88396 -240.699202)
			(xy 104.839498 -240.7203) (xy 104.792227 -240.733992) (xy 104.743372 -240.739924) (xy 104.694197 -240.737943)
			(xy 104.645978 -240.728099) (xy 104.599962 -240.710647) (xy 104.557341 -240.68604) (xy 104.51922 -240.654915)
			(xy 104.486585 -240.618078) (xy 104.460282 -240.576482) (xy 104.440991 -240.531206) (xy 104.429214 -240.483422)
			(xy 104.425254 -240.434368) (xy 104.096312 -240.434368) (xy 104.095817 -240.458975) (xy 104.087922 -240.507552)
			(xy 104.072338 -240.554233) (xy 104.049467 -240.59781) (xy 104.019902 -240.637154) (xy 103.984409 -240.671246)
			(xy 103.943906 -240.699202) (xy 103.899444 -240.7203) (xy 103.852173 -240.733992) (xy 103.803318 -240.739924)
			(xy 103.754143 -240.737943) (xy 103.705924 -240.728099) (xy 103.659908 -240.710647) (xy 103.617287 -240.68604)
			(xy 103.579166 -240.654915) (xy 103.546531 -240.618078) (xy 103.520228 -240.576482) (xy 103.500937 -240.531206)
			(xy 103.48916 -240.483422) (xy 103.4852 -240.434368) (xy 103.156258 -240.434368) (xy 103.155763 -240.458975)
			(xy 103.147868 -240.507552) (xy 103.132284 -240.554233) (xy 103.109413 -240.59781) (xy 103.079848 -240.637154)
			(xy 103.044355 -240.671246) (xy 103.003852 -240.699202) (xy 102.95939 -240.7203) (xy 102.912119 -240.733992)
			(xy 102.863264 -240.739924) (xy 102.814089 -240.737943) (xy 102.76587 -240.728099) (xy 102.719854 -240.710647)
			(xy 102.677233 -240.68604) (xy 102.639112 -240.654915) (xy 102.606477 -240.618078) (xy 102.580174 -240.576482)
			(xy 102.560883 -240.531206) (xy 102.549106 -240.483422) (xy 102.545146 -240.434368) (xy 102.216458 -240.434368)
			(xy 102.215963 -240.458975) (xy 102.208068 -240.507552) (xy 102.192484 -240.554233) (xy 102.169613 -240.59781)
			(xy 102.140048 -240.637154) (xy 102.104555 -240.671246) (xy 102.064052 -240.699202) (xy 102.01959 -240.7203)
			(xy 101.972319 -240.733992) (xy 101.923464 -240.739924) (xy 101.874289 -240.737943) (xy 101.82607 -240.728099)
			(xy 101.780054 -240.710647) (xy 101.737433 -240.68604) (xy 101.699312 -240.654915) (xy 101.666677 -240.618078)
			(xy 101.640374 -240.576482) (xy 101.621083 -240.531206) (xy 101.609306 -240.483422) (xy 101.605346 -240.434368)
			(xy 101.276404 -240.434368) (xy 101.275909 -240.458975) (xy 101.268014 -240.507552) (xy 101.25243 -240.554233)
			(xy 101.229559 -240.59781) (xy 101.199994 -240.637154) (xy 101.164501 -240.671246) (xy 101.123998 -240.699202)
			(xy 101.079536 -240.7203) (xy 101.032265 -240.733992) (xy 100.98341 -240.739924) (xy 100.934235 -240.737943)
			(xy 100.886016 -240.728099) (xy 100.84 -240.710647) (xy 100.797379 -240.68604) (xy 100.759258 -240.654915)
			(xy 100.726623 -240.618078) (xy 100.70032 -240.576482) (xy 100.681029 -240.531206) (xy 100.669252 -240.483422)
			(xy 100.665292 -240.434368) (xy 100.33635 -240.434368) (xy 100.335855 -240.458975) (xy 100.32796 -240.507552)
			(xy 100.312376 -240.554233) (xy 100.289505 -240.59781) (xy 100.25994 -240.637154) (xy 100.224447 -240.671246)
			(xy 100.183944 -240.699202) (xy 100.139482 -240.7203) (xy 100.092211 -240.733992) (xy 100.043356 -240.739924)
			(xy 99.994181 -240.737943) (xy 99.945962 -240.728099) (xy 99.899946 -240.710647) (xy 99.857325 -240.68604)
			(xy 99.819204 -240.654915) (xy 99.786569 -240.618078) (xy 99.760266 -240.576482) (xy 99.740975 -240.531206)
			(xy 99.729198 -240.483422) (xy 99.725238 -240.434368) (xy 99.396296 -240.434368) (xy 99.395801 -240.458975)
			(xy 99.387906 -240.507552) (xy 99.372322 -240.554233) (xy 99.349451 -240.59781) (xy 99.319886 -240.637154)
			(xy 99.284393 -240.671246) (xy 99.24389 -240.699202) (xy 99.199428 -240.7203) (xy 99.152157 -240.733992)
			(xy 99.103302 -240.739924) (xy 99.054127 -240.737943) (xy 99.005908 -240.728099) (xy 98.959892 -240.710647)
			(xy 98.917271 -240.68604) (xy 98.87915 -240.654915) (xy 98.846515 -240.618078) (xy 98.820212 -240.576482)
			(xy 98.800921 -240.531206) (xy 98.789144 -240.483422) (xy 98.785184 -240.434368) (xy 98.456242 -240.434368)
			(xy 98.455747 -240.458975) (xy 98.447852 -240.507552) (xy 98.432268 -240.554233) (xy 98.409397 -240.59781)
			(xy 98.379832 -240.637154) (xy 98.344339 -240.671246) (xy 98.303836 -240.699202) (xy 98.259374 -240.7203)
			(xy 98.212103 -240.733992) (xy 98.163248 -240.739924) (xy 98.114073 -240.737943) (xy 98.065854 -240.728099)
			(xy 98.019838 -240.710647) (xy 97.977217 -240.68604) (xy 97.939096 -240.654915) (xy 97.906461 -240.618078)
			(xy 97.880158 -240.576482) (xy 97.860867 -240.531206) (xy 97.84909 -240.483422) (xy 97.84513 -240.434368)
			(xy 97.516442 -240.434368) (xy 97.515947 -240.458975) (xy 97.508052 -240.507552) (xy 97.492468 -240.554233)
			(xy 97.469597 -240.59781) (xy 97.440032 -240.637154) (xy 97.404539 -240.671246) (xy 97.364036 -240.699202)
			(xy 97.319574 -240.7203) (xy 97.272303 -240.733992) (xy 97.223448 -240.739924) (xy 97.174273 -240.737943)
			(xy 97.126054 -240.728099) (xy 97.080038 -240.710647) (xy 97.037417 -240.68604) (xy 96.999296 -240.654915)
			(xy 96.966661 -240.618078) (xy 96.940358 -240.576482) (xy 96.921067 -240.531206) (xy 96.90929 -240.483422)
			(xy 96.90533 -240.434368) (xy 96.575907 -240.434368) (xy 96.575917 -240.458362) (xy 96.568374 -240.505953)
			(xy 96.553456 -240.551771) (xy 96.531532 -240.594679) (xy 96.503145 -240.633614) (xy 96.468999 -240.667612)
			(xy 96.42994 -240.695828) (xy 96.386937 -240.717565) (xy 96.341055 -240.732284) (xy 96.317308 -240.736374)
			(xy 96.3168 -240.736374) (xy 96.316292 -240.736628) (xy 96.307529 -240.738292) (xy 96.291911 -240.746883)
			(xy 96.285812 -240.753392) (xy 96.280224 -240.759742) (xy 96.273874 -240.77676) (xy 96.273874 -240.9317)
			(xy 96.274056 -240.937936) (xy 96.277129 -240.950023) (xy 96.27997 -240.955576) (xy 96.284542 -240.96345)
			(xy 96.295087 -240.982051) (xy 96.313653 -241.020572) (xy 96.321626 -241.040412) (xy 96.323658 -241.045492)
			(xy 96.326452 -241.053112) (xy 96.33712 -241.061494) (xy 96.342596 -241.065452) (xy 96.355085 -241.070595)
			(xy 96.361758 -241.071654) (xy 96.448372 -241.083084) (xy 96.45511 -241.083668) (xy 96.468494 -241.081749)
			(xy 96.474788 -241.079274) (xy 96.48698 -241.074194) (xy 96.490536 -241.069622) (xy 96.495616 -241.062764)
			(xy 96.510119 -241.043934) (xy 96.543974 -241.010577) (xy 96.582586 -240.982866) (xy 96.625025 -240.961471)
			(xy 96.670266 -240.946907) (xy 96.717217 -240.939527) (xy 96.74098 -240.939066) (xy 96.766241 -240.939557)
			(xy 96.816074 -240.94787) (xy 96.863859 -240.964272) (xy 96.908293 -240.988316) (xy 96.948163 -241.019345)
			(xy 96.982382 -241.056514) (xy 97.010016 -241.098809) (xy 97.030311 -241.145075) (xy 97.042714 -241.194051)
			(xy 97.046884 -241.244374) (xy 97.37523 -241.244374) (xy 97.37919 -241.19532) (xy 97.390967 -241.147536)
			(xy 97.410258 -241.10226) (xy 97.436561 -241.060664) (xy 97.469196 -241.023827) (xy 97.507317 -240.992702)
			(xy 97.549938 -240.968095) (xy 97.595954 -240.950643) (xy 97.644173 -240.940799) (xy 97.693348 -240.938818)
			(xy 97.742203 -240.94475) (xy 97.789474 -240.958442) (xy 97.833936 -240.97954) (xy 97.874439 -241.007496)
			(xy 97.909932 -241.041588) (xy 97.939497 -241.080932) (xy 97.962368 -241.124509) (xy 97.977952 -241.17119)
			(xy 97.985847 -241.219767) (xy 97.986342 -241.244374) (xy 98.315284 -241.244374) (xy 98.319244 -241.19532)
			(xy 98.331021 -241.147536) (xy 98.350312 -241.10226) (xy 98.376615 -241.060664) (xy 98.40925 -241.023827)
			(xy 98.447371 -240.992702) (xy 98.489992 -240.968095) (xy 98.536008 -240.950643) (xy 98.584227 -240.940799)
			(xy 98.633402 -240.938818) (xy 98.682257 -240.94475) (xy 98.729528 -240.958442) (xy 98.77399 -240.97954)
			(xy 98.814493 -241.007496) (xy 98.849986 -241.041588) (xy 98.879551 -241.080932) (xy 98.902422 -241.124509)
			(xy 98.918006 -241.17119) (xy 98.925901 -241.219767) (xy 98.926396 -241.244374) (xy 99.255338 -241.244374)
			(xy 99.259298 -241.19532) (xy 99.271075 -241.147536) (xy 99.290366 -241.10226) (xy 99.316669 -241.060664)
			(xy 99.349304 -241.023827) (xy 99.387425 -240.992702) (xy 99.430046 -240.968095) (xy 99.476062 -240.950643)
			(xy 99.524281 -240.940799) (xy 99.573456 -240.938818) (xy 99.622311 -240.94475) (xy 99.669582 -240.958442)
			(xy 99.714044 -240.97954) (xy 99.754547 -241.007496) (xy 99.79004 -241.041588) (xy 99.819605 -241.080932)
			(xy 99.842476 -241.124509) (xy 99.85806 -241.17119) (xy 99.865955 -241.219767) (xy 99.86645 -241.244374)
			(xy 100.195138 -241.244374) (xy 100.199098 -241.19532) (xy 100.210875 -241.147536) (xy 100.230166 -241.10226)
			(xy 100.256469 -241.060664) (xy 100.289104 -241.023827) (xy 100.327225 -240.992702) (xy 100.369846 -240.968095)
			(xy 100.415862 -240.950643) (xy 100.464081 -240.940799) (xy 100.513256 -240.938818) (xy 100.562111 -240.94475)
			(xy 100.609382 -240.958442) (xy 100.653844 -240.97954) (xy 100.694347 -241.007496) (xy 100.72984 -241.041588)
			(xy 100.759405 -241.080932) (xy 100.782276 -241.124509) (xy 100.79786 -241.17119) (xy 100.805755 -241.219767)
			(xy 100.80625 -241.244374) (xy 101.135192 -241.244374) (xy 101.139152 -241.19532) (xy 101.150929 -241.147536)
			(xy 101.17022 -241.10226) (xy 101.196523 -241.060664) (xy 101.229158 -241.023827) (xy 101.267279 -240.992702)
			(xy 101.3099 -240.968095) (xy 101.355916 -240.950643) (xy 101.404135 -240.940799) (xy 101.45331 -240.938818)
			(xy 101.502165 -240.94475) (xy 101.549436 -240.958442) (xy 101.593898 -240.97954) (xy 101.634401 -241.007496)
			(xy 101.669894 -241.041588) (xy 101.699459 -241.080932) (xy 101.72233 -241.124509) (xy 101.737914 -241.17119)
			(xy 101.745809 -241.219767) (xy 101.746304 -241.244374) (xy 102.075246 -241.244374) (xy 102.079206 -241.19532)
			(xy 102.090983 -241.147536) (xy 102.110274 -241.10226) (xy 102.136577 -241.060664) (xy 102.169212 -241.023827)
			(xy 102.207333 -240.992702) (xy 102.249954 -240.968095) (xy 102.29597 -240.950643) (xy 102.344189 -240.940799)
			(xy 102.393364 -240.938818) (xy 102.442219 -240.94475) (xy 102.48949 -240.958442) (xy 102.533952 -240.97954)
			(xy 102.574455 -241.007496) (xy 102.609948 -241.041588) (xy 102.639513 -241.080932) (xy 102.662384 -241.124509)
			(xy 102.677968 -241.17119) (xy 102.685863 -241.219767) (xy 102.686358 -241.244374) (xy 103.0153 -241.244374)
			(xy 103.01926 -241.19532) (xy 103.031037 -241.147536) (xy 103.050328 -241.10226) (xy 103.076631 -241.060664)
			(xy 103.109266 -241.023827) (xy 103.147387 -240.992702) (xy 103.190008 -240.968095) (xy 103.236024 -240.950643)
			(xy 103.284243 -240.940799) (xy 103.333418 -240.938818) (xy 103.382273 -240.94475) (xy 103.429544 -240.958442)
			(xy 103.474006 -240.97954) (xy 103.514509 -241.007496) (xy 103.550002 -241.041588) (xy 103.579567 -241.080932)
			(xy 103.602438 -241.124509) (xy 103.618022 -241.17119) (xy 103.625917 -241.219767) (xy 103.626412 -241.244374)
			(xy 103.955354 -241.244374) (xy 103.959314 -241.19532) (xy 103.971091 -241.147536) (xy 103.990382 -241.10226)
			(xy 104.016685 -241.060664) (xy 104.04932 -241.023827) (xy 104.087441 -240.992702) (xy 104.130062 -240.968095)
			(xy 104.176078 -240.950643) (xy 104.224297 -240.940799) (xy 104.273472 -240.938818) (xy 104.322327 -240.94475)
			(xy 104.369598 -240.958442) (xy 104.41406 -240.97954) (xy 104.454563 -241.007496) (xy 104.490056 -241.041588)
			(xy 104.519621 -241.080932) (xy 104.542492 -241.124509) (xy 104.558076 -241.17119) (xy 104.565971 -241.219767)
			(xy 104.566466 -241.244374) (xy 104.895154 -241.244374) (xy 104.899114 -241.19532) (xy 104.910891 -241.147536)
			(xy 104.930182 -241.10226) (xy 104.956485 -241.060664) (xy 104.98912 -241.023827) (xy 105.027241 -240.992702)
			(xy 105.069862 -240.968095) (xy 105.115878 -240.950643) (xy 105.164097 -240.940799) (xy 105.213272 -240.938818)
			(xy 105.262127 -240.94475) (xy 105.309398 -240.958442) (xy 105.35386 -240.97954) (xy 105.394363 -241.007496)
			(xy 105.429856 -241.041588) (xy 105.459421 -241.080932) (xy 105.482292 -241.124509) (xy 105.497876 -241.17119)
			(xy 105.505771 -241.219767) (xy 105.506266 -241.244374) (xy 105.835208 -241.244374) (xy 105.839168 -241.19532)
			(xy 105.850945 -241.147536) (xy 105.870236 -241.10226) (xy 105.896539 -241.060664) (xy 105.929174 -241.023827)
			(xy 105.967295 -240.992702) (xy 106.009916 -240.968095) (xy 106.055932 -240.950643) (xy 106.104151 -240.940799)
			(xy 106.153326 -240.938818) (xy 106.202181 -240.94475) (xy 106.249452 -240.958442) (xy 106.293914 -240.97954)
			(xy 106.334417 -241.007496) (xy 106.36991 -241.041588) (xy 106.399475 -241.080932) (xy 106.422346 -241.124509)
			(xy 106.43793 -241.17119) (xy 106.445825 -241.219767) (xy 106.44632 -241.244374) (xy 106.775262 -241.244374)
			(xy 106.779222 -241.19532) (xy 106.790999 -241.147536) (xy 106.81029 -241.10226) (xy 106.836593 -241.060664)
			(xy 106.869228 -241.023827) (xy 106.907349 -240.992702) (xy 106.94997 -240.968095) (xy 106.995986 -240.950643)
			(xy 107.044205 -240.940799) (xy 107.09338 -240.938818) (xy 107.142235 -240.94475) (xy 107.189506 -240.958442)
			(xy 107.233968 -240.97954) (xy 107.274471 -241.007496) (xy 107.309964 -241.041588) (xy 107.339529 -241.080932)
			(xy 107.3624 -241.124509) (xy 107.377984 -241.17119) (xy 107.385879 -241.219767) (xy 107.386374 -241.244374)
			(xy 107.715316 -241.244374) (xy 107.719276 -241.19532) (xy 107.731053 -241.147536) (xy 107.750344 -241.10226)
			(xy 107.776647 -241.060664) (xy 107.809282 -241.023827) (xy 107.847403 -240.992702) (xy 107.890024 -240.968095)
			(xy 107.93604 -240.950643) (xy 107.984259 -240.940799) (xy 108.033434 -240.938818) (xy 108.082289 -240.94475)
			(xy 108.12956 -240.958442) (xy 108.174022 -240.97954) (xy 108.214525 -241.007496) (xy 108.250018 -241.041588)
			(xy 108.279583 -241.080932) (xy 108.302454 -241.124509) (xy 108.318038 -241.17119) (xy 108.325933 -241.219767)
			(xy 108.326428 -241.244374) (xy 108.65537 -241.244374) (xy 108.65933 -241.19532) (xy 108.671107 -241.147536)
			(xy 108.690398 -241.10226) (xy 108.716701 -241.060664) (xy 108.749336 -241.023827) (xy 108.787457 -240.992702)
			(xy 108.830078 -240.968095) (xy 108.876094 -240.950643) (xy 108.924313 -240.940799) (xy 108.973488 -240.938818)
			(xy 109.022343 -240.94475) (xy 109.069614 -240.958442) (xy 109.114076 -240.97954) (xy 109.154579 -241.007496)
			(xy 109.190072 -241.041588) (xy 109.219637 -241.080932) (xy 109.242508 -241.124509) (xy 109.258092 -241.17119)
			(xy 109.265987 -241.219767) (xy 109.266482 -241.244374) (xy 109.59517 -241.244374) (xy 109.59913 -241.19532)
			(xy 109.610907 -241.147536) (xy 109.630198 -241.10226) (xy 109.656501 -241.060664) (xy 109.689136 -241.023827)
			(xy 109.727257 -240.992702) (xy 109.769878 -240.968095) (xy 109.815894 -240.950643) (xy 109.864113 -240.940799)
			(xy 109.913288 -240.938818) (xy 109.962143 -240.94475) (xy 110.009414 -240.958442) (xy 110.053876 -240.97954)
			(xy 110.094379 -241.007496) (xy 110.129872 -241.041588) (xy 110.159437 -241.080932) (xy 110.182308 -241.124509)
			(xy 110.197892 -241.17119) (xy 110.205787 -241.219767) (xy 110.206282 -241.244374) (xy 113.349036 -241.244374)
			(xy 113.352996 -241.19532) (xy 113.364773 -241.147536) (xy 113.384064 -241.10226) (xy 113.410367 -241.060664)
			(xy 113.443002 -241.023827) (xy 113.481123 -240.992702) (xy 113.523744 -240.968095) (xy 113.56976 -240.950643)
			(xy 113.617979 -240.940799) (xy 113.667154 -240.938818) (xy 113.716009 -240.94475) (xy 113.76328 -240.958442)
			(xy 113.807742 -240.97954) (xy 113.848245 -241.007496) (xy 113.883738 -241.041588) (xy 113.913303 -241.080932)
			(xy 113.936174 -241.124509) (xy 113.951758 -241.17119) (xy 113.959653 -241.219767) (xy 113.960148 -241.244374)
			(xy 114.288836 -241.244374) (xy 114.292796 -241.19532) (xy 114.304573 -241.147536) (xy 114.323864 -241.10226)
			(xy 114.350167 -241.060664) (xy 114.382802 -241.023827) (xy 114.420923 -240.992702) (xy 114.463544 -240.968095)
			(xy 114.50956 -240.950643) (xy 114.557779 -240.940799) (xy 114.606954 -240.938818) (xy 114.655809 -240.94475)
			(xy 114.70308 -240.958442) (xy 114.747542 -240.97954) (xy 114.788045 -241.007496) (xy 114.823538 -241.041588)
			(xy 114.853103 -241.080932) (xy 114.875974 -241.124509) (xy 114.891558 -241.17119) (xy 114.899453 -241.219767)
			(xy 114.899948 -241.244374) (xy 115.22889 -241.244374) (xy 115.23285 -241.19532) (xy 115.244627 -241.147536)
			(xy 115.263918 -241.10226) (xy 115.290221 -241.060664) (xy 115.322856 -241.023827) (xy 115.360977 -240.992702)
			(xy 115.403598 -240.968095) (xy 115.449614 -240.950643) (xy 115.497833 -240.940799) (xy 115.547008 -240.938818)
			(xy 115.595863 -240.94475) (xy 115.643134 -240.958442) (xy 115.687596 -240.97954) (xy 115.728099 -241.007496)
			(xy 115.763592 -241.041588) (xy 115.793157 -241.080932) (xy 115.816028 -241.124509) (xy 115.831612 -241.17119)
			(xy 115.839507 -241.219767) (xy 115.840002 -241.244374) (xy 116.168944 -241.244374) (xy 116.172904 -241.19532)
			(xy 116.184681 -241.147536) (xy 116.203972 -241.10226) (xy 116.230275 -241.060664) (xy 116.26291 -241.023827)
			(xy 116.301031 -240.992702) (xy 116.343652 -240.968095) (xy 116.389668 -240.950643) (xy 116.437887 -240.940799)
			(xy 116.487062 -240.938818) (xy 116.535917 -240.94475) (xy 116.583188 -240.958442) (xy 116.62765 -240.97954)
			(xy 116.668153 -241.007496) (xy 116.703646 -241.041588) (xy 116.733211 -241.080932) (xy 116.756082 -241.124509)
			(xy 116.771666 -241.17119) (xy 116.779561 -241.219767) (xy 116.780056 -241.244374) (xy 117.108998 -241.244374)
			(xy 117.112958 -241.19532) (xy 117.124735 -241.147536) (xy 117.144026 -241.10226) (xy 117.170329 -241.060664)
			(xy 117.202964 -241.023827) (xy 117.241085 -240.992702) (xy 117.283706 -240.968095) (xy 117.329722 -240.950643)
			(xy 117.377941 -240.940799) (xy 117.427116 -240.938818) (xy 117.475971 -240.94475) (xy 117.523242 -240.958442)
			(xy 117.567704 -240.97954) (xy 117.608207 -241.007496) (xy 117.6437 -241.041588) (xy 117.673265 -241.080932)
			(xy 117.696136 -241.124509) (xy 117.71172 -241.17119) (xy 117.719615 -241.219767) (xy 117.72011 -241.244374)
			(xy 118.049052 -241.244374) (xy 118.053012 -241.19532) (xy 118.064789 -241.147536) (xy 118.08408 -241.10226)
			(xy 118.110383 -241.060664) (xy 118.143018 -241.023827) (xy 118.181139 -240.992702) (xy 118.22376 -240.968095)
			(xy 118.269776 -240.950643) (xy 118.317995 -240.940799) (xy 118.36717 -240.938818) (xy 118.416025 -240.94475)
			(xy 118.463296 -240.958442) (xy 118.507758 -240.97954) (xy 118.548261 -241.007496) (xy 118.583754 -241.041588)
			(xy 118.613319 -241.080932) (xy 118.63619 -241.124509) (xy 118.651774 -241.17119) (xy 118.659669 -241.219767)
			(xy 118.660164 -241.244374) (xy 118.988852 -241.244374) (xy 118.992812 -241.19532) (xy 119.004589 -241.147536)
			(xy 119.02388 -241.10226) (xy 119.050183 -241.060664) (xy 119.082818 -241.023827) (xy 119.120939 -240.992702)
			(xy 119.16356 -240.968095) (xy 119.209576 -240.950643) (xy 119.257795 -240.940799) (xy 119.30697 -240.938818)
			(xy 119.355825 -240.94475) (xy 119.403096 -240.958442) (xy 119.447558 -240.97954) (xy 119.488061 -241.007496)
			(xy 119.523554 -241.041588) (xy 119.553119 -241.080932) (xy 119.57599 -241.124509) (xy 119.591574 -241.17119)
			(xy 119.599469 -241.219767) (xy 119.599964 -241.244374) (xy 119.928906 -241.244374) (xy 119.932866 -241.19532)
			(xy 119.944643 -241.147536) (xy 119.963934 -241.10226) (xy 119.990237 -241.060664) (xy 120.022872 -241.023827)
			(xy 120.060993 -240.992702) (xy 120.103614 -240.968095) (xy 120.14963 -240.950643) (xy 120.197849 -240.940799)
			(xy 120.247024 -240.938818) (xy 120.295879 -240.94475) (xy 120.34315 -240.958442) (xy 120.387612 -240.97954)
			(xy 120.428115 -241.007496) (xy 120.463608 -241.041588) (xy 120.493173 -241.080932) (xy 120.516044 -241.124509)
			(xy 120.531628 -241.17119) (xy 120.539523 -241.219767) (xy 120.540018 -241.244374) (xy 120.86896 -241.244374)
			(xy 120.87292 -241.19532) (xy 120.884697 -241.147536) (xy 120.903988 -241.10226) (xy 120.930291 -241.060664)
			(xy 120.962926 -241.023827) (xy 121.001047 -240.992702) (xy 121.043668 -240.968095) (xy 121.089684 -240.950643)
			(xy 121.137903 -240.940799) (xy 121.187078 -240.938818) (xy 121.235933 -240.94475) (xy 121.283204 -240.958442)
			(xy 121.327666 -240.97954) (xy 121.368169 -241.007496) (xy 121.403662 -241.041588) (xy 121.433227 -241.080932)
			(xy 121.456098 -241.124509) (xy 121.471682 -241.17119) (xy 121.479577 -241.219767) (xy 121.480072 -241.244374)
			(xy 121.809014 -241.244374) (xy 121.812974 -241.19532) (xy 121.824751 -241.147536) (xy 121.844042 -241.10226)
			(xy 121.870345 -241.060664) (xy 121.90298 -241.023827) (xy 121.941101 -240.992702) (xy 121.983722 -240.968095)
			(xy 122.029738 -240.950643) (xy 122.077957 -240.940799) (xy 122.127132 -240.938818) (xy 122.175987 -240.94475)
			(xy 122.223258 -240.958442) (xy 122.26772 -240.97954) (xy 122.308223 -241.007496) (xy 122.343716 -241.041588)
			(xy 122.373281 -241.080932) (xy 122.396152 -241.124509) (xy 122.411736 -241.17119) (xy 122.419631 -241.219767)
			(xy 122.420126 -241.244374) (xy 122.748814 -241.244374) (xy 122.752774 -241.19532) (xy 122.764551 -241.147536)
			(xy 122.783842 -241.10226) (xy 122.810145 -241.060664) (xy 122.84278 -241.023827) (xy 122.880901 -240.992702)
			(xy 122.923522 -240.968095) (xy 122.969538 -240.950643) (xy 123.017757 -240.940799) (xy 123.066932 -240.938818)
			(xy 123.115787 -240.94475) (xy 123.163058 -240.958442) (xy 123.20752 -240.97954) (xy 123.248023 -241.007496)
			(xy 123.283516 -241.041588) (xy 123.313081 -241.080932) (xy 123.335952 -241.124509) (xy 123.351536 -241.17119)
			(xy 123.359431 -241.219767) (xy 123.359926 -241.244374) (xy 123.688868 -241.244374) (xy 123.692828 -241.19532)
			(xy 123.704605 -241.147536) (xy 123.723896 -241.10226) (xy 123.750199 -241.060664) (xy 123.782834 -241.023827)
			(xy 123.820955 -240.992702) (xy 123.863576 -240.968095) (xy 123.909592 -240.950643) (xy 123.957811 -240.940799)
			(xy 124.006986 -240.938818) (xy 124.055841 -240.94475) (xy 124.103112 -240.958442) (xy 124.147574 -240.97954)
			(xy 124.188077 -241.007496) (xy 124.22357 -241.041588) (xy 124.253135 -241.080932) (xy 124.276006 -241.124509)
			(xy 124.29159 -241.17119) (xy 124.299485 -241.219767) (xy 124.29998 -241.244374) (xy 124.628922 -241.244374)
			(xy 124.632882 -241.19532) (xy 124.644659 -241.147536) (xy 124.66395 -241.10226) (xy 124.690253 -241.060664)
			(xy 124.722888 -241.023827) (xy 124.761009 -240.992702) (xy 124.80363 -240.968095) (xy 124.849646 -240.950643)
			(xy 124.897865 -240.940799) (xy 124.94704 -240.938818) (xy 124.995895 -240.94475) (xy 125.043166 -240.958442)
			(xy 125.087628 -240.97954) (xy 125.128131 -241.007496) (xy 125.163624 -241.041588) (xy 125.193189 -241.080932)
			(xy 125.21606 -241.124509) (xy 125.231644 -241.17119) (xy 125.239539 -241.219767) (xy 125.240034 -241.244374)
			(xy 125.568976 -241.244374) (xy 125.572936 -241.19532) (xy 125.584713 -241.147536) (xy 125.604004 -241.10226)
			(xy 125.630307 -241.060664) (xy 125.662942 -241.023827) (xy 125.701063 -240.992702) (xy 125.743684 -240.968095)
			(xy 125.7897 -240.950643) (xy 125.837919 -240.940799) (xy 125.887094 -240.938818) (xy 125.935949 -240.94475)
			(xy 125.98322 -240.958442) (xy 126.027682 -240.97954) (xy 126.068185 -241.007496) (xy 126.103678 -241.041588)
			(xy 126.133243 -241.080932) (xy 126.156114 -241.124509) (xy 126.171698 -241.17119) (xy 126.179593 -241.219767)
			(xy 126.180088 -241.244374) (xy 126.179593 -241.268981) (xy 126.171698 -241.317558) (xy 126.156114 -241.364239)
			(xy 126.133243 -241.407816) (xy 126.103678 -241.44716) (xy 126.068185 -241.481252) (xy 126.027682 -241.509208)
			(xy 125.98322 -241.530306) (xy 125.935949 -241.543998) (xy 125.887094 -241.54993) (xy 125.837919 -241.547949)
			(xy 125.7897 -241.538105) (xy 125.743684 -241.520653) (xy 125.701063 -241.496046) (xy 125.662942 -241.464921)
			(xy 125.630307 -241.428084) (xy 125.604004 -241.386488) (xy 125.584713 -241.341212) (xy 125.572936 -241.293428)
			(xy 125.568976 -241.244374) (xy 125.240034 -241.244374) (xy 125.239539 -241.268981) (xy 125.231644 -241.317558)
			(xy 125.21606 -241.364239) (xy 125.193189 -241.407816) (xy 125.163624 -241.44716) (xy 125.128131 -241.481252)
			(xy 125.087628 -241.509208) (xy 125.043166 -241.530306) (xy 124.995895 -241.543998) (xy 124.94704 -241.54993)
			(xy 124.897865 -241.547949) (xy 124.849646 -241.538105) (xy 124.80363 -241.520653) (xy 124.761009 -241.496046)
			(xy 124.722888 -241.464921) (xy 124.690253 -241.428084) (xy 124.66395 -241.386488) (xy 124.644659 -241.341212)
			(xy 124.632882 -241.293428) (xy 124.628922 -241.244374) (xy 124.29998 -241.244374) (xy 124.299485 -241.268981)
			(xy 124.29159 -241.317558) (xy 124.276006 -241.364239) (xy 124.253135 -241.407816) (xy 124.22357 -241.44716)
			(xy 124.188077 -241.481252) (xy 124.147574 -241.509208) (xy 124.103112 -241.530306) (xy 124.055841 -241.543998)
			(xy 124.006986 -241.54993) (xy 123.957811 -241.547949) (xy 123.909592 -241.538105) (xy 123.863576 -241.520653)
			(xy 123.820955 -241.496046) (xy 123.782834 -241.464921) (xy 123.750199 -241.428084) (xy 123.723896 -241.386488)
			(xy 123.704605 -241.341212) (xy 123.692828 -241.293428) (xy 123.688868 -241.244374) (xy 123.359926 -241.244374)
			(xy 123.359431 -241.268981) (xy 123.351536 -241.317558) (xy 123.335952 -241.364239) (xy 123.313081 -241.407816)
			(xy 123.283516 -241.44716) (xy 123.248023 -241.481252) (xy 123.20752 -241.509208) (xy 123.163058 -241.530306)
			(xy 123.115787 -241.543998) (xy 123.066932 -241.54993) (xy 123.017757 -241.547949) (xy 122.969538 -241.538105)
			(xy 122.923522 -241.520653) (xy 122.880901 -241.496046) (xy 122.84278 -241.464921) (xy 122.810145 -241.428084)
			(xy 122.783842 -241.386488) (xy 122.764551 -241.341212) (xy 122.752774 -241.293428) (xy 122.748814 -241.244374)
			(xy 122.420126 -241.244374) (xy 122.419631 -241.268981) (xy 122.411736 -241.317558) (xy 122.396152 -241.364239)
			(xy 122.373281 -241.407816) (xy 122.343716 -241.44716) (xy 122.308223 -241.481252) (xy 122.26772 -241.509208)
			(xy 122.223258 -241.530306) (xy 122.175987 -241.543998) (xy 122.127132 -241.54993) (xy 122.077957 -241.547949)
			(xy 122.029738 -241.538105) (xy 121.983722 -241.520653) (xy 121.941101 -241.496046) (xy 121.90298 -241.464921)
			(xy 121.870345 -241.428084) (xy 121.844042 -241.386488) (xy 121.824751 -241.341212) (xy 121.812974 -241.293428)
			(xy 121.809014 -241.244374) (xy 121.480072 -241.244374) (xy 121.479577 -241.268981) (xy 121.471682 -241.317558)
			(xy 121.456098 -241.364239) (xy 121.433227 -241.407816) (xy 121.403662 -241.44716) (xy 121.368169 -241.481252)
			(xy 121.327666 -241.509208) (xy 121.283204 -241.530306) (xy 121.235933 -241.543998) (xy 121.187078 -241.54993)
			(xy 121.137903 -241.547949) (xy 121.089684 -241.538105) (xy 121.043668 -241.520653) (xy 121.001047 -241.496046)
			(xy 120.962926 -241.464921) (xy 120.930291 -241.428084) (xy 120.903988 -241.386488) (xy 120.884697 -241.341212)
			(xy 120.87292 -241.293428) (xy 120.86896 -241.244374) (xy 120.540018 -241.244374) (xy 120.539523 -241.268981)
			(xy 120.531628 -241.317558) (xy 120.516044 -241.364239) (xy 120.493173 -241.407816) (xy 120.463608 -241.44716)
			(xy 120.428115 -241.481252) (xy 120.387612 -241.509208) (xy 120.34315 -241.530306) (xy 120.295879 -241.543998)
			(xy 120.247024 -241.54993) (xy 120.197849 -241.547949) (xy 120.14963 -241.538105) (xy 120.103614 -241.520653)
			(xy 120.060993 -241.496046) (xy 120.022872 -241.464921) (xy 119.990237 -241.428084) (xy 119.963934 -241.386488)
			(xy 119.944643 -241.341212) (xy 119.932866 -241.293428) (xy 119.928906 -241.244374) (xy 119.599964 -241.244374)
			(xy 119.599469 -241.268981) (xy 119.591574 -241.317558) (xy 119.57599 -241.364239) (xy 119.553119 -241.407816)
			(xy 119.523554 -241.44716) (xy 119.488061 -241.481252) (xy 119.447558 -241.509208) (xy 119.403096 -241.530306)
			(xy 119.355825 -241.543998) (xy 119.30697 -241.54993) (xy 119.257795 -241.547949) (xy 119.209576 -241.538105)
			(xy 119.16356 -241.520653) (xy 119.120939 -241.496046) (xy 119.082818 -241.464921) (xy 119.050183 -241.428084)
			(xy 119.02388 -241.386488) (xy 119.004589 -241.341212) (xy 118.992812 -241.293428) (xy 118.988852 -241.244374)
			(xy 118.660164 -241.244374) (xy 118.659669 -241.268981) (xy 118.651774 -241.317558) (xy 118.63619 -241.364239)
			(xy 118.613319 -241.407816) (xy 118.583754 -241.44716) (xy 118.548261 -241.481252) (xy 118.507758 -241.509208)
			(xy 118.463296 -241.530306) (xy 118.416025 -241.543998) (xy 118.36717 -241.54993) (xy 118.317995 -241.547949)
			(xy 118.269776 -241.538105) (xy 118.22376 -241.520653) (xy 118.181139 -241.496046) (xy 118.143018 -241.464921)
			(xy 118.110383 -241.428084) (xy 118.08408 -241.386488) (xy 118.064789 -241.341212) (xy 118.053012 -241.293428)
			(xy 118.049052 -241.244374) (xy 117.72011 -241.244374) (xy 117.719615 -241.268981) (xy 117.71172 -241.317558)
			(xy 117.696136 -241.364239) (xy 117.673265 -241.407816) (xy 117.6437 -241.44716) (xy 117.608207 -241.481252)
			(xy 117.567704 -241.509208) (xy 117.523242 -241.530306) (xy 117.475971 -241.543998) (xy 117.427116 -241.54993)
			(xy 117.377941 -241.547949) (xy 117.329722 -241.538105) (xy 117.283706 -241.520653) (xy 117.241085 -241.496046)
			(xy 117.202964 -241.464921) (xy 117.170329 -241.428084) (xy 117.144026 -241.386488) (xy 117.124735 -241.341212)
			(xy 117.112958 -241.293428) (xy 117.108998 -241.244374) (xy 116.780056 -241.244374) (xy 116.779561 -241.268981)
			(xy 116.771666 -241.317558) (xy 116.756082 -241.364239) (xy 116.733211 -241.407816) (xy 116.703646 -241.44716)
			(xy 116.668153 -241.481252) (xy 116.62765 -241.509208) (xy 116.583188 -241.530306) (xy 116.535917 -241.543998)
			(xy 116.487062 -241.54993) (xy 116.437887 -241.547949) (xy 116.389668 -241.538105) (xy 116.343652 -241.520653)
			(xy 116.301031 -241.496046) (xy 116.26291 -241.464921) (xy 116.230275 -241.428084) (xy 116.203972 -241.386488)
			(xy 116.184681 -241.341212) (xy 116.172904 -241.293428) (xy 116.168944 -241.244374) (xy 115.840002 -241.244374)
			(xy 115.839507 -241.268981) (xy 115.831612 -241.317558) (xy 115.816028 -241.364239) (xy 115.793157 -241.407816)
			(xy 115.763592 -241.44716) (xy 115.728099 -241.481252) (xy 115.687596 -241.509208) (xy 115.643134 -241.530306)
			(xy 115.595863 -241.543998) (xy 115.547008 -241.54993) (xy 115.497833 -241.547949) (xy 115.449614 -241.538105)
			(xy 115.403598 -241.520653) (xy 115.360977 -241.496046) (xy 115.322856 -241.464921) (xy 115.290221 -241.428084)
			(xy 115.263918 -241.386488) (xy 115.244627 -241.341212) (xy 115.23285 -241.293428) (xy 115.22889 -241.244374)
			(xy 114.899948 -241.244374) (xy 114.899453 -241.268981) (xy 114.891558 -241.317558) (xy 114.875974 -241.364239)
			(xy 114.853103 -241.407816) (xy 114.823538 -241.44716) (xy 114.788045 -241.481252) (xy 114.747542 -241.509208)
			(xy 114.70308 -241.530306) (xy 114.655809 -241.543998) (xy 114.606954 -241.54993) (xy 114.557779 -241.547949)
			(xy 114.50956 -241.538105) (xy 114.463544 -241.520653) (xy 114.420923 -241.496046) (xy 114.382802 -241.464921)
			(xy 114.350167 -241.428084) (xy 114.323864 -241.386488) (xy 114.304573 -241.341212) (xy 114.292796 -241.293428)
			(xy 114.288836 -241.244374) (xy 113.960148 -241.244374) (xy 113.959653 -241.268981) (xy 113.951758 -241.317558)
			(xy 113.936174 -241.364239) (xy 113.913303 -241.407816) (xy 113.883738 -241.44716) (xy 113.848245 -241.481252)
			(xy 113.807742 -241.509208) (xy 113.76328 -241.530306) (xy 113.716009 -241.543998) (xy 113.667154 -241.54993)
			(xy 113.617979 -241.547949) (xy 113.56976 -241.538105) (xy 113.523744 -241.520653) (xy 113.481123 -241.496046)
			(xy 113.443002 -241.464921) (xy 113.410367 -241.428084) (xy 113.384064 -241.386488) (xy 113.364773 -241.341212)
			(xy 113.352996 -241.293428) (xy 113.349036 -241.244374) (xy 110.206282 -241.244374) (xy 110.205787 -241.268981)
			(xy 110.197892 -241.317558) (xy 110.182308 -241.364239) (xy 110.159437 -241.407816) (xy 110.129872 -241.44716)
			(xy 110.094379 -241.481252) (xy 110.053876 -241.509208) (xy 110.009414 -241.530306) (xy 109.962143 -241.543998)
			(xy 109.913288 -241.54993) (xy 109.864113 -241.547949) (xy 109.815894 -241.538105) (xy 109.769878 -241.520653)
			(xy 109.727257 -241.496046) (xy 109.689136 -241.464921) (xy 109.656501 -241.428084) (xy 109.630198 -241.386488)
			(xy 109.610907 -241.341212) (xy 109.59913 -241.293428) (xy 109.59517 -241.244374) (xy 109.266482 -241.244374)
			(xy 109.265987 -241.268981) (xy 109.258092 -241.317558) (xy 109.242508 -241.364239) (xy 109.219637 -241.407816)
			(xy 109.190072 -241.44716) (xy 109.154579 -241.481252) (xy 109.114076 -241.509208) (xy 109.069614 -241.530306)
			(xy 109.022343 -241.543998) (xy 108.973488 -241.54993) (xy 108.924313 -241.547949) (xy 108.876094 -241.538105)
			(xy 108.830078 -241.520653) (xy 108.787457 -241.496046) (xy 108.749336 -241.464921) (xy 108.716701 -241.428084)
			(xy 108.690398 -241.386488) (xy 108.671107 -241.341212) (xy 108.65933 -241.293428) (xy 108.65537 -241.244374)
			(xy 108.326428 -241.244374) (xy 108.325933 -241.268981) (xy 108.318038 -241.317558) (xy 108.302454 -241.364239)
			(xy 108.279583 -241.407816) (xy 108.250018 -241.44716) (xy 108.214525 -241.481252) (xy 108.174022 -241.509208)
			(xy 108.12956 -241.530306) (xy 108.082289 -241.543998) (xy 108.033434 -241.54993) (xy 107.984259 -241.547949)
			(xy 107.93604 -241.538105) (xy 107.890024 -241.520653) (xy 107.847403 -241.496046) (xy 107.809282 -241.464921)
			(xy 107.776647 -241.428084) (xy 107.750344 -241.386488) (xy 107.731053 -241.341212) (xy 107.719276 -241.293428)
			(xy 107.715316 -241.244374) (xy 107.386374 -241.244374) (xy 107.385879 -241.268981) (xy 107.377984 -241.317558)
			(xy 107.3624 -241.364239) (xy 107.339529 -241.407816) (xy 107.309964 -241.44716) (xy 107.274471 -241.481252)
			(xy 107.233968 -241.509208) (xy 107.189506 -241.530306) (xy 107.142235 -241.543998) (xy 107.09338 -241.54993)
			(xy 107.044205 -241.547949) (xy 106.995986 -241.538105) (xy 106.94997 -241.520653) (xy 106.907349 -241.496046)
			(xy 106.869228 -241.464921) (xy 106.836593 -241.428084) (xy 106.81029 -241.386488) (xy 106.790999 -241.341212)
			(xy 106.779222 -241.293428) (xy 106.775262 -241.244374) (xy 106.44632 -241.244374) (xy 106.445825 -241.268981)
			(xy 106.43793 -241.317558) (xy 106.422346 -241.364239) (xy 106.399475 -241.407816) (xy 106.36991 -241.44716)
			(xy 106.334417 -241.481252) (xy 106.293914 -241.509208) (xy 106.249452 -241.530306) (xy 106.202181 -241.543998)
			(xy 106.153326 -241.54993) (xy 106.104151 -241.547949) (xy 106.055932 -241.538105) (xy 106.009916 -241.520653)
			(xy 105.967295 -241.496046) (xy 105.929174 -241.464921) (xy 105.896539 -241.428084) (xy 105.870236 -241.386488)
			(xy 105.850945 -241.341212) (xy 105.839168 -241.293428) (xy 105.835208 -241.244374) (xy 105.506266 -241.244374)
			(xy 105.505771 -241.268981) (xy 105.497876 -241.317558) (xy 105.482292 -241.364239) (xy 105.459421 -241.407816)
			(xy 105.429856 -241.44716) (xy 105.394363 -241.481252) (xy 105.35386 -241.509208) (xy 105.309398 -241.530306)
			(xy 105.262127 -241.543998) (xy 105.213272 -241.54993) (xy 105.164097 -241.547949) (xy 105.115878 -241.538105)
			(xy 105.069862 -241.520653) (xy 105.027241 -241.496046) (xy 104.98912 -241.464921) (xy 104.956485 -241.428084)
			(xy 104.930182 -241.386488) (xy 104.910891 -241.341212) (xy 104.899114 -241.293428) (xy 104.895154 -241.244374)
			(xy 104.566466 -241.244374) (xy 104.565971 -241.268981) (xy 104.558076 -241.317558) (xy 104.542492 -241.364239)
			(xy 104.519621 -241.407816) (xy 104.490056 -241.44716) (xy 104.454563 -241.481252) (xy 104.41406 -241.509208)
			(xy 104.369598 -241.530306) (xy 104.322327 -241.543998) (xy 104.273472 -241.54993) (xy 104.224297 -241.547949)
			(xy 104.176078 -241.538105) (xy 104.130062 -241.520653) (xy 104.087441 -241.496046) (xy 104.04932 -241.464921)
			(xy 104.016685 -241.428084) (xy 103.990382 -241.386488) (xy 103.971091 -241.341212) (xy 103.959314 -241.293428)
			(xy 103.955354 -241.244374) (xy 103.626412 -241.244374) (xy 103.625917 -241.268981) (xy 103.618022 -241.317558)
			(xy 103.602438 -241.364239) (xy 103.579567 -241.407816) (xy 103.550002 -241.44716) (xy 103.514509 -241.481252)
			(xy 103.474006 -241.509208) (xy 103.429544 -241.530306) (xy 103.382273 -241.543998) (xy 103.333418 -241.54993)
			(xy 103.284243 -241.547949) (xy 103.236024 -241.538105) (xy 103.190008 -241.520653) (xy 103.147387 -241.496046)
			(xy 103.109266 -241.464921) (xy 103.076631 -241.428084) (xy 103.050328 -241.386488) (xy 103.031037 -241.341212)
			(xy 103.01926 -241.293428) (xy 103.0153 -241.244374) (xy 102.686358 -241.244374) (xy 102.685863 -241.268981)
			(xy 102.677968 -241.317558) (xy 102.662384 -241.364239) (xy 102.639513 -241.407816) (xy 102.609948 -241.44716)
			(xy 102.574455 -241.481252) (xy 102.533952 -241.509208) (xy 102.48949 -241.530306) (xy 102.442219 -241.543998)
			(xy 102.393364 -241.54993) (xy 102.344189 -241.547949) (xy 102.29597 -241.538105) (xy 102.249954 -241.520653)
			(xy 102.207333 -241.496046) (xy 102.169212 -241.464921) (xy 102.136577 -241.428084) (xy 102.110274 -241.386488)
			(xy 102.090983 -241.341212) (xy 102.079206 -241.293428) (xy 102.075246 -241.244374) (xy 101.746304 -241.244374)
			(xy 101.745809 -241.268981) (xy 101.737914 -241.317558) (xy 101.72233 -241.364239) (xy 101.699459 -241.407816)
			(xy 101.669894 -241.44716) (xy 101.634401 -241.481252) (xy 101.593898 -241.509208) (xy 101.549436 -241.530306)
			(xy 101.502165 -241.543998) (xy 101.45331 -241.54993) (xy 101.404135 -241.547949) (xy 101.355916 -241.538105)
			(xy 101.3099 -241.520653) (xy 101.267279 -241.496046) (xy 101.229158 -241.464921) (xy 101.196523 -241.428084)
			(xy 101.17022 -241.386488) (xy 101.150929 -241.341212) (xy 101.139152 -241.293428) (xy 101.135192 -241.244374)
			(xy 100.80625 -241.244374) (xy 100.805755 -241.268981) (xy 100.79786 -241.317558) (xy 100.782276 -241.364239)
			(xy 100.759405 -241.407816) (xy 100.72984 -241.44716) (xy 100.694347 -241.481252) (xy 100.653844 -241.509208)
			(xy 100.609382 -241.530306) (xy 100.562111 -241.543998) (xy 100.513256 -241.54993) (xy 100.464081 -241.547949)
			(xy 100.415862 -241.538105) (xy 100.369846 -241.520653) (xy 100.327225 -241.496046) (xy 100.289104 -241.464921)
			(xy 100.256469 -241.428084) (xy 100.230166 -241.386488) (xy 100.210875 -241.341212) (xy 100.199098 -241.293428)
			(xy 100.195138 -241.244374) (xy 99.86645 -241.244374) (xy 99.865955 -241.268981) (xy 99.85806 -241.317558)
			(xy 99.842476 -241.364239) (xy 99.819605 -241.407816) (xy 99.79004 -241.44716) (xy 99.754547 -241.481252)
			(xy 99.714044 -241.509208) (xy 99.669582 -241.530306) (xy 99.622311 -241.543998) (xy 99.573456 -241.54993)
			(xy 99.524281 -241.547949) (xy 99.476062 -241.538105) (xy 99.430046 -241.520653) (xy 99.387425 -241.496046)
			(xy 99.349304 -241.464921) (xy 99.316669 -241.428084) (xy 99.290366 -241.386488) (xy 99.271075 -241.341212)
			(xy 99.259298 -241.293428) (xy 99.255338 -241.244374) (xy 98.926396 -241.244374) (xy 98.925901 -241.268981)
			(xy 98.918006 -241.317558) (xy 98.902422 -241.364239) (xy 98.879551 -241.407816) (xy 98.849986 -241.44716)
			(xy 98.814493 -241.481252) (xy 98.77399 -241.509208) (xy 98.729528 -241.530306) (xy 98.682257 -241.543998)
			(xy 98.633402 -241.54993) (xy 98.584227 -241.547949) (xy 98.536008 -241.538105) (xy 98.489992 -241.520653)
			(xy 98.447371 -241.496046) (xy 98.40925 -241.464921) (xy 98.376615 -241.428084) (xy 98.350312 -241.386488)
			(xy 98.331021 -241.341212) (xy 98.319244 -241.293428) (xy 98.315284 -241.244374) (xy 97.986342 -241.244374)
			(xy 97.985847 -241.268981) (xy 97.977952 -241.317558) (xy 97.962368 -241.364239) (xy 97.939497 -241.407816)
			(xy 97.909932 -241.44716) (xy 97.874439 -241.481252) (xy 97.833936 -241.509208) (xy 97.789474 -241.530306)
			(xy 97.742203 -241.543998) (xy 97.693348 -241.54993) (xy 97.644173 -241.547949) (xy 97.595954 -241.538105)
			(xy 97.549938 -241.520653) (xy 97.507317 -241.496046) (xy 97.469196 -241.464921) (xy 97.436561 -241.428084)
			(xy 97.410258 -241.386488) (xy 97.390967 -241.341212) (xy 97.37919 -241.293428) (xy 97.37523 -241.244374)
			(xy 97.046884 -241.244374) (xy 97.046886 -241.2444) (xy 97.042714 -241.294749) (xy 97.030311 -241.343725)
			(xy 97.010016 -241.389991) (xy 96.982382 -241.432286) (xy 96.948163 -241.469455) (xy 96.908293 -241.500484)
			(xy 96.863859 -241.524528) (xy 96.816074 -241.54093) (xy 96.766241 -241.549243) (xy 96.74098 -241.549682)
			(xy 96.717213 -241.549234) (xy 96.670254 -241.541874) (xy 96.625004 -241.527321) (xy 96.582559 -241.505925)
			(xy 96.543945 -241.478206) (xy 96.510098 -241.444833) (xy 96.495616 -241.425984) (xy 96.490536 -241.419126)
			(xy 96.48698 -241.414554) (xy 96.474788 -241.409474) (xy 96.468505 -241.406949) (xy 96.455111 -241.405007)
			(xy 96.448372 -241.405664) (xy 96.361758 -241.417094) (xy 96.355083 -241.418145) (xy 96.342591 -241.423289)
			(xy 96.33712 -241.427254) (xy 96.326452 -241.435636) (xy 96.323658 -241.443256) (xy 96.321626 -241.448336)
			(xy 96.308164 -241.479578) (xy 96.302017 -241.492703) (xy 96.288549 -241.51837) (xy 96.28124 -241.530886)
			(xy 96.280986 -241.53114) (xy 96.27743 -241.537236) (xy 96.275652 -241.543332) (xy 96.273874 -241.556794)
			(xy 96.273874 -241.70259) (xy 96.274252 -241.711693) (xy 96.280635 -241.728743) (xy 96.28632 -241.735864)
			(xy 96.291908 -241.742214) (xy 96.307402 -241.75085) (xy 96.317054 -241.752374) (xy 96.340799 -241.756468)
			(xy 96.386692 -241.771147) (xy 96.429712 -241.792847) (xy 96.468793 -241.82103) (xy 96.502967 -241.854997)
			(xy 96.531386 -241.893907) (xy 96.553346 -241.936794) (xy 96.568302 -241.982597) (xy 96.575884 -242.03018)
			(xy 96.575895 -242.05438) (xy 98.785184 -242.05438) (xy 98.789144 -242.005326) (xy 98.800921 -241.957542)
			(xy 98.820212 -241.912266) (xy 98.846515 -241.87067) (xy 98.87915 -241.833833) (xy 98.917271 -241.802708)
			(xy 98.959892 -241.778101) (xy 99.005908 -241.760649) (xy 99.054127 -241.750805) (xy 99.103302 -241.748824)
			(xy 99.152157 -241.754756) (xy 99.199428 -241.768448) (xy 99.24389 -241.789546) (xy 99.284393 -241.817502)
			(xy 99.319886 -241.851594) (xy 99.349451 -241.890938) (xy 99.372322 -241.934515) (xy 99.387906 -241.981196)
			(xy 99.395801 -242.029773) (xy 99.396296 -242.05438) (xy 101.605346 -242.05438) (xy 101.609306 -242.005326)
			(xy 101.621083 -241.957542) (xy 101.640374 -241.912266) (xy 101.666677 -241.87067) (xy 101.699312 -241.833833)
			(xy 101.737433 -241.802708) (xy 101.780054 -241.778101) (xy 101.82607 -241.760649) (xy 101.874289 -241.750805)
			(xy 101.923464 -241.748824) (xy 101.972319 -241.754756) (xy 102.01959 -241.768448) (xy 102.064052 -241.789546)
			(xy 102.104555 -241.817502) (xy 102.140048 -241.851594) (xy 102.169613 -241.890938) (xy 102.192484 -241.934515)
			(xy 102.208068 -241.981196) (xy 102.215963 -242.029773) (xy 102.216458 -242.05438) (xy 104.425254 -242.05438)
			(xy 104.429214 -242.005326) (xy 104.440991 -241.957542) (xy 104.460282 -241.912266) (xy 104.486585 -241.87067)
			(xy 104.51922 -241.833833) (xy 104.557341 -241.802708) (xy 104.599962 -241.778101) (xy 104.645978 -241.760649)
			(xy 104.694197 -241.750805) (xy 104.743372 -241.748824) (xy 104.792227 -241.754756) (xy 104.839498 -241.768448)
			(xy 104.88396 -241.789546) (xy 104.924463 -241.817502) (xy 104.959956 -241.851594) (xy 104.989521 -241.890938)
			(xy 105.012392 -241.934515) (xy 105.027976 -241.981196) (xy 105.035871 -242.029773) (xy 105.036366 -242.05438)
			(xy 107.245162 -242.05438) (xy 107.249122 -242.005326) (xy 107.260899 -241.957542) (xy 107.28019 -241.912266)
			(xy 107.306493 -241.87067) (xy 107.339128 -241.833833) (xy 107.377249 -241.802708) (xy 107.41987 -241.778101)
			(xy 107.465886 -241.760649) (xy 107.514105 -241.750805) (xy 107.56328 -241.748824) (xy 107.612135 -241.754756)
			(xy 107.659406 -241.768448) (xy 107.703868 -241.789546) (xy 107.744371 -241.817502) (xy 107.779864 -241.851594)
			(xy 107.809429 -241.890938) (xy 107.8323 -241.934515) (xy 107.847884 -241.981196) (xy 107.855779 -242.029773)
			(xy 107.856274 -242.05438) (xy 108.185216 -242.05438) (xy 108.189176 -242.005326) (xy 108.200953 -241.957542)
			(xy 108.220244 -241.912266) (xy 108.246547 -241.87067) (xy 108.279182 -241.833833) (xy 108.317303 -241.802708)
			(xy 108.359924 -241.778101) (xy 108.40594 -241.760649) (xy 108.454159 -241.750805) (xy 108.503334 -241.748824)
			(xy 108.552189 -241.754756) (xy 108.59946 -241.768448) (xy 108.643922 -241.789546) (xy 108.684425 -241.817502)
			(xy 108.719918 -241.851594) (xy 108.749483 -241.890938) (xy 108.772354 -241.934515) (xy 108.787938 -241.981196)
			(xy 108.795833 -242.029773) (xy 108.796328 -242.05438) (xy 109.12527 -242.05438) (xy 109.12923 -242.005326)
			(xy 109.141007 -241.957542) (xy 109.160298 -241.912266) (xy 109.186601 -241.87067) (xy 109.219236 -241.833833)
			(xy 109.257357 -241.802708) (xy 109.299978 -241.778101) (xy 109.345994 -241.760649) (xy 109.394213 -241.750805)
			(xy 109.443388 -241.748824) (xy 109.492243 -241.754756) (xy 109.539514 -241.768448) (xy 109.583976 -241.789546)
			(xy 109.624479 -241.817502) (xy 109.659972 -241.851594) (xy 109.689537 -241.890938) (xy 109.712408 -241.934515)
			(xy 109.727992 -241.981196) (xy 109.735887 -242.029773) (xy 109.736382 -242.05438) (xy 110.065324 -242.05438)
			(xy 110.069284 -242.005326) (xy 110.081061 -241.957542) (xy 110.100352 -241.912266) (xy 110.126655 -241.87067)
			(xy 110.15929 -241.833833) (xy 110.197411 -241.802708) (xy 110.240032 -241.778101) (xy 110.286048 -241.760649)
			(xy 110.334267 -241.750805) (xy 110.383442 -241.748824) (xy 110.432297 -241.754756) (xy 110.479568 -241.768448)
			(xy 110.52403 -241.789546) (xy 110.564533 -241.817502) (xy 110.600026 -241.851594) (xy 110.629591 -241.890938)
			(xy 110.652462 -241.934515) (xy 110.668046 -241.981196) (xy 110.675941 -242.029773) (xy 110.676436 -242.05438)
			(xy 112.878882 -242.05438) (xy 112.882842 -242.005326) (xy 112.894619 -241.957542) (xy 112.91391 -241.912266)
			(xy 112.940213 -241.87067) (xy 112.972848 -241.833833) (xy 113.010969 -241.802708) (xy 113.05359 -241.778101)
			(xy 113.099606 -241.760649) (xy 113.147825 -241.750805) (xy 113.197 -241.748824) (xy 113.245855 -241.754756)
			(xy 113.293126 -241.768448) (xy 113.337588 -241.789546) (xy 113.378091 -241.817502) (xy 113.413584 -241.851594)
			(xy 113.443149 -241.890938) (xy 113.46602 -241.934515) (xy 113.481604 -241.981196) (xy 113.489499 -242.029773)
			(xy 113.489994 -242.05438) (xy 113.818936 -242.05438) (xy 113.822896 -242.005326) (xy 113.834673 -241.957542)
			(xy 113.853964 -241.912266) (xy 113.880267 -241.87067) (xy 113.912902 -241.833833) (xy 113.951023 -241.802708)
			(xy 113.993644 -241.778101) (xy 114.03966 -241.760649) (xy 114.087879 -241.750805) (xy 114.137054 -241.748824)
			(xy 114.185909 -241.754756) (xy 114.23318 -241.768448) (xy 114.277642 -241.789546) (xy 114.318145 -241.817502)
			(xy 114.353638 -241.851594) (xy 114.383203 -241.890938) (xy 114.406074 -241.934515) (xy 114.421658 -241.981196)
			(xy 114.429553 -242.029773) (xy 114.430048 -242.05438) (xy 114.75899 -242.05438) (xy 114.76295 -242.005326)
			(xy 114.774727 -241.957542) (xy 114.794018 -241.912266) (xy 114.820321 -241.87067) (xy 114.852956 -241.833833)
			(xy 114.891077 -241.802708) (xy 114.933698 -241.778101) (xy 114.979714 -241.760649) (xy 115.027933 -241.750805)
			(xy 115.077108 -241.748824) (xy 115.125963 -241.754756) (xy 115.173234 -241.768448) (xy 115.217696 -241.789546)
			(xy 115.258199 -241.817502) (xy 115.293692 -241.851594) (xy 115.323257 -241.890938) (xy 115.346128 -241.934515)
			(xy 115.361712 -241.981196) (xy 115.369607 -242.029773) (xy 115.370102 -242.05438) (xy 115.699044 -242.05438)
			(xy 115.703004 -242.005326) (xy 115.714781 -241.957542) (xy 115.734072 -241.912266) (xy 115.760375 -241.87067)
			(xy 115.79301 -241.833833) (xy 115.831131 -241.802708) (xy 115.873752 -241.778101) (xy 115.919768 -241.760649)
			(xy 115.967987 -241.750805) (xy 116.017162 -241.748824) (xy 116.066017 -241.754756) (xy 116.113288 -241.768448)
			(xy 116.15775 -241.789546) (xy 116.198253 -241.817502) (xy 116.233746 -241.851594) (xy 116.263311 -241.890938)
			(xy 116.286182 -241.934515) (xy 116.301766 -241.981196) (xy 116.309661 -242.029773) (xy 116.310156 -242.05438)
			(xy 118.518952 -242.05438) (xy 118.522912 -242.005326) (xy 118.534689 -241.957542) (xy 118.55398 -241.912266)
			(xy 118.580283 -241.87067) (xy 118.612918 -241.833833) (xy 118.651039 -241.802708) (xy 118.69366 -241.778101)
			(xy 118.739676 -241.760649) (xy 118.787895 -241.750805) (xy 118.83707 -241.748824) (xy 118.885925 -241.754756)
			(xy 118.933196 -241.768448) (xy 118.977658 -241.789546) (xy 119.018161 -241.817502) (xy 119.053654 -241.851594)
			(xy 119.083219 -241.890938) (xy 119.10609 -241.934515) (xy 119.121674 -241.981196) (xy 119.129569 -242.029773)
			(xy 119.130064 -242.05438) (xy 121.33886 -242.05438) (xy 121.34282 -242.005326) (xy 121.354597 -241.957542)
			(xy 121.373888 -241.912266) (xy 121.400191 -241.87067) (xy 121.432826 -241.833833) (xy 121.470947 -241.802708)
			(xy 121.513568 -241.778101) (xy 121.559584 -241.760649) (xy 121.607803 -241.750805) (xy 121.656978 -241.748824)
			(xy 121.705833 -241.754756) (xy 121.753104 -241.768448) (xy 121.797566 -241.789546) (xy 121.838069 -241.817502)
			(xy 121.873562 -241.851594) (xy 121.903127 -241.890938) (xy 121.925998 -241.934515) (xy 121.941582 -241.981196)
			(xy 121.949477 -242.029773) (xy 121.949972 -242.05438) (xy 124.159022 -242.05438) (xy 124.162982 -242.005326)
			(xy 124.174759 -241.957542) (xy 124.19405 -241.912266) (xy 124.220353 -241.87067) (xy 124.252988 -241.833833)
			(xy 124.291109 -241.802708) (xy 124.33373 -241.778101) (xy 124.379746 -241.760649) (xy 124.427965 -241.750805)
			(xy 124.47714 -241.748824) (xy 124.525995 -241.754756) (xy 124.573266 -241.768448) (xy 124.617728 -241.789546)
			(xy 124.658231 -241.817502) (xy 124.693724 -241.851594) (xy 124.723289 -241.890938) (xy 124.74616 -241.934515)
			(xy 124.761744 -241.981196) (xy 124.769639 -242.029773) (xy 124.770134 -242.05438) (xy 124.769639 -242.078987)
			(xy 124.761744 -242.127564) (xy 124.74616 -242.174245) (xy 124.723289 -242.217822) (xy 124.693724 -242.257166)
			(xy 124.658231 -242.291258) (xy 124.617728 -242.319214) (xy 124.573266 -242.340312) (xy 124.525995 -242.354004)
			(xy 124.47714 -242.359936) (xy 124.427965 -242.357955) (xy 124.379746 -242.348111) (xy 124.33373 -242.330659)
			(xy 124.291109 -242.306052) (xy 124.252988 -242.274927) (xy 124.220353 -242.23809) (xy 124.19405 -242.196494)
			(xy 124.174759 -242.151218) (xy 124.162982 -242.103434) (xy 124.159022 -242.05438) (xy 121.949972 -242.05438)
			(xy 121.949477 -242.078987) (xy 121.941582 -242.127564) (xy 121.925998 -242.174245) (xy 121.903127 -242.217822)
			(xy 121.873562 -242.257166) (xy 121.838069 -242.291258) (xy 121.797566 -242.319214) (xy 121.753104 -242.340312)
			(xy 121.705833 -242.354004) (xy 121.656978 -242.359936) (xy 121.607803 -242.357955) (xy 121.559584 -242.348111)
			(xy 121.513568 -242.330659) (xy 121.470947 -242.306052) (xy 121.432826 -242.274927) (xy 121.400191 -242.23809)
			(xy 121.373888 -242.196494) (xy 121.354597 -242.151218) (xy 121.34282 -242.103434) (xy 121.33886 -242.05438)
			(xy 119.130064 -242.05438) (xy 119.129569 -242.078987) (xy 119.121674 -242.127564) (xy 119.10609 -242.174245)
			(xy 119.083219 -242.217822) (xy 119.053654 -242.257166) (xy 119.018161 -242.291258) (xy 118.977658 -242.319214)
			(xy 118.933196 -242.340312) (xy 118.885925 -242.354004) (xy 118.83707 -242.359936) (xy 118.787895 -242.357955)
			(xy 118.739676 -242.348111) (xy 118.69366 -242.330659) (xy 118.651039 -242.306052) (xy 118.612918 -242.274927)
			(xy 118.580283 -242.23809) (xy 118.55398 -242.196494) (xy 118.534689 -242.151218) (xy 118.522912 -242.103434)
			(xy 118.518952 -242.05438) (xy 116.310156 -242.05438) (xy 116.309661 -242.078987) (xy 116.301766 -242.127564)
			(xy 116.286182 -242.174245) (xy 116.263311 -242.217822) (xy 116.233746 -242.257166) (xy 116.198253 -242.291258)
			(xy 116.15775 -242.319214) (xy 116.113288 -242.340312) (xy 116.066017 -242.354004) (xy 116.017162 -242.359936)
			(xy 115.967987 -242.357955) (xy 115.919768 -242.348111) (xy 115.873752 -242.330659) (xy 115.831131 -242.306052)
			(xy 115.79301 -242.274927) (xy 115.760375 -242.23809) (xy 115.734072 -242.196494) (xy 115.714781 -242.151218)
			(xy 115.703004 -242.103434) (xy 115.699044 -242.05438) (xy 115.370102 -242.05438) (xy 115.369607 -242.078987)
			(xy 115.361712 -242.127564) (xy 115.346128 -242.174245) (xy 115.323257 -242.217822) (xy 115.293692 -242.257166)
			(xy 115.258199 -242.291258) (xy 115.217696 -242.319214) (xy 115.173234 -242.340312) (xy 115.125963 -242.354004)
			(xy 115.077108 -242.359936) (xy 115.027933 -242.357955) (xy 114.979714 -242.348111) (xy 114.933698 -242.330659)
			(xy 114.891077 -242.306052) (xy 114.852956 -242.274927) (xy 114.820321 -242.23809) (xy 114.794018 -242.196494)
			(xy 114.774727 -242.151218) (xy 114.76295 -242.103434) (xy 114.75899 -242.05438) (xy 114.430048 -242.05438)
			(xy 114.429553 -242.078987) (xy 114.421658 -242.127564) (xy 114.406074 -242.174245) (xy 114.383203 -242.217822)
			(xy 114.353638 -242.257166) (xy 114.318145 -242.291258) (xy 114.277642 -242.319214) (xy 114.23318 -242.340312)
			(xy 114.185909 -242.354004) (xy 114.137054 -242.359936) (xy 114.087879 -242.357955) (xy 114.03966 -242.348111)
			(xy 113.993644 -242.330659) (xy 113.951023 -242.306052) (xy 113.912902 -242.274927) (xy 113.880267 -242.23809)
			(xy 113.853964 -242.196494) (xy 113.834673 -242.151218) (xy 113.822896 -242.103434) (xy 113.818936 -242.05438)
			(xy 113.489994 -242.05438) (xy 113.489499 -242.078987) (xy 113.481604 -242.127564) (xy 113.46602 -242.174245)
			(xy 113.443149 -242.217822) (xy 113.413584 -242.257166) (xy 113.378091 -242.291258) (xy 113.337588 -242.319214)
			(xy 113.293126 -242.340312) (xy 113.245855 -242.354004) (xy 113.197 -242.359936) (xy 113.147825 -242.357955)
			(xy 113.099606 -242.348111) (xy 113.05359 -242.330659) (xy 113.010969 -242.306052) (xy 112.972848 -242.274927)
			(xy 112.940213 -242.23809) (xy 112.91391 -242.196494) (xy 112.894619 -242.151218) (xy 112.882842 -242.103434)
			(xy 112.878882 -242.05438) (xy 110.676436 -242.05438) (xy 110.675941 -242.078987) (xy 110.668046 -242.127564)
			(xy 110.652462 -242.174245) (xy 110.629591 -242.217822) (xy 110.600026 -242.257166) (xy 110.564533 -242.291258)
			(xy 110.52403 -242.319214) (xy 110.479568 -242.340312) (xy 110.432297 -242.354004) (xy 110.383442 -242.359936)
			(xy 110.334267 -242.357955) (xy 110.286048 -242.348111) (xy 110.240032 -242.330659) (xy 110.197411 -242.306052)
			(xy 110.15929 -242.274927) (xy 110.126655 -242.23809) (xy 110.100352 -242.196494) (xy 110.081061 -242.151218)
			(xy 110.069284 -242.103434) (xy 110.065324 -242.05438) (xy 109.736382 -242.05438) (xy 109.735887 -242.078987)
			(xy 109.727992 -242.127564) (xy 109.712408 -242.174245) (xy 109.689537 -242.217822) (xy 109.659972 -242.257166)
			(xy 109.624479 -242.291258) (xy 109.583976 -242.319214) (xy 109.539514 -242.340312) (xy 109.492243 -242.354004)
			(xy 109.443388 -242.359936) (xy 109.394213 -242.357955) (xy 109.345994 -242.348111) (xy 109.299978 -242.330659)
			(xy 109.257357 -242.306052) (xy 109.219236 -242.274927) (xy 109.186601 -242.23809) (xy 109.160298 -242.196494)
			(xy 109.141007 -242.151218) (xy 109.12923 -242.103434) (xy 109.12527 -242.05438) (xy 108.796328 -242.05438)
			(xy 108.795833 -242.078987) (xy 108.787938 -242.127564) (xy 108.772354 -242.174245) (xy 108.749483 -242.217822)
			(xy 108.719918 -242.257166) (xy 108.684425 -242.291258) (xy 108.643922 -242.319214) (xy 108.59946 -242.340312)
			(xy 108.552189 -242.354004) (xy 108.503334 -242.359936) (xy 108.454159 -242.357955) (xy 108.40594 -242.348111)
			(xy 108.359924 -242.330659) (xy 108.317303 -242.306052) (xy 108.279182 -242.274927) (xy 108.246547 -242.23809)
			(xy 108.220244 -242.196494) (xy 108.200953 -242.151218) (xy 108.189176 -242.103434) (xy 108.185216 -242.05438)
			(xy 107.856274 -242.05438) (xy 107.855779 -242.078987) (xy 107.847884 -242.127564) (xy 107.8323 -242.174245)
			(xy 107.809429 -242.217822) (xy 107.779864 -242.257166) (xy 107.744371 -242.291258) (xy 107.703868 -242.319214)
			(xy 107.659406 -242.340312) (xy 107.612135 -242.354004) (xy 107.56328 -242.359936) (xy 107.514105 -242.357955)
			(xy 107.465886 -242.348111) (xy 107.41987 -242.330659) (xy 107.377249 -242.306052) (xy 107.339128 -242.274927)
			(xy 107.306493 -242.23809) (xy 107.28019 -242.196494) (xy 107.260899 -242.151218) (xy 107.249122 -242.103434)
			(xy 107.245162 -242.05438) (xy 105.036366 -242.05438) (xy 105.035871 -242.078987) (xy 105.027976 -242.127564)
			(xy 105.012392 -242.174245) (xy 104.989521 -242.217822) (xy 104.959956 -242.257166) (xy 104.924463 -242.291258)
			(xy 104.88396 -242.319214) (xy 104.839498 -242.340312) (xy 104.792227 -242.354004) (xy 104.743372 -242.359936)
			(xy 104.694197 -242.357955) (xy 104.645978 -242.348111) (xy 104.599962 -242.330659) (xy 104.557341 -242.306052)
			(xy 104.51922 -242.274927) (xy 104.486585 -242.23809) (xy 104.460282 -242.196494) (xy 104.440991 -242.151218)
			(xy 104.429214 -242.103434) (xy 104.425254 -242.05438) (xy 102.216458 -242.05438) (xy 102.215963 -242.078987)
			(xy 102.208068 -242.127564) (xy 102.192484 -242.174245) (xy 102.169613 -242.217822) (xy 102.140048 -242.257166)
			(xy 102.104555 -242.291258) (xy 102.064052 -242.319214) (xy 102.01959 -242.340312) (xy 101.972319 -242.354004)
			(xy 101.923464 -242.359936) (xy 101.874289 -242.357955) (xy 101.82607 -242.348111) (xy 101.780054 -242.330659)
			(xy 101.737433 -242.306052) (xy 101.699312 -242.274927) (xy 101.666677 -242.23809) (xy 101.640374 -242.196494)
			(xy 101.621083 -242.151218) (xy 101.609306 -242.103434) (xy 101.605346 -242.05438) (xy 99.396296 -242.05438)
			(xy 99.395801 -242.078987) (xy 99.387906 -242.127564) (xy 99.372322 -242.174245) (xy 99.349451 -242.217822)
			(xy 99.319886 -242.257166) (xy 99.284393 -242.291258) (xy 99.24389 -242.319214) (xy 99.199428 -242.340312)
			(xy 99.152157 -242.354004) (xy 99.103302 -242.359936) (xy 99.054127 -242.357955) (xy 99.005908 -242.348111)
			(xy 98.959892 -242.330659) (xy 98.917271 -242.306052) (xy 98.87915 -242.274927) (xy 98.846515 -242.23809)
			(xy 98.820212 -242.196494) (xy 98.800921 -242.151218) (xy 98.789144 -242.103434) (xy 98.785184 -242.05438)
			(xy 96.575895 -242.05438) (xy 96.575905 -242.078363) (xy 96.568362 -242.125952) (xy 96.553445 -242.171768)
			(xy 96.531521 -242.214674) (xy 96.503135 -242.253608) (xy 96.46899 -242.287604) (xy 96.429932 -242.315819)
			(xy 96.38693 -242.337555) (xy 96.34105 -242.352273) (xy 96.317308 -242.356386) (xy 96.3168 -242.356386)
			(xy 96.316292 -242.35664) (xy 96.307529 -242.358305) (xy 96.291913 -242.366897) (xy 96.285812 -242.373404)
			(xy 96.280224 -242.379754) (xy 96.273874 -242.396772) (xy 96.273874 -242.551712) (xy 96.274058 -242.557948)
			(xy 96.277133 -242.570033) (xy 96.27997 -242.575588) (xy 96.284542 -242.583462) (xy 96.295087 -242.602063)
			(xy 96.313652 -242.640585) (xy 96.321626 -242.660424) (xy 96.323658 -242.665504) (xy 96.326452 -242.673124)
			(xy 96.33712 -242.681506) (xy 96.342596 -242.685463) (xy 96.355085 -242.690605) (xy 96.361758 -242.691666)
			(xy 96.448372 -242.703096) (xy 96.45511 -242.70368) (xy 96.468494 -242.701761) (xy 96.474788 -242.699286)
			(xy 96.48698 -242.694206) (xy 96.490536 -242.689634) (xy 96.495616 -242.682776) (xy 96.510119 -242.663945)
			(xy 96.543973 -242.630587) (xy 96.582585 -242.602875) (xy 96.625024 -242.581479) (xy 96.670265 -242.566915)
			(xy 96.717216 -242.559534) (xy 96.74098 -242.559078) (xy 96.76624 -242.559569) (xy 96.816071 -242.567882)
			(xy 96.863855 -242.584283) (xy 96.908287 -242.608326) (xy 96.948155 -242.639354) (xy 96.982372 -242.676522)
			(xy 97.010005 -242.718815) (xy 97.0303 -242.765079) (xy 97.042702 -242.814053) (xy 97.046873 -242.864386)
			(xy 97.37523 -242.864386) (xy 97.37919 -242.815332) (xy 97.390967 -242.767548) (xy 97.410258 -242.722272)
			(xy 97.436561 -242.680676) (xy 97.469196 -242.643839) (xy 97.507317 -242.612714) (xy 97.549938 -242.588107)
			(xy 97.595954 -242.570655) (xy 97.644173 -242.560811) (xy 97.693348 -242.55883) (xy 97.742203 -242.564762)
			(xy 97.789474 -242.578454) (xy 97.833936 -242.599552) (xy 97.874439 -242.627508) (xy 97.909932 -242.6616)
			(xy 97.939497 -242.700944) (xy 97.962368 -242.744521) (xy 97.977952 -242.791202) (xy 97.985847 -242.839779)
			(xy 97.986342 -242.864386) (xy 98.315284 -242.864386) (xy 98.319244 -242.815332) (xy 98.331021 -242.767548)
			(xy 98.350312 -242.722272) (xy 98.376615 -242.680676) (xy 98.40925 -242.643839) (xy 98.447371 -242.612714)
			(xy 98.489992 -242.588107) (xy 98.536008 -242.570655) (xy 98.584227 -242.560811) (xy 98.633402 -242.55883)
			(xy 98.682257 -242.564762) (xy 98.729528 -242.578454) (xy 98.77399 -242.599552) (xy 98.814493 -242.627508)
			(xy 98.849986 -242.6616) (xy 98.879551 -242.700944) (xy 98.902422 -242.744521) (xy 98.918006 -242.791202)
			(xy 98.925901 -242.839779) (xy 98.926396 -242.864386) (xy 99.255338 -242.864386) (xy 99.259298 -242.815332)
			(xy 99.271075 -242.767548) (xy 99.290366 -242.722272) (xy 99.316669 -242.680676) (xy 99.349304 -242.643839)
			(xy 99.387425 -242.612714) (xy 99.430046 -242.588107) (xy 99.476062 -242.570655) (xy 99.524281 -242.560811)
			(xy 99.573456 -242.55883) (xy 99.622311 -242.564762) (xy 99.669582 -242.578454) (xy 99.714044 -242.599552)
			(xy 99.754547 -242.627508) (xy 99.79004 -242.6616) (xy 99.819605 -242.700944) (xy 99.842476 -242.744521)
			(xy 99.85806 -242.791202) (xy 99.865955 -242.839779) (xy 99.86645 -242.864386) (xy 100.195138 -242.864386)
			(xy 100.199098 -242.815332) (xy 100.210875 -242.767548) (xy 100.230166 -242.722272) (xy 100.256469 -242.680676)
			(xy 100.289104 -242.643839) (xy 100.327225 -242.612714) (xy 100.369846 -242.588107) (xy 100.415862 -242.570655)
			(xy 100.464081 -242.560811) (xy 100.513256 -242.55883) (xy 100.562111 -242.564762) (xy 100.609382 -242.578454)
			(xy 100.653844 -242.599552) (xy 100.694347 -242.627508) (xy 100.72984 -242.6616) (xy 100.759405 -242.700944)
			(xy 100.782276 -242.744521) (xy 100.79786 -242.791202) (xy 100.805755 -242.839779) (xy 100.80625 -242.864386)
			(xy 101.135192 -242.864386) (xy 101.139152 -242.815332) (xy 101.150929 -242.767548) (xy 101.17022 -242.722272)
			(xy 101.196523 -242.680676) (xy 101.229158 -242.643839) (xy 101.267279 -242.612714) (xy 101.3099 -242.588107)
			(xy 101.355916 -242.570655) (xy 101.404135 -242.560811) (xy 101.45331 -242.55883) (xy 101.502165 -242.564762)
			(xy 101.549436 -242.578454) (xy 101.593898 -242.599552) (xy 101.634401 -242.627508) (xy 101.669894 -242.6616)
			(xy 101.699459 -242.700944) (xy 101.72233 -242.744521) (xy 101.737914 -242.791202) (xy 101.745809 -242.839779)
			(xy 101.746304 -242.864386) (xy 102.075246 -242.864386) (xy 102.079206 -242.815332) (xy 102.090983 -242.767548)
			(xy 102.110274 -242.722272) (xy 102.136577 -242.680676) (xy 102.169212 -242.643839) (xy 102.207333 -242.612714)
			(xy 102.249954 -242.588107) (xy 102.29597 -242.570655) (xy 102.344189 -242.560811) (xy 102.393364 -242.55883)
			(xy 102.442219 -242.564762) (xy 102.48949 -242.578454) (xy 102.533952 -242.599552) (xy 102.574455 -242.627508)
			(xy 102.609948 -242.6616) (xy 102.639513 -242.700944) (xy 102.662384 -242.744521) (xy 102.677968 -242.791202)
			(xy 102.685863 -242.839779) (xy 102.686358 -242.864386) (xy 103.0153 -242.864386) (xy 103.01926 -242.815332)
			(xy 103.031037 -242.767548) (xy 103.050328 -242.722272) (xy 103.076631 -242.680676) (xy 103.109266 -242.643839)
			(xy 103.147387 -242.612714) (xy 103.190008 -242.588107) (xy 103.236024 -242.570655) (xy 103.284243 -242.560811)
			(xy 103.333418 -242.55883) (xy 103.382273 -242.564762) (xy 103.429544 -242.578454) (xy 103.474006 -242.599552)
			(xy 103.514509 -242.627508) (xy 103.550002 -242.6616) (xy 103.579567 -242.700944) (xy 103.602438 -242.744521)
			(xy 103.618022 -242.791202) (xy 103.625917 -242.839779) (xy 103.626412 -242.864386) (xy 103.955354 -242.864386)
			(xy 103.959314 -242.815332) (xy 103.971091 -242.767548) (xy 103.990382 -242.722272) (xy 104.016685 -242.680676)
			(xy 104.04932 -242.643839) (xy 104.087441 -242.612714) (xy 104.130062 -242.588107) (xy 104.176078 -242.570655)
			(xy 104.224297 -242.560811) (xy 104.273472 -242.55883) (xy 104.322327 -242.564762) (xy 104.369598 -242.578454)
			(xy 104.41406 -242.599552) (xy 104.454563 -242.627508) (xy 104.490056 -242.6616) (xy 104.519621 -242.700944)
			(xy 104.542492 -242.744521) (xy 104.558076 -242.791202) (xy 104.565971 -242.839779) (xy 104.566466 -242.864386)
			(xy 104.895154 -242.864386) (xy 104.899114 -242.815332) (xy 104.910891 -242.767548) (xy 104.930182 -242.722272)
			(xy 104.956485 -242.680676) (xy 104.98912 -242.643839) (xy 105.027241 -242.612714) (xy 105.069862 -242.588107)
			(xy 105.115878 -242.570655) (xy 105.164097 -242.560811) (xy 105.213272 -242.55883) (xy 105.262127 -242.564762)
			(xy 105.309398 -242.578454) (xy 105.35386 -242.599552) (xy 105.394363 -242.627508) (xy 105.429856 -242.6616)
			(xy 105.459421 -242.700944) (xy 105.482292 -242.744521) (xy 105.497876 -242.791202) (xy 105.505771 -242.839779)
			(xy 105.506266 -242.864386) (xy 105.835208 -242.864386) (xy 105.839168 -242.815332) (xy 105.850945 -242.767548)
			(xy 105.870236 -242.722272) (xy 105.896539 -242.680676) (xy 105.929174 -242.643839) (xy 105.967295 -242.612714)
			(xy 106.009916 -242.588107) (xy 106.055932 -242.570655) (xy 106.104151 -242.560811) (xy 106.153326 -242.55883)
			(xy 106.202181 -242.564762) (xy 106.249452 -242.578454) (xy 106.293914 -242.599552) (xy 106.334417 -242.627508)
			(xy 106.36991 -242.6616) (xy 106.399475 -242.700944) (xy 106.422346 -242.744521) (xy 106.43793 -242.791202)
			(xy 106.445825 -242.839779) (xy 106.44632 -242.864386) (xy 106.775262 -242.864386) (xy 106.779222 -242.815332)
			(xy 106.790999 -242.767548) (xy 106.81029 -242.722272) (xy 106.836593 -242.680676) (xy 106.869228 -242.643839)
			(xy 106.907349 -242.612714) (xy 106.94997 -242.588107) (xy 106.995986 -242.570655) (xy 107.044205 -242.560811)
			(xy 107.09338 -242.55883) (xy 107.142235 -242.564762) (xy 107.189506 -242.578454) (xy 107.233968 -242.599552)
			(xy 107.274471 -242.627508) (xy 107.309964 -242.6616) (xy 107.339529 -242.700944) (xy 107.3624 -242.744521)
			(xy 107.377984 -242.791202) (xy 107.385879 -242.839779) (xy 107.386374 -242.864386) (xy 107.715316 -242.864386)
			(xy 107.719276 -242.815332) (xy 107.731053 -242.767548) (xy 107.750344 -242.722272) (xy 107.776647 -242.680676)
			(xy 107.809282 -242.643839) (xy 107.847403 -242.612714) (xy 107.890024 -242.588107) (xy 107.93604 -242.570655)
			(xy 107.984259 -242.560811) (xy 108.033434 -242.55883) (xy 108.082289 -242.564762) (xy 108.12956 -242.578454)
			(xy 108.174022 -242.599552) (xy 108.214525 -242.627508) (xy 108.250018 -242.6616) (xy 108.279583 -242.700944)
			(xy 108.302454 -242.744521) (xy 108.318038 -242.791202) (xy 108.325933 -242.839779) (xy 108.326428 -242.864386)
			(xy 115.22889 -242.864386) (xy 115.23285 -242.815332) (xy 115.244627 -242.767548) (xy 115.263918 -242.722272)
			(xy 115.290221 -242.680676) (xy 115.322856 -242.643839) (xy 115.360977 -242.612714) (xy 115.403598 -242.588107)
			(xy 115.449614 -242.570655) (xy 115.497833 -242.560811) (xy 115.547008 -242.55883) (xy 115.595863 -242.564762)
			(xy 115.643134 -242.578454) (xy 115.687596 -242.599552) (xy 115.728099 -242.627508) (xy 115.763592 -242.6616)
			(xy 115.793157 -242.700944) (xy 115.816028 -242.744521) (xy 115.831612 -242.791202) (xy 115.839507 -242.839779)
			(xy 115.840002 -242.864386) (xy 116.168944 -242.864386) (xy 116.172904 -242.815332) (xy 116.184681 -242.767548)
			(xy 116.203972 -242.722272) (xy 116.230275 -242.680676) (xy 116.26291 -242.643839) (xy 116.301031 -242.612714)
			(xy 116.343652 -242.588107) (xy 116.389668 -242.570655) (xy 116.437887 -242.560811) (xy 116.487062 -242.55883)
			(xy 116.535917 -242.564762) (xy 116.583188 -242.578454) (xy 116.62765 -242.599552) (xy 116.668153 -242.627508)
			(xy 116.703646 -242.6616) (xy 116.733211 -242.700944) (xy 116.756082 -242.744521) (xy 116.771666 -242.791202)
			(xy 116.779561 -242.839779) (xy 116.780056 -242.864386) (xy 117.108998 -242.864386) (xy 117.112958 -242.815332)
			(xy 117.124735 -242.767548) (xy 117.144026 -242.722272) (xy 117.170329 -242.680676) (xy 117.202964 -242.643839)
			(xy 117.241085 -242.612714) (xy 117.283706 -242.588107) (xy 117.329722 -242.570655) (xy 117.377941 -242.560811)
			(xy 117.427116 -242.55883) (xy 117.475971 -242.564762) (xy 117.523242 -242.578454) (xy 117.567704 -242.599552)
			(xy 117.608207 -242.627508) (xy 117.6437 -242.6616) (xy 117.673265 -242.700944) (xy 117.696136 -242.744521)
			(xy 117.71172 -242.791202) (xy 117.719615 -242.839779) (xy 117.72011 -242.864386) (xy 118.049052 -242.864386)
			(xy 118.053012 -242.815332) (xy 118.064789 -242.767548) (xy 118.08408 -242.722272) (xy 118.110383 -242.680676)
			(xy 118.143018 -242.643839) (xy 118.181139 -242.612714) (xy 118.22376 -242.588107) (xy 118.269776 -242.570655)
			(xy 118.317995 -242.560811) (xy 118.36717 -242.55883) (xy 118.416025 -242.564762) (xy 118.463296 -242.578454)
			(xy 118.507758 -242.599552) (xy 118.548261 -242.627508) (xy 118.583754 -242.6616) (xy 118.613319 -242.700944)
			(xy 118.63619 -242.744521) (xy 118.651774 -242.791202) (xy 118.659669 -242.839779) (xy 118.660164 -242.864386)
			(xy 118.988852 -242.864386) (xy 118.992812 -242.815332) (xy 119.004589 -242.767548) (xy 119.02388 -242.722272)
			(xy 119.050183 -242.680676) (xy 119.082818 -242.643839) (xy 119.120939 -242.612714) (xy 119.16356 -242.588107)
			(xy 119.209576 -242.570655) (xy 119.257795 -242.560811) (xy 119.30697 -242.55883) (xy 119.355825 -242.564762)
			(xy 119.403096 -242.578454) (xy 119.447558 -242.599552) (xy 119.488061 -242.627508) (xy 119.523554 -242.6616)
			(xy 119.553119 -242.700944) (xy 119.57599 -242.744521) (xy 119.591574 -242.791202) (xy 119.599469 -242.839779)
			(xy 119.599964 -242.864386) (xy 119.928906 -242.864386) (xy 119.932866 -242.815332) (xy 119.944643 -242.767548)
			(xy 119.963934 -242.722272) (xy 119.990237 -242.680676) (xy 120.022872 -242.643839) (xy 120.060993 -242.612714)
			(xy 120.103614 -242.588107) (xy 120.14963 -242.570655) (xy 120.197849 -242.560811) (xy 120.247024 -242.55883)
			(xy 120.295879 -242.564762) (xy 120.34315 -242.578454) (xy 120.387612 -242.599552) (xy 120.428115 -242.627508)
			(xy 120.463608 -242.6616) (xy 120.493173 -242.700944) (xy 120.516044 -242.744521) (xy 120.531628 -242.791202)
			(xy 120.539523 -242.839779) (xy 120.540018 -242.864386) (xy 120.86896 -242.864386) (xy 120.87292 -242.815332)
			(xy 120.884697 -242.767548) (xy 120.903988 -242.722272) (xy 120.930291 -242.680676) (xy 120.962926 -242.643839)
			(xy 121.001047 -242.612714) (xy 121.043668 -242.588107) (xy 121.089684 -242.570655) (xy 121.137903 -242.560811)
			(xy 121.187078 -242.55883) (xy 121.235933 -242.564762) (xy 121.283204 -242.578454) (xy 121.327666 -242.599552)
			(xy 121.368169 -242.627508) (xy 121.403662 -242.6616) (xy 121.433227 -242.700944) (xy 121.456098 -242.744521)
			(xy 121.471682 -242.791202) (xy 121.479577 -242.839779) (xy 121.480072 -242.864386) (xy 121.809014 -242.864386)
			(xy 121.812974 -242.815332) (xy 121.824751 -242.767548) (xy 121.844042 -242.722272) (xy 121.870345 -242.680676)
			(xy 121.90298 -242.643839) (xy 121.941101 -242.612714) (xy 121.983722 -242.588107) (xy 122.029738 -242.570655)
			(xy 122.077957 -242.560811) (xy 122.127132 -242.55883) (xy 122.175987 -242.564762) (xy 122.223258 -242.578454)
			(xy 122.26772 -242.599552) (xy 122.308223 -242.627508) (xy 122.343716 -242.6616) (xy 122.373281 -242.700944)
			(xy 122.396152 -242.744521) (xy 122.411736 -242.791202) (xy 122.419631 -242.839779) (xy 122.420126 -242.864386)
			(xy 122.748814 -242.864386) (xy 122.752774 -242.815332) (xy 122.764551 -242.767548) (xy 122.783842 -242.722272)
			(xy 122.810145 -242.680676) (xy 122.84278 -242.643839) (xy 122.880901 -242.612714) (xy 122.923522 -242.588107)
			(xy 122.969538 -242.570655) (xy 123.017757 -242.560811) (xy 123.066932 -242.55883) (xy 123.115787 -242.564762)
			(xy 123.163058 -242.578454) (xy 123.20752 -242.599552) (xy 123.248023 -242.627508) (xy 123.283516 -242.6616)
			(xy 123.313081 -242.700944) (xy 123.335952 -242.744521) (xy 123.351536 -242.791202) (xy 123.359431 -242.839779)
			(xy 123.359926 -242.864386) (xy 123.688868 -242.864386) (xy 123.692828 -242.815332) (xy 123.704605 -242.767548)
			(xy 123.723896 -242.722272) (xy 123.750199 -242.680676) (xy 123.782834 -242.643839) (xy 123.820955 -242.612714)
			(xy 123.863576 -242.588107) (xy 123.909592 -242.570655) (xy 123.957811 -242.560811) (xy 124.006986 -242.55883)
			(xy 124.055841 -242.564762) (xy 124.103112 -242.578454) (xy 124.147574 -242.599552) (xy 124.188077 -242.627508)
			(xy 124.22357 -242.6616) (xy 124.253135 -242.700944) (xy 124.276006 -242.744521) (xy 124.29159 -242.791202)
			(xy 124.299485 -242.839779) (xy 124.29998 -242.864386) (xy 124.628922 -242.864386) (xy 124.632882 -242.815332)
			(xy 124.644659 -242.767548) (xy 124.66395 -242.722272) (xy 124.690253 -242.680676) (xy 124.722888 -242.643839)
			(xy 124.761009 -242.612714) (xy 124.80363 -242.588107) (xy 124.849646 -242.570655) (xy 124.897865 -242.560811)
			(xy 124.94704 -242.55883) (xy 124.995895 -242.564762) (xy 125.043166 -242.578454) (xy 125.087628 -242.599552)
			(xy 125.128131 -242.627508) (xy 125.163624 -242.6616) (xy 125.193189 -242.700944) (xy 125.21606 -242.744521)
			(xy 125.231644 -242.791202) (xy 125.239539 -242.839779) (xy 125.240034 -242.864386) (xy 125.568976 -242.864386)
			(xy 125.572936 -242.815332) (xy 125.584713 -242.767548) (xy 125.604004 -242.722272) (xy 125.630307 -242.680676)
			(xy 125.662942 -242.643839) (xy 125.701063 -242.612714) (xy 125.743684 -242.588107) (xy 125.7897 -242.570655)
			(xy 125.837919 -242.560811) (xy 125.887094 -242.55883) (xy 125.935949 -242.564762) (xy 125.98322 -242.578454)
			(xy 126.027682 -242.599552) (xy 126.068185 -242.627508) (xy 126.103678 -242.6616) (xy 126.133243 -242.700944)
			(xy 126.156114 -242.744521) (xy 126.171698 -242.791202) (xy 126.179593 -242.839779) (xy 126.180088 -242.864386)
			(xy 126.179593 -242.888993) (xy 126.171698 -242.93757) (xy 126.156114 -242.984251) (xy 126.133243 -243.027828)
			(xy 126.103678 -243.067172) (xy 126.068185 -243.101264) (xy 126.027682 -243.12922) (xy 125.98322 -243.150318)
			(xy 125.935949 -243.16401) (xy 125.887094 -243.169942) (xy 125.837919 -243.167961) (xy 125.7897 -243.158117)
			(xy 125.743684 -243.140665) (xy 125.701063 -243.116058) (xy 125.662942 -243.084933) (xy 125.630307 -243.048096)
			(xy 125.604004 -243.0065) (xy 125.584713 -242.961224) (xy 125.572936 -242.91344) (xy 125.568976 -242.864386)
			(xy 125.240034 -242.864386) (xy 125.239539 -242.888993) (xy 125.231644 -242.93757) (xy 125.21606 -242.984251)
			(xy 125.193189 -243.027828) (xy 125.163624 -243.067172) (xy 125.128131 -243.101264) (xy 125.087628 -243.12922)
			(xy 125.043166 -243.150318) (xy 124.995895 -243.16401) (xy 124.94704 -243.169942) (xy 124.897865 -243.167961)
			(xy 124.849646 -243.158117) (xy 124.80363 -243.140665) (xy 124.761009 -243.116058) (xy 124.722888 -243.084933)
			(xy 124.690253 -243.048096) (xy 124.66395 -243.0065) (xy 124.644659 -242.961224) (xy 124.632882 -242.91344)
			(xy 124.628922 -242.864386) (xy 124.29998 -242.864386) (xy 124.299485 -242.888993) (xy 124.29159 -242.93757)
			(xy 124.276006 -242.984251) (xy 124.253135 -243.027828) (xy 124.22357 -243.067172) (xy 124.188077 -243.101264)
			(xy 124.147574 -243.12922) (xy 124.103112 -243.150318) (xy 124.055841 -243.16401) (xy 124.006986 -243.169942)
			(xy 123.957811 -243.167961) (xy 123.909592 -243.158117) (xy 123.863576 -243.140665) (xy 123.820955 -243.116058)
			(xy 123.782834 -243.084933) (xy 123.750199 -243.048096) (xy 123.723896 -243.0065) (xy 123.704605 -242.961224)
			(xy 123.692828 -242.91344) (xy 123.688868 -242.864386) (xy 123.359926 -242.864386) (xy 123.359431 -242.888993)
			(xy 123.351536 -242.93757) (xy 123.335952 -242.984251) (xy 123.313081 -243.027828) (xy 123.283516 -243.067172)
			(xy 123.248023 -243.101264) (xy 123.20752 -243.12922) (xy 123.163058 -243.150318) (xy 123.115787 -243.16401)
			(xy 123.066932 -243.169942) (xy 123.017757 -243.167961) (xy 122.969538 -243.158117) (xy 122.923522 -243.140665)
			(xy 122.880901 -243.116058) (xy 122.84278 -243.084933) (xy 122.810145 -243.048096) (xy 122.783842 -243.0065)
			(xy 122.764551 -242.961224) (xy 122.752774 -242.91344) (xy 122.748814 -242.864386) (xy 122.420126 -242.864386)
			(xy 122.419631 -242.888993) (xy 122.411736 -242.93757) (xy 122.396152 -242.984251) (xy 122.373281 -243.027828)
			(xy 122.343716 -243.067172) (xy 122.308223 -243.101264) (xy 122.26772 -243.12922) (xy 122.223258 -243.150318)
			(xy 122.175987 -243.16401) (xy 122.127132 -243.169942) (xy 122.077957 -243.167961) (xy 122.029738 -243.158117)
			(xy 121.983722 -243.140665) (xy 121.941101 -243.116058) (xy 121.90298 -243.084933) (xy 121.870345 -243.048096)
			(xy 121.844042 -243.0065) (xy 121.824751 -242.961224) (xy 121.812974 -242.91344) (xy 121.809014 -242.864386)
			(xy 121.480072 -242.864386) (xy 121.479577 -242.888993) (xy 121.471682 -242.93757) (xy 121.456098 -242.984251)
			(xy 121.433227 -243.027828) (xy 121.403662 -243.067172) (xy 121.368169 -243.101264) (xy 121.327666 -243.12922)
			(xy 121.283204 -243.150318) (xy 121.235933 -243.16401) (xy 121.187078 -243.169942) (xy 121.137903 -243.167961)
			(xy 121.089684 -243.158117) (xy 121.043668 -243.140665) (xy 121.001047 -243.116058) (xy 120.962926 -243.084933)
			(xy 120.930291 -243.048096) (xy 120.903988 -243.0065) (xy 120.884697 -242.961224) (xy 120.87292 -242.91344)
			(xy 120.86896 -242.864386) (xy 120.540018 -242.864386) (xy 120.539523 -242.888993) (xy 120.531628 -242.93757)
			(xy 120.516044 -242.984251) (xy 120.493173 -243.027828) (xy 120.463608 -243.067172) (xy 120.428115 -243.101264)
			(xy 120.387612 -243.12922) (xy 120.34315 -243.150318) (xy 120.295879 -243.16401) (xy 120.247024 -243.169942)
			(xy 120.197849 -243.167961) (xy 120.14963 -243.158117) (xy 120.103614 -243.140665) (xy 120.060993 -243.116058)
			(xy 120.022872 -243.084933) (xy 119.990237 -243.048096) (xy 119.963934 -243.0065) (xy 119.944643 -242.961224)
			(xy 119.932866 -242.91344) (xy 119.928906 -242.864386) (xy 119.599964 -242.864386) (xy 119.599469 -242.888993)
			(xy 119.591574 -242.93757) (xy 119.57599 -242.984251) (xy 119.553119 -243.027828) (xy 119.523554 -243.067172)
			(xy 119.488061 -243.101264) (xy 119.447558 -243.12922) (xy 119.403096 -243.150318) (xy 119.355825 -243.16401)
			(xy 119.30697 -243.169942) (xy 119.257795 -243.167961) (xy 119.209576 -243.158117) (xy 119.16356 -243.140665)
			(xy 119.120939 -243.116058) (xy 119.082818 -243.084933) (xy 119.050183 -243.048096) (xy 119.02388 -243.0065)
			(xy 119.004589 -242.961224) (xy 118.992812 -242.91344) (xy 118.988852 -242.864386) (xy 118.660164 -242.864386)
			(xy 118.659669 -242.888993) (xy 118.651774 -242.93757) (xy 118.63619 -242.984251) (xy 118.613319 -243.027828)
			(xy 118.583754 -243.067172) (xy 118.548261 -243.101264) (xy 118.507758 -243.12922) (xy 118.463296 -243.150318)
			(xy 118.416025 -243.16401) (xy 118.36717 -243.169942) (xy 118.317995 -243.167961) (xy 118.269776 -243.158117)
			(xy 118.22376 -243.140665) (xy 118.181139 -243.116058) (xy 118.143018 -243.084933) (xy 118.110383 -243.048096)
			(xy 118.08408 -243.0065) (xy 118.064789 -242.961224) (xy 118.053012 -242.91344) (xy 118.049052 -242.864386)
			(xy 117.72011 -242.864386) (xy 117.719615 -242.888993) (xy 117.71172 -242.93757) (xy 117.696136 -242.984251)
			(xy 117.673265 -243.027828) (xy 117.6437 -243.067172) (xy 117.608207 -243.101264) (xy 117.567704 -243.12922)
			(xy 117.523242 -243.150318) (xy 117.475971 -243.16401) (xy 117.427116 -243.169942) (xy 117.377941 -243.167961)
			(xy 117.329722 -243.158117) (xy 117.283706 -243.140665) (xy 117.241085 -243.116058) (xy 117.202964 -243.084933)
			(xy 117.170329 -243.048096) (xy 117.144026 -243.0065) (xy 117.124735 -242.961224) (xy 117.112958 -242.91344)
			(xy 117.108998 -242.864386) (xy 116.780056 -242.864386) (xy 116.779561 -242.888993) (xy 116.771666 -242.93757)
			(xy 116.756082 -242.984251) (xy 116.733211 -243.027828) (xy 116.703646 -243.067172) (xy 116.668153 -243.101264)
			(xy 116.62765 -243.12922) (xy 116.583188 -243.150318) (xy 116.535917 -243.16401) (xy 116.487062 -243.169942)
			(xy 116.437887 -243.167961) (xy 116.389668 -243.158117) (xy 116.343652 -243.140665) (xy 116.301031 -243.116058)
			(xy 116.26291 -243.084933) (xy 116.230275 -243.048096) (xy 116.203972 -243.0065) (xy 116.184681 -242.961224)
			(xy 116.172904 -242.91344) (xy 116.168944 -242.864386) (xy 115.840002 -242.864386) (xy 115.839507 -242.888993)
			(xy 115.831612 -242.93757) (xy 115.816028 -242.984251) (xy 115.793157 -243.027828) (xy 115.763592 -243.067172)
			(xy 115.728099 -243.101264) (xy 115.687596 -243.12922) (xy 115.643134 -243.150318) (xy 115.595863 -243.16401)
			(xy 115.547008 -243.169942) (xy 115.497833 -243.167961) (xy 115.449614 -243.158117) (xy 115.403598 -243.140665)
			(xy 115.360977 -243.116058) (xy 115.322856 -243.084933) (xy 115.290221 -243.048096) (xy 115.263918 -243.0065)
			(xy 115.244627 -242.961224) (xy 115.23285 -242.91344) (xy 115.22889 -242.864386) (xy 108.326428 -242.864386)
			(xy 108.325933 -242.888993) (xy 108.318038 -242.93757) (xy 108.302454 -242.984251) (xy 108.279583 -243.027828)
			(xy 108.250018 -243.067172) (xy 108.214525 -243.101264) (xy 108.174022 -243.12922) (xy 108.12956 -243.150318)
			(xy 108.082289 -243.16401) (xy 108.033434 -243.169942) (xy 107.984259 -243.167961) (xy 107.93604 -243.158117)
			(xy 107.890024 -243.140665) (xy 107.847403 -243.116058) (xy 107.809282 -243.084933) (xy 107.776647 -243.048096)
			(xy 107.750344 -243.0065) (xy 107.731053 -242.961224) (xy 107.719276 -242.91344) (xy 107.715316 -242.864386)
			(xy 107.386374 -242.864386) (xy 107.385879 -242.888993) (xy 107.377984 -242.93757) (xy 107.3624 -242.984251)
			(xy 107.339529 -243.027828) (xy 107.309964 -243.067172) (xy 107.274471 -243.101264) (xy 107.233968 -243.12922)
			(xy 107.189506 -243.150318) (xy 107.142235 -243.16401) (xy 107.09338 -243.169942) (xy 107.044205 -243.167961)
			(xy 106.995986 -243.158117) (xy 106.94997 -243.140665) (xy 106.907349 -243.116058) (xy 106.869228 -243.084933)
			(xy 106.836593 -243.048096) (xy 106.81029 -243.0065) (xy 106.790999 -242.961224) (xy 106.779222 -242.91344)
			(xy 106.775262 -242.864386) (xy 106.44632 -242.864386) (xy 106.445825 -242.888993) (xy 106.43793 -242.93757)
			(xy 106.422346 -242.984251) (xy 106.399475 -243.027828) (xy 106.36991 -243.067172) (xy 106.334417 -243.101264)
			(xy 106.293914 -243.12922) (xy 106.249452 -243.150318) (xy 106.202181 -243.16401) (xy 106.153326 -243.169942)
			(xy 106.104151 -243.167961) (xy 106.055932 -243.158117) (xy 106.009916 -243.140665) (xy 105.967295 -243.116058)
			(xy 105.929174 -243.084933) (xy 105.896539 -243.048096) (xy 105.870236 -243.0065) (xy 105.850945 -242.961224)
			(xy 105.839168 -242.91344) (xy 105.835208 -242.864386) (xy 105.506266 -242.864386) (xy 105.505771 -242.888993)
			(xy 105.497876 -242.93757) (xy 105.482292 -242.984251) (xy 105.459421 -243.027828) (xy 105.429856 -243.067172)
			(xy 105.394363 -243.101264) (xy 105.35386 -243.12922) (xy 105.309398 -243.150318) (xy 105.262127 -243.16401)
			(xy 105.213272 -243.169942) (xy 105.164097 -243.167961) (xy 105.115878 -243.158117) (xy 105.069862 -243.140665)
			(xy 105.027241 -243.116058) (xy 104.98912 -243.084933) (xy 104.956485 -243.048096) (xy 104.930182 -243.0065)
			(xy 104.910891 -242.961224) (xy 104.899114 -242.91344) (xy 104.895154 -242.864386) (xy 104.566466 -242.864386)
			(xy 104.565971 -242.888993) (xy 104.558076 -242.93757) (xy 104.542492 -242.984251) (xy 104.519621 -243.027828)
			(xy 104.490056 -243.067172) (xy 104.454563 -243.101264) (xy 104.41406 -243.12922) (xy 104.369598 -243.150318)
			(xy 104.322327 -243.16401) (xy 104.273472 -243.169942) (xy 104.224297 -243.167961) (xy 104.176078 -243.158117)
			(xy 104.130062 -243.140665) (xy 104.087441 -243.116058) (xy 104.04932 -243.084933) (xy 104.016685 -243.048096)
			(xy 103.990382 -243.0065) (xy 103.971091 -242.961224) (xy 103.959314 -242.91344) (xy 103.955354 -242.864386)
			(xy 103.626412 -242.864386) (xy 103.625917 -242.888993) (xy 103.618022 -242.93757) (xy 103.602438 -242.984251)
			(xy 103.579567 -243.027828) (xy 103.550002 -243.067172) (xy 103.514509 -243.101264) (xy 103.474006 -243.12922)
			(xy 103.429544 -243.150318) (xy 103.382273 -243.16401) (xy 103.333418 -243.169942) (xy 103.284243 -243.167961)
			(xy 103.236024 -243.158117) (xy 103.190008 -243.140665) (xy 103.147387 -243.116058) (xy 103.109266 -243.084933)
			(xy 103.076631 -243.048096) (xy 103.050328 -243.0065) (xy 103.031037 -242.961224) (xy 103.01926 -242.91344)
			(xy 103.0153 -242.864386) (xy 102.686358 -242.864386) (xy 102.685863 -242.888993) (xy 102.677968 -242.93757)
			(xy 102.662384 -242.984251) (xy 102.639513 -243.027828) (xy 102.609948 -243.067172) (xy 102.574455 -243.101264)
			(xy 102.533952 -243.12922) (xy 102.48949 -243.150318) (xy 102.442219 -243.16401) (xy 102.393364 -243.169942)
			(xy 102.344189 -243.167961) (xy 102.29597 -243.158117) (xy 102.249954 -243.140665) (xy 102.207333 -243.116058)
			(xy 102.169212 -243.084933) (xy 102.136577 -243.048096) (xy 102.110274 -243.0065) (xy 102.090983 -242.961224)
			(xy 102.079206 -242.91344) (xy 102.075246 -242.864386) (xy 101.746304 -242.864386) (xy 101.745809 -242.888993)
			(xy 101.737914 -242.93757) (xy 101.72233 -242.984251) (xy 101.699459 -243.027828) (xy 101.669894 -243.067172)
			(xy 101.634401 -243.101264) (xy 101.593898 -243.12922) (xy 101.549436 -243.150318) (xy 101.502165 -243.16401)
			(xy 101.45331 -243.169942) (xy 101.404135 -243.167961) (xy 101.355916 -243.158117) (xy 101.3099 -243.140665)
			(xy 101.267279 -243.116058) (xy 101.229158 -243.084933) (xy 101.196523 -243.048096) (xy 101.17022 -243.0065)
			(xy 101.150929 -242.961224) (xy 101.139152 -242.91344) (xy 101.135192 -242.864386) (xy 100.80625 -242.864386)
			(xy 100.805755 -242.888993) (xy 100.79786 -242.93757) (xy 100.782276 -242.984251) (xy 100.759405 -243.027828)
			(xy 100.72984 -243.067172) (xy 100.694347 -243.101264) (xy 100.653844 -243.12922) (xy 100.609382 -243.150318)
			(xy 100.562111 -243.16401) (xy 100.513256 -243.169942) (xy 100.464081 -243.167961) (xy 100.415862 -243.158117)
			(xy 100.369846 -243.140665) (xy 100.327225 -243.116058) (xy 100.289104 -243.084933) (xy 100.256469 -243.048096)
			(xy 100.230166 -243.0065) (xy 100.210875 -242.961224) (xy 100.199098 -242.91344) (xy 100.195138 -242.864386)
			(xy 99.86645 -242.864386) (xy 99.865955 -242.888993) (xy 99.85806 -242.93757) (xy 99.842476 -242.984251)
			(xy 99.819605 -243.027828) (xy 99.79004 -243.067172) (xy 99.754547 -243.101264) (xy 99.714044 -243.12922)
			(xy 99.669582 -243.150318) (xy 99.622311 -243.16401) (xy 99.573456 -243.169942) (xy 99.524281 -243.167961)
			(xy 99.476062 -243.158117) (xy 99.430046 -243.140665) (xy 99.387425 -243.116058) (xy 99.349304 -243.084933)
			(xy 99.316669 -243.048096) (xy 99.290366 -243.0065) (xy 99.271075 -242.961224) (xy 99.259298 -242.91344)
			(xy 99.255338 -242.864386) (xy 98.926396 -242.864386) (xy 98.925901 -242.888993) (xy 98.918006 -242.93757)
			(xy 98.902422 -242.984251) (xy 98.879551 -243.027828) (xy 98.849986 -243.067172) (xy 98.814493 -243.101264)
			(xy 98.77399 -243.12922) (xy 98.729528 -243.150318) (xy 98.682257 -243.16401) (xy 98.633402 -243.169942)
			(xy 98.584227 -243.167961) (xy 98.536008 -243.158117) (xy 98.489992 -243.140665) (xy 98.447371 -243.116058)
			(xy 98.40925 -243.084933) (xy 98.376615 -243.048096) (xy 98.350312 -243.0065) (xy 98.331021 -242.961224)
			(xy 98.319244 -242.91344) (xy 98.315284 -242.864386) (xy 97.986342 -242.864386) (xy 97.985847 -242.888993)
			(xy 97.977952 -242.93757) (xy 97.962368 -242.984251) (xy 97.939497 -243.027828) (xy 97.909932 -243.067172)
			(xy 97.874439 -243.101264) (xy 97.833936 -243.12922) (xy 97.789474 -243.150318) (xy 97.742203 -243.16401)
			(xy 97.693348 -243.169942) (xy 97.644173 -243.167961) (xy 97.595954 -243.158117) (xy 97.549938 -243.140665)
			(xy 97.507317 -243.116058) (xy 97.469196 -243.084933) (xy 97.436561 -243.048096) (xy 97.410258 -243.0065)
			(xy 97.390967 -242.961224) (xy 97.37919 -242.91344) (xy 97.37523 -242.864386) (xy 97.046873 -242.864386)
			(xy 97.046874 -242.8644) (xy 97.042702 -242.914747) (xy 97.0303 -242.963721) (xy 97.010005 -243.009985)
			(xy 96.982372 -243.052278) (xy 96.948155 -243.089446) (xy 96.908287 -243.120474) (xy 96.863855 -243.144517)
			(xy 96.816071 -243.160918) (xy 96.76624 -243.169231) (xy 96.74098 -243.169694) (xy 96.717213 -243.169246)
			(xy 96.670254 -243.161887) (xy 96.625003 -243.147333) (xy 96.582557 -243.125939) (xy 96.543943 -243.09822)
			(xy 96.510095 -243.064848) (xy 96.495616 -243.045996) (xy 96.490536 -243.039138) (xy 96.48698 -243.034566)
			(xy 96.474788 -243.029486) (xy 96.468505 -243.02696) (xy 96.455111 -243.025018) (xy 96.448372 -243.025676)
			(xy 96.361758 -243.037106) (xy 96.355081 -243.038155) (xy 96.342585 -243.043291) (xy 96.33712 -243.047266)
			(xy 96.326452 -243.055648) (xy 96.323658 -243.063268) (xy 96.321626 -243.068348) (xy 96.308164 -243.09959)
			(xy 96.302016 -243.112715) (xy 96.288548 -243.138382) (xy 96.28124 -243.150898) (xy 96.280986 -243.151152)
			(xy 96.27743 -243.157248) (xy 96.275652 -243.163344) (xy 96.273874 -243.176806) (xy 96.273874 -243.322602)
			(xy 96.274254 -243.331704) (xy 96.28064 -243.348752) (xy 96.28632 -243.355876) (xy 96.291908 -243.362226)
			(xy 96.307402 -243.370862) (xy 96.317054 -243.372386) (xy 96.340798 -243.37648) (xy 96.386689 -243.391159)
			(xy 96.429708 -243.412858) (xy 96.468787 -243.44104) (xy 96.502959 -243.475006) (xy 96.531377 -243.513914)
			(xy 96.553335 -243.556801) (xy 96.568291 -243.602602) (xy 96.575873 -243.650183) (xy 96.575883 -243.674392)
			(xy 96.90533 -243.674392) (xy 96.90929 -243.625338) (xy 96.921067 -243.577554) (xy 96.940358 -243.532278)
			(xy 96.966661 -243.490682) (xy 96.999296 -243.453845) (xy 97.037417 -243.42272) (xy 97.080038 -243.398113)
			(xy 97.126054 -243.380661) (xy 97.174273 -243.370817) (xy 97.223448 -243.368836) (xy 97.272303 -243.374768)
			(xy 97.319574 -243.38846) (xy 97.364036 -243.409558) (xy 97.404539 -243.437514) (xy 97.440032 -243.471606)
			(xy 97.469597 -243.51095) (xy 97.492468 -243.554527) (xy 97.508052 -243.601208) (xy 97.515947 -243.649785)
			(xy 97.516442 -243.674392) (xy 97.84513 -243.674392) (xy 97.84909 -243.625338) (xy 97.860867 -243.577554)
			(xy 97.880158 -243.532278) (xy 97.906461 -243.490682) (xy 97.939096 -243.453845) (xy 97.977217 -243.42272)
			(xy 98.019838 -243.398113) (xy 98.065854 -243.380661) (xy 98.114073 -243.370817) (xy 98.163248 -243.368836)
			(xy 98.212103 -243.374768) (xy 98.259374 -243.38846) (xy 98.303836 -243.409558) (xy 98.344339 -243.437514)
			(xy 98.379832 -243.471606) (xy 98.409397 -243.51095) (xy 98.432268 -243.554527) (xy 98.447852 -243.601208)
			(xy 98.455747 -243.649785) (xy 98.456242 -243.674392) (xy 98.785184 -243.674392) (xy 98.789144 -243.625338)
			(xy 98.800921 -243.577554) (xy 98.820212 -243.532278) (xy 98.846515 -243.490682) (xy 98.87915 -243.453845)
			(xy 98.917271 -243.42272) (xy 98.959892 -243.398113) (xy 99.005908 -243.380661) (xy 99.054127 -243.370817)
			(xy 99.103302 -243.368836) (xy 99.152157 -243.374768) (xy 99.199428 -243.38846) (xy 99.24389 -243.409558)
			(xy 99.284393 -243.437514) (xy 99.319886 -243.471606) (xy 99.349451 -243.51095) (xy 99.372322 -243.554527)
			(xy 99.387906 -243.601208) (xy 99.395801 -243.649785) (xy 99.396296 -243.674392) (xy 99.725238 -243.674392)
			(xy 99.729198 -243.625338) (xy 99.740975 -243.577554) (xy 99.760266 -243.532278) (xy 99.786569 -243.490682)
			(xy 99.819204 -243.453845) (xy 99.857325 -243.42272) (xy 99.899946 -243.398113) (xy 99.945962 -243.380661)
			(xy 99.994181 -243.370817) (xy 100.043356 -243.368836) (xy 100.092211 -243.374768) (xy 100.139482 -243.38846)
			(xy 100.183944 -243.409558) (xy 100.224447 -243.437514) (xy 100.25994 -243.471606) (xy 100.289505 -243.51095)
			(xy 100.312376 -243.554527) (xy 100.32796 -243.601208) (xy 100.335855 -243.649785) (xy 100.33635 -243.674392)
			(xy 100.665292 -243.674392) (xy 100.669252 -243.625338) (xy 100.681029 -243.577554) (xy 100.70032 -243.532278)
			(xy 100.726623 -243.490682) (xy 100.759258 -243.453845) (xy 100.797379 -243.42272) (xy 100.84 -243.398113)
			(xy 100.886016 -243.380661) (xy 100.934235 -243.370817) (xy 100.98341 -243.368836) (xy 101.032265 -243.374768)
			(xy 101.079536 -243.38846) (xy 101.123998 -243.409558) (xy 101.164501 -243.437514) (xy 101.199994 -243.471606)
			(xy 101.229559 -243.51095) (xy 101.25243 -243.554527) (xy 101.268014 -243.601208) (xy 101.275909 -243.649785)
			(xy 101.276404 -243.674392) (xy 101.605346 -243.674392) (xy 101.609306 -243.625338) (xy 101.621083 -243.577554)
			(xy 101.640374 -243.532278) (xy 101.666677 -243.490682) (xy 101.699312 -243.453845) (xy 101.737433 -243.42272)
			(xy 101.780054 -243.398113) (xy 101.82607 -243.380661) (xy 101.874289 -243.370817) (xy 101.923464 -243.368836)
			(xy 101.972319 -243.374768) (xy 102.01959 -243.38846) (xy 102.064052 -243.409558) (xy 102.104555 -243.437514)
			(xy 102.140048 -243.471606) (xy 102.169613 -243.51095) (xy 102.192484 -243.554527) (xy 102.208068 -243.601208)
			(xy 102.215963 -243.649785) (xy 102.216458 -243.674392) (xy 102.545146 -243.674392) (xy 102.549106 -243.625338)
			(xy 102.560883 -243.577554) (xy 102.580174 -243.532278) (xy 102.606477 -243.490682) (xy 102.639112 -243.453845)
			(xy 102.677233 -243.42272) (xy 102.719854 -243.398113) (xy 102.76587 -243.380661) (xy 102.814089 -243.370817)
			(xy 102.863264 -243.368836) (xy 102.912119 -243.374768) (xy 102.95939 -243.38846) (xy 103.003852 -243.409558)
			(xy 103.044355 -243.437514) (xy 103.079848 -243.471606) (xy 103.109413 -243.51095) (xy 103.132284 -243.554527)
			(xy 103.147868 -243.601208) (xy 103.155763 -243.649785) (xy 103.156258 -243.674392) (xy 103.4852 -243.674392)
			(xy 103.48916 -243.625338) (xy 103.500937 -243.577554) (xy 103.520228 -243.532278) (xy 103.546531 -243.490682)
			(xy 103.579166 -243.453845) (xy 103.617287 -243.42272) (xy 103.659908 -243.398113) (xy 103.705924 -243.380661)
			(xy 103.754143 -243.370817) (xy 103.803318 -243.368836) (xy 103.852173 -243.374768) (xy 103.899444 -243.38846)
			(xy 103.943906 -243.409558) (xy 103.984409 -243.437514) (xy 104.019902 -243.471606) (xy 104.049467 -243.51095)
			(xy 104.072338 -243.554527) (xy 104.087922 -243.601208) (xy 104.095817 -243.649785) (xy 104.096312 -243.674392)
			(xy 104.425254 -243.674392) (xy 104.429214 -243.625338) (xy 104.440991 -243.577554) (xy 104.460282 -243.532278)
			(xy 104.486585 -243.490682) (xy 104.51922 -243.453845) (xy 104.557341 -243.42272) (xy 104.599962 -243.398113)
			(xy 104.645978 -243.380661) (xy 104.694197 -243.370817) (xy 104.743372 -243.368836) (xy 104.792227 -243.374768)
			(xy 104.839498 -243.38846) (xy 104.88396 -243.409558) (xy 104.924463 -243.437514) (xy 104.959956 -243.471606)
			(xy 104.989521 -243.51095) (xy 105.012392 -243.554527) (xy 105.027976 -243.601208) (xy 105.035871 -243.649785)
			(xy 105.036366 -243.674392) (xy 105.365308 -243.674392) (xy 105.369268 -243.625338) (xy 105.381045 -243.577554)
			(xy 105.400336 -243.532278) (xy 105.426639 -243.490682) (xy 105.459274 -243.453845) (xy 105.497395 -243.42272)
			(xy 105.540016 -243.398113) (xy 105.586032 -243.380661) (xy 105.634251 -243.370817) (xy 105.683426 -243.368836)
			(xy 105.732281 -243.374768) (xy 105.779552 -243.38846) (xy 105.824014 -243.409558) (xy 105.864517 -243.437514)
			(xy 105.90001 -243.471606) (xy 105.929575 -243.51095) (xy 105.952446 -243.554527) (xy 105.96803 -243.601208)
			(xy 105.975925 -243.649785) (xy 105.97642 -243.674392) (xy 106.305362 -243.674392) (xy 106.309322 -243.625338)
			(xy 106.321099 -243.577554) (xy 106.34039 -243.532278) (xy 106.366693 -243.490682) (xy 106.399328 -243.453845)
			(xy 106.437449 -243.42272) (xy 106.48007 -243.398113) (xy 106.526086 -243.380661) (xy 106.574305 -243.370817)
			(xy 106.62348 -243.368836) (xy 106.672335 -243.374768) (xy 106.719606 -243.38846) (xy 106.764068 -243.409558)
			(xy 106.804571 -243.437514) (xy 106.840064 -243.471606) (xy 106.869629 -243.51095) (xy 106.8925 -243.554527)
			(xy 106.908084 -243.601208) (xy 106.915979 -243.649785) (xy 106.916474 -243.674392) (xy 107.245162 -243.674392)
			(xy 107.249122 -243.625338) (xy 107.260899 -243.577554) (xy 107.28019 -243.532278) (xy 107.306493 -243.490682)
			(xy 107.339128 -243.453845) (xy 107.377249 -243.42272) (xy 107.41987 -243.398113) (xy 107.465886 -243.380661)
			(xy 107.514105 -243.370817) (xy 107.56328 -243.368836) (xy 107.612135 -243.374768) (xy 107.659406 -243.38846)
			(xy 107.703868 -243.409558) (xy 107.744371 -243.437514) (xy 107.779864 -243.471606) (xy 107.809429 -243.51095)
			(xy 107.8323 -243.554527) (xy 107.847884 -243.601208) (xy 107.855779 -243.649785) (xy 107.856274 -243.674392)
			(xy 107.856274 -243.6744) (xy 108.185132 -243.6744) (xy 108.189304 -243.624054) (xy 108.201706 -243.575081)
			(xy 108.222 -243.528817) (xy 108.249632 -243.486525) (xy 108.283849 -243.449358) (xy 108.323717 -243.418331)
			(xy 108.368148 -243.394288) (xy 108.41593 -243.377887) (xy 108.465761 -243.369575) (xy 108.49102 -243.369084)
			(xy 109.431074 -243.369084) (xy 109.456332 -243.369591) (xy 109.506161 -243.377902) (xy 109.553942 -243.394301)
			(xy 109.598371 -243.418342) (xy 109.638238 -243.449368) (xy 109.672453 -243.486533) (xy 109.700085 -243.528823)
			(xy 109.720378 -243.575085) (xy 109.73278 -243.624056) (xy 109.736951 -243.674392) (xy 110.065324 -243.674392)
			(xy 110.069284 -243.625338) (xy 110.081061 -243.577554) (xy 110.100352 -243.532278) (xy 110.126655 -243.490682)
			(xy 110.15929 -243.453845) (xy 110.197411 -243.42272) (xy 110.240032 -243.398113) (xy 110.286048 -243.380661)
			(xy 110.334267 -243.370817) (xy 110.383442 -243.368836) (xy 110.432297 -243.374768) (xy 110.479568 -243.38846)
			(xy 110.52403 -243.409558) (xy 110.564533 -243.437514) (xy 110.600026 -243.471606) (xy 110.629591 -243.51095)
			(xy 110.652462 -243.554527) (xy 110.668046 -243.601208) (xy 110.675941 -243.649785) (xy 110.676436 -243.674392)
			(xy 112.878882 -243.674392) (xy 112.882842 -243.625338) (xy 112.894619 -243.577554) (xy 112.91391 -243.532278)
			(xy 112.940213 -243.490682) (xy 112.972848 -243.453845) (xy 113.010969 -243.42272) (xy 113.05359 -243.398113)
			(xy 113.099606 -243.380661) (xy 113.147825 -243.370817) (xy 113.197 -243.368836) (xy 113.245855 -243.374768)
			(xy 113.293126 -243.38846) (xy 113.337588 -243.409558) (xy 113.378091 -243.437514) (xy 113.413584 -243.471606)
			(xy 113.443149 -243.51095) (xy 113.46602 -243.554527) (xy 113.481604 -243.601208) (xy 113.489499 -243.649785)
			(xy 113.489994 -243.674392) (xy 113.818936 -243.674392) (xy 113.822896 -243.625338) (xy 113.834673 -243.577554)
			(xy 113.853964 -243.532278) (xy 113.880267 -243.490682) (xy 113.912902 -243.453845) (xy 113.951023 -243.42272)
			(xy 113.993644 -243.398113) (xy 114.03966 -243.380661) (xy 114.087879 -243.370817) (xy 114.137054 -243.368836)
			(xy 114.185909 -243.374768) (xy 114.23318 -243.38846) (xy 114.277642 -243.409558) (xy 114.318145 -243.437514)
			(xy 114.353638 -243.471606) (xy 114.383203 -243.51095) (xy 114.406074 -243.554527) (xy 114.421658 -243.601208)
			(xy 114.429553 -243.649785) (xy 114.430048 -243.674392) (xy 114.75899 -243.674392) (xy 114.76295 -243.625338)
			(xy 114.774727 -243.577554) (xy 114.794018 -243.532278) (xy 114.820321 -243.490682) (xy 114.852956 -243.453845)
			(xy 114.891077 -243.42272) (xy 114.933698 -243.398113) (xy 114.979714 -243.380661) (xy 115.027933 -243.370817)
			(xy 115.077108 -243.368836) (xy 115.125963 -243.374768) (xy 115.173234 -243.38846) (xy 115.217696 -243.409558)
			(xy 115.258199 -243.437514) (xy 115.293692 -243.471606) (xy 115.323257 -243.51095) (xy 115.346128 -243.554527)
			(xy 115.361712 -243.601208) (xy 115.369607 -243.649785) (xy 115.370102 -243.674392) (xy 115.699044 -243.674392)
			(xy 115.703004 -243.625338) (xy 115.714781 -243.577554) (xy 115.734072 -243.532278) (xy 115.760375 -243.490682)
			(xy 115.79301 -243.453845) (xy 115.831131 -243.42272) (xy 115.873752 -243.398113) (xy 115.919768 -243.380661)
			(xy 115.967987 -243.370817) (xy 116.017162 -243.368836) (xy 116.066017 -243.374768) (xy 116.113288 -243.38846)
			(xy 116.15775 -243.409558) (xy 116.198253 -243.437514) (xy 116.233746 -243.471606) (xy 116.263311 -243.51095)
			(xy 116.286182 -243.554527) (xy 116.301766 -243.601208) (xy 116.309661 -243.649785) (xy 116.310156 -243.674392)
			(xy 116.638844 -243.674392) (xy 116.642804 -243.625338) (xy 116.654581 -243.577554) (xy 116.673872 -243.532278)
			(xy 116.700175 -243.490682) (xy 116.73281 -243.453845) (xy 116.770931 -243.42272) (xy 116.813552 -243.398113)
			(xy 116.859568 -243.380661) (xy 116.907787 -243.370817) (xy 116.956962 -243.368836) (xy 117.005817 -243.374768)
			(xy 117.053088 -243.38846) (xy 117.09755 -243.409558) (xy 117.138053 -243.437514) (xy 117.173546 -243.471606)
			(xy 117.203111 -243.51095) (xy 117.225982 -243.554527) (xy 117.241566 -243.601208) (xy 117.249461 -243.649785)
			(xy 117.249956 -243.674392) (xy 117.578898 -243.674392) (xy 117.582858 -243.625338) (xy 117.594635 -243.577554)
			(xy 117.613926 -243.532278) (xy 117.640229 -243.490682) (xy 117.672864 -243.453845) (xy 117.710985 -243.42272)
			(xy 117.753606 -243.398113) (xy 117.799622 -243.380661) (xy 117.847841 -243.370817) (xy 117.897016 -243.368836)
			(xy 117.945871 -243.374768) (xy 117.993142 -243.38846) (xy 118.037604 -243.409558) (xy 118.078107 -243.437514)
			(xy 118.1136 -243.471606) (xy 118.143165 -243.51095) (xy 118.166036 -243.554527) (xy 118.18162 -243.601208)
			(xy 118.189515 -243.649785) (xy 118.19001 -243.674392) (xy 118.518952 -243.674392) (xy 118.522912 -243.625338)
			(xy 118.534689 -243.577554) (xy 118.55398 -243.532278) (xy 118.580283 -243.490682) (xy 118.612918 -243.453845)
			(xy 118.651039 -243.42272) (xy 118.69366 -243.398113) (xy 118.739676 -243.380661) (xy 118.787895 -243.370817)
			(xy 118.83707 -243.368836) (xy 118.885925 -243.374768) (xy 118.933196 -243.38846) (xy 118.977658 -243.409558)
			(xy 119.018161 -243.437514) (xy 119.053654 -243.471606) (xy 119.083219 -243.51095) (xy 119.10609 -243.554527)
			(xy 119.121674 -243.601208) (xy 119.129569 -243.649785) (xy 119.130064 -243.674392) (xy 119.459006 -243.674392)
			(xy 119.462966 -243.625338) (xy 119.474743 -243.577554) (xy 119.494034 -243.532278) (xy 119.520337 -243.490682)
			(xy 119.552972 -243.453845) (xy 119.591093 -243.42272) (xy 119.633714 -243.398113) (xy 119.67973 -243.380661)
			(xy 119.727949 -243.370817) (xy 119.777124 -243.368836) (xy 119.825979 -243.374768) (xy 119.87325 -243.38846)
			(xy 119.917712 -243.409558) (xy 119.958215 -243.437514) (xy 119.993708 -243.471606) (xy 120.023273 -243.51095)
			(xy 120.046144 -243.554527) (xy 120.061728 -243.601208) (xy 120.069623 -243.649785) (xy 120.070118 -243.674392)
			(xy 120.398806 -243.674392) (xy 120.402766 -243.625338) (xy 120.414543 -243.577554) (xy 120.433834 -243.532278)
			(xy 120.460137 -243.490682) (xy 120.492772 -243.453845) (xy 120.530893 -243.42272) (xy 120.573514 -243.398113)
			(xy 120.61953 -243.380661) (xy 120.667749 -243.370817) (xy 120.716924 -243.368836) (xy 120.765779 -243.374768)
			(xy 120.81305 -243.38846) (xy 120.857512 -243.409558) (xy 120.898015 -243.437514) (xy 120.933508 -243.471606)
			(xy 120.963073 -243.51095) (xy 120.985944 -243.554527) (xy 121.001528 -243.601208) (xy 121.009423 -243.649785)
			(xy 121.009918 -243.674392) (xy 121.33886 -243.674392) (xy 121.34282 -243.625338) (xy 121.354597 -243.577554)
			(xy 121.373888 -243.532278) (xy 121.400191 -243.490682) (xy 121.432826 -243.453845) (xy 121.470947 -243.42272)
			(xy 121.513568 -243.398113) (xy 121.559584 -243.380661) (xy 121.607803 -243.370817) (xy 121.656978 -243.368836)
			(xy 121.705833 -243.374768) (xy 121.753104 -243.38846) (xy 121.797566 -243.409558) (xy 121.838069 -243.437514)
			(xy 121.873562 -243.471606) (xy 121.903127 -243.51095) (xy 121.925998 -243.554527) (xy 121.941582 -243.601208)
			(xy 121.949477 -243.649785) (xy 121.949972 -243.674392) (xy 122.278914 -243.674392) (xy 122.282874 -243.625338)
			(xy 122.294651 -243.577554) (xy 122.313942 -243.532278) (xy 122.340245 -243.490682) (xy 122.37288 -243.453845)
			(xy 122.411001 -243.42272) (xy 122.453622 -243.398113) (xy 122.499638 -243.380661) (xy 122.547857 -243.370817)
			(xy 122.597032 -243.368836) (xy 122.645887 -243.374768) (xy 122.693158 -243.38846) (xy 122.73762 -243.409558)
			(xy 122.778123 -243.437514) (xy 122.813616 -243.471606) (xy 122.843181 -243.51095) (xy 122.866052 -243.554527)
			(xy 122.881636 -243.601208) (xy 122.889531 -243.649785) (xy 122.890026 -243.674392) (xy 123.218968 -243.674392)
			(xy 123.222928 -243.625338) (xy 123.234705 -243.577554) (xy 123.253996 -243.532278) (xy 123.280299 -243.490682)
			(xy 123.312934 -243.453845) (xy 123.351055 -243.42272) (xy 123.393676 -243.398113) (xy 123.439692 -243.380661)
			(xy 123.487911 -243.370817) (xy 123.537086 -243.368836) (xy 123.585941 -243.374768) (xy 123.633212 -243.38846)
			(xy 123.677674 -243.409558) (xy 123.718177 -243.437514) (xy 123.75367 -243.471606) (xy 123.783235 -243.51095)
			(xy 123.806106 -243.554527) (xy 123.82169 -243.601208) (xy 123.829585 -243.649785) (xy 123.83008 -243.674392)
			(xy 124.159022 -243.674392) (xy 124.162982 -243.625338) (xy 124.174759 -243.577554) (xy 124.19405 -243.532278)
			(xy 124.220353 -243.490682) (xy 124.252988 -243.453845) (xy 124.291109 -243.42272) (xy 124.33373 -243.398113)
			(xy 124.379746 -243.380661) (xy 124.427965 -243.370817) (xy 124.47714 -243.368836) (xy 124.525995 -243.374768)
			(xy 124.573266 -243.38846) (xy 124.617728 -243.409558) (xy 124.658231 -243.437514) (xy 124.693724 -243.471606)
			(xy 124.723289 -243.51095) (xy 124.74616 -243.554527) (xy 124.761744 -243.601208) (xy 124.769639 -243.649785)
			(xy 124.770134 -243.674392) (xy 125.098822 -243.674392) (xy 125.102782 -243.625338) (xy 125.114559 -243.577554)
			(xy 125.13385 -243.532278) (xy 125.160153 -243.490682) (xy 125.192788 -243.453845) (xy 125.230909 -243.42272)
			(xy 125.27353 -243.398113) (xy 125.319546 -243.380661) (xy 125.367765 -243.370817) (xy 125.41694 -243.368836)
			(xy 125.465795 -243.374768) (xy 125.513066 -243.38846) (xy 125.557528 -243.409558) (xy 125.598031 -243.437514)
			(xy 125.633524 -243.471606) (xy 125.663089 -243.51095) (xy 125.68596 -243.554527) (xy 125.701544 -243.601208)
			(xy 125.709439 -243.649785) (xy 125.709934 -243.674392) (xy 126.038876 -243.674392) (xy 126.042836 -243.625338)
			(xy 126.054613 -243.577554) (xy 126.073904 -243.532278) (xy 126.100207 -243.490682) (xy 126.132842 -243.453845)
			(xy 126.170963 -243.42272) (xy 126.213584 -243.398113) (xy 126.2596 -243.380661) (xy 126.307819 -243.370817)
			(xy 126.356994 -243.368836) (xy 126.405849 -243.374768) (xy 126.45312 -243.38846) (xy 126.497582 -243.409558)
			(xy 126.538085 -243.437514) (xy 126.573578 -243.471606) (xy 126.603143 -243.51095) (xy 126.626014 -243.554527)
			(xy 126.641598 -243.601208) (xy 126.649493 -243.649785) (xy 126.649988 -243.674392) (xy 126.649493 -243.698999)
			(xy 126.641598 -243.747576) (xy 126.626014 -243.794257) (xy 126.603143 -243.837834) (xy 126.573578 -243.877178)
			(xy 126.538085 -243.91127) (xy 126.497582 -243.939226) (xy 126.45312 -243.960324) (xy 126.405849 -243.974016)
			(xy 126.356994 -243.979948) (xy 126.307819 -243.977967) (xy 126.2596 -243.968123) (xy 126.213584 -243.950671)
			(xy 126.170963 -243.926064) (xy 126.132842 -243.894939) (xy 126.100207 -243.858102) (xy 126.073904 -243.816506)
			(xy 126.054613 -243.77123) (xy 126.042836 -243.723446) (xy 126.038876 -243.674392) (xy 125.709934 -243.674392)
			(xy 125.709439 -243.698999) (xy 125.701544 -243.747576) (xy 125.68596 -243.794257) (xy 125.663089 -243.837834)
			(xy 125.633524 -243.877178) (xy 125.598031 -243.91127) (xy 125.557528 -243.939226) (xy 125.513066 -243.960324)
			(xy 125.465795 -243.974016) (xy 125.41694 -243.979948) (xy 125.367765 -243.977967) (xy 125.319546 -243.968123)
			(xy 125.27353 -243.950671) (xy 125.230909 -243.926064) (xy 125.192788 -243.894939) (xy 125.160153 -243.858102)
			(xy 125.13385 -243.816506) (xy 125.114559 -243.77123) (xy 125.102782 -243.723446) (xy 125.098822 -243.674392)
			(xy 124.770134 -243.674392) (xy 124.769639 -243.698999) (xy 124.761744 -243.747576) (xy 124.74616 -243.794257)
			(xy 124.723289 -243.837834) (xy 124.693724 -243.877178) (xy 124.658231 -243.91127) (xy 124.617728 -243.939226)
			(xy 124.573266 -243.960324) (xy 124.525995 -243.974016) (xy 124.47714 -243.979948) (xy 124.427965 -243.977967)
			(xy 124.379746 -243.968123) (xy 124.33373 -243.950671) (xy 124.291109 -243.926064) (xy 124.252988 -243.894939)
			(xy 124.220353 -243.858102) (xy 124.19405 -243.816506) (xy 124.174759 -243.77123) (xy 124.162982 -243.723446)
			(xy 124.159022 -243.674392) (xy 123.83008 -243.674392) (xy 123.829585 -243.698999) (xy 123.82169 -243.747576)
			(xy 123.806106 -243.794257) (xy 123.783235 -243.837834) (xy 123.75367 -243.877178) (xy 123.718177 -243.91127)
			(xy 123.677674 -243.939226) (xy 123.633212 -243.960324) (xy 123.585941 -243.974016) (xy 123.537086 -243.979948)
			(xy 123.487911 -243.977967) (xy 123.439692 -243.968123) (xy 123.393676 -243.950671) (xy 123.351055 -243.926064)
			(xy 123.312934 -243.894939) (xy 123.280299 -243.858102) (xy 123.253996 -243.816506) (xy 123.234705 -243.77123)
			(xy 123.222928 -243.723446) (xy 123.218968 -243.674392) (xy 122.890026 -243.674392) (xy 122.889531 -243.698999)
			(xy 122.881636 -243.747576) (xy 122.866052 -243.794257) (xy 122.843181 -243.837834) (xy 122.813616 -243.877178)
			(xy 122.778123 -243.91127) (xy 122.73762 -243.939226) (xy 122.693158 -243.960324) (xy 122.645887 -243.974016)
			(xy 122.597032 -243.979948) (xy 122.547857 -243.977967) (xy 122.499638 -243.968123) (xy 122.453622 -243.950671)
			(xy 122.411001 -243.926064) (xy 122.37288 -243.894939) (xy 122.340245 -243.858102) (xy 122.313942 -243.816506)
			(xy 122.294651 -243.77123) (xy 122.282874 -243.723446) (xy 122.278914 -243.674392) (xy 121.949972 -243.674392)
			(xy 121.949477 -243.698999) (xy 121.941582 -243.747576) (xy 121.925998 -243.794257) (xy 121.903127 -243.837834)
			(xy 121.873562 -243.877178) (xy 121.838069 -243.91127) (xy 121.797566 -243.939226) (xy 121.753104 -243.960324)
			(xy 121.705833 -243.974016) (xy 121.656978 -243.979948) (xy 121.607803 -243.977967) (xy 121.559584 -243.968123)
			(xy 121.513568 -243.950671) (xy 121.470947 -243.926064) (xy 121.432826 -243.894939) (xy 121.400191 -243.858102)
			(xy 121.373888 -243.816506) (xy 121.354597 -243.77123) (xy 121.34282 -243.723446) (xy 121.33886 -243.674392)
			(xy 121.009918 -243.674392) (xy 121.009423 -243.698999) (xy 121.001528 -243.747576) (xy 120.985944 -243.794257)
			(xy 120.963073 -243.837834) (xy 120.933508 -243.877178) (xy 120.898015 -243.91127) (xy 120.857512 -243.939226)
			(xy 120.81305 -243.960324) (xy 120.765779 -243.974016) (xy 120.716924 -243.979948) (xy 120.667749 -243.977967)
			(xy 120.61953 -243.968123) (xy 120.573514 -243.950671) (xy 120.530893 -243.926064) (xy 120.492772 -243.894939)
			(xy 120.460137 -243.858102) (xy 120.433834 -243.816506) (xy 120.414543 -243.77123) (xy 120.402766 -243.723446)
			(xy 120.398806 -243.674392) (xy 120.070118 -243.674392) (xy 120.069623 -243.698999) (xy 120.061728 -243.747576)
			(xy 120.046144 -243.794257) (xy 120.023273 -243.837834) (xy 119.993708 -243.877178) (xy 119.958215 -243.91127)
			(xy 119.917712 -243.939226) (xy 119.87325 -243.960324) (xy 119.825979 -243.974016) (xy 119.777124 -243.979948)
			(xy 119.727949 -243.977967) (xy 119.67973 -243.968123) (xy 119.633714 -243.950671) (xy 119.591093 -243.926064)
			(xy 119.552972 -243.894939) (xy 119.520337 -243.858102) (xy 119.494034 -243.816506) (xy 119.474743 -243.77123)
			(xy 119.462966 -243.723446) (xy 119.459006 -243.674392) (xy 119.130064 -243.674392) (xy 119.129569 -243.698999)
			(xy 119.121674 -243.747576) (xy 119.10609 -243.794257) (xy 119.083219 -243.837834) (xy 119.053654 -243.877178)
			(xy 119.018161 -243.91127) (xy 118.977658 -243.939226) (xy 118.933196 -243.960324) (xy 118.885925 -243.974016)
			(xy 118.83707 -243.979948) (xy 118.787895 -243.977967) (xy 118.739676 -243.968123) (xy 118.69366 -243.950671)
			(xy 118.651039 -243.926064) (xy 118.612918 -243.894939) (xy 118.580283 -243.858102) (xy 118.55398 -243.816506)
			(xy 118.534689 -243.77123) (xy 118.522912 -243.723446) (xy 118.518952 -243.674392) (xy 118.19001 -243.674392)
			(xy 118.189515 -243.698999) (xy 118.18162 -243.747576) (xy 118.166036 -243.794257) (xy 118.143165 -243.837834)
			(xy 118.1136 -243.877178) (xy 118.078107 -243.91127) (xy 118.037604 -243.939226) (xy 117.993142 -243.960324)
			(xy 117.945871 -243.974016) (xy 117.897016 -243.979948) (xy 117.847841 -243.977967) (xy 117.799622 -243.968123)
			(xy 117.753606 -243.950671) (xy 117.710985 -243.926064) (xy 117.672864 -243.894939) (xy 117.640229 -243.858102)
			(xy 117.613926 -243.816506) (xy 117.594635 -243.77123) (xy 117.582858 -243.723446) (xy 117.578898 -243.674392)
			(xy 117.249956 -243.674392) (xy 117.249461 -243.698999) (xy 117.241566 -243.747576) (xy 117.225982 -243.794257)
			(xy 117.203111 -243.837834) (xy 117.173546 -243.877178) (xy 117.138053 -243.91127) (xy 117.09755 -243.939226)
			(xy 117.053088 -243.960324) (xy 117.005817 -243.974016) (xy 116.956962 -243.979948) (xy 116.907787 -243.977967)
			(xy 116.859568 -243.968123) (xy 116.813552 -243.950671) (xy 116.770931 -243.926064) (xy 116.73281 -243.894939)
			(xy 116.700175 -243.858102) (xy 116.673872 -243.816506) (xy 116.654581 -243.77123) (xy 116.642804 -243.723446)
			(xy 116.638844 -243.674392) (xy 116.310156 -243.674392) (xy 116.309661 -243.698999) (xy 116.301766 -243.747576)
			(xy 116.286182 -243.794257) (xy 116.263311 -243.837834) (xy 116.233746 -243.877178) (xy 116.198253 -243.91127)
			(xy 116.15775 -243.939226) (xy 116.113288 -243.960324) (xy 116.066017 -243.974016) (xy 116.017162 -243.979948)
			(xy 115.967987 -243.977967) (xy 115.919768 -243.968123) (xy 115.873752 -243.950671) (xy 115.831131 -243.926064)
			(xy 115.79301 -243.894939) (xy 115.760375 -243.858102) (xy 115.734072 -243.816506) (xy 115.714781 -243.77123)
			(xy 115.703004 -243.723446) (xy 115.699044 -243.674392) (xy 115.370102 -243.674392) (xy 115.369607 -243.698999)
			(xy 115.361712 -243.747576) (xy 115.346128 -243.794257) (xy 115.323257 -243.837834) (xy 115.293692 -243.877178)
			(xy 115.258199 -243.91127) (xy 115.217696 -243.939226) (xy 115.173234 -243.960324) (xy 115.125963 -243.974016)
			(xy 115.077108 -243.979948) (xy 115.027933 -243.977967) (xy 114.979714 -243.968123) (xy 114.933698 -243.950671)
			(xy 114.891077 -243.926064) (xy 114.852956 -243.894939) (xy 114.820321 -243.858102) (xy 114.794018 -243.816506)
			(xy 114.774727 -243.77123) (xy 114.76295 -243.723446) (xy 114.75899 -243.674392) (xy 114.430048 -243.674392)
			(xy 114.429553 -243.698999) (xy 114.421658 -243.747576) (xy 114.406074 -243.794257) (xy 114.383203 -243.837834)
			(xy 114.353638 -243.877178) (xy 114.318145 -243.91127) (xy 114.277642 -243.939226) (xy 114.23318 -243.960324)
			(xy 114.185909 -243.974016) (xy 114.137054 -243.979948) (xy 114.087879 -243.977967) (xy 114.03966 -243.968123)
			(xy 113.993644 -243.950671) (xy 113.951023 -243.926064) (xy 113.912902 -243.894939) (xy 113.880267 -243.858102)
			(xy 113.853964 -243.816506) (xy 113.834673 -243.77123) (xy 113.822896 -243.723446) (xy 113.818936 -243.674392)
			(xy 113.489994 -243.674392) (xy 113.489499 -243.698999) (xy 113.481604 -243.747576) (xy 113.46602 -243.794257)
			(xy 113.443149 -243.837834) (xy 113.413584 -243.877178) (xy 113.378091 -243.91127) (xy 113.337588 -243.939226)
			(xy 113.293126 -243.960324) (xy 113.245855 -243.974016) (xy 113.197 -243.979948) (xy 113.147825 -243.977967)
			(xy 113.099606 -243.968123) (xy 113.05359 -243.950671) (xy 113.010969 -243.926064) (xy 112.972848 -243.894939)
			(xy 112.940213 -243.858102) (xy 112.91391 -243.816506) (xy 112.894619 -243.77123) (xy 112.882842 -243.723446)
			(xy 112.878882 -243.674392) (xy 110.676436 -243.674392) (xy 110.675941 -243.698999) (xy 110.668046 -243.747576)
			(xy 110.652462 -243.794257) (xy 110.629591 -243.837834) (xy 110.600026 -243.877178) (xy 110.564533 -243.91127)
			(xy 110.52403 -243.939226) (xy 110.479568 -243.960324) (xy 110.432297 -243.974016) (xy 110.383442 -243.979948)
			(xy 110.334267 -243.977967) (xy 110.286048 -243.968123) (xy 110.240032 -243.950671) (xy 110.197411 -243.926064)
			(xy 110.15929 -243.894939) (xy 110.126655 -243.858102) (xy 110.100352 -243.816506) (xy 110.081061 -243.77123)
			(xy 110.069284 -243.723446) (xy 110.065324 -243.674392) (xy 109.736951 -243.674392) (xy 109.736952 -243.6744)
			(xy 109.73278 -243.724744) (xy 109.720378 -243.773715) (xy 109.700085 -243.819977) (xy 109.672453 -243.862267)
			(xy 109.638238 -243.899432) (xy 109.598371 -243.930458) (xy 109.553942 -243.954499) (xy 109.506161 -243.970898)
			(xy 109.456332 -243.979209) (xy 109.431074 -243.9797) (xy 108.49102 -243.9797) (xy 108.465761 -243.979225)
			(xy 108.41593 -243.970913) (xy 108.368148 -243.954512) (xy 108.323717 -243.930469) (xy 108.283849 -243.899442)
			(xy 108.249632 -243.862275) (xy 108.222 -243.819983) (xy 108.201706 -243.773719) (xy 108.189304 -243.724746)
			(xy 108.185132 -243.6744) (xy 107.856274 -243.6744) (xy 107.855779 -243.698999) (xy 107.847884 -243.747576)
			(xy 107.8323 -243.794257) (xy 107.809429 -243.837834) (xy 107.779864 -243.877178) (xy 107.744371 -243.91127)
			(xy 107.703868 -243.939226) (xy 107.659406 -243.960324) (xy 107.612135 -243.974016) (xy 107.56328 -243.979948)
			(xy 107.514105 -243.977967) (xy 107.465886 -243.968123) (xy 107.41987 -243.950671) (xy 107.377249 -243.926064)
			(xy 107.339128 -243.894939) (xy 107.306493 -243.858102) (xy 107.28019 -243.816506) (xy 107.260899 -243.77123)
			(xy 107.249122 -243.723446) (xy 107.245162 -243.674392) (xy 106.916474 -243.674392) (xy 106.915979 -243.698999)
			(xy 106.908084 -243.747576) (xy 106.8925 -243.794257) (xy 106.869629 -243.837834) (xy 106.840064 -243.877178)
			(xy 106.804571 -243.91127) (xy 106.764068 -243.939226) (xy 106.719606 -243.960324) (xy 106.672335 -243.974016)
			(xy 106.62348 -243.979948) (xy 106.574305 -243.977967) (xy 106.526086 -243.968123) (xy 106.48007 -243.950671)
			(xy 106.437449 -243.926064) (xy 106.399328 -243.894939) (xy 106.366693 -243.858102) (xy 106.34039 -243.816506)
			(xy 106.321099 -243.77123) (xy 106.309322 -243.723446) (xy 106.305362 -243.674392) (xy 105.97642 -243.674392)
			(xy 105.975925 -243.698999) (xy 105.96803 -243.747576) (xy 105.952446 -243.794257) (xy 105.929575 -243.837834)
			(xy 105.90001 -243.877178) (xy 105.864517 -243.91127) (xy 105.824014 -243.939226) (xy 105.779552 -243.960324)
			(xy 105.732281 -243.974016) (xy 105.683426 -243.979948) (xy 105.634251 -243.977967) (xy 105.586032 -243.968123)
			(xy 105.540016 -243.950671) (xy 105.497395 -243.926064) (xy 105.459274 -243.894939) (xy 105.426639 -243.858102)
			(xy 105.400336 -243.816506) (xy 105.381045 -243.77123) (xy 105.369268 -243.723446) (xy 105.365308 -243.674392)
			(xy 105.036366 -243.674392) (xy 105.035871 -243.698999) (xy 105.027976 -243.747576) (xy 105.012392 -243.794257)
			(xy 104.989521 -243.837834) (xy 104.959956 -243.877178) (xy 104.924463 -243.91127) (xy 104.88396 -243.939226)
			(xy 104.839498 -243.960324) (xy 104.792227 -243.974016) (xy 104.743372 -243.979948) (xy 104.694197 -243.977967)
			(xy 104.645978 -243.968123) (xy 104.599962 -243.950671) (xy 104.557341 -243.926064) (xy 104.51922 -243.894939)
			(xy 104.486585 -243.858102) (xy 104.460282 -243.816506) (xy 104.440991 -243.77123) (xy 104.429214 -243.723446)
			(xy 104.425254 -243.674392) (xy 104.096312 -243.674392) (xy 104.095817 -243.698999) (xy 104.087922 -243.747576)
			(xy 104.072338 -243.794257) (xy 104.049467 -243.837834) (xy 104.019902 -243.877178) (xy 103.984409 -243.91127)
			(xy 103.943906 -243.939226) (xy 103.899444 -243.960324) (xy 103.852173 -243.974016) (xy 103.803318 -243.979948)
			(xy 103.754143 -243.977967) (xy 103.705924 -243.968123) (xy 103.659908 -243.950671) (xy 103.617287 -243.926064)
			(xy 103.579166 -243.894939) (xy 103.546531 -243.858102) (xy 103.520228 -243.816506) (xy 103.500937 -243.77123)
			(xy 103.48916 -243.723446) (xy 103.4852 -243.674392) (xy 103.156258 -243.674392) (xy 103.155763 -243.698999)
			(xy 103.147868 -243.747576) (xy 103.132284 -243.794257) (xy 103.109413 -243.837834) (xy 103.079848 -243.877178)
			(xy 103.044355 -243.91127) (xy 103.003852 -243.939226) (xy 102.95939 -243.960324) (xy 102.912119 -243.974016)
			(xy 102.863264 -243.979948) (xy 102.814089 -243.977967) (xy 102.76587 -243.968123) (xy 102.719854 -243.950671)
			(xy 102.677233 -243.926064) (xy 102.639112 -243.894939) (xy 102.606477 -243.858102) (xy 102.580174 -243.816506)
			(xy 102.560883 -243.77123) (xy 102.549106 -243.723446) (xy 102.545146 -243.674392) (xy 102.216458 -243.674392)
			(xy 102.215963 -243.698999) (xy 102.208068 -243.747576) (xy 102.192484 -243.794257) (xy 102.169613 -243.837834)
			(xy 102.140048 -243.877178) (xy 102.104555 -243.91127) (xy 102.064052 -243.939226) (xy 102.01959 -243.960324)
			(xy 101.972319 -243.974016) (xy 101.923464 -243.979948) (xy 101.874289 -243.977967) (xy 101.82607 -243.968123)
			(xy 101.780054 -243.950671) (xy 101.737433 -243.926064) (xy 101.699312 -243.894939) (xy 101.666677 -243.858102)
			(xy 101.640374 -243.816506) (xy 101.621083 -243.77123) (xy 101.609306 -243.723446) (xy 101.605346 -243.674392)
			(xy 101.276404 -243.674392) (xy 101.275909 -243.698999) (xy 101.268014 -243.747576) (xy 101.25243 -243.794257)
			(xy 101.229559 -243.837834) (xy 101.199994 -243.877178) (xy 101.164501 -243.91127) (xy 101.123998 -243.939226)
			(xy 101.079536 -243.960324) (xy 101.032265 -243.974016) (xy 100.98341 -243.979948) (xy 100.934235 -243.977967)
			(xy 100.886016 -243.968123) (xy 100.84 -243.950671) (xy 100.797379 -243.926064) (xy 100.759258 -243.894939)
			(xy 100.726623 -243.858102) (xy 100.70032 -243.816506) (xy 100.681029 -243.77123) (xy 100.669252 -243.723446)
			(xy 100.665292 -243.674392) (xy 100.33635 -243.674392) (xy 100.335855 -243.698999) (xy 100.32796 -243.747576)
			(xy 100.312376 -243.794257) (xy 100.289505 -243.837834) (xy 100.25994 -243.877178) (xy 100.224447 -243.91127)
			(xy 100.183944 -243.939226) (xy 100.139482 -243.960324) (xy 100.092211 -243.974016) (xy 100.043356 -243.979948)
			(xy 99.994181 -243.977967) (xy 99.945962 -243.968123) (xy 99.899946 -243.950671) (xy 99.857325 -243.926064)
			(xy 99.819204 -243.894939) (xy 99.786569 -243.858102) (xy 99.760266 -243.816506) (xy 99.740975 -243.77123)
			(xy 99.729198 -243.723446) (xy 99.725238 -243.674392) (xy 99.396296 -243.674392) (xy 99.395801 -243.698999)
			(xy 99.387906 -243.747576) (xy 99.372322 -243.794257) (xy 99.349451 -243.837834) (xy 99.319886 -243.877178)
			(xy 99.284393 -243.91127) (xy 99.24389 -243.939226) (xy 99.199428 -243.960324) (xy 99.152157 -243.974016)
			(xy 99.103302 -243.979948) (xy 99.054127 -243.977967) (xy 99.005908 -243.968123) (xy 98.959892 -243.950671)
			(xy 98.917271 -243.926064) (xy 98.87915 -243.894939) (xy 98.846515 -243.858102) (xy 98.820212 -243.816506)
			(xy 98.800921 -243.77123) (xy 98.789144 -243.723446) (xy 98.785184 -243.674392) (xy 98.456242 -243.674392)
			(xy 98.455747 -243.698999) (xy 98.447852 -243.747576) (xy 98.432268 -243.794257) (xy 98.409397 -243.837834)
			(xy 98.379832 -243.877178) (xy 98.344339 -243.91127) (xy 98.303836 -243.939226) (xy 98.259374 -243.960324)
			(xy 98.212103 -243.974016) (xy 98.163248 -243.979948) (xy 98.114073 -243.977967) (xy 98.065854 -243.968123)
			(xy 98.019838 -243.950671) (xy 97.977217 -243.926064) (xy 97.939096 -243.894939) (xy 97.906461 -243.858102)
			(xy 97.880158 -243.816506) (xy 97.860867 -243.77123) (xy 97.84909 -243.723446) (xy 97.84513 -243.674392)
			(xy 97.516442 -243.674392) (xy 97.515947 -243.698999) (xy 97.508052 -243.747576) (xy 97.492468 -243.794257)
			(xy 97.469597 -243.837834) (xy 97.440032 -243.877178) (xy 97.404539 -243.91127) (xy 97.364036 -243.939226)
			(xy 97.319574 -243.960324) (xy 97.272303 -243.974016) (xy 97.223448 -243.979948) (xy 97.174273 -243.977967)
			(xy 97.126054 -243.968123) (xy 97.080038 -243.950671) (xy 97.037417 -243.926064) (xy 96.999296 -243.894939)
			(xy 96.966661 -243.858102) (xy 96.940358 -243.816506) (xy 96.921067 -243.77123) (xy 96.90929 -243.723446)
			(xy 96.90533 -243.674392) (xy 96.575883 -243.674392) (xy 96.575893 -243.698364) (xy 96.56835 -243.745951)
			(xy 96.553433 -243.791765) (xy 96.53151 -243.834669) (xy 96.503124 -243.873601) (xy 96.468981 -243.907596)
			(xy 96.429924 -243.93581) (xy 96.386924 -243.957545) (xy 96.341046 -243.972261) (xy 96.317308 -243.976398)
			(xy 96.3168 -243.976398) (xy 96.316292 -243.976652) (xy 96.30753 -243.978317) (xy 96.291915 -243.986911)
			(xy 96.285812 -243.993416) (xy 96.280224 -243.999766) (xy 96.273874 -244.016784) (xy 96.273874 -244.171724)
			(xy 96.274059 -244.177959) (xy 96.277137 -244.190043) (xy 96.27997 -244.1956) (xy 96.284542 -244.203474)
			(xy 96.295086 -244.222075) (xy 96.31365 -244.260597) (xy 96.321626 -244.280436) (xy 96.323658 -244.285516)
			(xy 96.326452 -244.293136) (xy 96.33712 -244.301518) (xy 96.342597 -244.305474) (xy 96.355085 -244.310615)
			(xy 96.361758 -244.311678) (xy 96.448372 -244.323108) (xy 96.455111 -244.323692) (xy 96.468494 -244.321773)
			(xy 96.474788 -244.319298) (xy 96.48698 -244.314218) (xy 96.490536 -244.309646) (xy 96.495616 -244.302788)
			(xy 96.510121 -244.283962) (xy 96.543979 -244.250612) (xy 96.582593 -244.222908) (xy 96.625031 -244.201519)
			(xy 96.67027 -244.186959) (xy 96.717218 -244.179581) (xy 96.74098 -244.17909) (xy 96.766239 -244.179581)
			(xy 96.816068 -244.187893) (xy 96.86385 -244.204294) (xy 96.90828 -244.228336) (xy 96.948147 -244.259363)
			(xy 96.982363 -244.296529) (xy 97.009995 -244.33882) (xy 97.030288 -244.385083) (xy 97.04269 -244.434055)
			(xy 97.046862 -244.4844) (xy 97.374883 -244.4844) (xy 97.379059 -244.434011) (xy 97.391472 -244.384997)
			(xy 97.411784 -244.338695) (xy 97.43944 -244.296368) (xy 97.473686 -244.259171) (xy 97.513588 -244.228118)
			(xy 97.558057 -244.204057) (xy 97.605881 -244.187644) (xy 97.655753 -244.179326) (xy 97.681034 -244.178836)
			(xy 98.621088 -244.178836) (xy 98.646367 -244.179332) (xy 98.696236 -244.187652) (xy 98.744056 -244.204067)
			(xy 98.788521 -244.228129) (xy 98.82842 -244.259181) (xy 98.862663 -244.296378) (xy 98.890316 -244.338703)
			(xy 98.910626 -244.385003) (xy 98.923037 -244.434014) (xy 98.927213 -244.484398) (xy 99.255338 -244.484398)
			(xy 99.259298 -244.435344) (xy 99.271075 -244.38756) (xy 99.290366 -244.342284) (xy 99.316669 -244.300688)
			(xy 99.349304 -244.263851) (xy 99.387425 -244.232726) (xy 99.430046 -244.208119) (xy 99.476062 -244.190667)
			(xy 99.524281 -244.180823) (xy 99.573456 -244.178842) (xy 99.622311 -244.184774) (xy 99.669582 -244.198466)
			(xy 99.714044 -244.219564) (xy 99.754547 -244.24752) (xy 99.79004 -244.281612) (xy 99.819605 -244.320956)
			(xy 99.842476 -244.364533) (xy 99.85806 -244.411214) (xy 99.865955 -244.459791) (xy 99.86645 -244.484398)
			(xy 99.86645 -244.4844) (xy 100.194783 -244.4844) (xy 100.198959 -244.434011) (xy 100.211373 -244.384996)
			(xy 100.231685 -244.338693) (xy 100.259342 -244.296365) (xy 100.293589 -244.259168) (xy 100.333492 -244.228115)
			(xy 100.377963 -244.204054) (xy 100.425787 -244.187642) (xy 100.475661 -244.179326) (xy 100.500942 -244.178836)
			(xy 101.440996 -244.178836) (xy 101.466275 -244.179333) (xy 101.516143 -244.187654) (xy 101.563961 -244.204069)
			(xy 101.608426 -244.228131) (xy 101.648323 -244.259184) (xy 101.682565 -244.29638) (xy 101.710217 -244.338705)
			(xy 101.730526 -244.385005) (xy 101.742937 -244.434015) (xy 101.747113 -244.484398) (xy 102.075246 -244.484398)
			(xy 102.079206 -244.435344) (xy 102.090983 -244.38756) (xy 102.110274 -244.342284) (xy 102.136577 -244.300688)
			(xy 102.169212 -244.263851) (xy 102.207333 -244.232726) (xy 102.249954 -244.208119) (xy 102.29597 -244.190667)
			(xy 102.344189 -244.180823) (xy 102.393364 -244.178842) (xy 102.442219 -244.184774) (xy 102.48949 -244.198466)
			(xy 102.533952 -244.219564) (xy 102.574455 -244.24752) (xy 102.609948 -244.281612) (xy 102.639513 -244.320956)
			(xy 102.662384 -244.364533) (xy 102.677968 -244.411214) (xy 102.685863 -244.459791) (xy 102.686358 -244.484398)
			(xy 102.686358 -244.4844) (xy 103.014983 -244.4844) (xy 103.019159 -244.434014) (xy 103.03157 -244.385003)
			(xy 103.051879 -244.338704) (xy 103.079532 -244.296378) (xy 103.113774 -244.259181) (xy 103.153672 -244.228128)
			(xy 103.198137 -244.204065) (xy 103.245956 -244.18765) (xy 103.295825 -244.179329) (xy 103.321104 -244.178836)
			(xy 104.261158 -244.178836) (xy 104.286439 -244.17933) (xy 104.336312 -244.187646) (xy 104.384136 -244.204058)
			(xy 104.428605 -244.228118) (xy 104.468508 -244.259171) (xy 104.502755 -244.296368) (xy 104.530412 -244.338695)
			(xy 104.550724 -244.384997) (xy 104.563137 -244.434011) (xy 104.567313 -244.484398) (xy 104.895154 -244.484398)
			(xy 104.899114 -244.435344) (xy 104.910891 -244.38756) (xy 104.930182 -244.342284) (xy 104.956485 -244.300688)
			(xy 104.98912 -244.263851) (xy 105.027241 -244.232726) (xy 105.069862 -244.208119) (xy 105.115878 -244.190667)
			(xy 105.164097 -244.180823) (xy 105.213272 -244.178842) (xy 105.262127 -244.184774) (xy 105.309398 -244.198466)
			(xy 105.35386 -244.219564) (xy 105.394363 -244.24752) (xy 105.429856 -244.281612) (xy 105.459421 -244.320956)
			(xy 105.482292 -244.364533) (xy 105.497876 -244.411214) (xy 105.505771 -244.459791) (xy 105.506266 -244.484398)
			(xy 105.506266 -244.4844) (xy 105.834883 -244.4844) (xy 105.839059 -244.434014) (xy 105.851471 -244.385002)
			(xy 105.87178 -244.338701) (xy 105.899434 -244.296375) (xy 105.933678 -244.259178) (xy 105.973577 -244.228125)
			(xy 106.018043 -244.204063) (xy 106.065863 -244.187648) (xy 106.115732 -244.179328) (xy 106.141012 -244.178836)
			(xy 107.081066 -244.178836) (xy 107.106346 -244.17933) (xy 107.156218 -244.187647) (xy 107.204041 -244.20406)
			(xy 107.24851 -244.228121) (xy 107.288411 -244.259174) (xy 107.322657 -244.29637) (xy 107.350313 -244.338697)
			(xy 107.370624 -244.384999) (xy 107.383037 -244.434012) (xy 107.387213 -244.484398) (xy 107.715316 -244.484398)
			(xy 107.719276 -244.435344) (xy 107.731053 -244.38756) (xy 107.750344 -244.342284) (xy 107.776647 -244.300688)
			(xy 107.809282 -244.263851) (xy 107.847403 -244.232726) (xy 107.890024 -244.208119) (xy 107.93604 -244.190667)
			(xy 107.984259 -244.180823) (xy 108.033434 -244.178842) (xy 108.082289 -244.184774) (xy 108.12956 -244.198466)
			(xy 108.174022 -244.219564) (xy 108.214525 -244.24752) (xy 108.250018 -244.281612) (xy 108.279583 -244.320956)
			(xy 108.302454 -244.364533) (xy 108.318038 -244.411214) (xy 108.325933 -244.459791) (xy 108.326428 -244.484398)
			(xy 108.65537 -244.484398) (xy 108.65933 -244.435344) (xy 108.671107 -244.38756) (xy 108.690398 -244.342284)
			(xy 108.716701 -244.300688) (xy 108.749336 -244.263851) (xy 108.787457 -244.232726) (xy 108.830078 -244.208119)
			(xy 108.876094 -244.190667) (xy 108.924313 -244.180823) (xy 108.973488 -244.178842) (xy 109.022343 -244.184774)
			(xy 109.069614 -244.198466) (xy 109.114076 -244.219564) (xy 109.154579 -244.24752) (xy 109.190072 -244.281612)
			(xy 109.219637 -244.320956) (xy 109.242508 -244.364533) (xy 109.258092 -244.411214) (xy 109.265987 -244.459791)
			(xy 109.266482 -244.484398) (xy 109.59517 -244.484398) (xy 109.59913 -244.435344) (xy 109.610907 -244.38756)
			(xy 109.630198 -244.342284) (xy 109.656501 -244.300688) (xy 109.689136 -244.263851) (xy 109.727257 -244.232726)
			(xy 109.769878 -244.208119) (xy 109.815894 -244.190667) (xy 109.864113 -244.180823) (xy 109.913288 -244.178842)
			(xy 109.962143 -244.184774) (xy 110.009414 -244.198466) (xy 110.053876 -244.219564) (xy 110.094379 -244.24752)
			(xy 110.129872 -244.281612) (xy 110.159437 -244.320956) (xy 110.182308 -244.364533) (xy 110.197892 -244.411214)
			(xy 110.205787 -244.459791) (xy 110.206282 -244.484398) (xy 113.349036 -244.484398) (xy 113.352996 -244.435344)
			(xy 113.364773 -244.38756) (xy 113.384064 -244.342284) (xy 113.410367 -244.300688) (xy 113.443002 -244.263851)
			(xy 113.481123 -244.232726) (xy 113.523744 -244.208119) (xy 113.56976 -244.190667) (xy 113.617979 -244.180823)
			(xy 113.667154 -244.178842) (xy 113.716009 -244.184774) (xy 113.76328 -244.198466) (xy 113.807742 -244.219564)
			(xy 113.848245 -244.24752) (xy 113.883738 -244.281612) (xy 113.913303 -244.320956) (xy 113.936174 -244.364533)
			(xy 113.951758 -244.411214) (xy 113.959653 -244.459791) (xy 113.960148 -244.484398) (xy 114.288836 -244.484398)
			(xy 114.292796 -244.435344) (xy 114.304573 -244.38756) (xy 114.323864 -244.342284) (xy 114.350167 -244.300688)
			(xy 114.382802 -244.263851) (xy 114.420923 -244.232726) (xy 114.463544 -244.208119) (xy 114.50956 -244.190667)
			(xy 114.557779 -244.180823) (xy 114.606954 -244.178842) (xy 114.655809 -244.184774) (xy 114.70308 -244.198466)
			(xy 114.747542 -244.219564) (xy 114.788045 -244.24752) (xy 114.823538 -244.281612) (xy 114.853103 -244.320956)
			(xy 114.875974 -244.364533) (xy 114.891558 -244.411214) (xy 114.899453 -244.459791) (xy 114.899948 -244.484398)
			(xy 115.22889 -244.484398) (xy 115.23285 -244.435344) (xy 115.244627 -244.38756) (xy 115.263918 -244.342284)
			(xy 115.290221 -244.300688) (xy 115.322856 -244.263851) (xy 115.360977 -244.232726) (xy 115.403598 -244.208119)
			(xy 115.449614 -244.190667) (xy 115.497833 -244.180823) (xy 115.547008 -244.178842) (xy 115.595863 -244.184774)
			(xy 115.643134 -244.198466) (xy 115.687596 -244.219564) (xy 115.728099 -244.24752) (xy 115.763592 -244.281612)
			(xy 115.793157 -244.320956) (xy 115.816028 -244.364533) (xy 115.831612 -244.411214) (xy 115.839507 -244.459791)
			(xy 115.840002 -244.484398) (xy 116.168944 -244.484398) (xy 116.172904 -244.435344) (xy 116.184681 -244.38756)
			(xy 116.203972 -244.342284) (xy 116.230275 -244.300688) (xy 116.26291 -244.263851) (xy 116.301031 -244.232726)
			(xy 116.343652 -244.208119) (xy 116.389668 -244.190667) (xy 116.437887 -244.180823) (xy 116.487062 -244.178842)
			(xy 116.535917 -244.184774) (xy 116.583188 -244.198466) (xy 116.62765 -244.219564) (xy 116.668153 -244.24752)
			(xy 116.703646 -244.281612) (xy 116.733211 -244.320956) (xy 116.756082 -244.364533) (xy 116.771666 -244.411214)
			(xy 116.779561 -244.459791) (xy 116.780056 -244.484398) (xy 117.108998 -244.484398) (xy 117.112958 -244.435344)
			(xy 117.124735 -244.38756) (xy 117.144026 -244.342284) (xy 117.170329 -244.300688) (xy 117.202964 -244.263851)
			(xy 117.241085 -244.232726) (xy 117.283706 -244.208119) (xy 117.329722 -244.190667) (xy 117.377941 -244.180823)
			(xy 117.427116 -244.178842) (xy 117.475971 -244.184774) (xy 117.523242 -244.198466) (xy 117.567704 -244.219564)
			(xy 117.608207 -244.24752) (xy 117.6437 -244.281612) (xy 117.673265 -244.320956) (xy 117.696136 -244.364533)
			(xy 117.71172 -244.411214) (xy 117.719615 -244.459791) (xy 117.72011 -244.484398) (xy 118.049052 -244.484398)
			(xy 118.053012 -244.435344) (xy 118.064789 -244.38756) (xy 118.08408 -244.342284) (xy 118.110383 -244.300688)
			(xy 118.143018 -244.263851) (xy 118.181139 -244.232726) (xy 118.22376 -244.208119) (xy 118.269776 -244.190667)
			(xy 118.317995 -244.180823) (xy 118.36717 -244.178842) (xy 118.416025 -244.184774) (xy 118.463296 -244.198466)
			(xy 118.507758 -244.219564) (xy 118.548261 -244.24752) (xy 118.583754 -244.281612) (xy 118.613319 -244.320956)
			(xy 118.63619 -244.364533) (xy 118.651774 -244.411214) (xy 118.659669 -244.459791) (xy 118.660164 -244.484398)
			(xy 118.988852 -244.484398) (xy 118.992812 -244.435344) (xy 119.004589 -244.38756) (xy 119.02388 -244.342284)
			(xy 119.050183 -244.300688) (xy 119.082818 -244.263851) (xy 119.120939 -244.232726) (xy 119.16356 -244.208119)
			(xy 119.209576 -244.190667) (xy 119.257795 -244.180823) (xy 119.30697 -244.178842) (xy 119.355825 -244.184774)
			(xy 119.403096 -244.198466) (xy 119.447558 -244.219564) (xy 119.488061 -244.24752) (xy 119.523554 -244.281612)
			(xy 119.553119 -244.320956) (xy 119.57599 -244.364533) (xy 119.591574 -244.411214) (xy 119.599469 -244.459791)
			(xy 119.599964 -244.484398) (xy 119.928906 -244.484398) (xy 119.932866 -244.435344) (xy 119.944643 -244.38756)
			(xy 119.963934 -244.342284) (xy 119.990237 -244.300688) (xy 120.022872 -244.263851) (xy 120.060993 -244.232726)
			(xy 120.103614 -244.208119) (xy 120.14963 -244.190667) (xy 120.197849 -244.180823) (xy 120.247024 -244.178842)
			(xy 120.295879 -244.184774) (xy 120.34315 -244.198466) (xy 120.387612 -244.219564) (xy 120.428115 -244.24752)
			(xy 120.463608 -244.281612) (xy 120.493173 -244.320956) (xy 120.516044 -244.364533) (xy 120.531628 -244.411214)
			(xy 120.539523 -244.459791) (xy 120.540018 -244.484398) (xy 120.86896 -244.484398) (xy 120.87292 -244.435344)
			(xy 120.884697 -244.38756) (xy 120.903988 -244.342284) (xy 120.930291 -244.300688) (xy 120.962926 -244.263851)
			(xy 121.001047 -244.232726) (xy 121.043668 -244.208119) (xy 121.089684 -244.190667) (xy 121.137903 -244.180823)
			(xy 121.187078 -244.178842) (xy 121.235933 -244.184774) (xy 121.283204 -244.198466) (xy 121.327666 -244.219564)
			(xy 121.368169 -244.24752) (xy 121.403662 -244.281612) (xy 121.433227 -244.320956) (xy 121.456098 -244.364533)
			(xy 121.471682 -244.411214) (xy 121.479577 -244.459791) (xy 121.480072 -244.484398) (xy 121.809014 -244.484398)
			(xy 121.812974 -244.435344) (xy 121.824751 -244.38756) (xy 121.844042 -244.342284) (xy 121.870345 -244.300688)
			(xy 121.90298 -244.263851) (xy 121.941101 -244.232726) (xy 121.983722 -244.208119) (xy 122.029738 -244.190667)
			(xy 122.077957 -244.180823) (xy 122.127132 -244.178842) (xy 122.175987 -244.184774) (xy 122.223258 -244.198466)
			(xy 122.26772 -244.219564) (xy 122.308223 -244.24752) (xy 122.343716 -244.281612) (xy 122.373281 -244.320956)
			(xy 122.396152 -244.364533) (xy 122.411736 -244.411214) (xy 122.419631 -244.459791) (xy 122.420126 -244.484398)
			(xy 122.748814 -244.484398) (xy 122.752774 -244.435344) (xy 122.764551 -244.38756) (xy 122.783842 -244.342284)
			(xy 122.810145 -244.300688) (xy 122.84278 -244.263851) (xy 122.880901 -244.232726) (xy 122.923522 -244.208119)
			(xy 122.969538 -244.190667) (xy 123.017757 -244.180823) (xy 123.066932 -244.178842) (xy 123.115787 -244.184774)
			(xy 123.163058 -244.198466) (xy 123.20752 -244.219564) (xy 123.248023 -244.24752) (xy 123.283516 -244.281612)
			(xy 123.313081 -244.320956) (xy 123.335952 -244.364533) (xy 123.351536 -244.411214) (xy 123.359431 -244.459791)
			(xy 123.359926 -244.484398) (xy 123.688868 -244.484398) (xy 123.692828 -244.435344) (xy 123.704605 -244.38756)
			(xy 123.723896 -244.342284) (xy 123.750199 -244.300688) (xy 123.782834 -244.263851) (xy 123.820955 -244.232726)
			(xy 123.863576 -244.208119) (xy 123.909592 -244.190667) (xy 123.957811 -244.180823) (xy 124.006986 -244.178842)
			(xy 124.055841 -244.184774) (xy 124.103112 -244.198466) (xy 124.147574 -244.219564) (xy 124.188077 -244.24752)
			(xy 124.22357 -244.281612) (xy 124.253135 -244.320956) (xy 124.276006 -244.364533) (xy 124.29159 -244.411214)
			(xy 124.299485 -244.459791) (xy 124.29998 -244.484398) (xy 124.628922 -244.484398) (xy 124.632882 -244.435344)
			(xy 124.644659 -244.38756) (xy 124.66395 -244.342284) (xy 124.690253 -244.300688) (xy 124.722888 -244.263851)
			(xy 124.761009 -244.232726) (xy 124.80363 -244.208119) (xy 124.849646 -244.190667) (xy 124.897865 -244.180823)
			(xy 124.94704 -244.178842) (xy 124.995895 -244.184774) (xy 125.043166 -244.198466) (xy 125.087628 -244.219564)
			(xy 125.128131 -244.24752) (xy 125.163624 -244.281612) (xy 125.193189 -244.320956) (xy 125.21606 -244.364533)
			(xy 125.231644 -244.411214) (xy 125.239539 -244.459791) (xy 125.240034 -244.484398) (xy 125.568976 -244.484398)
			(xy 125.572936 -244.435344) (xy 125.584713 -244.38756) (xy 125.604004 -244.342284) (xy 125.630307 -244.300688)
			(xy 125.662942 -244.263851) (xy 125.701063 -244.232726) (xy 125.743684 -244.208119) (xy 125.7897 -244.190667)
			(xy 125.837919 -244.180823) (xy 125.887094 -244.178842) (xy 125.935949 -244.184774) (xy 125.98322 -244.198466)
			(xy 126.027682 -244.219564) (xy 126.068185 -244.24752) (xy 126.103678 -244.281612) (xy 126.133243 -244.320956)
			(xy 126.156114 -244.364533) (xy 126.171698 -244.411214) (xy 126.179593 -244.459791) (xy 126.180088 -244.484398)
			(xy 126.179593 -244.509005) (xy 126.171698 -244.557582) (xy 126.156114 -244.604263) (xy 126.133243 -244.64784)
			(xy 126.103678 -244.687184) (xy 126.068185 -244.721276) (xy 126.027682 -244.749232) (xy 125.98322 -244.77033)
			(xy 125.935949 -244.784022) (xy 125.887094 -244.789954) (xy 125.837919 -244.787973) (xy 125.7897 -244.778129)
			(xy 125.743684 -244.760677) (xy 125.701063 -244.73607) (xy 125.662942 -244.704945) (xy 125.630307 -244.668108)
			(xy 125.604004 -244.626512) (xy 125.584713 -244.581236) (xy 125.572936 -244.533452) (xy 125.568976 -244.484398)
			(xy 125.240034 -244.484398) (xy 125.239539 -244.509005) (xy 125.231644 -244.557582) (xy 125.21606 -244.604263)
			(xy 125.193189 -244.64784) (xy 125.163624 -244.687184) (xy 125.128131 -244.721276) (xy 125.087628 -244.749232)
			(xy 125.043166 -244.77033) (xy 124.995895 -244.784022) (xy 124.94704 -244.789954) (xy 124.897865 -244.787973)
			(xy 124.849646 -244.778129) (xy 124.80363 -244.760677) (xy 124.761009 -244.73607) (xy 124.722888 -244.704945)
			(xy 124.690253 -244.668108) (xy 124.66395 -244.626512) (xy 124.644659 -244.581236) (xy 124.632882 -244.533452)
			(xy 124.628922 -244.484398) (xy 124.29998 -244.484398) (xy 124.299485 -244.509005) (xy 124.29159 -244.557582)
			(xy 124.276006 -244.604263) (xy 124.253135 -244.64784) (xy 124.22357 -244.687184) (xy 124.188077 -244.721276)
			(xy 124.147574 -244.749232) (xy 124.103112 -244.77033) (xy 124.055841 -244.784022) (xy 124.006986 -244.789954)
			(xy 123.957811 -244.787973) (xy 123.909592 -244.778129) (xy 123.863576 -244.760677) (xy 123.820955 -244.73607)
			(xy 123.782834 -244.704945) (xy 123.750199 -244.668108) (xy 123.723896 -244.626512) (xy 123.704605 -244.581236)
			(xy 123.692828 -244.533452) (xy 123.688868 -244.484398) (xy 123.359926 -244.484398) (xy 123.359431 -244.509005)
			(xy 123.351536 -244.557582) (xy 123.335952 -244.604263) (xy 123.313081 -244.64784) (xy 123.283516 -244.687184)
			(xy 123.248023 -244.721276) (xy 123.20752 -244.749232) (xy 123.163058 -244.77033) (xy 123.115787 -244.784022)
			(xy 123.066932 -244.789954) (xy 123.017757 -244.787973) (xy 122.969538 -244.778129) (xy 122.923522 -244.760677)
			(xy 122.880901 -244.73607) (xy 122.84278 -244.704945) (xy 122.810145 -244.668108) (xy 122.783842 -244.626512)
			(xy 122.764551 -244.581236) (xy 122.752774 -244.533452) (xy 122.748814 -244.484398) (xy 122.420126 -244.484398)
			(xy 122.419631 -244.509005) (xy 122.411736 -244.557582) (xy 122.396152 -244.604263) (xy 122.373281 -244.64784)
			(xy 122.343716 -244.687184) (xy 122.308223 -244.721276) (xy 122.26772 -244.749232) (xy 122.223258 -244.77033)
			(xy 122.175987 -244.784022) (xy 122.127132 -244.789954) (xy 122.077957 -244.787973) (xy 122.029738 -244.778129)
			(xy 121.983722 -244.760677) (xy 121.941101 -244.73607) (xy 121.90298 -244.704945) (xy 121.870345 -244.668108)
			(xy 121.844042 -244.626512) (xy 121.824751 -244.581236) (xy 121.812974 -244.533452) (xy 121.809014 -244.484398)
			(xy 121.480072 -244.484398) (xy 121.479577 -244.509005) (xy 121.471682 -244.557582) (xy 121.456098 -244.604263)
			(xy 121.433227 -244.64784) (xy 121.403662 -244.687184) (xy 121.368169 -244.721276) (xy 121.327666 -244.749232)
			(xy 121.283204 -244.77033) (xy 121.235933 -244.784022) (xy 121.187078 -244.789954) (xy 121.137903 -244.787973)
			(xy 121.089684 -244.778129) (xy 121.043668 -244.760677) (xy 121.001047 -244.73607) (xy 120.962926 -244.704945)
			(xy 120.930291 -244.668108) (xy 120.903988 -244.626512) (xy 120.884697 -244.581236) (xy 120.87292 -244.533452)
			(xy 120.86896 -244.484398) (xy 120.540018 -244.484398) (xy 120.539523 -244.509005) (xy 120.531628 -244.557582)
			(xy 120.516044 -244.604263) (xy 120.493173 -244.64784) (xy 120.463608 -244.687184) (xy 120.428115 -244.721276)
			(xy 120.387612 -244.749232) (xy 120.34315 -244.77033) (xy 120.295879 -244.784022) (xy 120.247024 -244.789954)
			(xy 120.197849 -244.787973) (xy 120.14963 -244.778129) (xy 120.103614 -244.760677) (xy 120.060993 -244.73607)
			(xy 120.022872 -244.704945) (xy 119.990237 -244.668108) (xy 119.963934 -244.626512) (xy 119.944643 -244.581236)
			(xy 119.932866 -244.533452) (xy 119.928906 -244.484398) (xy 119.599964 -244.484398) (xy 119.599469 -244.509005)
			(xy 119.591574 -244.557582) (xy 119.57599 -244.604263) (xy 119.553119 -244.64784) (xy 119.523554 -244.687184)
			(xy 119.488061 -244.721276) (xy 119.447558 -244.749232) (xy 119.403096 -244.77033) (xy 119.355825 -244.784022)
			(xy 119.30697 -244.789954) (xy 119.257795 -244.787973) (xy 119.209576 -244.778129) (xy 119.16356 -244.760677)
			(xy 119.120939 -244.73607) (xy 119.082818 -244.704945) (xy 119.050183 -244.668108) (xy 119.02388 -244.626512)
			(xy 119.004589 -244.581236) (xy 118.992812 -244.533452) (xy 118.988852 -244.484398) (xy 118.660164 -244.484398)
			(xy 118.659669 -244.509005) (xy 118.651774 -244.557582) (xy 118.63619 -244.604263) (xy 118.613319 -244.64784)
			(xy 118.583754 -244.687184) (xy 118.548261 -244.721276) (xy 118.507758 -244.749232) (xy 118.463296 -244.77033)
			(xy 118.416025 -244.784022) (xy 118.36717 -244.789954) (xy 118.317995 -244.787973) (xy 118.269776 -244.778129)
			(xy 118.22376 -244.760677) (xy 118.181139 -244.73607) (xy 118.143018 -244.704945) (xy 118.110383 -244.668108)
			(xy 118.08408 -244.626512) (xy 118.064789 -244.581236) (xy 118.053012 -244.533452) (xy 118.049052 -244.484398)
			(xy 117.72011 -244.484398) (xy 117.719615 -244.509005) (xy 117.71172 -244.557582) (xy 117.696136 -244.604263)
			(xy 117.673265 -244.64784) (xy 117.6437 -244.687184) (xy 117.608207 -244.721276) (xy 117.567704 -244.749232)
			(xy 117.523242 -244.77033) (xy 117.475971 -244.784022) (xy 117.427116 -244.789954) (xy 117.377941 -244.787973)
			(xy 117.329722 -244.778129) (xy 117.283706 -244.760677) (xy 117.241085 -244.73607) (xy 117.202964 -244.704945)
			(xy 117.170329 -244.668108) (xy 117.144026 -244.626512) (xy 117.124735 -244.581236) (xy 117.112958 -244.533452)
			(xy 117.108998 -244.484398) (xy 116.780056 -244.484398) (xy 116.779561 -244.509005) (xy 116.771666 -244.557582)
			(xy 116.756082 -244.604263) (xy 116.733211 -244.64784) (xy 116.703646 -244.687184) (xy 116.668153 -244.721276)
			(xy 116.62765 -244.749232) (xy 116.583188 -244.77033) (xy 116.535917 -244.784022) (xy 116.487062 -244.789954)
			(xy 116.437887 -244.787973) (xy 116.389668 -244.778129) (xy 116.343652 -244.760677) (xy 116.301031 -244.73607)
			(xy 116.26291 -244.704945) (xy 116.230275 -244.668108) (xy 116.203972 -244.626512) (xy 116.184681 -244.581236)
			(xy 116.172904 -244.533452) (xy 116.168944 -244.484398) (xy 115.840002 -244.484398) (xy 115.839507 -244.509005)
			(xy 115.831612 -244.557582) (xy 115.816028 -244.604263) (xy 115.793157 -244.64784) (xy 115.763592 -244.687184)
			(xy 115.728099 -244.721276) (xy 115.687596 -244.749232) (xy 115.643134 -244.77033) (xy 115.595863 -244.784022)
			(xy 115.547008 -244.789954) (xy 115.497833 -244.787973) (xy 115.449614 -244.778129) (xy 115.403598 -244.760677)
			(xy 115.360977 -244.73607) (xy 115.322856 -244.704945) (xy 115.290221 -244.668108) (xy 115.263918 -244.626512)
			(xy 115.244627 -244.581236) (xy 115.23285 -244.533452) (xy 115.22889 -244.484398) (xy 114.899948 -244.484398)
			(xy 114.899453 -244.509005) (xy 114.891558 -244.557582) (xy 114.875974 -244.604263) (xy 114.853103 -244.64784)
			(xy 114.823538 -244.687184) (xy 114.788045 -244.721276) (xy 114.747542 -244.749232) (xy 114.70308 -244.77033)
			(xy 114.655809 -244.784022) (xy 114.606954 -244.789954) (xy 114.557779 -244.787973) (xy 114.50956 -244.778129)
			(xy 114.463544 -244.760677) (xy 114.420923 -244.73607) (xy 114.382802 -244.704945) (xy 114.350167 -244.668108)
			(xy 114.323864 -244.626512) (xy 114.304573 -244.581236) (xy 114.292796 -244.533452) (xy 114.288836 -244.484398)
			(xy 113.960148 -244.484398) (xy 113.959653 -244.509005) (xy 113.951758 -244.557582) (xy 113.936174 -244.604263)
			(xy 113.913303 -244.64784) (xy 113.883738 -244.687184) (xy 113.848245 -244.721276) (xy 113.807742 -244.749232)
			(xy 113.76328 -244.77033) (xy 113.716009 -244.784022) (xy 113.667154 -244.789954) (xy 113.617979 -244.787973)
			(xy 113.56976 -244.778129) (xy 113.523744 -244.760677) (xy 113.481123 -244.73607) (xy 113.443002 -244.704945)
			(xy 113.410367 -244.668108) (xy 113.384064 -244.626512) (xy 113.364773 -244.581236) (xy 113.352996 -244.533452)
			(xy 113.349036 -244.484398) (xy 110.206282 -244.484398) (xy 110.205787 -244.509005) (xy 110.197892 -244.557582)
			(xy 110.182308 -244.604263) (xy 110.159437 -244.64784) (xy 110.129872 -244.687184) (xy 110.094379 -244.721276)
			(xy 110.053876 -244.749232) (xy 110.009414 -244.77033) (xy 109.962143 -244.784022) (xy 109.913288 -244.789954)
			(xy 109.864113 -244.787973) (xy 109.815894 -244.778129) (xy 109.769878 -244.760677) (xy 109.727257 -244.73607)
			(xy 109.689136 -244.704945) (xy 109.656501 -244.668108) (xy 109.630198 -244.626512) (xy 109.610907 -244.581236)
			(xy 109.59913 -244.533452) (xy 109.59517 -244.484398) (xy 109.266482 -244.484398) (xy 109.265987 -244.509005)
			(xy 109.258092 -244.557582) (xy 109.242508 -244.604263) (xy 109.219637 -244.64784) (xy 109.190072 -244.687184)
			(xy 109.154579 -244.721276) (xy 109.114076 -244.749232) (xy 109.069614 -244.77033) (xy 109.022343 -244.784022)
			(xy 108.973488 -244.789954) (xy 108.924313 -244.787973) (xy 108.876094 -244.778129) (xy 108.830078 -244.760677)
			(xy 108.787457 -244.73607) (xy 108.749336 -244.704945) (xy 108.716701 -244.668108) (xy 108.690398 -244.626512)
			(xy 108.671107 -244.581236) (xy 108.65933 -244.533452) (xy 108.65537 -244.484398) (xy 108.326428 -244.484398)
			(xy 108.325933 -244.509005) (xy 108.318038 -244.557582) (xy 108.302454 -244.604263) (xy 108.279583 -244.64784)
			(xy 108.250018 -244.687184) (xy 108.214525 -244.721276) (xy 108.174022 -244.749232) (xy 108.12956 -244.77033)
			(xy 108.082289 -244.784022) (xy 108.033434 -244.789954) (xy 107.984259 -244.787973) (xy 107.93604 -244.778129)
			(xy 107.890024 -244.760677) (xy 107.847403 -244.73607) (xy 107.809282 -244.704945) (xy 107.776647 -244.668108)
			(xy 107.750344 -244.626512) (xy 107.731053 -244.581236) (xy 107.719276 -244.533452) (xy 107.715316 -244.484398)
			(xy 107.387213 -244.484398) (xy 107.387213 -244.4844) (xy 107.383037 -244.534788) (xy 107.370624 -244.583801)
			(xy 107.350313 -244.630103) (xy 107.322657 -244.67243) (xy 107.288411 -244.709626) (xy 107.24851 -244.740679)
			(xy 107.204041 -244.76474) (xy 107.156218 -244.781153) (xy 107.106346 -244.78947) (xy 107.081066 -244.78996)
			(xy 106.141012 -244.78996) (xy 106.115732 -244.789472) (xy 106.065863 -244.781152) (xy 106.018043 -244.764737)
			(xy 105.973577 -244.740675) (xy 105.933678 -244.709622) (xy 105.899434 -244.672425) (xy 105.87178 -244.630099)
			(xy 105.851471 -244.583798) (xy 105.839059 -244.534786) (xy 105.834883 -244.4844) (xy 105.506266 -244.4844)
			(xy 105.505771 -244.509005) (xy 105.497876 -244.557582) (xy 105.482292 -244.604263) (xy 105.459421 -244.64784)
			(xy 105.429856 -244.687184) (xy 105.394363 -244.721276) (xy 105.35386 -244.749232) (xy 105.309398 -244.77033)
			(xy 105.262127 -244.784022) (xy 105.213272 -244.789954) (xy 105.164097 -244.787973) (xy 105.115878 -244.778129)
			(xy 105.069862 -244.760677) (xy 105.027241 -244.73607) (xy 104.98912 -244.704945) (xy 104.956485 -244.668108)
			(xy 104.930182 -244.626512) (xy 104.910891 -244.581236) (xy 104.899114 -244.533452) (xy 104.895154 -244.484398)
			(xy 104.567313 -244.484398) (xy 104.567313 -244.4844) (xy 104.563137 -244.534789) (xy 104.550724 -244.583803)
			(xy 104.530412 -244.630105) (xy 104.502755 -244.672432) (xy 104.468508 -244.709629) (xy 104.428605 -244.740682)
			(xy 104.384136 -244.764742) (xy 104.336312 -244.781154) (xy 104.286439 -244.78947) (xy 104.261158 -244.78996)
			(xy 103.321104 -244.78996) (xy 103.295825 -244.789471) (xy 103.245956 -244.78115) (xy 103.198137 -244.764735)
			(xy 103.153672 -244.740672) (xy 103.113774 -244.709619) (xy 103.079532 -244.672422) (xy 103.051879 -244.630096)
			(xy 103.03157 -244.583797) (xy 103.019159 -244.534786) (xy 103.014983 -244.4844) (xy 102.686358 -244.4844)
			(xy 102.685863 -244.509005) (xy 102.677968 -244.557582) (xy 102.662384 -244.604263) (xy 102.639513 -244.64784)
			(xy 102.609948 -244.687184) (xy 102.574455 -244.721276) (xy 102.533952 -244.749232) (xy 102.48949 -244.77033)
			(xy 102.442219 -244.784022) (xy 102.393364 -244.789954) (xy 102.344189 -244.787973) (xy 102.29597 -244.778129)
			(xy 102.249954 -244.760677) (xy 102.207333 -244.73607) (xy 102.169212 -244.704945) (xy 102.136577 -244.668108)
			(xy 102.110274 -244.626512) (xy 102.090983 -244.581236) (xy 102.079206 -244.533452) (xy 102.075246 -244.484398)
			(xy 101.747113 -244.484398) (xy 101.747113 -244.4844) (xy 101.742937 -244.534785) (xy 101.730526 -244.583795)
			(xy 101.710217 -244.630095) (xy 101.682565 -244.67242) (xy 101.648323 -244.709616) (xy 101.608426 -244.740669)
			(xy 101.563961 -244.764731) (xy 101.516143 -244.781146) (xy 101.466275 -244.789467) (xy 101.440996 -244.78996)
			(xy 100.500942 -244.78996) (xy 100.475661 -244.789474) (xy 100.425787 -244.781158) (xy 100.377963 -244.764746)
			(xy 100.333492 -244.740685) (xy 100.293589 -244.709632) (xy 100.259342 -244.672435) (xy 100.231685 -244.630107)
			(xy 100.211373 -244.583804) (xy 100.198959 -244.534789) (xy 100.194783 -244.4844) (xy 99.86645 -244.4844)
			(xy 99.865955 -244.509005) (xy 99.85806 -244.557582) (xy 99.842476 -244.604263) (xy 99.819605 -244.64784)
			(xy 99.79004 -244.687184) (xy 99.754547 -244.721276) (xy 99.714044 -244.749232) (xy 99.669582 -244.77033)
			(xy 99.622311 -244.784022) (xy 99.573456 -244.789954) (xy 99.524281 -244.787973) (xy 99.476062 -244.778129)
			(xy 99.430046 -244.760677) (xy 99.387425 -244.73607) (xy 99.349304 -244.704945) (xy 99.316669 -244.668108)
			(xy 99.290366 -244.626512) (xy 99.271075 -244.581236) (xy 99.259298 -244.533452) (xy 99.255338 -244.484398)
			(xy 98.927213 -244.484398) (xy 98.927213 -244.4844) (xy 98.923037 -244.534786) (xy 98.910626 -244.583797)
			(xy 98.890316 -244.630097) (xy 98.862663 -244.672422) (xy 98.82842 -244.709619) (xy 98.788521 -244.740671)
			(xy 98.744056 -244.764733) (xy 98.696236 -244.781148) (xy 98.646367 -244.789468) (xy 98.621088 -244.78996)
			(xy 97.681034 -244.78996) (xy 97.655753 -244.789474) (xy 97.605881 -244.781156) (xy 97.558057 -244.764743)
			(xy 97.513588 -244.740682) (xy 97.473686 -244.709629) (xy 97.43944 -244.672432) (xy 97.411784 -244.630105)
			(xy 97.391472 -244.583803) (xy 97.379059 -244.534789) (xy 97.374883 -244.4844) (xy 97.046862 -244.4844)
			(xy 97.04269 -244.534745) (xy 97.030288 -244.583717) (xy 97.009995 -244.62998) (xy 96.982363 -244.672271)
			(xy 96.948147 -244.709437) (xy 96.90828 -244.740464) (xy 96.86385 -244.764506) (xy 96.816068 -244.780907)
			(xy 96.766239 -244.789219) (xy 96.74098 -244.789706) (xy 96.717213 -244.789258) (xy 96.670253 -244.781899)
			(xy 96.625002 -244.767346) (xy 96.582556 -244.745952) (xy 96.543941 -244.718234) (xy 96.510092 -244.684863)
			(xy 96.495616 -244.666008) (xy 96.490536 -244.65915) (xy 96.48698 -244.654578) (xy 96.474788 -244.649498)
			(xy 96.468505 -244.646972) (xy 96.45511 -244.645029) (xy 96.448372 -244.645688) (xy 96.361758 -244.657118)
			(xy 96.355082 -244.658168) (xy 96.342586 -244.663305) (xy 96.33712 -244.667278) (xy 96.326452 -244.67566)
			(xy 96.323658 -244.68328) (xy 96.321626 -244.68836) (xy 96.308164 -244.719602) (xy 96.302016 -244.732727)
			(xy 96.288547 -244.758394) (xy 96.28124 -244.77091) (xy 96.280986 -244.771164) (xy 96.27743 -244.77726)
			(xy 96.275652 -244.783356) (xy 96.273874 -244.796818) (xy 96.273874 -244.942614) (xy 96.274256 -244.951715)
			(xy 96.280645 -244.96876) (xy 96.28632 -244.975888) (xy 96.291908 -244.982238) (xy 96.307402 -244.990874)
			(xy 96.317054 -244.992398) (xy 96.340797 -244.996492) (xy 96.386686 -245.011171) (xy 96.429703 -245.032869)
			(xy 96.468781 -245.06105) (xy 96.502951 -245.095015) (xy 96.531368 -245.133922) (xy 96.553325 -245.176807)
			(xy 96.56828 -245.222607) (xy 96.575861 -245.270186) (xy 96.575871 -245.294404) (xy 98.785184 -245.294404)
			(xy 98.789144 -245.24535) (xy 98.800921 -245.197566) (xy 98.820212 -245.15229) (xy 98.846515 -245.110694)
			(xy 98.87915 -245.073857) (xy 98.917271 -245.042732) (xy 98.959892 -245.018125) (xy 99.005908 -245.000673)
			(xy 99.054127 -244.990829) (xy 99.103302 -244.988848) (xy 99.152157 -244.99478) (xy 99.199428 -245.008472)
			(xy 99.24389 -245.02957) (xy 99.284393 -245.057526) (xy 99.319886 -245.091618) (xy 99.349451 -245.130962)
			(xy 99.372322 -245.174539) (xy 99.387906 -245.22122) (xy 99.395801 -245.269797) (xy 99.396296 -245.294404)
			(xy 101.605346 -245.294404) (xy 101.609306 -245.24535) (xy 101.621083 -245.197566) (xy 101.640374 -245.15229)
			(xy 101.666677 -245.110694) (xy 101.699312 -245.073857) (xy 101.737433 -245.042732) (xy 101.780054 -245.018125)
			(xy 101.82607 -245.000673) (xy 101.874289 -244.990829) (xy 101.923464 -244.988848) (xy 101.972319 -244.99478)
			(xy 102.01959 -245.008472) (xy 102.064052 -245.02957) (xy 102.104555 -245.057526) (xy 102.140048 -245.091618)
			(xy 102.169613 -245.130962) (xy 102.192484 -245.174539) (xy 102.208068 -245.22122) (xy 102.215963 -245.269797)
			(xy 102.216458 -245.294404) (xy 104.425254 -245.294404) (xy 104.429214 -245.24535) (xy 104.440991 -245.197566)
			(xy 104.460282 -245.15229) (xy 104.486585 -245.110694) (xy 104.51922 -245.073857) (xy 104.557341 -245.042732)
			(xy 104.599962 -245.018125) (xy 104.645978 -245.000673) (xy 104.694197 -244.990829) (xy 104.743372 -244.988848)
			(xy 104.792227 -244.99478) (xy 104.839498 -245.008472) (xy 104.88396 -245.02957) (xy 104.924463 -245.057526)
			(xy 104.959956 -245.091618) (xy 104.989521 -245.130962) (xy 105.012392 -245.174539) (xy 105.027976 -245.22122)
			(xy 105.035871 -245.269797) (xy 105.036366 -245.294404) (xy 107.245162 -245.294404) (xy 107.249122 -245.24535)
			(xy 107.260899 -245.197566) (xy 107.28019 -245.15229) (xy 107.306493 -245.110694) (xy 107.339128 -245.073857)
			(xy 107.377249 -245.042732) (xy 107.41987 -245.018125) (xy 107.465886 -245.000673) (xy 107.514105 -244.990829)
			(xy 107.56328 -244.988848) (xy 107.612135 -244.99478) (xy 107.659406 -245.008472) (xy 107.703868 -245.02957)
			(xy 107.744371 -245.057526) (xy 107.779864 -245.091618) (xy 107.809429 -245.130962) (xy 107.8323 -245.174539)
			(xy 107.847884 -245.22122) (xy 107.855779 -245.269797) (xy 107.856274 -245.2944) (xy 108.185144 -245.2944)
			(xy 108.189316 -245.244056) (xy 108.201717 -245.195085) (xy 108.222011 -245.148823) (xy 108.249642 -245.106533)
			(xy 108.283857 -245.069367) (xy 108.323723 -245.038341) (xy 108.368153 -245.014299) (xy 108.415933 -244.997899)
			(xy 108.465762 -244.989587) (xy 108.49102 -244.989096) (xy 109.431074 -244.989096) (xy 109.456333 -244.989579)
			(xy 109.506164 -244.99789) (xy 109.553947 -245.01429) (xy 109.598378 -245.038332) (xy 109.638246 -245.069359)
			(xy 109.672463 -245.106526) (xy 109.700095 -245.148818) (xy 109.72039 -245.195081) (xy 109.732792 -245.244054)
			(xy 109.736964 -245.2944) (xy 109.736964 -245.294404) (xy 110.065324 -245.294404) (xy 110.069284 -245.24535)
			(xy 110.081061 -245.197566) (xy 110.100352 -245.15229) (xy 110.126655 -245.110694) (xy 110.15929 -245.073857)
			(xy 110.197411 -245.042732) (xy 110.240032 -245.018125) (xy 110.286048 -245.000673) (xy 110.334267 -244.990829)
			(xy 110.383442 -244.988848) (xy 110.432297 -244.99478) (xy 110.479568 -245.008472) (xy 110.52403 -245.02957)
			(xy 110.564533 -245.057526) (xy 110.600026 -245.091618) (xy 110.629591 -245.130962) (xy 110.652462 -245.174539)
			(xy 110.668046 -245.22122) (xy 110.675941 -245.269797) (xy 110.676436 -245.294404) (xy 110.675941 -245.319011)
			(xy 110.668046 -245.367588) (xy 110.652462 -245.414269) (xy 110.629591 -245.457846) (xy 110.600026 -245.49719)
			(xy 110.564533 -245.531282) (xy 110.534206 -245.552214) (xy 111.456473 -245.552214) (xy 111.460503 -245.499716)
			(xy 111.4725 -245.448448) (xy 111.492183 -245.399613) (xy 111.519089 -245.354354) (xy 111.552589 -245.313733)
			(xy 111.591897 -245.278702) (xy 111.636092 -245.250082) (xy 111.684137 -245.228543) (xy 111.734908 -245.214591)
			(xy 111.787213 -245.208553) (xy 111.839827 -245.21057) (xy 111.891517 -245.220594) (xy 111.94107 -245.238392)
			(xy 111.987326 -245.263545) (xy 112.027809 -245.294404) (xy 112.878882 -245.294404) (xy 112.882842 -245.24535)
			(xy 112.894619 -245.197566) (xy 112.91391 -245.15229) (xy 112.940213 -245.110694) (xy 112.972848 -245.073857)
			(xy 113.010969 -245.042732) (xy 113.05359 -245.018125) (xy 113.099606 -245.000673) (xy 113.147825 -244.990829)
			(xy 113.197 -244.988848) (xy 113.245855 -244.99478) (xy 113.293126 -245.008472) (xy 113.337588 -245.02957)
			(xy 113.378091 -245.057526) (xy 113.413584 -245.091618) (xy 113.443149 -245.130962) (xy 113.46602 -245.174539)
			(xy 113.481604 -245.22122) (xy 113.489499 -245.269797) (xy 113.489994 -245.294404) (xy 113.818936 -245.294404)
			(xy 113.822896 -245.24535) (xy 113.834673 -245.197566) (xy 113.853964 -245.15229) (xy 113.880267 -245.110694)
			(xy 113.912902 -245.073857) (xy 113.951023 -245.042732) (xy 113.993644 -245.018125) (xy 114.03966 -245.000673)
			(xy 114.087879 -244.990829) (xy 114.137054 -244.988848) (xy 114.185909 -244.99478) (xy 114.23318 -245.008472)
			(xy 114.277642 -245.02957) (xy 114.318145 -245.057526) (xy 114.353638 -245.091618) (xy 114.383203 -245.130962)
			(xy 114.406074 -245.174539) (xy 114.421658 -245.22122) (xy 114.429553 -245.269797) (xy 114.430048 -245.294404)
			(xy 114.75899 -245.294404) (xy 114.76295 -245.24535) (xy 114.774727 -245.197566) (xy 114.794018 -245.15229)
			(xy 114.820321 -245.110694) (xy 114.852956 -245.073857) (xy 114.891077 -245.042732) (xy 114.933698 -245.018125)
			(xy 114.979714 -245.000673) (xy 115.027933 -244.990829) (xy 115.077108 -244.988848) (xy 115.125963 -244.99478)
			(xy 115.173234 -245.008472) (xy 115.217696 -245.02957) (xy 115.258199 -245.057526) (xy 115.293692 -245.091618)
			(xy 115.323257 -245.130962) (xy 115.346128 -245.174539) (xy 115.361712 -245.22122) (xy 115.369607 -245.269797)
			(xy 115.370102 -245.294404) (xy 115.699044 -245.294404) (xy 115.703004 -245.24535) (xy 115.714781 -245.197566)
			(xy 115.734072 -245.15229) (xy 115.760375 -245.110694) (xy 115.79301 -245.073857) (xy 115.831131 -245.042732)
			(xy 115.873752 -245.018125) (xy 115.919768 -245.000673) (xy 115.967987 -244.990829) (xy 116.017162 -244.988848)
			(xy 116.066017 -244.99478) (xy 116.113288 -245.008472) (xy 116.15775 -245.02957) (xy 116.198253 -245.057526)
			(xy 116.233746 -245.091618) (xy 116.263311 -245.130962) (xy 116.286182 -245.174539) (xy 116.301766 -245.22122)
			(xy 116.309661 -245.269797) (xy 116.310156 -245.294404) (xy 118.518952 -245.294404) (xy 118.522912 -245.24535)
			(xy 118.534689 -245.197566) (xy 118.55398 -245.15229) (xy 118.580283 -245.110694) (xy 118.612918 -245.073857)
			(xy 118.651039 -245.042732) (xy 118.69366 -245.018125) (xy 118.739676 -245.000673) (xy 118.787895 -244.990829)
			(xy 118.83707 -244.988848) (xy 118.885925 -244.99478) (xy 118.933196 -245.008472) (xy 118.977658 -245.02957)
			(xy 119.018161 -245.057526) (xy 119.053654 -245.091618) (xy 119.083219 -245.130962) (xy 119.10609 -245.174539)
			(xy 119.121674 -245.22122) (xy 119.129569 -245.269797) (xy 119.130064 -245.294404) (xy 121.33886 -245.294404)
			(xy 121.34282 -245.24535) (xy 121.354597 -245.197566) (xy 121.373888 -245.15229) (xy 121.400191 -245.110694)
			(xy 121.432826 -245.073857) (xy 121.470947 -245.042732) (xy 121.513568 -245.018125) (xy 121.559584 -245.000673)
			(xy 121.607803 -244.990829) (xy 121.656978 -244.988848) (xy 121.705833 -244.99478) (xy 121.753104 -245.008472)
			(xy 121.797566 -245.02957) (xy 121.838069 -245.057526) (xy 121.873562 -245.091618) (xy 121.903127 -245.130962)
			(xy 121.925998 -245.174539) (xy 121.941582 -245.22122) (xy 121.949477 -245.269797) (xy 121.949972 -245.294404)
			(xy 124.159022 -245.294404) (xy 124.162982 -245.24535) (xy 124.174759 -245.197566) (xy 124.19405 -245.15229)
			(xy 124.220353 -245.110694) (xy 124.252988 -245.073857) (xy 124.291109 -245.042732) (xy 124.33373 -245.018125)
			(xy 124.379746 -245.000673) (xy 124.427965 -244.990829) (xy 124.47714 -244.988848) (xy 124.525995 -244.99478)
			(xy 124.573266 -245.008472) (xy 124.617728 -245.02957) (xy 124.658231 -245.057526) (xy 124.693724 -245.091618)
			(xy 124.723289 -245.130962) (xy 124.74616 -245.174539) (xy 124.761744 -245.22122) (xy 124.769639 -245.269797)
			(xy 124.770134 -245.294404) (xy 124.769639 -245.319011) (xy 124.761744 -245.367588) (xy 124.74616 -245.414269)
			(xy 124.723289 -245.457846) (xy 124.693724 -245.49719) (xy 124.658231 -245.531282) (xy 124.617728 -245.559238)
			(xy 124.573266 -245.580336) (xy 124.525995 -245.594028) (xy 124.47714 -245.59996) (xy 124.427965 -245.597979)
			(xy 124.379746 -245.588135) (xy 124.33373 -245.570683) (xy 124.291109 -245.546076) (xy 124.252988 -245.514951)
			(xy 124.220353 -245.478114) (xy 124.19405 -245.436518) (xy 124.174759 -245.391242) (xy 124.162982 -245.343458)
			(xy 124.159022 -245.294404) (xy 121.949972 -245.294404) (xy 121.949477 -245.319011) (xy 121.941582 -245.367588)
			(xy 121.925998 -245.414269) (xy 121.903127 -245.457846) (xy 121.873562 -245.49719) (xy 121.838069 -245.531282)
			(xy 121.797566 -245.559238) (xy 121.753104 -245.580336) (xy 121.705833 -245.594028) (xy 121.656978 -245.59996)
			(xy 121.607803 -245.597979) (xy 121.559584 -245.588135) (xy 121.513568 -245.570683) (xy 121.470947 -245.546076)
			(xy 121.432826 -245.514951) (xy 121.400191 -245.478114) (xy 121.373888 -245.436518) (xy 121.354597 -245.391242)
			(xy 121.34282 -245.343458) (xy 121.33886 -245.294404) (xy 119.130064 -245.294404) (xy 119.129569 -245.319011)
			(xy 119.121674 -245.367588) (xy 119.10609 -245.414269) (xy 119.083219 -245.457846) (xy 119.053654 -245.49719)
			(xy 119.018161 -245.531282) (xy 118.977658 -245.559238) (xy 118.933196 -245.580336) (xy 118.885925 -245.594028)
			(xy 118.83707 -245.59996) (xy 118.787895 -245.597979) (xy 118.739676 -245.588135) (xy 118.69366 -245.570683)
			(xy 118.651039 -245.546076) (xy 118.612918 -245.514951) (xy 118.580283 -245.478114) (xy 118.55398 -245.436518)
			(xy 118.534689 -245.391242) (xy 118.522912 -245.343458) (xy 118.518952 -245.294404) (xy 116.310156 -245.294404)
			(xy 116.309661 -245.319011) (xy 116.301766 -245.367588) (xy 116.286182 -245.414269) (xy 116.263311 -245.457846)
			(xy 116.233746 -245.49719) (xy 116.198253 -245.531282) (xy 116.15775 -245.559238) (xy 116.113288 -245.580336)
			(xy 116.066017 -245.594028) (xy 116.017162 -245.59996) (xy 115.967987 -245.597979) (xy 115.919768 -245.588135)
			(xy 115.873752 -245.570683) (xy 115.831131 -245.546076) (xy 115.79301 -245.514951) (xy 115.760375 -245.478114)
			(xy 115.734072 -245.436518) (xy 115.714781 -245.391242) (xy 115.703004 -245.343458) (xy 115.699044 -245.294404)
			(xy 115.370102 -245.294404) (xy 115.369607 -245.319011) (xy 115.361712 -245.367588) (xy 115.346128 -245.414269)
			(xy 115.323257 -245.457846) (xy 115.293692 -245.49719) (xy 115.258199 -245.531282) (xy 115.217696 -245.559238)
			(xy 115.173234 -245.580336) (xy 115.125963 -245.594028) (xy 115.077108 -245.59996) (xy 115.027933 -245.597979)
			(xy 114.979714 -245.588135) (xy 114.933698 -245.570683) (xy 114.891077 -245.546076) (xy 114.852956 -245.514951)
			(xy 114.820321 -245.478114) (xy 114.794018 -245.436518) (xy 114.774727 -245.391242) (xy 114.76295 -245.343458)
			(xy 114.75899 -245.294404) (xy 114.430048 -245.294404) (xy 114.429553 -245.319011) (xy 114.421658 -245.367588)
			(xy 114.406074 -245.414269) (xy 114.383203 -245.457846) (xy 114.353638 -245.49719) (xy 114.318145 -245.531282)
			(xy 114.277642 -245.559238) (xy 114.23318 -245.580336) (xy 114.185909 -245.594028) (xy 114.137054 -245.59996)
			(xy 114.087879 -245.597979) (xy 114.03966 -245.588135) (xy 113.993644 -245.570683) (xy 113.951023 -245.546076)
			(xy 113.912902 -245.514951) (xy 113.880267 -245.478114) (xy 113.853964 -245.436518) (xy 113.834673 -245.391242)
			(xy 113.822896 -245.343458) (xy 113.818936 -245.294404) (xy 113.489994 -245.294404) (xy 113.489499 -245.319011)
			(xy 113.481604 -245.367588) (xy 113.46602 -245.414269) (xy 113.443149 -245.457846) (xy 113.413584 -245.49719)
			(xy 113.378091 -245.531282) (xy 113.337588 -245.559238) (xy 113.293126 -245.580336) (xy 113.245855 -245.594028)
			(xy 113.197 -245.59996) (xy 113.147825 -245.597979) (xy 113.099606 -245.588135) (xy 113.05359 -245.570683)
			(xy 113.010969 -245.546076) (xy 112.972848 -245.514951) (xy 112.940213 -245.478114) (xy 112.91391 -245.436518)
			(xy 112.894619 -245.391242) (xy 112.882842 -245.343458) (xy 112.878882 -245.294404) (xy 112.027809 -245.294404)
			(xy 112.0292 -245.295464) (xy 112.065712 -245.333402) (xy 112.096004 -245.376468) (xy 112.119367 -245.423653)
			(xy 112.135253 -245.473852) (xy 112.14329 -245.525888) (xy 112.143794 -245.552214) (xy 112.14329 -245.57854)
			(xy 112.135253 -245.630576) (xy 112.119367 -245.680775) (xy 112.096004 -245.72796) (xy 112.065712 -245.771026)
			(xy 112.0292 -245.808964) (xy 111.987326 -245.840883) (xy 111.94107 -245.866036) (xy 111.891517 -245.883834)
			(xy 111.839827 -245.893858) (xy 111.787213 -245.895875) (xy 111.734908 -245.889837) (xy 111.684137 -245.875885)
			(xy 111.636092 -245.854346) (xy 111.591897 -245.825726) (xy 111.552589 -245.790695) (xy 111.519089 -245.750074)
			(xy 111.492183 -245.704815) (xy 111.4725 -245.65598) (xy 111.460503 -245.604712) (xy 111.456473 -245.552214)
			(xy 110.534206 -245.552214) (xy 110.52403 -245.559238) (xy 110.479568 -245.580336) (xy 110.432297 -245.594028)
			(xy 110.383442 -245.59996) (xy 110.334267 -245.597979) (xy 110.286048 -245.588135) (xy 110.240032 -245.570683)
			(xy 110.197411 -245.546076) (xy 110.15929 -245.514951) (xy 110.126655 -245.478114) (xy 110.100352 -245.436518)
			(xy 110.081061 -245.391242) (xy 110.069284 -245.343458) (xy 110.065324 -245.294404) (xy 109.736964 -245.294404)
			(xy 109.732792 -245.344746) (xy 109.72039 -245.393719) (xy 109.700095 -245.439982) (xy 109.672463 -245.482274)
			(xy 109.638246 -245.519441) (xy 109.598378 -245.550468) (xy 109.553947 -245.57451) (xy 109.506164 -245.59091)
			(xy 109.456333 -245.599221) (xy 109.431074 -245.599712) (xy 108.49102 -245.599712) (xy 108.465762 -245.599213)
			(xy 108.415933 -245.590901) (xy 108.368153 -245.574501) (xy 108.323723 -245.550459) (xy 108.283857 -245.519433)
			(xy 108.249642 -245.482267) (xy 108.222011 -245.439977) (xy 108.201717 -245.393715) (xy 108.189316 -245.344744)
			(xy 108.185144 -245.2944) (xy 107.856274 -245.2944) (xy 107.856274 -245.294404) (xy 107.855779 -245.319011)
			(xy 107.847884 -245.367588) (xy 107.8323 -245.414269) (xy 107.809429 -245.457846) (xy 107.779864 -245.49719)
			(xy 107.744371 -245.531282) (xy 107.703868 -245.559238) (xy 107.659406 -245.580336) (xy 107.612135 -245.594028)
			(xy 107.56328 -245.59996) (xy 107.514105 -245.597979) (xy 107.465886 -245.588135) (xy 107.41987 -245.570683)
			(xy 107.377249 -245.546076) (xy 107.339128 -245.514951) (xy 107.306493 -245.478114) (xy 107.28019 -245.436518)
			(xy 107.260899 -245.391242) (xy 107.249122 -245.343458) (xy 107.245162 -245.294404) (xy 105.036366 -245.294404)
			(xy 105.035871 -245.319011) (xy 105.027976 -245.367588) (xy 105.012392 -245.414269) (xy 104.989521 -245.457846)
			(xy 104.959956 -245.49719) (xy 104.924463 -245.531282) (xy 104.88396 -245.559238) (xy 104.839498 -245.580336)
			(xy 104.792227 -245.594028) (xy 104.743372 -245.59996) (xy 104.694197 -245.597979) (xy 104.645978 -245.588135)
			(xy 104.599962 -245.570683) (xy 104.557341 -245.546076) (xy 104.51922 -245.514951) (xy 104.486585 -245.478114)
			(xy 104.460282 -245.436518) (xy 104.440991 -245.391242) (xy 104.429214 -245.343458) (xy 104.425254 -245.294404)
			(xy 102.216458 -245.294404) (xy 102.215963 -245.319011) (xy 102.208068 -245.367588) (xy 102.192484 -245.414269)
			(xy 102.169613 -245.457846) (xy 102.140048 -245.49719) (xy 102.104555 -245.531282) (xy 102.064052 -245.559238)
			(xy 102.01959 -245.580336) (xy 101.972319 -245.594028) (xy 101.923464 -245.59996) (xy 101.874289 -245.597979)
			(xy 101.82607 -245.588135) (xy 101.780054 -245.570683) (xy 101.737433 -245.546076) (xy 101.699312 -245.514951)
			(xy 101.666677 -245.478114) (xy 101.640374 -245.436518) (xy 101.621083 -245.391242) (xy 101.609306 -245.343458)
			(xy 101.605346 -245.294404) (xy 99.396296 -245.294404) (xy 99.395801 -245.319011) (xy 99.387906 -245.367588)
			(xy 99.372322 -245.414269) (xy 99.349451 -245.457846) (xy 99.319886 -245.49719) (xy 99.284393 -245.531282)
			(xy 99.24389 -245.559238) (xy 99.199428 -245.580336) (xy 99.152157 -245.594028) (xy 99.103302 -245.59996)
			(xy 99.054127 -245.597979) (xy 99.005908 -245.588135) (xy 98.959892 -245.570683) (xy 98.917271 -245.546076)
			(xy 98.87915 -245.514951) (xy 98.846515 -245.478114) (xy 98.820212 -245.436518) (xy 98.800921 -245.391242)
			(xy 98.789144 -245.343458) (xy 98.785184 -245.294404) (xy 96.575871 -245.294404) (xy 96.575881 -245.318365)
			(xy 96.568338 -245.36595) (xy 96.553421 -245.411762) (xy 96.531499 -245.454665) (xy 96.503114 -245.493595)
			(xy 96.468971 -245.527588) (xy 96.429917 -245.555801) (xy 96.386918 -245.577535) (xy 96.341041 -245.59225)
			(xy 96.317308 -245.59641) (xy 96.3168 -245.59641) (xy 96.316292 -245.596664) (xy 96.307527 -245.598325)
			(xy 96.291901 -245.606909) (xy 96.285812 -245.613428) (xy 96.280224 -245.619778) (xy 96.273874 -245.636796)
			(xy 96.273874 -245.791736) (xy 96.274061 -245.797971) (xy 96.277141 -245.810053) (xy 96.27997 -245.815612)
			(xy 96.284542 -245.823486) (xy 96.295086 -245.842087) (xy 96.313649 -245.88061) (xy 96.321626 -245.900448)
			(xy 96.323658 -245.905528) (xy 96.326452 -245.913148) (xy 96.33712 -245.92153) (xy 96.342594 -245.925492)
			(xy 96.355082 -245.930642) (xy 96.361758 -245.93169) (xy 96.448372 -245.94312) (xy 96.455111 -245.943704)
			(xy 96.468494 -245.941786) (xy 96.474788 -245.93931) (xy 96.48698 -245.93423) (xy 96.490536 -245.929658)
			(xy 96.495616 -245.9228) (xy 96.510121 -245.903973) (xy 96.543978 -245.870622) (xy 96.582592 -245.842917)
			(xy 96.62503 -245.821527) (xy 96.67027 -245.806967) (xy 96.717218 -245.799588) (xy 96.74098 -245.799102)
			(xy 96.766238 -245.799593) (xy 96.816065 -245.807905) (xy 96.863845 -245.824305) (xy 96.908274 -245.848346)
			(xy 96.948139 -245.879372) (xy 96.982353 -245.916536) (xy 97.009984 -245.958826) (xy 97.030277 -246.005087)
			(xy 97.042678 -246.054057) (xy 97.04685 -246.1044) (xy 97.374895 -246.1044) (xy 97.379071 -246.054013)
			(xy 97.391483 -246.005001) (xy 97.411794 -245.958701) (xy 97.439449 -245.916375) (xy 97.473694 -245.879179)
			(xy 97.513595 -245.848128) (xy 97.558062 -245.824068) (xy 97.605884 -245.807655) (xy 97.655754 -245.799338)
			(xy 97.681034 -245.798848) (xy 98.621088 -245.798848) (xy 98.646368 -245.79932) (xy 98.696239 -245.80764)
			(xy 98.744061 -245.824056) (xy 98.788528 -245.848119) (xy 98.828428 -245.879173) (xy 98.862672 -245.91637)
			(xy 98.890327 -245.958698) (xy 98.910637 -246.004999) (xy 98.923049 -246.054012) (xy 98.927225 -246.1044)
			(xy 98.927224 -246.10441) (xy 99.255338 -246.10441) (xy 99.259298 -246.055356) (xy 99.271075 -246.007572)
			(xy 99.290366 -245.962296) (xy 99.316669 -245.9207) (xy 99.349304 -245.883863) (xy 99.387425 -245.852738)
			(xy 99.430046 -245.828131) (xy 99.476062 -245.810679) (xy 99.524281 -245.800835) (xy 99.573456 -245.798854)
			(xy 99.622311 -245.804786) (xy 99.669582 -245.818478) (xy 99.714044 -245.839576) (xy 99.754547 -245.867532)
			(xy 99.79004 -245.901624) (xy 99.819605 -245.940968) (xy 99.842476 -245.984545) (xy 99.85806 -246.031226)
			(xy 99.865955 -246.079803) (xy 99.86645 -246.1044) (xy 100.194795 -246.1044) (xy 100.198971 -246.054012)
			(xy 100.211384 -246.005) (xy 100.231695 -245.958699) (xy 100.259351 -245.916373) (xy 100.293597 -245.879177)
			(xy 100.333499 -245.848125) (xy 100.377968 -245.824065) (xy 100.42579 -245.807654) (xy 100.475662 -245.799338)
			(xy 100.500942 -245.798848) (xy 101.440996 -245.798848) (xy 101.466276 -245.799321) (xy 101.516146 -245.807642)
			(xy 101.563966 -245.824058) (xy 101.608432 -245.848121) (xy 101.648331 -245.879175) (xy 101.682574 -245.916373)
			(xy 101.710228 -245.9587) (xy 101.730538 -246.005001) (xy 101.742949 -246.054013) (xy 101.747125 -246.1044)
			(xy 101.747124 -246.10441) (xy 102.075246 -246.10441) (xy 102.079206 -246.055356) (xy 102.090983 -246.007572)
			(xy 102.110274 -245.962296) (xy 102.136577 -245.9207) (xy 102.169212 -245.883863) (xy 102.207333 -245.852738)
			(xy 102.249954 -245.828131) (xy 102.29597 -245.810679) (xy 102.344189 -245.800835) (xy 102.393364 -245.798854)
			(xy 102.442219 -245.804786) (xy 102.48949 -245.818478) (xy 102.533952 -245.839576) (xy 102.574455 -245.867532)
			(xy 102.609948 -245.901624) (xy 102.639513 -245.940968) (xy 102.662384 -245.984545) (xy 102.677968 -246.031226)
			(xy 102.685863 -246.079803) (xy 102.686358 -246.1044) (xy 103.014995 -246.1044) (xy 103.01917 -246.054016)
			(xy 103.031581 -246.005007) (xy 103.05189 -245.958709) (xy 103.079542 -245.916385) (xy 103.113783 -245.87919)
			(xy 103.153679 -245.848138) (xy 103.198142 -245.824076) (xy 103.245959 -245.807661) (xy 103.295826 -245.799341)
			(xy 103.321104 -245.798848) (xy 104.261158 -245.798848) (xy 104.28644 -245.799318) (xy 104.336315 -245.807634)
			(xy 104.38414 -245.824047) (xy 104.428612 -245.848108) (xy 104.468516 -245.879162) (xy 104.502764 -245.91636)
			(xy 104.530422 -245.958689) (xy 104.550735 -246.004993) (xy 104.563149 -246.054009) (xy 104.567325 -246.1044)
			(xy 104.567324 -246.10441) (xy 104.895154 -246.10441) (xy 104.899114 -246.055356) (xy 104.910891 -246.007572)
			(xy 104.930182 -245.962296) (xy 104.956485 -245.9207) (xy 104.98912 -245.883863) (xy 105.027241 -245.852738)
			(xy 105.069862 -245.828131) (xy 105.115878 -245.810679) (xy 105.164097 -245.800835) (xy 105.213272 -245.798854)
			(xy 105.262127 -245.804786) (xy 105.309398 -245.818478) (xy 105.35386 -245.839576) (xy 105.394363 -245.867532)
			(xy 105.429856 -245.901624) (xy 105.459421 -245.940968) (xy 105.482292 -245.984545) (xy 105.497876 -246.031226)
			(xy 105.505771 -246.079803) (xy 105.506266 -246.1044) (xy 105.834895 -246.1044) (xy 105.839071 -246.054016)
			(xy 105.851482 -246.005006) (xy 105.871791 -245.958707) (xy 105.899444 -245.916383) (xy 105.933686 -245.879187)
			(xy 105.973583 -245.848135) (xy 106.018047 -245.824074) (xy 106.065866 -245.80766) (xy 106.115733 -245.79934)
			(xy 106.141012 -245.798848) (xy 107.081066 -245.798848) (xy 107.106347 -245.799318) (xy 107.156221 -245.807636)
			(xy 107.204046 -245.824049) (xy 107.248516 -245.848111) (xy 107.288419 -245.879165) (xy 107.322666 -245.916363)
			(xy 107.350323 -245.958691) (xy 107.370636 -246.004995) (xy 107.383049 -246.05401) (xy 107.387225 -246.1044)
			(xy 107.387224 -246.10441) (xy 107.715316 -246.10441) (xy 107.719276 -246.055356) (xy 107.731053 -246.007572)
			(xy 107.750344 -245.962296) (xy 107.776647 -245.9207) (xy 107.809282 -245.883863) (xy 107.847403 -245.852738)
			(xy 107.890024 -245.828131) (xy 107.93604 -245.810679) (xy 107.984259 -245.800835) (xy 108.033434 -245.798854)
			(xy 108.082289 -245.804786) (xy 108.12956 -245.818478) (xy 108.174022 -245.839576) (xy 108.214525 -245.867532)
			(xy 108.250018 -245.901624) (xy 108.279583 -245.940968) (xy 108.302454 -245.984545) (xy 108.318038 -246.031226)
			(xy 108.325933 -246.079803) (xy 108.326428 -246.10441) (xy 115.22889 -246.10441) (xy 115.23285 -246.055356)
			(xy 115.244627 -246.007572) (xy 115.263918 -245.962296) (xy 115.290221 -245.9207) (xy 115.322856 -245.883863)
			(xy 115.360977 -245.852738) (xy 115.403598 -245.828131) (xy 115.449614 -245.810679) (xy 115.497833 -245.800835)
			(xy 115.547008 -245.798854) (xy 115.595863 -245.804786) (xy 115.643134 -245.818478) (xy 115.687596 -245.839576)
			(xy 115.728099 -245.867532) (xy 115.763592 -245.901624) (xy 115.793157 -245.940968) (xy 115.816028 -245.984545)
			(xy 115.831612 -246.031226) (xy 115.839507 -246.079803) (xy 115.840002 -246.10441) (xy 116.168944 -246.10441)
			(xy 116.172904 -246.055356) (xy 116.184681 -246.007572) (xy 116.203972 -245.962296) (xy 116.230275 -245.9207)
			(xy 116.26291 -245.883863) (xy 116.301031 -245.852738) (xy 116.343652 -245.828131) (xy 116.389668 -245.810679)
			(xy 116.437887 -245.800835) (xy 116.487062 -245.798854) (xy 116.535917 -245.804786) (xy 116.583188 -245.818478)
			(xy 116.62765 -245.839576) (xy 116.668153 -245.867532) (xy 116.703646 -245.901624) (xy 116.733211 -245.940968)
			(xy 116.756082 -245.984545) (xy 116.771666 -246.031226) (xy 116.779561 -246.079803) (xy 116.780056 -246.10441)
			(xy 117.108998 -246.10441) (xy 117.112958 -246.055356) (xy 117.124735 -246.007572) (xy 117.144026 -245.962296)
			(xy 117.170329 -245.9207) (xy 117.202964 -245.883863) (xy 117.241085 -245.852738) (xy 117.283706 -245.828131)
			(xy 117.329722 -245.810679) (xy 117.377941 -245.800835) (xy 117.427116 -245.798854) (xy 117.475971 -245.804786)
			(xy 117.523242 -245.818478) (xy 117.567704 -245.839576) (xy 117.608207 -245.867532) (xy 117.6437 -245.901624)
			(xy 117.673265 -245.940968) (xy 117.696136 -245.984545) (xy 117.71172 -246.031226) (xy 117.719615 -246.079803)
			(xy 117.72011 -246.10441) (xy 118.049052 -246.10441) (xy 118.053012 -246.055356) (xy 118.064789 -246.007572)
			(xy 118.08408 -245.962296) (xy 118.110383 -245.9207) (xy 118.143018 -245.883863) (xy 118.181139 -245.852738)
			(xy 118.22376 -245.828131) (xy 118.269776 -245.810679) (xy 118.317995 -245.800835) (xy 118.36717 -245.798854)
			(xy 118.416025 -245.804786) (xy 118.463296 -245.818478) (xy 118.507758 -245.839576) (xy 118.548261 -245.867532)
			(xy 118.583754 -245.901624) (xy 118.613319 -245.940968) (xy 118.63619 -245.984545) (xy 118.651774 -246.031226)
			(xy 118.659669 -246.079803) (xy 118.660164 -246.10441) (xy 118.988852 -246.10441) (xy 118.992812 -246.055356)
			(xy 119.004589 -246.007572) (xy 119.02388 -245.962296) (xy 119.050183 -245.9207) (xy 119.082818 -245.883863)
			(xy 119.120939 -245.852738) (xy 119.16356 -245.828131) (xy 119.209576 -245.810679) (xy 119.257795 -245.800835)
			(xy 119.30697 -245.798854) (xy 119.355825 -245.804786) (xy 119.403096 -245.818478) (xy 119.447558 -245.839576)
			(xy 119.488061 -245.867532) (xy 119.523554 -245.901624) (xy 119.553119 -245.940968) (xy 119.57599 -245.984545)
			(xy 119.591574 -246.031226) (xy 119.599469 -246.079803) (xy 119.599964 -246.10441) (xy 119.928906 -246.10441)
			(xy 119.932866 -246.055356) (xy 119.944643 -246.007572) (xy 119.963934 -245.962296) (xy 119.990237 -245.9207)
			(xy 120.022872 -245.883863) (xy 120.060993 -245.852738) (xy 120.103614 -245.828131) (xy 120.14963 -245.810679)
			(xy 120.197849 -245.800835) (xy 120.247024 -245.798854) (xy 120.295879 -245.804786) (xy 120.34315 -245.818478)
			(xy 120.387612 -245.839576) (xy 120.428115 -245.867532) (xy 120.463608 -245.901624) (xy 120.493173 -245.940968)
			(xy 120.516044 -245.984545) (xy 120.531628 -246.031226) (xy 120.539523 -246.079803) (xy 120.540018 -246.10441)
			(xy 120.86896 -246.10441) (xy 120.87292 -246.055356) (xy 120.884697 -246.007572) (xy 120.903988 -245.962296)
			(xy 120.930291 -245.9207) (xy 120.962926 -245.883863) (xy 121.001047 -245.852738) (xy 121.043668 -245.828131)
			(xy 121.089684 -245.810679) (xy 121.137903 -245.800835) (xy 121.187078 -245.798854) (xy 121.235933 -245.804786)
			(xy 121.283204 -245.818478) (xy 121.327666 -245.839576) (xy 121.368169 -245.867532) (xy 121.403662 -245.901624)
			(xy 121.433227 -245.940968) (xy 121.456098 -245.984545) (xy 121.471682 -246.031226) (xy 121.479577 -246.079803)
			(xy 121.480072 -246.10441) (xy 121.809014 -246.10441) (xy 121.812974 -246.055356) (xy 121.824751 -246.007572)
			(xy 121.844042 -245.962296) (xy 121.870345 -245.9207) (xy 121.90298 -245.883863) (xy 121.941101 -245.852738)
			(xy 121.983722 -245.828131) (xy 122.029738 -245.810679) (xy 122.077957 -245.800835) (xy 122.127132 -245.798854)
			(xy 122.175987 -245.804786) (xy 122.223258 -245.818478) (xy 122.26772 -245.839576) (xy 122.308223 -245.867532)
			(xy 122.343716 -245.901624) (xy 122.373281 -245.940968) (xy 122.396152 -245.984545) (xy 122.411736 -246.031226)
			(xy 122.419631 -246.079803) (xy 122.420126 -246.10441) (xy 122.748814 -246.10441) (xy 122.752774 -246.055356)
			(xy 122.764551 -246.007572) (xy 122.783842 -245.962296) (xy 122.810145 -245.9207) (xy 122.84278 -245.883863)
			(xy 122.880901 -245.852738) (xy 122.923522 -245.828131) (xy 122.969538 -245.810679) (xy 123.017757 -245.800835)
			(xy 123.066932 -245.798854) (xy 123.115787 -245.804786) (xy 123.163058 -245.818478) (xy 123.20752 -245.839576)
			(xy 123.248023 -245.867532) (xy 123.283516 -245.901624) (xy 123.313081 -245.940968) (xy 123.335952 -245.984545)
			(xy 123.351536 -246.031226) (xy 123.359431 -246.079803) (xy 123.359926 -246.10441) (xy 123.688868 -246.10441)
			(xy 123.692828 -246.055356) (xy 123.704605 -246.007572) (xy 123.723896 -245.962296) (xy 123.750199 -245.9207)
			(xy 123.782834 -245.883863) (xy 123.820955 -245.852738) (xy 123.863576 -245.828131) (xy 123.909592 -245.810679)
			(xy 123.957811 -245.800835) (xy 124.006986 -245.798854) (xy 124.055841 -245.804786) (xy 124.103112 -245.818478)
			(xy 124.147574 -245.839576) (xy 124.188077 -245.867532) (xy 124.22357 -245.901624) (xy 124.253135 -245.940968)
			(xy 124.276006 -245.984545) (xy 124.29159 -246.031226) (xy 124.299485 -246.079803) (xy 124.29998 -246.10441)
			(xy 124.628922 -246.10441) (xy 124.632882 -246.055356) (xy 124.644659 -246.007572) (xy 124.66395 -245.962296)
			(xy 124.690253 -245.9207) (xy 124.722888 -245.883863) (xy 124.761009 -245.852738) (xy 124.80363 -245.828131)
			(xy 124.849646 -245.810679) (xy 124.897865 -245.800835) (xy 124.94704 -245.798854) (xy 124.995895 -245.804786)
			(xy 125.043166 -245.818478) (xy 125.087628 -245.839576) (xy 125.128131 -245.867532) (xy 125.163624 -245.901624)
			(xy 125.193189 -245.940968) (xy 125.21606 -245.984545) (xy 125.231644 -246.031226) (xy 125.239539 -246.079803)
			(xy 125.240034 -246.10441) (xy 125.568976 -246.10441) (xy 125.572936 -246.055356) (xy 125.584713 -246.007572)
			(xy 125.604004 -245.962296) (xy 125.630307 -245.9207) (xy 125.662942 -245.883863) (xy 125.701063 -245.852738)
			(xy 125.743684 -245.828131) (xy 125.7897 -245.810679) (xy 125.837919 -245.800835) (xy 125.887094 -245.798854)
			(xy 125.935949 -245.804786) (xy 125.98322 -245.818478) (xy 126.027682 -245.839576) (xy 126.068185 -245.867532)
			(xy 126.103678 -245.901624) (xy 126.133243 -245.940968) (xy 126.156114 -245.984545) (xy 126.171698 -246.031226)
			(xy 126.179593 -246.079803) (xy 126.180088 -246.10441) (xy 126.179593 -246.129017) (xy 126.171698 -246.177594)
			(xy 126.156114 -246.224275) (xy 126.133243 -246.267852) (xy 126.103678 -246.307196) (xy 126.068185 -246.341288)
			(xy 126.027682 -246.369244) (xy 125.98322 -246.390342) (xy 125.935949 -246.404034) (xy 125.887094 -246.409966)
			(xy 125.837919 -246.407985) (xy 125.7897 -246.398141) (xy 125.743684 -246.380689) (xy 125.701063 -246.356082)
			(xy 125.662942 -246.324957) (xy 125.630307 -246.28812) (xy 125.604004 -246.246524) (xy 125.584713 -246.201248)
			(xy 125.572936 -246.153464) (xy 125.568976 -246.10441) (xy 125.240034 -246.10441) (xy 125.239539 -246.129017)
			(xy 125.231644 -246.177594) (xy 125.21606 -246.224275) (xy 125.193189 -246.267852) (xy 125.163624 -246.307196)
			(xy 125.128131 -246.341288) (xy 125.087628 -246.369244) (xy 125.043166 -246.390342) (xy 124.995895 -246.404034)
			(xy 124.94704 -246.409966) (xy 124.897865 -246.407985) (xy 124.849646 -246.398141) (xy 124.80363 -246.380689)
			(xy 124.761009 -246.356082) (xy 124.722888 -246.324957) (xy 124.690253 -246.28812) (xy 124.66395 -246.246524)
			(xy 124.644659 -246.201248) (xy 124.632882 -246.153464) (xy 124.628922 -246.10441) (xy 124.29998 -246.10441)
			(xy 124.299485 -246.129017) (xy 124.29159 -246.177594) (xy 124.276006 -246.224275) (xy 124.253135 -246.267852)
			(xy 124.22357 -246.307196) (xy 124.188077 -246.341288) (xy 124.147574 -246.369244) (xy 124.103112 -246.390342)
			(xy 124.055841 -246.404034) (xy 124.006986 -246.409966) (xy 123.957811 -246.407985) (xy 123.909592 -246.398141)
			(xy 123.863576 -246.380689) (xy 123.820955 -246.356082) (xy 123.782834 -246.324957) (xy 123.750199 -246.28812)
			(xy 123.723896 -246.246524) (xy 123.704605 -246.201248) (xy 123.692828 -246.153464) (xy 123.688868 -246.10441)
			(xy 123.359926 -246.10441) (xy 123.359431 -246.129017) (xy 123.351536 -246.177594) (xy 123.335952 -246.224275)
			(xy 123.313081 -246.267852) (xy 123.283516 -246.307196) (xy 123.248023 -246.341288) (xy 123.20752 -246.369244)
			(xy 123.163058 -246.390342) (xy 123.115787 -246.404034) (xy 123.066932 -246.409966) (xy 123.017757 -246.407985)
			(xy 122.969538 -246.398141) (xy 122.923522 -246.380689) (xy 122.880901 -246.356082) (xy 122.84278 -246.324957)
			(xy 122.810145 -246.28812) (xy 122.783842 -246.246524) (xy 122.764551 -246.201248) (xy 122.752774 -246.153464)
			(xy 122.748814 -246.10441) (xy 122.420126 -246.10441) (xy 122.419631 -246.129017) (xy 122.411736 -246.177594)
			(xy 122.396152 -246.224275) (xy 122.373281 -246.267852) (xy 122.343716 -246.307196) (xy 122.308223 -246.341288)
			(xy 122.26772 -246.369244) (xy 122.223258 -246.390342) (xy 122.175987 -246.404034) (xy 122.127132 -246.409966)
			(xy 122.077957 -246.407985) (xy 122.029738 -246.398141) (xy 121.983722 -246.380689) (xy 121.941101 -246.356082)
			(xy 121.90298 -246.324957) (xy 121.870345 -246.28812) (xy 121.844042 -246.246524) (xy 121.824751 -246.201248)
			(xy 121.812974 -246.153464) (xy 121.809014 -246.10441) (xy 121.480072 -246.10441) (xy 121.479577 -246.129017)
			(xy 121.471682 -246.177594) (xy 121.456098 -246.224275) (xy 121.433227 -246.267852) (xy 121.403662 -246.307196)
			(xy 121.368169 -246.341288) (xy 121.327666 -246.369244) (xy 121.283204 -246.390342) (xy 121.235933 -246.404034)
			(xy 121.187078 -246.409966) (xy 121.137903 -246.407985) (xy 121.089684 -246.398141) (xy 121.043668 -246.380689)
			(xy 121.001047 -246.356082) (xy 120.962926 -246.324957) (xy 120.930291 -246.28812) (xy 120.903988 -246.246524)
			(xy 120.884697 -246.201248) (xy 120.87292 -246.153464) (xy 120.86896 -246.10441) (xy 120.540018 -246.10441)
			(xy 120.539523 -246.129017) (xy 120.531628 -246.177594) (xy 120.516044 -246.224275) (xy 120.493173 -246.267852)
			(xy 120.463608 -246.307196) (xy 120.428115 -246.341288) (xy 120.387612 -246.369244) (xy 120.34315 -246.390342)
			(xy 120.295879 -246.404034) (xy 120.247024 -246.409966) (xy 120.197849 -246.407985) (xy 120.14963 -246.398141)
			(xy 120.103614 -246.380689) (xy 120.060993 -246.356082) (xy 120.022872 -246.324957) (xy 119.990237 -246.28812)
			(xy 119.963934 -246.246524) (xy 119.944643 -246.201248) (xy 119.932866 -246.153464) (xy 119.928906 -246.10441)
			(xy 119.599964 -246.10441) (xy 119.599469 -246.129017) (xy 119.591574 -246.177594) (xy 119.57599 -246.224275)
			(xy 119.553119 -246.267852) (xy 119.523554 -246.307196) (xy 119.488061 -246.341288) (xy 119.447558 -246.369244)
			(xy 119.403096 -246.390342) (xy 119.355825 -246.404034) (xy 119.30697 -246.409966) (xy 119.257795 -246.407985)
			(xy 119.209576 -246.398141) (xy 119.16356 -246.380689) (xy 119.120939 -246.356082) (xy 119.082818 -246.324957)
			(xy 119.050183 -246.28812) (xy 119.02388 -246.246524) (xy 119.004589 -246.201248) (xy 118.992812 -246.153464)
			(xy 118.988852 -246.10441) (xy 118.660164 -246.10441) (xy 118.659669 -246.129017) (xy 118.651774 -246.177594)
			(xy 118.63619 -246.224275) (xy 118.613319 -246.267852) (xy 118.583754 -246.307196) (xy 118.548261 -246.341288)
			(xy 118.507758 -246.369244) (xy 118.463296 -246.390342) (xy 118.416025 -246.404034) (xy 118.36717 -246.409966)
			(xy 118.317995 -246.407985) (xy 118.269776 -246.398141) (xy 118.22376 -246.380689) (xy 118.181139 -246.356082)
			(xy 118.143018 -246.324957) (xy 118.110383 -246.28812) (xy 118.08408 -246.246524) (xy 118.064789 -246.201248)
			(xy 118.053012 -246.153464) (xy 118.049052 -246.10441) (xy 117.72011 -246.10441) (xy 117.719615 -246.129017)
			(xy 117.71172 -246.177594) (xy 117.696136 -246.224275) (xy 117.673265 -246.267852) (xy 117.6437 -246.307196)
			(xy 117.608207 -246.341288) (xy 117.567704 -246.369244) (xy 117.523242 -246.390342) (xy 117.475971 -246.404034)
			(xy 117.427116 -246.409966) (xy 117.377941 -246.407985) (xy 117.329722 -246.398141) (xy 117.283706 -246.380689)
			(xy 117.241085 -246.356082) (xy 117.202964 -246.324957) (xy 117.170329 -246.28812) (xy 117.144026 -246.246524)
			(xy 117.124735 -246.201248) (xy 117.112958 -246.153464) (xy 117.108998 -246.10441) (xy 116.780056 -246.10441)
			(xy 116.779561 -246.129017) (xy 116.771666 -246.177594) (xy 116.756082 -246.224275) (xy 116.733211 -246.267852)
			(xy 116.703646 -246.307196) (xy 116.668153 -246.341288) (xy 116.62765 -246.369244) (xy 116.583188 -246.390342)
			(xy 116.535917 -246.404034) (xy 116.487062 -246.409966) (xy 116.437887 -246.407985) (xy 116.389668 -246.398141)
			(xy 116.343652 -246.380689) (xy 116.301031 -246.356082) (xy 116.26291 -246.324957) (xy 116.230275 -246.28812)
			(xy 116.203972 -246.246524) (xy 116.184681 -246.201248) (xy 116.172904 -246.153464) (xy 116.168944 -246.10441)
			(xy 115.840002 -246.10441) (xy 115.839507 -246.129017) (xy 115.831612 -246.177594) (xy 115.816028 -246.224275)
			(xy 115.793157 -246.267852) (xy 115.763592 -246.307196) (xy 115.728099 -246.341288) (xy 115.687596 -246.369244)
			(xy 115.643134 -246.390342) (xy 115.595863 -246.404034) (xy 115.547008 -246.409966) (xy 115.497833 -246.407985)
			(xy 115.449614 -246.398141) (xy 115.403598 -246.380689) (xy 115.360977 -246.356082) (xy 115.322856 -246.324957)
			(xy 115.290221 -246.28812) (xy 115.263918 -246.246524) (xy 115.244627 -246.201248) (xy 115.23285 -246.153464)
			(xy 115.22889 -246.10441) (xy 108.326428 -246.10441) (xy 108.325933 -246.129017) (xy 108.318038 -246.177594)
			(xy 108.302454 -246.224275) (xy 108.279583 -246.267852) (xy 108.250018 -246.307196) (xy 108.214525 -246.341288)
			(xy 108.174022 -246.369244) (xy 108.12956 -246.390342) (xy 108.082289 -246.404034) (xy 108.033434 -246.409966)
			(xy 107.984259 -246.407985) (xy 107.93604 -246.398141) (xy 107.890024 -246.380689) (xy 107.847403 -246.356082)
			(xy 107.809282 -246.324957) (xy 107.776647 -246.28812) (xy 107.750344 -246.246524) (xy 107.731053 -246.201248)
			(xy 107.719276 -246.153464) (xy 107.715316 -246.10441) (xy 107.387224 -246.10441) (xy 107.383049 -246.15479)
			(xy 107.370636 -246.203805) (xy 107.350323 -246.250109) (xy 107.322666 -246.292437) (xy 107.288419 -246.329635)
			(xy 107.248516 -246.360689) (xy 107.204046 -246.384751) (xy 107.156221 -246.401164) (xy 107.106347 -246.409482)
			(xy 107.081066 -246.409972) (xy 106.141012 -246.409972) (xy 106.115733 -246.40946) (xy 106.065866 -246.40114)
			(xy 106.018047 -246.384726) (xy 105.973583 -246.360665) (xy 105.933686 -246.329613) (xy 105.899444 -246.292417)
			(xy 105.871791 -246.250093) (xy 105.851482 -246.203794) (xy 105.839071 -246.154784) (xy 105.834895 -246.1044)
			(xy 105.506266 -246.1044) (xy 105.506266 -246.10441) (xy 105.505771 -246.129017) (xy 105.497876 -246.177594)
			(xy 105.482292 -246.224275) (xy 105.459421 -246.267852) (xy 105.429856 -246.307196) (xy 105.394363 -246.341288)
			(xy 105.35386 -246.369244) (xy 105.309398 -246.390342) (xy 105.262127 -246.404034) (xy 105.213272 -246.409966)
			(xy 105.164097 -246.407985) (xy 105.115878 -246.398141) (xy 105.069862 -246.380689) (xy 105.027241 -246.356082)
			(xy 104.98912 -246.324957) (xy 104.956485 -246.28812) (xy 104.930182 -246.246524) (xy 104.910891 -246.201248)
			(xy 104.899114 -246.153464) (xy 104.895154 -246.10441) (xy 104.567324 -246.10441) (xy 104.563149 -246.154791)
			(xy 104.550735 -246.203807) (xy 104.530422 -246.250111) (xy 104.502764 -246.29244) (xy 104.468516 -246.329638)
			(xy 104.428612 -246.360692) (xy 104.38414 -246.384753) (xy 104.336315 -246.401166) (xy 104.28644 -246.409482)
			(xy 104.261158 -246.409972) (xy 103.321104 -246.409972) (xy 103.295826 -246.409459) (xy 103.245959 -246.401139)
			(xy 103.198142 -246.384724) (xy 103.153679 -246.360662) (xy 103.113783 -246.32961) (xy 103.079542 -246.292415)
			(xy 103.05189 -246.250091) (xy 103.031581 -246.203793) (xy 103.01917 -246.154784) (xy 103.014995 -246.1044)
			(xy 102.686358 -246.1044) (xy 102.686358 -246.10441) (xy 102.685863 -246.129017) (xy 102.677968 -246.177594)
			(xy 102.662384 -246.224275) (xy 102.639513 -246.267852) (xy 102.609948 -246.307196) (xy 102.574455 -246.341288)
			(xy 102.533952 -246.369244) (xy 102.48949 -246.390342) (xy 102.442219 -246.404034) (xy 102.393364 -246.409966)
			(xy 102.344189 -246.407985) (xy 102.29597 -246.398141) (xy 102.249954 -246.380689) (xy 102.207333 -246.356082)
			(xy 102.169212 -246.324957) (xy 102.136577 -246.28812) (xy 102.110274 -246.246524) (xy 102.090983 -246.201248)
			(xy 102.079206 -246.153464) (xy 102.075246 -246.10441) (xy 101.747124 -246.10441) (xy 101.742949 -246.154787)
			(xy 101.730538 -246.203799) (xy 101.710228 -246.2501) (xy 101.682574 -246.292427) (xy 101.648331 -246.329625)
			(xy 101.608432 -246.360679) (xy 101.563966 -246.384742) (xy 101.516146 -246.401158) (xy 101.466276 -246.409479)
			(xy 101.440996 -246.409972) (xy 100.500942 -246.409972) (xy 100.475662 -246.409462) (xy 100.42579 -246.401146)
			(xy 100.377968 -246.384735) (xy 100.333499 -246.360675) (xy 100.293597 -246.329623) (xy 100.259351 -246.292427)
			(xy 100.231695 -246.250101) (xy 100.211384 -246.2038) (xy 100.198971 -246.154788) (xy 100.194795 -246.1044)
			(xy 99.86645 -246.1044) (xy 99.86645 -246.10441) (xy 99.865955 -246.129017) (xy 99.85806 -246.177594)
			(xy 99.842476 -246.224275) (xy 99.819605 -246.267852) (xy 99.79004 -246.307196) (xy 99.754547 -246.341288)
			(xy 99.714044 -246.369244) (xy 99.669582 -246.390342) (xy 99.622311 -246.404034) (xy 99.573456 -246.409966)
			(xy 99.524281 -246.407985) (xy 99.476062 -246.398141) (xy 99.430046 -246.380689) (xy 99.387425 -246.356082)
			(xy 99.349304 -246.324957) (xy 99.316669 -246.28812) (xy 99.290366 -246.246524) (xy 99.271075 -246.201248)
			(xy 99.259298 -246.153464) (xy 99.255338 -246.10441) (xy 98.927224 -246.10441) (xy 98.923049 -246.154788)
			(xy 98.910637 -246.203801) (xy 98.890327 -246.250102) (xy 98.862672 -246.29243) (xy 98.828428 -246.329627)
			(xy 98.788528 -246.360681) (xy 98.744061 -246.384744) (xy 98.696239 -246.40116) (xy 98.646368 -246.40948)
			(xy 98.621088 -246.409972) (xy 97.681034 -246.409972) (xy 97.655754 -246.409462) (xy 97.605884 -246.401145)
			(xy 97.558062 -246.384732) (xy 97.513595 -246.360672) (xy 97.473694 -246.329621) (xy 97.439449 -246.292425)
			(xy 97.411794 -246.250099) (xy 97.391483 -246.203799) (xy 97.379071 -246.154787) (xy 97.374895 -246.1044)
			(xy 97.04685 -246.1044) (xy 97.042678 -246.154743) (xy 97.030277 -246.203713) (xy 97.009984 -246.249974)
			(xy 96.982353 -246.292264) (xy 96.948139 -246.329428) (xy 96.908274 -246.360454) (xy 96.863845 -246.384495)
			(xy 96.816065 -246.400895) (xy 96.766238 -246.409207) (xy 96.74098 -246.409718) (xy 96.717213 -246.40927)
			(xy 96.670253 -246.401911) (xy 96.625002 -246.387359) (xy 96.582555 -246.365965) (xy 96.543939 -246.338248)
			(xy 96.510088 -246.304877) (xy 96.495616 -246.28602) (xy 96.490536 -246.279162) (xy 96.48698 -246.27459)
			(xy 96.474788 -246.26951) (xy 96.468506 -246.266983) (xy 96.45511 -246.26504) (xy 96.448372 -246.2657)
			(xy 96.361758 -246.27713) (xy 96.355082 -246.27818) (xy 96.342587 -246.283318) (xy 96.33712 -246.28729)
			(xy 96.326452 -246.295672) (xy 96.323658 -246.303292) (xy 96.321626 -246.308372) (xy 96.308164 -246.339614)
			(xy 96.302016 -246.352739) (xy 96.288547 -246.378405) (xy 96.28124 -246.390922) (xy 96.280986 -246.391176)
			(xy 96.27743 -246.397272) (xy 96.275652 -246.403368) (xy 96.273874 -246.41683) (xy 96.273874 -246.562626)
			(xy 96.274241 -246.571734) (xy 96.280608 -246.588798) (xy 96.28632 -246.5959) (xy 96.291908 -246.60225)
			(xy 96.307402 -246.610886) (xy 96.317054 -246.61241) (xy 96.340797 -246.616504) (xy 96.386684 -246.631182)
			(xy 96.429698 -246.65288) (xy 96.468774 -246.68106) (xy 96.502943 -246.715024) (xy 96.531358 -246.75393)
			(xy 96.553315 -246.796813) (xy 96.568269 -246.842611) (xy 96.575849 -246.890188) (xy 96.575859 -246.914416)
			(xy 96.90533 -246.914416) (xy 96.90929 -246.865362) (xy 96.921067 -246.817578) (xy 96.940358 -246.772302)
			(xy 96.966661 -246.730706) (xy 96.999296 -246.693869) (xy 97.037417 -246.662744) (xy 97.080038 -246.638137)
			(xy 97.126054 -246.620685) (xy 97.174273 -246.610841) (xy 97.223448 -246.60886) (xy 97.272303 -246.614792)
			(xy 97.319574 -246.628484) (xy 97.364036 -246.649582) (xy 97.404539 -246.677538) (xy 97.440032 -246.71163)
			(xy 97.469597 -246.750974) (xy 97.492468 -246.794551) (xy 97.508052 -246.841232) (xy 97.515947 -246.889809)
			(xy 97.516442 -246.914416) (xy 97.84513 -246.914416) (xy 97.84909 -246.865362) (xy 97.860867 -246.817578)
			(xy 97.880158 -246.772302) (xy 97.906461 -246.730706) (xy 97.939096 -246.693869) (xy 97.977217 -246.662744)
			(xy 98.019838 -246.638137) (xy 98.065854 -246.620685) (xy 98.114073 -246.610841) (xy 98.163248 -246.60886)
			(xy 98.212103 -246.614792) (xy 98.259374 -246.628484) (xy 98.303836 -246.649582) (xy 98.344339 -246.677538)
			(xy 98.379832 -246.71163) (xy 98.409397 -246.750974) (xy 98.432268 -246.794551) (xy 98.447852 -246.841232)
			(xy 98.455747 -246.889809) (xy 98.456242 -246.914416) (xy 98.785184 -246.914416) (xy 98.789144 -246.865362)
			(xy 98.800921 -246.817578) (xy 98.820212 -246.772302) (xy 98.846515 -246.730706) (xy 98.87915 -246.693869)
			(xy 98.917271 -246.662744) (xy 98.959892 -246.638137) (xy 99.005908 -246.620685) (xy 99.054127 -246.610841)
			(xy 99.103302 -246.60886) (xy 99.152157 -246.614792) (xy 99.199428 -246.628484) (xy 99.24389 -246.649582)
			(xy 99.284393 -246.677538) (xy 99.319886 -246.71163) (xy 99.349451 -246.750974) (xy 99.372322 -246.794551)
			(xy 99.387906 -246.841232) (xy 99.395801 -246.889809) (xy 99.396296 -246.914416) (xy 99.725238 -246.914416)
			(xy 99.729198 -246.865362) (xy 99.740975 -246.817578) (xy 99.760266 -246.772302) (xy 99.786569 -246.730706)
			(xy 99.819204 -246.693869) (xy 99.857325 -246.662744) (xy 99.899946 -246.638137) (xy 99.945962 -246.620685)
			(xy 99.994181 -246.610841) (xy 100.043356 -246.60886) (xy 100.092211 -246.614792) (xy 100.139482 -246.628484)
			(xy 100.183944 -246.649582) (xy 100.224447 -246.677538) (xy 100.25994 -246.71163) (xy 100.289505 -246.750974)
			(xy 100.312376 -246.794551) (xy 100.32796 -246.841232) (xy 100.335855 -246.889809) (xy 100.33635 -246.914416)
			(xy 100.665292 -246.914416) (xy 100.669252 -246.865362) (xy 100.681029 -246.817578) (xy 100.70032 -246.772302)
			(xy 100.726623 -246.730706) (xy 100.759258 -246.693869) (xy 100.797379 -246.662744) (xy 100.84 -246.638137)
			(xy 100.886016 -246.620685) (xy 100.934235 -246.610841) (xy 100.98341 -246.60886) (xy 101.032265 -246.614792)
			(xy 101.079536 -246.628484) (xy 101.123998 -246.649582) (xy 101.164501 -246.677538) (xy 101.199994 -246.71163)
			(xy 101.229559 -246.750974) (xy 101.25243 -246.794551) (xy 101.268014 -246.841232) (xy 101.275909 -246.889809)
			(xy 101.276404 -246.914416) (xy 101.605346 -246.914416) (xy 101.609306 -246.865362) (xy 101.621083 -246.817578)
			(xy 101.640374 -246.772302) (xy 101.666677 -246.730706) (xy 101.699312 -246.693869) (xy 101.737433 -246.662744)
			(xy 101.780054 -246.638137) (xy 101.82607 -246.620685) (xy 101.874289 -246.610841) (xy 101.923464 -246.60886)
			(xy 101.972319 -246.614792) (xy 102.01959 -246.628484) (xy 102.064052 -246.649582) (xy 102.104555 -246.677538)
			(xy 102.140048 -246.71163) (xy 102.169613 -246.750974) (xy 102.192484 -246.794551) (xy 102.208068 -246.841232)
			(xy 102.215963 -246.889809) (xy 102.216458 -246.914416) (xy 102.545146 -246.914416) (xy 102.549106 -246.865362)
			(xy 102.560883 -246.817578) (xy 102.580174 -246.772302) (xy 102.606477 -246.730706) (xy 102.639112 -246.693869)
			(xy 102.677233 -246.662744) (xy 102.719854 -246.638137) (xy 102.76587 -246.620685) (xy 102.814089 -246.610841)
			(xy 102.863264 -246.60886) (xy 102.912119 -246.614792) (xy 102.95939 -246.628484) (xy 103.003852 -246.649582)
			(xy 103.044355 -246.677538) (xy 103.079848 -246.71163) (xy 103.109413 -246.750974) (xy 103.132284 -246.794551)
			(xy 103.147868 -246.841232) (xy 103.155763 -246.889809) (xy 103.156258 -246.914416) (xy 103.4852 -246.914416)
			(xy 103.48916 -246.865362) (xy 103.500937 -246.817578) (xy 103.520228 -246.772302) (xy 103.546531 -246.730706)
			(xy 103.579166 -246.693869) (xy 103.617287 -246.662744) (xy 103.659908 -246.638137) (xy 103.705924 -246.620685)
			(xy 103.754143 -246.610841) (xy 103.803318 -246.60886) (xy 103.852173 -246.614792) (xy 103.899444 -246.628484)
			(xy 103.943906 -246.649582) (xy 103.984409 -246.677538) (xy 104.019902 -246.71163) (xy 104.049467 -246.750974)
			(xy 104.072338 -246.794551) (xy 104.087922 -246.841232) (xy 104.095817 -246.889809) (xy 104.096312 -246.914416)
			(xy 104.425254 -246.914416) (xy 104.429214 -246.865362) (xy 104.440991 -246.817578) (xy 104.460282 -246.772302)
			(xy 104.486585 -246.730706) (xy 104.51922 -246.693869) (xy 104.557341 -246.662744) (xy 104.599962 -246.638137)
			(xy 104.645978 -246.620685) (xy 104.694197 -246.610841) (xy 104.743372 -246.60886) (xy 104.792227 -246.614792)
			(xy 104.839498 -246.628484) (xy 104.88396 -246.649582) (xy 104.924463 -246.677538) (xy 104.959956 -246.71163)
			(xy 104.989521 -246.750974) (xy 105.012392 -246.794551) (xy 105.027976 -246.841232) (xy 105.035871 -246.889809)
			(xy 105.036366 -246.914416) (xy 105.365308 -246.914416) (xy 105.369268 -246.865362) (xy 105.381045 -246.817578)
			(xy 105.400336 -246.772302) (xy 105.426639 -246.730706) (xy 105.459274 -246.693869) (xy 105.497395 -246.662744)
			(xy 105.540016 -246.638137) (xy 105.586032 -246.620685) (xy 105.634251 -246.610841) (xy 105.683426 -246.60886)
			(xy 105.732281 -246.614792) (xy 105.779552 -246.628484) (xy 105.824014 -246.649582) (xy 105.864517 -246.677538)
			(xy 105.90001 -246.71163) (xy 105.929575 -246.750974) (xy 105.952446 -246.794551) (xy 105.96803 -246.841232)
			(xy 105.975925 -246.889809) (xy 105.97642 -246.914416) (xy 106.305362 -246.914416) (xy 106.309322 -246.865362)
			(xy 106.321099 -246.817578) (xy 106.34039 -246.772302) (xy 106.366693 -246.730706) (xy 106.399328 -246.693869)
			(xy 106.437449 -246.662744) (xy 106.48007 -246.638137) (xy 106.526086 -246.620685) (xy 106.574305 -246.610841)
			(xy 106.62348 -246.60886) (xy 106.672335 -246.614792) (xy 106.719606 -246.628484) (xy 106.764068 -246.649582)
			(xy 106.804571 -246.677538) (xy 106.840064 -246.71163) (xy 106.869629 -246.750974) (xy 106.8925 -246.794551)
			(xy 106.908084 -246.841232) (xy 106.915979 -246.889809) (xy 106.916474 -246.914416) (xy 107.245162 -246.914416)
			(xy 107.249122 -246.865362) (xy 107.260899 -246.817578) (xy 107.28019 -246.772302) (xy 107.306493 -246.730706)
			(xy 107.339128 -246.693869) (xy 107.377249 -246.662744) (xy 107.41987 -246.638137) (xy 107.465886 -246.620685)
			(xy 107.514105 -246.610841) (xy 107.56328 -246.60886) (xy 107.612135 -246.614792) (xy 107.659406 -246.628484)
			(xy 107.703868 -246.649582) (xy 107.744371 -246.677538) (xy 107.779864 -246.71163) (xy 107.809429 -246.750974)
			(xy 107.8323 -246.794551) (xy 107.847884 -246.841232) (xy 107.855779 -246.889809) (xy 107.856274 -246.9144)
			(xy 108.185156 -246.9144) (xy 108.189328 -246.864058) (xy 108.201729 -246.815089) (xy 108.222021 -246.768829)
			(xy 108.249651 -246.72654) (xy 108.283865 -246.689376) (xy 108.32373 -246.658351) (xy 108.368157 -246.63431)
			(xy 108.415936 -246.617911) (xy 108.465763 -246.609599) (xy 108.49102 -246.609108) (xy 109.431074 -246.609108)
			(xy 109.456334 -246.609567) (xy 109.506167 -246.617878) (xy 109.553951 -246.634279) (xy 109.598385 -246.658322)
			(xy 109.638254 -246.68935) (xy 109.672472 -246.726518) (xy 109.700106 -246.768812) (xy 109.720401 -246.815077)
			(xy 109.732804 -246.864052) (xy 109.736976 -246.9144) (xy 109.736975 -246.914416) (xy 110.065324 -246.914416)
			(xy 110.069284 -246.865362) (xy 110.081061 -246.817578) (xy 110.100352 -246.772302) (xy 110.126655 -246.730706)
			(xy 110.15929 -246.693869) (xy 110.197411 -246.662744) (xy 110.240032 -246.638137) (xy 110.286048 -246.620685)
			(xy 110.334267 -246.610841) (xy 110.383442 -246.60886) (xy 110.432297 -246.614792) (xy 110.479568 -246.628484)
			(xy 110.52403 -246.649582) (xy 110.564533 -246.677538) (xy 110.600026 -246.71163) (xy 110.629591 -246.750974)
			(xy 110.652462 -246.794551) (xy 110.668046 -246.841232) (xy 110.675941 -246.889809) (xy 110.676436 -246.914416)
			(xy 112.878882 -246.914416) (xy 112.882842 -246.865362) (xy 112.894619 -246.817578) (xy 112.91391 -246.772302)
			(xy 112.940213 -246.730706) (xy 112.972848 -246.693869) (xy 113.010969 -246.662744) (xy 113.05359 -246.638137)
			(xy 113.099606 -246.620685) (xy 113.147825 -246.610841) (xy 113.197 -246.60886) (xy 113.245855 -246.614792)
			(xy 113.293126 -246.628484) (xy 113.337588 -246.649582) (xy 113.378091 -246.677538) (xy 113.413584 -246.71163)
			(xy 113.443149 -246.750974) (xy 113.46602 -246.794551) (xy 113.481604 -246.841232) (xy 113.489499 -246.889809)
			(xy 113.489994 -246.914416) (xy 113.818936 -246.914416) (xy 113.822896 -246.865362) (xy 113.834673 -246.817578)
			(xy 113.853964 -246.772302) (xy 113.880267 -246.730706) (xy 113.912902 -246.693869) (xy 113.951023 -246.662744)
			(xy 113.993644 -246.638137) (xy 114.03966 -246.620685) (xy 114.087879 -246.610841) (xy 114.137054 -246.60886)
			(xy 114.185909 -246.614792) (xy 114.23318 -246.628484) (xy 114.277642 -246.649582) (xy 114.318145 -246.677538)
			(xy 114.353638 -246.71163) (xy 114.383203 -246.750974) (xy 114.406074 -246.794551) (xy 114.421658 -246.841232)
			(xy 114.429553 -246.889809) (xy 114.430048 -246.914416) (xy 114.75899 -246.914416) (xy 114.76295 -246.865362)
			(xy 114.774727 -246.817578) (xy 114.794018 -246.772302) (xy 114.820321 -246.730706) (xy 114.852956 -246.693869)
			(xy 114.891077 -246.662744) (xy 114.933698 -246.638137) (xy 114.979714 -246.620685) (xy 115.027933 -246.610841)
			(xy 115.077108 -246.60886) (xy 115.125963 -246.614792) (xy 115.173234 -246.628484) (xy 115.217696 -246.649582)
			(xy 115.258199 -246.677538) (xy 115.293692 -246.71163) (xy 115.323257 -246.750974) (xy 115.346128 -246.794551)
			(xy 115.361712 -246.841232) (xy 115.369607 -246.889809) (xy 115.370102 -246.914416) (xy 115.699044 -246.914416)
			(xy 115.703004 -246.865362) (xy 115.714781 -246.817578) (xy 115.734072 -246.772302) (xy 115.760375 -246.730706)
			(xy 115.79301 -246.693869) (xy 115.831131 -246.662744) (xy 115.873752 -246.638137) (xy 115.919768 -246.620685)
			(xy 115.967987 -246.610841) (xy 116.017162 -246.60886) (xy 116.066017 -246.614792) (xy 116.113288 -246.628484)
			(xy 116.15775 -246.649582) (xy 116.198253 -246.677538) (xy 116.233746 -246.71163) (xy 116.263311 -246.750974)
			(xy 116.286182 -246.794551) (xy 116.301766 -246.841232) (xy 116.309661 -246.889809) (xy 116.310156 -246.914416)
			(xy 116.638844 -246.914416) (xy 116.642804 -246.865362) (xy 116.654581 -246.817578) (xy 116.673872 -246.772302)
			(xy 116.700175 -246.730706) (xy 116.73281 -246.693869) (xy 116.770931 -246.662744) (xy 116.813552 -246.638137)
			(xy 116.859568 -246.620685) (xy 116.907787 -246.610841) (xy 116.956962 -246.60886) (xy 117.005817 -246.614792)
			(xy 117.053088 -246.628484) (xy 117.09755 -246.649582) (xy 117.138053 -246.677538) (xy 117.173546 -246.71163)
			(xy 117.203111 -246.750974) (xy 117.225982 -246.794551) (xy 117.241566 -246.841232) (xy 117.249461 -246.889809)
			(xy 117.249956 -246.914416) (xy 117.578898 -246.914416) (xy 117.582858 -246.865362) (xy 117.594635 -246.817578)
			(xy 117.613926 -246.772302) (xy 117.640229 -246.730706) (xy 117.672864 -246.693869) (xy 117.710985 -246.662744)
			(xy 117.753606 -246.638137) (xy 117.799622 -246.620685) (xy 117.847841 -246.610841) (xy 117.897016 -246.60886)
			(xy 117.945871 -246.614792) (xy 117.993142 -246.628484) (xy 118.037604 -246.649582) (xy 118.078107 -246.677538)
			(xy 118.1136 -246.71163) (xy 118.143165 -246.750974) (xy 118.166036 -246.794551) (xy 118.18162 -246.841232)
			(xy 118.189515 -246.889809) (xy 118.19001 -246.914416) (xy 118.518952 -246.914416) (xy 118.522912 -246.865362)
			(xy 118.534689 -246.817578) (xy 118.55398 -246.772302) (xy 118.580283 -246.730706) (xy 118.612918 -246.693869)
			(xy 118.651039 -246.662744) (xy 118.69366 -246.638137) (xy 118.739676 -246.620685) (xy 118.787895 -246.610841)
			(xy 118.83707 -246.60886) (xy 118.885925 -246.614792) (xy 118.933196 -246.628484) (xy 118.977658 -246.649582)
			(xy 119.018161 -246.677538) (xy 119.053654 -246.71163) (xy 119.083219 -246.750974) (xy 119.10609 -246.794551)
			(xy 119.121674 -246.841232) (xy 119.129569 -246.889809) (xy 119.130064 -246.914416) (xy 119.459006 -246.914416)
			(xy 119.462966 -246.865362) (xy 119.474743 -246.817578) (xy 119.494034 -246.772302) (xy 119.520337 -246.730706)
			(xy 119.552972 -246.693869) (xy 119.591093 -246.662744) (xy 119.633714 -246.638137) (xy 119.67973 -246.620685)
			(xy 119.727949 -246.610841) (xy 119.777124 -246.60886) (xy 119.825979 -246.614792) (xy 119.87325 -246.628484)
			(xy 119.917712 -246.649582) (xy 119.958215 -246.677538) (xy 119.993708 -246.71163) (xy 120.023273 -246.750974)
			(xy 120.046144 -246.794551) (xy 120.061728 -246.841232) (xy 120.069623 -246.889809) (xy 120.070118 -246.914416)
			(xy 120.398806 -246.914416) (xy 120.402766 -246.865362) (xy 120.414543 -246.817578) (xy 120.433834 -246.772302)
			(xy 120.460137 -246.730706) (xy 120.492772 -246.693869) (xy 120.530893 -246.662744) (xy 120.573514 -246.638137)
			(xy 120.61953 -246.620685) (xy 120.667749 -246.610841) (xy 120.716924 -246.60886) (xy 120.765779 -246.614792)
			(xy 120.81305 -246.628484) (xy 120.857512 -246.649582) (xy 120.898015 -246.677538) (xy 120.933508 -246.71163)
			(xy 120.963073 -246.750974) (xy 120.985944 -246.794551) (xy 121.001528 -246.841232) (xy 121.009423 -246.889809)
			(xy 121.009918 -246.914416) (xy 121.33886 -246.914416) (xy 121.34282 -246.865362) (xy 121.354597 -246.817578)
			(xy 121.373888 -246.772302) (xy 121.400191 -246.730706) (xy 121.432826 -246.693869) (xy 121.470947 -246.662744)
			(xy 121.513568 -246.638137) (xy 121.559584 -246.620685) (xy 121.607803 -246.610841) (xy 121.656978 -246.60886)
			(xy 121.705833 -246.614792) (xy 121.753104 -246.628484) (xy 121.797566 -246.649582) (xy 121.838069 -246.677538)
			(xy 121.873562 -246.71163) (xy 121.903127 -246.750974) (xy 121.925998 -246.794551) (xy 121.941582 -246.841232)
			(xy 121.949477 -246.889809) (xy 121.949972 -246.914416) (xy 122.278914 -246.914416) (xy 122.282874 -246.865362)
			(xy 122.294651 -246.817578) (xy 122.313942 -246.772302) (xy 122.340245 -246.730706) (xy 122.37288 -246.693869)
			(xy 122.411001 -246.662744) (xy 122.453622 -246.638137) (xy 122.499638 -246.620685) (xy 122.547857 -246.610841)
			(xy 122.597032 -246.60886) (xy 122.645887 -246.614792) (xy 122.693158 -246.628484) (xy 122.73762 -246.649582)
			(xy 122.778123 -246.677538) (xy 122.813616 -246.71163) (xy 122.843181 -246.750974) (xy 122.866052 -246.794551)
			(xy 122.881636 -246.841232) (xy 122.889531 -246.889809) (xy 122.890026 -246.914416) (xy 123.218968 -246.914416)
			(xy 123.222928 -246.865362) (xy 123.234705 -246.817578) (xy 123.253996 -246.772302) (xy 123.280299 -246.730706)
			(xy 123.312934 -246.693869) (xy 123.351055 -246.662744) (xy 123.393676 -246.638137) (xy 123.439692 -246.620685)
			(xy 123.487911 -246.610841) (xy 123.537086 -246.60886) (xy 123.585941 -246.614792) (xy 123.633212 -246.628484)
			(xy 123.677674 -246.649582) (xy 123.718177 -246.677538) (xy 123.75367 -246.71163) (xy 123.783235 -246.750974)
			(xy 123.806106 -246.794551) (xy 123.82169 -246.841232) (xy 123.829585 -246.889809) (xy 123.83008 -246.914416)
			(xy 124.159022 -246.914416) (xy 124.162982 -246.865362) (xy 124.174759 -246.817578) (xy 124.19405 -246.772302)
			(xy 124.220353 -246.730706) (xy 124.252988 -246.693869) (xy 124.291109 -246.662744) (xy 124.33373 -246.638137)
			(xy 124.379746 -246.620685) (xy 124.427965 -246.610841) (xy 124.47714 -246.60886) (xy 124.525995 -246.614792)
			(xy 124.573266 -246.628484) (xy 124.617728 -246.649582) (xy 124.658231 -246.677538) (xy 124.693724 -246.71163)
			(xy 124.723289 -246.750974) (xy 124.74616 -246.794551) (xy 124.761744 -246.841232) (xy 124.769639 -246.889809)
			(xy 124.770134 -246.914416) (xy 125.098822 -246.914416) (xy 125.102782 -246.865362) (xy 125.114559 -246.817578)
			(xy 125.13385 -246.772302) (xy 125.160153 -246.730706) (xy 125.192788 -246.693869) (xy 125.230909 -246.662744)
			(xy 125.27353 -246.638137) (xy 125.319546 -246.620685) (xy 125.367765 -246.610841) (xy 125.41694 -246.60886)
			(xy 125.465795 -246.614792) (xy 125.513066 -246.628484) (xy 125.557528 -246.649582) (xy 125.598031 -246.677538)
			(xy 125.633524 -246.71163) (xy 125.663089 -246.750974) (xy 125.68596 -246.794551) (xy 125.701544 -246.841232)
			(xy 125.709439 -246.889809) (xy 125.709934 -246.914416) (xy 126.038876 -246.914416) (xy 126.042836 -246.865362)
			(xy 126.054613 -246.817578) (xy 126.073904 -246.772302) (xy 126.100207 -246.730706) (xy 126.132842 -246.693869)
			(xy 126.170963 -246.662744) (xy 126.213584 -246.638137) (xy 126.2596 -246.620685) (xy 126.307819 -246.610841)
			(xy 126.356994 -246.60886) (xy 126.405849 -246.614792) (xy 126.45312 -246.628484) (xy 126.497582 -246.649582)
			(xy 126.538085 -246.677538) (xy 126.573578 -246.71163) (xy 126.603143 -246.750974) (xy 126.626014 -246.794551)
			(xy 126.641598 -246.841232) (xy 126.649493 -246.889809) (xy 126.649988 -246.914416) (xy 126.649493 -246.939023)
			(xy 126.641598 -246.9876) (xy 126.626014 -247.034281) (xy 126.603143 -247.077858) (xy 126.573578 -247.117202)
			(xy 126.538085 -247.151294) (xy 126.497582 -247.17925) (xy 126.45312 -247.200348) (xy 126.405849 -247.21404)
			(xy 126.356994 -247.219972) (xy 126.307819 -247.217991) (xy 126.2596 -247.208147) (xy 126.213584 -247.190695)
			(xy 126.170963 -247.166088) (xy 126.132842 -247.134963) (xy 126.100207 -247.098126) (xy 126.073904 -247.05653)
			(xy 126.054613 -247.011254) (xy 126.042836 -246.96347) (xy 126.038876 -246.914416) (xy 125.709934 -246.914416)
			(xy 125.709439 -246.939023) (xy 125.701544 -246.9876) (xy 125.68596 -247.034281) (xy 125.663089 -247.077858)
			(xy 125.633524 -247.117202) (xy 125.598031 -247.151294) (xy 125.557528 -247.17925) (xy 125.513066 -247.200348)
			(xy 125.465795 -247.21404) (xy 125.41694 -247.219972) (xy 125.367765 -247.217991) (xy 125.319546 -247.208147)
			(xy 125.27353 -247.190695) (xy 125.230909 -247.166088) (xy 125.192788 -247.134963) (xy 125.160153 -247.098126)
			(xy 125.13385 -247.05653) (xy 125.114559 -247.011254) (xy 125.102782 -246.96347) (xy 125.098822 -246.914416)
			(xy 124.770134 -246.914416) (xy 124.769639 -246.939023) (xy 124.761744 -246.9876) (xy 124.74616 -247.034281)
			(xy 124.723289 -247.077858) (xy 124.693724 -247.117202) (xy 124.658231 -247.151294) (xy 124.617728 -247.17925)
			(xy 124.573266 -247.200348) (xy 124.525995 -247.21404) (xy 124.47714 -247.219972) (xy 124.427965 -247.217991)
			(xy 124.379746 -247.208147) (xy 124.33373 -247.190695) (xy 124.291109 -247.166088) (xy 124.252988 -247.134963)
			(xy 124.220353 -247.098126) (xy 124.19405 -247.05653) (xy 124.174759 -247.011254) (xy 124.162982 -246.96347)
			(xy 124.159022 -246.914416) (xy 123.83008 -246.914416) (xy 123.829585 -246.939023) (xy 123.82169 -246.9876)
			(xy 123.806106 -247.034281) (xy 123.783235 -247.077858) (xy 123.75367 -247.117202) (xy 123.718177 -247.151294)
			(xy 123.677674 -247.17925) (xy 123.633212 -247.200348) (xy 123.585941 -247.21404) (xy 123.537086 -247.219972)
			(xy 123.487911 -247.217991) (xy 123.439692 -247.208147) (xy 123.393676 -247.190695) (xy 123.351055 -247.166088)
			(xy 123.312934 -247.134963) (xy 123.280299 -247.098126) (xy 123.253996 -247.05653) (xy 123.234705 -247.011254)
			(xy 123.222928 -246.96347) (xy 123.218968 -246.914416) (xy 122.890026 -246.914416) (xy 122.889531 -246.939023)
			(xy 122.881636 -246.9876) (xy 122.866052 -247.034281) (xy 122.843181 -247.077858) (xy 122.813616 -247.117202)
			(xy 122.778123 -247.151294) (xy 122.73762 -247.17925) (xy 122.693158 -247.200348) (xy 122.645887 -247.21404)
			(xy 122.597032 -247.219972) (xy 122.547857 -247.217991) (xy 122.499638 -247.208147) (xy 122.453622 -247.190695)
			(xy 122.411001 -247.166088) (xy 122.37288 -247.134963) (xy 122.340245 -247.098126) (xy 122.313942 -247.05653)
			(xy 122.294651 -247.011254) (xy 122.282874 -246.96347) (xy 122.278914 -246.914416) (xy 121.949972 -246.914416)
			(xy 121.949477 -246.939023) (xy 121.941582 -246.9876) (xy 121.925998 -247.034281) (xy 121.903127 -247.077858)
			(xy 121.873562 -247.117202) (xy 121.838069 -247.151294) (xy 121.797566 -247.17925) (xy 121.753104 -247.200348)
			(xy 121.705833 -247.21404) (xy 121.656978 -247.219972) (xy 121.607803 -247.217991) (xy 121.559584 -247.208147)
			(xy 121.513568 -247.190695) (xy 121.470947 -247.166088) (xy 121.432826 -247.134963) (xy 121.400191 -247.098126)
			(xy 121.373888 -247.05653) (xy 121.354597 -247.011254) (xy 121.34282 -246.96347) (xy 121.33886 -246.914416)
			(xy 121.009918 -246.914416) (xy 121.009423 -246.939023) (xy 121.001528 -246.9876) (xy 120.985944 -247.034281)
			(xy 120.963073 -247.077858) (xy 120.933508 -247.117202) (xy 120.898015 -247.151294) (xy 120.857512 -247.17925)
			(xy 120.81305 -247.200348) (xy 120.765779 -247.21404) (xy 120.716924 -247.219972) (xy 120.667749 -247.217991)
			(xy 120.61953 -247.208147) (xy 120.573514 -247.190695) (xy 120.530893 -247.166088) (xy 120.492772 -247.134963)
			(xy 120.460137 -247.098126) (xy 120.433834 -247.05653) (xy 120.414543 -247.011254) (xy 120.402766 -246.96347)
			(xy 120.398806 -246.914416) (xy 120.070118 -246.914416) (xy 120.069623 -246.939023) (xy 120.061728 -246.9876)
			(xy 120.046144 -247.034281) (xy 120.023273 -247.077858) (xy 119.993708 -247.117202) (xy 119.958215 -247.151294)
			(xy 119.917712 -247.17925) (xy 119.87325 -247.200348) (xy 119.825979 -247.21404) (xy 119.777124 -247.219972)
			(xy 119.727949 -247.217991) (xy 119.67973 -247.208147) (xy 119.633714 -247.190695) (xy 119.591093 -247.166088)
			(xy 119.552972 -247.134963) (xy 119.520337 -247.098126) (xy 119.494034 -247.05653) (xy 119.474743 -247.011254)
			(xy 119.462966 -246.96347) (xy 119.459006 -246.914416) (xy 119.130064 -246.914416) (xy 119.129569 -246.939023)
			(xy 119.121674 -246.9876) (xy 119.10609 -247.034281) (xy 119.083219 -247.077858) (xy 119.053654 -247.117202)
			(xy 119.018161 -247.151294) (xy 118.977658 -247.17925) (xy 118.933196 -247.200348) (xy 118.885925 -247.21404)
			(xy 118.83707 -247.219972) (xy 118.787895 -247.217991) (xy 118.739676 -247.208147) (xy 118.69366 -247.190695)
			(xy 118.651039 -247.166088) (xy 118.612918 -247.134963) (xy 118.580283 -247.098126) (xy 118.55398 -247.05653)
			(xy 118.534689 -247.011254) (xy 118.522912 -246.96347) (xy 118.518952 -246.914416) (xy 118.19001 -246.914416)
			(xy 118.189515 -246.939023) (xy 118.18162 -246.9876) (xy 118.166036 -247.034281) (xy 118.143165 -247.077858)
			(xy 118.1136 -247.117202) (xy 118.078107 -247.151294) (xy 118.037604 -247.17925) (xy 117.993142 -247.200348)
			(xy 117.945871 -247.21404) (xy 117.897016 -247.219972) (xy 117.847841 -247.217991) (xy 117.799622 -247.208147)
			(xy 117.753606 -247.190695) (xy 117.710985 -247.166088) (xy 117.672864 -247.134963) (xy 117.640229 -247.098126)
			(xy 117.613926 -247.05653) (xy 117.594635 -247.011254) (xy 117.582858 -246.96347) (xy 117.578898 -246.914416)
			(xy 117.249956 -246.914416) (xy 117.249461 -246.939023) (xy 117.241566 -246.9876) (xy 117.225982 -247.034281)
			(xy 117.203111 -247.077858) (xy 117.173546 -247.117202) (xy 117.138053 -247.151294) (xy 117.09755 -247.17925)
			(xy 117.053088 -247.200348) (xy 117.005817 -247.21404) (xy 116.956962 -247.219972) (xy 116.907787 -247.217991)
			(xy 116.859568 -247.208147) (xy 116.813552 -247.190695) (xy 116.770931 -247.166088) (xy 116.73281 -247.134963)
			(xy 116.700175 -247.098126) (xy 116.673872 -247.05653) (xy 116.654581 -247.011254) (xy 116.642804 -246.96347)
			(xy 116.638844 -246.914416) (xy 116.310156 -246.914416) (xy 116.309661 -246.939023) (xy 116.301766 -246.9876)
			(xy 116.286182 -247.034281) (xy 116.263311 -247.077858) (xy 116.233746 -247.117202) (xy 116.198253 -247.151294)
			(xy 116.15775 -247.17925) (xy 116.113288 -247.200348) (xy 116.066017 -247.21404) (xy 116.017162 -247.219972)
			(xy 115.967987 -247.217991) (xy 115.919768 -247.208147) (xy 115.873752 -247.190695) (xy 115.831131 -247.166088)
			(xy 115.79301 -247.134963) (xy 115.760375 -247.098126) (xy 115.734072 -247.05653) (xy 115.714781 -247.011254)
			(xy 115.703004 -246.96347) (xy 115.699044 -246.914416) (xy 115.370102 -246.914416) (xy 115.369607 -246.939023)
			(xy 115.361712 -246.9876) (xy 115.346128 -247.034281) (xy 115.323257 -247.077858) (xy 115.293692 -247.117202)
			(xy 115.258199 -247.151294) (xy 115.217696 -247.17925) (xy 115.173234 -247.200348) (xy 115.125963 -247.21404)
			(xy 115.077108 -247.219972) (xy 115.027933 -247.217991) (xy 114.979714 -247.208147) (xy 114.933698 -247.190695)
			(xy 114.891077 -247.166088) (xy 114.852956 -247.134963) (xy 114.820321 -247.098126) (xy 114.794018 -247.05653)
			(xy 114.774727 -247.011254) (xy 114.76295 -246.96347) (xy 114.75899 -246.914416) (xy 114.430048 -246.914416)
			(xy 114.429553 -246.939023) (xy 114.421658 -246.9876) (xy 114.406074 -247.034281) (xy 114.383203 -247.077858)
			(xy 114.353638 -247.117202) (xy 114.318145 -247.151294) (xy 114.277642 -247.17925) (xy 114.23318 -247.200348)
			(xy 114.185909 -247.21404) (xy 114.137054 -247.219972) (xy 114.087879 -247.217991) (xy 114.03966 -247.208147)
			(xy 113.993644 -247.190695) (xy 113.951023 -247.166088) (xy 113.912902 -247.134963) (xy 113.880267 -247.098126)
			(xy 113.853964 -247.05653) (xy 113.834673 -247.011254) (xy 113.822896 -246.96347) (xy 113.818936 -246.914416)
			(xy 113.489994 -246.914416) (xy 113.489499 -246.939023) (xy 113.481604 -246.9876) (xy 113.46602 -247.034281)
			(xy 113.443149 -247.077858) (xy 113.413584 -247.117202) (xy 113.378091 -247.151294) (xy 113.337588 -247.17925)
			(xy 113.293126 -247.200348) (xy 113.245855 -247.21404) (xy 113.197 -247.219972) (xy 113.147825 -247.217991)
			(xy 113.099606 -247.208147) (xy 113.05359 -247.190695) (xy 113.010969 -247.166088) (xy 112.972848 -247.134963)
			(xy 112.940213 -247.098126) (xy 112.91391 -247.05653) (xy 112.894619 -247.011254) (xy 112.882842 -246.96347)
			(xy 112.878882 -246.914416) (xy 110.676436 -246.914416) (xy 110.675941 -246.939023) (xy 110.668046 -246.9876)
			(xy 110.652462 -247.034281) (xy 110.629591 -247.077858) (xy 110.600026 -247.117202) (xy 110.564533 -247.151294)
			(xy 110.52403 -247.17925) (xy 110.479568 -247.200348) (xy 110.432297 -247.21404) (xy 110.383442 -247.219972)
			(xy 110.334267 -247.217991) (xy 110.286048 -247.208147) (xy 110.240032 -247.190695) (xy 110.197411 -247.166088)
			(xy 110.15929 -247.134963) (xy 110.126655 -247.098126) (xy 110.100352 -247.05653) (xy 110.081061 -247.011254)
			(xy 110.069284 -246.96347) (xy 110.065324 -246.914416) (xy 109.736975 -246.914416) (xy 109.732804 -246.964748)
			(xy 109.720401 -247.013723) (xy 109.700106 -247.059988) (xy 109.672472 -247.102282) (xy 109.638254 -247.13945)
			(xy 109.598385 -247.170478) (xy 109.553951 -247.194521) (xy 109.506167 -247.210922) (xy 109.456334 -247.219233)
			(xy 109.431074 -247.219724) (xy 108.49102 -247.219724) (xy 108.465763 -247.219201) (xy 108.415936 -247.210889)
			(xy 108.368157 -247.19449) (xy 108.32373 -247.170449) (xy 108.283865 -247.139424) (xy 108.249651 -247.10226)
			(xy 108.222021 -247.059971) (xy 108.201729 -247.013711) (xy 108.189328 -246.964742) (xy 108.185156 -246.9144)
			(xy 107.856274 -246.9144) (xy 107.856274 -246.914416) (xy 107.855779 -246.939023) (xy 107.847884 -246.9876)
			(xy 107.8323 -247.034281) (xy 107.809429 -247.077858) (xy 107.779864 -247.117202) (xy 107.744371 -247.151294)
			(xy 107.703868 -247.17925) (xy 107.659406 -247.200348) (xy 107.612135 -247.21404) (xy 107.56328 -247.219972)
			(xy 107.514105 -247.217991) (xy 107.465886 -247.208147) (xy 107.41987 -247.190695) (xy 107.377249 -247.166088)
			(xy 107.339128 -247.134963) (xy 107.306493 -247.098126) (xy 107.28019 -247.05653) (xy 107.260899 -247.011254)
			(xy 107.249122 -246.96347) (xy 107.245162 -246.914416) (xy 106.916474 -246.914416) (xy 106.915979 -246.939023)
			(xy 106.908084 -246.9876) (xy 106.8925 -247.034281) (xy 106.869629 -247.077858) (xy 106.840064 -247.117202)
			(xy 106.804571 -247.151294) (xy 106.764068 -247.17925) (xy 106.719606 -247.200348) (xy 106.672335 -247.21404)
			(xy 106.62348 -247.219972) (xy 106.574305 -247.217991) (xy 106.526086 -247.208147) (xy 106.48007 -247.190695)
			(xy 106.437449 -247.166088) (xy 106.399328 -247.134963) (xy 106.366693 -247.098126) (xy 106.34039 -247.05653)
			(xy 106.321099 -247.011254) (xy 106.309322 -246.96347) (xy 106.305362 -246.914416) (xy 105.97642 -246.914416)
			(xy 105.975925 -246.939023) (xy 105.96803 -246.9876) (xy 105.952446 -247.034281) (xy 105.929575 -247.077858)
			(xy 105.90001 -247.117202) (xy 105.864517 -247.151294) (xy 105.824014 -247.17925) (xy 105.779552 -247.200348)
			(xy 105.732281 -247.21404) (xy 105.683426 -247.219972) (xy 105.634251 -247.217991) (xy 105.586032 -247.208147)
			(xy 105.540016 -247.190695) (xy 105.497395 -247.166088) (xy 105.459274 -247.134963) (xy 105.426639 -247.098126)
			(xy 105.400336 -247.05653) (xy 105.381045 -247.011254) (xy 105.369268 -246.96347) (xy 105.365308 -246.914416)
			(xy 105.036366 -246.914416) (xy 105.035871 -246.939023) (xy 105.027976 -246.9876) (xy 105.012392 -247.034281)
			(xy 104.989521 -247.077858) (xy 104.959956 -247.117202) (xy 104.924463 -247.151294) (xy 104.88396 -247.17925)
			(xy 104.839498 -247.200348) (xy 104.792227 -247.21404) (xy 104.743372 -247.219972) (xy 104.694197 -247.217991)
			(xy 104.645978 -247.208147) (xy 104.599962 -247.190695) (xy 104.557341 -247.166088) (xy 104.51922 -247.134963)
			(xy 104.486585 -247.098126) (xy 104.460282 -247.05653) (xy 104.440991 -247.011254) (xy 104.429214 -246.96347)
			(xy 104.425254 -246.914416) (xy 104.096312 -246.914416) (xy 104.095817 -246.939023) (xy 104.087922 -246.9876)
			(xy 104.072338 -247.034281) (xy 104.049467 -247.077858) (xy 104.019902 -247.117202) (xy 103.984409 -247.151294)
			(xy 103.943906 -247.17925) (xy 103.899444 -247.200348) (xy 103.852173 -247.21404) (xy 103.803318 -247.219972)
			(xy 103.754143 -247.217991) (xy 103.705924 -247.208147) (xy 103.659908 -247.190695) (xy 103.617287 -247.166088)
			(xy 103.579166 -247.134963) (xy 103.546531 -247.098126) (xy 103.520228 -247.05653) (xy 103.500937 -247.011254)
			(xy 103.48916 -246.96347) (xy 103.4852 -246.914416) (xy 103.156258 -246.914416) (xy 103.155763 -246.939023)
			(xy 103.147868 -246.9876) (xy 103.132284 -247.034281) (xy 103.109413 -247.077858) (xy 103.079848 -247.117202)
			(xy 103.044355 -247.151294) (xy 103.003852 -247.17925) (xy 102.95939 -247.200348) (xy 102.912119 -247.21404)
			(xy 102.863264 -247.219972) (xy 102.814089 -247.217991) (xy 102.76587 -247.208147) (xy 102.719854 -247.190695)
			(xy 102.677233 -247.166088) (xy 102.639112 -247.134963) (xy 102.606477 -247.098126) (xy 102.580174 -247.05653)
			(xy 102.560883 -247.011254) (xy 102.549106 -246.96347) (xy 102.545146 -246.914416) (xy 102.216458 -246.914416)
			(xy 102.215963 -246.939023) (xy 102.208068 -246.9876) (xy 102.192484 -247.034281) (xy 102.169613 -247.077858)
			(xy 102.140048 -247.117202) (xy 102.104555 -247.151294) (xy 102.064052 -247.17925) (xy 102.01959 -247.200348)
			(xy 101.972319 -247.21404) (xy 101.923464 -247.219972) (xy 101.874289 -247.217991) (xy 101.82607 -247.208147)
			(xy 101.780054 -247.190695) (xy 101.737433 -247.166088) (xy 101.699312 -247.134963) (xy 101.666677 -247.098126)
			(xy 101.640374 -247.05653) (xy 101.621083 -247.011254) (xy 101.609306 -246.96347) (xy 101.605346 -246.914416)
			(xy 101.276404 -246.914416) (xy 101.275909 -246.939023) (xy 101.268014 -246.9876) (xy 101.25243 -247.034281)
			(xy 101.229559 -247.077858) (xy 101.199994 -247.117202) (xy 101.164501 -247.151294) (xy 101.123998 -247.17925)
			(xy 101.079536 -247.200348) (xy 101.032265 -247.21404) (xy 100.98341 -247.219972) (xy 100.934235 -247.217991)
			(xy 100.886016 -247.208147) (xy 100.84 -247.190695) (xy 100.797379 -247.166088) (xy 100.759258 -247.134963)
			(xy 100.726623 -247.098126) (xy 100.70032 -247.05653) (xy 100.681029 -247.011254) (xy 100.669252 -246.96347)
			(xy 100.665292 -246.914416) (xy 100.33635 -246.914416) (xy 100.335855 -246.939023) (xy 100.32796 -246.9876)
			(xy 100.312376 -247.034281) (xy 100.289505 -247.077858) (xy 100.25994 -247.117202) (xy 100.224447 -247.151294)
			(xy 100.183944 -247.17925) (xy 100.139482 -247.200348) (xy 100.092211 -247.21404) (xy 100.043356 -247.219972)
			(xy 99.994181 -247.217991) (xy 99.945962 -247.208147) (xy 99.899946 -247.190695) (xy 99.857325 -247.166088)
			(xy 99.819204 -247.134963) (xy 99.786569 -247.098126) (xy 99.760266 -247.05653) (xy 99.740975 -247.011254)
			(xy 99.729198 -246.96347) (xy 99.725238 -246.914416) (xy 99.396296 -246.914416) (xy 99.395801 -246.939023)
			(xy 99.387906 -246.9876) (xy 99.372322 -247.034281) (xy 99.349451 -247.077858) (xy 99.319886 -247.117202)
			(xy 99.284393 -247.151294) (xy 99.24389 -247.17925) (xy 99.199428 -247.200348) (xy 99.152157 -247.21404)
			(xy 99.103302 -247.219972) (xy 99.054127 -247.217991) (xy 99.005908 -247.208147) (xy 98.959892 -247.190695)
			(xy 98.917271 -247.166088) (xy 98.87915 -247.134963) (xy 98.846515 -247.098126) (xy 98.820212 -247.05653)
			(xy 98.800921 -247.011254) (xy 98.789144 -246.96347) (xy 98.785184 -246.914416) (xy 98.456242 -246.914416)
			(xy 98.455747 -246.939023) (xy 98.447852 -246.9876) (xy 98.432268 -247.034281) (xy 98.409397 -247.077858)
			(xy 98.379832 -247.117202) (xy 98.344339 -247.151294) (xy 98.303836 -247.17925) (xy 98.259374 -247.200348)
			(xy 98.212103 -247.21404) (xy 98.163248 -247.219972) (xy 98.114073 -247.217991) (xy 98.065854 -247.208147)
			(xy 98.019838 -247.190695) (xy 97.977217 -247.166088) (xy 97.939096 -247.134963) (xy 97.906461 -247.098126)
			(xy 97.880158 -247.05653) (xy 97.860867 -247.011254) (xy 97.84909 -246.96347) (xy 97.84513 -246.914416)
			(xy 97.516442 -246.914416) (xy 97.515947 -246.939023) (xy 97.508052 -246.9876) (xy 97.492468 -247.034281)
			(xy 97.469597 -247.077858) (xy 97.440032 -247.117202) (xy 97.404539 -247.151294) (xy 97.364036 -247.17925)
			(xy 97.319574 -247.200348) (xy 97.272303 -247.21404) (xy 97.223448 -247.219972) (xy 97.174273 -247.217991)
			(xy 97.126054 -247.208147) (xy 97.080038 -247.190695) (xy 97.037417 -247.166088) (xy 96.999296 -247.134963)
			(xy 96.966661 -247.098126) (xy 96.940358 -247.05653) (xy 96.921067 -247.011254) (xy 96.90929 -246.96347)
			(xy 96.90533 -246.914416) (xy 96.575859 -246.914416) (xy 96.575869 -246.938366) (xy 96.568327 -246.985949)
			(xy 96.55341 -247.031759) (xy 96.531488 -247.07466) (xy 96.503104 -247.113589) (xy 96.468962 -247.14758)
			(xy 96.429909 -247.175792) (xy 96.386912 -247.197524) (xy 96.341037 -247.212239) (xy 96.317308 -247.216422)
			(xy 96.3168 -247.216422) (xy 96.316292 -247.216676) (xy 96.307527 -247.218338) (xy 96.291903 -247.226923)
			(xy 96.285812 -247.23344) (xy 96.280224 -247.23979) (xy 96.273874 -247.256808) (xy 96.273874 -247.411748)
			(xy 96.274062 -247.417982) (xy 96.277145 -247.430063) (xy 96.27997 -247.435624) (xy 96.284542 -247.443498)
			(xy 96.295086 -247.462099) (xy 96.313648 -247.500622) (xy 96.321626 -247.52046) (xy 96.323658 -247.52554)
			(xy 96.326452 -247.53316) (xy 96.33712 -247.541542) (xy 96.342594 -247.545504) (xy 96.355083 -247.550652)
			(xy 96.361758 -247.551702) (xy 96.448372 -247.563132) (xy 96.455111 -247.563716) (xy 96.468494 -247.561798)
			(xy 96.474788 -247.559322) (xy 96.48698 -247.554242) (xy 96.490536 -247.54967) (xy 96.495616 -247.542812)
			(xy 96.510121 -247.523984) (xy 96.543977 -247.490632) (xy 96.582591 -247.462927) (xy 96.625029 -247.441535)
			(xy 96.670269 -247.426974) (xy 96.717218 -247.419595) (xy 96.74098 -247.419114) (xy 96.766237 -247.419605)
			(xy 96.816062 -247.427916) (xy 96.86384 -247.444316) (xy 96.908267 -247.468356) (xy 96.948131 -247.499381)
			(xy 96.982344 -247.536544) (xy 97.009973 -247.578832) (xy 97.030265 -247.625091) (xy 97.042666 -247.674059)
			(xy 97.046838 -247.7244) (xy 97.374907 -247.7244) (xy 97.379083 -247.674015) (xy 97.391495 -247.625005)
			(xy 97.411805 -247.578707) (xy 97.439459 -247.536383) (xy 97.473702 -247.499188) (xy 97.513601 -247.468138)
			(xy 97.558067 -247.444079) (xy 97.605887 -247.427667) (xy 97.655755 -247.41935) (xy 97.681034 -247.41886)
			(xy 98.621088 -247.41886) (xy 98.646369 -247.419308) (xy 98.696242 -247.427629) (xy 98.744066 -247.444045)
			(xy 98.788534 -247.468109) (xy 98.828436 -247.499164) (xy 98.862682 -247.536363) (xy 98.890337 -247.578692)
			(xy 98.910648 -247.624995) (xy 98.923061 -247.67401) (xy 98.927237 -247.7244) (xy 98.927235 -247.724422)
			(xy 99.255338 -247.724422) (xy 99.259298 -247.675368) (xy 99.271075 -247.627584) (xy 99.290366 -247.582308)
			(xy 99.316669 -247.540712) (xy 99.349304 -247.503875) (xy 99.387425 -247.47275) (xy 99.430046 -247.448143)
			(xy 99.476062 -247.430691) (xy 99.524281 -247.420847) (xy 99.573456 -247.418866) (xy 99.622311 -247.424798)
			(xy 99.669582 -247.43849) (xy 99.714044 -247.459588) (xy 99.754547 -247.487544) (xy 99.79004 -247.521636)
			(xy 99.819605 -247.56098) (xy 99.842476 -247.604557) (xy 99.85806 -247.651238) (xy 99.865955 -247.699815)
			(xy 99.86645 -247.7244) (xy 100.194807 -247.7244) (xy 100.198983 -247.674014) (xy 100.211395 -247.625004)
			(xy 100.231706 -247.578704) (xy 100.259361 -247.53638) (xy 100.293605 -247.499185) (xy 100.333506 -247.468135)
			(xy 100.377972 -247.444076) (xy 100.425793 -247.427665) (xy 100.475663 -247.41935) (xy 100.500942 -247.41886)
			(xy 101.440996 -247.41886) (xy 101.466277 -247.419309) (xy 101.516149 -247.42763) (xy 101.563971 -247.444047)
			(xy 101.608439 -247.468111) (xy 101.648339 -247.499167) (xy 101.682584 -247.536366) (xy 101.710238 -247.578694)
			(xy 101.730549 -247.624997) (xy 101.742961 -247.674011) (xy 101.747137 -247.7244) (xy 101.747135 -247.724422)
			(xy 102.075246 -247.724422) (xy 102.079206 -247.675368) (xy 102.090983 -247.627584) (xy 102.110274 -247.582308)
			(xy 102.136577 -247.540712) (xy 102.169212 -247.503875) (xy 102.207333 -247.47275) (xy 102.249954 -247.448143)
			(xy 102.29597 -247.430691) (xy 102.344189 -247.420847) (xy 102.393364 -247.418866) (xy 102.442219 -247.424798)
			(xy 102.48949 -247.43849) (xy 102.533952 -247.459588) (xy 102.574455 -247.487544) (xy 102.609948 -247.521636)
			(xy 102.639513 -247.56098) (xy 102.662384 -247.604557) (xy 102.677968 -247.651238) (xy 102.685863 -247.699815)
			(xy 102.686358 -247.7244) (xy 103.015007 -247.7244) (xy 103.019182 -247.674018) (xy 103.031593 -247.625011)
			(xy 103.0519 -247.578715) (xy 103.079551 -247.536393) (xy 103.113791 -247.499199) (xy 103.153685 -247.468148)
			(xy 103.198147 -247.444087) (xy 103.245962 -247.427673) (xy 103.295827 -247.419353) (xy 103.321104 -247.41886)
			(xy 104.261158 -247.41886) (xy 104.286441 -247.419306) (xy 104.336318 -247.427622) (xy 104.384145 -247.444036)
			(xy 104.428619 -247.468098) (xy 104.468524 -247.499153) (xy 104.502774 -247.536353) (xy 104.530433 -247.578683)
			(xy 104.550746 -247.624989) (xy 104.56316 -247.674007) (xy 104.567337 -247.7244) (xy 104.567335 -247.724422)
			(xy 104.895154 -247.724422) (xy 104.899114 -247.675368) (xy 104.910891 -247.627584) (xy 104.930182 -247.582308)
			(xy 104.956485 -247.540712) (xy 104.98912 -247.503875) (xy 105.027241 -247.47275) (xy 105.069862 -247.448143)
			(xy 105.115878 -247.430691) (xy 105.164097 -247.420847) (xy 105.213272 -247.418866) (xy 105.262127 -247.424798)
			(xy 105.309398 -247.43849) (xy 105.35386 -247.459588) (xy 105.394363 -247.487544) (xy 105.429856 -247.521636)
			(xy 105.459421 -247.56098) (xy 105.482292 -247.604557) (xy 105.497876 -247.651238) (xy 105.505771 -247.699815)
			(xy 105.506266 -247.7244) (xy 105.834907 -247.7244) (xy 105.839082 -247.674018) (xy 105.851493 -247.62501)
			(xy 105.871801 -247.578713) (xy 105.899453 -247.53639) (xy 105.933694 -247.499196) (xy 105.97359 -247.468145)
			(xy 106.018052 -247.444085) (xy 106.065869 -247.427671) (xy 106.115734 -247.419352) (xy 106.141012 -247.41886)
			(xy 107.081066 -247.41886) (xy 107.106348 -247.419306) (xy 107.156224 -247.427624) (xy 107.204051 -247.444038)
			(xy 107.248523 -247.468101) (xy 107.288427 -247.499156) (xy 107.322676 -247.536356) (xy 107.350334 -247.578686)
			(xy 107.370647 -247.624991) (xy 107.383061 -247.674008) (xy 107.387237 -247.7244) (xy 107.387235 -247.724422)
			(xy 107.715316 -247.724422) (xy 107.719276 -247.675368) (xy 107.731053 -247.627584) (xy 107.750344 -247.582308)
			(xy 107.776647 -247.540712) (xy 107.809282 -247.503875) (xy 107.847403 -247.47275) (xy 107.890024 -247.448143)
			(xy 107.93604 -247.430691) (xy 107.984259 -247.420847) (xy 108.033434 -247.418866) (xy 108.082289 -247.424798)
			(xy 108.12956 -247.43849) (xy 108.174022 -247.459588) (xy 108.214525 -247.487544) (xy 108.250018 -247.521636)
			(xy 108.279583 -247.56098) (xy 108.302454 -247.604557) (xy 108.318038 -247.651238) (xy 108.325933 -247.699815)
			(xy 108.326428 -247.724422) (xy 108.65537 -247.724422) (xy 108.65933 -247.675368) (xy 108.671107 -247.627584)
			(xy 108.690398 -247.582308) (xy 108.716701 -247.540712) (xy 108.749336 -247.503875) (xy 108.787457 -247.47275)
			(xy 108.830078 -247.448143) (xy 108.876094 -247.430691) (xy 108.924313 -247.420847) (xy 108.973488 -247.418866)
			(xy 109.022343 -247.424798) (xy 109.069614 -247.43849) (xy 109.114076 -247.459588) (xy 109.154579 -247.487544)
			(xy 109.190072 -247.521636) (xy 109.219637 -247.56098) (xy 109.242508 -247.604557) (xy 109.258092 -247.651238)
			(xy 109.265987 -247.699815) (xy 109.266482 -247.724422) (xy 109.59517 -247.724422) (xy 109.59913 -247.675368)
			(xy 109.610907 -247.627584) (xy 109.630198 -247.582308) (xy 109.656501 -247.540712) (xy 109.689136 -247.503875)
			(xy 109.727257 -247.47275) (xy 109.769878 -247.448143) (xy 109.815894 -247.430691) (xy 109.864113 -247.420847)
			(xy 109.913288 -247.418866) (xy 109.962143 -247.424798) (xy 110.009414 -247.43849) (xy 110.048873 -247.457214)
			(xy 111.456473 -247.457214) (xy 111.460503 -247.404716) (xy 111.4725 -247.353448) (xy 111.492183 -247.304613)
			(xy 111.519089 -247.259354) (xy 111.552589 -247.218733) (xy 111.591897 -247.183702) (xy 111.636092 -247.155082)
			(xy 111.684137 -247.133543) (xy 111.734908 -247.119591) (xy 111.787213 -247.113553) (xy 111.839827 -247.11557)
			(xy 111.891517 -247.125594) (xy 111.94107 -247.143392) (xy 111.987326 -247.168545) (xy 112.0292 -247.200464)
			(xy 112.065712 -247.238402) (xy 112.096004 -247.281468) (xy 112.119367 -247.328653) (xy 112.135253 -247.378852)
			(xy 112.14329 -247.430888) (xy 112.143794 -247.457214) (xy 112.14329 -247.48354) (xy 112.135253 -247.535576)
			(xy 112.119367 -247.585775) (xy 112.096004 -247.63296) (xy 112.065712 -247.676026) (xy 112.0292 -247.713964)
			(xy 112.01548 -247.724422) (xy 113.349036 -247.724422) (xy 113.352996 -247.675368) (xy 113.364773 -247.627584)
			(xy 113.384064 -247.582308) (xy 113.410367 -247.540712) (xy 113.443002 -247.503875) (xy 113.481123 -247.47275)
			(xy 113.523744 -247.448143) (xy 113.56976 -247.430691) (xy 113.617979 -247.420847) (xy 113.667154 -247.418866)
			(xy 113.716009 -247.424798) (xy 113.76328 -247.43849) (xy 113.807742 -247.459588) (xy 113.848245 -247.487544)
			(xy 113.883738 -247.521636) (xy 113.913303 -247.56098) (xy 113.936174 -247.604557) (xy 113.951758 -247.651238)
			(xy 113.959653 -247.699815) (xy 113.960148 -247.724422) (xy 114.288836 -247.724422) (xy 114.292796 -247.675368)
			(xy 114.304573 -247.627584) (xy 114.323864 -247.582308) (xy 114.350167 -247.540712) (xy 114.382802 -247.503875)
			(xy 114.420923 -247.47275) (xy 114.463544 -247.448143) (xy 114.50956 -247.430691) (xy 114.557779 -247.420847)
			(xy 114.606954 -247.418866) (xy 114.655809 -247.424798) (xy 114.70308 -247.43849) (xy 114.747542 -247.459588)
			(xy 114.788045 -247.487544) (xy 114.823538 -247.521636) (xy 114.853103 -247.56098) (xy 114.875974 -247.604557)
			(xy 114.891558 -247.651238) (xy 114.899453 -247.699815) (xy 114.899948 -247.724422) (xy 115.22889 -247.724422)
			(xy 115.23285 -247.675368) (xy 115.244627 -247.627584) (xy 115.263918 -247.582308) (xy 115.290221 -247.540712)
			(xy 115.322856 -247.503875) (xy 115.360977 -247.47275) (xy 115.403598 -247.448143) (xy 115.449614 -247.430691)
			(xy 115.497833 -247.420847) (xy 115.547008 -247.418866) (xy 115.595863 -247.424798) (xy 115.643134 -247.43849)
			(xy 115.687596 -247.459588) (xy 115.728099 -247.487544) (xy 115.763592 -247.521636) (xy 115.793157 -247.56098)
			(xy 115.816028 -247.604557) (xy 115.831612 -247.651238) (xy 115.839507 -247.699815) (xy 115.840002 -247.724422)
			(xy 116.168944 -247.724422) (xy 116.172904 -247.675368) (xy 116.184681 -247.627584) (xy 116.203972 -247.582308)
			(xy 116.230275 -247.540712) (xy 116.26291 -247.503875) (xy 116.301031 -247.47275) (xy 116.343652 -247.448143)
			(xy 116.389668 -247.430691) (xy 116.437887 -247.420847) (xy 116.487062 -247.418866) (xy 116.535917 -247.424798)
			(xy 116.583188 -247.43849) (xy 116.62765 -247.459588) (xy 116.668153 -247.487544) (xy 116.703646 -247.521636)
			(xy 116.733211 -247.56098) (xy 116.756082 -247.604557) (xy 116.771666 -247.651238) (xy 116.779561 -247.699815)
			(xy 116.780056 -247.724422) (xy 117.108998 -247.724422) (xy 117.112958 -247.675368) (xy 117.124735 -247.627584)
			(xy 117.144026 -247.582308) (xy 117.170329 -247.540712) (xy 117.202964 -247.503875) (xy 117.241085 -247.47275)
			(xy 117.283706 -247.448143) (xy 117.329722 -247.430691) (xy 117.377941 -247.420847) (xy 117.427116 -247.418866)
			(xy 117.475971 -247.424798) (xy 117.523242 -247.43849) (xy 117.567704 -247.459588) (xy 117.608207 -247.487544)
			(xy 117.6437 -247.521636) (xy 117.673265 -247.56098) (xy 117.696136 -247.604557) (xy 117.71172 -247.651238)
			(xy 117.719615 -247.699815) (xy 117.72011 -247.724422) (xy 118.049052 -247.724422) (xy 118.053012 -247.675368)
			(xy 118.064789 -247.627584) (xy 118.08408 -247.582308) (xy 118.110383 -247.540712) (xy 118.143018 -247.503875)
			(xy 118.181139 -247.47275) (xy 118.22376 -247.448143) (xy 118.269776 -247.430691) (xy 118.317995 -247.420847)
			(xy 118.36717 -247.418866) (xy 118.416025 -247.424798) (xy 118.463296 -247.43849) (xy 118.507758 -247.459588)
			(xy 118.548261 -247.487544) (xy 118.583754 -247.521636) (xy 118.613319 -247.56098) (xy 118.63619 -247.604557)
			(xy 118.651774 -247.651238) (xy 118.659669 -247.699815) (xy 118.660164 -247.724422) (xy 118.988852 -247.724422)
			(xy 118.992812 -247.675368) (xy 119.004589 -247.627584) (xy 119.02388 -247.582308) (xy 119.050183 -247.540712)
			(xy 119.082818 -247.503875) (xy 119.120939 -247.47275) (xy 119.16356 -247.448143) (xy 119.209576 -247.430691)
			(xy 119.257795 -247.420847) (xy 119.30697 -247.418866) (xy 119.355825 -247.424798) (xy 119.403096 -247.43849)
			(xy 119.447558 -247.459588) (xy 119.488061 -247.487544) (xy 119.523554 -247.521636) (xy 119.553119 -247.56098)
			(xy 119.57599 -247.604557) (xy 119.591574 -247.651238) (xy 119.599469 -247.699815) (xy 119.599964 -247.724422)
			(xy 119.928906 -247.724422) (xy 119.932866 -247.675368) (xy 119.944643 -247.627584) (xy 119.963934 -247.582308)
			(xy 119.990237 -247.540712) (xy 120.022872 -247.503875) (xy 120.060993 -247.47275) (xy 120.103614 -247.448143)
			(xy 120.14963 -247.430691) (xy 120.197849 -247.420847) (xy 120.247024 -247.418866) (xy 120.295879 -247.424798)
			(xy 120.34315 -247.43849) (xy 120.387612 -247.459588) (xy 120.428115 -247.487544) (xy 120.463608 -247.521636)
			(xy 120.493173 -247.56098) (xy 120.516044 -247.604557) (xy 120.531628 -247.651238) (xy 120.539523 -247.699815)
			(xy 120.540018 -247.724422) (xy 120.86896 -247.724422) (xy 120.87292 -247.675368) (xy 120.884697 -247.627584)
			(xy 120.903988 -247.582308) (xy 120.930291 -247.540712) (xy 120.962926 -247.503875) (xy 121.001047 -247.47275)
			(xy 121.043668 -247.448143) (xy 121.089684 -247.430691) (xy 121.137903 -247.420847) (xy 121.187078 -247.418866)
			(xy 121.235933 -247.424798) (xy 121.283204 -247.43849) (xy 121.327666 -247.459588) (xy 121.368169 -247.487544)
			(xy 121.403662 -247.521636) (xy 121.433227 -247.56098) (xy 121.456098 -247.604557) (xy 121.471682 -247.651238)
			(xy 121.479577 -247.699815) (xy 121.480072 -247.724422) (xy 121.809014 -247.724422) (xy 121.812974 -247.675368)
			(xy 121.824751 -247.627584) (xy 121.844042 -247.582308) (xy 121.870345 -247.540712) (xy 121.90298 -247.503875)
			(xy 121.941101 -247.47275) (xy 121.983722 -247.448143) (xy 122.029738 -247.430691) (xy 122.077957 -247.420847)
			(xy 122.127132 -247.418866) (xy 122.175987 -247.424798) (xy 122.223258 -247.43849) (xy 122.26772 -247.459588)
			(xy 122.308223 -247.487544) (xy 122.343716 -247.521636) (xy 122.373281 -247.56098) (xy 122.396152 -247.604557)
			(xy 122.411736 -247.651238) (xy 122.419631 -247.699815) (xy 122.420126 -247.724422) (xy 122.748814 -247.724422)
			(xy 122.752774 -247.675368) (xy 122.764551 -247.627584) (xy 122.783842 -247.582308) (xy 122.810145 -247.540712)
			(xy 122.84278 -247.503875) (xy 122.880901 -247.47275) (xy 122.923522 -247.448143) (xy 122.969538 -247.430691)
			(xy 123.017757 -247.420847) (xy 123.066932 -247.418866) (xy 123.115787 -247.424798) (xy 123.163058 -247.43849)
			(xy 123.20752 -247.459588) (xy 123.248023 -247.487544) (xy 123.283516 -247.521636) (xy 123.313081 -247.56098)
			(xy 123.335952 -247.604557) (xy 123.351536 -247.651238) (xy 123.359431 -247.699815) (xy 123.359926 -247.724422)
			(xy 123.688868 -247.724422) (xy 123.692828 -247.675368) (xy 123.704605 -247.627584) (xy 123.723896 -247.582308)
			(xy 123.750199 -247.540712) (xy 123.782834 -247.503875) (xy 123.820955 -247.47275) (xy 123.863576 -247.448143)
			(xy 123.909592 -247.430691) (xy 123.957811 -247.420847) (xy 124.006986 -247.418866) (xy 124.055841 -247.424798)
			(xy 124.103112 -247.43849) (xy 124.147574 -247.459588) (xy 124.188077 -247.487544) (xy 124.22357 -247.521636)
			(xy 124.253135 -247.56098) (xy 124.276006 -247.604557) (xy 124.29159 -247.651238) (xy 124.299485 -247.699815)
			(xy 124.29998 -247.724422) (xy 124.628922 -247.724422) (xy 124.632882 -247.675368) (xy 124.644659 -247.627584)
			(xy 124.66395 -247.582308) (xy 124.690253 -247.540712) (xy 124.722888 -247.503875) (xy 124.761009 -247.47275)
			(xy 124.80363 -247.448143) (xy 124.849646 -247.430691) (xy 124.897865 -247.420847) (xy 124.94704 -247.418866)
			(xy 124.995895 -247.424798) (xy 125.043166 -247.43849) (xy 125.087628 -247.459588) (xy 125.128131 -247.487544)
			(xy 125.163624 -247.521636) (xy 125.193189 -247.56098) (xy 125.21606 -247.604557) (xy 125.231644 -247.651238)
			(xy 125.239539 -247.699815) (xy 125.240034 -247.724422) (xy 125.568976 -247.724422) (xy 125.572936 -247.675368)
			(xy 125.584713 -247.627584) (xy 125.604004 -247.582308) (xy 125.630307 -247.540712) (xy 125.662942 -247.503875)
			(xy 125.701063 -247.47275) (xy 125.743684 -247.448143) (xy 125.7897 -247.430691) (xy 125.837919 -247.420847)
			(xy 125.887094 -247.418866) (xy 125.935949 -247.424798) (xy 125.98322 -247.43849) (xy 126.027682 -247.459588)
			(xy 126.068185 -247.487544) (xy 126.103678 -247.521636) (xy 126.133243 -247.56098) (xy 126.156114 -247.604557)
			(xy 126.171698 -247.651238) (xy 126.179593 -247.699815) (xy 126.180088 -247.724422) (xy 126.179593 -247.749029)
			(xy 126.171698 -247.797606) (xy 126.156114 -247.844287) (xy 126.133243 -247.887864) (xy 126.103678 -247.927208)
			(xy 126.068185 -247.9613) (xy 126.027682 -247.989256) (xy 125.98322 -248.010354) (xy 125.935949 -248.024046)
			(xy 125.887094 -248.029978) (xy 125.837919 -248.027997) (xy 125.7897 -248.018153) (xy 125.743684 -248.000701)
			(xy 125.701063 -247.976094) (xy 125.662942 -247.944969) (xy 125.630307 -247.908132) (xy 125.604004 -247.866536)
			(xy 125.584713 -247.82126) (xy 125.572936 -247.773476) (xy 125.568976 -247.724422) (xy 125.240034 -247.724422)
			(xy 125.239539 -247.749029) (xy 125.231644 -247.797606) (xy 125.21606 -247.844287) (xy 125.193189 -247.887864)
			(xy 125.163624 -247.927208) (xy 125.128131 -247.9613) (xy 125.087628 -247.989256) (xy 125.043166 -248.010354)
			(xy 124.995895 -248.024046) (xy 124.94704 -248.029978) (xy 124.897865 -248.027997) (xy 124.849646 -248.018153)
			(xy 124.80363 -248.000701) (xy 124.761009 -247.976094) (xy 124.722888 -247.944969) (xy 124.690253 -247.908132)
			(xy 124.66395 -247.866536) (xy 124.644659 -247.82126) (xy 124.632882 -247.773476) (xy 124.628922 -247.724422)
			(xy 124.29998 -247.724422) (xy 124.299485 -247.749029) (xy 124.29159 -247.797606) (xy 124.276006 -247.844287)
			(xy 124.253135 -247.887864) (xy 124.22357 -247.927208) (xy 124.188077 -247.9613) (xy 124.147574 -247.989256)
			(xy 124.103112 -248.010354) (xy 124.055841 -248.024046) (xy 124.006986 -248.029978) (xy 123.957811 -248.027997)
			(xy 123.909592 -248.018153) (xy 123.863576 -248.000701) (xy 123.820955 -247.976094) (xy 123.782834 -247.944969)
			(xy 123.750199 -247.908132) (xy 123.723896 -247.866536) (xy 123.704605 -247.82126) (xy 123.692828 -247.773476)
			(xy 123.688868 -247.724422) (xy 123.359926 -247.724422) (xy 123.359431 -247.749029) (xy 123.351536 -247.797606)
			(xy 123.335952 -247.844287) (xy 123.313081 -247.887864) (xy 123.283516 -247.927208) (xy 123.248023 -247.9613)
			(xy 123.20752 -247.989256) (xy 123.163058 -248.010354) (xy 123.115787 -248.024046) (xy 123.066932 -248.029978)
			(xy 123.017757 -248.027997) (xy 122.969538 -248.018153) (xy 122.923522 -248.000701) (xy 122.880901 -247.976094)
			(xy 122.84278 -247.944969) (xy 122.810145 -247.908132) (xy 122.783842 -247.866536) (xy 122.764551 -247.82126)
			(xy 122.752774 -247.773476) (xy 122.748814 -247.724422) (xy 122.420126 -247.724422) (xy 122.419631 -247.749029)
			(xy 122.411736 -247.797606) (xy 122.396152 -247.844287) (xy 122.373281 -247.887864) (xy 122.343716 -247.927208)
			(xy 122.308223 -247.9613) (xy 122.26772 -247.989256) (xy 122.223258 -248.010354) (xy 122.175987 -248.024046)
			(xy 122.127132 -248.029978) (xy 122.077957 -248.027997) (xy 122.029738 -248.018153) (xy 121.983722 -248.000701)
			(xy 121.941101 -247.976094) (xy 121.90298 -247.944969) (xy 121.870345 -247.908132) (xy 121.844042 -247.866536)
			(xy 121.824751 -247.82126) (xy 121.812974 -247.773476) (xy 121.809014 -247.724422) (xy 121.480072 -247.724422)
			(xy 121.479577 -247.749029) (xy 121.471682 -247.797606) (xy 121.456098 -247.844287) (xy 121.433227 -247.887864)
			(xy 121.403662 -247.927208) (xy 121.368169 -247.9613) (xy 121.327666 -247.989256) (xy 121.283204 -248.010354)
			(xy 121.235933 -248.024046) (xy 121.187078 -248.029978) (xy 121.137903 -248.027997) (xy 121.089684 -248.018153)
			(xy 121.043668 -248.000701) (xy 121.001047 -247.976094) (xy 120.962926 -247.944969) (xy 120.930291 -247.908132)
			(xy 120.903988 -247.866536) (xy 120.884697 -247.82126) (xy 120.87292 -247.773476) (xy 120.86896 -247.724422)
			(xy 120.540018 -247.724422) (xy 120.539523 -247.749029) (xy 120.531628 -247.797606) (xy 120.516044 -247.844287)
			(xy 120.493173 -247.887864) (xy 120.463608 -247.927208) (xy 120.428115 -247.9613) (xy 120.387612 -247.989256)
			(xy 120.34315 -248.010354) (xy 120.295879 -248.024046) (xy 120.247024 -248.029978) (xy 120.197849 -248.027997)
			(xy 120.14963 -248.018153) (xy 120.103614 -248.000701) (xy 120.060993 -247.976094) (xy 120.022872 -247.944969)
			(xy 119.990237 -247.908132) (xy 119.963934 -247.866536) (xy 119.944643 -247.82126) (xy 119.932866 -247.773476)
			(xy 119.928906 -247.724422) (xy 119.599964 -247.724422) (xy 119.599469 -247.749029) (xy 119.591574 -247.797606)
			(xy 119.57599 -247.844287) (xy 119.553119 -247.887864) (xy 119.523554 -247.927208) (xy 119.488061 -247.9613)
			(xy 119.447558 -247.989256) (xy 119.403096 -248.010354) (xy 119.355825 -248.024046) (xy 119.30697 -248.029978)
			(xy 119.257795 -248.027997) (xy 119.209576 -248.018153) (xy 119.16356 -248.000701) (xy 119.120939 -247.976094)
			(xy 119.082818 -247.944969) (xy 119.050183 -247.908132) (xy 119.02388 -247.866536) (xy 119.004589 -247.82126)
			(xy 118.992812 -247.773476) (xy 118.988852 -247.724422) (xy 118.660164 -247.724422) (xy 118.659669 -247.749029)
			(xy 118.651774 -247.797606) (xy 118.63619 -247.844287) (xy 118.613319 -247.887864) (xy 118.583754 -247.927208)
			(xy 118.548261 -247.9613) (xy 118.507758 -247.989256) (xy 118.463296 -248.010354) (xy 118.416025 -248.024046)
			(xy 118.36717 -248.029978) (xy 118.317995 -248.027997) (xy 118.269776 -248.018153) (xy 118.22376 -248.000701)
			(xy 118.181139 -247.976094) (xy 118.143018 -247.944969) (xy 118.110383 -247.908132) (xy 118.08408 -247.866536)
			(xy 118.064789 -247.82126) (xy 118.053012 -247.773476) (xy 118.049052 -247.724422) (xy 117.72011 -247.724422)
			(xy 117.719615 -247.749029) (xy 117.71172 -247.797606) (xy 117.696136 -247.844287) (xy 117.673265 -247.887864)
			(xy 117.6437 -247.927208) (xy 117.608207 -247.9613) (xy 117.567704 -247.989256) (xy 117.523242 -248.010354)
			(xy 117.475971 -248.024046) (xy 117.427116 -248.029978) (xy 117.377941 -248.027997) (xy 117.329722 -248.018153)
			(xy 117.283706 -248.000701) (xy 117.241085 -247.976094) (xy 117.202964 -247.944969) (xy 117.170329 -247.908132)
			(xy 117.144026 -247.866536) (xy 117.124735 -247.82126) (xy 117.112958 -247.773476) (xy 117.108998 -247.724422)
			(xy 116.780056 -247.724422) (xy 116.779561 -247.749029) (xy 116.771666 -247.797606) (xy 116.756082 -247.844287)
			(xy 116.733211 -247.887864) (xy 116.703646 -247.927208) (xy 116.668153 -247.9613) (xy 116.62765 -247.989256)
			(xy 116.583188 -248.010354) (xy 116.535917 -248.024046) (xy 116.487062 -248.029978) (xy 116.437887 -248.027997)
			(xy 116.389668 -248.018153) (xy 116.343652 -248.000701) (xy 116.301031 -247.976094) (xy 116.26291 -247.944969)
			(xy 116.230275 -247.908132) (xy 116.203972 -247.866536) (xy 116.184681 -247.82126) (xy 116.172904 -247.773476)
			(xy 116.168944 -247.724422) (xy 115.840002 -247.724422) (xy 115.839507 -247.749029) (xy 115.831612 -247.797606)
			(xy 115.816028 -247.844287) (xy 115.793157 -247.887864) (xy 115.763592 -247.927208) (xy 115.728099 -247.9613)
			(xy 115.687596 -247.989256) (xy 115.643134 -248.010354) (xy 115.595863 -248.024046) (xy 115.547008 -248.029978)
			(xy 115.497833 -248.027997) (xy 115.449614 -248.018153) (xy 115.403598 -248.000701) (xy 115.360977 -247.976094)
			(xy 115.322856 -247.944969) (xy 115.290221 -247.908132) (xy 115.263918 -247.866536) (xy 115.244627 -247.82126)
			(xy 115.23285 -247.773476) (xy 115.22889 -247.724422) (xy 114.899948 -247.724422) (xy 114.899453 -247.749029)
			(xy 114.891558 -247.797606) (xy 114.875974 -247.844287) (xy 114.853103 -247.887864) (xy 114.823538 -247.927208)
			(xy 114.788045 -247.9613) (xy 114.747542 -247.989256) (xy 114.70308 -248.010354) (xy 114.655809 -248.024046)
			(xy 114.606954 -248.029978) (xy 114.557779 -248.027997) (xy 114.50956 -248.018153) (xy 114.463544 -248.000701)
			(xy 114.420923 -247.976094) (xy 114.382802 -247.944969) (xy 114.350167 -247.908132) (xy 114.323864 -247.866536)
			(xy 114.304573 -247.82126) (xy 114.292796 -247.773476) (xy 114.288836 -247.724422) (xy 113.960148 -247.724422)
			(xy 113.959653 -247.749029) (xy 113.951758 -247.797606) (xy 113.936174 -247.844287) (xy 113.913303 -247.887864)
			(xy 113.883738 -247.927208) (xy 113.848245 -247.9613) (xy 113.807742 -247.989256) (xy 113.76328 -248.010354)
			(xy 113.716009 -248.024046) (xy 113.667154 -248.029978) (xy 113.617979 -248.027997) (xy 113.56976 -248.018153)
			(xy 113.523744 -248.000701) (xy 113.481123 -247.976094) (xy 113.443002 -247.944969) (xy 113.410367 -247.908132)
			(xy 113.384064 -247.866536) (xy 113.364773 -247.82126) (xy 113.352996 -247.773476) (xy 113.349036 -247.724422)
			(xy 112.01548 -247.724422) (xy 111.987326 -247.745883) (xy 111.94107 -247.771036) (xy 111.891517 -247.788834)
			(xy 111.839827 -247.798858) (xy 111.787213 -247.800875) (xy 111.734908 -247.794837) (xy 111.684137 -247.780885)
			(xy 111.636092 -247.759346) (xy 111.591897 -247.730726) (xy 111.552589 -247.695695) (xy 111.519089 -247.655074)
			(xy 111.492183 -247.609815) (xy 111.4725 -247.56098) (xy 111.460503 -247.509712) (xy 111.456473 -247.457214)
			(xy 110.048873 -247.457214) (xy 110.053876 -247.459588) (xy 110.094379 -247.487544) (xy 110.129872 -247.521636)
			(xy 110.159437 -247.56098) (xy 110.182308 -247.604557) (xy 110.197892 -247.651238) (xy 110.205787 -247.699815)
			(xy 110.206282 -247.724422) (xy 110.205787 -247.749029) (xy 110.197892 -247.797606) (xy 110.182308 -247.844287)
			(xy 110.159437 -247.887864) (xy 110.129872 -247.927208) (xy 110.094379 -247.9613) (xy 110.053876 -247.989256)
			(xy 110.009414 -248.010354) (xy 109.962143 -248.024046) (xy 109.913288 -248.029978) (xy 109.864113 -248.027997)
			(xy 109.815894 -248.018153) (xy 109.769878 -248.000701) (xy 109.727257 -247.976094) (xy 109.689136 -247.944969)
			(xy 109.656501 -247.908132) (xy 109.630198 -247.866536) (xy 109.610907 -247.82126) (xy 109.59913 -247.773476)
			(xy 109.59517 -247.724422) (xy 109.266482 -247.724422) (xy 109.265987 -247.749029) (xy 109.258092 -247.797606)
			(xy 109.242508 -247.844287) (xy 109.219637 -247.887864) (xy 109.190072 -247.927208) (xy 109.154579 -247.9613)
			(xy 109.114076 -247.989256) (xy 109.069614 -248.010354) (xy 109.022343 -248.024046) (xy 108.973488 -248.029978)
			(xy 108.924313 -248.027997) (xy 108.876094 -248.018153) (xy 108.830078 -248.000701) (xy 108.787457 -247.976094)
			(xy 108.749336 -247.944969) (xy 108.716701 -247.908132) (xy 108.690398 -247.866536) (xy 108.671107 -247.82126)
			(xy 108.65933 -247.773476) (xy 108.65537 -247.724422) (xy 108.326428 -247.724422) (xy 108.325933 -247.749029)
			(xy 108.318038 -247.797606) (xy 108.302454 -247.844287) (xy 108.279583 -247.887864) (xy 108.250018 -247.927208)
			(xy 108.214525 -247.9613) (xy 108.174022 -247.989256) (xy 108.12956 -248.010354) (xy 108.082289 -248.024046)
			(xy 108.033434 -248.029978) (xy 107.984259 -248.027997) (xy 107.93604 -248.018153) (xy 107.890024 -248.000701)
			(xy 107.847403 -247.976094) (xy 107.809282 -247.944969) (xy 107.776647 -247.908132) (xy 107.750344 -247.866536)
			(xy 107.731053 -247.82126) (xy 107.719276 -247.773476) (xy 107.715316 -247.724422) (xy 107.387235 -247.724422)
			(xy 107.383061 -247.774792) (xy 107.370647 -247.823809) (xy 107.350334 -247.870114) (xy 107.322676 -247.912444)
			(xy 107.288427 -247.949644) (xy 107.248523 -247.980699) (xy 107.204051 -248.004762) (xy 107.156224 -248.021176)
			(xy 107.106348 -248.029494) (xy 107.081066 -248.029984) (xy 106.141012 -248.029984) (xy 106.115734 -248.029448)
			(xy 106.065869 -248.021129) (xy 106.018052 -248.004715) (xy 105.97359 -247.980655) (xy 105.933694 -247.949604)
			(xy 105.899453 -247.91241) (xy 105.871801 -247.870087) (xy 105.851493 -247.82379) (xy 105.839082 -247.774782)
			(xy 105.834907 -247.7244) (xy 105.506266 -247.7244) (xy 105.506266 -247.724422) (xy 105.505771 -247.749029)
			(xy 105.497876 -247.797606) (xy 105.482292 -247.844287) (xy 105.459421 -247.887864) (xy 105.429856 -247.927208)
			(xy 105.394363 -247.9613) (xy 105.35386 -247.989256) (xy 105.309398 -248.010354) (xy 105.262127 -248.024046)
			(xy 105.213272 -248.029978) (xy 105.164097 -248.027997) (xy 105.115878 -248.018153) (xy 105.069862 -248.000701)
			(xy 105.027241 -247.976094) (xy 104.98912 -247.944969) (xy 104.956485 -247.908132) (xy 104.930182 -247.866536)
			(xy 104.910891 -247.82126) (xy 104.899114 -247.773476) (xy 104.895154 -247.724422) (xy 104.567335 -247.724422)
			(xy 104.56316 -247.774793) (xy 104.550746 -247.823811) (xy 104.530433 -247.870117) (xy 104.502774 -247.912447)
			(xy 104.468524 -247.949647) (xy 104.428619 -247.980702) (xy 104.384145 -248.004764) (xy 104.336318 -248.021178)
			(xy 104.286441 -248.029494) (xy 104.261158 -248.029984) (xy 103.321104 -248.029984) (xy 103.295827 -248.029447)
			(xy 103.245962 -248.021127) (xy 103.198147 -248.004713) (xy 103.153685 -247.980652) (xy 103.113791 -247.949601)
			(xy 103.079551 -247.912407) (xy 103.0519 -247.870085) (xy 103.031593 -247.823789) (xy 103.019182 -247.774782)
			(xy 103.015007 -247.7244) (xy 102.686358 -247.7244) (xy 102.686358 -247.724422) (xy 102.685863 -247.749029)
			(xy 102.677968 -247.797606) (xy 102.662384 -247.844287) (xy 102.639513 -247.887864) (xy 102.609948 -247.927208)
			(xy 102.574455 -247.9613) (xy 102.533952 -247.989256) (xy 102.48949 -248.010354) (xy 102.442219 -248.024046)
			(xy 102.393364 -248.029978) (xy 102.344189 -248.027997) (xy 102.29597 -248.018153) (xy 102.249954 -248.000701)
			(xy 102.207333 -247.976094) (xy 102.169212 -247.944969) (xy 102.136577 -247.908132) (xy 102.110274 -247.866536)
			(xy 102.090983 -247.82126) (xy 102.079206 -247.773476) (xy 102.075246 -247.724422) (xy 101.747135 -247.724422)
			(xy 101.742961 -247.774789) (xy 101.730549 -247.823803) (xy 101.710238 -247.870106) (xy 101.682584 -247.912434)
			(xy 101.648339 -247.949633) (xy 101.608439 -247.980689) (xy 101.563971 -248.004753) (xy 101.516149 -248.02117)
			(xy 101.466277 -248.029491) (xy 101.440996 -248.029984) (xy 100.500942 -248.029984) (xy 100.475663 -248.02945)
			(xy 100.425793 -248.021135) (xy 100.377972 -248.004724) (xy 100.333506 -247.980665) (xy 100.293605 -247.949615)
			(xy 100.259361 -247.91242) (xy 100.231706 -247.870096) (xy 100.211395 -247.823796) (xy 100.198983 -247.774786)
			(xy 100.194807 -247.7244) (xy 99.86645 -247.7244) (xy 99.86645 -247.724422) (xy 99.865955 -247.749029)
			(xy 99.85806 -247.797606) (xy 99.842476 -247.844287) (xy 99.819605 -247.887864) (xy 99.79004 -247.927208)
			(xy 99.754547 -247.9613) (xy 99.714044 -247.989256) (xy 99.669582 -248.010354) (xy 99.622311 -248.024046)
			(xy 99.573456 -248.029978) (xy 99.524281 -248.027997) (xy 99.476062 -248.018153) (xy 99.430046 -248.000701)
			(xy 99.387425 -247.976094) (xy 99.349304 -247.944969) (xy 99.316669 -247.908132) (xy 99.290366 -247.866536)
			(xy 99.271075 -247.82126) (xy 99.259298 -247.773476) (xy 99.255338 -247.724422) (xy 98.927235 -247.724422)
			(xy 98.923061 -247.77479) (xy 98.910648 -247.823805) (xy 98.890337 -247.870108) (xy 98.862682 -247.912437)
			(xy 98.828436 -247.949636) (xy 98.788534 -247.980691) (xy 98.744066 -248.004755) (xy 98.696242 -248.021171)
			(xy 98.646369 -248.029492) (xy 98.621088 -248.029984) (xy 97.681034 -248.029984) (xy 97.655755 -248.02945)
			(xy 97.605887 -248.021133) (xy 97.558067 -248.004721) (xy 97.513601 -247.980662) (xy 97.473702 -247.949612)
			(xy 97.439459 -247.912417) (xy 97.411805 -247.870093) (xy 97.391495 -247.823795) (xy 97.379083 -247.774785)
			(xy 97.374907 -247.7244) (xy 97.046838 -247.7244) (xy 97.042666 -247.774741) (xy 97.030265 -247.823709)
			(xy 97.009973 -247.869968) (xy 96.982344 -247.912256) (xy 96.948131 -247.949419) (xy 96.908267 -247.980444)
			(xy 96.86384 -248.004484) (xy 96.816062 -248.020884) (xy 96.766237 -248.029195) (xy 96.74098 -248.02973)
			(xy 96.717213 -248.029283) (xy 96.670252 -248.021924) (xy 96.625001 -248.007372) (xy 96.582553 -247.985979)
			(xy 96.543936 -247.958262) (xy 96.510085 -247.924892) (xy 96.495616 -247.906032) (xy 96.490536 -247.899174)
			(xy 96.48698 -247.894602) (xy 96.474788 -247.889522) (xy 96.468505 -247.886999) (xy 96.455111 -247.885059)
			(xy 96.448372 -247.885712) (xy 96.361758 -247.897142) (xy 96.355082 -247.898192) (xy 96.342588 -247.903331)
			(xy 96.33712 -247.907302) (xy 96.326452 -247.915684) (xy 96.323658 -247.923304) (xy 96.321626 -247.928384)
			(xy 96.308164 -247.959626) (xy 96.302016 -247.972751) (xy 96.288546 -247.998417) (xy 96.28124 -248.010934)
			(xy 96.280986 -248.011188) (xy 96.27743 -248.017284) (xy 96.275652 -248.02338) (xy 96.273874 -248.036842)
			(xy 96.273874 -248.061226) (xy 96.274383 -248.070979) (xy 96.281824 -248.089016) (xy 96.288352 -248.096278)
			(xy 96.636586 -248.444512) (xy 96.641463 -248.449645) (xy 96.648313 -248.462032) (xy 96.650048 -248.468896)
			(xy 96.650302 -248.470166) (xy 96.653096 -248.481596) (xy 96.966532 -248.795032) (xy 96.970149 -248.798466)
			(xy 96.978467 -248.803967) (xy 96.983042 -248.805954) (xy 96.991932 -248.809764) (xy 98.725228 -248.809764)
			(xy 98.733629 -248.809395) (xy 98.749473 -248.803793) (xy 98.762612 -248.793315) (xy 98.767392 -248.786396)
			(xy 98.812604 -248.714768) (xy 98.815908 -248.709255) (xy 98.81989 -248.697039) (xy 98.820478 -248.690638)
			(xy 98.82124 -248.677938) (xy 98.815398 -248.666) (xy 98.806036 -248.645387) (xy 98.792812 -248.60209)
			(xy 98.786114 -248.557317) (xy 98.78568 -248.534682) (xy 98.78568 -248.534428) (xy 98.786202 -248.509173)
			(xy 98.794515 -248.459351) (xy 98.810916 -248.411577) (xy 98.834957 -248.367154) (xy 98.865981 -248.327294)
			(xy 98.903143 -248.293084) (xy 98.945429 -248.265458) (xy 98.991685 -248.245168) (xy 99.04065 -248.232768)
			(xy 99.090988 -248.228597) (xy 99.141326 -248.232768) (xy 99.190291 -248.245168) (xy 99.236547 -248.265458)
			(xy 99.278833 -248.293084) (xy 99.315995 -248.327294) (xy 99.347019 -248.367154) (xy 99.37106 -248.411577)
			(xy 99.387461 -248.459351) (xy 99.395774 -248.509173) (xy 99.396296 -248.534428) (xy 101.605346 -248.534428)
			(xy 101.609306 -248.485374) (xy 101.621083 -248.43759) (xy 101.640374 -248.392314) (xy 101.666677 -248.350718)
			(xy 101.699312 -248.313881) (xy 101.737433 -248.282756) (xy 101.780054 -248.258149) (xy 101.82607 -248.240697)
			(xy 101.874289 -248.230853) (xy 101.923464 -248.228872) (xy 101.972319 -248.234804) (xy 102.01959 -248.248496)
			(xy 102.064052 -248.269594) (xy 102.104555 -248.29755) (xy 102.140048 -248.331642) (xy 102.169613 -248.370986)
			(xy 102.192484 -248.414563) (xy 102.208068 -248.461244) (xy 102.215963 -248.509821) (xy 102.216458 -248.534428)
			(xy 104.425254 -248.534428) (xy 104.429214 -248.485374) (xy 104.440991 -248.43759) (xy 104.460282 -248.392314)
			(xy 104.486585 -248.350718) (xy 104.51922 -248.313881) (xy 104.557341 -248.282756) (xy 104.599962 -248.258149)
			(xy 104.645978 -248.240697) (xy 104.694197 -248.230853) (xy 104.743372 -248.228872) (xy 104.792227 -248.234804)
			(xy 104.839498 -248.248496) (xy 104.88396 -248.269594) (xy 104.924463 -248.29755) (xy 104.959956 -248.331642)
			(xy 104.989521 -248.370986) (xy 105.012392 -248.414563) (xy 105.027976 -248.461244) (xy 105.035871 -248.509821)
			(xy 105.036366 -248.534428) (xy 107.245162 -248.534428) (xy 107.249122 -248.485374) (xy 107.260899 -248.43759)
			(xy 107.28019 -248.392314) (xy 107.306493 -248.350718) (xy 107.339128 -248.313881) (xy 107.377249 -248.282756)
			(xy 107.41987 -248.258149) (xy 107.465886 -248.240697) (xy 107.514105 -248.230853) (xy 107.56328 -248.228872)
			(xy 107.612135 -248.234804) (xy 107.659406 -248.248496) (xy 107.703868 -248.269594) (xy 107.744371 -248.29755)
			(xy 107.779864 -248.331642) (xy 107.809429 -248.370986) (xy 107.8323 -248.414563) (xy 107.847884 -248.461244)
			(xy 107.855779 -248.509821) (xy 107.856273 -248.5344) (xy 108.185168 -248.5344) (xy 108.189339 -248.48406)
			(xy 108.20174 -248.435093) (xy 108.222032 -248.388834) (xy 108.249661 -248.346547) (xy 108.283873 -248.309385)
			(xy 108.323736 -248.278361) (xy 108.368162 -248.254321) (xy 108.415939 -248.237922) (xy 108.465764 -248.229611)
			(xy 108.49102 -248.22912) (xy 109.431074 -248.22912) (xy 109.456335 -248.229555) (xy 109.50617 -248.237867)
			(xy 109.553956 -248.254268) (xy 109.598391 -248.278312) (xy 109.638262 -248.309342) (xy 109.672482 -248.346511)
			(xy 109.700117 -248.388806) (xy 109.720412 -248.435073) (xy 109.732816 -248.48405) (xy 109.736988 -248.5344)
			(xy 109.736986 -248.534428) (xy 110.065324 -248.534428) (xy 110.069284 -248.485374) (xy 110.081061 -248.43759)
			(xy 110.100352 -248.392314) (xy 110.126655 -248.350718) (xy 110.15929 -248.313881) (xy 110.197411 -248.282756)
			(xy 110.240032 -248.258149) (xy 110.286048 -248.240697) (xy 110.334267 -248.230853) (xy 110.383442 -248.228872)
			(xy 110.432297 -248.234804) (xy 110.479568 -248.248496) (xy 110.52403 -248.269594) (xy 110.564533 -248.29755)
			(xy 110.600026 -248.331642) (xy 110.629591 -248.370986) (xy 110.652462 -248.414563) (xy 110.668046 -248.461244)
			(xy 110.675941 -248.509821) (xy 110.676436 -248.534428) (xy 112.878882 -248.534428) (xy 112.882842 -248.485374)
			(xy 112.894619 -248.43759) (xy 112.91391 -248.392314) (xy 112.940213 -248.350718) (xy 112.972848 -248.313881)
			(xy 113.010969 -248.282756) (xy 113.05359 -248.258149) (xy 113.099606 -248.240697) (xy 113.147825 -248.230853)
			(xy 113.197 -248.228872) (xy 113.245855 -248.234804) (xy 113.293126 -248.248496) (xy 113.337588 -248.269594)
			(xy 113.378091 -248.29755) (xy 113.413584 -248.331642) (xy 113.443149 -248.370986) (xy 113.46602 -248.414563)
			(xy 113.481604 -248.461244) (xy 113.489499 -248.509821) (xy 113.489994 -248.534428) (xy 113.818936 -248.534428)
			(xy 113.822896 -248.485374) (xy 113.834673 -248.43759) (xy 113.853964 -248.392314) (xy 113.880267 -248.350718)
			(xy 113.912902 -248.313881) (xy 113.951023 -248.282756) (xy 113.993644 -248.258149) (xy 114.03966 -248.240697)
			(xy 114.087879 -248.230853) (xy 114.137054 -248.228872) (xy 114.185909 -248.234804) (xy 114.23318 -248.248496)
			(xy 114.277642 -248.269594) (xy 114.318145 -248.29755) (xy 114.353638 -248.331642) (xy 114.383203 -248.370986)
			(xy 114.406074 -248.414563) (xy 114.421658 -248.461244) (xy 114.429553 -248.509821) (xy 114.430048 -248.534428)
			(xy 114.75899 -248.534428) (xy 114.76295 -248.485374) (xy 114.774727 -248.43759) (xy 114.794018 -248.392314)
			(xy 114.820321 -248.350718) (xy 114.852956 -248.313881) (xy 114.891077 -248.282756) (xy 114.933698 -248.258149)
			(xy 114.979714 -248.240697) (xy 115.027933 -248.230853) (xy 115.077108 -248.228872) (xy 115.125963 -248.234804)
			(xy 115.173234 -248.248496) (xy 115.217696 -248.269594) (xy 115.258199 -248.29755) (xy 115.293692 -248.331642)
			(xy 115.323257 -248.370986) (xy 115.346128 -248.414563) (xy 115.361712 -248.461244) (xy 115.369607 -248.509821)
			(xy 115.370102 -248.534428) (xy 115.699044 -248.534428) (xy 115.703004 -248.485374) (xy 115.714781 -248.43759)
			(xy 115.734072 -248.392314) (xy 115.760375 -248.350718) (xy 115.79301 -248.313881) (xy 115.831131 -248.282756)
			(xy 115.873752 -248.258149) (xy 115.919768 -248.240697) (xy 115.967987 -248.230853) (xy 116.017162 -248.228872)
			(xy 116.066017 -248.234804) (xy 116.113288 -248.248496) (xy 116.15775 -248.269594) (xy 116.198253 -248.29755)
			(xy 116.233746 -248.331642) (xy 116.263311 -248.370986) (xy 116.286182 -248.414563) (xy 116.301766 -248.461244)
			(xy 116.309661 -248.509821) (xy 116.310156 -248.534428) (xy 118.518952 -248.534428) (xy 118.522912 -248.485374)
			(xy 118.534689 -248.43759) (xy 118.55398 -248.392314) (xy 118.580283 -248.350718) (xy 118.612918 -248.313881)
			(xy 118.651039 -248.282756) (xy 118.69366 -248.258149) (xy 118.739676 -248.240697) (xy 118.787895 -248.230853)
			(xy 118.83707 -248.228872) (xy 118.885925 -248.234804) (xy 118.933196 -248.248496) (xy 118.977658 -248.269594)
			(xy 119.018161 -248.29755) (xy 119.053654 -248.331642) (xy 119.083219 -248.370986) (xy 119.10609 -248.414563)
			(xy 119.121674 -248.461244) (xy 119.129569 -248.509821) (xy 119.130064 -248.534428) (xy 121.33886 -248.534428)
			(xy 121.34282 -248.485374) (xy 121.354597 -248.43759) (xy 121.373888 -248.392314) (xy 121.400191 -248.350718)
			(xy 121.432826 -248.313881) (xy 121.470947 -248.282756) (xy 121.513568 -248.258149) (xy 121.559584 -248.240697)
			(xy 121.607803 -248.230853) (xy 121.656978 -248.228872) (xy 121.705833 -248.234804) (xy 121.753104 -248.248496)
			(xy 121.797566 -248.269594) (xy 121.838069 -248.29755) (xy 121.873562 -248.331642) (xy 121.903127 -248.370986)
			(xy 121.925998 -248.414563) (xy 121.941582 -248.461244) (xy 121.949477 -248.509821) (xy 121.949972 -248.534428)
			(xy 124.159022 -248.534428) (xy 124.162982 -248.485374) (xy 124.174759 -248.43759) (xy 124.19405 -248.392314)
			(xy 124.220353 -248.350718) (xy 124.252988 -248.313881) (xy 124.291109 -248.282756) (xy 124.33373 -248.258149)
			(xy 124.379746 -248.240697) (xy 124.427965 -248.230853) (xy 124.47714 -248.228872) (xy 124.525995 -248.234804)
			(xy 124.573266 -248.248496) (xy 124.617728 -248.269594) (xy 124.658231 -248.29755) (xy 124.693724 -248.331642)
			(xy 124.723289 -248.370986) (xy 124.74616 -248.414563) (xy 124.761744 -248.461244) (xy 124.769639 -248.509821)
			(xy 124.770134 -248.534428) (xy 124.769639 -248.559035) (xy 124.761744 -248.607612) (xy 124.74616 -248.654293)
			(xy 124.723289 -248.69787) (xy 124.693724 -248.737214) (xy 124.658231 -248.771306) (xy 124.617728 -248.799262)
			(xy 124.573266 -248.82036) (xy 124.525995 -248.834052) (xy 124.47714 -248.839984) (xy 124.427965 -248.838003)
			(xy 124.379746 -248.828159) (xy 124.33373 -248.810707) (xy 124.291109 -248.7861) (xy 124.252988 -248.754975)
			(xy 124.220353 -248.718138) (xy 124.19405 -248.676542) (xy 124.174759 -248.631266) (xy 124.162982 -248.583482)
			(xy 124.159022 -248.534428) (xy 121.949972 -248.534428) (xy 121.949477 -248.559035) (xy 121.941582 -248.607612)
			(xy 121.925998 -248.654293) (xy 121.903127 -248.69787) (xy 121.873562 -248.737214) (xy 121.838069 -248.771306)
			(xy 121.797566 -248.799262) (xy 121.753104 -248.82036) (xy 121.705833 -248.834052) (xy 121.656978 -248.839984)
			(xy 121.607803 -248.838003) (xy 121.559584 -248.828159) (xy 121.513568 -248.810707) (xy 121.470947 -248.7861)
			(xy 121.432826 -248.754975) (xy 121.400191 -248.718138) (xy 121.373888 -248.676542) (xy 121.354597 -248.631266)
			(xy 121.34282 -248.583482) (xy 121.33886 -248.534428) (xy 119.130064 -248.534428) (xy 119.129569 -248.559035)
			(xy 119.121674 -248.607612) (xy 119.10609 -248.654293) (xy 119.083219 -248.69787) (xy 119.053654 -248.737214)
			(xy 119.018161 -248.771306) (xy 118.977658 -248.799262) (xy 118.933196 -248.82036) (xy 118.885925 -248.834052)
			(xy 118.83707 -248.839984) (xy 118.787895 -248.838003) (xy 118.739676 -248.828159) (xy 118.69366 -248.810707)
			(xy 118.651039 -248.7861) (xy 118.612918 -248.754975) (xy 118.580283 -248.718138) (xy 118.55398 -248.676542)
			(xy 118.534689 -248.631266) (xy 118.522912 -248.583482) (xy 118.518952 -248.534428) (xy 116.310156 -248.534428)
			(xy 116.309661 -248.559035) (xy 116.301766 -248.607612) (xy 116.286182 -248.654293) (xy 116.263311 -248.69787)
			(xy 116.233746 -248.737214) (xy 116.198253 -248.771306) (xy 116.15775 -248.799262) (xy 116.113288 -248.82036)
			(xy 116.066017 -248.834052) (xy 116.017162 -248.839984) (xy 115.967987 -248.838003) (xy 115.919768 -248.828159)
			(xy 115.873752 -248.810707) (xy 115.831131 -248.7861) (xy 115.79301 -248.754975) (xy 115.760375 -248.718138)
			(xy 115.734072 -248.676542) (xy 115.714781 -248.631266) (xy 115.703004 -248.583482) (xy 115.699044 -248.534428)
			(xy 115.370102 -248.534428) (xy 115.369607 -248.559035) (xy 115.361712 -248.607612) (xy 115.346128 -248.654293)
			(xy 115.323257 -248.69787) (xy 115.293692 -248.737214) (xy 115.258199 -248.771306) (xy 115.217696 -248.799262)
			(xy 115.173234 -248.82036) (xy 115.125963 -248.834052) (xy 115.077108 -248.839984) (xy 115.027933 -248.838003)
			(xy 114.979714 -248.828159) (xy 114.933698 -248.810707) (xy 114.891077 -248.7861) (xy 114.852956 -248.754975)
			(xy 114.820321 -248.718138) (xy 114.794018 -248.676542) (xy 114.774727 -248.631266) (xy 114.76295 -248.583482)
			(xy 114.75899 -248.534428) (xy 114.430048 -248.534428) (xy 114.429553 -248.559035) (xy 114.421658 -248.607612)
			(xy 114.406074 -248.654293) (xy 114.383203 -248.69787) (xy 114.353638 -248.737214) (xy 114.318145 -248.771306)
			(xy 114.277642 -248.799262) (xy 114.23318 -248.82036) (xy 114.185909 -248.834052) (xy 114.137054 -248.839984)
			(xy 114.087879 -248.838003) (xy 114.03966 -248.828159) (xy 113.993644 -248.810707) (xy 113.951023 -248.7861)
			(xy 113.912902 -248.754975) (xy 113.880267 -248.718138) (xy 113.853964 -248.676542) (xy 113.834673 -248.631266)
			(xy 113.822896 -248.583482) (xy 113.818936 -248.534428) (xy 113.489994 -248.534428) (xy 113.489499 -248.559035)
			(xy 113.481604 -248.607612) (xy 113.46602 -248.654293) (xy 113.443149 -248.69787) (xy 113.413584 -248.737214)
			(xy 113.378091 -248.771306) (xy 113.337588 -248.799262) (xy 113.293126 -248.82036) (xy 113.245855 -248.834052)
			(xy 113.197 -248.839984) (xy 113.147825 -248.838003) (xy 113.099606 -248.828159) (xy 113.05359 -248.810707)
			(xy 113.010969 -248.7861) (xy 112.972848 -248.754975) (xy 112.940213 -248.718138) (xy 112.91391 -248.676542)
			(xy 112.894619 -248.631266) (xy 112.882842 -248.583482) (xy 112.878882 -248.534428) (xy 110.676436 -248.534428)
			(xy 110.675941 -248.559035) (xy 110.668046 -248.607612) (xy 110.652462 -248.654293) (xy 110.629591 -248.69787)
			(xy 110.600026 -248.737214) (xy 110.564533 -248.771306) (xy 110.52403 -248.799262) (xy 110.479568 -248.82036)
			(xy 110.432297 -248.834052) (xy 110.383442 -248.839984) (xy 110.334267 -248.838003) (xy 110.286048 -248.828159)
			(xy 110.240032 -248.810707) (xy 110.197411 -248.7861) (xy 110.15929 -248.754975) (xy 110.126655 -248.718138)
			(xy 110.100352 -248.676542) (xy 110.081061 -248.631266) (xy 110.069284 -248.583482) (xy 110.065324 -248.534428)
			(xy 109.736986 -248.534428) (xy 109.732816 -248.58475) (xy 109.720412 -248.633727) (xy 109.700117 -248.679994)
			(xy 109.672482 -248.722289) (xy 109.638262 -248.759458) (xy 109.598391 -248.790488) (xy 109.553956 -248.814532)
			(xy 109.50617 -248.830933) (xy 109.456335 -248.839245) (xy 109.431074 -248.839736) (xy 108.49102 -248.839736)
			(xy 108.465764 -248.839189) (xy 108.415939 -248.830878) (xy 108.368162 -248.814479) (xy 108.323736 -248.790439)
			(xy 108.283873 -248.759415) (xy 108.249661 -248.722253) (xy 108.222032 -248.679966) (xy 108.20174 -248.633707)
			(xy 108.189339 -248.58474) (xy 108.185168 -248.5344) (xy 107.856273 -248.5344) (xy 107.856274 -248.534428)
			(xy 107.855779 -248.559035) (xy 107.847884 -248.607612) (xy 107.8323 -248.654293) (xy 107.809429 -248.69787)
			(xy 107.779864 -248.737214) (xy 107.744371 -248.771306) (xy 107.703868 -248.799262) (xy 107.659406 -248.82036)
			(xy 107.612135 -248.834052) (xy 107.56328 -248.839984) (xy 107.514105 -248.838003) (xy 107.465886 -248.828159)
			(xy 107.41987 -248.810707) (xy 107.377249 -248.7861) (xy 107.339128 -248.754975) (xy 107.306493 -248.718138)
			(xy 107.28019 -248.676542) (xy 107.260899 -248.631266) (xy 107.249122 -248.583482) (xy 107.245162 -248.534428)
			(xy 105.036366 -248.534428) (xy 105.035871 -248.559035) (xy 105.027976 -248.607612) (xy 105.012392 -248.654293)
			(xy 104.989521 -248.69787) (xy 104.959956 -248.737214) (xy 104.924463 -248.771306) (xy 104.88396 -248.799262)
			(xy 104.839498 -248.82036) (xy 104.792227 -248.834052) (xy 104.743372 -248.839984) (xy 104.694197 -248.838003)
			(xy 104.645978 -248.828159) (xy 104.599962 -248.810707) (xy 104.557341 -248.7861) (xy 104.51922 -248.754975)
			(xy 104.486585 -248.718138) (xy 104.460282 -248.676542) (xy 104.440991 -248.631266) (xy 104.429214 -248.583482)
			(xy 104.425254 -248.534428) (xy 102.216458 -248.534428) (xy 102.215963 -248.559035) (xy 102.208068 -248.607612)
			(xy 102.192484 -248.654293) (xy 102.169613 -248.69787) (xy 102.140048 -248.737214) (xy 102.104555 -248.771306)
			(xy 102.064052 -248.799262) (xy 102.01959 -248.82036) (xy 101.972319 -248.834052) (xy 101.923464 -248.839984)
			(xy 101.874289 -248.838003) (xy 101.82607 -248.828159) (xy 101.780054 -248.810707) (xy 101.737433 -248.7861)
			(xy 101.699312 -248.754975) (xy 101.666677 -248.718138) (xy 101.640374 -248.676542) (xy 101.621083 -248.631266)
			(xy 101.609306 -248.583482) (xy 101.605346 -248.534428) (xy 99.396296 -248.534428) (xy 99.395793 -248.559783)
			(xy 99.387413 -248.609794) (xy 99.370887 -248.657735) (xy 99.346669 -248.702288) (xy 99.315425 -248.742228)
			(xy 99.278013 -248.776459) (xy 99.235461 -248.804041) (xy 99.2124 -248.81459) (xy 99.202494 -248.818908)
			(xy 99.200716 -248.81967) (xy 99.193096 -248.829068) (xy 99.189404 -248.834059) (xy 99.184271 -248.845357)
			(xy 99.182936 -248.85142) (xy 99.177602 -248.878344) (xy 99.167442 -248.932192) (xy 99.166426 -248.941844)
			(xy 99.166426 -248.952258) (xy 99.170236 -248.961148) (xy 99.172243 -248.965712) (xy 99.177741 -248.974027)
			(xy 99.181158 -248.977658) (xy 99.302824 -249.099324) (xy 99.309538 -249.105391) (xy 99.326063 -249.112737)
			(xy 99.344113 -249.113827) (xy 99.352862 -249.111516) (xy 99.37115 -249.105166) (xy 99.377246 -249.100594)
			(xy 99.397248 -249.086132) (xy 99.440938 -249.063174) (xy 99.487749 -249.047531) (xy 99.536464 -249.039611)
			(xy 99.561142 -249.039126) (xy 99.585408 -249.039589) (xy 99.633331 -249.047259) (xy 99.679436 -249.062414)
			(xy 99.722563 -249.084674) (xy 99.761624 -249.113476) (xy 99.795637 -249.148096) (xy 99.823743 -249.187662)
			(xy 99.845235 -249.231176) (xy 99.859572 -249.277542) (xy 99.863402 -249.301508) (xy 99.864164 -249.306334)
			(xy 99.86518 -249.314462) (xy 99.866704 -249.344434) (xy 101.135192 -249.344434) (xy 101.139152 -249.29538)
			(xy 101.150929 -249.247596) (xy 101.17022 -249.20232) (xy 101.196523 -249.160724) (xy 101.229158 -249.123887)
			(xy 101.267279 -249.092762) (xy 101.3099 -249.068155) (xy 101.355916 -249.050703) (xy 101.404135 -249.040859)
			(xy 101.45331 -249.038878) (xy 101.502165 -249.04481) (xy 101.549436 -249.058502) (xy 101.593898 -249.0796)
			(xy 101.634401 -249.107556) (xy 101.669894 -249.141648) (xy 101.699459 -249.180992) (xy 101.72233 -249.224569)
			(xy 101.737914 -249.27125) (xy 101.745809 -249.319827) (xy 101.746304 -249.344434) (xy 103.0153 -249.344434)
			(xy 103.01926 -249.29538) (xy 103.031037 -249.247596) (xy 103.050328 -249.20232) (xy 103.076631 -249.160724)
			(xy 103.109266 -249.123887) (xy 103.147387 -249.092762) (xy 103.190008 -249.068155) (xy 103.236024 -249.050703)
			(xy 103.284243 -249.040859) (xy 103.333418 -249.038878) (xy 103.382273 -249.04481) (xy 103.429544 -249.058502)
			(xy 103.474006 -249.0796) (xy 103.514509 -249.107556) (xy 103.550002 -249.141648) (xy 103.579567 -249.180992)
			(xy 103.602438 -249.224569) (xy 103.618022 -249.27125) (xy 103.625917 -249.319827) (xy 103.626412 -249.344434)
			(xy 104.895154 -249.344434) (xy 104.899114 -249.29538) (xy 104.910891 -249.247596) (xy 104.930182 -249.20232)
			(xy 104.956485 -249.160724) (xy 104.98912 -249.123887) (xy 105.027241 -249.092762) (xy 105.069862 -249.068155)
			(xy 105.115878 -249.050703) (xy 105.164097 -249.040859) (xy 105.213272 -249.038878) (xy 105.262127 -249.04481)
			(xy 105.309398 -249.058502) (xy 105.35386 -249.0796) (xy 105.394363 -249.107556) (xy 105.429856 -249.141648)
			(xy 105.459421 -249.180992) (xy 105.482292 -249.224569) (xy 105.497876 -249.27125) (xy 105.505771 -249.319827)
			(xy 105.506266 -249.344434) (xy 106.775262 -249.344434) (xy 106.779222 -249.29538) (xy 106.790999 -249.247596)
			(xy 106.81029 -249.20232) (xy 106.836593 -249.160724) (xy 106.869228 -249.123887) (xy 106.907349 -249.092762)
			(xy 106.94997 -249.068155) (xy 106.995986 -249.050703) (xy 107.044205 -249.040859) (xy 107.09338 -249.038878)
			(xy 107.142235 -249.04481) (xy 107.189506 -249.058502) (xy 107.233968 -249.0796) (xy 107.274471 -249.107556)
			(xy 107.309964 -249.141648) (xy 107.339529 -249.180992) (xy 107.3624 -249.224569) (xy 107.377984 -249.27125)
			(xy 107.385879 -249.319827) (xy 107.386374 -249.344434) (xy 108.65537 -249.344434) (xy 108.65933 -249.29538)
			(xy 108.671107 -249.247596) (xy 108.690398 -249.20232) (xy 108.716701 -249.160724) (xy 108.749336 -249.123887)
			(xy 108.787457 -249.092762) (xy 108.830078 -249.068155) (xy 108.876094 -249.050703) (xy 108.924313 -249.040859)
			(xy 108.973488 -249.038878) (xy 109.022343 -249.04481) (xy 109.069614 -249.058502) (xy 109.114076 -249.0796)
			(xy 109.154579 -249.107556) (xy 109.190072 -249.141648) (xy 109.219637 -249.180992) (xy 109.242508 -249.224569)
			(xy 109.258092 -249.27125) (xy 109.265987 -249.319827) (xy 109.266482 -249.344434) (xy 109.266124 -249.362214)
			(xy 111.456473 -249.362214) (xy 111.460503 -249.309716) (xy 111.4725 -249.258448) (xy 111.492183 -249.209613)
			(xy 111.519089 -249.164354) (xy 111.552589 -249.123733) (xy 111.591897 -249.088702) (xy 111.636092 -249.060082)
			(xy 111.684137 -249.038543) (xy 111.734908 -249.024591) (xy 111.787213 -249.018553) (xy 111.839827 -249.02057)
			(xy 111.891517 -249.030594) (xy 111.94107 -249.048392) (xy 111.987326 -249.073545) (xy 112.0292 -249.105464)
			(xy 112.065712 -249.143402) (xy 112.096004 -249.186468) (xy 112.119367 -249.233653) (xy 112.135253 -249.283852)
			(xy 112.14329 -249.335888) (xy 112.143454 -249.344434) (xy 113.349036 -249.344434) (xy 113.352996 -249.29538)
			(xy 113.364773 -249.247596) (xy 113.384064 -249.20232) (xy 113.410367 -249.160724) (xy 113.443002 -249.123887)
			(xy 113.481123 -249.092762) (xy 113.523744 -249.068155) (xy 113.56976 -249.050703) (xy 113.617979 -249.040859)
			(xy 113.667154 -249.038878) (xy 113.716009 -249.04481) (xy 113.76328 -249.058502) (xy 113.807742 -249.0796)
			(xy 113.848245 -249.107556) (xy 113.883738 -249.141648) (xy 113.913303 -249.180992) (xy 113.936174 -249.224569)
			(xy 113.951758 -249.27125) (xy 113.959653 -249.319827) (xy 113.960148 -249.344434) (xy 115.22889 -249.344434)
			(xy 115.23285 -249.29538) (xy 115.244627 -249.247596) (xy 115.263918 -249.20232) (xy 115.290221 -249.160724)
			(xy 115.322856 -249.123887) (xy 115.360977 -249.092762) (xy 115.403598 -249.068155) (xy 115.449614 -249.050703)
			(xy 115.497833 -249.040859) (xy 115.547008 -249.038878) (xy 115.595863 -249.04481) (xy 115.643134 -249.058502)
			(xy 115.687596 -249.0796) (xy 115.728099 -249.107556) (xy 115.763592 -249.141648) (xy 115.793157 -249.180992)
			(xy 115.816028 -249.224569) (xy 115.831612 -249.27125) (xy 115.839507 -249.319827) (xy 115.840002 -249.344434)
			(xy 117.108998 -249.344434) (xy 117.112958 -249.29538) (xy 117.124735 -249.247596) (xy 117.144026 -249.20232)
			(xy 117.170329 -249.160724) (xy 117.202964 -249.123887) (xy 117.241085 -249.092762) (xy 117.283706 -249.068155)
			(xy 117.329722 -249.050703) (xy 117.377941 -249.040859) (xy 117.427116 -249.038878) (xy 117.475971 -249.04481)
			(xy 117.523242 -249.058502) (xy 117.567704 -249.0796) (xy 117.608207 -249.107556) (xy 117.6437 -249.141648)
			(xy 117.673265 -249.180992) (xy 117.696136 -249.224569) (xy 117.71172 -249.27125) (xy 117.719615 -249.319827)
			(xy 117.72011 -249.344434) (xy 118.988852 -249.344434) (xy 118.992812 -249.29538) (xy 119.004589 -249.247596)
			(xy 119.02388 -249.20232) (xy 119.050183 -249.160724) (xy 119.082818 -249.123887) (xy 119.120939 -249.092762)
			(xy 119.16356 -249.068155) (xy 119.209576 -249.050703) (xy 119.257795 -249.040859) (xy 119.30697 -249.038878)
			(xy 119.355825 -249.04481) (xy 119.403096 -249.058502) (xy 119.447558 -249.0796) (xy 119.488061 -249.107556)
			(xy 119.523554 -249.141648) (xy 119.553119 -249.180992) (xy 119.57599 -249.224569) (xy 119.591574 -249.27125)
			(xy 119.599469 -249.319827) (xy 119.599964 -249.344434) (xy 120.86896 -249.344434) (xy 120.87292 -249.29538)
			(xy 120.884697 -249.247596) (xy 120.903988 -249.20232) (xy 120.930291 -249.160724) (xy 120.962926 -249.123887)
			(xy 121.001047 -249.092762) (xy 121.043668 -249.068155) (xy 121.089684 -249.050703) (xy 121.137903 -249.040859)
			(xy 121.187078 -249.038878) (xy 121.235933 -249.04481) (xy 121.283204 -249.058502) (xy 121.327666 -249.0796)
			(xy 121.368169 -249.107556) (xy 121.403662 -249.141648) (xy 121.433227 -249.180992) (xy 121.456098 -249.224569)
			(xy 121.471682 -249.27125) (xy 121.479577 -249.319827) (xy 121.480072 -249.344434) (xy 122.748814 -249.344434)
			(xy 122.752774 -249.29538) (xy 122.764551 -249.247596) (xy 122.783842 -249.20232) (xy 122.810145 -249.160724)
			(xy 122.84278 -249.123887) (xy 122.880901 -249.092762) (xy 122.923522 -249.068155) (xy 122.969538 -249.050703)
			(xy 123.017757 -249.040859) (xy 123.066932 -249.038878) (xy 123.115787 -249.04481) (xy 123.163058 -249.058502)
			(xy 123.20752 -249.0796) (xy 123.248023 -249.107556) (xy 123.283516 -249.141648) (xy 123.313081 -249.180992)
			(xy 123.335952 -249.224569) (xy 123.351536 -249.27125) (xy 123.359431 -249.319827) (xy 123.359926 -249.344434)
			(xy 124.628922 -249.344434) (xy 124.632882 -249.29538) (xy 124.644659 -249.247596) (xy 124.66395 -249.20232)
			(xy 124.690253 -249.160724) (xy 124.722888 -249.123887) (xy 124.761009 -249.092762) (xy 124.80363 -249.068155)
			(xy 124.849646 -249.050703) (xy 124.897865 -249.040859) (xy 124.94704 -249.038878) (xy 124.995895 -249.04481)
			(xy 125.043166 -249.058502) (xy 125.087628 -249.0796) (xy 125.128131 -249.107556) (xy 125.163624 -249.141648)
			(xy 125.193189 -249.180992) (xy 125.21606 -249.224569) (xy 125.231644 -249.27125) (xy 125.239539 -249.319827)
			(xy 125.240034 -249.344434) (xy 125.239539 -249.369041) (xy 125.231644 -249.417618) (xy 125.21606 -249.464299)
			(xy 125.193189 -249.507876) (xy 125.163624 -249.54722) (xy 125.128131 -249.581312) (xy 125.087628 -249.609268)
			(xy 125.043166 -249.630366) (xy 124.995895 -249.644058) (xy 124.94704 -249.64999) (xy 124.897865 -249.648009)
			(xy 124.849646 -249.638165) (xy 124.80363 -249.620713) (xy 124.761009 -249.596106) (xy 124.722888 -249.564981)
			(xy 124.690253 -249.528144) (xy 124.66395 -249.486548) (xy 124.644659 -249.441272) (xy 124.632882 -249.393488)
			(xy 124.628922 -249.344434) (xy 123.359926 -249.344434) (xy 123.359431 -249.369041) (xy 123.351536 -249.417618)
			(xy 123.335952 -249.464299) (xy 123.313081 -249.507876) (xy 123.283516 -249.54722) (xy 123.248023 -249.581312)
			(xy 123.20752 -249.609268) (xy 123.163058 -249.630366) (xy 123.115787 -249.644058) (xy 123.066932 -249.64999)
			(xy 123.017757 -249.648009) (xy 122.969538 -249.638165) (xy 122.923522 -249.620713) (xy 122.880901 -249.596106)
			(xy 122.84278 -249.564981) (xy 122.810145 -249.528144) (xy 122.783842 -249.486548) (xy 122.764551 -249.441272)
			(xy 122.752774 -249.393488) (xy 122.748814 -249.344434) (xy 121.480072 -249.344434) (xy 121.479577 -249.369041)
			(xy 121.471682 -249.417618) (xy 121.456098 -249.464299) (xy 121.433227 -249.507876) (xy 121.403662 -249.54722)
			(xy 121.368169 -249.581312) (xy 121.327666 -249.609268) (xy 121.283204 -249.630366) (xy 121.235933 -249.644058)
			(xy 121.187078 -249.64999) (xy 121.137903 -249.648009) (xy 121.089684 -249.638165) (xy 121.043668 -249.620713)
			(xy 121.001047 -249.596106) (xy 120.962926 -249.564981) (xy 120.930291 -249.528144) (xy 120.903988 -249.486548)
			(xy 120.884697 -249.441272) (xy 120.87292 -249.393488) (xy 120.86896 -249.344434) (xy 119.599964 -249.344434)
			(xy 119.599469 -249.369041) (xy 119.591574 -249.417618) (xy 119.57599 -249.464299) (xy 119.553119 -249.507876)
			(xy 119.523554 -249.54722) (xy 119.488061 -249.581312) (xy 119.447558 -249.609268) (xy 119.403096 -249.630366)
			(xy 119.355825 -249.644058) (xy 119.30697 -249.64999) (xy 119.257795 -249.648009) (xy 119.209576 -249.638165)
			(xy 119.16356 -249.620713) (xy 119.120939 -249.596106) (xy 119.082818 -249.564981) (xy 119.050183 -249.528144)
			(xy 119.02388 -249.486548) (xy 119.004589 -249.441272) (xy 118.992812 -249.393488) (xy 118.988852 -249.344434)
			(xy 117.72011 -249.344434) (xy 117.719615 -249.369041) (xy 117.71172 -249.417618) (xy 117.696136 -249.464299)
			(xy 117.673265 -249.507876) (xy 117.6437 -249.54722) (xy 117.608207 -249.581312) (xy 117.567704 -249.609268)
			(xy 117.523242 -249.630366) (xy 117.475971 -249.644058) (xy 117.427116 -249.64999) (xy 117.377941 -249.648009)
			(xy 117.329722 -249.638165) (xy 117.283706 -249.620713) (xy 117.241085 -249.596106) (xy 117.202964 -249.564981)
			(xy 117.170329 -249.528144) (xy 117.144026 -249.486548) (xy 117.124735 -249.441272) (xy 117.112958 -249.393488)
			(xy 117.108998 -249.344434) (xy 115.840002 -249.344434) (xy 115.839507 -249.369041) (xy 115.831612 -249.417618)
			(xy 115.816028 -249.464299) (xy 115.793157 -249.507876) (xy 115.763592 -249.54722) (xy 115.728099 -249.581312)
			(xy 115.687596 -249.609268) (xy 115.643134 -249.630366) (xy 115.595863 -249.644058) (xy 115.547008 -249.64999)
			(xy 115.497833 -249.648009) (xy 115.449614 -249.638165) (xy 115.403598 -249.620713) (xy 115.360977 -249.596106)
			(xy 115.322856 -249.564981) (xy 115.290221 -249.528144) (xy 115.263918 -249.486548) (xy 115.244627 -249.441272)
			(xy 115.23285 -249.393488) (xy 115.22889 -249.344434) (xy 113.960148 -249.344434) (xy 113.959653 -249.369041)
			(xy 113.951758 -249.417618) (xy 113.936174 -249.464299) (xy 113.913303 -249.507876) (xy 113.883738 -249.54722)
			(xy 113.848245 -249.581312) (xy 113.807742 -249.609268) (xy 113.76328 -249.630366) (xy 113.716009 -249.644058)
			(xy 113.667154 -249.64999) (xy 113.617979 -249.648009) (xy 113.56976 -249.638165) (xy 113.523744 -249.620713)
			(xy 113.481123 -249.596106) (xy 113.443002 -249.564981) (xy 113.410367 -249.528144) (xy 113.384064 -249.486548)
			(xy 113.364773 -249.441272) (xy 113.352996 -249.393488) (xy 113.349036 -249.344434) (xy 112.143454 -249.344434)
			(xy 112.143794 -249.362214) (xy 112.14329 -249.38854) (xy 112.135253 -249.440576) (xy 112.119367 -249.490775)
			(xy 112.096004 -249.53796) (xy 112.065712 -249.581026) (xy 112.0292 -249.618964) (xy 111.987326 -249.650883)
			(xy 111.94107 -249.676036) (xy 111.891517 -249.693834) (xy 111.839827 -249.703858) (xy 111.787213 -249.705875)
			(xy 111.734908 -249.699837) (xy 111.684137 -249.685885) (xy 111.636092 -249.664346) (xy 111.591897 -249.635726)
			(xy 111.552589 -249.600695) (xy 111.519089 -249.560074) (xy 111.492183 -249.514815) (xy 111.4725 -249.46598)
			(xy 111.460503 -249.414712) (xy 111.456473 -249.362214) (xy 109.266124 -249.362214) (xy 109.265987 -249.369041)
			(xy 109.258092 -249.417618) (xy 109.242508 -249.464299) (xy 109.219637 -249.507876) (xy 109.190072 -249.54722)
			(xy 109.154579 -249.581312) (xy 109.114076 -249.609268) (xy 109.069614 -249.630366) (xy 109.022343 -249.644058)
			(xy 108.973488 -249.64999) (xy 108.924313 -249.648009) (xy 108.876094 -249.638165) (xy 108.830078 -249.620713)
			(xy 108.787457 -249.596106) (xy 108.749336 -249.564981) (xy 108.716701 -249.528144) (xy 108.690398 -249.486548)
			(xy 108.671107 -249.441272) (xy 108.65933 -249.393488) (xy 108.65537 -249.344434) (xy 107.386374 -249.344434)
			(xy 107.385879 -249.369041) (xy 107.377984 -249.417618) (xy 107.3624 -249.464299) (xy 107.339529 -249.507876)
			(xy 107.309964 -249.54722) (xy 107.274471 -249.581312) (xy 107.233968 -249.609268) (xy 107.189506 -249.630366)
			(xy 107.142235 -249.644058) (xy 107.09338 -249.64999) (xy 107.044205 -249.648009) (xy 106.995986 -249.638165)
			(xy 106.94997 -249.620713) (xy 106.907349 -249.596106) (xy 106.869228 -249.564981) (xy 106.836593 -249.528144)
			(xy 106.81029 -249.486548) (xy 106.790999 -249.441272) (xy 106.779222 -249.393488) (xy 106.775262 -249.344434)
			(xy 105.506266 -249.344434) (xy 105.505771 -249.369041) (xy 105.497876 -249.417618) (xy 105.482292 -249.464299)
			(xy 105.459421 -249.507876) (xy 105.429856 -249.54722) (xy 105.394363 -249.581312) (xy 105.35386 -249.609268)
			(xy 105.309398 -249.630366) (xy 105.262127 -249.644058) (xy 105.213272 -249.64999) (xy 105.164097 -249.648009)
			(xy 105.115878 -249.638165) (xy 105.069862 -249.620713) (xy 105.027241 -249.596106) (xy 104.98912 -249.564981)
			(xy 104.956485 -249.528144) (xy 104.930182 -249.486548) (xy 104.910891 -249.441272) (xy 104.899114 -249.393488)
			(xy 104.895154 -249.344434) (xy 103.626412 -249.344434) (xy 103.625917 -249.369041) (xy 103.618022 -249.417618)
			(xy 103.602438 -249.464299) (xy 103.579567 -249.507876) (xy 103.550002 -249.54722) (xy 103.514509 -249.581312)
			(xy 103.474006 -249.609268) (xy 103.429544 -249.630366) (xy 103.382273 -249.644058) (xy 103.333418 -249.64999)
			(xy 103.284243 -249.648009) (xy 103.236024 -249.638165) (xy 103.190008 -249.620713) (xy 103.147387 -249.596106)
			(xy 103.109266 -249.564981) (xy 103.076631 -249.528144) (xy 103.050328 -249.486548) (xy 103.031037 -249.441272)
			(xy 103.01926 -249.393488) (xy 103.0153 -249.344434) (xy 101.746304 -249.344434) (xy 101.745809 -249.369041)
			(xy 101.737914 -249.417618) (xy 101.72233 -249.464299) (xy 101.699459 -249.507876) (xy 101.669894 -249.54722)
			(xy 101.634401 -249.581312) (xy 101.593898 -249.609268) (xy 101.549436 -249.630366) (xy 101.502165 -249.644058)
			(xy 101.45331 -249.64999) (xy 101.404135 -249.648009) (xy 101.355916 -249.638165) (xy 101.3099 -249.620713)
			(xy 101.267279 -249.596106) (xy 101.229158 -249.564981) (xy 101.196523 -249.528144) (xy 101.17022 -249.486548)
			(xy 101.150929 -249.441272) (xy 101.139152 -249.393488) (xy 101.135192 -249.344434) (xy 99.866704 -249.344434)
			(xy 99.866704 -249.364754) (xy 99.864926 -249.376692) (xy 99.861408 -249.404101) (xy 99.845789 -249.457103)
			(xy 99.82092 -249.506445) (xy 99.804728 -249.528838) (xy 99.80041 -249.53468) (xy 99.793552 -249.554238)
			(xy 99.791621 -249.562799) (xy 99.793074 -249.580276) (xy 99.800396 -249.596212) (xy 99.806252 -249.602752)
			(xy 100.040948 -249.837448) (xy 100.043931 -249.840355) (xy 100.050697 -249.845212) (xy 100.05441 -249.8471)
			(xy 100.061268 -249.850402) (xy 100.070158 -249.851672) (xy 100.094966 -249.855392) (xy 100.14299 -249.869873)
			(xy 100.188001 -249.892011) (xy 100.228786 -249.92121) (xy 100.26425 -249.956684) (xy 100.293436 -249.997478)
			(xy 100.31556 -250.042495) (xy 100.330027 -250.090524) (xy 100.33381 -250.115324) (xy 100.33508 -250.124214)
			(xy 100.338382 -250.131072) (xy 100.340316 -250.134757) (xy 100.345166 -250.141519) (xy 100.348034 -250.144534)
			(xy 100.35794 -250.15444) (xy 101.605346 -250.15444) (xy 101.609306 -250.105386) (xy 101.621083 -250.057602)
			(xy 101.640374 -250.012326) (xy 101.666677 -249.97073) (xy 101.699312 -249.933893) (xy 101.737433 -249.902768)
			(xy 101.780054 -249.878161) (xy 101.82607 -249.860709) (xy 101.874289 -249.850865) (xy 101.923464 -249.848884)
			(xy 101.972319 -249.854816) (xy 102.01959 -249.868508) (xy 102.064052 -249.889606) (xy 102.104555 -249.917562)
			(xy 102.140048 -249.951654) (xy 102.169613 -249.990998) (xy 102.192484 -250.034575) (xy 102.208068 -250.081256)
			(xy 102.215963 -250.129833) (xy 102.216458 -250.15444) (xy 103.4852 -250.15444) (xy 103.48916 -250.105386)
			(xy 103.500937 -250.057602) (xy 103.520228 -250.012326) (xy 103.546531 -249.97073) (xy 103.579166 -249.933893)
			(xy 103.617287 -249.902768) (xy 103.659908 -249.878161) (xy 103.705924 -249.860709) (xy 103.754143 -249.850865)
			(xy 103.803318 -249.848884) (xy 103.852173 -249.854816) (xy 103.899444 -249.868508) (xy 103.943906 -249.889606)
			(xy 103.984409 -249.917562) (xy 104.019902 -249.951654) (xy 104.049467 -249.990998) (xy 104.072338 -250.034575)
			(xy 104.087922 -250.081256) (xy 104.095817 -250.129833) (xy 104.096312 -250.15444) (xy 105.365308 -250.15444)
			(xy 105.369268 -250.105386) (xy 105.381045 -250.057602) (xy 105.400336 -250.012326) (xy 105.426639 -249.97073)
			(xy 105.459274 -249.933893) (xy 105.497395 -249.902768) (xy 105.540016 -249.878161) (xy 105.586032 -249.860709)
			(xy 105.634251 -249.850865) (xy 105.683426 -249.848884) (xy 105.732281 -249.854816) (xy 105.779552 -249.868508)
			(xy 105.824014 -249.889606) (xy 105.864517 -249.917562) (xy 105.90001 -249.951654) (xy 105.929575 -249.990998)
			(xy 105.952446 -250.034575) (xy 105.96803 -250.081256) (xy 105.975925 -250.129833) (xy 105.97642 -250.15444)
			(xy 107.245162 -250.15444) (xy 107.249122 -250.105386) (xy 107.260899 -250.057602) (xy 107.28019 -250.012326)
			(xy 107.306493 -249.97073) (xy 107.339128 -249.933893) (xy 107.377249 -249.902768) (xy 107.41987 -249.878161)
			(xy 107.465886 -249.860709) (xy 107.514105 -249.850865) (xy 107.56328 -249.848884) (xy 107.612135 -249.854816)
			(xy 107.659406 -249.868508) (xy 107.703868 -249.889606) (xy 107.744371 -249.917562) (xy 107.779864 -249.951654)
			(xy 107.809429 -249.990998) (xy 107.8323 -250.034575) (xy 107.847884 -250.081256) (xy 107.855779 -250.129833)
			(xy 107.856274 -250.15444) (xy 107.855779 -250.179047) (xy 107.847884 -250.227624) (xy 107.8323 -250.274305)
			(xy 107.809429 -250.317882) (xy 107.779864 -250.357226) (xy 107.744371 -250.391318) (xy 107.703868 -250.419274)
			(xy 107.659406 -250.440372) (xy 107.612135 -250.454064) (xy 107.56328 -250.459996) (xy 107.514105 -250.458015)
			(xy 107.465886 -250.448171) (xy 107.41987 -250.430719) (xy 107.377249 -250.406112) (xy 107.339128 -250.374987)
			(xy 107.306493 -250.33815) (xy 107.28019 -250.296554) (xy 107.260899 -250.251278) (xy 107.249122 -250.203494)
			(xy 107.245162 -250.15444) (xy 105.97642 -250.15444) (xy 105.975925 -250.179047) (xy 105.96803 -250.227624)
			(xy 105.952446 -250.274305) (xy 105.929575 -250.317882) (xy 105.90001 -250.357226) (xy 105.864517 -250.391318)
			(xy 105.824014 -250.419274) (xy 105.779552 -250.440372) (xy 105.732281 -250.454064) (xy 105.683426 -250.459996)
			(xy 105.634251 -250.458015) (xy 105.586032 -250.448171) (xy 105.540016 -250.430719) (xy 105.497395 -250.406112)
			(xy 105.459274 -250.374987) (xy 105.426639 -250.33815) (xy 105.400336 -250.296554) (xy 105.381045 -250.251278)
			(xy 105.369268 -250.203494) (xy 105.365308 -250.15444) (xy 104.096312 -250.15444) (xy 104.095817 -250.179047)
			(xy 104.087922 -250.227624) (xy 104.072338 -250.274305) (xy 104.049467 -250.317882) (xy 104.019902 -250.357226)
			(xy 103.984409 -250.391318) (xy 103.943906 -250.419274) (xy 103.899444 -250.440372) (xy 103.852173 -250.454064)
			(xy 103.803318 -250.459996) (xy 103.754143 -250.458015) (xy 103.705924 -250.448171) (xy 103.659908 -250.430719)
			(xy 103.617287 -250.406112) (xy 103.579166 -250.374987) (xy 103.546531 -250.33815) (xy 103.520228 -250.296554)
			(xy 103.500937 -250.251278) (xy 103.48916 -250.203494) (xy 103.4852 -250.15444) (xy 102.216458 -250.15444)
			(xy 102.215963 -250.179047) (xy 102.208068 -250.227624) (xy 102.192484 -250.274305) (xy 102.169613 -250.317882)
			(xy 102.140048 -250.357226) (xy 102.104555 -250.391318) (xy 102.064052 -250.419274) (xy 102.01959 -250.440372)
			(xy 101.972319 -250.454064) (xy 101.923464 -250.459996) (xy 101.874289 -250.458015) (xy 101.82607 -250.448171)
			(xy 101.780054 -250.430719) (xy 101.737433 -250.406112) (xy 101.699312 -250.374987) (xy 101.666677 -250.33815)
			(xy 101.640374 -250.296554) (xy 101.621083 -250.251278) (xy 101.609306 -250.203494) (xy 101.605346 -250.15444)
			(xy 100.35794 -250.15444) (xy 100.700332 -250.496832) (xy 100.703949 -250.500266) (xy 100.712267 -250.505767)
			(xy 100.716842 -250.507754) (xy 100.725732 -250.511564) (xy 101.48189 -250.511564) (xy 101.491727 -250.512103)
			(xy 101.509886 -250.519691) (xy 101.517196 -250.526296) (xy 102.148132 -251.157232) (xy 102.151749 -251.160666)
			(xy 102.160067 -251.166167) (xy 102.164642 -251.168154) (xy 102.173532 -251.171964) (xy 102.929944 -251.171964)
			(xy 102.941458 -251.171392) (xy 102.962104 -251.161193) (xy 102.969568 -251.152406) (xy 103.018082 -251.08916)
			(xy 103.02159 -251.084321) (xy 103.02647 -251.073412) (xy 103.027734 -251.06757) (xy 103.029766 -251.056902)
			(xy 103.026718 -251.045218) (xy 103.021608 -251.025417) (xy 103.016131 -250.984893) (xy 103.015796 -250.964446)
			(xy 103.016318 -250.939191) (xy 103.024631 -250.889369) (xy 103.041032 -250.841595) (xy 103.065073 -250.797172)
			(xy 103.096097 -250.757312) (xy 103.133259 -250.723102) (xy 103.175545 -250.695476) (xy 103.221801 -250.675186)
			(xy 103.270766 -250.662786) (xy 103.321104 -250.658615) (xy 103.371442 -250.662786) (xy 103.420407 -250.675186)
			(xy 103.466663 -250.695476) (xy 103.508949 -250.723102) (xy 103.546111 -250.757312) (xy 103.577135 -250.797172)
			(xy 103.601176 -250.841595) (xy 103.617577 -250.889369) (xy 103.62589 -250.939191) (xy 103.626412 -250.964446)
			(xy 103.626051 -250.984891) (xy 103.620572 -251.025412) (xy 103.61549 -251.045218) (xy 103.612442 -251.056902)
			(xy 103.614474 -251.06757) (xy 103.615738 -251.073412) (xy 103.620616 -251.084322) (xy 103.624126 -251.08916)
			(xy 103.67264 -251.152406) (xy 103.680119 -251.161168) (xy 103.70076 -251.171342) (xy 103.712264 -251.171964)
			(xy 104.809798 -251.171964) (xy 104.821317 -251.171401) (xy 104.841978 -251.161214) (xy 104.849422 -251.152406)
			(xy 104.897936 -251.08916) (xy 104.901441 -251.084319) (xy 104.906315 -251.07341) (xy 104.907588 -251.06757)
			(xy 104.90962 -251.056902) (xy 104.906572 -251.045218) (xy 104.901463 -251.025417) (xy 104.895987 -250.984893)
			(xy 104.89565 -250.964446) (xy 104.896172 -250.939191) (xy 104.904485 -250.889369) (xy 104.920886 -250.841595)
			(xy 104.944927 -250.797172) (xy 104.975951 -250.757312) (xy 105.013113 -250.723102) (xy 105.055399 -250.695476)
			(xy 105.101655 -250.675186) (xy 105.15062 -250.662786) (xy 105.200958 -250.658615) (xy 105.251296 -250.662786)
			(xy 105.300261 -250.675186) (xy 105.346517 -250.695476) (xy 105.388803 -250.723102) (xy 105.425965 -250.757312)
			(xy 105.456989 -250.797172) (xy 105.48103 -250.841595) (xy 105.497431 -250.889369) (xy 105.505744 -250.939191)
			(xy 105.506266 -250.964446) (xy 105.505905 -250.984891) (xy 105.500427 -251.025412) (xy 105.495344 -251.045218)
			(xy 105.492296 -251.056902) (xy 105.494328 -251.06757) (xy 105.495594 -251.073411) (xy 105.500476 -251.084318)
			(xy 105.50398 -251.08916) (xy 105.552494 -251.152406) (xy 105.55997 -251.161176) (xy 105.58061 -251.171368)
			(xy 105.592118 -251.171964) (xy 106.689906 -251.171964) (xy 106.701424 -251.1714) (xy 106.722083 -251.16121)
			(xy 106.72953 -251.152406) (xy 106.778044 -251.08916) (xy 106.781549 -251.084319) (xy 106.786422 -251.073409)
			(xy 106.787696 -251.06757) (xy 106.789728 -251.056902) (xy 106.78668 -251.045218) (xy 106.781571 -251.025417)
			(xy 106.776095 -250.984893) (xy 106.775758 -250.964446) (xy 106.77628 -250.939191) (xy 106.784593 -250.889369)
			(xy 106.800994 -250.841595) (xy 106.825035 -250.797172) (xy 106.856059 -250.757312) (xy 106.893221 -250.723102)
			(xy 106.935507 -250.695476) (xy 106.981763 -250.675186) (xy 107.030728 -250.662786) (xy 107.081066 -250.658615)
			(xy 107.131404 -250.662786) (xy 107.180369 -250.675186) (xy 107.226625 -250.695476) (xy 107.268911 -250.723102)
			(xy 107.306073 -250.757312) (xy 107.337097 -250.797172) (xy 107.361138 -250.841595) (xy 107.377539 -250.889369)
			(xy 107.385852 -250.939191) (xy 107.386374 -250.964446) (xy 107.386012 -250.984891) (xy 107.380533 -251.025412)
			(xy 107.375452 -251.045218) (xy 107.372404 -251.056902) (xy 107.374436 -251.06757) (xy 107.375702 -251.073411)
			(xy 107.380584 -251.084317) (xy 107.384088 -251.08916) (xy 107.432602 -251.152406) (xy 107.440078 -251.161174)
			(xy 107.460719 -251.171363) (xy 107.472226 -251.171964) (xy 108.365036 -251.171964) (xy 108.370055 -251.171873)
			(xy 108.379908 -251.169954) (xy 108.384594 -251.168154) (xy 108.393484 -251.164344) (xy 108.650278 -250.90755)
			(xy 108.657644 -250.898152) (xy 108.658406 -250.896628) (xy 108.667042 -250.881896) (xy 108.668058 -250.878594)
			(xy 108.66882 -250.876054) (xy 108.676548 -250.852219) (xy 108.698673 -250.807267) (xy 108.727838 -250.766528)
			(xy 108.76326 -250.731096) (xy 108.80399 -250.701919) (xy 108.848936 -250.679781) (xy 108.872782 -250.672092)
			(xy 108.875322 -250.67133) (xy 108.878624 -250.670314) (xy 108.893356 -250.661678) (xy 108.89488 -250.660916)
			(xy 108.904278 -250.65355) (xy 109.097064 -250.460764) (xy 109.11078 -250.460764) (xy 109.168438 -250.359672)
			(xy 109.171534 -250.353855) (xy 109.17488 -250.341114) (xy 109.175042 -250.334526) (xy 109.175042 -250.321318)
			(xy 109.16793 -250.309126) (xy 109.15473 -250.285503) (xy 109.135958 -250.234753) (xy 109.126394 -250.181494)
			(xy 109.125766 -250.15444) (xy 109.126288 -250.129185) (xy 109.134601 -250.079363) (xy 109.151002 -250.031589)
			(xy 109.175043 -249.987166) (xy 109.206067 -249.947306) (xy 109.243229 -249.913096) (xy 109.285515 -249.88547)
			(xy 109.331771 -249.86518) (xy 109.380736 -249.85278) (xy 109.431074 -249.848609) (xy 109.481412 -249.85278)
			(xy 109.530377 -249.86518) (xy 109.576633 -249.88547) (xy 109.618919 -249.913096) (xy 109.656081 -249.947306)
			(xy 109.687105 -249.987166) (xy 109.711146 -250.031589) (xy 109.727547 -250.079363) (xy 109.73586 -250.129185)
			(xy 109.736382 -250.15444) (xy 109.735808 -250.181501) (xy 109.726271 -250.234775) (xy 109.707467 -250.285524)
			(xy 109.694218 -250.309126) (xy 109.6899 -250.316492) (xy 109.68736 -250.321064) (xy 109.68736 -250.334272)
			(xy 109.687519 -250.340981) (xy 109.690866 -250.353973) (xy 109.693964 -250.359926) (xy 109.737906 -250.436888)
			(xy 109.741462 -250.442222) (xy 109.748916 -250.450493) (xy 109.768955 -250.460134) (xy 109.78007 -250.460764)
			(xy 112.12449 -250.460764) (xy 112.133621 -250.461167) (xy 112.150679 -250.467688) (xy 112.157764 -250.473464)
			(xy 112.16513 -250.480068) (xy 112.173004 -250.483116) (xy 112.177304 -250.484565) (xy 112.186247 -250.486103)
			(xy 112.190784 -250.486164) (xy 112.851692 -250.486164) (xy 112.860759 -250.485773) (xy 112.877716 -250.479345)
			(xy 112.89129 -250.467321) (xy 112.895888 -250.459494) (xy 112.935766 -250.383548) (xy 112.939969 -250.37455)
			(xy 112.941668 -250.354779) (xy 112.939068 -250.345194) (xy 112.933988 -250.328938) (xy 112.931448 -250.324874)
			(xy 112.929924 -250.322842) (xy 112.917952 -250.304052) (xy 112.899038 -250.263714) (xy 112.886206 -250.221049)
			(xy 112.879728 -250.17697) (xy 112.879378 -250.154694) (xy 112.879378 -250.15444) (xy 112.8799 -250.129185)
			(xy 112.888213 -250.079363) (xy 112.904614 -250.031589) (xy 112.928655 -249.987166) (xy 112.959679 -249.947306)
			(xy 112.996841 -249.913096) (xy 113.039127 -249.88547) (xy 113.085383 -249.86518) (xy 113.134348 -249.85278)
			(xy 113.184686 -249.848609) (xy 113.235024 -249.85278) (xy 113.283989 -249.86518) (xy 113.330245 -249.88547)
			(xy 113.372531 -249.913096) (xy 113.409693 -249.947306) (xy 113.440717 -249.987166) (xy 113.464758 -250.031589)
			(xy 113.481159 -250.079363) (xy 113.489472 -250.129185) (xy 113.489994 -250.15444) (xy 113.489565 -250.177589)
			(xy 113.482577 -250.223355) (xy 113.468768 -250.267545) (xy 113.448454 -250.309148) (xy 113.435638 -250.32843)
			(xy 113.42878 -250.338336) (xy 113.42751 -250.340114) (xy 113.426748 -250.354084) (xy 113.426496 -250.360912)
			(xy 113.42921 -250.374299) (xy 113.432082 -250.3805) (xy 113.434368 -250.384818) (xy 113.475008 -250.46178)
			(xy 113.47972 -250.468961) (xy 113.492965 -250.479876) (xy 113.509101 -250.485726) (xy 113.51768 -250.486164)
			(xy 114.7318 -250.486164) (xy 114.740866 -250.485772) (xy 114.757821 -250.479342) (xy 114.771393 -250.467317)
			(xy 114.775996 -250.459494) (xy 114.815874 -250.383548) (xy 114.820076 -250.37455) (xy 114.821775 -250.354779)
			(xy 114.819176 -250.345194) (xy 114.814096 -250.328938) (xy 114.811556 -250.324874) (xy 114.810032 -250.322842)
			(xy 114.79806 -250.304052) (xy 114.779146 -250.263714) (xy 114.766313 -250.22105) (xy 114.759835 -250.17697)
			(xy 114.759486 -250.154694) (xy 114.759486 -250.15444) (xy 114.760008 -250.129185) (xy 114.768321 -250.079363)
			(xy 114.784722 -250.031589) (xy 114.808763 -249.987166) (xy 114.839787 -249.947306) (xy 114.876949 -249.913096)
			(xy 114.919235 -249.88547) (xy 114.965491 -249.86518) (xy 115.014456 -249.85278) (xy 115.064794 -249.848609)
			(xy 115.115132 -249.85278) (xy 115.164097 -249.86518) (xy 115.210353 -249.88547) (xy 115.252639 -249.913096)
			(xy 115.289801 -249.947306) (xy 115.320825 -249.987166) (xy 115.344866 -250.031589) (xy 115.361267 -250.079363)
			(xy 115.36958 -250.129185) (xy 115.370102 -250.15444) (xy 116.638844 -250.15444) (xy 116.642804 -250.105386)
			(xy 116.654581 -250.057602) (xy 116.673872 -250.012326) (xy 116.700175 -249.97073) (xy 116.73281 -249.933893)
			(xy 116.770931 -249.902768) (xy 116.813552 -249.878161) (xy 116.859568 -249.860709) (xy 116.907787 -249.850865)
			(xy 116.956962 -249.848884) (xy 117.005817 -249.854816) (xy 117.053088 -249.868508) (xy 117.09755 -249.889606)
			(xy 117.138053 -249.917562) (xy 117.173546 -249.951654) (xy 117.203111 -249.990998) (xy 117.225982 -250.034575)
			(xy 117.241566 -250.081256) (xy 117.249461 -250.129833) (xy 117.249956 -250.15444) (xy 117.249461 -250.179047)
			(xy 117.241566 -250.227624) (xy 117.225982 -250.274305) (xy 117.203111 -250.317882) (xy 117.173546 -250.357226)
			(xy 117.138053 -250.391318) (xy 117.09755 -250.419274) (xy 117.053088 -250.440372) (xy 117.005817 -250.454064)
			(xy 116.956962 -250.459996) (xy 116.907787 -250.458015) (xy 116.859568 -250.448171) (xy 116.813552 -250.430719)
			(xy 116.770931 -250.406112) (xy 116.73281 -250.374987) (xy 116.700175 -250.33815) (xy 116.673872 -250.296554)
			(xy 116.654581 -250.251278) (xy 116.642804 -250.203494) (xy 116.638844 -250.15444) (xy 115.370102 -250.15444)
			(xy 115.369673 -250.177589) (xy 115.362685 -250.223356) (xy 115.348877 -250.267546) (xy 115.328563 -250.309148)
			(xy 115.315746 -250.32843) (xy 115.308888 -250.338336) (xy 115.307618 -250.340114) (xy 115.306856 -250.354084)
			(xy 115.306604 -250.360912) (xy 115.309319 -250.374299) (xy 115.31219 -250.3805) (xy 115.314476 -250.384818)
			(xy 115.355116 -250.46178) (xy 115.359828 -250.46896) (xy 115.373074 -250.479873) (xy 115.389209 -250.48572)
			(xy 115.397788 -250.486164) (xy 115.47729 -250.486164) (xy 115.487127 -250.486703) (xy 115.505286 -250.494291)
			(xy 115.512596 -250.500896) (xy 116.245132 -251.233432) (xy 116.248749 -251.236866) (xy 116.257067 -251.242367)
			(xy 116.261642 -251.244354) (xy 116.270532 -251.248164)
		)
		(stroke
			(width 0)
			(type solid)
		)
		(fill yes)
		(layer "In2.Cu")
		(net "PVDDCR_CPU0_P1")
	)
	(gr_poly
		(pts
			(xy 374.863106 -296.53357) (xy 374.87055 -296.540262) (xy 374.889047 -296.547858) (xy 374.909044 -296.54784)
			(xy 374.918478 -296.544492) (xy 374.932702 -296.53865) (xy 374.94972 -296.51325) (xy 374.94972 -296.400474)
			(xy 374.949186 -296.388075) (xy 374.937748 -296.366081) (xy 374.927876 -296.358564) (xy 374.907946 -296.344185)
			(xy 374.872528 -296.31012) (xy 374.843028 -296.27082) (xy 374.820208 -296.227299) (xy 374.804658 -296.180683)
			(xy 374.796781 -296.132177) (xy 374.79678 -296.083036) (xy 374.804655 -296.034531) (xy 374.820203 -295.987914)
			(xy 374.843021 -295.944392) (xy 374.872519 -295.90509) (xy 374.907936 -295.871024) (xy 374.927876 -295.85666)
			(xy 374.937589 -295.849) (xy 374.949006 -295.827099) (xy 374.94972 -295.81475) (xy 374.94972 -295.213278)
			(xy 374.949294 -295.203209) (xy 374.941576 -295.184609) (xy 374.934734 -295.17721) (xy 374.421146 -294.663622)
			(xy 374.410986 -294.655748) (xy 374.317006 -294.601392) (xy 374.309188 -294.59725) (xy 374.291806 -294.594031)
			(xy 374.274363 -294.596906) (xy 374.26646 -294.600884) (xy 374.266206 -294.601138) (xy 374.243182 -294.613662)
			(xy 374.193899 -294.631493) (xy 374.142294 -294.640637) (xy 374.116092 -294.64127) (xy 374.10898 -294.64127)
			(xy 374.084043 -294.640298) (xy 374.034969 -294.631246) (xy 373.98802 -294.614335) (xy 373.944446 -294.590013)
			(xy 373.905407 -294.55893) (xy 373.871942 -294.521912) (xy 373.844943 -294.479945) (xy 373.825127 -294.434147)
			(xy 373.813022 -294.385735) (xy 373.808952 -294.335999) (xy 373.813023 -294.286264) (xy 373.825127 -294.237852)
			(xy 373.844943 -294.192053) (xy 373.871943 -294.150086) (xy 373.905408 -294.113069) (xy 373.944447 -294.081986)
			(xy 373.988021 -294.057665) (xy 374.03497 -294.040753) (xy 374.084044 -294.031702) (xy 374.10898 -294.030654)
			(xy 374.115076 -294.030654) (xy 374.141448 -294.031231) (xy 374.193403 -294.040323) (xy 374.24303 -294.05819)
			(xy 374.266206 -294.070786) (xy 374.26646 -294.07104) (xy 374.274336 -294.075103) (xy 374.291806 -294.07801)
			(xy 374.309216 -294.074756) (xy 374.317006 -294.070532) (xy 374.392952 -294.02659) (xy 374.400443 -294.021809)
			(xy 374.411856 -294.008204) (xy 374.417953 -293.991526) (xy 374.418352 -293.982648) (xy 374.418352 -293.820088)
			(xy 374.418205 -293.814219) (xy 374.415518 -293.802794) (xy 374.413018 -293.797482) (xy 374.40108 -293.773098)
			(xy 374.39473 -293.76497) (xy 374.390412 -293.761414) (xy 374.371872 -293.745464) (xy 374.339625 -293.708699)
			(xy 374.313648 -293.667266) (xy 374.294605 -293.622222) (xy 374.282983 -293.574719) (xy 374.279078 -293.525972)
			(xy 374.282992 -293.477225) (xy 374.294622 -293.429725) (xy 374.313674 -293.384685) (xy 374.339658 -293.343256)
			(xy 374.371912 -293.306497) (xy 374.390412 -293.290498) (xy 374.39473 -293.286942) (xy 374.40108 -293.278814)
			(xy 374.413018 -293.25443) (xy 374.415475 -293.249103) (xy 374.418161 -293.237687) (xy 374.418352 -293.231824)
			(xy 374.418352 -293.178738) (xy 374.41378 -293.16426) (xy 374.409462 -293.15791) (xy 374.392519 -293.132813)
			(xy 374.362133 -293.080428) (xy 374.348756 -293.053262) (xy 374.344692 -293.04488) (xy 374.33758 -293.038276)
			(xy 374.334075 -293.035121) (xy 374.32615 -293.030011) (xy 374.321832 -293.028116) (xy 374.249442 -292.998906)
			(xy 374.230392 -292.998652) (xy 374.221502 -293.001954) (xy 374.195752 -293.010945) (xy 374.14209 -293.020662)
			(xy 374.114822 -293.021258) (xy 374.089559 -293.020767) (xy 374.039722 -293.012454) (xy 373.991932 -292.996051)
			(xy 373.947495 -292.972005) (xy 373.907621 -292.940973) (xy 373.8734 -292.903801) (xy 373.845763 -292.861503)
			(xy 373.825467 -292.815233) (xy 373.813063 -292.766253) (xy 373.80889 -292.7159) (xy 373.813063 -292.665547)
			(xy 373.825467 -292.616567) (xy 373.845763 -292.570297) (xy 373.8734 -292.527999) (xy 373.907621 -292.490827)
			(xy 373.947495 -292.459795) (xy 373.991932 -292.435749) (xy 374.039722 -292.419346) (xy 374.089559 -292.411033)
			(xy 374.114822 -292.410642) (xy 374.142087 -292.411265) (xy 374.195749 -292.42097) (xy 374.221502 -292.429946)
			(xy 374.230392 -292.433248) (xy 374.249442 -292.432994) (xy 374.321578 -292.40353) (xy 374.325913 -292.401665)
			(xy 374.333844 -292.396554) (xy 374.337326 -292.39337) (xy 374.344438 -292.386766) (xy 374.348502 -292.378384)
			(xy 374.358989 -292.35682) (xy 374.382245 -292.314879) (xy 374.394984 -292.294564) (xy 374.409462 -292.27272)
			(xy 374.409462 -292.272466) (xy 374.413519 -292.266059) (xy 374.41805 -292.251595) (xy 374.418352 -292.244018)
			(xy 374.418352 -292.200076) (xy 374.418204 -292.194207) (xy 374.415514 -292.182783) (xy 374.413018 -292.17747)
			(xy 374.40108 -292.153086) (xy 374.39473 -292.144958) (xy 374.390412 -292.141402) (xy 374.371865 -292.125452)
			(xy 374.339604 -292.088685) (xy 374.313613 -292.047247) (xy 374.294558 -292.002197) (xy 374.282925 -291.954686)
			(xy 374.27901 -291.905928) (xy 374.282916 -291.85717) (xy 374.29454 -291.809657) (xy 374.313587 -291.764603)
			(xy 374.33957 -291.72316) (xy 374.371825 -291.686387) (xy 374.390412 -291.670486) (xy 374.39473 -291.66693)
			(xy 374.40108 -291.658802) (xy 374.413018 -291.634418) (xy 374.415474 -291.629091) (xy 374.418157 -291.617675)
			(xy 374.418352 -291.611812) (xy 374.418352 -291.558726) (xy 374.41378 -291.544248) (xy 374.409462 -291.537898)
			(xy 374.392519 -291.512801) (xy 374.362134 -291.460416) (xy 374.348756 -291.43325) (xy 374.344692 -291.424614)
			(xy 374.330722 -291.41166) (xy 374.249696 -291.379148) (xy 374.2309 -291.378894) (xy 374.22201 -291.382196)
			(xy 374.196133 -291.391202) (xy 374.142215 -291.400909) (xy 374.114822 -291.4015) (xy 373.174768 -291.4015)
			(xy 373.14949 -291.400975) (xy 373.099625 -291.39265) (xy 373.05181 -291.37623) (xy 373.007349 -291.352165)
			(xy 372.967456 -291.321111) (xy 372.933217 -291.283914) (xy 372.905568 -291.24159) (xy 372.885261 -291.195292)
			(xy 372.872851 -291.146283) (xy 372.868676 -291.0959) (xy 372.872851 -291.045517) (xy 372.885261 -290.996508)
			(xy 372.905568 -290.95021) (xy 372.933217 -290.907886) (xy 372.967456 -290.870689) (xy 373.007349 -290.839635)
			(xy 373.05181 -290.81557) (xy 373.099625 -290.79915) (xy 373.14949 -290.790825) (xy 373.174768 -290.790376)
			(xy 374.114822 -290.790376) (xy 374.142024 -290.791013) (xy 374.195558 -290.800716) (xy 374.221248 -290.80968)
			(xy 374.230392 -290.812982) (xy 374.249188 -290.812728) (xy 374.330468 -290.779962) (xy 374.344438 -290.767008)
			(xy 374.348502 -290.758372) (xy 374.358989 -290.736808) (xy 374.382246 -290.694868) (xy 374.394984 -290.674552)
			(xy 374.409462 -290.652708) (xy 374.409462 -290.652454) (xy 374.413517 -290.646046) (xy 374.418045 -290.631582)
			(xy 374.418352 -290.624006) (xy 374.418352 -290.599622) (xy 374.417805 -290.587232) (xy 374.406344 -290.565268)
			(xy 374.396508 -290.557712) (xy 374.374927 -290.542137) (xy 374.336573 -290.505241) (xy 374.304628 -290.462677)
			(xy 374.279917 -290.415543) (xy 374.263078 -290.365058) (xy 374.254547 -290.312528) (xy 374.254544 -290.259309)
			(xy 374.263069 -290.206777) (xy 374.279902 -290.156291) (xy 374.304609 -290.109154) (xy 374.336549 -290.066586)
			(xy 374.374898 -290.029686) (xy 374.396508 -290.014152) (xy 374.406215 -290.006488) (xy 374.417621 -289.984589)
			(xy 374.418352 -289.972242) (xy 374.418352 -289.947858) (xy 374.418037 -289.940282) (xy 374.413518 -289.925817)
			(xy 374.409462 -289.91941) (xy 374.409462 -289.919156) (xy 374.394984 -289.897312) (xy 374.382248 -289.876995)
			(xy 374.358993 -289.835054) (xy 374.348502 -289.813492) (xy 374.344438 -289.804856) (xy 374.330468 -289.791902)
			(xy 374.249188 -289.759136) (xy 374.230392 -289.758882) (xy 374.221502 -289.762184) (xy 374.195812 -289.771151)
			(xy 374.142279 -289.780865) (xy 374.115076 -289.781488) (xy 373.174768 -289.781488) (xy 373.149491 -289.780963)
			(xy 373.099628 -289.772638) (xy 373.051815 -289.756219) (xy 373.007356 -289.732155) (xy 372.967464 -289.701102)
			(xy 372.933227 -289.663907) (xy 372.905578 -289.621584) (xy 372.885272 -289.575288) (xy 372.872863 -289.526281)
			(xy 372.868688 -289.4759) (xy 372.872863 -289.425519) (xy 372.885272 -289.376512) (xy 372.905578 -289.330216)
			(xy 372.933227 -289.287893) (xy 372.967464 -289.250698) (xy 373.007356 -289.219645) (xy 373.051815 -289.195581)
			(xy 373.099628 -289.179162) (xy 373.149491 -289.170837) (xy 373.174768 -289.170364) (xy 374.114822 -289.170364)
			(xy 374.130497 -289.170618) (xy 374.161673 -289.173928) (xy 374.177052 -289.176968) (xy 374.177306 -289.176968)
			(xy 374.188621 -289.179467) (xy 374.21087 -289.185949) (xy 374.221756 -289.189922) (xy 374.2309 -289.193224)
			(xy 374.249696 -289.19297) (xy 374.330976 -289.160204) (xy 374.344946 -289.14725) (xy 374.34901 -289.138614)
			(xy 374.360694 -289.115246) (xy 374.3718 -289.094417) (xy 374.396201 -289.054002) (xy 374.409462 -289.034474)
			(xy 374.41378 -289.02787) (xy 374.418352 -289.013646) (xy 374.418352 -288.960052) (xy 374.418201 -288.954184)
			(xy 374.415506 -288.942762) (xy 374.413018 -288.937446) (xy 374.40108 -288.913062) (xy 374.39473 -288.904934)
			(xy 374.390412 -288.901378) (xy 374.371867 -288.885428) (xy 374.339609 -288.848661) (xy 374.313623 -288.807225)
			(xy 374.294571 -288.762176) (xy 374.28294 -288.714668) (xy 374.279029 -288.665913) (xy 374.282936 -288.617158)
			(xy 374.294563 -288.569648) (xy 374.313611 -288.524598) (xy 374.339594 -288.483159) (xy 374.371849 -288.44639)
			(xy 374.390412 -288.430462) (xy 374.39473 -288.426906) (xy 374.40108 -288.418778) (xy 374.413018 -288.394394)
			(xy 374.415482 -288.389069) (xy 374.418181 -288.377653) (xy 374.418352 -288.371788) (xy 374.418352 -288.318702)
			(xy 374.41378 -288.304224) (xy 374.409462 -288.297874) (xy 374.401842 -288.286698) (xy 374.387172 -288.264152)
			(xy 374.360602 -288.217376) (xy 374.348756 -288.193226) (xy 374.344438 -288.184844) (xy 374.330722 -288.17189)
			(xy 374.249696 -288.139124) (xy 374.2309 -288.13887) (xy 374.221756 -288.142172) (xy 374.195955 -288.151214)
			(xy 374.142156 -288.160926) (xy 374.114822 -288.161476) (xy 373.174768 -288.161476) (xy 373.149517 -288.160952)
			(xy 373.099705 -288.152635) (xy 373.05194 -288.136233) (xy 373.007527 -288.112194) (xy 372.967676 -288.081172)
			(xy 372.933473 -288.044015) (xy 372.905853 -288.001735) (xy 372.885568 -287.955486) (xy 372.873171 -287.90653)
			(xy 372.869001 -287.8562) (xy 372.873171 -287.80587) (xy 372.885568 -287.756914) (xy 372.905853 -287.710665)
			(xy 372.933473 -287.668385) (xy 372.967676 -287.631228) (xy 373.007527 -287.600206) (xy 373.05194 -287.576167)
			(xy 373.099705 -287.559765) (xy 373.149517 -287.551448) (xy 373.174768 -287.55086) (xy 374.114822 -287.55086)
			(xy 374.133749 -287.551096) (xy 374.171324 -287.55568) (xy 374.189752 -287.560004) (xy 374.190006 -287.560004)
			(xy 374.221502 -287.56991) (xy 374.230392 -287.573212) (xy 374.249188 -287.572958) (xy 374.330468 -287.540192)
			(xy 374.344438 -287.527238) (xy 374.348502 -287.518602) (xy 374.358988 -287.497037) (xy 374.382244 -287.455096)
			(xy 374.394984 -287.434782) (xy 374.409462 -287.412938) (xy 374.409462 -287.412684) (xy 374.413508 -287.406274)
			(xy 374.418016 -287.39181) (xy 374.418352 -287.384236) (xy 374.418352 -287.359598) (xy 374.417799 -287.34721)
			(xy 374.406333 -287.325256) (xy 374.396508 -287.317688) (xy 374.374928 -287.302113) (xy 374.336579 -287.265218)
			(xy 374.304637 -287.222655) (xy 374.279929 -287.175523) (xy 374.263094 -287.12504) (xy 374.254565 -287.072512)
			(xy 374.254564 -287.019297) (xy 374.263091 -286.966769) (xy 374.279926 -286.916286) (xy 374.304633 -286.869153)
			(xy 374.336573 -286.826589) (xy 374.374921 -286.789693) (xy 374.396508 -286.774128) (xy 374.406211 -286.766463)
			(xy 374.417607 -286.744563) (xy 374.418352 -286.732218) (xy 374.418352 -286.69869) (xy 374.41378 -286.684212)
			(xy 374.409462 -286.677862) (xy 374.401842 -286.666686) (xy 374.387172 -286.64414) (xy 374.360603 -286.597363)
			(xy 374.348756 -286.573214) (xy 374.344438 -286.564832) (xy 374.330722 -286.551878) (xy 374.249696 -286.519112)
			(xy 374.2309 -286.518858) (xy 374.221756 -286.52216) (xy 374.195955 -286.531202) (xy 374.142156 -286.540915)
			(xy 374.114822 -286.541464) (xy 373.174768 -286.541464) (xy 373.149518 -286.54094) (xy 373.099708 -286.532623)
			(xy 373.051945 -286.516222) (xy 373.007533 -286.492184) (xy 372.967684 -286.461163) (xy 372.933483 -286.424008)
			(xy 372.905864 -286.38173) (xy 372.885579 -286.335482) (xy 372.873183 -286.286528) (xy 372.869013 -286.2362)
			(xy 372.873183 -286.185872) (xy 372.885579 -286.136918) (xy 372.905864 -286.09067) (xy 372.933483 -286.048392)
			(xy 372.967684 -286.011237) (xy 373.007533 -285.980216) (xy 373.051945 -285.956178) (xy 373.099708 -285.939777)
			(xy 373.149518 -285.93146) (xy 373.174768 -285.930848) (xy 374.114822 -285.930848) (xy 374.142015 -285.931416)
			(xy 374.195549 -285.940992) (xy 374.221248 -285.949898) (xy 374.230138 -285.9532) (xy 374.249188 -285.952946)
			(xy 374.330468 -285.92018) (xy 374.344184 -285.907226) (xy 374.348502 -285.89859) (xy 374.361921 -285.871164)
			(xy 374.392437 -285.818272) (xy 374.409462 -285.792926) (xy 374.413526 -285.78683) (xy 374.415812 -285.779718)
			(xy 374.416958 -285.775945) (xy 374.418233 -285.768165) (xy 374.418352 -285.764224) (xy 374.418352 -285.720282)
			(xy 374.418205 -285.714413) (xy 374.415516 -285.702988) (xy 374.413018 -285.697676) (xy 374.40108 -285.673292)
			(xy 374.39473 -285.665164) (xy 374.390412 -285.661608) (xy 374.371873 -285.645658) (xy 374.339626 -285.608893)
			(xy 374.31365 -285.56746) (xy 374.294608 -285.522417) (xy 374.282987 -285.474915) (xy 374.279083 -285.426168)
			(xy 374.282997 -285.377422) (xy 374.294628 -285.329923) (xy 374.313679 -285.284883) (xy 374.339664 -285.243455)
			(xy 374.371918 -285.206697) (xy 374.390412 -285.190692) (xy 374.39473 -285.187136) (xy 374.40108 -285.179008)
			(xy 374.413018 -285.154624) (xy 374.415474 -285.149297) (xy 374.418159 -285.137881) (xy 374.418352 -285.132018)
			(xy 374.418352 -285.088584) (xy 374.417082 -285.077154) (xy 374.414288 -285.064962) (xy 374.4087 -285.057088)
			(xy 374.400488 -285.045028) (xy 374.384862 -285.020384) (xy 374.377458 -285.007812) (xy 374.369669 -284.994231)
			(xy 374.355061 -284.966536) (xy 374.348248 -284.95244) (xy 374.34393 -284.944058) (xy 374.330214 -284.931104)
			(xy 374.250458 -284.898846) (xy 374.231662 -284.898592) (xy 374.222518 -284.901894) (xy 374.196538 -284.91103)
			(xy 374.142356 -284.920864) (xy 374.114822 -284.921452) (xy 373.174768 -284.921452) (xy 373.149511 -284.920928)
			(xy 373.099686 -284.912609) (xy 373.05191 -284.896203) (xy 373.007485 -284.872158) (xy 372.967624 -284.841128)
			(xy 372.933413 -284.803962) (xy 372.905786 -284.761672) (xy 372.885495 -284.715411) (xy 372.873096 -284.666442)
			(xy 372.868924 -284.6161) (xy 372.873096 -284.565758) (xy 372.885495 -284.516789) (xy 372.905786 -284.470528)
			(xy 372.933413 -284.428238) (xy 372.967624 -284.391072) (xy 373.007485 -284.360042) (xy 373.05191 -284.335997)
			(xy 373.099686 -284.319591) (xy 373.149511 -284.311272) (xy 373.174768 -284.310836) (xy 374.114822 -284.310836)
			(xy 374.142294 -284.311416) (xy 374.19635 -284.321256) (xy 374.222264 -284.330394) (xy 374.231154 -284.333442)
			(xy 374.240552 -284.333442) (xy 374.245251 -284.33325) (xy 374.254458 -284.331338) (xy 374.25884 -284.329632)
			(xy 374.330214 -284.30093) (xy 374.34393 -284.287976) (xy 374.347994 -284.27934) (xy 374.365524 -284.24376)
			(xy 374.406744 -284.175988) (xy 374.454604 -284.112732) (xy 374.508615 -284.054638) (xy 374.568222 -284.002303)
			(xy 374.600216 -283.978858) (xy 374.624854 -283.962856) (xy 374.662954 -283.940758) (xy 374.663208 -283.940504)
			(xy 374.678956 -283.93136) (xy 374.685814 -283.92628) (xy 374.701099 -283.912591) (xy 374.724642 -283.879006)
			(xy 374.7387 -283.840476) (xy 374.741186 -283.820108) (xy 374.741694 -283.806138) (xy 374.741694 -283.804868)
			(xy 374.741948 -283.802582) (xy 374.741948 -283.799026) (xy 374.741694 -283.79674) (xy 374.73998 -283.777896)
			(xy 374.728542 -283.741839) (xy 374.70868 -283.709646) (xy 374.681586 -283.683248) (xy 374.665494 -283.673296)
			(xy 374.6627 -283.671772) (xy 374.65889 -283.669486) (xy 374.658382 -283.668978) (xy 374.655842 -283.667454)
			(xy 374.653556 -283.666184) (xy 374.653302 -283.66593) (xy 374.620712 -283.646045) (xy 374.559185 -283.600842)
			(xy 374.502374 -283.549837) (xy 374.450824 -283.493519) (xy 374.405029 -283.43243) (xy 374.36543 -283.367155)
			(xy 374.348502 -283.332936) (xy 374.348248 -283.332682) (xy 374.343801 -283.324387) (xy 374.33012 -283.311488)
			(xy 374.321578 -283.307536) (xy 374.250458 -283.278834) (xy 374.231662 -283.27858) (xy 374.222518 -283.281882)
			(xy 374.196538 -283.291019) (xy 374.142356 -283.300853) (xy 374.114822 -283.30144) (xy 373.174768 -283.30144)
			(xy 373.149512 -283.300916) (xy 373.099689 -283.292597) (xy 373.051915 -283.276192) (xy 373.007492 -283.252147)
			(xy 372.967632 -283.221119) (xy 372.933423 -283.183954) (xy 372.905797 -283.141666) (xy 372.885507 -283.095407)
			(xy 372.873108 -283.04644) (xy 372.868937 -282.9961) (xy 372.873108 -282.94576) (xy 372.885507 -282.896793)
			(xy 372.905797 -282.850534) (xy 372.933423 -282.808246) (xy 372.967632 -282.771081) (xy 373.007492 -282.740053)
			(xy 373.051915 -282.716008) (xy 373.099689 -282.699603) (xy 373.149512 -282.691284) (xy 373.174768 -282.690824)
			(xy 374.114822 -282.690824) (xy 374.142294 -282.691404) (xy 374.19635 -282.701244) (xy 374.222264 -282.710382)
			(xy 374.231154 -282.71343) (xy 374.240552 -282.71343) (xy 374.245251 -282.713238) (xy 374.254458 -282.711326)
			(xy 374.25884 -282.70962) (xy 374.32107 -282.684474) (xy 374.329725 -282.680622) (xy 374.343561 -282.667701)
			(xy 374.347994 -282.659328) (xy 374.347994 -282.659074) (xy 374.361264 -282.631988) (xy 374.391395 -282.579732)
			(xy 374.408192 -282.55468) (xy 374.413526 -282.546806) (xy 374.417844 -282.528518) (xy 374.405906 -282.443174)
			(xy 374.397016 -282.427172) (xy 374.389396 -282.420822) (xy 374.36916 -282.403259) (xy 374.334585 -282.362329)
			(xy 374.307683 -282.315993) (xy 374.289282 -282.265674) (xy 374.279944 -282.212915) (xy 374.279414 -282.186126)
			(xy 374.279976 -282.159286) (xy 374.289361 -282.106434) (xy 374.307845 -282.056037) (xy 374.334861 -282.009651)
			(xy 374.369573 -281.968706) (xy 374.389904 -281.951176) (xy 374.39727 -281.94508) (xy 374.406414 -281.92857)
			(xy 374.417082 -281.852624) (xy 374.417618 -281.847987) (xy 374.417227 -281.838662) (xy 374.41632 -281.834082)
			(xy 374.414034 -281.824684) (xy 374.404355 -281.810811) (xy 374.386062 -281.782352) (xy 374.377458 -281.767788)
			(xy 374.369668 -281.754207) (xy 374.355058 -281.726513) (xy 374.348248 -281.712416) (xy 374.34393 -281.704034)
			(xy 374.330214 -281.69108) (xy 374.250458 -281.658822) (xy 374.231662 -281.658568) (xy 374.222518 -281.66187)
			(xy 374.196537 -281.671004) (xy 374.142355 -281.680835) (xy 374.114822 -281.681428) (xy 373.174768 -281.681428)
			(xy 373.149513 -281.680904) (xy 373.099692 -281.672585) (xy 373.051919 -281.656181) (xy 373.007498 -281.632137)
			(xy 372.96764 -281.60111) (xy 372.933432 -281.563947) (xy 372.905807 -281.52166) (xy 372.885519 -281.475403)
			(xy 372.87312 -281.426438) (xy 372.868949 -281.3761) (xy 372.87312 -281.325762) (xy 372.885519 -281.276797)
			(xy 372.905807 -281.23054) (xy 372.933432 -281.188253) (xy 372.96764 -281.15109) (xy 373.007498 -281.120063)
			(xy 373.051919 -281.096019) (xy 373.099692 -281.079615) (xy 373.149513 -281.071296) (xy 373.174768 -281.070812)
			(xy 374.114822 -281.070812) (xy 374.142294 -281.071392) (xy 374.19635 -281.081231) (xy 374.222264 -281.09037)
			(xy 374.231154 -281.093418) (xy 374.240552 -281.093418) (xy 374.245251 -281.093226) (xy 374.254458 -281.091313)
			(xy 374.25884 -281.089608) (xy 374.32107 -281.064462) (xy 374.329724 -281.060609) (xy 374.343558 -281.047687)
			(xy 374.347994 -281.039316) (xy 374.347994 -281.039062) (xy 374.361264 -281.011976) (xy 374.391396 -280.959721)
			(xy 374.408192 -280.934668) (xy 374.413526 -280.926794) (xy 374.417844 -280.908506) (xy 374.405906 -280.823162)
			(xy 374.397016 -280.80716) (xy 374.389396 -280.80081) (xy 374.36916 -280.783247) (xy 374.334587 -280.742316)
			(xy 374.307688 -280.695981) (xy 374.289288 -280.645661) (xy 374.279952 -280.592903) (xy 374.279414 -280.566114)
			(xy 374.279977 -280.539275) (xy 374.289363 -280.486423) (xy 374.30785 -280.436028) (xy 374.334866 -280.389644)
			(xy 374.369578 -280.3487) (xy 374.389904 -280.331164) (xy 374.39727 -280.325068) (xy 374.406414 -280.308558)
			(xy 374.417082 -280.232612) (xy 374.417626 -280.227974) (xy 374.41725 -280.218646) (xy 374.41632 -280.21407)
			(xy 374.414034 -280.204672) (xy 374.404354 -280.1908) (xy 374.386058 -280.162342) (xy 374.377458 -280.147776)
			(xy 374.369668 -280.134195) (xy 374.355058 -280.106501) (xy 374.348248 -280.092404) (xy 374.34393 -280.084022)
			(xy 374.330214 -280.071068) (xy 374.259094 -280.042366) (xy 374.250182 -280.039162) (xy 374.231258 -280.038892)
			(xy 374.222264 -280.041858) (xy 374.196336 -280.050944) (xy 374.142289 -280.060782) (xy 374.114822 -280.061416)
			(xy 374.110758 -280.061416) (xy 374.086977 -280.060646) (xy 374.040077 -280.052642) (xy 373.994987 -280.037459)
			(xy 373.952799 -280.015463) (xy 373.914535 -279.987188) (xy 373.881121 -279.953318) (xy 373.853367 -279.914674)
			(xy 373.831944 -279.872192) (xy 373.817373 -279.826901) (xy 373.810005 -279.779897) (xy 373.809514 -279.756108)
			(xy 373.80996 -279.732115) (xy 373.817465 -279.68472) (xy 373.832294 -279.639083) (xy 373.854079 -279.596327)
			(xy 373.882285 -279.557506) (xy 373.916217 -279.523576) (xy 373.955039 -279.495372) (xy 373.997796 -279.473588)
			(xy 374.043434 -279.458762) (xy 374.090829 -279.451259) (xy 374.114822 -279.4508) (xy 374.115584 -279.4508)
			(xy 374.142848 -279.451429) (xy 374.196505 -279.461146) (xy 374.222264 -279.470104) (xy 374.231154 -279.47366)
			(xy 374.250204 -279.473406) (xy 374.330214 -279.440894) (xy 374.34393 -279.42794) (xy 374.347994 -279.419304)
			(xy 374.365522 -279.383722) (xy 374.406737 -279.315946) (xy 374.454594 -279.252686) (xy 374.508603 -279.194588)
			(xy 374.568209 -279.142249) (xy 374.600216 -279.118822) (xy 374.624854 -279.10282) (xy 374.65381 -279.086056)
			(xy 374.659652 -279.0825) (xy 374.659906 -279.082246) (xy 374.663208 -279.080468) (xy 374.664224 -279.079706)
			(xy 374.664986 -279.079452) (xy 374.685306 -279.065228) (xy 374.698207 -279.054079) (xy 374.719205 -279.027222)
			(xy 374.733792 -278.99641) (xy 374.741257 -278.963147) (xy 374.741694 -278.946102) (xy 374.741694 -278.940514)
			(xy 374.740643 -278.923366) (xy 374.732019 -278.890118) (xy 374.7164 -278.859526) (xy 374.694528 -278.833041)
			(xy 374.681242 -278.82215) (xy 374.673368 -278.817578) (xy 374.672606 -278.81707) (xy 374.656096 -278.807672)
			(xy 374.655334 -278.807164) (xy 374.622495 -278.787268) (xy 374.560507 -278.74195) (xy 374.503282 -278.69075)
			(xy 374.451376 -278.634164) (xy 374.405293 -278.572743) (xy 374.36548 -278.507084) (xy 374.348502 -278.472646)
			(xy 374.348248 -278.472646) (xy 374.343808 -278.464344) (xy 374.330132 -278.45143) (xy 374.321578 -278.4475)
			(xy 374.250458 -278.418798) (xy 374.231408 -278.418544) (xy 374.222518 -278.421846) (xy 374.196589 -278.430928)
			(xy 374.142542 -278.440759) (xy 374.115076 -278.441404) (xy 373.174768 -278.441404) (xy 373.149515 -278.44088)
			(xy 373.099698 -278.432562) (xy 373.051929 -278.416159) (xy 373.007512 -278.392117) (xy 372.967657 -278.361093)
			(xy 372.933451 -278.323932) (xy 372.905828 -278.281649) (xy 372.885541 -278.235395) (xy 372.873144 -278.186434)
			(xy 372.868973 -278.1361) (xy 372.873144 -278.085766) (xy 372.885541 -278.036805) (xy 372.905828 -277.990551)
			(xy 372.933451 -277.948268) (xy 372.967657 -277.911107) (xy 373.007512 -277.880083) (xy 373.051929 -277.856041)
			(xy 373.099698 -277.839638) (xy 373.149515 -277.83132) (xy 373.174768 -277.830788) (xy 374.114822 -277.830788)
			(xy 374.142149 -277.83141) (xy 374.195934 -277.841126) (xy 374.221756 -277.850092) (xy 374.22201 -277.850092)
			(xy 374.231154 -277.853394) (xy 374.240552 -277.853394) (xy 374.245251 -277.853202) (xy 374.254457 -277.851288)
			(xy 374.25884 -277.849584) (xy 374.32107 -277.824438) (xy 374.329722 -277.820583) (xy 374.34355 -277.807658)
			(xy 374.347994 -277.799292) (xy 374.347994 -277.799038) (xy 374.361265 -277.771953) (xy 374.391398 -277.719698)
			(xy 374.408192 -277.694644) (xy 374.413526 -277.68677) (xy 374.417844 -277.668482) (xy 374.405906 -277.583138)
			(xy 374.397016 -277.567136) (xy 374.389396 -277.560786) (xy 374.369162 -277.543222) (xy 374.334592 -277.502291)
			(xy 374.307696 -277.455955) (xy 374.2893 -277.405636) (xy 374.279968 -277.352878) (xy 374.279414 -277.32609)
			(xy 374.279979 -277.299252) (xy 374.289369 -277.246403) (xy 374.307858 -277.196011) (xy 374.334876 -277.149629)
			(xy 374.36959 -277.108689) (xy 374.389904 -277.09114) (xy 374.39727 -277.085044) (xy 374.406414 -277.068534)
			(xy 374.417082 -276.992588) (xy 374.417624 -276.987951) (xy 374.417244 -276.978623) (xy 374.41632 -276.974046)
			(xy 374.414034 -276.964648) (xy 374.404354 -276.950776) (xy 374.386059 -276.922318) (xy 374.377458 -276.907752)
			(xy 374.369669 -276.894171) (xy 374.35506 -276.866477) (xy 374.348248 -276.85238) (xy 374.34393 -276.843998)
			(xy 374.330214 -276.831044) (xy 374.250458 -276.798786) (xy 374.231408 -276.798532) (xy 374.222518 -276.801834)
			(xy 374.196589 -276.810917) (xy 374.142542 -276.820748) (xy 374.115076 -276.821392) (xy 373.174768 -276.821392)
			(xy 373.149516 -276.820868) (xy 373.099701 -276.812551) (xy 373.051934 -276.796148) (xy 373.007518 -276.772107)
			(xy 372.967665 -276.741084) (xy 372.933461 -276.703925) (xy 372.905839 -276.661643) (xy 372.885553 -276.615392)
			(xy 372.873155 -276.566432) (xy 372.868985 -276.5161) (xy 372.873155 -276.465768) (xy 372.885553 -276.416808)
			(xy 372.905839 -276.370557) (xy 372.933461 -276.328275) (xy 372.967665 -276.291116) (xy 373.007518 -276.260093)
			(xy 373.051934 -276.236052) (xy 373.099701 -276.219649) (xy 373.149516 -276.211332) (xy 373.174768 -276.210776)
			(xy 374.114822 -276.210776) (xy 374.142149 -276.211398) (xy 374.195934 -276.221113) (xy 374.221756 -276.23008)
			(xy 374.22201 -276.23008) (xy 374.231154 -276.233382) (xy 374.240552 -276.233382) (xy 374.245251 -276.23319)
			(xy 374.254459 -276.23128) (xy 374.25884 -276.229572) (xy 374.330214 -276.20087) (xy 374.34393 -276.187916)
			(xy 374.347994 -276.17928) (xy 374.365523 -276.143699) (xy 374.40674 -276.075925) (xy 374.454598 -276.012665)
			(xy 374.508607 -275.954569) (xy 374.568214 -275.902232) (xy 374.600216 -275.878798) (xy 374.624854 -275.862796)
			(xy 374.65381 -275.846032) (xy 374.659652 -275.842476) (xy 374.659906 -275.842222) (xy 374.663208 -275.840444)
			(xy 374.664224 -275.839682) (xy 374.664986 -275.839428) (xy 374.685306 -275.825204) (xy 374.698205 -275.814054)
			(xy 374.719198 -275.787197) (xy 374.733781 -275.756385) (xy 374.741241 -275.723123) (xy 374.741694 -275.706078)
			(xy 374.741694 -275.70049) (xy 374.740641 -275.683343) (xy 374.732013 -275.650098) (xy 374.716391 -275.61951)
			(xy 374.694517 -275.59303) (xy 374.681242 -275.582126) (xy 374.673368 -275.577554) (xy 374.672606 -275.577046)
			(xy 374.656096 -275.567648) (xy 374.655334 -275.56714) (xy 374.622495 -275.547244) (xy 374.560509 -275.501925)
			(xy 374.503285 -275.450724) (xy 374.45138 -275.394137) (xy 374.405299 -275.332716) (xy 374.365488 -275.267056)
			(xy 374.348502 -275.232622) (xy 374.348248 -275.232622) (xy 374.343805 -275.224323) (xy 374.330127 -275.211414)
			(xy 374.321578 -275.207476) (xy 374.250458 -275.178774) (xy 374.231408 -275.17852) (xy 374.222518 -275.181822)
			(xy 374.196589 -275.190905) (xy 374.142542 -275.200736) (xy 374.115076 -275.20138) (xy 373.174768 -275.20138)
			(xy 373.149517 -275.200856) (xy 373.099704 -275.192539) (xy 373.051939 -275.176137) (xy 373.007525 -275.152097)
			(xy 372.967673 -275.121075) (xy 372.93347 -275.083917) (xy 372.905849 -275.041637) (xy 372.885564 -274.995388)
			(xy 372.873167 -274.94643) (xy 372.868997 -274.8961) (xy 372.873167 -274.84577) (xy 372.885564 -274.796812)
			(xy 372.905849 -274.750563) (xy 372.93347 -274.708283) (xy 372.967673 -274.671125) (xy 373.007525 -274.640103)
			(xy 373.051939 -274.616063) (xy 373.099704 -274.599661) (xy 373.149517 -274.591344) (xy 373.174768 -274.590764)
			(xy 374.114822 -274.590764) (xy 374.142149 -274.591387) (xy 374.195933 -274.601105) (xy 374.221756 -274.610068)
			(xy 374.22201 -274.610068) (xy 374.231154 -274.61337) (xy 374.240552 -274.61337) (xy 374.245251 -274.613178)
			(xy 374.254458 -274.611268) (xy 374.25884 -274.60956) (xy 374.32107 -274.584414) (xy 374.329721 -274.580558)
			(xy 374.343543 -274.56763) (xy 374.347994 -274.559268) (xy 374.347994 -274.559014) (xy 374.361266 -274.531929)
			(xy 374.3914 -274.479675) (xy 374.408192 -274.45462) (xy 374.413526 -274.446746) (xy 374.417844 -274.428458)
			(xy 374.405906 -274.343114) (xy 374.397016 -274.327112) (xy 374.389396 -274.320762) (xy 374.369164 -274.303197)
			(xy 374.334597 -274.262265) (xy 374.307705 -274.215929) (xy 374.289313 -274.16561) (xy 374.279985 -274.112854)
			(xy 374.279414 -274.086066) (xy 374.279981 -274.059229) (xy 374.289375 -274.006382) (xy 374.307866 -273.955993)
			(xy 374.334886 -273.909615) (xy 374.369602 -273.868677) (xy 374.389904 -273.851116) (xy 374.39727 -273.84502)
			(xy 374.406414 -273.82851) (xy 374.417082 -273.752564) (xy 374.417622 -273.747927) (xy 374.417237 -273.7386)
			(xy 374.41632 -273.734022) (xy 374.414034 -273.724624) (xy 374.404355 -273.710751) (xy 374.38606 -273.682293)
			(xy 374.377458 -273.667728) (xy 374.369669 -273.654147) (xy 374.355061 -273.626452) (xy 374.348248 -273.612356)
			(xy 374.34393 -273.603974) (xy 374.330214 -273.59102) (xy 374.250458 -273.558762) (xy 374.231408 -273.558508)
			(xy 374.222518 -273.56181) (xy 374.196589 -273.570893) (xy 374.142543 -273.580725) (xy 374.115076 -273.581368)
			(xy 373.174768 -273.581368) (xy 373.149518 -273.580844) (xy 373.099707 -273.572527) (xy 373.051944 -273.556126)
			(xy 373.007531 -273.532087) (xy 372.967681 -273.501066) (xy 372.93348 -273.46391) (xy 372.90586 -273.421632)
			(xy 372.885575 -273.375384) (xy 372.873179 -273.326428) (xy 372.869009 -273.2761) (xy 372.873179 -273.225772)
			(xy 372.885575 -273.176816) (xy 372.90586 -273.130568) (xy 372.93348 -273.08829) (xy 372.967681 -273.051134)
			(xy 373.007531 -273.020113) (xy 373.051944 -272.996074) (xy 373.099707 -272.979673) (xy 373.149518 -272.971356)
			(xy 373.174768 -272.970752) (xy 374.114822 -272.970752) (xy 374.142149 -272.971374) (xy 374.195933 -272.981092)
			(xy 374.221756 -272.990056) (xy 374.22201 -272.990056) (xy 374.231154 -272.993358) (xy 374.240552 -272.993358)
			(xy 374.245251 -272.993166) (xy 374.254458 -272.991255) (xy 374.25884 -272.989548) (xy 374.330214 -272.960846)
			(xy 374.34393 -272.947892) (xy 374.347994 -272.939256) (xy 374.365524 -272.903675) (xy 374.406742 -272.835903)
			(xy 374.454601 -272.772645) (xy 374.508612 -272.714551) (xy 374.568219 -272.662215) (xy 374.600216 -272.638774)
			(xy 374.624854 -272.622772) (xy 374.662954 -272.600674) (xy 374.663208 -272.60042) (xy 374.678956 -272.591276)
			(xy 374.685814 -272.586196) (xy 374.7011 -272.572508) (xy 374.724647 -272.538924) (xy 374.738709 -272.500393)
			(xy 374.741186 -272.480024) (xy 374.741694 -272.466054) (xy 374.741694 -272.464784) (xy 374.741948 -272.462498)
			(xy 374.741948 -272.458942) (xy 374.741694 -272.456656) (xy 374.73997 -272.437817) (xy 374.728518 -272.401775)
			(xy 374.708648 -272.369597) (xy 374.681551 -272.343215) (xy 374.665494 -272.333212) (xy 374.6627 -272.331688)
			(xy 374.65889 -272.329402) (xy 374.658382 -272.328894) (xy 374.655842 -272.32737) (xy 374.653556 -272.3261)
			(xy 374.653302 -272.325846) (xy 374.620714 -272.30596) (xy 374.559191 -272.260753) (xy 374.502384 -272.209745)
			(xy 374.45084 -272.153426) (xy 374.405051 -272.092334) (xy 374.365459 -272.027056) (xy 374.348502 -271.992852)
			(xy 374.348248 -271.992598) (xy 374.343802 -271.984302) (xy 374.330122 -271.971399) (xy 374.321578 -271.967452)
			(xy 374.250458 -271.93875) (xy 374.231408 -271.938496) (xy 374.222518 -271.941798) (xy 374.196589 -271.950879)
			(xy 374.142542 -271.960708) (xy 374.115076 -271.961356) (xy 373.174768 -271.961356) (xy 373.14951 -271.960832)
			(xy 373.099685 -271.952513) (xy 373.051908 -271.936107) (xy 373.007483 -271.912061) (xy 372.967621 -271.881031)
			(xy 372.93341 -271.843864) (xy 372.905782 -271.801574) (xy 372.885492 -271.755313) (xy 372.873092 -271.706343)
			(xy 372.86892 -271.656) (xy 372.873092 -271.605657) (xy 372.885492 -271.556687) (xy 372.905782 -271.510426)
			(xy 372.93341 -271.468136) (xy 372.967621 -271.430969) (xy 373.007483 -271.399939) (xy 373.051908 -271.375893)
			(xy 373.099685 -271.359487) (xy 373.14951 -271.351168) (xy 373.174768 -271.35074) (xy 374.114822 -271.35074)
			(xy 374.142149 -271.351362) (xy 374.195933 -271.36108) (xy 374.221756 -271.370044) (xy 374.22201 -271.370044)
			(xy 374.231154 -271.373346) (xy 374.240552 -271.373346) (xy 374.245251 -271.373154) (xy 374.254458 -271.371243)
			(xy 374.25884 -271.369536) (xy 374.32107 -271.34439) (xy 374.329719 -271.340532) (xy 374.343536 -271.327601)
			(xy 374.347994 -271.319244) (xy 374.347994 -271.31899) (xy 374.361267 -271.291906) (xy 374.391402 -271.239653)
			(xy 374.408192 -271.214596) (xy 374.413526 -271.206722) (xy 374.417844 -271.188434) (xy 374.405906 -271.10309)
			(xy 374.397016 -271.087088) (xy 374.389396 -271.080738) (xy 374.369165 -271.063173) (xy 374.334602 -271.02224)
			(xy 374.307713 -270.975903) (xy 374.289325 -270.925585) (xy 374.280002 -270.872829) (xy 374.279414 -270.846042)
			(xy 374.279974 -270.819202) (xy 374.289357 -270.766347) (xy 374.30784 -270.715949) (xy 374.334854 -270.669561)
			(xy 374.369565 -270.628613) (xy 374.389904 -270.611092) (xy 374.39727 -270.604996) (xy 374.406414 -270.588486)
			(xy 374.417082 -270.51254) (xy 374.41762 -270.507903) (xy 374.417231 -270.498577) (xy 374.41632 -270.493998)
			(xy 374.414034 -270.4846) (xy 374.404355 -270.470727) (xy 374.386061 -270.442268) (xy 374.377458 -270.427704)
			(xy 374.369668 -270.414124) (xy 374.355057 -270.38643) (xy 374.348248 -270.372332) (xy 374.34393 -270.36395)
			(xy 374.330214 -270.350996) (xy 374.250458 -270.318738) (xy 374.231408 -270.318484) (xy 374.222518 -270.321786)
			(xy 374.196589 -270.330867) (xy 374.142542 -270.340697) (xy 374.115076 -270.341344) (xy 373.174768 -270.341344)
			(xy 373.149511 -270.34082) (xy 373.099688 -270.332501) (xy 373.051913 -270.316095) (xy 373.00749 -270.292051)
			(xy 372.96763 -270.261022) (xy 372.93342 -270.223857) (xy 372.905793 -270.181568) (xy 372.885504 -270.135308)
			(xy 372.873104 -270.086341) (xy 372.868933 -270.036) (xy 372.873104 -269.985659) (xy 372.885504 -269.936692)
			(xy 372.905793 -269.890432) (xy 372.93342 -269.848143) (xy 372.96763 -269.810978) (xy 373.00749 -269.779949)
			(xy 373.051913 -269.755905) (xy 373.099688 -269.739499) (xy 373.149511 -269.73118) (xy 373.174768 -269.730728)
			(xy 374.114822 -269.730728) (xy 374.142149 -269.73135) (xy 374.195933 -269.741067) (xy 374.221756 -269.750032)
			(xy 374.22201 -269.750032) (xy 374.231154 -269.753334) (xy 374.240552 -269.753334) (xy 374.245251 -269.753142)
			(xy 374.254458 -269.75123) (xy 374.25884 -269.749524) (xy 374.330214 -269.720822) (xy 374.34393 -269.707868)
			(xy 374.347994 -269.699232) (xy 374.365521 -269.663649) (xy 374.406735 -269.595872) (xy 374.45459 -269.532609)
			(xy 374.508597 -269.47451) (xy 374.568203 -269.422169) (xy 374.600216 -269.39875) (xy 374.624854 -269.382748)
			(xy 374.65381 -269.365984) (xy 374.659652 -269.362428) (xy 374.659906 -269.362174) (xy 374.663208 -269.360396)
			(xy 374.664224 -269.359634) (xy 374.664986 -269.35938) (xy 374.685306 -269.345156) (xy 374.698202 -269.334005)
			(xy 374.719186 -269.307146) (xy 374.733759 -269.276333) (xy 374.741209 -269.243073) (xy 374.741694 -269.22603)
			(xy 374.741694 -269.220442) (xy 374.740636 -269.203298) (xy 374.732 -269.170059) (xy 374.716372 -269.139479)
			(xy 374.694495 -269.113006) (xy 374.681242 -269.102078) (xy 374.673368 -269.097506) (xy 374.672606 -269.096998)
			(xy 374.66397 -269.092172) (xy 374.663716 -269.092172) (xy 374.65889 -269.089378) (xy 374.656604 -269.088108)
			(xy 374.65635 -269.087854) (xy 374.621537 -269.066802) (xy 374.556052 -269.018519) (xy 374.495958 -268.963672)
			(xy 374.441909 -268.902859) (xy 374.394494 -268.836744) (xy 374.354229 -268.766046) (xy 374.321554 -268.691535)
			(xy 374.296824 -268.614025) (xy 374.280309 -268.534358) (xy 374.272189 -268.453404) (xy 374.271794 -268.412722)
			(xy 374.271794 -268.409166) (xy 374.270704 -268.393153) (xy 374.262837 -268.362043) (xy 374.248843 -268.333165)
			(xy 374.229298 -268.307714) (xy 374.217438 -268.296898) (xy 374.213628 -268.29385) (xy 374.193054 -268.281912)
			(xy 374.1928 -268.281658) (xy 374.159526 -268.262354) (xy 374.137936 -268.248638) (xy 374.09882 -268.219682)
			(xy 374.079008 -268.203426) (xy 374.050468 -268.178683) (xy 373.997772 -268.124561) (xy 373.950534 -268.065614)
			(xy 373.909195 -268.002391) (xy 373.874139 -267.935479) (xy 373.845693 -267.865501) (xy 373.82412 -267.793108)
			(xy 373.809622 -267.718974) (xy 373.802333 -267.643787) (xy 373.801894 -267.606018) (xy 373.801894 -267.399008)
			(xy 373.80142 -267.389184) (xy 373.793922 -267.371023) (xy 373.78006 -267.3571) (xy 373.761932 -267.349523)
			(xy 373.75211 -267.34897) (xy 373.078756 -267.34897) (xy 373.072152 -267.349478) (xy 373.062644 -267.351151)
			(xy 373.045799 -267.36055) (xy 373.039386 -267.367766) (xy 373.036592 -267.371576) (xy 372.990872 -267.440156)
			(xy 372.984486 -267.451086) (xy 372.982219 -267.476268) (xy 372.986554 -267.488162) (xy 372.997656 -267.516611)
			(xy 373.00955 -267.576501) (xy 373.010176 -267.607034) (xy 373.010176 -267.61059) (xy 373.0093 -267.635598)
			(xy 373.000403 -267.684836) (xy 372.983599 -267.731966) (xy 372.959335 -267.775725) (xy 372.928261 -267.814942)
			(xy 372.891209 -267.848568) (xy 372.84917 -267.875704) (xy 372.80327 -267.895622) (xy 372.754736 -267.907791)
			(xy 372.704868 -267.911883) (xy 372.655 -267.907791) (xy 372.606466 -267.895622) (xy 372.560566 -267.875704)
			(xy 372.518527 -267.848568) (xy 372.481475 -267.814942) (xy 372.450401 -267.775725) (xy 372.426137 -267.731966)
			(xy 372.409333 -267.684836) (xy 372.400436 -267.635598) (xy 372.39956 -267.61059) (xy 372.39956 -267.607034)
			(xy 372.400199 -267.576503) (xy 372.412098 -267.516617) (xy 372.423182 -267.488162) (xy 372.427568 -267.476271)
			(xy 372.42532 -267.45106) (xy 372.418864 -267.440156) (xy 372.373144 -267.371576) (xy 372.37035 -267.367766)
			(xy 372.363943 -267.36054) (xy 372.347099 -267.351124) (xy 372.337584 -267.349478) (xy 372.33098 -267.34897)
			(xy 372.112286 -267.34897) (xy 372.102445 -267.348443) (xy 372.084272 -267.340867) (xy 372.07698 -267.334238)
			(xy 371.699028 -266.956286) (xy 371.6909 -266.948158) (xy 371.669818 -266.940538) (xy 371.571266 -266.949682)
			(xy 371.552216 -266.960858) (xy 371.545612 -266.970256) (xy 371.531214 -266.990115) (xy 371.497141 -267.025398)
			(xy 371.457866 -267.05478) (xy 371.414398 -267.077505) (xy 371.367857 -267.092989) (xy 371.319439 -267.100833)
			(xy 371.294914 -267.10132) (xy 371.27092 -267.100875) (xy 371.223522 -267.09337) (xy 371.177882 -267.078543)
			(xy 371.135123 -267.056758) (xy 371.096298 -267.028553) (xy 371.062364 -266.994622) (xy 371.034155 -266.9558)
			(xy 371.012367 -266.913042) (xy 370.997536 -266.867403) (xy 370.990027 -266.820006) (xy 370.989606 -266.796012)
			(xy 370.990083 -266.771274) (xy 370.998057 -266.722446) (xy 371.013797 -266.675541) (xy 371.036892 -266.631787)
			(xy 371.066739 -266.592328) (xy 371.102556 -266.558196) (xy 371.143406 -266.530284) (xy 371.165628 -266.519406)
			(xy 371.173756 -266.515596) (xy 371.180106 -266.509246) (xy 371.186824 -266.501812) (xy 371.194464 -266.483312)
			(xy 371.194465 -266.463295) (xy 371.186828 -266.444794) (xy 371.180106 -266.437364) (xy 371.161818 -266.419076)
			(xy 371.154706 -266.41171) (xy 371.13591 -266.40409) (xy 370.283486 -266.40409) (xy 370.273644 -266.404615)
			(xy 370.255467 -266.412187) (xy 370.24818 -266.418822) (xy 369.398804 -267.268198) (xy 369.391568 -267.274915)
			(xy 369.373362 -267.282517) (xy 369.363498 -267.28293) (xy 369.283742 -267.28293) (xy 369.28298 -267.28293)
			(xy 369.271215 -267.28377) (xy 369.250301 -267.294617) (xy 369.242848 -267.303758) (xy 369.239038 -267.309854)
			(xy 369.191286 -267.399008) (xy 369.192302 -267.42644) (xy 369.200176 -267.438378) (xy 369.212003 -267.457154)
			(xy 369.230701 -267.497398) (xy 369.243388 -267.539921) (xy 369.249797 -267.58383) (xy 369.250214 -267.606018)
			(xy 370.518956 -267.606018) (xy 370.522916 -267.556964) (xy 370.534693 -267.50918) (xy 370.553984 -267.463904)
			(xy 370.580287 -267.422308) (xy 370.612922 -267.385471) (xy 370.651043 -267.354346) (xy 370.693664 -267.329739)
			(xy 370.73968 -267.312287) (xy 370.787899 -267.302443) (xy 370.837074 -267.300462) (xy 370.885929 -267.306394)
			(xy 370.9332 -267.320086) (xy 370.977662 -267.341184) (xy 371.018165 -267.36914) (xy 371.053658 -267.403232)
			(xy 371.083223 -267.442576) (xy 371.106094 -267.486153) (xy 371.121678 -267.532834) (xy 371.129573 -267.581411)
			(xy 371.130068 -267.606018) (xy 371.129573 -267.630625) (xy 371.121678 -267.679202) (xy 371.106094 -267.725883)
			(xy 371.083223 -267.76946) (xy 371.053658 -267.808804) (xy 371.018165 -267.842896) (xy 370.977662 -267.870852)
			(xy 370.9332 -267.89195) (xy 370.885929 -267.905642) (xy 370.837074 -267.911574) (xy 370.787899 -267.909593)
			(xy 370.73968 -267.899749) (xy 370.693664 -267.882297) (xy 370.651043 -267.85769) (xy 370.612922 -267.826565)
			(xy 370.580287 -267.789728) (xy 370.553984 -267.748132) (xy 370.534693 -267.702856) (xy 370.522916 -267.655072)
			(xy 370.518956 -267.606018) (xy 369.250214 -267.606018) (xy 369.250214 -267.615924) (xy 369.249706 -267.62456)
			(xy 369.247763 -267.64877) (xy 369.237179 -267.696168) (xy 369.219225 -267.741293) (xy 369.194355 -267.783008)
			(xy 369.163196 -267.82026) (xy 369.126534 -267.852111) (xy 369.085292 -267.877757) (xy 369.04051 -267.896552)
			(xy 368.993318 -267.908022) (xy 368.944906 -267.911878) (xy 368.896494 -267.908022) (xy 368.849302 -267.896552)
			(xy 368.80452 -267.877757) (xy 368.763278 -267.852111) (xy 368.726616 -267.82026) (xy 368.695457 -267.783008)
			(xy 368.670587 -267.741293) (xy 368.652633 -267.696168) (xy 368.642049 -267.64877) (xy 368.640106 -267.62456)
			(xy 368.639598 -267.615924) (xy 368.639598 -267.606018) (xy 368.639975 -267.583827) (xy 368.646368 -267.53991)
			(xy 368.659064 -267.497384) (xy 368.677795 -267.45715) (xy 368.689636 -267.438378) (xy 368.69751 -267.42644)
			(xy 368.698526 -267.399008) (xy 368.650774 -267.309854) (xy 368.646964 -267.303758) (xy 368.63954 -267.294578)
			(xy 368.618612 -267.283713) (xy 368.606832 -267.28293) (xy 368.215926 -267.28293) (xy 368.206088 -267.282394)
			(xy 368.187925 -267.27481) (xy 368.18062 -267.268198) (xy 367.908078 -266.995656) (xy 367.900712 -266.98829)
			(xy 367.881154 -266.980416) (xy 367.787936 -266.982956) (xy 367.769394 -266.991592) (xy 367.762282 -266.999466)
			(xy 367.744755 -267.018267) (xy 367.704562 -267.050298) (xy 367.659575 -267.075152) (xy 367.611064 -267.092127)
			(xy 367.560396 -267.100744) (xy 367.534698 -267.10132) (xy 367.510707 -267.100849) (xy 367.463314 -267.093343)
			(xy 367.41768 -267.078516) (xy 367.374927 -267.056732) (xy 367.336107 -267.028529) (xy 367.302178 -266.9946)
			(xy 367.273973 -266.955782) (xy 367.252188 -266.913029) (xy 367.237359 -266.867395) (xy 367.229852 -266.820003)
			(xy 367.22939 -266.796012) (xy 367.229866 -266.771573) (xy 367.237656 -266.72332) (xy 367.253054 -266.676931)
			(xy 367.263934 -266.655042) (xy 367.27003 -266.643104) (xy 367.269268 -266.616942) (xy 367.218468 -266.532868)
			(xy 367.213653 -266.525591) (xy 367.200159 -266.514547) (xy 367.183751 -266.508647) (xy 367.175034 -266.50823)
			(xy 366.404906 -266.50823) (xy 366.395071 -266.508771) (xy 366.376919 -266.516367) (xy 366.3696 -266.522962)
			(xy 365.583724 -267.308838) (xy 365.576487 -267.315554) (xy 365.558282 -267.323157) (xy 365.548418 -267.32357)
			(xy 365.547148 -267.32357) (xy 365.539277 -267.323869) (xy 365.524281 -267.328663) (xy 365.517684 -267.332968)
			(xy 365.509302 -267.339064) (xy 365.45266 -267.430758) (xy 365.45139 -267.45692) (xy 365.457486 -267.468858)
			(xy 365.467734 -267.490255) (xy 365.482221 -267.535428) (xy 365.489552 -267.582298) (xy 365.489998 -267.606018)
			(xy 366.758994 -267.606018) (xy 366.762954 -267.556964) (xy 366.774731 -267.50918) (xy 366.794022 -267.463904)
			(xy 366.820325 -267.422308) (xy 366.85296 -267.385471) (xy 366.891081 -267.354346) (xy 366.933702 -267.329739)
			(xy 366.979718 -267.312287) (xy 367.027937 -267.302443) (xy 367.077112 -267.300462) (xy 367.125967 -267.306394)
			(xy 367.173238 -267.320086) (xy 367.2177 -267.341184) (xy 367.258203 -267.36914) (xy 367.293696 -267.403232)
			(xy 367.323261 -267.442576) (xy 367.346132 -267.486153) (xy 367.361716 -267.532834) (xy 367.369611 -267.581411)
			(xy 367.370106 -267.606018) (xy 367.369611 -267.630625) (xy 367.361716 -267.679202) (xy 367.346132 -267.725883)
			(xy 367.323261 -267.76946) (xy 367.293696 -267.808804) (xy 367.258203 -267.842896) (xy 367.2177 -267.870852)
			(xy 367.173238 -267.89195) (xy 367.125967 -267.905642) (xy 367.077112 -267.911574) (xy 367.027937 -267.909593)
			(xy 366.979718 -267.899749) (xy 366.933702 -267.882297) (xy 366.891081 -267.85769) (xy 366.85296 -267.826565)
			(xy 366.820325 -267.789728) (xy 366.794022 -267.748132) (xy 366.774731 -267.702856) (xy 366.762954 -267.655072)
			(xy 366.758994 -267.606018) (xy 365.489998 -267.606018) (xy 365.489476 -267.631273) (xy 365.481163 -267.681095)
			(xy 365.464762 -267.728869) (xy 365.440721 -267.773292) (xy 365.409697 -267.813152) (xy 365.372535 -267.847362)
			(xy 365.330249 -267.874988) (xy 365.283993 -267.895278) (xy 365.235028 -267.907678) (xy 365.18469 -267.911849)
			(xy 365.134352 -267.907678) (xy 365.085387 -267.895278) (xy 365.039131 -267.874988) (xy 364.996845 -267.847362)
			(xy 364.959683 -267.813152) (xy 364.928659 -267.773292) (xy 364.904618 -267.728869) (xy 364.888217 -267.681095)
			(xy 364.879904 -267.631273) (xy 364.879382 -267.606018) (xy 364.879829 -267.582298) (xy 364.887156 -267.535427)
			(xy 364.901639 -267.490251) (xy 364.911894 -267.468858) (xy 364.91799 -267.45692) (xy 364.91672 -267.430758)
			(xy 364.865412 -267.3477) (xy 364.862655 -267.343444) (xy 364.855743 -267.336025) (xy 364.851696 -267.332968)
			(xy 364.844838 -267.328142) (xy 364.830106 -267.32357) (xy 364.438946 -267.32357) (xy 364.429108 -267.323036)
			(xy 364.410945 -267.31545) (xy 364.40364 -267.308838) (xy 364.119414 -267.024612) (xy 364.112239 -267.01801)
			(xy 364.094343 -267.010312) (xy 364.084616 -267.009626) (xy 364.00613 -267.007848) (xy 363.988096 -267.014706)
			(xy 363.98073 -267.02131) (xy 363.963756 -267.036271) (xy 363.926224 -267.061538) (xy 363.885376 -267.080993)
			(xy 363.842105 -267.094211) (xy 363.797358 -267.100904) (xy 363.774736 -267.10132) (xy 363.749511 -267.100804)
			(xy 363.699746 -267.092516) (xy 363.65202 -267.07616) (xy 363.607633 -267.052181) (xy 363.567791 -267.02123)
			(xy 363.53358 -266.984152) (xy 363.50593 -266.941953) (xy 363.485592 -266.895784) (xy 363.473122 -266.846899)
			(xy 363.468858 -266.796629) (xy 363.472915 -266.746342) (xy 363.485185 -266.697406) (xy 363.494828 -266.674092)
			(xy 363.499908 -266.662154) (xy 363.497876 -266.636754) (xy 363.445298 -266.55649) (xy 363.441742 -266.551664)
			(xy 363.434355 -266.543688) (xy 363.414744 -266.534354) (xy 363.403896 -266.53363) (xy 362.638086 -266.53363)
			(xy 362.628245 -266.534157) (xy 362.610072 -266.541733) (xy 362.60278 -266.548362) (xy 361.870244 -267.280898)
			(xy 361.86301 -267.287621) (xy 361.844805 -267.295238) (xy 361.834938 -267.29563) (xy 361.771692 -267.29563)
			(xy 361.762704 -267.295974) (xy 361.745833 -267.302178) (xy 361.732163 -267.31385) (xy 361.727496 -267.321538)
			(xy 361.67822 -267.409168) (xy 361.678982 -267.436346) (xy 361.686094 -267.448284) (xy 361.699847 -267.472228)
			(xy 361.719417 -267.523856) (xy 361.729404 -267.578158) (xy 361.730036 -267.605764) (xy 361.730036 -267.606018)
			(xy 362.999032 -267.606018) (xy 363.002992 -267.556964) (xy 363.014769 -267.50918) (xy 363.03406 -267.463904)
			(xy 363.060363 -267.422308) (xy 363.092998 -267.385471) (xy 363.131119 -267.354346) (xy 363.17374 -267.329739)
			(xy 363.219756 -267.312287) (xy 363.267975 -267.302443) (xy 363.31715 -267.300462) (xy 363.366005 -267.306394)
			(xy 363.413276 -267.320086) (xy 363.457738 -267.341184) (xy 363.498241 -267.36914) (xy 363.533734 -267.403232)
			(xy 363.563299 -267.442576) (xy 363.58617 -267.486153) (xy 363.601754 -267.532834) (xy 363.609649 -267.581411)
			(xy 363.610144 -267.606018) (xy 363.609649 -267.630625) (xy 363.601754 -267.679202) (xy 363.58617 -267.725883)
			(xy 363.563299 -267.76946) (xy 363.533734 -267.808804) (xy 363.498241 -267.842896) (xy 363.457738 -267.870852)
			(xy 363.413276 -267.89195) (xy 363.366005 -267.905642) (xy 363.31715 -267.911574) (xy 363.267975 -267.909593)
			(xy 363.219756 -267.899749) (xy 363.17374 -267.882297) (xy 363.131119 -267.85769) (xy 363.092998 -267.826565)
			(xy 363.060363 -267.789728) (xy 363.03406 -267.748132) (xy 363.014769 -267.702856) (xy 363.002992 -267.655072)
			(xy 362.999032 -267.606018) (xy 361.730036 -267.606018) (xy 361.730036 -267.612114) (xy 361.729043 -267.637039)
			(xy 361.719956 -267.686085) (xy 361.703018 -267.733001) (xy 361.678681 -267.776541) (xy 361.647591 -267.815546)
			(xy 361.610575 -267.848981) (xy 361.568618 -267.875955) (xy 361.522834 -267.895751) (xy 361.474442 -267.907844)
			(xy 361.424728 -267.91191) (xy 361.375014 -267.907844) (xy 361.326622 -267.895751) (xy 361.280838 -267.875955)
			(xy 361.238881 -267.848981) (xy 361.201865 -267.815546) (xy 361.170775 -267.776541) (xy 361.146438 -267.733001)
			(xy 361.1295 -267.686085) (xy 361.120413 -267.637039) (xy 361.11942 -267.612114) (xy 361.11942 -267.606018)
			(xy 361.120018 -267.578367) (xy 361.129976 -267.52397) (xy 361.149571 -267.472257) (xy 361.163362 -267.448284)
			(xy 361.170474 -267.436346) (xy 361.171236 -267.409168) (xy 361.145074 -267.362432) (xy 361.139994 -267.357352)
			(xy 360.429048 -266.646406) (xy 360.421936 -266.63904) (xy 360.40314 -266.63142) (xy 359.328212 -266.63142)
			(xy 359.318141 -266.631841) (xy 359.299535 -266.639555) (xy 359.292144 -266.646406) (xy 358.657906 -267.280644)
			(xy 358.650511 -267.287497) (xy 358.631912 -267.295243) (xy 358.621838 -267.29563) (xy 358.01808 -267.29563)
			(xy 358.009093 -267.295976) (xy 357.992225 -267.302183) (xy 357.978558 -267.313855) (xy 357.973884 -267.321538)
			(xy 357.924608 -267.409168) (xy 357.92537 -267.436346) (xy 357.932482 -267.448284) (xy 357.946235 -267.472228)
			(xy 357.965806 -267.523856) (xy 357.975793 -267.578158) (xy 357.976424 -267.605764) (xy 357.976424 -267.612114)
			(xy 357.97551 -267.635794) (xy 357.967267 -267.682458) (xy 357.951913 -267.727288) (xy 357.929816 -267.769207)
			(xy 357.901508 -267.807208) (xy 357.867668 -267.840379) (xy 357.829108 -267.867923) (xy 357.786756 -267.889178)
			(xy 357.741629 -267.903633) (xy 357.694809 -267.910942) (xy 357.671116 -267.911326) (xy 357.647123 -267.910857)
			(xy 357.599729 -267.903353) (xy 357.554091 -267.888527) (xy 357.511335 -267.866744) (xy 357.472513 -267.838542)
			(xy 357.438581 -267.804613) (xy 357.410373 -267.765794) (xy 357.388586 -267.72304) (xy 357.373755 -267.677404)
			(xy 357.366246 -267.630011) (xy 357.365808 -267.606018) (xy 357.366298 -267.581452) (xy 357.374161 -267.532953)
			(xy 357.389688 -267.486339) (xy 357.412477 -267.442811) (xy 357.441941 -267.403494) (xy 357.47732 -267.369402)
			(xy 357.517701 -267.341413) (xy 357.562042 -267.320251) (xy 357.609199 -267.30646) (xy 357.633524 -267.302996)
			(xy 357.64294 -267.301474) (xy 357.659721 -267.292435) (xy 357.672004 -267.277861) (xy 357.675434 -267.26896)
			(xy 357.704136 -267.184886) (xy 357.705152 -267.181584) (xy 357.707041 -267.172898) (xy 357.705452 -267.155207)
			(xy 357.697961 -267.139102) (xy 357.691944 -267.132562) (xy 357.565198 -267.005816) (xy 357.557832 -266.99845)
			(xy 357.538782 -266.990576) (xy 357.457756 -266.991592) (xy 357.447621 -266.992197) (xy 357.429034 -267.000329)
			(xy 357.421688 -267.00734) (xy 357.404285 -267.024792) (xy 357.364891 -267.054408) (xy 357.321254 -267.077316)
			(xy 357.274506 -267.092921) (xy 357.225858 -267.10082) (xy 357.201216 -267.10132) (xy 357.177222 -267.100875)
			(xy 357.129824 -267.09337) (xy 357.084183 -267.078543) (xy 357.041424 -267.056759) (xy 357.002599 -267.028554)
			(xy 356.968664 -266.994622) (xy 356.940456 -266.9558) (xy 356.918667 -266.913043) (xy 356.903836 -266.867404)
			(xy 356.896327 -266.820006) (xy 356.895908 -266.796012) (xy 356.896362 -266.771896) (xy 356.903942 -266.724263)
			(xy 356.918914 -266.678414) (xy 356.940908 -266.635488) (xy 356.969375 -266.596553) (xy 357.003609 -266.562577)
			(xy 357.022908 -266.548108) (xy 357.027226 -266.54506) (xy 357.03129 -266.540742) (xy 357.037541 -266.533258)
			(xy 357.044387 -266.515018) (xy 357.043954 -266.49554) (xy 357.036305 -266.477621) (xy 357.029766 -266.470384)
			(xy 357.029258 -266.469876) (xy 357.021861 -266.463028) (xy 357.003262 -266.455297) (xy 356.99319 -266.45489)
			(xy 356.247446 -266.45489) (xy 356.237607 -266.455423) (xy 356.219441 -266.463004) (xy 356.21214 -266.469622)
			(xy 355.426264 -267.255498) (xy 355.419025 -267.262209) (xy 355.40082 -267.269796) (xy 355.390958 -267.27023)
			(xy 354.241354 -267.27023) (xy 354.238052 -267.27023) (xy 354.227197 -267.271516) (xy 354.207995 -267.281921)
			(xy 354.200968 -267.290296) (xy 354.196142 -267.297916) (xy 354.149406 -267.388848) (xy 354.151438 -267.417042)
			(xy 354.15982 -267.428726) (xy 354.17317 -267.448255) (xy 354.194327 -267.490564) (xy 354.208717 -267.535626)
			(xy 354.215998 -267.582366) (xy 354.216462 -267.606018) (xy 355.485204 -267.606018) (xy 355.489164 -267.556964)
			(xy 355.500941 -267.50918) (xy 355.520232 -267.463904) (xy 355.546535 -267.422308) (xy 355.57917 -267.385471)
			(xy 355.617291 -267.354346) (xy 355.659912 -267.329739) (xy 355.705928 -267.312287) (xy 355.754147 -267.302443)
			(xy 355.803322 -267.300462) (xy 355.852177 -267.306394) (xy 355.899448 -267.320086) (xy 355.94391 -267.341184)
			(xy 355.984413 -267.36914) (xy 356.019906 -267.403232) (xy 356.049471 -267.442576) (xy 356.072342 -267.486153)
			(xy 356.087926 -267.532834) (xy 356.095821 -267.581411) (xy 356.096316 -267.606018) (xy 356.095821 -267.630625)
			(xy 356.087926 -267.679202) (xy 356.072342 -267.725883) (xy 356.049471 -267.76946) (xy 356.019906 -267.808804)
			(xy 355.984413 -267.842896) (xy 355.94391 -267.870852) (xy 355.899448 -267.89195) (xy 355.852177 -267.905642)
			(xy 355.803322 -267.911574) (xy 355.754147 -267.909593) (xy 355.705928 -267.899749) (xy 355.659912 -267.882297)
			(xy 355.617291 -267.85769) (xy 355.57917 -267.826565) (xy 355.546535 -267.789728) (xy 355.520232 -267.748132)
			(xy 355.500941 -267.702856) (xy 355.489164 -267.655072) (xy 355.485204 -267.606018) (xy 354.216462 -267.606018)
			(xy 354.21594 -267.631273) (xy 354.207627 -267.681095) (xy 354.191226 -267.728869) (xy 354.167185 -267.773292)
			(xy 354.136161 -267.813152) (xy 354.098999 -267.847362) (xy 354.056713 -267.874988) (xy 354.010457 -267.895278)
			(xy 353.961492 -267.907678) (xy 353.911154 -267.911849) (xy 353.860816 -267.907678) (xy 353.811851 -267.895278)
			(xy 353.765595 -267.874988) (xy 353.723309 -267.847362) (xy 353.686147 -267.813152) (xy 353.655123 -267.773292)
			(xy 353.631082 -267.728869) (xy 353.614681 -267.681095) (xy 353.606368 -267.631273) (xy 353.605846 -267.606018)
			(xy 353.606354 -267.580557) (xy 353.614798 -267.530339) (xy 353.631457 -267.482218) (xy 353.655867 -267.437527)
			(xy 353.687352 -267.397504) (xy 353.725041 -267.363259) (xy 353.767888 -267.335741) (xy 353.814706 -267.315711)
			(xy 353.864199 -267.303726) (xy 353.889564 -267.301472) (xy 353.90455 -267.300456) (xy 353.928172 -267.282676)
			(xy 353.965256 -267.184378) (xy 353.967796 -267.17498) (xy 353.969148 -267.1633) (xy 353.962408 -267.140799)
			(xy 353.954842 -267.1318) (xy 353.953572 -267.13053) (xy 353.816412 -266.99337) (xy 353.807014 -266.986004)
			(xy 353.800523 -266.982264) (xy 353.786058 -266.978393) (xy 353.778566 -266.978384) (xy 353.695508 -266.981178)
			(xy 353.676966 -266.989814) (xy 353.669854 -266.997942) (xy 353.652322 -267.017011) (xy 353.61201 -267.049534)
			(xy 353.566785 -267.074785) (xy 353.517948 -267.092038) (xy 353.466898 -267.100799) (xy 353.441 -267.10132)
			(xy 353.417008 -267.100849) (xy 353.369616 -267.093343) (xy 353.323981 -267.078516) (xy 353.281228 -267.056733)
			(xy 353.242408 -267.02853) (xy 353.208478 -266.994601) (xy 353.180274 -266.955783) (xy 353.158488 -266.91303)
			(xy 353.143659 -266.867396) (xy 353.136152 -266.820004) (xy 353.135692 -266.796012) (xy 353.136168 -266.771573)
			(xy 353.143958 -266.72332) (xy 353.159356 -266.676931) (xy 353.170236 -266.655042) (xy 353.176332 -266.643104)
			(xy 353.17557 -266.616942) (xy 353.12477 -266.532868) (xy 353.119955 -266.525591) (xy 353.106461 -266.514547)
			(xy 353.090053 -266.508645) (xy 353.081336 -266.50823) (xy 352.429826 -266.50823) (xy 352.41999 -266.508767)
			(xy 352.401832 -266.516359) (xy 352.39452 -266.522962) (xy 351.583244 -267.334238) (xy 351.576008 -267.340957)
			(xy 351.557803 -267.348567) (xy 351.547938 -267.34897) (xy 350.52508 -267.34897) (xy 350.518476 -267.349478)
			(xy 350.508966 -267.351147) (xy 350.492114 -267.360541) (xy 350.48571 -267.367766) (xy 350.482916 -267.371576)
			(xy 350.437196 -267.440156) (xy 350.430808 -267.451086) (xy 350.42854 -267.476269) (xy 350.432878 -267.488162)
			(xy 350.443979 -267.516612) (xy 350.455872 -267.576501) (xy 350.456479 -267.606018) (xy 351.725242 -267.606018)
			(xy 351.729202 -267.556964) (xy 351.740979 -267.50918) (xy 351.76027 -267.463904) (xy 351.786573 -267.422308)
			(xy 351.819208 -267.385471) (xy 351.857329 -267.354346) (xy 351.89995 -267.329739) (xy 351.945966 -267.312287)
			(xy 351.994185 -267.302443) (xy 352.04336 -267.300462) (xy 352.092215 -267.306394) (xy 352.139486 -267.320086)
			(xy 352.183948 -267.341184) (xy 352.224451 -267.36914) (xy 352.259944 -267.403232) (xy 352.289509 -267.442576)
			(xy 352.31238 -267.486153) (xy 352.327964 -267.532834) (xy 352.335859 -267.581411) (xy 352.336354 -267.606018)
			(xy 352.335859 -267.630625) (xy 352.327964 -267.679202) (xy 352.31238 -267.725883) (xy 352.289509 -267.76946)
			(xy 352.259944 -267.808804) (xy 352.224451 -267.842896) (xy 352.183948 -267.870852) (xy 352.139486 -267.89195)
			(xy 352.092215 -267.905642) (xy 352.04336 -267.911574) (xy 351.994185 -267.909593) (xy 351.945966 -267.899749)
			(xy 351.89995 -267.882297) (xy 351.857329 -267.85769) (xy 351.819208 -267.826565) (xy 351.786573 -267.789728)
			(xy 351.76027 -267.748132) (xy 351.740979 -267.702856) (xy 351.729202 -267.655072) (xy 351.725242 -267.606018)
			(xy 350.456479 -267.606018) (xy 350.4565 -267.607034) (xy 350.4565 -267.61059) (xy 350.45569 -267.634342)
			(xy 350.447619 -267.681175) (xy 350.432388 -267.726192) (xy 350.410364 -267.768303) (xy 350.382079 -267.806493)
			(xy 350.348217 -267.839838) (xy 350.309597 -267.867531) (xy 350.267151 -267.888905) (xy 350.221906 -267.903441)
			(xy 350.174954 -267.91079) (xy 350.151192 -267.911326) (xy 350.127502 -267.910879) (xy 350.080691 -267.903561)
			(xy 350.035572 -267.889103) (xy 349.993226 -267.86785) (xy 349.95467 -267.840313) (xy 349.920829 -267.807153)
			(xy 349.892514 -267.769165) (xy 349.870406 -267.72726) (xy 349.855033 -267.682443) (xy 349.846766 -267.635791)
			(xy 349.845884 -267.612114) (xy 349.845884 -267.60678) (xy 349.846359 -267.580522) (xy 349.855214 -267.528762)
			(xy 349.872814 -267.479286) (xy 349.885254 -267.456158) (xy 349.888302 -267.45057) (xy 349.892112 -267.435838)
			(xy 349.894091 -267.426742) (xy 349.892151 -267.408244) (xy 349.888302 -267.39977) (xy 349.870014 -267.363956)
			(xy 349.84563 -267.34897) (xy 349.831406 -267.34897) (xy 349.821571 -267.348429) (xy 349.803419 -267.340833)
			(xy 349.7961 -267.334238) (xy 349.515684 -267.053822) (xy 349.508826 -267.048234) (xy 349.507048 -267.046964)
			(xy 349.484896 -267.030868) (xy 349.446177 -266.992157) (xy 349.430086 -266.970002) (xy 349.428816 -266.968224)
			(xy 349.423228 -266.961366) (xy 349.023178 -266.561316) (xy 349.016066 -266.55395) (xy 348.99727 -266.54633)
			(xy 348.327726 -266.54633) (xy 348.31789 -266.546867) (xy 348.299732 -266.554459) (xy 348.29242 -266.561062)
			(xy 348.112588 -266.740894) (xy 348.104968 -266.761468) (xy 348.10573 -266.772644) (xy 348.106492 -266.796012)
			(xy 348.106045 -266.820004) (xy 348.098537 -266.867397) (xy 348.083707 -266.913032) (xy 348.061921 -266.955785)
			(xy 348.033714 -266.994604) (xy 347.999783 -267.028533) (xy 347.960962 -267.056735) (xy 347.918206 -267.078517)
			(xy 347.87257 -267.093343) (xy 347.825176 -267.100847) (xy 347.801184 -267.10132) (xy 347.777816 -267.100558)
			(xy 347.76664 -267.099796) (xy 347.746066 -267.107416) (xy 347.574616 -267.278866) (xy 347.568342 -267.285782)
			(xy 347.560797 -267.302846) (xy 347.559884 -267.31214) (xy 347.556582 -267.378688) (xy 347.556524 -267.388005)
			(xy 347.562244 -267.405722) (xy 347.567758 -267.413232) (xy 347.568012 -267.413486) (xy 347.584033 -267.434043)
			(xy 347.609549 -267.479484) (xy 347.626977 -267.528599) (xy 347.635808 -267.57996) (xy 347.636338 -267.606018)
			(xy 347.96528 -267.606018) (xy 347.96924 -267.556964) (xy 347.981017 -267.50918) (xy 348.000308 -267.463904)
			(xy 348.026611 -267.422308) (xy 348.059246 -267.385471) (xy 348.097367 -267.354346) (xy 348.139988 -267.329739)
			(xy 348.186004 -267.312287) (xy 348.234223 -267.302443) (xy 348.283398 -267.300462) (xy 348.332253 -267.306394)
			(xy 348.379524 -267.320086) (xy 348.423986 -267.341184) (xy 348.464489 -267.36914) (xy 348.499982 -267.403232)
			(xy 348.529547 -267.442576) (xy 348.552418 -267.486153) (xy 348.568002 -267.532834) (xy 348.575897 -267.581411)
			(xy 348.576392 -267.606018) (xy 348.575897 -267.630625) (xy 348.568002 -267.679202) (xy 348.552418 -267.725883)
			(xy 348.529547 -267.76946) (xy 348.499982 -267.808804) (xy 348.464489 -267.842896) (xy 348.423986 -267.870852)
			(xy 348.379524 -267.89195) (xy 348.332253 -267.905642) (xy 348.283398 -267.911574) (xy 348.234223 -267.909593)
			(xy 348.186004 -267.899749) (xy 348.139988 -267.882297) (xy 348.097367 -267.85769) (xy 348.059246 -267.826565)
			(xy 348.026611 -267.789728) (xy 348.000308 -267.748132) (xy 347.981017 -267.702856) (xy 347.96924 -267.655072)
			(xy 347.96528 -267.606018) (xy 347.636338 -267.606018) (xy 347.636338 -267.613892) (xy 347.635295 -267.637478)
			(xy 347.626838 -267.683925) (xy 347.61133 -267.728515) (xy 347.589142 -267.770186) (xy 347.560802 -267.807944)
			(xy 347.526987 -267.840889) (xy 347.488502 -267.868234) (xy 347.446267 -267.889328) (xy 347.401287 -267.903667)
			(xy 347.354635 -267.91091) (xy 347.33103 -267.911326) (xy 347.305555 -267.910818) (xy 347.25531 -267.902365)
			(xy 347.207165 -267.88569) (xy 347.162457 -267.861254) (xy 347.122425 -267.829736) (xy 347.08818 -267.79201)
			(xy 347.060672 -267.749123) (xy 347.040665 -267.702265) (xy 347.028713 -267.652736) (xy 347.026484 -267.627354)
			(xy 347.02496 -267.607288) (xy 346.996004 -267.58011) (xy 346.726256 -267.58011) (xy 346.6973 -267.607288)
			(xy 346.695776 -267.627354) (xy 346.693634 -267.651393) (xy 346.682729 -267.698404) (xy 346.664564 -267.743115)
			(xy 346.63959 -267.78441) (xy 346.608431 -267.821262) (xy 346.571862 -267.852754) (xy 346.530794 -267.878099)
			(xy 346.48625 -267.896668) (xy 346.439339 -267.907998) (xy 346.39123 -267.911806) (xy 346.343121 -267.907998)
			(xy 346.29621 -267.896668) (xy 346.251666 -267.878099) (xy 346.210598 -267.852754) (xy 346.174029 -267.821262)
			(xy 346.14287 -267.78441) (xy 346.117896 -267.743115) (xy 346.099731 -267.698404) (xy 346.088826 -267.651393)
			(xy 346.086684 -267.627354) (xy 346.08516 -267.607288) (xy 346.056204 -267.58011) (xy 345.786202 -267.58011)
			(xy 345.757246 -267.607288) (xy 345.755722 -267.627354) (xy 345.753432 -267.652729) (xy 345.741484 -267.702256)
			(xy 345.721483 -267.749112) (xy 345.693983 -267.792) (xy 345.659747 -267.829729) (xy 345.619724 -267.861253)
			(xy 345.575024 -267.885698) (xy 345.526888 -267.902385) (xy 345.476649 -267.910853) (xy 345.451176 -267.911326)
			(xy 345.424904 -267.910776) (xy 345.373135 -267.901777) (xy 345.323671 -267.884049) (xy 345.277973 -267.858115)
			(xy 345.237388 -267.82474) (xy 345.203116 -267.784911) (xy 345.176168 -267.739803) (xy 345.166188 -267.715492)
			(xy 345.161616 -267.7033) (xy 345.142058 -267.68679) (xy 345.048332 -267.66647) (xy 345.036743 -267.664597)
			(xy 345.013994 -267.670293) (xy 345.004644 -267.677392) (xy 345.002866 -267.678916) (xy 344.895424 -267.786358)
			(xy 344.888699 -267.793591) (xy 344.881079 -267.811797) (xy 344.880692 -267.821664) (xy 344.880692 -268.00556)
			(xy 359.650541 -268.00556) (xy 359.654571 -267.953062) (xy 359.666568 -267.901794) (xy 359.686251 -267.852959)
			(xy 359.713157 -267.8077) (xy 359.746657 -267.767079) (xy 359.785965 -267.732048) (xy 359.83016 -267.703428)
			(xy 359.878205 -267.681889) (xy 359.928976 -267.667937) (xy 359.981281 -267.661899) (xy 360.033895 -267.663916)
			(xy 360.085585 -267.67394) (xy 360.135138 -267.691738) (xy 360.181394 -267.716891) (xy 360.223268 -267.74881)
			(xy 360.25978 -267.786748) (xy 360.290072 -267.829814) (xy 360.313435 -267.876999) (xy 360.329321 -267.927198)
			(xy 360.337358 -267.979234) (xy 360.337862 -268.00556) (xy 360.337358 -268.031886) (xy 360.329321 -268.083922)
			(xy 360.313435 -268.134121) (xy 360.290072 -268.181306) (xy 360.25978 -268.224372) (xy 360.223268 -268.26231)
			(xy 360.181394 -268.294229) (xy 360.135138 -268.319382) (xy 360.085585 -268.33718) (xy 360.033895 -268.347204)
			(xy 359.981281 -268.349221) (xy 359.928976 -268.343183) (xy 359.878205 -268.329231) (xy 359.83016 -268.307692)
			(xy 359.785965 -268.279072) (xy 359.746657 -268.244041) (xy 359.713157 -268.20342) (xy 359.686251 -268.158161)
			(xy 359.666568 -268.109326) (xy 359.654571 -268.058058) (xy 359.650541 -268.00556) (xy 344.880692 -268.00556)
			(xy 344.880692 -268.010132) (xy 344.881154 -268.020008) (xy 344.8886 -268.038304) (xy 344.89517 -268.045692)
			(xy 344.895424 -268.045946) (xy 344.945208 -268.09573) (xy 344.952604 -268.102583) (xy 344.971202 -268.110325)
			(xy 344.981276 -268.110716) (xy 345.006514 -268.111259) (xy 345.056297 -268.119608) (xy 345.104028 -268.136032)
			(xy 345.148407 -268.160084) (xy 345.188225 -268.191109) (xy 345.222396 -268.228261) (xy 345.249991 -268.270529)
			(xy 345.270257 -268.31676) (xy 345.282641 -268.365695) (xy 345.286807 -268.416) (xy 345.286805 -268.416024)
			(xy 345.615272 -268.416024) (xy 345.619232 -268.36697) (xy 345.631009 -268.319186) (xy 345.6503 -268.27391)
			(xy 345.676603 -268.232314) (xy 345.709238 -268.195477) (xy 345.747359 -268.164352) (xy 345.78998 -268.139745)
			(xy 345.835996 -268.122293) (xy 345.884215 -268.112449) (xy 345.93339 -268.110468) (xy 345.982245 -268.1164)
			(xy 346.029516 -268.130092) (xy 346.073978 -268.15119) (xy 346.114481 -268.179146) (xy 346.149974 -268.213238)
			(xy 346.179539 -268.252582) (xy 346.20241 -268.296159) (xy 346.217994 -268.34284) (xy 346.225889 -268.391417)
			(xy 346.226384 -268.416024) (xy 347.49538 -268.416024) (xy 347.49934 -268.36697) (xy 347.511117 -268.319186)
			(xy 347.530408 -268.27391) (xy 347.556711 -268.232314) (xy 347.589346 -268.195477) (xy 347.627467 -268.164352)
			(xy 347.670088 -268.139745) (xy 347.716104 -268.122293) (xy 347.764323 -268.112449) (xy 347.813498 -268.110468)
			(xy 347.862353 -268.1164) (xy 347.909624 -268.130092) (xy 347.954086 -268.15119) (xy 347.994589 -268.179146)
			(xy 348.030082 -268.213238) (xy 348.059647 -268.252582) (xy 348.082518 -268.296159) (xy 348.098102 -268.34284)
			(xy 348.105997 -268.391417) (xy 348.106492 -268.416024) (xy 349.375234 -268.416024) (xy 349.379194 -268.36697)
			(xy 349.390971 -268.319186) (xy 349.410262 -268.27391) (xy 349.436565 -268.232314) (xy 349.4692 -268.195477)
			(xy 349.507321 -268.164352) (xy 349.549942 -268.139745) (xy 349.595958 -268.122293) (xy 349.644177 -268.112449)
			(xy 349.693352 -268.110468) (xy 349.742207 -268.1164) (xy 349.789478 -268.130092) (xy 349.83394 -268.15119)
			(xy 349.874443 -268.179146) (xy 349.909936 -268.213238) (xy 349.939501 -268.252582) (xy 349.962372 -268.296159)
			(xy 349.977956 -268.34284) (xy 349.985851 -268.391417) (xy 349.986346 -268.416024) (xy 351.255342 -268.416024)
			(xy 351.259302 -268.36697) (xy 351.271079 -268.319186) (xy 351.29037 -268.27391) (xy 351.316673 -268.232314)
			(xy 351.349308 -268.195477) (xy 351.387429 -268.164352) (xy 351.43005 -268.139745) (xy 351.476066 -268.122293)
			(xy 351.524285 -268.112449) (xy 351.57346 -268.110468) (xy 351.622315 -268.1164) (xy 351.669586 -268.130092)
			(xy 351.714048 -268.15119) (xy 351.754551 -268.179146) (xy 351.790044 -268.213238) (xy 351.819609 -268.252582)
			(xy 351.84248 -268.296159) (xy 351.858064 -268.34284) (xy 351.865959 -268.391417) (xy 351.866454 -268.416024)
			(xy 353.135196 -268.416024) (xy 353.139156 -268.36697) (xy 353.150933 -268.319186) (xy 353.170224 -268.27391)
			(xy 353.196527 -268.232314) (xy 353.229162 -268.195477) (xy 353.267283 -268.164352) (xy 353.309904 -268.139745)
			(xy 353.35592 -268.122293) (xy 353.404139 -268.112449) (xy 353.453314 -268.110468) (xy 353.502169 -268.1164)
			(xy 353.54944 -268.130092) (xy 353.593902 -268.15119) (xy 353.634405 -268.179146) (xy 353.669898 -268.213238)
			(xy 353.699463 -268.252582) (xy 353.722334 -268.296159) (xy 353.737918 -268.34284) (xy 353.745813 -268.391417)
			(xy 353.746308 -268.416024) (xy 355.015304 -268.416024) (xy 355.019264 -268.36697) (xy 355.031041 -268.319186)
			(xy 355.050332 -268.27391) (xy 355.076635 -268.232314) (xy 355.10927 -268.195477) (xy 355.147391 -268.164352)
			(xy 355.190012 -268.139745) (xy 355.236028 -268.122293) (xy 355.284247 -268.112449) (xy 355.333422 -268.110468)
			(xy 355.382277 -268.1164) (xy 355.429548 -268.130092) (xy 355.47401 -268.15119) (xy 355.514513 -268.179146)
			(xy 355.550006 -268.213238) (xy 355.579571 -268.252582) (xy 355.602442 -268.296159) (xy 355.618026 -268.34284)
			(xy 355.625921 -268.391417) (xy 355.626416 -268.416024) (xy 356.895412 -268.416024) (xy 356.899372 -268.36697)
			(xy 356.911149 -268.319186) (xy 356.93044 -268.27391) (xy 356.956743 -268.232314) (xy 356.989378 -268.195477)
			(xy 357.027499 -268.164352) (xy 357.07012 -268.139745) (xy 357.116136 -268.122293) (xy 357.164355 -268.112449)
			(xy 357.21353 -268.110468) (xy 357.262385 -268.1164) (xy 357.309656 -268.130092) (xy 357.354118 -268.15119)
			(xy 357.394621 -268.179146) (xy 357.430114 -268.213238) (xy 357.459679 -268.252582) (xy 357.48255 -268.296159)
			(xy 357.498134 -268.34284) (xy 357.506029 -268.391417) (xy 357.506524 -268.416024) (xy 361.589078 -268.416024)
			(xy 361.593038 -268.36697) (xy 361.604815 -268.319186) (xy 361.624106 -268.27391) (xy 361.650409 -268.232314)
			(xy 361.683044 -268.195477) (xy 361.721165 -268.164352) (xy 361.763786 -268.139745) (xy 361.809802 -268.122293)
			(xy 361.858021 -268.112449) (xy 361.907196 -268.110468) (xy 361.956051 -268.1164) (xy 362.003322 -268.130092)
			(xy 362.047784 -268.15119) (xy 362.088287 -268.179146) (xy 362.12378 -268.213238) (xy 362.153345 -268.252582)
			(xy 362.176216 -268.296159) (xy 362.1918 -268.34284) (xy 362.199695 -268.391417) (xy 362.20019 -268.416024)
			(xy 363.468932 -268.416024) (xy 363.472892 -268.36697) (xy 363.484669 -268.319186) (xy 363.50396 -268.27391)
			(xy 363.530263 -268.232314) (xy 363.562898 -268.195477) (xy 363.601019 -268.164352) (xy 363.64364 -268.139745)
			(xy 363.689656 -268.122293) (xy 363.737875 -268.112449) (xy 363.78705 -268.110468) (xy 363.835905 -268.1164)
			(xy 363.883176 -268.130092) (xy 363.927638 -268.15119) (xy 363.968141 -268.179146) (xy 364.003634 -268.213238)
			(xy 364.033199 -268.252582) (xy 364.05607 -268.296159) (xy 364.071654 -268.34284) (xy 364.079549 -268.391417)
			(xy 364.080044 -268.416024) (xy 365.34904 -268.416024) (xy 365.353 -268.36697) (xy 365.364777 -268.319186)
			(xy 365.384068 -268.27391) (xy 365.410371 -268.232314) (xy 365.443006 -268.195477) (xy 365.481127 -268.164352)
			(xy 365.523748 -268.139745) (xy 365.569764 -268.122293) (xy 365.617983 -268.112449) (xy 365.667158 -268.110468)
			(xy 365.716013 -268.1164) (xy 365.763284 -268.130092) (xy 365.807746 -268.15119) (xy 365.848249 -268.179146)
			(xy 365.883742 -268.213238) (xy 365.913307 -268.252582) (xy 365.936178 -268.296159) (xy 365.951762 -268.34284)
			(xy 365.959657 -268.391417) (xy 365.960152 -268.416024) (xy 367.228894 -268.416024) (xy 367.232854 -268.36697)
			(xy 367.244631 -268.319186) (xy 367.263922 -268.27391) (xy 367.290225 -268.232314) (xy 367.32286 -268.195477)
			(xy 367.360981 -268.164352) (xy 367.403602 -268.139745) (xy 367.449618 -268.122293) (xy 367.497837 -268.112449)
			(xy 367.547012 -268.110468) (xy 367.595867 -268.1164) (xy 367.643138 -268.130092) (xy 367.6876 -268.15119)
			(xy 367.728103 -268.179146) (xy 367.763596 -268.213238) (xy 367.793161 -268.252582) (xy 367.816032 -268.296159)
			(xy 367.831616 -268.34284) (xy 367.839511 -268.391417) (xy 367.840006 -268.416024) (xy 369.109002 -268.416024)
			(xy 369.112962 -268.36697) (xy 369.124739 -268.319186) (xy 369.14403 -268.27391) (xy 369.170333 -268.232314)
			(xy 369.202968 -268.195477) (xy 369.241089 -268.164352) (xy 369.28371 -268.139745) (xy 369.329726 -268.122293)
			(xy 369.377945 -268.112449) (xy 369.42712 -268.110468) (xy 369.475975 -268.1164) (xy 369.523246 -268.130092)
			(xy 369.567708 -268.15119) (xy 369.608211 -268.179146) (xy 369.643704 -268.213238) (xy 369.673269 -268.252582)
			(xy 369.69614 -268.296159) (xy 369.711724 -268.34284) (xy 369.719619 -268.391417) (xy 369.720114 -268.416024)
			(xy 370.98911 -268.416024) (xy 370.99307 -268.36697) (xy 371.004847 -268.319186) (xy 371.024138 -268.27391)
			(xy 371.050441 -268.232314) (xy 371.083076 -268.195477) (xy 371.121197 -268.164352) (xy 371.163818 -268.139745)
			(xy 371.209834 -268.122293) (xy 371.258053 -268.112449) (xy 371.307228 -268.110468) (xy 371.356083 -268.1164)
			(xy 371.403354 -268.130092) (xy 371.447816 -268.15119) (xy 371.488319 -268.179146) (xy 371.523812 -268.213238)
			(xy 371.553377 -268.252582) (xy 371.576248 -268.296159) (xy 371.591832 -268.34284) (xy 371.599727 -268.391417)
			(xy 371.600222 -268.416024) (xy 372.868964 -268.416024) (xy 372.872924 -268.36697) (xy 372.884701 -268.319186)
			(xy 372.903992 -268.27391) (xy 372.930295 -268.232314) (xy 372.96293 -268.195477) (xy 373.001051 -268.164352)
			(xy 373.043672 -268.139745) (xy 373.089688 -268.122293) (xy 373.137907 -268.112449) (xy 373.187082 -268.110468)
			(xy 373.235937 -268.1164) (xy 373.283208 -268.130092) (xy 373.32767 -268.15119) (xy 373.368173 -268.179146)
			(xy 373.403666 -268.213238) (xy 373.433231 -268.252582) (xy 373.456102 -268.296159) (xy 373.471686 -268.34284)
			(xy 373.479581 -268.391417) (xy 373.480076 -268.416024) (xy 373.479581 -268.440631) (xy 373.471686 -268.489208)
			(xy 373.456102 -268.535889) (xy 373.433231 -268.579466) (xy 373.403666 -268.61881) (xy 373.368173 -268.652902)
			(xy 373.32767 -268.680858) (xy 373.283208 -268.701956) (xy 373.235937 -268.715648) (xy 373.187082 -268.72158)
			(xy 373.137907 -268.719599) (xy 373.089688 -268.709755) (xy 373.043672 -268.692303) (xy 373.001051 -268.667696)
			(xy 372.96293 -268.636571) (xy 372.930295 -268.599734) (xy 372.903992 -268.558138) (xy 372.884701 -268.512862)
			(xy 372.872924 -268.465078) (xy 372.868964 -268.416024) (xy 371.600222 -268.416024) (xy 371.599727 -268.440631)
			(xy 371.591832 -268.489208) (xy 371.576248 -268.535889) (xy 371.553377 -268.579466) (xy 371.523812 -268.61881)
			(xy 371.488319 -268.652902) (xy 371.447816 -268.680858) (xy 371.403354 -268.701956) (xy 371.356083 -268.715648)
			(xy 371.307228 -268.72158) (xy 371.258053 -268.719599) (xy 371.209834 -268.709755) (xy 371.163818 -268.692303)
			(xy 371.121197 -268.667696) (xy 371.083076 -268.636571) (xy 371.050441 -268.599734) (xy 371.024138 -268.558138)
			(xy 371.004847 -268.512862) (xy 370.99307 -268.465078) (xy 370.98911 -268.416024) (xy 369.720114 -268.416024)
			(xy 369.719619 -268.440631) (xy 369.711724 -268.489208) (xy 369.69614 -268.535889) (xy 369.673269 -268.579466)
			(xy 369.643704 -268.61881) (xy 369.608211 -268.652902) (xy 369.567708 -268.680858) (xy 369.523246 -268.701956)
			(xy 369.475975 -268.715648) (xy 369.42712 -268.72158) (xy 369.377945 -268.719599) (xy 369.329726 -268.709755)
			(xy 369.28371 -268.692303) (xy 369.241089 -268.667696) (xy 369.202968 -268.636571) (xy 369.170333 -268.599734)
			(xy 369.14403 -268.558138) (xy 369.124739 -268.512862) (xy 369.112962 -268.465078) (xy 369.109002 -268.416024)
			(xy 367.840006 -268.416024) (xy 367.839511 -268.440631) (xy 367.831616 -268.489208) (xy 367.816032 -268.535889)
			(xy 367.793161 -268.579466) (xy 367.763596 -268.61881) (xy 367.728103 -268.652902) (xy 367.6876 -268.680858)
			(xy 367.643138 -268.701956) (xy 367.595867 -268.715648) (xy 367.547012 -268.72158) (xy 367.497837 -268.719599)
			(xy 367.449618 -268.709755) (xy 367.403602 -268.692303) (xy 367.360981 -268.667696) (xy 367.32286 -268.636571)
			(xy 367.290225 -268.599734) (xy 367.263922 -268.558138) (xy 367.244631 -268.512862) (xy 367.232854 -268.465078)
			(xy 367.228894 -268.416024) (xy 365.960152 -268.416024) (xy 365.959657 -268.440631) (xy 365.951762 -268.489208)
			(xy 365.936178 -268.535889) (xy 365.913307 -268.579466) (xy 365.883742 -268.61881) (xy 365.848249 -268.652902)
			(xy 365.807746 -268.680858) (xy 365.763284 -268.701956) (xy 365.716013 -268.715648) (xy 365.667158 -268.72158)
			(xy 365.617983 -268.719599) (xy 365.569764 -268.709755) (xy 365.523748 -268.692303) (xy 365.481127 -268.667696)
			(xy 365.443006 -268.636571) (xy 365.410371 -268.599734) (xy 365.384068 -268.558138) (xy 365.364777 -268.512862)
			(xy 365.353 -268.465078) (xy 365.34904 -268.416024) (xy 364.080044 -268.416024) (xy 364.079549 -268.440631)
			(xy 364.071654 -268.489208) (xy 364.05607 -268.535889) (xy 364.033199 -268.579466) (xy 364.003634 -268.61881)
			(xy 363.968141 -268.652902) (xy 363.927638 -268.680858) (xy 363.883176 -268.701956) (xy 363.835905 -268.715648)
			(xy 363.78705 -268.72158) (xy 363.737875 -268.719599) (xy 363.689656 -268.709755) (xy 363.64364 -268.692303)
			(xy 363.601019 -268.667696) (xy 363.562898 -268.636571) (xy 363.530263 -268.599734) (xy 363.50396 -268.558138)
			(xy 363.484669 -268.512862) (xy 363.472892 -268.465078) (xy 363.468932 -268.416024) (xy 362.20019 -268.416024)
			(xy 362.199695 -268.440631) (xy 362.1918 -268.489208) (xy 362.176216 -268.535889) (xy 362.153345 -268.579466)
			(xy 362.12378 -268.61881) (xy 362.088287 -268.652902) (xy 362.047784 -268.680858) (xy 362.003322 -268.701956)
			(xy 361.956051 -268.715648) (xy 361.907196 -268.72158) (xy 361.858021 -268.719599) (xy 361.809802 -268.709755)
			(xy 361.763786 -268.692303) (xy 361.721165 -268.667696) (xy 361.683044 -268.636571) (xy 361.650409 -268.599734)
			(xy 361.624106 -268.558138) (xy 361.604815 -268.512862) (xy 361.593038 -268.465078) (xy 361.589078 -268.416024)
			(xy 357.506524 -268.416024) (xy 357.506029 -268.440631) (xy 357.498134 -268.489208) (xy 357.48255 -268.535889)
			(xy 357.459679 -268.579466) (xy 357.430114 -268.61881) (xy 357.394621 -268.652902) (xy 357.354118 -268.680858)
			(xy 357.309656 -268.701956) (xy 357.262385 -268.715648) (xy 357.21353 -268.72158) (xy 357.164355 -268.719599)
			(xy 357.116136 -268.709755) (xy 357.07012 -268.692303) (xy 357.027499 -268.667696) (xy 356.989378 -268.636571)
			(xy 356.956743 -268.599734) (xy 356.93044 -268.558138) (xy 356.911149 -268.512862) (xy 356.899372 -268.465078)
			(xy 356.895412 -268.416024) (xy 355.626416 -268.416024) (xy 355.625921 -268.440631) (xy 355.618026 -268.489208)
			(xy 355.602442 -268.535889) (xy 355.579571 -268.579466) (xy 355.550006 -268.61881) (xy 355.514513 -268.652902)
			(xy 355.47401 -268.680858) (xy 355.429548 -268.701956) (xy 355.382277 -268.715648) (xy 355.333422 -268.72158)
			(xy 355.284247 -268.719599) (xy 355.236028 -268.709755) (xy 355.190012 -268.692303) (xy 355.147391 -268.667696)
			(xy 355.10927 -268.636571) (xy 355.076635 -268.599734) (xy 355.050332 -268.558138) (xy 355.031041 -268.512862)
			(xy 355.019264 -268.465078) (xy 355.015304 -268.416024) (xy 353.746308 -268.416024) (xy 353.745813 -268.440631)
			(xy 353.737918 -268.489208) (xy 353.722334 -268.535889) (xy 353.699463 -268.579466) (xy 353.669898 -268.61881)
			(xy 353.634405 -268.652902) (xy 353.593902 -268.680858) (xy 353.54944 -268.701956) (xy 353.502169 -268.715648)
			(xy 353.453314 -268.72158) (xy 353.404139 -268.719599) (xy 353.35592 -268.709755) (xy 353.309904 -268.692303)
			(xy 353.267283 -268.667696) (xy 353.229162 -268.636571) (xy 353.196527 -268.599734) (xy 353.170224 -268.558138)
			(xy 353.150933 -268.512862) (xy 353.139156 -268.465078) (xy 353.135196 -268.416024) (xy 351.866454 -268.416024)
			(xy 351.865959 -268.440631) (xy 351.858064 -268.489208) (xy 351.84248 -268.535889) (xy 351.819609 -268.579466)
			(xy 351.790044 -268.61881) (xy 351.754551 -268.652902) (xy 351.714048 -268.680858) (xy 351.669586 -268.701956)
			(xy 351.622315 -268.715648) (xy 351.57346 -268.72158) (xy 351.524285 -268.719599) (xy 351.476066 -268.709755)
			(xy 351.43005 -268.692303) (xy 351.387429 -268.667696) (xy 351.349308 -268.636571) (xy 351.316673 -268.599734)
			(xy 351.29037 -268.558138) (xy 351.271079 -268.512862) (xy 351.259302 -268.465078) (xy 351.255342 -268.416024)
			(xy 349.986346 -268.416024) (xy 349.985851 -268.440631) (xy 349.977956 -268.489208) (xy 349.962372 -268.535889)
			(xy 349.939501 -268.579466) (xy 349.909936 -268.61881) (xy 349.874443 -268.652902) (xy 349.83394 -268.680858)
			(xy 349.789478 -268.701956) (xy 349.742207 -268.715648) (xy 349.693352 -268.72158) (xy 349.644177 -268.719599)
			(xy 349.595958 -268.709755) (xy 349.549942 -268.692303) (xy 349.507321 -268.667696) (xy 349.4692 -268.636571)
			(xy 349.436565 -268.599734) (xy 349.410262 -268.558138) (xy 349.390971 -268.512862) (xy 349.379194 -268.465078)
			(xy 349.375234 -268.416024) (xy 348.106492 -268.416024) (xy 348.105997 -268.440631) (xy 348.098102 -268.489208)
			(xy 348.082518 -268.535889) (xy 348.059647 -268.579466) (xy 348.030082 -268.61881) (xy 347.994589 -268.652902)
			(xy 347.954086 -268.680858) (xy 347.909624 -268.701956) (xy 347.862353 -268.715648) (xy 347.813498 -268.72158)
			(xy 347.764323 -268.719599) (xy 347.716104 -268.709755) (xy 347.670088 -268.692303) (xy 347.627467 -268.667696)
			(xy 347.589346 -268.636571) (xy 347.556711 -268.599734) (xy 347.530408 -268.558138) (xy 347.511117 -268.512862)
			(xy 347.49934 -268.465078) (xy 347.49538 -268.416024) (xy 346.226384 -268.416024) (xy 346.225889 -268.440631)
			(xy 346.217994 -268.489208) (xy 346.20241 -268.535889) (xy 346.179539 -268.579466) (xy 346.149974 -268.61881)
			(xy 346.114481 -268.652902) (xy 346.073978 -268.680858) (xy 346.029516 -268.701956) (xy 345.982245 -268.715648)
			(xy 345.93339 -268.72158) (xy 345.884215 -268.719599) (xy 345.835996 -268.709755) (xy 345.78998 -268.692303)
			(xy 345.747359 -268.667696) (xy 345.709238 -268.636571) (xy 345.676603 -268.599734) (xy 345.6503 -268.558138)
			(xy 345.631009 -268.512862) (xy 345.619232 -268.465078) (xy 345.615272 -268.416024) (xy 345.286805 -268.416024)
			(xy 345.282641 -268.466306) (xy 345.270257 -268.51524) (xy 345.249991 -268.561471) (xy 345.222396 -268.603739)
			(xy 345.188225 -268.640891) (xy 345.148407 -268.671916) (xy 345.104028 -268.695968) (xy 345.056297 -268.712392)
			(xy 345.006514 -268.720741) (xy 344.981276 -268.721332) (xy 344.971208 -268.72176) (xy 344.952613 -268.729484)
			(xy 344.945208 -268.736318) (xy 344.895424 -268.786102) (xy 344.888705 -268.793338) (xy 344.881102 -268.811543)
			(xy 344.880692 -268.821408) (xy 344.880692 -269.22603) (xy 347.025226 -269.22603) (xy 347.029186 -269.176976)
			(xy 347.040963 -269.129192) (xy 347.060254 -269.083916) (xy 347.086557 -269.04232) (xy 347.119192 -269.005483)
			(xy 347.157313 -268.974358) (xy 347.199934 -268.949751) (xy 347.24595 -268.932299) (xy 347.294169 -268.922455)
			(xy 347.343344 -268.920474) (xy 347.392199 -268.926406) (xy 347.43947 -268.940098) (xy 347.483932 -268.961196)
			(xy 347.524435 -268.989152) (xy 347.559928 -269.023244) (xy 347.589493 -269.062588) (xy 347.612364 -269.106165)
			(xy 347.627948 -269.152846) (xy 347.635843 -269.201423) (xy 347.636338 -269.22603) (xy 349.845388 -269.22603)
			(xy 349.849348 -269.176976) (xy 349.861125 -269.129192) (xy 349.880416 -269.083916) (xy 349.906719 -269.04232)
			(xy 349.939354 -269.005483) (xy 349.977475 -268.974358) (xy 350.020096 -268.949751) (xy 350.066112 -268.932299)
			(xy 350.114331 -268.922455) (xy 350.163506 -268.920474) (xy 350.212361 -268.926406) (xy 350.259632 -268.940098)
			(xy 350.304094 -268.961196) (xy 350.344597 -268.989152) (xy 350.38009 -269.023244) (xy 350.409655 -269.062588)
			(xy 350.432526 -269.106165) (xy 350.44811 -269.152846) (xy 350.456005 -269.201423) (xy 350.4565 -269.22603)
			(xy 352.665296 -269.22603) (xy 352.669256 -269.176976) (xy 352.681033 -269.129192) (xy 352.700324 -269.083916)
			(xy 352.726627 -269.04232) (xy 352.759262 -269.005483) (xy 352.797383 -268.974358) (xy 352.840004 -268.949751)
			(xy 352.88602 -268.932299) (xy 352.934239 -268.922455) (xy 352.983414 -268.920474) (xy 353.032269 -268.926406)
			(xy 353.07954 -268.940098) (xy 353.124002 -268.961196) (xy 353.164505 -268.989152) (xy 353.199998 -269.023244)
			(xy 353.229563 -269.062588) (xy 353.252434 -269.106165) (xy 353.268018 -269.152846) (xy 353.275913 -269.201423)
			(xy 353.276408 -269.22603) (xy 355.485204 -269.22603) (xy 355.489164 -269.176976) (xy 355.500941 -269.129192)
			(xy 355.520232 -269.083916) (xy 355.546535 -269.04232) (xy 355.57917 -269.005483) (xy 355.617291 -268.974358)
			(xy 355.659912 -268.949751) (xy 355.705928 -268.932299) (xy 355.754147 -268.922455) (xy 355.803322 -268.920474)
			(xy 355.852177 -268.926406) (xy 355.899448 -268.940098) (xy 355.94391 -268.961196) (xy 355.984413 -268.989152)
			(xy 356.019906 -269.023244) (xy 356.049471 -269.062588) (xy 356.072342 -269.106165) (xy 356.087926 -269.152846)
			(xy 356.095821 -269.201423) (xy 356.096316 -269.22603) (xy 356.425258 -269.22603) (xy 356.429218 -269.176976)
			(xy 356.440995 -269.129192) (xy 356.460286 -269.083916) (xy 356.486589 -269.04232) (xy 356.519224 -269.005483)
			(xy 356.557345 -268.974358) (xy 356.599966 -268.949751) (xy 356.645982 -268.932299) (xy 356.694201 -268.922455)
			(xy 356.743376 -268.920474) (xy 356.792231 -268.926406) (xy 356.839502 -268.940098) (xy 356.883964 -268.961196)
			(xy 356.924467 -268.989152) (xy 356.95996 -269.023244) (xy 356.989525 -269.062588) (xy 357.012396 -269.106165)
			(xy 357.02798 -269.152846) (xy 357.035875 -269.201423) (xy 357.03637 -269.22603) (xy 357.365312 -269.22603)
			(xy 357.369272 -269.176976) (xy 357.381049 -269.129192) (xy 357.40034 -269.083916) (xy 357.426643 -269.04232)
			(xy 357.459278 -269.005483) (xy 357.497399 -268.974358) (xy 357.54002 -268.949751) (xy 357.586036 -268.932299)
			(xy 357.634255 -268.922455) (xy 357.68343 -268.920474) (xy 357.732285 -268.926406) (xy 357.779556 -268.940098)
			(xy 357.824018 -268.961196) (xy 357.864521 -268.989152) (xy 357.900014 -269.023244) (xy 357.929579 -269.062588)
			(xy 357.95245 -269.106165) (xy 357.968034 -269.152846) (xy 357.975929 -269.201423) (xy 357.976424 -269.22603)
			(xy 358.305366 -269.22603) (xy 358.309326 -269.176976) (xy 358.321103 -269.129192) (xy 358.340394 -269.083916)
			(xy 358.366697 -269.04232) (xy 358.399332 -269.005483) (xy 358.437453 -268.974358) (xy 358.480074 -268.949751)
			(xy 358.52609 -268.932299) (xy 358.574309 -268.922455) (xy 358.623484 -268.920474) (xy 358.672339 -268.926406)
			(xy 358.71961 -268.940098) (xy 358.764072 -268.961196) (xy 358.804575 -268.989152) (xy 358.840068 -269.023244)
			(xy 358.869633 -269.062588) (xy 358.892504 -269.106165) (xy 358.908088 -269.152846) (xy 358.915983 -269.201423)
			(xy 358.916478 -269.22603) (xy 361.118924 -269.22603) (xy 361.122884 -269.176976) (xy 361.134661 -269.129192)
			(xy 361.153952 -269.083916) (xy 361.180255 -269.04232) (xy 361.21289 -269.005483) (xy 361.251011 -268.974358)
			(xy 361.293632 -268.949751) (xy 361.339648 -268.932299) (xy 361.387867 -268.922455) (xy 361.437042 -268.920474)
			(xy 361.485897 -268.926406) (xy 361.533168 -268.940098) (xy 361.57763 -268.961196) (xy 361.618133 -268.989152)
			(xy 361.653626 -269.023244) (xy 361.683191 -269.062588) (xy 361.706062 -269.106165) (xy 361.721646 -269.152846)
			(xy 361.729541 -269.201423) (xy 361.730036 -269.22603) (xy 362.058978 -269.22603) (xy 362.062938 -269.176976)
			(xy 362.074715 -269.129192) (xy 362.094006 -269.083916) (xy 362.120309 -269.04232) (xy 362.152944 -269.005483)
			(xy 362.191065 -268.974358) (xy 362.233686 -268.949751) (xy 362.279702 -268.932299) (xy 362.327921 -268.922455)
			(xy 362.377096 -268.920474) (xy 362.425951 -268.926406) (xy 362.473222 -268.940098) (xy 362.517684 -268.961196)
			(xy 362.558187 -268.989152) (xy 362.59368 -269.023244) (xy 362.623245 -269.062588) (xy 362.646116 -269.106165)
			(xy 362.6617 -269.152846) (xy 362.669595 -269.201423) (xy 362.67009 -269.22603) (xy 362.999032 -269.22603)
			(xy 363.002992 -269.176976) (xy 363.014769 -269.129192) (xy 363.03406 -269.083916) (xy 363.060363 -269.04232)
			(xy 363.092998 -269.005483) (xy 363.131119 -268.974358) (xy 363.17374 -268.949751) (xy 363.219756 -268.932299)
			(xy 363.267975 -268.922455) (xy 363.31715 -268.920474) (xy 363.366005 -268.926406) (xy 363.413276 -268.940098)
			(xy 363.457738 -268.961196) (xy 363.498241 -268.989152) (xy 363.533734 -269.023244) (xy 363.563299 -269.062588)
			(xy 363.58617 -269.106165) (xy 363.601754 -269.152846) (xy 363.609649 -269.201423) (xy 363.610144 -269.22603)
			(xy 363.939086 -269.22603) (xy 363.943046 -269.176976) (xy 363.954823 -269.129192) (xy 363.974114 -269.083916)
			(xy 364.000417 -269.04232) (xy 364.033052 -269.005483) (xy 364.071173 -268.974358) (xy 364.113794 -268.949751)
			(xy 364.15981 -268.932299) (xy 364.208029 -268.922455) (xy 364.257204 -268.920474) (xy 364.306059 -268.926406)
			(xy 364.35333 -268.940098) (xy 364.397792 -268.961196) (xy 364.438295 -268.989152) (xy 364.473788 -269.023244)
			(xy 364.503353 -269.062588) (xy 364.526224 -269.106165) (xy 364.541808 -269.152846) (xy 364.549703 -269.201423)
			(xy 364.550198 -269.22603) (xy 366.758994 -269.22603) (xy 366.762954 -269.176976) (xy 366.774731 -269.129192)
			(xy 366.794022 -269.083916) (xy 366.820325 -269.04232) (xy 366.85296 -269.005483) (xy 366.891081 -268.974358)
			(xy 366.933702 -268.949751) (xy 366.979718 -268.932299) (xy 367.027937 -268.922455) (xy 367.077112 -268.920474)
			(xy 367.125967 -268.926406) (xy 367.173238 -268.940098) (xy 367.2177 -268.961196) (xy 367.258203 -268.989152)
			(xy 367.293696 -269.023244) (xy 367.323261 -269.062588) (xy 367.346132 -269.106165) (xy 367.361716 -269.152846)
			(xy 367.369611 -269.201423) (xy 367.370106 -269.22603) (xy 369.578902 -269.22603) (xy 369.582862 -269.176976)
			(xy 369.594639 -269.129192) (xy 369.61393 -269.083916) (xy 369.640233 -269.04232) (xy 369.672868 -269.005483)
			(xy 369.710989 -268.974358) (xy 369.75361 -268.949751) (xy 369.799626 -268.932299) (xy 369.847845 -268.922455)
			(xy 369.89702 -268.920474) (xy 369.945875 -268.926406) (xy 369.993146 -268.940098) (xy 370.037608 -268.961196)
			(xy 370.078111 -268.989152) (xy 370.113604 -269.023244) (xy 370.143169 -269.062588) (xy 370.16604 -269.106165)
			(xy 370.181624 -269.152846) (xy 370.189519 -269.201423) (xy 370.190014 -269.22603) (xy 372.399064 -269.22603)
			(xy 372.403024 -269.176976) (xy 372.414801 -269.129192) (xy 372.434092 -269.083916) (xy 372.460395 -269.04232)
			(xy 372.49303 -269.005483) (xy 372.531151 -268.974358) (xy 372.573772 -268.949751) (xy 372.619788 -268.932299)
			(xy 372.668007 -268.922455) (xy 372.717182 -268.920474) (xy 372.766037 -268.926406) (xy 372.813308 -268.940098)
			(xy 372.85777 -268.961196) (xy 372.898273 -268.989152) (xy 372.933766 -269.023244) (xy 372.963331 -269.062588)
			(xy 372.986202 -269.106165) (xy 373.001786 -269.152846) (xy 373.009681 -269.201423) (xy 373.010176 -269.22603)
			(xy 373.009681 -269.250637) (xy 373.001786 -269.299214) (xy 372.986202 -269.345895) (xy 372.963331 -269.389472)
			(xy 372.933766 -269.428816) (xy 372.898273 -269.462908) (xy 372.85777 -269.490864) (xy 372.813308 -269.511962)
			(xy 372.766037 -269.525654) (xy 372.717182 -269.531586) (xy 372.668007 -269.529605) (xy 372.619788 -269.519761)
			(xy 372.573772 -269.502309) (xy 372.531151 -269.477702) (xy 372.49303 -269.446577) (xy 372.460395 -269.40974)
			(xy 372.434092 -269.368144) (xy 372.414801 -269.322868) (xy 372.403024 -269.275084) (xy 372.399064 -269.22603)
			(xy 370.190014 -269.22603) (xy 370.189519 -269.250637) (xy 370.181624 -269.299214) (xy 370.16604 -269.345895)
			(xy 370.143169 -269.389472) (xy 370.113604 -269.428816) (xy 370.078111 -269.462908) (xy 370.037608 -269.490864)
			(xy 369.993146 -269.511962) (xy 369.945875 -269.525654) (xy 369.89702 -269.531586) (xy 369.847845 -269.529605)
			(xy 369.799626 -269.519761) (xy 369.75361 -269.502309) (xy 369.710989 -269.477702) (xy 369.672868 -269.446577)
			(xy 369.640233 -269.40974) (xy 369.61393 -269.368144) (xy 369.594639 -269.322868) (xy 369.582862 -269.275084)
			(xy 369.578902 -269.22603) (xy 367.370106 -269.22603) (xy 367.369611 -269.250637) (xy 367.361716 -269.299214)
			(xy 367.346132 -269.345895) (xy 367.323261 -269.389472) (xy 367.293696 -269.428816) (xy 367.258203 -269.462908)
			(xy 367.2177 -269.490864) (xy 367.173238 -269.511962) (xy 367.125967 -269.525654) (xy 367.077112 -269.531586)
			(xy 367.027937 -269.529605) (xy 366.979718 -269.519761) (xy 366.933702 -269.502309) (xy 366.891081 -269.477702)
			(xy 366.85296 -269.446577) (xy 366.820325 -269.40974) (xy 366.794022 -269.368144) (xy 366.774731 -269.322868)
			(xy 366.762954 -269.275084) (xy 366.758994 -269.22603) (xy 364.550198 -269.22603) (xy 364.549703 -269.250637)
			(xy 364.541808 -269.299214) (xy 364.526224 -269.345895) (xy 364.503353 -269.389472) (xy 364.473788 -269.428816)
			(xy 364.438295 -269.462908) (xy 364.397792 -269.490864) (xy 364.35333 -269.511962) (xy 364.306059 -269.525654)
			(xy 364.257204 -269.531586) (xy 364.208029 -269.529605) (xy 364.15981 -269.519761) (xy 364.113794 -269.502309)
			(xy 364.071173 -269.477702) (xy 364.033052 -269.446577) (xy 364.000417 -269.40974) (xy 363.974114 -269.368144)
			(xy 363.954823 -269.322868) (xy 363.943046 -269.275084) (xy 363.939086 -269.22603) (xy 363.610144 -269.22603)
			(xy 363.609649 -269.250637) (xy 363.601754 -269.299214) (xy 363.58617 -269.345895) (xy 363.563299 -269.389472)
			(xy 363.533734 -269.428816) (xy 363.498241 -269.462908) (xy 363.457738 -269.490864) (xy 363.413276 -269.511962)
			(xy 363.366005 -269.525654) (xy 363.31715 -269.531586) (xy 363.267975 -269.529605) (xy 363.219756 -269.519761)
			(xy 363.17374 -269.502309) (xy 363.131119 -269.477702) (xy 363.092998 -269.446577) (xy 363.060363 -269.40974)
			(xy 363.03406 -269.368144) (xy 363.014769 -269.322868) (xy 363.002992 -269.275084) (xy 362.999032 -269.22603)
			(xy 362.67009 -269.22603) (xy 362.669595 -269.250637) (xy 362.6617 -269.299214) (xy 362.646116 -269.345895)
			(xy 362.623245 -269.389472) (xy 362.59368 -269.428816) (xy 362.558187 -269.462908) (xy 362.517684 -269.490864)
			(xy 362.473222 -269.511962) (xy 362.425951 -269.525654) (xy 362.377096 -269.531586) (xy 362.327921 -269.529605)
			(xy 362.279702 -269.519761) (xy 362.233686 -269.502309) (xy 362.191065 -269.477702) (xy 362.152944 -269.446577)
			(xy 362.120309 -269.40974) (xy 362.094006 -269.368144) (xy 362.074715 -269.322868) (xy 362.062938 -269.275084)
			(xy 362.058978 -269.22603) (xy 361.730036 -269.22603) (xy 361.729541 -269.250637) (xy 361.721646 -269.299214)
			(xy 361.706062 -269.345895) (xy 361.683191 -269.389472) (xy 361.653626 -269.428816) (xy 361.618133 -269.462908)
			(xy 361.57763 -269.490864) (xy 361.533168 -269.511962) (xy 361.485897 -269.525654) (xy 361.437042 -269.531586)
			(xy 361.387867 -269.529605) (xy 361.339648 -269.519761) (xy 361.293632 -269.502309) (xy 361.251011 -269.477702)
			(xy 361.21289 -269.446577) (xy 361.180255 -269.40974) (xy 361.153952 -269.368144) (xy 361.134661 -269.322868)
			(xy 361.122884 -269.275084) (xy 361.118924 -269.22603) (xy 358.916478 -269.22603) (xy 358.915983 -269.250637)
			(xy 358.908088 -269.299214) (xy 358.892504 -269.345895) (xy 358.869633 -269.389472) (xy 358.840068 -269.428816)
			(xy 358.804575 -269.462908) (xy 358.764072 -269.490864) (xy 358.71961 -269.511962) (xy 358.672339 -269.525654)
			(xy 358.623484 -269.531586) (xy 358.574309 -269.529605) (xy 358.52609 -269.519761) (xy 358.480074 -269.502309)
			(xy 358.437453 -269.477702) (xy 358.399332 -269.446577) (xy 358.366697 -269.40974) (xy 358.340394 -269.368144)
			(xy 358.321103 -269.322868) (xy 358.309326 -269.275084) (xy 358.305366 -269.22603) (xy 357.976424 -269.22603)
			(xy 357.975929 -269.250637) (xy 357.968034 -269.299214) (xy 357.95245 -269.345895) (xy 357.929579 -269.389472)
			(xy 357.900014 -269.428816) (xy 357.864521 -269.462908) (xy 357.824018 -269.490864) (xy 357.779556 -269.511962)
			(xy 357.732285 -269.525654) (xy 357.68343 -269.531586) (xy 357.634255 -269.529605) (xy 357.586036 -269.519761)
			(xy 357.54002 -269.502309) (xy 357.497399 -269.477702) (xy 357.459278 -269.446577) (xy 357.426643 -269.40974)
			(xy 357.40034 -269.368144) (xy 357.381049 -269.322868) (xy 357.369272 -269.275084) (xy 357.365312 -269.22603)
			(xy 357.03637 -269.22603) (xy 357.035875 -269.250637) (xy 357.02798 -269.299214) (xy 357.012396 -269.345895)
			(xy 356.989525 -269.389472) (xy 356.95996 -269.428816) (xy 356.924467 -269.462908) (xy 356.883964 -269.490864)
			(xy 356.839502 -269.511962) (xy 356.792231 -269.525654) (xy 356.743376 -269.531586) (xy 356.694201 -269.529605)
			(xy 356.645982 -269.519761) (xy 356.599966 -269.502309) (xy 356.557345 -269.477702) (xy 356.519224 -269.446577)
			(xy 356.486589 -269.40974) (xy 356.460286 -269.368144) (xy 356.440995 -269.322868) (xy 356.429218 -269.275084)
			(xy 356.425258 -269.22603) (xy 356.096316 -269.22603) (xy 356.095821 -269.250637) (xy 356.087926 -269.299214)
			(xy 356.072342 -269.345895) (xy 356.049471 -269.389472) (xy 356.019906 -269.428816) (xy 355.984413 -269.462908)
			(xy 355.94391 -269.490864) (xy 355.899448 -269.511962) (xy 355.852177 -269.525654) (xy 355.803322 -269.531586)
			(xy 355.754147 -269.529605) (xy 355.705928 -269.519761) (xy 355.659912 -269.502309) (xy 355.617291 -269.477702)
			(xy 355.57917 -269.446577) (xy 355.546535 -269.40974) (xy 355.520232 -269.368144) (xy 355.500941 -269.322868)
			(xy 355.489164 -269.275084) (xy 355.485204 -269.22603) (xy 353.276408 -269.22603) (xy 353.275913 -269.250637)
			(xy 353.268018 -269.299214) (xy 353.252434 -269.345895) (xy 353.229563 -269.389472) (xy 353.199998 -269.428816)
			(xy 353.164505 -269.462908) (xy 353.124002 -269.490864) (xy 353.07954 -269.511962) (xy 353.032269 -269.525654)
			(xy 352.983414 -269.531586) (xy 352.934239 -269.529605) (xy 352.88602 -269.519761) (xy 352.840004 -269.502309)
			(xy 352.797383 -269.477702) (xy 352.759262 -269.446577) (xy 352.726627 -269.40974) (xy 352.700324 -269.368144)
			(xy 352.681033 -269.322868) (xy 352.669256 -269.275084) (xy 352.665296 -269.22603) (xy 350.4565 -269.22603)
			(xy 350.456005 -269.250637) (xy 350.44811 -269.299214) (xy 350.432526 -269.345895) (xy 350.409655 -269.389472)
			(xy 350.38009 -269.428816) (xy 350.344597 -269.462908) (xy 350.304094 -269.490864) (xy 350.259632 -269.511962)
			(xy 350.212361 -269.525654) (xy 350.163506 -269.531586) (xy 350.114331 -269.529605) (xy 350.066112 -269.519761)
			(xy 350.020096 -269.502309) (xy 349.977475 -269.477702) (xy 349.939354 -269.446577) (xy 349.906719 -269.40974)
			(xy 349.880416 -269.368144) (xy 349.861125 -269.322868) (xy 349.849348 -269.275084) (xy 349.845388 -269.22603)
			(xy 347.636338 -269.22603) (xy 347.635843 -269.250637) (xy 347.627948 -269.299214) (xy 347.612364 -269.345895)
			(xy 347.589493 -269.389472) (xy 347.559928 -269.428816) (xy 347.524435 -269.462908) (xy 347.483932 -269.490864)
			(xy 347.43947 -269.511962) (xy 347.392199 -269.525654) (xy 347.343344 -269.531586) (xy 347.294169 -269.529605)
			(xy 347.24595 -269.519761) (xy 347.199934 -269.502309) (xy 347.157313 -269.477702) (xy 347.119192 -269.446577)
			(xy 347.086557 -269.40974) (xy 347.060254 -269.368144) (xy 347.040963 -269.322868) (xy 347.029186 -269.275084)
			(xy 347.025226 -269.22603) (xy 344.880692 -269.22603) (xy 344.880692 -269.630144) (xy 344.881157 -269.640019)
			(xy 344.888606 -269.658312) (xy 344.89517 -269.665704) (xy 344.895424 -269.665958) (xy 344.945208 -269.715742)
			(xy 344.952604 -269.722594) (xy 344.971203 -269.730334) (xy 344.981276 -269.730728) (xy 345.006513 -269.731271)
			(xy 345.056294 -269.739619) (xy 345.104023 -269.756043) (xy 345.1484 -269.780094) (xy 345.188216 -269.811118)
			(xy 345.222387 -269.848269) (xy 345.24998 -269.890534) (xy 345.270245 -269.936764) (xy 345.282629 -269.985697)
			(xy 345.286795 -270.036) (xy 345.286792 -270.036036) (xy 345.615272 -270.036036) (xy 345.619232 -269.986982)
			(xy 345.631009 -269.939198) (xy 345.6503 -269.893922) (xy 345.676603 -269.852326) (xy 345.709238 -269.815489)
			(xy 345.747359 -269.784364) (xy 345.78998 -269.759757) (xy 345.835996 -269.742305) (xy 345.884215 -269.732461)
			(xy 345.93339 -269.73048) (xy 345.982245 -269.736412) (xy 346.029516 -269.750104) (xy 346.073978 -269.771202)
			(xy 346.114481 -269.799158) (xy 346.149974 -269.83325) (xy 346.179539 -269.872594) (xy 346.20241 -269.916171)
			(xy 346.217994 -269.962852) (xy 346.225889 -270.011429) (xy 346.226384 -270.036036) (xy 346.555326 -270.036036)
			(xy 346.559286 -269.986982) (xy 346.571063 -269.939198) (xy 346.590354 -269.893922) (xy 346.616657 -269.852326)
			(xy 346.649292 -269.815489) (xy 346.687413 -269.784364) (xy 346.730034 -269.759757) (xy 346.77605 -269.742305)
			(xy 346.824269 -269.732461) (xy 346.873444 -269.73048) (xy 346.922299 -269.736412) (xy 346.96957 -269.750104)
			(xy 347.014032 -269.771202) (xy 347.054535 -269.799158) (xy 347.090028 -269.83325) (xy 347.119593 -269.872594)
			(xy 347.142464 -269.916171) (xy 347.158048 -269.962852) (xy 347.165943 -270.011429) (xy 347.166438 -270.036036)
			(xy 347.49538 -270.036036) (xy 347.49934 -269.986982) (xy 347.511117 -269.939198) (xy 347.530408 -269.893922)
			(xy 347.556711 -269.852326) (xy 347.589346 -269.815489) (xy 347.627467 -269.784364) (xy 347.670088 -269.759757)
			(xy 347.716104 -269.742305) (xy 347.764323 -269.732461) (xy 347.813498 -269.73048) (xy 347.862353 -269.736412)
			(xy 347.909624 -269.750104) (xy 347.954086 -269.771202) (xy 347.994589 -269.799158) (xy 348.030082 -269.83325)
			(xy 348.059647 -269.872594) (xy 348.082518 -269.916171) (xy 348.098102 -269.962852) (xy 348.105997 -270.011429)
			(xy 348.106492 -270.036036) (xy 348.435434 -270.036036) (xy 348.439394 -269.986982) (xy 348.451171 -269.939198)
			(xy 348.470462 -269.893922) (xy 348.496765 -269.852326) (xy 348.5294 -269.815489) (xy 348.567521 -269.784364)
			(xy 348.610142 -269.759757) (xy 348.656158 -269.742305) (xy 348.704377 -269.732461) (xy 348.753552 -269.73048)
			(xy 348.802407 -269.736412) (xy 348.849678 -269.750104) (xy 348.89414 -269.771202) (xy 348.934643 -269.799158)
			(xy 348.970136 -269.83325) (xy 348.999701 -269.872594) (xy 349.022572 -269.916171) (xy 349.038156 -269.962852)
			(xy 349.046051 -270.011429) (xy 349.046546 -270.036036) (xy 349.375234 -270.036036) (xy 349.379194 -269.986982)
			(xy 349.390971 -269.939198) (xy 349.410262 -269.893922) (xy 349.436565 -269.852326) (xy 349.4692 -269.815489)
			(xy 349.507321 -269.784364) (xy 349.549942 -269.759757) (xy 349.595958 -269.742305) (xy 349.644177 -269.732461)
			(xy 349.693352 -269.73048) (xy 349.742207 -269.736412) (xy 349.789478 -269.750104) (xy 349.83394 -269.771202)
			(xy 349.874443 -269.799158) (xy 349.909936 -269.83325) (xy 349.939501 -269.872594) (xy 349.962372 -269.916171)
			(xy 349.977956 -269.962852) (xy 349.985851 -270.011429) (xy 349.986346 -270.036036) (xy 350.315288 -270.036036)
			(xy 350.319248 -269.986982) (xy 350.331025 -269.939198) (xy 350.350316 -269.893922) (xy 350.376619 -269.852326)
			(xy 350.409254 -269.815489) (xy 350.447375 -269.784364) (xy 350.489996 -269.759757) (xy 350.536012 -269.742305)
			(xy 350.584231 -269.732461) (xy 350.633406 -269.73048) (xy 350.682261 -269.736412) (xy 350.729532 -269.750104)
			(xy 350.773994 -269.771202) (xy 350.814497 -269.799158) (xy 350.84999 -269.83325) (xy 350.879555 -269.872594)
			(xy 350.902426 -269.916171) (xy 350.91801 -269.962852) (xy 350.925905 -270.011429) (xy 350.9264 -270.036036)
			(xy 351.255342 -270.036036) (xy 351.259302 -269.986982) (xy 351.271079 -269.939198) (xy 351.29037 -269.893922)
			(xy 351.316673 -269.852326) (xy 351.349308 -269.815489) (xy 351.387429 -269.784364) (xy 351.43005 -269.759757)
			(xy 351.476066 -269.742305) (xy 351.524285 -269.732461) (xy 351.57346 -269.73048) (xy 351.622315 -269.736412)
			(xy 351.669586 -269.750104) (xy 351.714048 -269.771202) (xy 351.754551 -269.799158) (xy 351.790044 -269.83325)
			(xy 351.819609 -269.872594) (xy 351.84248 -269.916171) (xy 351.858064 -269.962852) (xy 351.865959 -270.011429)
			(xy 351.866454 -270.036036) (xy 352.195396 -270.036036) (xy 352.199356 -269.986982) (xy 352.211133 -269.939198)
			(xy 352.230424 -269.893922) (xy 352.256727 -269.852326) (xy 352.289362 -269.815489) (xy 352.327483 -269.784364)
			(xy 352.370104 -269.759757) (xy 352.41612 -269.742305) (xy 352.464339 -269.732461) (xy 352.513514 -269.73048)
			(xy 352.562369 -269.736412) (xy 352.60964 -269.750104) (xy 352.654102 -269.771202) (xy 352.694605 -269.799158)
			(xy 352.730098 -269.83325) (xy 352.759663 -269.872594) (xy 352.782534 -269.916171) (xy 352.798118 -269.962852)
			(xy 352.806013 -270.011429) (xy 352.806508 -270.036036) (xy 353.135196 -270.036036) (xy 353.139156 -269.986982)
			(xy 353.150933 -269.939198) (xy 353.170224 -269.893922) (xy 353.196527 -269.852326) (xy 353.229162 -269.815489)
			(xy 353.267283 -269.784364) (xy 353.309904 -269.759757) (xy 353.35592 -269.742305) (xy 353.404139 -269.732461)
			(xy 353.453314 -269.73048) (xy 353.502169 -269.736412) (xy 353.54944 -269.750104) (xy 353.593902 -269.771202)
			(xy 353.634405 -269.799158) (xy 353.669898 -269.83325) (xy 353.699463 -269.872594) (xy 353.722334 -269.916171)
			(xy 353.737918 -269.962852) (xy 353.745813 -270.011429) (xy 353.746308 -270.036036) (xy 354.07525 -270.036036)
			(xy 354.07921 -269.986982) (xy 354.090987 -269.939198) (xy 354.110278 -269.893922) (xy 354.136581 -269.852326)
			(xy 354.169216 -269.815489) (xy 354.207337 -269.784364) (xy 354.249958 -269.759757) (xy 354.295974 -269.742305)
			(xy 354.344193 -269.732461) (xy 354.393368 -269.73048) (xy 354.442223 -269.736412) (xy 354.489494 -269.750104)
			(xy 354.533956 -269.771202) (xy 354.574459 -269.799158) (xy 354.609952 -269.83325) (xy 354.639517 -269.872594)
			(xy 354.662388 -269.916171) (xy 354.677972 -269.962852) (xy 354.685867 -270.011429) (xy 354.686362 -270.036036)
			(xy 355.015304 -270.036036) (xy 355.019264 -269.986982) (xy 355.031041 -269.939198) (xy 355.050332 -269.893922)
			(xy 355.076635 -269.852326) (xy 355.10927 -269.815489) (xy 355.147391 -269.784364) (xy 355.190012 -269.759757)
			(xy 355.236028 -269.742305) (xy 355.284247 -269.732461) (xy 355.333422 -269.73048) (xy 355.382277 -269.736412)
			(xy 355.429548 -269.750104) (xy 355.47401 -269.771202) (xy 355.514513 -269.799158) (xy 355.550006 -269.83325)
			(xy 355.579571 -269.872594) (xy 355.602442 -269.916171) (xy 355.618026 -269.962852) (xy 355.625921 -270.011429)
			(xy 355.626416 -270.036036) (xy 355.955358 -270.036036) (xy 355.959318 -269.986982) (xy 355.971095 -269.939198)
			(xy 355.990386 -269.893922) (xy 356.016689 -269.852326) (xy 356.049324 -269.815489) (xy 356.087445 -269.784364)
			(xy 356.130066 -269.759757) (xy 356.176082 -269.742305) (xy 356.224301 -269.732461) (xy 356.273476 -269.73048)
			(xy 356.322331 -269.736412) (xy 356.369602 -269.750104) (xy 356.414064 -269.771202) (xy 356.454567 -269.799158)
			(xy 356.49006 -269.83325) (xy 356.519625 -269.872594) (xy 356.542496 -269.916171) (xy 356.55808 -269.962852)
			(xy 356.565975 -270.011429) (xy 356.56647 -270.036036) (xy 356.895412 -270.036036) (xy 356.899372 -269.986982)
			(xy 356.911149 -269.939198) (xy 356.93044 -269.893922) (xy 356.956743 -269.852326) (xy 356.989378 -269.815489)
			(xy 357.027499 -269.784364) (xy 357.07012 -269.759757) (xy 357.116136 -269.742305) (xy 357.164355 -269.732461)
			(xy 357.21353 -269.73048) (xy 357.262385 -269.736412) (xy 357.309656 -269.750104) (xy 357.354118 -269.771202)
			(xy 357.394621 -269.799158) (xy 357.430114 -269.83325) (xy 357.459679 -269.872594) (xy 357.48255 -269.916171)
			(xy 357.498134 -269.962852) (xy 357.506029 -270.011429) (xy 357.506524 -270.036036) (xy 357.835212 -270.036036)
			(xy 357.839172 -269.986982) (xy 357.850949 -269.939198) (xy 357.87024 -269.893922) (xy 357.896543 -269.852326)
			(xy 357.929178 -269.815489) (xy 357.967299 -269.784364) (xy 358.00992 -269.759757) (xy 358.055936 -269.742305)
			(xy 358.104155 -269.732461) (xy 358.15333 -269.73048) (xy 358.202185 -269.736412) (xy 358.249456 -269.750104)
			(xy 358.293918 -269.771202) (xy 358.334421 -269.799158) (xy 358.369914 -269.83325) (xy 358.399479 -269.872594)
			(xy 358.42235 -269.916171) (xy 358.437934 -269.962852) (xy 358.445829 -270.011429) (xy 358.446324 -270.036036)
			(xy 361.589078 -270.036036) (xy 361.593038 -269.986982) (xy 361.604815 -269.939198) (xy 361.624106 -269.893922)
			(xy 361.650409 -269.852326) (xy 361.683044 -269.815489) (xy 361.721165 -269.784364) (xy 361.763786 -269.759757)
			(xy 361.809802 -269.742305) (xy 361.858021 -269.732461) (xy 361.907196 -269.73048) (xy 361.956051 -269.736412)
			(xy 362.003322 -269.750104) (xy 362.047784 -269.771202) (xy 362.088287 -269.799158) (xy 362.12378 -269.83325)
			(xy 362.153345 -269.872594) (xy 362.176216 -269.916171) (xy 362.1918 -269.962852) (xy 362.199695 -270.011429)
			(xy 362.20019 -270.036036) (xy 362.528878 -270.036036) (xy 362.532838 -269.986982) (xy 362.544615 -269.939198)
			(xy 362.563906 -269.893922) (xy 362.590209 -269.852326) (xy 362.622844 -269.815489) (xy 362.660965 -269.784364)
			(xy 362.703586 -269.759757) (xy 362.749602 -269.742305) (xy 362.797821 -269.732461) (xy 362.846996 -269.73048)
			(xy 362.895851 -269.736412) (xy 362.943122 -269.750104) (xy 362.987584 -269.771202) (xy 363.028087 -269.799158)
			(xy 363.06358 -269.83325) (xy 363.093145 -269.872594) (xy 363.116016 -269.916171) (xy 363.1316 -269.962852)
			(xy 363.139495 -270.011429) (xy 363.13999 -270.036036) (xy 363.468932 -270.036036) (xy 363.472892 -269.986982)
			(xy 363.484669 -269.939198) (xy 363.50396 -269.893922) (xy 363.530263 -269.852326) (xy 363.562898 -269.815489)
			(xy 363.601019 -269.784364) (xy 363.64364 -269.759757) (xy 363.689656 -269.742305) (xy 363.737875 -269.732461)
			(xy 363.78705 -269.73048) (xy 363.835905 -269.736412) (xy 363.883176 -269.750104) (xy 363.927638 -269.771202)
			(xy 363.968141 -269.799158) (xy 364.003634 -269.83325) (xy 364.033199 -269.872594) (xy 364.05607 -269.916171)
			(xy 364.071654 -269.962852) (xy 364.079549 -270.011429) (xy 364.080044 -270.036036) (xy 364.408986 -270.036036)
			(xy 364.412946 -269.986982) (xy 364.424723 -269.939198) (xy 364.444014 -269.893922) (xy 364.470317 -269.852326)
			(xy 364.502952 -269.815489) (xy 364.541073 -269.784364) (xy 364.583694 -269.759757) (xy 364.62971 -269.742305)
			(xy 364.677929 -269.732461) (xy 364.727104 -269.73048) (xy 364.775959 -269.736412) (xy 364.82323 -269.750104)
			(xy 364.867692 -269.771202) (xy 364.908195 -269.799158) (xy 364.943688 -269.83325) (xy 364.973253 -269.872594)
			(xy 364.996124 -269.916171) (xy 365.011708 -269.962852) (xy 365.019603 -270.011429) (xy 365.020098 -270.036036)
			(xy 365.34904 -270.036036) (xy 365.353 -269.986982) (xy 365.364777 -269.939198) (xy 365.384068 -269.893922)
			(xy 365.410371 -269.852326) (xy 365.443006 -269.815489) (xy 365.481127 -269.784364) (xy 365.523748 -269.759757)
			(xy 365.569764 -269.742305) (xy 365.617983 -269.732461) (xy 365.667158 -269.73048) (xy 365.716013 -269.736412)
			(xy 365.763284 -269.750104) (xy 365.807746 -269.771202) (xy 365.848249 -269.799158) (xy 365.883742 -269.83325)
			(xy 365.913307 -269.872594) (xy 365.936178 -269.916171) (xy 365.951762 -269.962852) (xy 365.959657 -270.011429)
			(xy 365.960152 -270.036036) (xy 366.289094 -270.036036) (xy 366.293054 -269.986982) (xy 366.304831 -269.939198)
			(xy 366.324122 -269.893922) (xy 366.350425 -269.852326) (xy 366.38306 -269.815489) (xy 366.421181 -269.784364)
			(xy 366.463802 -269.759757) (xy 366.509818 -269.742305) (xy 366.558037 -269.732461) (xy 366.607212 -269.73048)
			(xy 366.656067 -269.736412) (xy 366.703338 -269.750104) (xy 366.7478 -269.771202) (xy 366.788303 -269.799158)
			(xy 366.823796 -269.83325) (xy 366.853361 -269.872594) (xy 366.876232 -269.916171) (xy 366.891816 -269.962852)
			(xy 366.899711 -270.011429) (xy 366.900206 -270.036036) (xy 367.228894 -270.036036) (xy 367.232854 -269.986982)
			(xy 367.244631 -269.939198) (xy 367.263922 -269.893922) (xy 367.290225 -269.852326) (xy 367.32286 -269.815489)
			(xy 367.360981 -269.784364) (xy 367.403602 -269.759757) (xy 367.449618 -269.742305) (xy 367.497837 -269.732461)
			(xy 367.547012 -269.73048) (xy 367.595867 -269.736412) (xy 367.643138 -269.750104) (xy 367.6876 -269.771202)
			(xy 367.728103 -269.799158) (xy 367.763596 -269.83325) (xy 367.793161 -269.872594) (xy 367.816032 -269.916171)
			(xy 367.831616 -269.962852) (xy 367.839511 -270.011429) (xy 367.840006 -270.036036) (xy 368.168948 -270.036036)
			(xy 368.172908 -269.986982) (xy 368.184685 -269.939198) (xy 368.203976 -269.893922) (xy 368.230279 -269.852326)
			(xy 368.262914 -269.815489) (xy 368.301035 -269.784364) (xy 368.343656 -269.759757) (xy 368.389672 -269.742305)
			(xy 368.437891 -269.732461) (xy 368.487066 -269.73048) (xy 368.535921 -269.736412) (xy 368.583192 -269.750104)
			(xy 368.627654 -269.771202) (xy 368.668157 -269.799158) (xy 368.70365 -269.83325) (xy 368.733215 -269.872594)
			(xy 368.756086 -269.916171) (xy 368.77167 -269.962852) (xy 368.779565 -270.011429) (xy 368.78006 -270.036036)
			(xy 369.109002 -270.036036) (xy 369.112962 -269.986982) (xy 369.124739 -269.939198) (xy 369.14403 -269.893922)
			(xy 369.170333 -269.852326) (xy 369.202968 -269.815489) (xy 369.241089 -269.784364) (xy 369.28371 -269.759757)
			(xy 369.329726 -269.742305) (xy 369.377945 -269.732461) (xy 369.42712 -269.73048) (xy 369.475975 -269.736412)
			(xy 369.523246 -269.750104) (xy 369.567708 -269.771202) (xy 369.608211 -269.799158) (xy 369.643704 -269.83325)
			(xy 369.673269 -269.872594) (xy 369.69614 -269.916171) (xy 369.711724 -269.962852) (xy 369.719619 -270.011429)
			(xy 369.720114 -270.036036) (xy 370.049056 -270.036036) (xy 370.053016 -269.986982) (xy 370.064793 -269.939198)
			(xy 370.084084 -269.893922) (xy 370.110387 -269.852326) (xy 370.143022 -269.815489) (xy 370.181143 -269.784364)
			(xy 370.223764 -269.759757) (xy 370.26978 -269.742305) (xy 370.317999 -269.732461) (xy 370.367174 -269.73048)
			(xy 370.416029 -269.736412) (xy 370.4633 -269.750104) (xy 370.507762 -269.771202) (xy 370.548265 -269.799158)
			(xy 370.583758 -269.83325) (xy 370.613323 -269.872594) (xy 370.636194 -269.916171) (xy 370.651778 -269.962852)
			(xy 370.659673 -270.011429) (xy 370.660168 -270.036036) (xy 370.98911 -270.036036) (xy 370.99307 -269.986982)
			(xy 371.004847 -269.939198) (xy 371.024138 -269.893922) (xy 371.050441 -269.852326) (xy 371.083076 -269.815489)
			(xy 371.121197 -269.784364) (xy 371.163818 -269.759757) (xy 371.209834 -269.742305) (xy 371.258053 -269.732461)
			(xy 371.307228 -269.73048) (xy 371.356083 -269.736412) (xy 371.403354 -269.750104) (xy 371.447816 -269.771202)
			(xy 371.488319 -269.799158) (xy 371.523812 -269.83325) (xy 371.553377 -269.872594) (xy 371.576248 -269.916171)
			(xy 371.591832 -269.962852) (xy 371.599727 -270.011429) (xy 371.600222 -270.036036) (xy 371.92891 -270.036036)
			(xy 371.93287 -269.986982) (xy 371.944647 -269.939198) (xy 371.963938 -269.893922) (xy 371.990241 -269.852326)
			(xy 372.022876 -269.815489) (xy 372.060997 -269.784364) (xy 372.103618 -269.759757) (xy 372.149634 -269.742305)
			(xy 372.197853 -269.732461) (xy 372.247028 -269.73048) (xy 372.295883 -269.736412) (xy 372.343154 -269.750104)
			(xy 372.387616 -269.771202) (xy 372.428119 -269.799158) (xy 372.463612 -269.83325) (xy 372.493177 -269.872594)
			(xy 372.516048 -269.916171) (xy 372.531632 -269.962852) (xy 372.539527 -270.011429) (xy 372.540022 -270.036036)
			(xy 372.539527 -270.060643) (xy 372.531632 -270.10922) (xy 372.516048 -270.155901) (xy 372.493177 -270.199478)
			(xy 372.463612 -270.238822) (xy 372.428119 -270.272914) (xy 372.387616 -270.30087) (xy 372.343154 -270.321968)
			(xy 372.295883 -270.33566) (xy 372.247028 -270.341592) (xy 372.197853 -270.339611) (xy 372.149634 -270.329767)
			(xy 372.103618 -270.312315) (xy 372.060997 -270.287708) (xy 372.022876 -270.256583) (xy 371.990241 -270.219746)
			(xy 371.963938 -270.17815) (xy 371.944647 -270.132874) (xy 371.93287 -270.08509) (xy 371.92891 -270.036036)
			(xy 371.600222 -270.036036) (xy 371.599727 -270.060643) (xy 371.591832 -270.10922) (xy 371.576248 -270.155901)
			(xy 371.553377 -270.199478) (xy 371.523812 -270.238822) (xy 371.488319 -270.272914) (xy 371.447816 -270.30087)
			(xy 371.403354 -270.321968) (xy 371.356083 -270.33566) (xy 371.307228 -270.341592) (xy 371.258053 -270.339611)
			(xy 371.209834 -270.329767) (xy 371.163818 -270.312315) (xy 371.121197 -270.287708) (xy 371.083076 -270.256583)
			(xy 371.050441 -270.219746) (xy 371.024138 -270.17815) (xy 371.004847 -270.132874) (xy 370.99307 -270.08509)
			(xy 370.98911 -270.036036) (xy 370.660168 -270.036036) (xy 370.659673 -270.060643) (xy 370.651778 -270.10922)
			(xy 370.636194 -270.155901) (xy 370.613323 -270.199478) (xy 370.583758 -270.238822) (xy 370.548265 -270.272914)
			(xy 370.507762 -270.30087) (xy 370.4633 -270.321968) (xy 370.416029 -270.33566) (xy 370.367174 -270.341592)
			(xy 370.317999 -270.339611) (xy 370.26978 -270.329767) (xy 370.223764 -270.312315) (xy 370.181143 -270.287708)
			(xy 370.143022 -270.256583) (xy 370.110387 -270.219746) (xy 370.084084 -270.17815) (xy 370.064793 -270.132874)
			(xy 370.053016 -270.08509) (xy 370.049056 -270.036036) (xy 369.720114 -270.036036) (xy 369.719619 -270.060643)
			(xy 369.711724 -270.10922) (xy 369.69614 -270.155901) (xy 369.673269 -270.199478) (xy 369.643704 -270.238822)
			(xy 369.608211 -270.272914) (xy 369.567708 -270.30087) (xy 369.523246 -270.321968) (xy 369.475975 -270.33566)
			(xy 369.42712 -270.341592) (xy 369.377945 -270.339611) (xy 369.329726 -270.329767) (xy 369.28371 -270.312315)
			(xy 369.241089 -270.287708) (xy 369.202968 -270.256583) (xy 369.170333 -270.219746) (xy 369.14403 -270.17815)
			(xy 369.124739 -270.132874) (xy 369.112962 -270.08509) (xy 369.109002 -270.036036) (xy 368.78006 -270.036036)
			(xy 368.779565 -270.060643) (xy 368.77167 -270.10922) (xy 368.756086 -270.155901) (xy 368.733215 -270.199478)
			(xy 368.70365 -270.238822) (xy 368.668157 -270.272914) (xy 368.627654 -270.30087) (xy 368.583192 -270.321968)
			(xy 368.535921 -270.33566) (xy 368.487066 -270.341592) (xy 368.437891 -270.339611) (xy 368.389672 -270.329767)
			(xy 368.343656 -270.312315) (xy 368.301035 -270.287708) (xy 368.262914 -270.256583) (xy 368.230279 -270.219746)
			(xy 368.203976 -270.17815) (xy 368.184685 -270.132874) (xy 368.172908 -270.08509) (xy 368.168948 -270.036036)
			(xy 367.840006 -270.036036) (xy 367.839511 -270.060643) (xy 367.831616 -270.10922) (xy 367.816032 -270.155901)
			(xy 367.793161 -270.199478) (xy 367.763596 -270.238822) (xy 367.728103 -270.272914) (xy 367.6876 -270.30087)
			(xy 367.643138 -270.321968) (xy 367.595867 -270.33566) (xy 367.547012 -270.341592) (xy 367.497837 -270.339611)
			(xy 367.449618 -270.329767) (xy 367.403602 -270.312315) (xy 367.360981 -270.287708) (xy 367.32286 -270.256583)
			(xy 367.290225 -270.219746) (xy 367.263922 -270.17815) (xy 367.244631 -270.132874) (xy 367.232854 -270.08509)
			(xy 367.228894 -270.036036) (xy 366.900206 -270.036036) (xy 366.899711 -270.060643) (xy 366.891816 -270.10922)
			(xy 366.876232 -270.155901) (xy 366.853361 -270.199478) (xy 366.823796 -270.238822) (xy 366.788303 -270.272914)
			(xy 366.7478 -270.30087) (xy 366.703338 -270.321968) (xy 366.656067 -270.33566) (xy 366.607212 -270.341592)
			(xy 366.558037 -270.339611) (xy 366.509818 -270.329767) (xy 366.463802 -270.312315) (xy 366.421181 -270.287708)
			(xy 366.38306 -270.256583) (xy 366.350425 -270.219746) (xy 366.324122 -270.17815) (xy 366.304831 -270.132874)
			(xy 366.293054 -270.08509) (xy 366.289094 -270.036036) (xy 365.960152 -270.036036) (xy 365.959657 -270.060643)
			(xy 365.951762 -270.10922) (xy 365.936178 -270.155901) (xy 365.913307 -270.199478) (xy 365.883742 -270.238822)
			(xy 365.848249 -270.272914) (xy 365.807746 -270.30087) (xy 365.763284 -270.321968) (xy 365.716013 -270.33566)
			(xy 365.667158 -270.341592) (xy 365.617983 -270.339611) (xy 365.569764 -270.329767) (xy 365.523748 -270.312315)
			(xy 365.481127 -270.287708) (xy 365.443006 -270.256583) (xy 365.410371 -270.219746) (xy 365.384068 -270.17815)
			(xy 365.364777 -270.132874) (xy 365.353 -270.08509) (xy 365.34904 -270.036036) (xy 365.020098 -270.036036)
			(xy 365.019603 -270.060643) (xy 365.011708 -270.10922) (xy 364.996124 -270.155901) (xy 364.973253 -270.199478)
			(xy 364.943688 -270.238822) (xy 364.908195 -270.272914) (xy 364.867692 -270.30087) (xy 364.82323 -270.321968)
			(xy 364.775959 -270.33566) (xy 364.727104 -270.341592) (xy 364.677929 -270.339611) (xy 364.62971 -270.329767)
			(xy 364.583694 -270.312315) (xy 364.541073 -270.287708) (xy 364.502952 -270.256583) (xy 364.470317 -270.219746)
			(xy 364.444014 -270.17815) (xy 364.424723 -270.132874) (xy 364.412946 -270.08509) (xy 364.408986 -270.036036)
			(xy 364.080044 -270.036036) (xy 364.079549 -270.060643) (xy 364.071654 -270.10922) (xy 364.05607 -270.155901)
			(xy 364.033199 -270.199478) (xy 364.003634 -270.238822) (xy 363.968141 -270.272914) (xy 363.927638 -270.30087)
			(xy 363.883176 -270.321968) (xy 363.835905 -270.33566) (xy 363.78705 -270.341592) (xy 363.737875 -270.339611)
			(xy 363.689656 -270.329767) (xy 363.64364 -270.312315) (xy 363.601019 -270.287708) (xy 363.562898 -270.256583)
			(xy 363.530263 -270.219746) (xy 363.50396 -270.17815) (xy 363.484669 -270.132874) (xy 363.472892 -270.08509)
			(xy 363.468932 -270.036036) (xy 363.13999 -270.036036) (xy 363.139495 -270.060643) (xy 363.1316 -270.10922)
			(xy 363.116016 -270.155901) (xy 363.093145 -270.199478) (xy 363.06358 -270.238822) (xy 363.028087 -270.272914)
			(xy 362.987584 -270.30087) (xy 362.943122 -270.321968) (xy 362.895851 -270.33566) (xy 362.846996 -270.341592)
			(xy 362.797821 -270.339611) (xy 362.749602 -270.329767) (xy 362.703586 -270.312315) (xy 362.660965 -270.287708)
			(xy 362.622844 -270.256583) (xy 362.590209 -270.219746) (xy 362.563906 -270.17815) (xy 362.544615 -270.132874)
			(xy 362.532838 -270.08509) (xy 362.528878 -270.036036) (xy 362.20019 -270.036036) (xy 362.199695 -270.060643)
			(xy 362.1918 -270.10922) (xy 362.176216 -270.155901) (xy 362.153345 -270.199478) (xy 362.12378 -270.238822)
			(xy 362.088287 -270.272914) (xy 362.047784 -270.30087) (xy 362.003322 -270.321968) (xy 361.956051 -270.33566)
			(xy 361.907196 -270.341592) (xy 361.858021 -270.339611) (xy 361.809802 -270.329767) (xy 361.763786 -270.312315)
			(xy 361.721165 -270.287708) (xy 361.683044 -270.256583) (xy 361.650409 -270.219746) (xy 361.624106 -270.17815)
			(xy 361.604815 -270.132874) (xy 361.593038 -270.08509) (xy 361.589078 -270.036036) (xy 358.446324 -270.036036)
			(xy 358.445829 -270.060643) (xy 358.437934 -270.10922) (xy 358.42235 -270.155901) (xy 358.399479 -270.199478)
			(xy 358.369914 -270.238822) (xy 358.334421 -270.272914) (xy 358.293918 -270.30087) (xy 358.249456 -270.321968)
			(xy 358.202185 -270.33566) (xy 358.15333 -270.341592) (xy 358.104155 -270.339611) (xy 358.055936 -270.329767)
			(xy 358.00992 -270.312315) (xy 357.967299 -270.287708) (xy 357.929178 -270.256583) (xy 357.896543 -270.219746)
			(xy 357.87024 -270.17815) (xy 357.850949 -270.132874) (xy 357.839172 -270.08509) (xy 357.835212 -270.036036)
			(xy 357.506524 -270.036036) (xy 357.506029 -270.060643) (xy 357.498134 -270.10922) (xy 357.48255 -270.155901)
			(xy 357.459679 -270.199478) (xy 357.430114 -270.238822) (xy 357.394621 -270.272914) (xy 357.354118 -270.30087)
			(xy 357.309656 -270.321968) (xy 357.262385 -270.33566) (xy 357.21353 -270.341592) (xy 357.164355 -270.339611)
			(xy 357.116136 -270.329767) (xy 357.07012 -270.312315) (xy 357.027499 -270.287708) (xy 356.989378 -270.256583)
			(xy 356.956743 -270.219746) (xy 356.93044 -270.17815) (xy 356.911149 -270.132874) (xy 356.899372 -270.08509)
			(xy 356.895412 -270.036036) (xy 356.56647 -270.036036) (xy 356.565975 -270.060643) (xy 356.55808 -270.10922)
			(xy 356.542496 -270.155901) (xy 356.519625 -270.199478) (xy 356.49006 -270.238822) (xy 356.454567 -270.272914)
			(xy 356.414064 -270.30087) (xy 356.369602 -270.321968) (xy 356.322331 -270.33566) (xy 356.273476 -270.341592)
			(xy 356.224301 -270.339611) (xy 356.176082 -270.329767) (xy 356.130066 -270.312315) (xy 356.087445 -270.287708)
			(xy 356.049324 -270.256583) (xy 356.016689 -270.219746) (xy 355.990386 -270.17815) (xy 355.971095 -270.132874)
			(xy 355.959318 -270.08509) (xy 355.955358 -270.036036) (xy 355.626416 -270.036036) (xy 355.625921 -270.060643)
			(xy 355.618026 -270.10922) (xy 355.602442 -270.155901) (xy 355.579571 -270.199478) (xy 355.550006 -270.238822)
			(xy 355.514513 -270.272914) (xy 355.47401 -270.30087) (xy 355.429548 -270.321968) (xy 355.382277 -270.33566)
			(xy 355.333422 -270.341592) (xy 355.284247 -270.339611) (xy 355.236028 -270.329767) (xy 355.190012 -270.312315)
			(xy 355.147391 -270.287708) (xy 355.10927 -270.256583) (xy 355.076635 -270.219746) (xy 355.050332 -270.17815)
			(xy 355.031041 -270.132874) (xy 355.019264 -270.08509) (xy 355.015304 -270.036036) (xy 354.686362 -270.036036)
			(xy 354.685867 -270.060643) (xy 354.677972 -270.10922) (xy 354.662388 -270.155901) (xy 354.639517 -270.199478)
			(xy 354.609952 -270.238822) (xy 354.574459 -270.272914) (xy 354.533956 -270.30087) (xy 354.489494 -270.321968)
			(xy 354.442223 -270.33566) (xy 354.393368 -270.341592) (xy 354.344193 -270.339611) (xy 354.295974 -270.329767)
			(xy 354.249958 -270.312315) (xy 354.207337 -270.287708) (xy 354.169216 -270.256583) (xy 354.136581 -270.219746)
			(xy 354.110278 -270.17815) (xy 354.090987 -270.132874) (xy 354.07921 -270.08509) (xy 354.07525 -270.036036)
			(xy 353.746308 -270.036036) (xy 353.745813 -270.060643) (xy 353.737918 -270.10922) (xy 353.722334 -270.155901)
			(xy 353.699463 -270.199478) (xy 353.669898 -270.238822) (xy 353.634405 -270.272914) (xy 353.593902 -270.30087)
			(xy 353.54944 -270.321968) (xy 353.502169 -270.33566) (xy 353.453314 -270.341592) (xy 353.404139 -270.339611)
			(xy 353.35592 -270.329767) (xy 353.309904 -270.312315) (xy 353.267283 -270.287708) (xy 353.229162 -270.256583)
			(xy 353.196527 -270.219746) (xy 353.170224 -270.17815) (xy 353.150933 -270.132874) (xy 353.139156 -270.08509)
			(xy 353.135196 -270.036036) (xy 352.806508 -270.036036) (xy 352.806013 -270.060643) (xy 352.798118 -270.10922)
			(xy 352.782534 -270.155901) (xy 352.759663 -270.199478) (xy 352.730098 -270.238822) (xy 352.694605 -270.272914)
			(xy 352.654102 -270.30087) (xy 352.60964 -270.321968) (xy 352.562369 -270.33566) (xy 352.513514 -270.341592)
			(xy 352.464339 -270.339611) (xy 352.41612 -270.329767) (xy 352.370104 -270.312315) (xy 352.327483 -270.287708)
			(xy 352.289362 -270.256583) (xy 352.256727 -270.219746) (xy 352.230424 -270.17815) (xy 352.211133 -270.132874)
			(xy 352.199356 -270.08509) (xy 352.195396 -270.036036) (xy 351.866454 -270.036036) (xy 351.865959 -270.060643)
			(xy 351.858064 -270.10922) (xy 351.84248 -270.155901) (xy 351.819609 -270.199478) (xy 351.790044 -270.238822)
			(xy 351.754551 -270.272914) (xy 351.714048 -270.30087) (xy 351.669586 -270.321968) (xy 351.622315 -270.33566)
			(xy 351.57346 -270.341592) (xy 351.524285 -270.339611) (xy 351.476066 -270.329767) (xy 351.43005 -270.312315)
			(xy 351.387429 -270.287708) (xy 351.349308 -270.256583) (xy 351.316673 -270.219746) (xy 351.29037 -270.17815)
			(xy 351.271079 -270.132874) (xy 351.259302 -270.08509) (xy 351.255342 -270.036036) (xy 350.9264 -270.036036)
			(xy 350.925905 -270.060643) (xy 350.91801 -270.10922) (xy 350.902426 -270.155901) (xy 350.879555 -270.199478)
			(xy 350.84999 -270.238822) (xy 350.814497 -270.272914) (xy 350.773994 -270.30087) (xy 350.729532 -270.321968)
			(xy 350.682261 -270.33566) (xy 350.633406 -270.341592) (xy 350.584231 -270.339611) (xy 350.536012 -270.329767)
			(xy 350.489996 -270.312315) (xy 350.447375 -270.287708) (xy 350.409254 -270.256583) (xy 350.376619 -270.219746)
			(xy 350.350316 -270.17815) (xy 350.331025 -270.132874) (xy 350.319248 -270.08509) (xy 350.315288 -270.036036)
			(xy 349.986346 -270.036036) (xy 349.985851 -270.060643) (xy 349.977956 -270.10922) (xy 349.962372 -270.155901)
			(xy 349.939501 -270.199478) (xy 349.909936 -270.238822) (xy 349.874443 -270.272914) (xy 349.83394 -270.30087)
			(xy 349.789478 -270.321968) (xy 349.742207 -270.33566) (xy 349.693352 -270.341592) (xy 349.644177 -270.339611)
			(xy 349.595958 -270.329767) (xy 349.549942 -270.312315) (xy 349.507321 -270.287708) (xy 349.4692 -270.256583)
			(xy 349.436565 -270.219746) (xy 349.410262 -270.17815) (xy 349.390971 -270.132874) (xy 349.379194 -270.08509)
			(xy 349.375234 -270.036036) (xy 349.046546 -270.036036) (xy 349.046051 -270.060643) (xy 349.038156 -270.10922)
			(xy 349.022572 -270.155901) (xy 348.999701 -270.199478) (xy 348.970136 -270.238822) (xy 348.934643 -270.272914)
			(xy 348.89414 -270.30087) (xy 348.849678 -270.321968) (xy 348.802407 -270.33566) (xy 348.753552 -270.341592)
			(xy 348.704377 -270.339611) (xy 348.656158 -270.329767) (xy 348.610142 -270.312315) (xy 348.567521 -270.287708)
			(xy 348.5294 -270.256583) (xy 348.496765 -270.219746) (xy 348.470462 -270.17815) (xy 348.451171 -270.132874)
			(xy 348.439394 -270.08509) (xy 348.435434 -270.036036) (xy 348.106492 -270.036036) (xy 348.105997 -270.060643)
			(xy 348.098102 -270.10922) (xy 348.082518 -270.155901) (xy 348.059647 -270.199478) (xy 348.030082 -270.238822)
			(xy 347.994589 -270.272914) (xy 347.954086 -270.30087) (xy 347.909624 -270.321968) (xy 347.862353 -270.33566)
			(xy 347.813498 -270.341592) (xy 347.764323 -270.339611) (xy 347.716104 -270.329767) (xy 347.670088 -270.312315)
			(xy 347.627467 -270.287708) (xy 347.589346 -270.256583) (xy 347.556711 -270.219746) (xy 347.530408 -270.17815)
			(xy 347.511117 -270.132874) (xy 347.49934 -270.08509) (xy 347.49538 -270.036036) (xy 347.166438 -270.036036)
			(xy 347.165943 -270.060643) (xy 347.158048 -270.10922) (xy 347.142464 -270.155901) (xy 347.119593 -270.199478)
			(xy 347.090028 -270.238822) (xy 347.054535 -270.272914) (xy 347.014032 -270.30087) (xy 346.96957 -270.321968)
			(xy 346.922299 -270.33566) (xy 346.873444 -270.341592) (xy 346.824269 -270.339611) (xy 346.77605 -270.329767)
			(xy 346.730034 -270.312315) (xy 346.687413 -270.287708) (xy 346.649292 -270.256583) (xy 346.616657 -270.219746)
			(xy 346.590354 -270.17815) (xy 346.571063 -270.132874) (xy 346.559286 -270.08509) (xy 346.555326 -270.036036)
			(xy 346.226384 -270.036036) (xy 346.225889 -270.060643) (xy 346.217994 -270.10922) (xy 346.20241 -270.155901)
			(xy 346.179539 -270.199478) (xy 346.149974 -270.238822) (xy 346.114481 -270.272914) (xy 346.073978 -270.30087)
			(xy 346.029516 -270.321968) (xy 345.982245 -270.33566) (xy 345.93339 -270.341592) (xy 345.884215 -270.339611)
			(xy 345.835996 -270.329767) (xy 345.78998 -270.312315) (xy 345.747359 -270.287708) (xy 345.709238 -270.256583)
			(xy 345.676603 -270.219746) (xy 345.6503 -270.17815) (xy 345.631009 -270.132874) (xy 345.619232 -270.08509)
			(xy 345.615272 -270.036036) (xy 345.286792 -270.036036) (xy 345.282629 -270.086304) (xy 345.270245 -270.135236)
			(xy 345.24998 -270.181466) (xy 345.222387 -270.223731) (xy 345.188216 -270.260882) (xy 345.1484 -270.291906)
			(xy 345.104023 -270.315957) (xy 345.056294 -270.332381) (xy 345.006513 -270.340729) (xy 344.981276 -270.341344)
			(xy 344.971209 -270.341773) (xy 344.952615 -270.349498) (xy 344.945208 -270.35633) (xy 344.895424 -270.406114)
			(xy 344.888707 -270.41335) (xy 344.881108 -270.431556) (xy 344.880692 -270.44142) (xy 344.880692 -270.846042)
			(xy 345.145372 -270.846042) (xy 345.149332 -270.796988) (xy 345.161109 -270.749204) (xy 345.1804 -270.703928)
			(xy 345.206703 -270.662332) (xy 345.239338 -270.625495) (xy 345.277459 -270.59437) (xy 345.32008 -270.569763)
			(xy 345.366096 -270.552311) (xy 345.414315 -270.542467) (xy 345.46349 -270.540486) (xy 345.512345 -270.546418)
			(xy 345.559616 -270.56011) (xy 345.604078 -270.581208) (xy 345.644581 -270.609164) (xy 345.680074 -270.643256)
			(xy 345.709639 -270.6826) (xy 345.73251 -270.726177) (xy 345.748094 -270.772858) (xy 345.755989 -270.821435)
			(xy 345.756484 -270.846042) (xy 346.085426 -270.846042) (xy 346.089386 -270.796988) (xy 346.101163 -270.749204)
			(xy 346.120454 -270.703928) (xy 346.146757 -270.662332) (xy 346.179392 -270.625495) (xy 346.217513 -270.59437)
			(xy 346.260134 -270.569763) (xy 346.30615 -270.552311) (xy 346.354369 -270.542467) (xy 346.403544 -270.540486)
			(xy 346.452399 -270.546418) (xy 346.49967 -270.56011) (xy 346.544132 -270.581208) (xy 346.584635 -270.609164)
			(xy 346.620128 -270.643256) (xy 346.649693 -270.6826) (xy 346.672564 -270.726177) (xy 346.688148 -270.772858)
			(xy 346.696043 -270.821435) (xy 346.696538 -270.846042) (xy 347.025226 -270.846042) (xy 347.029186 -270.796988)
			(xy 347.040963 -270.749204) (xy 347.060254 -270.703928) (xy 347.086557 -270.662332) (xy 347.119192 -270.625495)
			(xy 347.157313 -270.59437) (xy 347.199934 -270.569763) (xy 347.24595 -270.552311) (xy 347.294169 -270.542467)
			(xy 347.343344 -270.540486) (xy 347.392199 -270.546418) (xy 347.43947 -270.56011) (xy 347.483932 -270.581208)
			(xy 347.524435 -270.609164) (xy 347.559928 -270.643256) (xy 347.589493 -270.6826) (xy 347.612364 -270.726177)
			(xy 347.627948 -270.772858) (xy 347.635843 -270.821435) (xy 347.636338 -270.846042) (xy 347.96528 -270.846042)
			(xy 347.96924 -270.796988) (xy 347.981017 -270.749204) (xy 348.000308 -270.703928) (xy 348.026611 -270.662332)
			(xy 348.059246 -270.625495) (xy 348.097367 -270.59437) (xy 348.139988 -270.569763) (xy 348.186004 -270.552311)
			(xy 348.234223 -270.542467) (xy 348.283398 -270.540486) (xy 348.332253 -270.546418) (xy 348.379524 -270.56011)
			(xy 348.423986 -270.581208) (xy 348.464489 -270.609164) (xy 348.499982 -270.643256) (xy 348.529547 -270.6826)
			(xy 348.552418 -270.726177) (xy 348.568002 -270.772858) (xy 348.575897 -270.821435) (xy 348.576392 -270.846042)
			(xy 348.905334 -270.846042) (xy 348.909294 -270.796988) (xy 348.921071 -270.749204) (xy 348.940362 -270.703928)
			(xy 348.966665 -270.662332) (xy 348.9993 -270.625495) (xy 349.037421 -270.59437) (xy 349.080042 -270.569763)
			(xy 349.126058 -270.552311) (xy 349.174277 -270.542467) (xy 349.223452 -270.540486) (xy 349.272307 -270.546418)
			(xy 349.319578 -270.56011) (xy 349.36404 -270.581208) (xy 349.404543 -270.609164) (xy 349.440036 -270.643256)
			(xy 349.469601 -270.6826) (xy 349.492472 -270.726177) (xy 349.508056 -270.772858) (xy 349.515951 -270.821435)
			(xy 349.516446 -270.846042) (xy 349.845388 -270.846042) (xy 349.849348 -270.796988) (xy 349.861125 -270.749204)
			(xy 349.880416 -270.703928) (xy 349.906719 -270.662332) (xy 349.939354 -270.625495) (xy 349.977475 -270.59437)
			(xy 350.020096 -270.569763) (xy 350.066112 -270.552311) (xy 350.114331 -270.542467) (xy 350.163506 -270.540486)
			(xy 350.212361 -270.546418) (xy 350.259632 -270.56011) (xy 350.304094 -270.581208) (xy 350.344597 -270.609164)
			(xy 350.38009 -270.643256) (xy 350.409655 -270.6826) (xy 350.432526 -270.726177) (xy 350.44811 -270.772858)
			(xy 350.456005 -270.821435) (xy 350.4565 -270.846042) (xy 350.785442 -270.846042) (xy 350.789402 -270.796988)
			(xy 350.801179 -270.749204) (xy 350.82047 -270.703928) (xy 350.846773 -270.662332) (xy 350.879408 -270.625495)
			(xy 350.917529 -270.59437) (xy 350.96015 -270.569763) (xy 351.006166 -270.552311) (xy 351.054385 -270.542467)
			(xy 351.10356 -270.540486) (xy 351.152415 -270.546418) (xy 351.199686 -270.56011) (xy 351.244148 -270.581208)
			(xy 351.284651 -270.609164) (xy 351.320144 -270.643256) (xy 351.349709 -270.6826) (xy 351.37258 -270.726177)
			(xy 351.388164 -270.772858) (xy 351.396059 -270.821435) (xy 351.396554 -270.846042) (xy 351.725242 -270.846042)
			(xy 351.729202 -270.796988) (xy 351.740979 -270.749204) (xy 351.76027 -270.703928) (xy 351.786573 -270.662332)
			(xy 351.819208 -270.625495) (xy 351.857329 -270.59437) (xy 351.89995 -270.569763) (xy 351.945966 -270.552311)
			(xy 351.994185 -270.542467) (xy 352.04336 -270.540486) (xy 352.092215 -270.546418) (xy 352.139486 -270.56011)
			(xy 352.183948 -270.581208) (xy 352.224451 -270.609164) (xy 352.259944 -270.643256) (xy 352.289509 -270.6826)
			(xy 352.31238 -270.726177) (xy 352.327964 -270.772858) (xy 352.335859 -270.821435) (xy 352.336354 -270.846042)
			(xy 352.665296 -270.846042) (xy 352.669256 -270.796988) (xy 352.681033 -270.749204) (xy 352.700324 -270.703928)
			(xy 352.726627 -270.662332) (xy 352.759262 -270.625495) (xy 352.797383 -270.59437) (xy 352.840004 -270.569763)
			(xy 352.88602 -270.552311) (xy 352.934239 -270.542467) (xy 352.983414 -270.540486) (xy 353.032269 -270.546418)
			(xy 353.07954 -270.56011) (xy 353.124002 -270.581208) (xy 353.164505 -270.609164) (xy 353.199998 -270.643256)
			(xy 353.229563 -270.6826) (xy 353.252434 -270.726177) (xy 353.268018 -270.772858) (xy 353.275913 -270.821435)
			(xy 353.276408 -270.846042) (xy 353.60535 -270.846042) (xy 353.60931 -270.796988) (xy 353.621087 -270.749204)
			(xy 353.640378 -270.703928) (xy 353.666681 -270.662332) (xy 353.699316 -270.625495) (xy 353.737437 -270.59437)
			(xy 353.780058 -270.569763) (xy 353.826074 -270.552311) (xy 353.874293 -270.542467) (xy 353.923468 -270.540486)
			(xy 353.972323 -270.546418) (xy 354.019594 -270.56011) (xy 354.064056 -270.581208) (xy 354.104559 -270.609164)
			(xy 354.140052 -270.643256) (xy 354.169617 -270.6826) (xy 354.192488 -270.726177) (xy 354.208072 -270.772858)
			(xy 354.215967 -270.821435) (xy 354.216462 -270.846042) (xy 354.545404 -270.846042) (xy 354.549364 -270.796988)
			(xy 354.561141 -270.749204) (xy 354.580432 -270.703928) (xy 354.606735 -270.662332) (xy 354.63937 -270.625495)
			(xy 354.677491 -270.59437) (xy 354.720112 -270.569763) (xy 354.766128 -270.552311) (xy 354.814347 -270.542467)
			(xy 354.863522 -270.540486) (xy 354.912377 -270.546418) (xy 354.959648 -270.56011) (xy 355.00411 -270.581208)
			(xy 355.044613 -270.609164) (xy 355.080106 -270.643256) (xy 355.109671 -270.6826) (xy 355.132542 -270.726177)
			(xy 355.148126 -270.772858) (xy 355.156021 -270.821435) (xy 355.156516 -270.846042) (xy 355.485204 -270.846042)
			(xy 355.489164 -270.796988) (xy 355.500941 -270.749204) (xy 355.520232 -270.703928) (xy 355.546535 -270.662332)
			(xy 355.57917 -270.625495) (xy 355.617291 -270.59437) (xy 355.659912 -270.569763) (xy 355.705928 -270.552311)
			(xy 355.754147 -270.542467) (xy 355.803322 -270.540486) (xy 355.852177 -270.546418) (xy 355.899448 -270.56011)
			(xy 355.94391 -270.581208) (xy 355.984413 -270.609164) (xy 356.019906 -270.643256) (xy 356.049471 -270.6826)
			(xy 356.072342 -270.726177) (xy 356.087926 -270.772858) (xy 356.095821 -270.821435) (xy 356.096316 -270.846042)
			(xy 356.425258 -270.846042) (xy 356.429218 -270.796988) (xy 356.440995 -270.749204) (xy 356.460286 -270.703928)
			(xy 356.486589 -270.662332) (xy 356.519224 -270.625495) (xy 356.557345 -270.59437) (xy 356.599966 -270.569763)
			(xy 356.645982 -270.552311) (xy 356.694201 -270.542467) (xy 356.743376 -270.540486) (xy 356.792231 -270.546418)
			(xy 356.839502 -270.56011) (xy 356.883964 -270.581208) (xy 356.924467 -270.609164) (xy 356.95996 -270.643256)
			(xy 356.989525 -270.6826) (xy 357.012396 -270.726177) (xy 357.02798 -270.772858) (xy 357.035875 -270.821435)
			(xy 357.03637 -270.846042) (xy 357.365312 -270.846042) (xy 357.369272 -270.796988) (xy 357.381049 -270.749204)
			(xy 357.40034 -270.703928) (xy 357.426643 -270.662332) (xy 357.459278 -270.625495) (xy 357.497399 -270.59437)
			(xy 357.54002 -270.569763) (xy 357.586036 -270.552311) (xy 357.634255 -270.542467) (xy 357.68343 -270.540486)
			(xy 357.732285 -270.546418) (xy 357.779556 -270.56011) (xy 357.824018 -270.581208) (xy 357.864521 -270.609164)
			(xy 357.900014 -270.643256) (xy 357.929579 -270.6826) (xy 357.95245 -270.726177) (xy 357.968034 -270.772858)
			(xy 357.975929 -270.821435) (xy 357.976424 -270.846042) (xy 358.305366 -270.846042) (xy 358.309326 -270.796988)
			(xy 358.321103 -270.749204) (xy 358.340394 -270.703928) (xy 358.366697 -270.662332) (xy 358.399332 -270.625495)
			(xy 358.437453 -270.59437) (xy 358.480074 -270.569763) (xy 358.52609 -270.552311) (xy 358.574309 -270.542467)
			(xy 358.623484 -270.540486) (xy 358.672339 -270.546418) (xy 358.71961 -270.56011) (xy 358.764072 -270.581208)
			(xy 358.804575 -270.609164) (xy 358.840068 -270.643256) (xy 358.869633 -270.6826) (xy 358.892504 -270.726177)
			(xy 358.908088 -270.772858) (xy 358.915983 -270.821435) (xy 358.916478 -270.846042) (xy 361.118924 -270.846042)
			(xy 361.122884 -270.796988) (xy 361.134661 -270.749204) (xy 361.153952 -270.703928) (xy 361.180255 -270.662332)
			(xy 361.21289 -270.625495) (xy 361.251011 -270.59437) (xy 361.293632 -270.569763) (xy 361.339648 -270.552311)
			(xy 361.387867 -270.542467) (xy 361.437042 -270.540486) (xy 361.485897 -270.546418) (xy 361.533168 -270.56011)
			(xy 361.57763 -270.581208) (xy 361.618133 -270.609164) (xy 361.653626 -270.643256) (xy 361.683191 -270.6826)
			(xy 361.706062 -270.726177) (xy 361.721646 -270.772858) (xy 361.729541 -270.821435) (xy 361.730036 -270.846042)
			(xy 362.058978 -270.846042) (xy 362.062938 -270.796988) (xy 362.074715 -270.749204) (xy 362.094006 -270.703928)
			(xy 362.120309 -270.662332) (xy 362.152944 -270.625495) (xy 362.191065 -270.59437) (xy 362.233686 -270.569763)
			(xy 362.279702 -270.552311) (xy 362.327921 -270.542467) (xy 362.377096 -270.540486) (xy 362.425951 -270.546418)
			(xy 362.473222 -270.56011) (xy 362.517684 -270.581208) (xy 362.558187 -270.609164) (xy 362.59368 -270.643256)
			(xy 362.623245 -270.6826) (xy 362.646116 -270.726177) (xy 362.6617 -270.772858) (xy 362.669595 -270.821435)
			(xy 362.67009 -270.846042) (xy 362.999032 -270.846042) (xy 363.002992 -270.796988) (xy 363.014769 -270.749204)
			(xy 363.03406 -270.703928) (xy 363.060363 -270.662332) (xy 363.092998 -270.625495) (xy 363.131119 -270.59437)
			(xy 363.17374 -270.569763) (xy 363.219756 -270.552311) (xy 363.267975 -270.542467) (xy 363.31715 -270.540486)
			(xy 363.366005 -270.546418) (xy 363.413276 -270.56011) (xy 363.457738 -270.581208) (xy 363.498241 -270.609164)
			(xy 363.533734 -270.643256) (xy 363.563299 -270.6826) (xy 363.58617 -270.726177) (xy 363.601754 -270.772858)
			(xy 363.609649 -270.821435) (xy 363.610144 -270.846042) (xy 363.939086 -270.846042) (xy 363.943046 -270.796988)
			(xy 363.954823 -270.749204) (xy 363.974114 -270.703928) (xy 364.000417 -270.662332) (xy 364.033052 -270.625495)
			(xy 364.071173 -270.59437) (xy 364.113794 -270.569763) (xy 364.15981 -270.552311) (xy 364.208029 -270.542467)
			(xy 364.257204 -270.540486) (xy 364.306059 -270.546418) (xy 364.35333 -270.56011) (xy 364.397792 -270.581208)
			(xy 364.438295 -270.609164) (xy 364.473788 -270.643256) (xy 364.503353 -270.6826) (xy 364.526224 -270.726177)
			(xy 364.541808 -270.772858) (xy 364.549703 -270.821435) (xy 364.550198 -270.846042) (xy 364.878886 -270.846042)
			(xy 364.882846 -270.796988) (xy 364.894623 -270.749204) (xy 364.913914 -270.703928) (xy 364.940217 -270.662332)
			(xy 364.972852 -270.625495) (xy 365.010973 -270.59437) (xy 365.053594 -270.569763) (xy 365.09961 -270.552311)
			(xy 365.147829 -270.542467) (xy 365.197004 -270.540486) (xy 365.245859 -270.546418) (xy 365.29313 -270.56011)
			(xy 365.337592 -270.581208) (xy 365.378095 -270.609164) (xy 365.413588 -270.643256) (xy 365.443153 -270.6826)
			(xy 365.466024 -270.726177) (xy 365.481608 -270.772858) (xy 365.489503 -270.821435) (xy 365.489998 -270.846042)
			(xy 365.81894 -270.846042) (xy 365.8229 -270.796988) (xy 365.834677 -270.749204) (xy 365.853968 -270.703928)
			(xy 365.880271 -270.662332) (xy 365.912906 -270.625495) (xy 365.951027 -270.59437) (xy 365.993648 -270.569763)
			(xy 366.039664 -270.552311) (xy 366.087883 -270.542467) (xy 366.137058 -270.540486) (xy 366.185913 -270.546418)
			(xy 366.233184 -270.56011) (xy 366.277646 -270.581208) (xy 366.318149 -270.609164) (xy 366.353642 -270.643256)
			(xy 366.383207 -270.6826) (xy 366.406078 -270.726177) (xy 366.421662 -270.772858) (xy 366.429557 -270.821435)
			(xy 366.430052 -270.846042) (xy 366.758994 -270.846042) (xy 366.762954 -270.796988) (xy 366.774731 -270.749204)
			(xy 366.794022 -270.703928) (xy 366.820325 -270.662332) (xy 366.85296 -270.625495) (xy 366.891081 -270.59437)
			(xy 366.933702 -270.569763) (xy 366.979718 -270.552311) (xy 367.027937 -270.542467) (xy 367.077112 -270.540486)
			(xy 367.125967 -270.546418) (xy 367.173238 -270.56011) (xy 367.2177 -270.581208) (xy 367.258203 -270.609164)
			(xy 367.293696 -270.643256) (xy 367.323261 -270.6826) (xy 367.346132 -270.726177) (xy 367.361716 -270.772858)
			(xy 367.369611 -270.821435) (xy 367.370106 -270.846042) (xy 367.699048 -270.846042) (xy 367.703008 -270.796988)
			(xy 367.714785 -270.749204) (xy 367.734076 -270.703928) (xy 367.760379 -270.662332) (xy 367.793014 -270.625495)
			(xy 367.831135 -270.59437) (xy 367.873756 -270.569763) (xy 367.919772 -270.552311) (xy 367.967991 -270.542467)
			(xy 368.017166 -270.540486) (xy 368.066021 -270.546418) (xy 368.113292 -270.56011) (xy 368.157754 -270.581208)
			(xy 368.198257 -270.609164) (xy 368.23375 -270.643256) (xy 368.263315 -270.6826) (xy 368.286186 -270.726177)
			(xy 368.30177 -270.772858) (xy 368.309665 -270.821435) (xy 368.31016 -270.846042) (xy 368.639102 -270.846042)
			(xy 368.643062 -270.796988) (xy 368.654839 -270.749204) (xy 368.67413 -270.703928) (xy 368.700433 -270.662332)
			(xy 368.733068 -270.625495) (xy 368.771189 -270.59437) (xy 368.81381 -270.569763) (xy 368.859826 -270.552311)
			(xy 368.908045 -270.542467) (xy 368.95722 -270.540486) (xy 369.006075 -270.546418) (xy 369.053346 -270.56011)
			(xy 369.097808 -270.581208) (xy 369.138311 -270.609164) (xy 369.173804 -270.643256) (xy 369.203369 -270.6826)
			(xy 369.22624 -270.726177) (xy 369.241824 -270.772858) (xy 369.249719 -270.821435) (xy 369.250214 -270.846042)
			(xy 369.578902 -270.846042) (xy 369.582862 -270.796988) (xy 369.594639 -270.749204) (xy 369.61393 -270.703928)
			(xy 369.640233 -270.662332) (xy 369.672868 -270.625495) (xy 369.710989 -270.59437) (xy 369.75361 -270.569763)
			(xy 369.799626 -270.552311) (xy 369.847845 -270.542467) (xy 369.89702 -270.540486) (xy 369.945875 -270.546418)
			(xy 369.993146 -270.56011) (xy 370.037608 -270.581208) (xy 370.078111 -270.609164) (xy 370.113604 -270.643256)
			(xy 370.143169 -270.6826) (xy 370.16604 -270.726177) (xy 370.181624 -270.772858) (xy 370.189519 -270.821435)
			(xy 370.190014 -270.846042) (xy 370.518956 -270.846042) (xy 370.522916 -270.796988) (xy 370.534693 -270.749204)
			(xy 370.553984 -270.703928) (xy 370.580287 -270.662332) (xy 370.612922 -270.625495) (xy 370.651043 -270.59437)
			(xy 370.693664 -270.569763) (xy 370.73968 -270.552311) (xy 370.787899 -270.542467) (xy 370.837074 -270.540486)
			(xy 370.885929 -270.546418) (xy 370.9332 -270.56011) (xy 370.977662 -270.581208) (xy 371.018165 -270.609164)
			(xy 371.053658 -270.643256) (xy 371.083223 -270.6826) (xy 371.106094 -270.726177) (xy 371.121678 -270.772858)
			(xy 371.129573 -270.821435) (xy 371.130068 -270.846042) (xy 371.45901 -270.846042) (xy 371.46297 -270.796988)
			(xy 371.474747 -270.749204) (xy 371.494038 -270.703928) (xy 371.520341 -270.662332) (xy 371.552976 -270.625495)
			(xy 371.591097 -270.59437) (xy 371.633718 -270.569763) (xy 371.679734 -270.552311) (xy 371.727953 -270.542467)
			(xy 371.777128 -270.540486) (xy 371.825983 -270.546418) (xy 371.873254 -270.56011) (xy 371.917716 -270.581208)
			(xy 371.958219 -270.609164) (xy 371.993712 -270.643256) (xy 372.023277 -270.6826) (xy 372.046148 -270.726177)
			(xy 372.061732 -270.772858) (xy 372.069627 -270.821435) (xy 372.070122 -270.846042) (xy 372.399064 -270.846042)
			(xy 372.403024 -270.796988) (xy 372.414801 -270.749204) (xy 372.434092 -270.703928) (xy 372.460395 -270.662332)
			(xy 372.49303 -270.625495) (xy 372.531151 -270.59437) (xy 372.573772 -270.569763) (xy 372.619788 -270.552311)
			(xy 372.668007 -270.542467) (xy 372.717182 -270.540486) (xy 372.766037 -270.546418) (xy 372.813308 -270.56011)
			(xy 372.85777 -270.581208) (xy 372.898273 -270.609164) (xy 372.933766 -270.643256) (xy 372.963331 -270.6826)
			(xy 372.986202 -270.726177) (xy 373.001786 -270.772858) (xy 373.009681 -270.821435) (xy 373.010176 -270.846042)
			(xy 373.339118 -270.846042) (xy 373.343078 -270.796988) (xy 373.354855 -270.749204) (xy 373.374146 -270.703928)
			(xy 373.400449 -270.662332) (xy 373.433084 -270.625495) (xy 373.471205 -270.59437) (xy 373.513826 -270.569763)
			(xy 373.559842 -270.552311) (xy 373.608061 -270.542467) (xy 373.657236 -270.540486) (xy 373.706091 -270.546418)
			(xy 373.753362 -270.56011) (xy 373.797824 -270.581208) (xy 373.838327 -270.609164) (xy 373.87382 -270.643256)
			(xy 373.903385 -270.6826) (xy 373.926256 -270.726177) (xy 373.94184 -270.772858) (xy 373.949735 -270.821435)
			(xy 373.95023 -270.846042) (xy 373.949735 -270.870649) (xy 373.94184 -270.919226) (xy 373.926256 -270.965907)
			(xy 373.903385 -271.009484) (xy 373.87382 -271.048828) (xy 373.838327 -271.08292) (xy 373.797824 -271.110876)
			(xy 373.753362 -271.131974) (xy 373.706091 -271.145666) (xy 373.657236 -271.151598) (xy 373.608061 -271.149617)
			(xy 373.559842 -271.139773) (xy 373.513826 -271.122321) (xy 373.471205 -271.097714) (xy 373.433084 -271.066589)
			(xy 373.400449 -271.029752) (xy 373.374146 -270.988156) (xy 373.354855 -270.94288) (xy 373.343078 -270.895096)
			(xy 373.339118 -270.846042) (xy 373.010176 -270.846042) (xy 373.009681 -270.870649) (xy 373.001786 -270.919226)
			(xy 372.986202 -270.965907) (xy 372.963331 -271.009484) (xy 372.933766 -271.048828) (xy 372.898273 -271.08292)
			(xy 372.85777 -271.110876) (xy 372.813308 -271.131974) (xy 372.766037 -271.145666) (xy 372.717182 -271.151598)
			(xy 372.668007 -271.149617) (xy 372.619788 -271.139773) (xy 372.573772 -271.122321) (xy 372.531151 -271.097714)
			(xy 372.49303 -271.066589) (xy 372.460395 -271.029752) (xy 372.434092 -270.988156) (xy 372.414801 -270.94288)
			(xy 372.403024 -270.895096) (xy 372.399064 -270.846042) (xy 372.070122 -270.846042) (xy 372.069627 -270.870649)
			(xy 372.061732 -270.919226) (xy 372.046148 -270.965907) (xy 372.023277 -271.009484) (xy 371.993712 -271.048828)
			(xy 371.958219 -271.08292) (xy 371.917716 -271.110876) (xy 371.873254 -271.131974) (xy 371.825983 -271.145666)
			(xy 371.777128 -271.151598) (xy 371.727953 -271.149617) (xy 371.679734 -271.139773) (xy 371.633718 -271.122321)
			(xy 371.591097 -271.097714) (xy 371.552976 -271.066589) (xy 371.520341 -271.029752) (xy 371.494038 -270.988156)
			(xy 371.474747 -270.94288) (xy 371.46297 -270.895096) (xy 371.45901 -270.846042) (xy 371.130068 -270.846042)
			(xy 371.129573 -270.870649) (xy 371.121678 -270.919226) (xy 371.106094 -270.965907) (xy 371.083223 -271.009484)
			(xy 371.053658 -271.048828) (xy 371.018165 -271.08292) (xy 370.977662 -271.110876) (xy 370.9332 -271.131974)
			(xy 370.885929 -271.145666) (xy 370.837074 -271.151598) (xy 370.787899 -271.149617) (xy 370.73968 -271.139773)
			(xy 370.693664 -271.122321) (xy 370.651043 -271.097714) (xy 370.612922 -271.066589) (xy 370.580287 -271.029752)
			(xy 370.553984 -270.988156) (xy 370.534693 -270.94288) (xy 370.522916 -270.895096) (xy 370.518956 -270.846042)
			(xy 370.190014 -270.846042) (xy 370.189519 -270.870649) (xy 370.181624 -270.919226) (xy 370.16604 -270.965907)
			(xy 370.143169 -271.009484) (xy 370.113604 -271.048828) (xy 370.078111 -271.08292) (xy 370.037608 -271.110876)
			(xy 369.993146 -271.131974) (xy 369.945875 -271.145666) (xy 369.89702 -271.151598) (xy 369.847845 -271.149617)
			(xy 369.799626 -271.139773) (xy 369.75361 -271.122321) (xy 369.710989 -271.097714) (xy 369.672868 -271.066589)
			(xy 369.640233 -271.029752) (xy 369.61393 -270.988156) (xy 369.594639 -270.94288) (xy 369.582862 -270.895096)
			(xy 369.578902 -270.846042) (xy 369.250214 -270.846042) (xy 369.249719 -270.870649) (xy 369.241824 -270.919226)
			(xy 369.22624 -270.965907) (xy 369.203369 -271.009484) (xy 369.173804 -271.048828) (xy 369.138311 -271.08292)
			(xy 369.097808 -271.110876) (xy 369.053346 -271.131974) (xy 369.006075 -271.145666) (xy 368.95722 -271.151598)
			(xy 368.908045 -271.149617) (xy 368.859826 -271.139773) (xy 368.81381 -271.122321) (xy 368.771189 -271.097714)
			(xy 368.733068 -271.066589) (xy 368.700433 -271.029752) (xy 368.67413 -270.988156) (xy 368.654839 -270.94288)
			(xy 368.643062 -270.895096) (xy 368.639102 -270.846042) (xy 368.31016 -270.846042) (xy 368.309665 -270.870649)
			(xy 368.30177 -270.919226) (xy 368.286186 -270.965907) (xy 368.263315 -271.009484) (xy 368.23375 -271.048828)
			(xy 368.198257 -271.08292) (xy 368.157754 -271.110876) (xy 368.113292 -271.131974) (xy 368.066021 -271.145666)
			(xy 368.017166 -271.151598) (xy 367.967991 -271.149617) (xy 367.919772 -271.139773) (xy 367.873756 -271.122321)
			(xy 367.831135 -271.097714) (xy 367.793014 -271.066589) (xy 367.760379 -271.029752) (xy 367.734076 -270.988156)
			(xy 367.714785 -270.94288) (xy 367.703008 -270.895096) (xy 367.699048 -270.846042) (xy 367.370106 -270.846042)
			(xy 367.369611 -270.870649) (xy 367.361716 -270.919226) (xy 367.346132 -270.965907) (xy 367.323261 -271.009484)
			(xy 367.293696 -271.048828) (xy 367.258203 -271.08292) (xy 367.2177 -271.110876) (xy 367.173238 -271.131974)
			(xy 367.125967 -271.145666) (xy 367.077112 -271.151598) (xy 367.027937 -271.149617) (xy 366.979718 -271.139773)
			(xy 366.933702 -271.122321) (xy 366.891081 -271.097714) (xy 366.85296 -271.066589) (xy 366.820325 -271.029752)
			(xy 366.794022 -270.988156) (xy 366.774731 -270.94288) (xy 366.762954 -270.895096) (xy 366.758994 -270.846042)
			(xy 366.430052 -270.846042) (xy 366.429557 -270.870649) (xy 366.421662 -270.919226) (xy 366.406078 -270.965907)
			(xy 366.383207 -271.009484) (xy 366.353642 -271.048828) (xy 366.318149 -271.08292) (xy 366.277646 -271.110876)
			(xy 366.233184 -271.131974) (xy 366.185913 -271.145666) (xy 366.137058 -271.151598) (xy 366.087883 -271.149617)
			(xy 366.039664 -271.139773) (xy 365.993648 -271.122321) (xy 365.951027 -271.097714) (xy 365.912906 -271.066589)
			(xy 365.880271 -271.029752) (xy 365.853968 -270.988156) (xy 365.834677 -270.94288) (xy 365.8229 -270.895096)
			(xy 365.81894 -270.846042) (xy 365.489998 -270.846042) (xy 365.489503 -270.870649) (xy 365.481608 -270.919226)
			(xy 365.466024 -270.965907) (xy 365.443153 -271.009484) (xy 365.413588 -271.048828) (xy 365.378095 -271.08292)
			(xy 365.337592 -271.110876) (xy 365.29313 -271.131974) (xy 365.245859 -271.145666) (xy 365.197004 -271.151598)
			(xy 365.147829 -271.149617) (xy 365.09961 -271.139773) (xy 365.053594 -271.122321) (xy 365.010973 -271.097714)
			(xy 364.972852 -271.066589) (xy 364.940217 -271.029752) (xy 364.913914 -270.988156) (xy 364.894623 -270.94288)
			(xy 364.882846 -270.895096) (xy 364.878886 -270.846042) (xy 364.550198 -270.846042) (xy 364.549703 -270.870649)
			(xy 364.541808 -270.919226) (xy 364.526224 -270.965907) (xy 364.503353 -271.009484) (xy 364.473788 -271.048828)
			(xy 364.438295 -271.08292) (xy 364.397792 -271.110876) (xy 364.35333 -271.131974) (xy 364.306059 -271.145666)
			(xy 364.257204 -271.151598) (xy 364.208029 -271.149617) (xy 364.15981 -271.139773) (xy 364.113794 -271.122321)
			(xy 364.071173 -271.097714) (xy 364.033052 -271.066589) (xy 364.000417 -271.029752) (xy 363.974114 -270.988156)
			(xy 363.954823 -270.94288) (xy 363.943046 -270.895096) (xy 363.939086 -270.846042) (xy 363.610144 -270.846042)
			(xy 363.609649 -270.870649) (xy 363.601754 -270.919226) (xy 363.58617 -270.965907) (xy 363.563299 -271.009484)
			(xy 363.533734 -271.048828) (xy 363.498241 -271.08292) (xy 363.457738 -271.110876) (xy 363.413276 -271.131974)
			(xy 363.366005 -271.145666) (xy 363.31715 -271.151598) (xy 363.267975 -271.149617) (xy 363.219756 -271.139773)
			(xy 363.17374 -271.122321) (xy 363.131119 -271.097714) (xy 363.092998 -271.066589) (xy 363.060363 -271.029752)
			(xy 363.03406 -270.988156) (xy 363.014769 -270.94288) (xy 363.002992 -270.895096) (xy 362.999032 -270.846042)
			(xy 362.67009 -270.846042) (xy 362.669595 -270.870649) (xy 362.6617 -270.919226) (xy 362.646116 -270.965907)
			(xy 362.623245 -271.009484) (xy 362.59368 -271.048828) (xy 362.558187 -271.08292) (xy 362.517684 -271.110876)
			(xy 362.473222 -271.131974) (xy 362.425951 -271.145666) (xy 362.377096 -271.151598) (xy 362.327921 -271.149617)
			(xy 362.279702 -271.139773) (xy 362.233686 -271.122321) (xy 362.191065 -271.097714) (xy 362.152944 -271.066589)
			(xy 362.120309 -271.029752) (xy 362.094006 -270.988156) (xy 362.074715 -270.94288) (xy 362.062938 -270.895096)
			(xy 362.058978 -270.846042) (xy 361.730036 -270.846042) (xy 361.729541 -270.870649) (xy 361.721646 -270.919226)
			(xy 361.706062 -270.965907) (xy 361.683191 -271.009484) (xy 361.653626 -271.048828) (xy 361.618133 -271.08292)
			(xy 361.57763 -271.110876) (xy 361.533168 -271.131974) (xy 361.485897 -271.145666) (xy 361.437042 -271.151598)
			(xy 361.387867 -271.149617) (xy 361.339648 -271.139773) (xy 361.293632 -271.122321) (xy 361.251011 -271.097714)
			(xy 361.21289 -271.066589) (xy 361.180255 -271.029752) (xy 361.153952 -270.988156) (xy 361.134661 -270.94288)
			(xy 361.122884 -270.895096) (xy 361.118924 -270.846042) (xy 358.916478 -270.846042) (xy 358.915983 -270.870649)
			(xy 358.908088 -270.919226) (xy 358.892504 -270.965907) (xy 358.869633 -271.009484) (xy 358.840068 -271.048828)
			(xy 358.804575 -271.08292) (xy 358.764072 -271.110876) (xy 358.71961 -271.131974) (xy 358.672339 -271.145666)
			(xy 358.623484 -271.151598) (xy 358.574309 -271.149617) (xy 358.52609 -271.139773) (xy 358.480074 -271.122321)
			(xy 358.437453 -271.097714) (xy 358.399332 -271.066589) (xy 358.366697 -271.029752) (xy 358.340394 -270.988156)
			(xy 358.321103 -270.94288) (xy 358.309326 -270.895096) (xy 358.305366 -270.846042) (xy 357.976424 -270.846042)
			(xy 357.975929 -270.870649) (xy 357.968034 -270.919226) (xy 357.95245 -270.965907) (xy 357.929579 -271.009484)
			(xy 357.900014 -271.048828) (xy 357.864521 -271.08292) (xy 357.824018 -271.110876) (xy 357.779556 -271.131974)
			(xy 357.732285 -271.145666) (xy 357.68343 -271.151598) (xy 357.634255 -271.149617) (xy 357.586036 -271.139773)
			(xy 357.54002 -271.122321) (xy 357.497399 -271.097714) (xy 357.459278 -271.066589) (xy 357.426643 -271.029752)
			(xy 357.40034 -270.988156) (xy 357.381049 -270.94288) (xy 357.369272 -270.895096) (xy 357.365312 -270.846042)
			(xy 357.03637 -270.846042) (xy 357.035875 -270.870649) (xy 357.02798 -270.919226) (xy 357.012396 -270.965907)
			(xy 356.989525 -271.009484) (xy 356.95996 -271.048828) (xy 356.924467 -271.08292) (xy 356.883964 -271.110876)
			(xy 356.839502 -271.131974) (xy 356.792231 -271.145666) (xy 356.743376 -271.151598) (xy 356.694201 -271.149617)
			(xy 356.645982 -271.139773) (xy 356.599966 -271.122321) (xy 356.557345 -271.097714) (xy 356.519224 -271.066589)
			(xy 356.486589 -271.029752) (xy 356.460286 -270.988156) (xy 356.440995 -270.94288) (xy 356.429218 -270.895096)
			(xy 356.425258 -270.846042) (xy 356.096316 -270.846042) (xy 356.095821 -270.870649) (xy 356.087926 -270.919226)
			(xy 356.072342 -270.965907) (xy 356.049471 -271.009484) (xy 356.019906 -271.048828) (xy 355.984413 -271.08292)
			(xy 355.94391 -271.110876) (xy 355.899448 -271.131974) (xy 355.852177 -271.145666) (xy 355.803322 -271.151598)
			(xy 355.754147 -271.149617) (xy 355.705928 -271.139773) (xy 355.659912 -271.122321) (xy 355.617291 -271.097714)
			(xy 355.57917 -271.066589) (xy 355.546535 -271.029752) (xy 355.520232 -270.988156) (xy 355.500941 -270.94288)
			(xy 355.489164 -270.895096) (xy 355.485204 -270.846042) (xy 355.156516 -270.846042) (xy 355.156021 -270.870649)
			(xy 355.148126 -270.919226) (xy 355.132542 -270.965907) (xy 355.109671 -271.009484) (xy 355.080106 -271.048828)
			(xy 355.044613 -271.08292) (xy 355.00411 -271.110876) (xy 354.959648 -271.131974) (xy 354.912377 -271.145666)
			(xy 354.863522 -271.151598) (xy 354.814347 -271.149617) (xy 354.766128 -271.139773) (xy 354.720112 -271.122321)
			(xy 354.677491 -271.097714) (xy 354.63937 -271.066589) (xy 354.606735 -271.029752) (xy 354.580432 -270.988156)
			(xy 354.561141 -270.94288) (xy 354.549364 -270.895096) (xy 354.545404 -270.846042) (xy 354.216462 -270.846042)
			(xy 354.215967 -270.870649) (xy 354.208072 -270.919226) (xy 354.192488 -270.965907) (xy 354.169617 -271.009484)
			(xy 354.140052 -271.048828) (xy 354.104559 -271.08292) (xy 354.064056 -271.110876) (xy 354.019594 -271.131974)
			(xy 353.972323 -271.145666) (xy 353.923468 -271.151598) (xy 353.874293 -271.149617) (xy 353.826074 -271.139773)
			(xy 353.780058 -271.122321) (xy 353.737437 -271.097714) (xy 353.699316 -271.066589) (xy 353.666681 -271.029752)
			(xy 353.640378 -270.988156) (xy 353.621087 -270.94288) (xy 353.60931 -270.895096) (xy 353.60535 -270.846042)
			(xy 353.276408 -270.846042) (xy 353.275913 -270.870649) (xy 353.268018 -270.919226) (xy 353.252434 -270.965907)
			(xy 353.229563 -271.009484) (xy 353.199998 -271.048828) (xy 353.164505 -271.08292) (xy 353.124002 -271.110876)
			(xy 353.07954 -271.131974) (xy 353.032269 -271.145666) (xy 352.983414 -271.151598) (xy 352.934239 -271.149617)
			(xy 352.88602 -271.139773) (xy 352.840004 -271.122321) (xy 352.797383 -271.097714) (xy 352.759262 -271.066589)
			(xy 352.726627 -271.029752) (xy 352.700324 -270.988156) (xy 352.681033 -270.94288) (xy 352.669256 -270.895096)
			(xy 352.665296 -270.846042) (xy 352.336354 -270.846042) (xy 352.335859 -270.870649) (xy 352.327964 -270.919226)
			(xy 352.31238 -270.965907) (xy 352.289509 -271.009484) (xy 352.259944 -271.048828) (xy 352.224451 -271.08292)
			(xy 352.183948 -271.110876) (xy 352.139486 -271.131974) (xy 352.092215 -271.145666) (xy 352.04336 -271.151598)
			(xy 351.994185 -271.149617) (xy 351.945966 -271.139773) (xy 351.89995 -271.122321) (xy 351.857329 -271.097714)
			(xy 351.819208 -271.066589) (xy 351.786573 -271.029752) (xy 351.76027 -270.988156) (xy 351.740979 -270.94288)
			(xy 351.729202 -270.895096) (xy 351.725242 -270.846042) (xy 351.396554 -270.846042) (xy 351.396059 -270.870649)
			(xy 351.388164 -270.919226) (xy 351.37258 -270.965907) (xy 351.349709 -271.009484) (xy 351.320144 -271.048828)
			(xy 351.284651 -271.08292) (xy 351.244148 -271.110876) (xy 351.199686 -271.131974) (xy 351.152415 -271.145666)
			(xy 351.10356 -271.151598) (xy 351.054385 -271.149617) (xy 351.006166 -271.139773) (xy 350.96015 -271.122321)
			(xy 350.917529 -271.097714) (xy 350.879408 -271.066589) (xy 350.846773 -271.029752) (xy 350.82047 -270.988156)
			(xy 350.801179 -270.94288) (xy 350.789402 -270.895096) (xy 350.785442 -270.846042) (xy 350.4565 -270.846042)
			(xy 350.456005 -270.870649) (xy 350.44811 -270.919226) (xy 350.432526 -270.965907) (xy 350.409655 -271.009484)
			(xy 350.38009 -271.048828) (xy 350.344597 -271.08292) (xy 350.304094 -271.110876) (xy 350.259632 -271.131974)
			(xy 350.212361 -271.145666) (xy 350.163506 -271.151598) (xy 350.114331 -271.149617) (xy 350.066112 -271.139773)
			(xy 350.020096 -271.122321) (xy 349.977475 -271.097714) (xy 349.939354 -271.066589) (xy 349.906719 -271.029752)
			(xy 349.880416 -270.988156) (xy 349.861125 -270.94288) (xy 349.849348 -270.895096) (xy 349.845388 -270.846042)
			(xy 349.516446 -270.846042) (xy 349.515951 -270.870649) (xy 349.508056 -270.919226) (xy 349.492472 -270.965907)
			(xy 349.469601 -271.009484) (xy 349.440036 -271.048828) (xy 349.404543 -271.08292) (xy 349.36404 -271.110876)
			(xy 349.319578 -271.131974) (xy 349.272307 -271.145666) (xy 349.223452 -271.151598) (xy 349.174277 -271.149617)
			(xy 349.126058 -271.139773) (xy 349.080042 -271.122321) (xy 349.037421 -271.097714) (xy 348.9993 -271.066589)
			(xy 348.966665 -271.029752) (xy 348.940362 -270.988156) (xy 348.921071 -270.94288) (xy 348.909294 -270.895096)
			(xy 348.905334 -270.846042) (xy 348.576392 -270.846042) (xy 348.575897 -270.870649) (xy 348.568002 -270.919226)
			(xy 348.552418 -270.965907) (xy 348.529547 -271.009484) (xy 348.499982 -271.048828) (xy 348.464489 -271.08292)
			(xy 348.423986 -271.110876) (xy 348.379524 -271.131974) (xy 348.332253 -271.145666) (xy 348.283398 -271.151598)
			(xy 348.234223 -271.149617) (xy 348.186004 -271.139773) (xy 348.139988 -271.122321) (xy 348.097367 -271.097714)
			(xy 348.059246 -271.066589) (xy 348.026611 -271.029752) (xy 348.000308 -270.988156) (xy 347.981017 -270.94288)
			(xy 347.96924 -270.895096) (xy 347.96528 -270.846042) (xy 347.636338 -270.846042) (xy 347.635843 -270.870649)
			(xy 347.627948 -270.919226) (xy 347.612364 -270.965907) (xy 347.589493 -271.009484) (xy 347.559928 -271.048828)
			(xy 347.524435 -271.08292) (xy 347.483932 -271.110876) (xy 347.43947 -271.131974) (xy 347.392199 -271.145666)
			(xy 347.343344 -271.151598) (xy 347.294169 -271.149617) (xy 347.24595 -271.139773) (xy 347.199934 -271.122321)
			(xy 347.157313 -271.097714) (xy 347.119192 -271.066589) (xy 347.086557 -271.029752) (xy 347.060254 -270.988156)
			(xy 347.040963 -270.94288) (xy 347.029186 -270.895096) (xy 347.025226 -270.846042) (xy 346.696538 -270.846042)
			(xy 346.696043 -270.870649) (xy 346.688148 -270.919226) (xy 346.672564 -270.965907) (xy 346.649693 -271.009484)
			(xy 346.620128 -271.048828) (xy 346.584635 -271.08292) (xy 346.544132 -271.110876) (xy 346.49967 -271.131974)
			(xy 346.452399 -271.145666) (xy 346.403544 -271.151598) (xy 346.354369 -271.149617) (xy 346.30615 -271.139773)
			(xy 346.260134 -271.122321) (xy 346.217513 -271.097714) (xy 346.179392 -271.066589) (xy 346.146757 -271.029752)
			(xy 346.120454 -270.988156) (xy 346.101163 -270.94288) (xy 346.089386 -270.895096) (xy 346.085426 -270.846042)
			(xy 345.756484 -270.846042) (xy 345.755989 -270.870649) (xy 345.748094 -270.919226) (xy 345.73251 -270.965907)
			(xy 345.709639 -271.009484) (xy 345.680074 -271.048828) (xy 345.644581 -271.08292) (xy 345.604078 -271.110876)
			(xy 345.559616 -271.131974) (xy 345.512345 -271.145666) (xy 345.46349 -271.151598) (xy 345.414315 -271.149617)
			(xy 345.366096 -271.139773) (xy 345.32008 -271.122321) (xy 345.277459 -271.097714) (xy 345.239338 -271.066589)
			(xy 345.206703 -271.029752) (xy 345.1804 -270.988156) (xy 345.161109 -270.94288) (xy 345.149332 -270.895096)
			(xy 345.145372 -270.846042) (xy 344.880692 -270.846042) (xy 344.880692 -271.250156) (xy 344.881159 -271.26003)
			(xy 344.888611 -271.27832) (xy 344.89517 -271.285716) (xy 344.895424 -271.28597) (xy 344.945208 -271.335754)
			(xy 344.952605 -271.342604) (xy 344.971203 -271.350343) (xy 344.981276 -271.35074) (xy 345.006512 -271.351283)
			(xy 345.056291 -271.359631) (xy 345.104018 -271.376054) (xy 345.148394 -271.400104) (xy 345.188208 -271.431127)
			(xy 345.222377 -271.468276) (xy 345.24997 -271.51054) (xy 345.270234 -271.556767) (xy 345.282617 -271.605698)
			(xy 345.286783 -271.656) (xy 345.286779 -271.656048) (xy 345.615272 -271.656048) (xy 345.619232 -271.606994)
			(xy 345.631009 -271.55921) (xy 345.6503 -271.513934) (xy 345.676603 -271.472338) (xy 345.709238 -271.435501)
			(xy 345.747359 -271.404376) (xy 345.78998 -271.379769) (xy 345.835996 -271.362317) (xy 345.884215 -271.352473)
			(xy 345.93339 -271.350492) (xy 345.982245 -271.356424) (xy 346.029516 -271.370116) (xy 346.073978 -271.391214)
			(xy 346.114481 -271.41917) (xy 346.149974 -271.453262) (xy 346.179539 -271.492606) (xy 346.20241 -271.536183)
			(xy 346.217994 -271.582864) (xy 346.225889 -271.631441) (xy 346.226384 -271.656048) (xy 346.555326 -271.656048)
			(xy 346.559286 -271.606994) (xy 346.571063 -271.55921) (xy 346.590354 -271.513934) (xy 346.616657 -271.472338)
			(xy 346.649292 -271.435501) (xy 346.687413 -271.404376) (xy 346.730034 -271.379769) (xy 346.77605 -271.362317)
			(xy 346.824269 -271.352473) (xy 346.873444 -271.350492) (xy 346.922299 -271.356424) (xy 346.96957 -271.370116)
			(xy 347.014032 -271.391214) (xy 347.054535 -271.41917) (xy 347.090028 -271.453262) (xy 347.119593 -271.492606)
			(xy 347.142464 -271.536183) (xy 347.158048 -271.582864) (xy 347.165943 -271.631441) (xy 347.166438 -271.656048)
			(xy 347.49538 -271.656048) (xy 347.49934 -271.606994) (xy 347.511117 -271.55921) (xy 347.530408 -271.513934)
			(xy 347.556711 -271.472338) (xy 347.589346 -271.435501) (xy 347.627467 -271.404376) (xy 347.670088 -271.379769)
			(xy 347.716104 -271.362317) (xy 347.764323 -271.352473) (xy 347.813498 -271.350492) (xy 347.862353 -271.356424)
			(xy 347.909624 -271.370116) (xy 347.954086 -271.391214) (xy 347.994589 -271.41917) (xy 348.030082 -271.453262)
			(xy 348.059647 -271.492606) (xy 348.082518 -271.536183) (xy 348.098102 -271.582864) (xy 348.105997 -271.631441)
			(xy 348.106492 -271.656048) (xy 348.435434 -271.656048) (xy 348.439394 -271.606994) (xy 348.451171 -271.55921)
			(xy 348.470462 -271.513934) (xy 348.496765 -271.472338) (xy 348.5294 -271.435501) (xy 348.567521 -271.404376)
			(xy 348.610142 -271.379769) (xy 348.656158 -271.362317) (xy 348.704377 -271.352473) (xy 348.753552 -271.350492)
			(xy 348.802407 -271.356424) (xy 348.849678 -271.370116) (xy 348.89414 -271.391214) (xy 348.934643 -271.41917)
			(xy 348.970136 -271.453262) (xy 348.999701 -271.492606) (xy 349.022572 -271.536183) (xy 349.038156 -271.582864)
			(xy 349.046051 -271.631441) (xy 349.046546 -271.656048) (xy 349.375234 -271.656048) (xy 349.379194 -271.606994)
			(xy 349.390971 -271.55921) (xy 349.410262 -271.513934) (xy 349.436565 -271.472338) (xy 349.4692 -271.435501)
			(xy 349.507321 -271.404376) (xy 349.549942 -271.379769) (xy 349.595958 -271.362317) (xy 349.644177 -271.352473)
			(xy 349.693352 -271.350492) (xy 349.742207 -271.356424) (xy 349.789478 -271.370116) (xy 349.83394 -271.391214)
			(xy 349.874443 -271.41917) (xy 349.909936 -271.453262) (xy 349.939501 -271.492606) (xy 349.962372 -271.536183)
			(xy 349.977956 -271.582864) (xy 349.985851 -271.631441) (xy 349.986346 -271.656048) (xy 350.315288 -271.656048)
			(xy 350.319248 -271.606994) (xy 350.331025 -271.55921) (xy 350.350316 -271.513934) (xy 350.376619 -271.472338)
			(xy 350.409254 -271.435501) (xy 350.447375 -271.404376) (xy 350.489996 -271.379769) (xy 350.536012 -271.362317)
			(xy 350.584231 -271.352473) (xy 350.633406 -271.350492) (xy 350.682261 -271.356424) (xy 350.729532 -271.370116)
			(xy 350.773994 -271.391214) (xy 350.814497 -271.41917) (xy 350.84999 -271.453262) (xy 350.879555 -271.492606)
			(xy 350.902426 -271.536183) (xy 350.91801 -271.582864) (xy 350.925905 -271.631441) (xy 350.9264 -271.656048)
			(xy 351.255342 -271.656048) (xy 351.259302 -271.606994) (xy 351.271079 -271.55921) (xy 351.29037 -271.513934)
			(xy 351.316673 -271.472338) (xy 351.349308 -271.435501) (xy 351.387429 -271.404376) (xy 351.43005 -271.379769)
			(xy 351.476066 -271.362317) (xy 351.524285 -271.352473) (xy 351.57346 -271.350492) (xy 351.622315 -271.356424)
			(xy 351.669586 -271.370116) (xy 351.714048 -271.391214) (xy 351.754551 -271.41917) (xy 351.790044 -271.453262)
			(xy 351.819609 -271.492606) (xy 351.84248 -271.536183) (xy 351.858064 -271.582864) (xy 351.865959 -271.631441)
			(xy 351.866454 -271.656048) (xy 352.195396 -271.656048) (xy 352.199356 -271.606994) (xy 352.211133 -271.55921)
			(xy 352.230424 -271.513934) (xy 352.256727 -271.472338) (xy 352.289362 -271.435501) (xy 352.327483 -271.404376)
			(xy 352.370104 -271.379769) (xy 352.41612 -271.362317) (xy 352.464339 -271.352473) (xy 352.513514 -271.350492)
			(xy 352.562369 -271.356424) (xy 352.60964 -271.370116) (xy 352.654102 -271.391214) (xy 352.694605 -271.41917)
			(xy 352.730098 -271.453262) (xy 352.759663 -271.492606) (xy 352.782534 -271.536183) (xy 352.798118 -271.582864)
			(xy 352.806013 -271.631441) (xy 352.806508 -271.656048) (xy 353.135196 -271.656048) (xy 353.139156 -271.606994)
			(xy 353.150933 -271.55921) (xy 353.170224 -271.513934) (xy 353.196527 -271.472338) (xy 353.229162 -271.435501)
			(xy 353.267283 -271.404376) (xy 353.309904 -271.379769) (xy 353.35592 -271.362317) (xy 353.404139 -271.352473)
			(xy 353.453314 -271.350492) (xy 353.502169 -271.356424) (xy 353.54944 -271.370116) (xy 353.593902 -271.391214)
			(xy 353.634405 -271.41917) (xy 353.669898 -271.453262) (xy 353.699463 -271.492606) (xy 353.722334 -271.536183)
			(xy 353.737918 -271.582864) (xy 353.745813 -271.631441) (xy 353.746308 -271.656048) (xy 354.07525 -271.656048)
			(xy 354.07921 -271.606994) (xy 354.090987 -271.55921) (xy 354.110278 -271.513934) (xy 354.136581 -271.472338)
			(xy 354.169216 -271.435501) (xy 354.207337 -271.404376) (xy 354.249958 -271.379769) (xy 354.295974 -271.362317)
			(xy 354.344193 -271.352473) (xy 354.393368 -271.350492) (xy 354.442223 -271.356424) (xy 354.489494 -271.370116)
			(xy 354.533956 -271.391214) (xy 354.574459 -271.41917) (xy 354.609952 -271.453262) (xy 354.639517 -271.492606)
			(xy 354.662388 -271.536183) (xy 354.677972 -271.582864) (xy 354.685867 -271.631441) (xy 354.686362 -271.656048)
			(xy 355.015304 -271.656048) (xy 355.019264 -271.606994) (xy 355.031041 -271.55921) (xy 355.050332 -271.513934)
			(xy 355.076635 -271.472338) (xy 355.10927 -271.435501) (xy 355.147391 -271.404376) (xy 355.190012 -271.379769)
			(xy 355.236028 -271.362317) (xy 355.284247 -271.352473) (xy 355.333422 -271.350492) (xy 355.382277 -271.356424)
			(xy 355.429548 -271.370116) (xy 355.47401 -271.391214) (xy 355.514513 -271.41917) (xy 355.550006 -271.453262)
			(xy 355.579571 -271.492606) (xy 355.602442 -271.536183) (xy 355.618026 -271.582864) (xy 355.625921 -271.631441)
			(xy 355.626416 -271.656048) (xy 355.955358 -271.656048) (xy 355.959318 -271.606994) (xy 355.971095 -271.55921)
			(xy 355.990386 -271.513934) (xy 356.016689 -271.472338) (xy 356.049324 -271.435501) (xy 356.087445 -271.404376)
			(xy 356.130066 -271.379769) (xy 356.176082 -271.362317) (xy 356.224301 -271.352473) (xy 356.273476 -271.350492)
			(xy 356.322331 -271.356424) (xy 356.369602 -271.370116) (xy 356.414064 -271.391214) (xy 356.454567 -271.41917)
			(xy 356.49006 -271.453262) (xy 356.519625 -271.492606) (xy 356.542496 -271.536183) (xy 356.55808 -271.582864)
			(xy 356.565975 -271.631441) (xy 356.56647 -271.656048) (xy 363.468932 -271.656048) (xy 363.472892 -271.606994)
			(xy 363.484669 -271.55921) (xy 363.50396 -271.513934) (xy 363.530263 -271.472338) (xy 363.562898 -271.435501)
			(xy 363.601019 -271.404376) (xy 363.64364 -271.379769) (xy 363.689656 -271.362317) (xy 363.737875 -271.352473)
			(xy 363.78705 -271.350492) (xy 363.835905 -271.356424) (xy 363.883176 -271.370116) (xy 363.927638 -271.391214)
			(xy 363.968141 -271.41917) (xy 364.003634 -271.453262) (xy 364.033199 -271.492606) (xy 364.05607 -271.536183)
			(xy 364.071654 -271.582864) (xy 364.079549 -271.631441) (xy 364.080044 -271.656048) (xy 364.408986 -271.656048)
			(xy 364.412946 -271.606994) (xy 364.424723 -271.55921) (xy 364.444014 -271.513934) (xy 364.470317 -271.472338)
			(xy 364.502952 -271.435501) (xy 364.541073 -271.404376) (xy 364.583694 -271.379769) (xy 364.62971 -271.362317)
			(xy 364.677929 -271.352473) (xy 364.727104 -271.350492) (xy 364.775959 -271.356424) (xy 364.82323 -271.370116)
			(xy 364.867692 -271.391214) (xy 364.908195 -271.41917) (xy 364.943688 -271.453262) (xy 364.973253 -271.492606)
			(xy 364.996124 -271.536183) (xy 365.011708 -271.582864) (xy 365.019603 -271.631441) (xy 365.020098 -271.656048)
			(xy 365.34904 -271.656048) (xy 365.353 -271.606994) (xy 365.364777 -271.55921) (xy 365.384068 -271.513934)
			(xy 365.410371 -271.472338) (xy 365.443006 -271.435501) (xy 365.481127 -271.404376) (xy 365.523748 -271.379769)
			(xy 365.569764 -271.362317) (xy 365.617983 -271.352473) (xy 365.667158 -271.350492) (xy 365.716013 -271.356424)
			(xy 365.763284 -271.370116) (xy 365.807746 -271.391214) (xy 365.848249 -271.41917) (xy 365.883742 -271.453262)
			(xy 365.913307 -271.492606) (xy 365.936178 -271.536183) (xy 365.951762 -271.582864) (xy 365.959657 -271.631441)
			(xy 365.960152 -271.656048) (xy 366.289094 -271.656048) (xy 366.293054 -271.606994) (xy 366.304831 -271.55921)
			(xy 366.324122 -271.513934) (xy 366.350425 -271.472338) (xy 366.38306 -271.435501) (xy 366.421181 -271.404376)
			(xy 366.463802 -271.379769) (xy 366.509818 -271.362317) (xy 366.558037 -271.352473) (xy 366.607212 -271.350492)
			(xy 366.656067 -271.356424) (xy 366.703338 -271.370116) (xy 366.7478 -271.391214) (xy 366.788303 -271.41917)
			(xy 366.823796 -271.453262) (xy 366.853361 -271.492606) (xy 366.876232 -271.536183) (xy 366.891816 -271.582864)
			(xy 366.899711 -271.631441) (xy 366.900206 -271.656048) (xy 367.228894 -271.656048) (xy 367.232854 -271.606994)
			(xy 367.244631 -271.55921) (xy 367.263922 -271.513934) (xy 367.290225 -271.472338) (xy 367.32286 -271.435501)
			(xy 367.360981 -271.404376) (xy 367.403602 -271.379769) (xy 367.449618 -271.362317) (xy 367.497837 -271.352473)
			(xy 367.547012 -271.350492) (xy 367.595867 -271.356424) (xy 367.643138 -271.370116) (xy 367.6876 -271.391214)
			(xy 367.728103 -271.41917) (xy 367.763596 -271.453262) (xy 367.793161 -271.492606) (xy 367.816032 -271.536183)
			(xy 367.831616 -271.582864) (xy 367.839511 -271.631441) (xy 367.840006 -271.656048) (xy 368.168948 -271.656048)
			(xy 368.172908 -271.606994) (xy 368.184685 -271.55921) (xy 368.203976 -271.513934) (xy 368.230279 -271.472338)
			(xy 368.262914 -271.435501) (xy 368.301035 -271.404376) (xy 368.343656 -271.379769) (xy 368.389672 -271.362317)
			(xy 368.437891 -271.352473) (xy 368.487066 -271.350492) (xy 368.535921 -271.356424) (xy 368.583192 -271.370116)
			(xy 368.627654 -271.391214) (xy 368.668157 -271.41917) (xy 368.70365 -271.453262) (xy 368.733215 -271.492606)
			(xy 368.756086 -271.536183) (xy 368.77167 -271.582864) (xy 368.779565 -271.631441) (xy 368.78006 -271.656048)
			(xy 369.109002 -271.656048) (xy 369.112962 -271.606994) (xy 369.124739 -271.55921) (xy 369.14403 -271.513934)
			(xy 369.170333 -271.472338) (xy 369.202968 -271.435501) (xy 369.241089 -271.404376) (xy 369.28371 -271.379769)
			(xy 369.329726 -271.362317) (xy 369.377945 -271.352473) (xy 369.42712 -271.350492) (xy 369.475975 -271.356424)
			(xy 369.523246 -271.370116) (xy 369.567708 -271.391214) (xy 369.608211 -271.41917) (xy 369.643704 -271.453262)
			(xy 369.673269 -271.492606) (xy 369.69614 -271.536183) (xy 369.711724 -271.582864) (xy 369.719619 -271.631441)
			(xy 369.720114 -271.656048) (xy 370.049056 -271.656048) (xy 370.053016 -271.606994) (xy 370.064793 -271.55921)
			(xy 370.084084 -271.513934) (xy 370.110387 -271.472338) (xy 370.143022 -271.435501) (xy 370.181143 -271.404376)
			(xy 370.223764 -271.379769) (xy 370.26978 -271.362317) (xy 370.317999 -271.352473) (xy 370.367174 -271.350492)
			(xy 370.416029 -271.356424) (xy 370.4633 -271.370116) (xy 370.507762 -271.391214) (xy 370.548265 -271.41917)
			(xy 370.583758 -271.453262) (xy 370.613323 -271.492606) (xy 370.636194 -271.536183) (xy 370.651778 -271.582864)
			(xy 370.659673 -271.631441) (xy 370.660168 -271.656048) (xy 370.98911 -271.656048) (xy 370.99307 -271.606994)
			(xy 371.004847 -271.55921) (xy 371.024138 -271.513934) (xy 371.050441 -271.472338) (xy 371.083076 -271.435501)
			(xy 371.121197 -271.404376) (xy 371.163818 -271.379769) (xy 371.209834 -271.362317) (xy 371.258053 -271.352473)
			(xy 371.307228 -271.350492) (xy 371.356083 -271.356424) (xy 371.403354 -271.370116) (xy 371.447816 -271.391214)
			(xy 371.488319 -271.41917) (xy 371.523812 -271.453262) (xy 371.553377 -271.492606) (xy 371.576248 -271.536183)
			(xy 371.591832 -271.582864) (xy 371.599727 -271.631441) (xy 371.600222 -271.656048) (xy 371.92891 -271.656048)
			(xy 371.93287 -271.606994) (xy 371.944647 -271.55921) (xy 371.963938 -271.513934) (xy 371.990241 -271.472338)
			(xy 372.022876 -271.435501) (xy 372.060997 -271.404376) (xy 372.103618 -271.379769) (xy 372.149634 -271.362317)
			(xy 372.197853 -271.352473) (xy 372.247028 -271.350492) (xy 372.295883 -271.356424) (xy 372.343154 -271.370116)
			(xy 372.387616 -271.391214) (xy 372.428119 -271.41917) (xy 372.463612 -271.453262) (xy 372.493177 -271.492606)
			(xy 372.516048 -271.536183) (xy 372.531632 -271.582864) (xy 372.539527 -271.631441) (xy 372.540022 -271.656048)
			(xy 372.539527 -271.680655) (xy 372.531632 -271.729232) (xy 372.516048 -271.775913) (xy 372.493177 -271.81949)
			(xy 372.463612 -271.858834) (xy 372.428119 -271.892926) (xy 372.387616 -271.920882) (xy 372.343154 -271.94198)
			(xy 372.295883 -271.955672) (xy 372.247028 -271.961604) (xy 372.197853 -271.959623) (xy 372.149634 -271.949779)
			(xy 372.103618 -271.932327) (xy 372.060997 -271.90772) (xy 372.022876 -271.876595) (xy 371.990241 -271.839758)
			(xy 371.963938 -271.798162) (xy 371.944647 -271.752886) (xy 371.93287 -271.705102) (xy 371.92891 -271.656048)
			(xy 371.600222 -271.656048) (xy 371.599727 -271.680655) (xy 371.591832 -271.729232) (xy 371.576248 -271.775913)
			(xy 371.553377 -271.81949) (xy 371.523812 -271.858834) (xy 371.488319 -271.892926) (xy 371.447816 -271.920882)
			(xy 371.403354 -271.94198) (xy 371.356083 -271.955672) (xy 371.307228 -271.961604) (xy 371.258053 -271.959623)
			(xy 371.209834 -271.949779) (xy 371.163818 -271.932327) (xy 371.121197 -271.90772) (xy 371.083076 -271.876595)
			(xy 371.050441 -271.839758) (xy 371.024138 -271.798162) (xy 371.004847 -271.752886) (xy 370.99307 -271.705102)
			(xy 370.98911 -271.656048) (xy 370.660168 -271.656048) (xy 370.659673 -271.680655) (xy 370.651778 -271.729232)
			(xy 370.636194 -271.775913) (xy 370.613323 -271.81949) (xy 370.583758 -271.858834) (xy 370.548265 -271.892926)
			(xy 370.507762 -271.920882) (xy 370.4633 -271.94198) (xy 370.416029 -271.955672) (xy 370.367174 -271.961604)
			(xy 370.317999 -271.959623) (xy 370.26978 -271.949779) (xy 370.223764 -271.932327) (xy 370.181143 -271.90772)
			(xy 370.143022 -271.876595) (xy 370.110387 -271.839758) (xy 370.084084 -271.798162) (xy 370.064793 -271.752886)
			(xy 370.053016 -271.705102) (xy 370.049056 -271.656048) (xy 369.720114 -271.656048) (xy 369.719619 -271.680655)
			(xy 369.711724 -271.729232) (xy 369.69614 -271.775913) (xy 369.673269 -271.81949) (xy 369.643704 -271.858834)
			(xy 369.608211 -271.892926) (xy 369.567708 -271.920882) (xy 369.523246 -271.94198) (xy 369.475975 -271.955672)
			(xy 369.42712 -271.961604) (xy 369.377945 -271.959623) (xy 369.329726 -271.949779) (xy 369.28371 -271.932327)
			(xy 369.241089 -271.90772) (xy 369.202968 -271.876595) (xy 369.170333 -271.839758) (xy 369.14403 -271.798162)
			(xy 369.124739 -271.752886) (xy 369.112962 -271.705102) (xy 369.109002 -271.656048) (xy 368.78006 -271.656048)
			(xy 368.779565 -271.680655) (xy 368.77167 -271.729232) (xy 368.756086 -271.775913) (xy 368.733215 -271.81949)
			(xy 368.70365 -271.858834) (xy 368.668157 -271.892926) (xy 368.627654 -271.920882) (xy 368.583192 -271.94198)
			(xy 368.535921 -271.955672) (xy 368.487066 -271.961604) (xy 368.437891 -271.959623) (xy 368.389672 -271.949779)
			(xy 368.343656 -271.932327) (xy 368.301035 -271.90772) (xy 368.262914 -271.876595) (xy 368.230279 -271.839758)
			(xy 368.203976 -271.798162) (xy 368.184685 -271.752886) (xy 368.172908 -271.705102) (xy 368.168948 -271.656048)
			(xy 367.840006 -271.656048) (xy 367.839511 -271.680655) (xy 367.831616 -271.729232) (xy 367.816032 -271.775913)
			(xy 367.793161 -271.81949) (xy 367.763596 -271.858834) (xy 367.728103 -271.892926) (xy 367.6876 -271.920882)
			(xy 367.643138 -271.94198) (xy 367.595867 -271.955672) (xy 367.547012 -271.961604) (xy 367.497837 -271.959623)
			(xy 367.449618 -271.949779) (xy 367.403602 -271.932327) (xy 367.360981 -271.90772) (xy 367.32286 -271.876595)
			(xy 367.290225 -271.839758) (xy 367.263922 -271.798162) (xy 367.244631 -271.752886) (xy 367.232854 -271.705102)
			(xy 367.228894 -271.656048) (xy 366.900206 -271.656048) (xy 366.899711 -271.680655) (xy 366.891816 -271.729232)
			(xy 366.876232 -271.775913) (xy 366.853361 -271.81949) (xy 366.823796 -271.858834) (xy 366.788303 -271.892926)
			(xy 366.7478 -271.920882) (xy 366.703338 -271.94198) (xy 366.656067 -271.955672) (xy 366.607212 -271.961604)
			(xy 366.558037 -271.959623) (xy 366.509818 -271.949779) (xy 366.463802 -271.932327) (xy 366.421181 -271.90772)
			(xy 366.38306 -271.876595) (xy 366.350425 -271.839758) (xy 366.324122 -271.798162) (xy 366.304831 -271.752886)
			(xy 366.293054 -271.705102) (xy 366.289094 -271.656048) (xy 365.960152 -271.656048) (xy 365.959657 -271.680655)
			(xy 365.951762 -271.729232) (xy 365.936178 -271.775913) (xy 365.913307 -271.81949) (xy 365.883742 -271.858834)
			(xy 365.848249 -271.892926) (xy 365.807746 -271.920882) (xy 365.763284 -271.94198) (xy 365.716013 -271.955672)
			(xy 365.667158 -271.961604) (xy 365.617983 -271.959623) (xy 365.569764 -271.949779) (xy 365.523748 -271.932327)
			(xy 365.481127 -271.90772) (xy 365.443006 -271.876595) (xy 365.410371 -271.839758) (xy 365.384068 -271.798162)
			(xy 365.364777 -271.752886) (xy 365.353 -271.705102) (xy 365.34904 -271.656048) (xy 365.020098 -271.656048)
			(xy 365.019603 -271.680655) (xy 365.011708 -271.729232) (xy 364.996124 -271.775913) (xy 364.973253 -271.81949)
			(xy 364.943688 -271.858834) (xy 364.908195 -271.892926) (xy 364.867692 -271.920882) (xy 364.82323 -271.94198)
			(xy 364.775959 -271.955672) (xy 364.727104 -271.961604) (xy 364.677929 -271.959623) (xy 364.62971 -271.949779)
			(xy 364.583694 -271.932327) (xy 364.541073 -271.90772) (xy 364.502952 -271.876595) (xy 364.470317 -271.839758)
			(xy 364.444014 -271.798162) (xy 364.424723 -271.752886) (xy 364.412946 -271.705102) (xy 364.408986 -271.656048)
			(xy 364.080044 -271.656048) (xy 364.079549 -271.680655) (xy 364.071654 -271.729232) (xy 364.05607 -271.775913)
			(xy 364.033199 -271.81949) (xy 364.003634 -271.858834) (xy 363.968141 -271.892926) (xy 363.927638 -271.920882)
			(xy 363.883176 -271.94198) (xy 363.835905 -271.955672) (xy 363.78705 -271.961604) (xy 363.737875 -271.959623)
			(xy 363.689656 -271.949779) (xy 363.64364 -271.932327) (xy 363.601019 -271.90772) (xy 363.562898 -271.876595)
			(xy 363.530263 -271.839758) (xy 363.50396 -271.798162) (xy 363.484669 -271.752886) (xy 363.472892 -271.705102)
			(xy 363.468932 -271.656048) (xy 356.56647 -271.656048) (xy 356.565975 -271.680655) (xy 356.55808 -271.729232)
			(xy 356.542496 -271.775913) (xy 356.519625 -271.81949) (xy 356.49006 -271.858834) (xy 356.454567 -271.892926)
			(xy 356.414064 -271.920882) (xy 356.369602 -271.94198) (xy 356.322331 -271.955672) (xy 356.273476 -271.961604)
			(xy 356.224301 -271.959623) (xy 356.176082 -271.949779) (xy 356.130066 -271.932327) (xy 356.087445 -271.90772)
			(xy 356.049324 -271.876595) (xy 356.016689 -271.839758) (xy 355.990386 -271.798162) (xy 355.971095 -271.752886)
			(xy 355.959318 -271.705102) (xy 355.955358 -271.656048) (xy 355.626416 -271.656048) (xy 355.625921 -271.680655)
			(xy 355.618026 -271.729232) (xy 355.602442 -271.775913) (xy 355.579571 -271.81949) (xy 355.550006 -271.858834)
			(xy 355.514513 -271.892926) (xy 355.47401 -271.920882) (xy 355.429548 -271.94198) (xy 355.382277 -271.955672)
			(xy 355.333422 -271.961604) (xy 355.284247 -271.959623) (xy 355.236028 -271.949779) (xy 355.190012 -271.932327)
			(xy 355.147391 -271.90772) (xy 355.10927 -271.876595) (xy 355.076635 -271.839758) (xy 355.050332 -271.798162)
			(xy 355.031041 -271.752886) (xy 355.019264 -271.705102) (xy 355.015304 -271.656048) (xy 354.686362 -271.656048)
			(xy 354.685867 -271.680655) (xy 354.677972 -271.729232) (xy 354.662388 -271.775913) (xy 354.639517 -271.81949)
			(xy 354.609952 -271.858834) (xy 354.574459 -271.892926) (xy 354.533956 -271.920882) (xy 354.489494 -271.94198)
			(xy 354.442223 -271.955672) (xy 354.393368 -271.961604) (xy 354.344193 -271.959623) (xy 354.295974 -271.949779)
			(xy 354.249958 -271.932327) (xy 354.207337 -271.90772) (xy 354.169216 -271.876595) (xy 354.136581 -271.839758)
			(xy 354.110278 -271.798162) (xy 354.090987 -271.752886) (xy 354.07921 -271.705102) (xy 354.07525 -271.656048)
			(xy 353.746308 -271.656048) (xy 353.745813 -271.680655) (xy 353.737918 -271.729232) (xy 353.722334 -271.775913)
			(xy 353.699463 -271.81949) (xy 353.669898 -271.858834) (xy 353.634405 -271.892926) (xy 353.593902 -271.920882)
			(xy 353.54944 -271.94198) (xy 353.502169 -271.955672) (xy 353.453314 -271.961604) (xy 353.404139 -271.959623)
			(xy 353.35592 -271.949779) (xy 353.309904 -271.932327) (xy 353.267283 -271.90772) (xy 353.229162 -271.876595)
			(xy 353.196527 -271.839758) (xy 353.170224 -271.798162) (xy 353.150933 -271.752886) (xy 353.139156 -271.705102)
			(xy 353.135196 -271.656048) (xy 352.806508 -271.656048) (xy 352.806013 -271.680655) (xy 352.798118 -271.729232)
			(xy 352.782534 -271.775913) (xy 352.759663 -271.81949) (xy 352.730098 -271.858834) (xy 352.694605 -271.892926)
			(xy 352.654102 -271.920882) (xy 352.60964 -271.94198) (xy 352.562369 -271.955672) (xy 352.513514 -271.961604)
			(xy 352.464339 -271.959623) (xy 352.41612 -271.949779) (xy 352.370104 -271.932327) (xy 352.327483 -271.90772)
			(xy 352.289362 -271.876595) (xy 352.256727 -271.839758) (xy 352.230424 -271.798162) (xy 352.211133 -271.752886)
			(xy 352.199356 -271.705102) (xy 352.195396 -271.656048) (xy 351.866454 -271.656048) (xy 351.865959 -271.680655)
			(xy 351.858064 -271.729232) (xy 351.84248 -271.775913) (xy 351.819609 -271.81949) (xy 351.790044 -271.858834)
			(xy 351.754551 -271.892926) (xy 351.714048 -271.920882) (xy 351.669586 -271.94198) (xy 351.622315 -271.955672)
			(xy 351.57346 -271.961604) (xy 351.524285 -271.959623) (xy 351.476066 -271.949779) (xy 351.43005 -271.932327)
			(xy 351.387429 -271.90772) (xy 351.349308 -271.876595) (xy 351.316673 -271.839758) (xy 351.29037 -271.798162)
			(xy 351.271079 -271.752886) (xy 351.259302 -271.705102) (xy 351.255342 -271.656048) (xy 350.9264 -271.656048)
			(xy 350.925905 -271.680655) (xy 350.91801 -271.729232) (xy 350.902426 -271.775913) (xy 350.879555 -271.81949)
			(xy 350.84999 -271.858834) (xy 350.814497 -271.892926) (xy 350.773994 -271.920882) (xy 350.729532 -271.94198)
			(xy 350.682261 -271.955672) (xy 350.633406 -271.961604) (xy 350.584231 -271.959623) (xy 350.536012 -271.949779)
			(xy 350.489996 -271.932327) (xy 350.447375 -271.90772) (xy 350.409254 -271.876595) (xy 350.376619 -271.839758)
			(xy 350.350316 -271.798162) (xy 350.331025 -271.752886) (xy 350.319248 -271.705102) (xy 350.315288 -271.656048)
			(xy 349.986346 -271.656048) (xy 349.985851 -271.680655) (xy 349.977956 -271.729232) (xy 349.962372 -271.775913)
			(xy 349.939501 -271.81949) (xy 349.909936 -271.858834) (xy 349.874443 -271.892926) (xy 349.83394 -271.920882)
			(xy 349.789478 -271.94198) (xy 349.742207 -271.955672) (xy 349.693352 -271.961604) (xy 349.644177 -271.959623)
			(xy 349.595958 -271.949779) (xy 349.549942 -271.932327) (xy 349.507321 -271.90772) (xy 349.4692 -271.876595)
			(xy 349.436565 -271.839758) (xy 349.410262 -271.798162) (xy 349.390971 -271.752886) (xy 349.379194 -271.705102)
			(xy 349.375234 -271.656048) (xy 349.046546 -271.656048) (xy 349.046051 -271.680655) (xy 349.038156 -271.729232)
			(xy 349.022572 -271.775913) (xy 348.999701 -271.81949) (xy 348.970136 -271.858834) (xy 348.934643 -271.892926)
			(xy 348.89414 -271.920882) (xy 348.849678 -271.94198) (xy 348.802407 -271.955672) (xy 348.753552 -271.961604)
			(xy 348.704377 -271.959623) (xy 348.656158 -271.949779) (xy 348.610142 -271.932327) (xy 348.567521 -271.90772)
			(xy 348.5294 -271.876595) (xy 348.496765 -271.839758) (xy 348.470462 -271.798162) (xy 348.451171 -271.752886)
			(xy 348.439394 -271.705102) (xy 348.435434 -271.656048) (xy 348.106492 -271.656048) (xy 348.105997 -271.680655)
			(xy 348.098102 -271.729232) (xy 348.082518 -271.775913) (xy 348.059647 -271.81949) (xy 348.030082 -271.858834)
			(xy 347.994589 -271.892926) (xy 347.954086 -271.920882) (xy 347.909624 -271.94198) (xy 347.862353 -271.955672)
			(xy 347.813498 -271.961604) (xy 347.764323 -271.959623) (xy 347.716104 -271.949779) (xy 347.670088 -271.932327)
			(xy 347.627467 -271.90772) (xy 347.589346 -271.876595) (xy 347.556711 -271.839758) (xy 347.530408 -271.798162)
			(xy 347.511117 -271.752886) (xy 347.49934 -271.705102) (xy 347.49538 -271.656048) (xy 347.166438 -271.656048)
			(xy 347.165943 -271.680655) (xy 347.158048 -271.729232) (xy 347.142464 -271.775913) (xy 347.119593 -271.81949)
			(xy 347.090028 -271.858834) (xy 347.054535 -271.892926) (xy 347.014032 -271.920882) (xy 346.96957 -271.94198)
			(xy 346.922299 -271.955672) (xy 346.873444 -271.961604) (xy 346.824269 -271.959623) (xy 346.77605 -271.949779)
			(xy 346.730034 -271.932327) (xy 346.687413 -271.90772) (xy 346.649292 -271.876595) (xy 346.616657 -271.839758)
			(xy 346.590354 -271.798162) (xy 346.571063 -271.752886) (xy 346.559286 -271.705102) (xy 346.555326 -271.656048)
			(xy 346.226384 -271.656048) (xy 346.225889 -271.680655) (xy 346.217994 -271.729232) (xy 346.20241 -271.775913)
			(xy 346.179539 -271.81949) (xy 346.149974 -271.858834) (xy 346.114481 -271.892926) (xy 346.073978 -271.920882)
			(xy 346.029516 -271.94198) (xy 345.982245 -271.955672) (xy 345.93339 -271.961604) (xy 345.884215 -271.959623)
			(xy 345.835996 -271.949779) (xy 345.78998 -271.932327) (xy 345.747359 -271.90772) (xy 345.709238 -271.876595)
			(xy 345.676603 -271.839758) (xy 345.6503 -271.798162) (xy 345.631009 -271.752886) (xy 345.619232 -271.705102)
			(xy 345.615272 -271.656048) (xy 345.286779 -271.656048) (xy 345.282617 -271.706302) (xy 345.270234 -271.755233)
			(xy 345.24997 -271.80146) (xy 345.222377 -271.843724) (xy 345.188208 -271.880873) (xy 345.148394 -271.911896)
			(xy 345.104018 -271.935946) (xy 345.056291 -271.952369) (xy 345.006512 -271.960717) (xy 344.981276 -271.961356)
			(xy 344.971209 -271.961785) (xy 344.952616 -271.969512) (xy 344.945208 -271.976342) (xy 344.895424 -272.026126)
			(xy 344.888709 -272.033363) (xy 344.881115 -272.051569) (xy 344.880692 -272.061432) (xy 344.880692 -272.466054)
			(xy 347.025226 -272.466054) (xy 347.029186 -272.417) (xy 347.040963 -272.369216) (xy 347.060254 -272.32394)
			(xy 347.086557 -272.282344) (xy 347.119192 -272.245507) (xy 347.157313 -272.214382) (xy 347.199934 -272.189775)
			(xy 347.24595 -272.172323) (xy 347.294169 -272.162479) (xy 347.343344 -272.160498) (xy 347.392199 -272.16643)
			(xy 347.43947 -272.180122) (xy 347.483932 -272.20122) (xy 347.524435 -272.229176) (xy 347.559928 -272.263268)
			(xy 347.589493 -272.302612) (xy 347.612364 -272.346189) (xy 347.627948 -272.39287) (xy 347.635843 -272.441447)
			(xy 347.636338 -272.466054) (xy 349.845388 -272.466054) (xy 349.849348 -272.417) (xy 349.861125 -272.369216)
			(xy 349.880416 -272.32394) (xy 349.906719 -272.282344) (xy 349.939354 -272.245507) (xy 349.977475 -272.214382)
			(xy 350.020096 -272.189775) (xy 350.066112 -272.172323) (xy 350.114331 -272.162479) (xy 350.163506 -272.160498)
			(xy 350.212361 -272.16643) (xy 350.259632 -272.180122) (xy 350.304094 -272.20122) (xy 350.344597 -272.229176)
			(xy 350.38009 -272.263268) (xy 350.409655 -272.302612) (xy 350.432526 -272.346189) (xy 350.44811 -272.39287)
			(xy 350.456005 -272.441447) (xy 350.4565 -272.466054) (xy 352.665296 -272.466054) (xy 352.669256 -272.417)
			(xy 352.681033 -272.369216) (xy 352.700324 -272.32394) (xy 352.726627 -272.282344) (xy 352.759262 -272.245507)
			(xy 352.797383 -272.214382) (xy 352.840004 -272.189775) (xy 352.88602 -272.172323) (xy 352.934239 -272.162479)
			(xy 352.983414 -272.160498) (xy 353.032269 -272.16643) (xy 353.07954 -272.180122) (xy 353.124002 -272.20122)
			(xy 353.164505 -272.229176) (xy 353.199998 -272.263268) (xy 353.229563 -272.302612) (xy 353.252434 -272.346189)
			(xy 353.268018 -272.39287) (xy 353.275913 -272.441447) (xy 353.276408 -272.466054) (xy 355.485204 -272.466054)
			(xy 355.489164 -272.417) (xy 355.500941 -272.369216) (xy 355.520232 -272.32394) (xy 355.546535 -272.282344)
			(xy 355.57917 -272.245507) (xy 355.617291 -272.214382) (xy 355.659912 -272.189775) (xy 355.705928 -272.172323)
			(xy 355.754147 -272.162479) (xy 355.803322 -272.160498) (xy 355.852177 -272.16643) (xy 355.899448 -272.180122)
			(xy 355.94391 -272.20122) (xy 355.984413 -272.229176) (xy 356.019906 -272.263268) (xy 356.049471 -272.302612)
			(xy 356.072342 -272.346189) (xy 356.087926 -272.39287) (xy 356.095821 -272.441447) (xy 356.096316 -272.466054)
			(xy 356.425258 -272.466054) (xy 356.429218 -272.417) (xy 356.440995 -272.369216) (xy 356.460286 -272.32394)
			(xy 356.486589 -272.282344) (xy 356.519224 -272.245507) (xy 356.557345 -272.214382) (xy 356.599966 -272.189775)
			(xy 356.645982 -272.172323) (xy 356.694201 -272.162479) (xy 356.743376 -272.160498) (xy 356.792231 -272.16643)
			(xy 356.839502 -272.180122) (xy 356.883964 -272.20122) (xy 356.924467 -272.229176) (xy 356.95996 -272.263268)
			(xy 356.989525 -272.302612) (xy 357.012396 -272.346189) (xy 357.02798 -272.39287) (xy 357.035875 -272.441447)
			(xy 357.03637 -272.466054) (xy 357.365312 -272.466054) (xy 357.369272 -272.417) (xy 357.381049 -272.369216)
			(xy 357.40034 -272.32394) (xy 357.426643 -272.282344) (xy 357.459278 -272.245507) (xy 357.497399 -272.214382)
			(xy 357.54002 -272.189775) (xy 357.586036 -272.172323) (xy 357.634255 -272.162479) (xy 357.68343 -272.160498)
			(xy 357.732285 -272.16643) (xy 357.779556 -272.180122) (xy 357.824018 -272.20122) (xy 357.864521 -272.229176)
			(xy 357.900014 -272.263268) (xy 357.929579 -272.302612) (xy 357.95245 -272.346189) (xy 357.968034 -272.39287)
			(xy 357.975929 -272.441447) (xy 357.976424 -272.466054) (xy 358.305366 -272.466054) (xy 358.309326 -272.417)
			(xy 358.321103 -272.369216) (xy 358.340394 -272.32394) (xy 358.366697 -272.282344) (xy 358.399332 -272.245507)
			(xy 358.437453 -272.214382) (xy 358.480074 -272.189775) (xy 358.52609 -272.172323) (xy 358.574309 -272.162479)
			(xy 358.623484 -272.160498) (xy 358.672339 -272.16643) (xy 358.71961 -272.180122) (xy 358.764072 -272.20122)
			(xy 358.804575 -272.229176) (xy 358.840068 -272.263268) (xy 358.869633 -272.302612) (xy 358.892504 -272.346189)
			(xy 358.908088 -272.39287) (xy 358.915983 -272.441447) (xy 358.916478 -272.466054) (xy 361.118924 -272.466054)
			(xy 361.122884 -272.417) (xy 361.134661 -272.369216) (xy 361.153952 -272.32394) (xy 361.180255 -272.282344)
			(xy 361.21289 -272.245507) (xy 361.251011 -272.214382) (xy 361.293632 -272.189775) (xy 361.339648 -272.172323)
			(xy 361.387867 -272.162479) (xy 361.437042 -272.160498) (xy 361.485897 -272.16643) (xy 361.533168 -272.180122)
			(xy 361.57763 -272.20122) (xy 361.618133 -272.229176) (xy 361.653626 -272.263268) (xy 361.683191 -272.302612)
			(xy 361.706062 -272.346189) (xy 361.721646 -272.39287) (xy 361.729541 -272.441447) (xy 361.730036 -272.466054)
			(xy 362.058978 -272.466054) (xy 362.062938 -272.417) (xy 362.074715 -272.369216) (xy 362.094006 -272.32394)
			(xy 362.120309 -272.282344) (xy 362.152944 -272.245507) (xy 362.191065 -272.214382) (xy 362.233686 -272.189775)
			(xy 362.279702 -272.172323) (xy 362.327921 -272.162479) (xy 362.377096 -272.160498) (xy 362.425951 -272.16643)
			(xy 362.473222 -272.180122) (xy 362.517684 -272.20122) (xy 362.558187 -272.229176) (xy 362.59368 -272.263268)
			(xy 362.623245 -272.302612) (xy 362.646116 -272.346189) (xy 362.6617 -272.39287) (xy 362.669595 -272.441447)
			(xy 362.67009 -272.466054) (xy 362.999032 -272.466054) (xy 363.002992 -272.417) (xy 363.014769 -272.369216)
			(xy 363.03406 -272.32394) (xy 363.060363 -272.282344) (xy 363.092998 -272.245507) (xy 363.131119 -272.214382)
			(xy 363.17374 -272.189775) (xy 363.219756 -272.172323) (xy 363.267975 -272.162479) (xy 363.31715 -272.160498)
			(xy 363.366005 -272.16643) (xy 363.413276 -272.180122) (xy 363.457738 -272.20122) (xy 363.498241 -272.229176)
			(xy 363.533734 -272.263268) (xy 363.563299 -272.302612) (xy 363.58617 -272.346189) (xy 363.601754 -272.39287)
			(xy 363.609649 -272.441447) (xy 363.610144 -272.466054) (xy 363.939086 -272.466054) (xy 363.943046 -272.417)
			(xy 363.954823 -272.369216) (xy 363.974114 -272.32394) (xy 364.000417 -272.282344) (xy 364.033052 -272.245507)
			(xy 364.071173 -272.214382) (xy 364.113794 -272.189775) (xy 364.15981 -272.172323) (xy 364.208029 -272.162479)
			(xy 364.257204 -272.160498) (xy 364.306059 -272.16643) (xy 364.35333 -272.180122) (xy 364.397792 -272.20122)
			(xy 364.438295 -272.229176) (xy 364.473788 -272.263268) (xy 364.503353 -272.302612) (xy 364.526224 -272.346189)
			(xy 364.541808 -272.39287) (xy 364.549703 -272.441447) (xy 364.550198 -272.466054) (xy 366.758994 -272.466054)
			(xy 366.762954 -272.417) (xy 366.774731 -272.369216) (xy 366.794022 -272.32394) (xy 366.820325 -272.282344)
			(xy 366.85296 -272.245507) (xy 366.891081 -272.214382) (xy 366.933702 -272.189775) (xy 366.979718 -272.172323)
			(xy 367.027937 -272.162479) (xy 367.077112 -272.160498) (xy 367.125967 -272.16643) (xy 367.173238 -272.180122)
			(xy 367.2177 -272.20122) (xy 367.258203 -272.229176) (xy 367.293696 -272.263268) (xy 367.323261 -272.302612)
			(xy 367.346132 -272.346189) (xy 367.361716 -272.39287) (xy 367.369611 -272.441447) (xy 367.370106 -272.466054)
			(xy 369.578902 -272.466054) (xy 369.582862 -272.417) (xy 369.594639 -272.369216) (xy 369.61393 -272.32394)
			(xy 369.640233 -272.282344) (xy 369.672868 -272.245507) (xy 369.710989 -272.214382) (xy 369.75361 -272.189775)
			(xy 369.799626 -272.172323) (xy 369.847845 -272.162479) (xy 369.89702 -272.160498) (xy 369.945875 -272.16643)
			(xy 369.993146 -272.180122) (xy 370.037608 -272.20122) (xy 370.078111 -272.229176) (xy 370.113604 -272.263268)
			(xy 370.143169 -272.302612) (xy 370.16604 -272.346189) (xy 370.181624 -272.39287) (xy 370.189519 -272.441447)
			(xy 370.190014 -272.466054) (xy 372.399064 -272.466054) (xy 372.403024 -272.417) (xy 372.414801 -272.369216)
			(xy 372.434092 -272.32394) (xy 372.460395 -272.282344) (xy 372.49303 -272.245507) (xy 372.531151 -272.214382)
			(xy 372.573772 -272.189775) (xy 372.619788 -272.172323) (xy 372.668007 -272.162479) (xy 372.717182 -272.160498)
			(xy 372.766037 -272.16643) (xy 372.813308 -272.180122) (xy 372.85777 -272.20122) (xy 372.898273 -272.229176)
			(xy 372.933766 -272.263268) (xy 372.963331 -272.302612) (xy 372.986202 -272.346189) (xy 373.001786 -272.39287)
			(xy 373.009681 -272.441447) (xy 373.010176 -272.466054) (xy 373.009681 -272.490661) (xy 373.001786 -272.539238)
			(xy 372.986202 -272.585919) (xy 372.963331 -272.629496) (xy 372.933766 -272.66884) (xy 372.898273 -272.702932)
			(xy 372.85777 -272.730888) (xy 372.813308 -272.751986) (xy 372.766037 -272.765678) (xy 372.717182 -272.77161)
			(xy 372.668007 -272.769629) (xy 372.619788 -272.759785) (xy 372.573772 -272.742333) (xy 372.531151 -272.717726)
			(xy 372.49303 -272.686601) (xy 372.460395 -272.649764) (xy 372.434092 -272.608168) (xy 372.414801 -272.562892)
			(xy 372.403024 -272.515108) (xy 372.399064 -272.466054) (xy 370.190014 -272.466054) (xy 370.189519 -272.490661)
			(xy 370.181624 -272.539238) (xy 370.16604 -272.585919) (xy 370.143169 -272.629496) (xy 370.113604 -272.66884)
			(xy 370.078111 -272.702932) (xy 370.037608 -272.730888) (xy 369.993146 -272.751986) (xy 369.945875 -272.765678)
			(xy 369.89702 -272.77161) (xy 369.847845 -272.769629) (xy 369.799626 -272.759785) (xy 369.75361 -272.742333)
			(xy 369.710989 -272.717726) (xy 369.672868 -272.686601) (xy 369.640233 -272.649764) (xy 369.61393 -272.608168)
			(xy 369.594639 -272.562892) (xy 369.582862 -272.515108) (xy 369.578902 -272.466054) (xy 367.370106 -272.466054)
			(xy 367.369611 -272.490661) (xy 367.361716 -272.539238) (xy 367.346132 -272.585919) (xy 367.323261 -272.629496)
			(xy 367.293696 -272.66884) (xy 367.258203 -272.702932) (xy 367.2177 -272.730888) (xy 367.173238 -272.751986)
			(xy 367.125967 -272.765678) (xy 367.077112 -272.77161) (xy 367.027937 -272.769629) (xy 366.979718 -272.759785)
			(xy 366.933702 -272.742333) (xy 366.891081 -272.717726) (xy 366.85296 -272.686601) (xy 366.820325 -272.649764)
			(xy 366.794022 -272.608168) (xy 366.774731 -272.562892) (xy 366.762954 -272.515108) (xy 366.758994 -272.466054)
			(xy 364.550198 -272.466054) (xy 364.549703 -272.490661) (xy 364.541808 -272.539238) (xy 364.526224 -272.585919)
			(xy 364.503353 -272.629496) (xy 364.473788 -272.66884) (xy 364.438295 -272.702932) (xy 364.397792 -272.730888)
			(xy 364.35333 -272.751986) (xy 364.306059 -272.765678) (xy 364.257204 -272.77161) (xy 364.208029 -272.769629)
			(xy 364.15981 -272.759785) (xy 364.113794 -272.742333) (xy 364.071173 -272.717726) (xy 364.033052 -272.686601)
			(xy 364.000417 -272.649764) (xy 363.974114 -272.608168) (xy 363.954823 -272.562892) (xy 363.943046 -272.515108)
			(xy 363.939086 -272.466054) (xy 363.610144 -272.466054) (xy 363.609649 -272.490661) (xy 363.601754 -272.539238)
			(xy 363.58617 -272.585919) (xy 363.563299 -272.629496) (xy 363.533734 -272.66884) (xy 363.498241 -272.702932)
			(xy 363.457738 -272.730888) (xy 363.413276 -272.751986) (xy 363.366005 -272.765678) (xy 363.31715 -272.77161)
			(xy 363.267975 -272.769629) (xy 363.219756 -272.759785) (xy 363.17374 -272.742333) (xy 363.131119 -272.717726)
			(xy 363.092998 -272.686601) (xy 363.060363 -272.649764) (xy 363.03406 -272.608168) (xy 363.014769 -272.562892)
			(xy 363.002992 -272.515108) (xy 362.999032 -272.466054) (xy 362.67009 -272.466054) (xy 362.669595 -272.490661)
			(xy 362.6617 -272.539238) (xy 362.646116 -272.585919) (xy 362.623245 -272.629496) (xy 362.59368 -272.66884)
			(xy 362.558187 -272.702932) (xy 362.517684 -272.730888) (xy 362.473222 -272.751986) (xy 362.425951 -272.765678)
			(xy 362.377096 -272.77161) (xy 362.327921 -272.769629) (xy 362.279702 -272.759785) (xy 362.233686 -272.742333)
			(xy 362.191065 -272.717726) (xy 362.152944 -272.686601) (xy 362.120309 -272.649764) (xy 362.094006 -272.608168)
			(xy 362.074715 -272.562892) (xy 362.062938 -272.515108) (xy 362.058978 -272.466054) (xy 361.730036 -272.466054)
			(xy 361.729541 -272.490661) (xy 361.721646 -272.539238) (xy 361.706062 -272.585919) (xy 361.683191 -272.629496)
			(xy 361.653626 -272.66884) (xy 361.618133 -272.702932) (xy 361.57763 -272.730888) (xy 361.533168 -272.751986)
			(xy 361.485897 -272.765678) (xy 361.437042 -272.77161) (xy 361.387867 -272.769629) (xy 361.339648 -272.759785)
			(xy 361.293632 -272.742333) (xy 361.251011 -272.717726) (xy 361.21289 -272.686601) (xy 361.180255 -272.649764)
			(xy 361.153952 -272.608168) (xy 361.134661 -272.562892) (xy 361.122884 -272.515108) (xy 361.118924 -272.466054)
			(xy 358.916478 -272.466054) (xy 358.915983 -272.490661) (xy 358.908088 -272.539238) (xy 358.892504 -272.585919)
			(xy 358.869633 -272.629496) (xy 358.840068 -272.66884) (xy 358.804575 -272.702932) (xy 358.764072 -272.730888)
			(xy 358.71961 -272.751986) (xy 358.672339 -272.765678) (xy 358.623484 -272.77161) (xy 358.574309 -272.769629)
			(xy 358.52609 -272.759785) (xy 358.480074 -272.742333) (xy 358.437453 -272.717726) (xy 358.399332 -272.686601)
			(xy 358.366697 -272.649764) (xy 358.340394 -272.608168) (xy 358.321103 -272.562892) (xy 358.309326 -272.515108)
			(xy 358.305366 -272.466054) (xy 357.976424 -272.466054) (xy 357.975929 -272.490661) (xy 357.968034 -272.539238)
			(xy 357.95245 -272.585919) (xy 357.929579 -272.629496) (xy 357.900014 -272.66884) (xy 357.864521 -272.702932)
			(xy 357.824018 -272.730888) (xy 357.779556 -272.751986) (xy 357.732285 -272.765678) (xy 357.68343 -272.77161)
			(xy 357.634255 -272.769629) (xy 357.586036 -272.759785) (xy 357.54002 -272.742333) (xy 357.497399 -272.717726)
			(xy 357.459278 -272.686601) (xy 357.426643 -272.649764) (xy 357.40034 -272.608168) (xy 357.381049 -272.562892)
			(xy 357.369272 -272.515108) (xy 357.365312 -272.466054) (xy 357.03637 -272.466054) (xy 357.035875 -272.490661)
			(xy 357.02798 -272.539238) (xy 357.012396 -272.585919) (xy 356.989525 -272.629496) (xy 356.95996 -272.66884)
			(xy 356.924467 -272.702932) (xy 356.883964 -272.730888) (xy 356.839502 -272.751986) (xy 356.792231 -272.765678)
			(xy 356.743376 -272.77161) (xy 356.694201 -272.769629) (xy 356.645982 -272.759785) (xy 356.599966 -272.742333)
			(xy 356.557345 -272.717726) (xy 356.519224 -272.686601) (xy 356.486589 -272.649764) (xy 356.460286 -272.608168)
			(xy 356.440995 -272.562892) (xy 356.429218 -272.515108) (xy 356.425258 -272.466054) (xy 356.096316 -272.466054)
			(xy 356.095821 -272.490661) (xy 356.087926 -272.539238) (xy 356.072342 -272.585919) (xy 356.049471 -272.629496)
			(xy 356.019906 -272.66884) (xy 355.984413 -272.702932) (xy 355.94391 -272.730888) (xy 355.899448 -272.751986)
			(xy 355.852177 -272.765678) (xy 355.803322 -272.77161) (xy 355.754147 -272.769629) (xy 355.705928 -272.759785)
			(xy 355.659912 -272.742333) (xy 355.617291 -272.717726) (xy 355.57917 -272.686601) (xy 355.546535 -272.649764)
			(xy 355.520232 -272.608168) (xy 355.500941 -272.562892) (xy 355.489164 -272.515108) (xy 355.485204 -272.466054)
			(xy 353.276408 -272.466054) (xy 353.275913 -272.490661) (xy 353.268018 -272.539238) (xy 353.252434 -272.585919)
			(xy 353.229563 -272.629496) (xy 353.199998 -272.66884) (xy 353.164505 -272.702932) (xy 353.124002 -272.730888)
			(xy 353.07954 -272.751986) (xy 353.032269 -272.765678) (xy 352.983414 -272.77161) (xy 352.934239 -272.769629)
			(xy 352.88602 -272.759785) (xy 352.840004 -272.742333) (xy 352.797383 -272.717726) (xy 352.759262 -272.686601)
			(xy 352.726627 -272.649764) (xy 352.700324 -272.608168) (xy 352.681033 -272.562892) (xy 352.669256 -272.515108)
			(xy 352.665296 -272.466054) (xy 350.4565 -272.466054) (xy 350.456005 -272.490661) (xy 350.44811 -272.539238)
			(xy 350.432526 -272.585919) (xy 350.409655 -272.629496) (xy 350.38009 -272.66884) (xy 350.344597 -272.702932)
			(xy 350.304094 -272.730888) (xy 350.259632 -272.751986) (xy 350.212361 -272.765678) (xy 350.163506 -272.77161)
			(xy 350.114331 -272.769629) (xy 350.066112 -272.759785) (xy 350.020096 -272.742333) (xy 349.977475 -272.717726)
			(xy 349.939354 -272.686601) (xy 349.906719 -272.649764) (xy 349.880416 -272.608168) (xy 349.861125 -272.562892)
			(xy 349.849348 -272.515108) (xy 349.845388 -272.466054) (xy 347.636338 -272.466054) (xy 347.635843 -272.490661)
			(xy 347.627948 -272.539238) (xy 347.612364 -272.585919) (xy 347.589493 -272.629496) (xy 347.559928 -272.66884)
			(xy 347.524435 -272.702932) (xy 347.483932 -272.730888) (xy 347.43947 -272.751986) (xy 347.392199 -272.765678)
			(xy 347.343344 -272.77161) (xy 347.294169 -272.769629) (xy 347.24595 -272.759785) (xy 347.199934 -272.742333)
			(xy 347.157313 -272.717726) (xy 347.119192 -272.686601) (xy 347.086557 -272.649764) (xy 347.060254 -272.608168)
			(xy 347.040963 -272.562892) (xy 347.029186 -272.515108) (xy 347.025226 -272.466054) (xy 344.880692 -272.466054)
			(xy 344.880692 -272.870168) (xy 344.881161 -272.880041) (xy 344.888616 -272.898328) (xy 344.89517 -272.905728)
			(xy 344.895424 -272.905982) (xy 344.945208 -272.955766) (xy 344.952605 -272.962615) (xy 344.971204 -272.970352)
			(xy 344.981276 -272.970752) (xy 345.00652 -272.971295) (xy 345.056313 -272.979646) (xy 345.104054 -272.996073)
			(xy 345.148442 -273.02013) (xy 345.188268 -273.051162) (xy 345.222447 -273.088322) (xy 345.250047 -273.130598)
			(xy 345.270317 -273.176839) (xy 345.282704 -273.225784) (xy 345.286868 -273.27606) (xy 345.615272 -273.27606)
			(xy 345.619232 -273.227006) (xy 345.631009 -273.179222) (xy 345.6503 -273.133946) (xy 345.676603 -273.09235)
			(xy 345.709238 -273.055513) (xy 345.747359 -273.024388) (xy 345.78998 -272.999781) (xy 345.835996 -272.982329)
			(xy 345.884215 -272.972485) (xy 345.93339 -272.970504) (xy 345.982245 -272.976436) (xy 346.029516 -272.990128)
			(xy 346.073978 -273.011226) (xy 346.114481 -273.039182) (xy 346.149974 -273.073274) (xy 346.179539 -273.112618)
			(xy 346.20241 -273.156195) (xy 346.217994 -273.202876) (xy 346.225889 -273.251453) (xy 346.226384 -273.27606)
			(xy 346.555326 -273.27606) (xy 346.559286 -273.227006) (xy 346.571063 -273.179222) (xy 346.590354 -273.133946)
			(xy 346.616657 -273.09235) (xy 346.649292 -273.055513) (xy 346.687413 -273.024388) (xy 346.730034 -272.999781)
			(xy 346.77605 -272.982329) (xy 346.824269 -272.972485) (xy 346.873444 -272.970504) (xy 346.922299 -272.976436)
			(xy 346.96957 -272.990128) (xy 347.014032 -273.011226) (xy 347.054535 -273.039182) (xy 347.090028 -273.073274)
			(xy 347.119593 -273.112618) (xy 347.142464 -273.156195) (xy 347.158048 -273.202876) (xy 347.165943 -273.251453)
			(xy 347.166438 -273.27606) (xy 347.49538 -273.27606) (xy 347.49934 -273.227006) (xy 347.511117 -273.179222)
			(xy 347.530408 -273.133946) (xy 347.556711 -273.09235) (xy 347.589346 -273.055513) (xy 347.627467 -273.024388)
			(xy 347.670088 -272.999781) (xy 347.716104 -272.982329) (xy 347.764323 -272.972485) (xy 347.813498 -272.970504)
			(xy 347.862353 -272.976436) (xy 347.909624 -272.990128) (xy 347.954086 -273.011226) (xy 347.994589 -273.039182)
			(xy 348.030082 -273.073274) (xy 348.059647 -273.112618) (xy 348.082518 -273.156195) (xy 348.098102 -273.202876)
			(xy 348.105997 -273.251453) (xy 348.106492 -273.27606) (xy 348.435434 -273.27606) (xy 348.439394 -273.227006)
			(xy 348.451171 -273.179222) (xy 348.470462 -273.133946) (xy 348.496765 -273.09235) (xy 348.5294 -273.055513)
			(xy 348.567521 -273.024388) (xy 348.610142 -272.999781) (xy 348.656158 -272.982329) (xy 348.704377 -272.972485)
			(xy 348.753552 -272.970504) (xy 348.802407 -272.976436) (xy 348.849678 -272.990128) (xy 348.89414 -273.011226)
			(xy 348.934643 -273.039182) (xy 348.970136 -273.073274) (xy 348.999701 -273.112618) (xy 349.022572 -273.156195)
			(xy 349.038156 -273.202876) (xy 349.046051 -273.251453) (xy 349.046546 -273.27606) (xy 349.375234 -273.27606)
			(xy 349.379194 -273.227006) (xy 349.390971 -273.179222) (xy 349.410262 -273.133946) (xy 349.436565 -273.09235)
			(xy 349.4692 -273.055513) (xy 349.507321 -273.024388) (xy 349.549942 -272.999781) (xy 349.595958 -272.982329)
			(xy 349.644177 -272.972485) (xy 349.693352 -272.970504) (xy 349.742207 -272.976436) (xy 349.789478 -272.990128)
			(xy 349.83394 -273.011226) (xy 349.874443 -273.039182) (xy 349.909936 -273.073274) (xy 349.939501 -273.112618)
			(xy 349.962372 -273.156195) (xy 349.977956 -273.202876) (xy 349.985851 -273.251453) (xy 349.986346 -273.27606)
			(xy 350.315288 -273.27606) (xy 350.319248 -273.227006) (xy 350.331025 -273.179222) (xy 350.350316 -273.133946)
			(xy 350.376619 -273.09235) (xy 350.409254 -273.055513) (xy 350.447375 -273.024388) (xy 350.489996 -272.999781)
			(xy 350.536012 -272.982329) (xy 350.584231 -272.972485) (xy 350.633406 -272.970504) (xy 350.682261 -272.976436)
			(xy 350.729532 -272.990128) (xy 350.773994 -273.011226) (xy 350.814497 -273.039182) (xy 350.84999 -273.073274)
			(xy 350.879555 -273.112618) (xy 350.902426 -273.156195) (xy 350.91801 -273.202876) (xy 350.925905 -273.251453)
			(xy 350.9264 -273.27606) (xy 351.255342 -273.27606) (xy 351.259302 -273.227006) (xy 351.271079 -273.179222)
			(xy 351.29037 -273.133946) (xy 351.316673 -273.09235) (xy 351.349308 -273.055513) (xy 351.387429 -273.024388)
			(xy 351.43005 -272.999781) (xy 351.476066 -272.982329) (xy 351.524285 -272.972485) (xy 351.57346 -272.970504)
			(xy 351.622315 -272.976436) (xy 351.669586 -272.990128) (xy 351.714048 -273.011226) (xy 351.754551 -273.039182)
			(xy 351.790044 -273.073274) (xy 351.819609 -273.112618) (xy 351.84248 -273.156195) (xy 351.858064 -273.202876)
			(xy 351.865959 -273.251453) (xy 351.866454 -273.27606) (xy 352.195396 -273.27606) (xy 352.199356 -273.227006)
			(xy 352.211133 -273.179222) (xy 352.230424 -273.133946) (xy 352.256727 -273.09235) (xy 352.289362 -273.055513)
			(xy 352.327483 -273.024388) (xy 352.370104 -272.999781) (xy 352.41612 -272.982329) (xy 352.464339 -272.972485)
			(xy 352.513514 -272.970504) (xy 352.562369 -272.976436) (xy 352.60964 -272.990128) (xy 352.654102 -273.011226)
			(xy 352.694605 -273.039182) (xy 352.730098 -273.073274) (xy 352.759663 -273.112618) (xy 352.782534 -273.156195)
			(xy 352.798118 -273.202876) (xy 352.806013 -273.251453) (xy 352.806508 -273.27606) (xy 353.135196 -273.27606)
			(xy 353.139156 -273.227006) (xy 353.150933 -273.179222) (xy 353.170224 -273.133946) (xy 353.196527 -273.09235)
			(xy 353.229162 -273.055513) (xy 353.267283 -273.024388) (xy 353.309904 -272.999781) (xy 353.35592 -272.982329)
			(xy 353.404139 -272.972485) (xy 353.453314 -272.970504) (xy 353.502169 -272.976436) (xy 353.54944 -272.990128)
			(xy 353.593902 -273.011226) (xy 353.634405 -273.039182) (xy 353.669898 -273.073274) (xy 353.699463 -273.112618)
			(xy 353.722334 -273.156195) (xy 353.737918 -273.202876) (xy 353.745813 -273.251453) (xy 353.746308 -273.27606)
			(xy 354.07525 -273.27606) (xy 354.07921 -273.227006) (xy 354.090987 -273.179222) (xy 354.110278 -273.133946)
			(xy 354.136581 -273.09235) (xy 354.169216 -273.055513) (xy 354.207337 -273.024388) (xy 354.249958 -272.999781)
			(xy 354.295974 -272.982329) (xy 354.344193 -272.972485) (xy 354.393368 -272.970504) (xy 354.442223 -272.976436)
			(xy 354.489494 -272.990128) (xy 354.533956 -273.011226) (xy 354.574459 -273.039182) (xy 354.609952 -273.073274)
			(xy 354.639517 -273.112618) (xy 354.662388 -273.156195) (xy 354.677972 -273.202876) (xy 354.685867 -273.251453)
			(xy 354.686362 -273.27606) (xy 355.015304 -273.27606) (xy 355.019264 -273.227006) (xy 355.031041 -273.179222)
			(xy 355.050332 -273.133946) (xy 355.076635 -273.09235) (xy 355.10927 -273.055513) (xy 355.147391 -273.024388)
			(xy 355.190012 -272.999781) (xy 355.236028 -272.982329) (xy 355.284247 -272.972485) (xy 355.333422 -272.970504)
			(xy 355.382277 -272.976436) (xy 355.429548 -272.990128) (xy 355.47401 -273.011226) (xy 355.514513 -273.039182)
			(xy 355.550006 -273.073274) (xy 355.579571 -273.112618) (xy 355.602442 -273.156195) (xy 355.618026 -273.202876)
			(xy 355.625921 -273.251453) (xy 355.626416 -273.27606) (xy 355.955358 -273.27606) (xy 355.959318 -273.227006)
			(xy 355.971095 -273.179222) (xy 355.990386 -273.133946) (xy 356.016689 -273.09235) (xy 356.049324 -273.055513)
			(xy 356.087445 -273.024388) (xy 356.130066 -272.999781) (xy 356.176082 -272.982329) (xy 356.224301 -272.972485)
			(xy 356.273476 -272.970504) (xy 356.322331 -272.976436) (xy 356.369602 -272.990128) (xy 356.414064 -273.011226)
			(xy 356.454567 -273.039182) (xy 356.49006 -273.073274) (xy 356.519625 -273.112618) (xy 356.542496 -273.156195)
			(xy 356.55808 -273.202876) (xy 356.565975 -273.251453) (xy 356.56647 -273.27606) (xy 356.895412 -273.27606)
			(xy 356.899372 -273.227006) (xy 356.911149 -273.179222) (xy 356.93044 -273.133946) (xy 356.956743 -273.09235)
			(xy 356.989378 -273.055513) (xy 357.027499 -273.024388) (xy 357.07012 -272.999781) (xy 357.116136 -272.982329)
			(xy 357.164355 -272.972485) (xy 357.21353 -272.970504) (xy 357.262385 -272.976436) (xy 357.309656 -272.990128)
			(xy 357.354118 -273.011226) (xy 357.394621 -273.039182) (xy 357.430114 -273.073274) (xy 357.459679 -273.112618)
			(xy 357.48255 -273.156195) (xy 357.498134 -273.202876) (xy 357.506029 -273.251453) (xy 357.506524 -273.27606)
			(xy 357.835212 -273.27606) (xy 357.839172 -273.227006) (xy 357.850949 -273.179222) (xy 357.87024 -273.133946)
			(xy 357.896543 -273.09235) (xy 357.929178 -273.055513) (xy 357.967299 -273.024388) (xy 358.00992 -272.999781)
			(xy 358.055936 -272.982329) (xy 358.104155 -272.972485) (xy 358.15333 -272.970504) (xy 358.202185 -272.976436)
			(xy 358.249456 -272.990128) (xy 358.293918 -273.011226) (xy 358.334421 -273.039182) (xy 358.369914 -273.073274)
			(xy 358.399479 -273.112618) (xy 358.42235 -273.156195) (xy 358.437934 -273.202876) (xy 358.445829 -273.251453)
			(xy 358.446324 -273.27606) (xy 361.589078 -273.27606) (xy 361.593038 -273.227006) (xy 361.604815 -273.179222)
			(xy 361.624106 -273.133946) (xy 361.650409 -273.09235) (xy 361.683044 -273.055513) (xy 361.721165 -273.024388)
			(xy 361.763786 -272.999781) (xy 361.809802 -272.982329) (xy 361.858021 -272.972485) (xy 361.907196 -272.970504)
			(xy 361.956051 -272.976436) (xy 362.003322 -272.990128) (xy 362.047784 -273.011226) (xy 362.088287 -273.039182)
			(xy 362.12378 -273.073274) (xy 362.153345 -273.112618) (xy 362.176216 -273.156195) (xy 362.1918 -273.202876)
			(xy 362.199695 -273.251453) (xy 362.20019 -273.27606) (xy 362.528878 -273.27606) (xy 362.532838 -273.227006)
			(xy 362.544615 -273.179222) (xy 362.563906 -273.133946) (xy 362.590209 -273.09235) (xy 362.622844 -273.055513)
			(xy 362.660965 -273.024388) (xy 362.703586 -272.999781) (xy 362.749602 -272.982329) (xy 362.797821 -272.972485)
			(xy 362.846996 -272.970504) (xy 362.895851 -272.976436) (xy 362.943122 -272.990128) (xy 362.987584 -273.011226)
			(xy 363.028087 -273.039182) (xy 363.06358 -273.073274) (xy 363.093145 -273.112618) (xy 363.116016 -273.156195)
			(xy 363.1316 -273.202876) (xy 363.139495 -273.251453) (xy 363.13999 -273.27606) (xy 363.468932 -273.27606)
			(xy 363.472892 -273.227006) (xy 363.484669 -273.179222) (xy 363.50396 -273.133946) (xy 363.530263 -273.09235)
			(xy 363.562898 -273.055513) (xy 363.601019 -273.024388) (xy 363.64364 -272.999781) (xy 363.689656 -272.982329)
			(xy 363.737875 -272.972485) (xy 363.78705 -272.970504) (xy 363.835905 -272.976436) (xy 363.883176 -272.990128)
			(xy 363.927638 -273.011226) (xy 363.968141 -273.039182) (xy 364.003634 -273.073274) (xy 364.033199 -273.112618)
			(xy 364.05607 -273.156195) (xy 364.071654 -273.202876) (xy 364.079549 -273.251453) (xy 364.080044 -273.27606)
			(xy 364.408986 -273.27606) (xy 364.412946 -273.227006) (xy 364.424723 -273.179222) (xy 364.444014 -273.133946)
			(xy 364.470317 -273.09235) (xy 364.502952 -273.055513) (xy 364.541073 -273.024388) (xy 364.583694 -272.999781)
			(xy 364.62971 -272.982329) (xy 364.677929 -272.972485) (xy 364.727104 -272.970504) (xy 364.775959 -272.976436)
			(xy 364.82323 -272.990128) (xy 364.867692 -273.011226) (xy 364.908195 -273.039182) (xy 364.943688 -273.073274)
			(xy 364.973253 -273.112618) (xy 364.996124 -273.156195) (xy 365.011708 -273.202876) (xy 365.019603 -273.251453)
			(xy 365.020098 -273.27606) (xy 365.34904 -273.27606) (xy 365.353 -273.227006) (xy 365.364777 -273.179222)
			(xy 365.384068 -273.133946) (xy 365.410371 -273.09235) (xy 365.443006 -273.055513) (xy 365.481127 -273.024388)
			(xy 365.523748 -272.999781) (xy 365.569764 -272.982329) (xy 365.617983 -272.972485) (xy 365.667158 -272.970504)
			(xy 365.716013 -272.976436) (xy 365.763284 -272.990128) (xy 365.807746 -273.011226) (xy 365.848249 -273.039182)
			(xy 365.883742 -273.073274) (xy 365.913307 -273.112618) (xy 365.936178 -273.156195) (xy 365.951762 -273.202876)
			(xy 365.959657 -273.251453) (xy 365.960152 -273.27606) (xy 366.289094 -273.27606) (xy 366.293054 -273.227006)
			(xy 366.304831 -273.179222) (xy 366.324122 -273.133946) (xy 366.350425 -273.09235) (xy 366.38306 -273.055513)
			(xy 366.421181 -273.024388) (xy 366.463802 -272.999781) (xy 366.509818 -272.982329) (xy 366.558037 -272.972485)
			(xy 366.607212 -272.970504) (xy 366.656067 -272.976436) (xy 366.703338 -272.990128) (xy 366.7478 -273.011226)
			(xy 366.788303 -273.039182) (xy 366.823796 -273.073274) (xy 366.853361 -273.112618) (xy 366.876232 -273.156195)
			(xy 366.891816 -273.202876) (xy 366.899711 -273.251453) (xy 366.900206 -273.27606) (xy 367.228894 -273.27606)
			(xy 367.232854 -273.227006) (xy 367.244631 -273.179222) (xy 367.263922 -273.133946) (xy 367.290225 -273.09235)
			(xy 367.32286 -273.055513) (xy 367.360981 -273.024388) (xy 367.403602 -272.999781) (xy 367.449618 -272.982329)
			(xy 367.497837 -272.972485) (xy 367.547012 -272.970504) (xy 367.595867 -272.976436) (xy 367.643138 -272.990128)
			(xy 367.6876 -273.011226) (xy 367.728103 -273.039182) (xy 367.763596 -273.073274) (xy 367.793161 -273.112618)
			(xy 367.816032 -273.156195) (xy 367.831616 -273.202876) (xy 367.839511 -273.251453) (xy 367.840006 -273.27606)
			(xy 368.168948 -273.27606) (xy 368.172908 -273.227006) (xy 368.184685 -273.179222) (xy 368.203976 -273.133946)
			(xy 368.230279 -273.09235) (xy 368.262914 -273.055513) (xy 368.301035 -273.024388) (xy 368.343656 -272.999781)
			(xy 368.389672 -272.982329) (xy 368.437891 -272.972485) (xy 368.487066 -272.970504) (xy 368.535921 -272.976436)
			(xy 368.583192 -272.990128) (xy 368.627654 -273.011226) (xy 368.668157 -273.039182) (xy 368.70365 -273.073274)
			(xy 368.733215 -273.112618) (xy 368.756086 -273.156195) (xy 368.77167 -273.202876) (xy 368.779565 -273.251453)
			(xy 368.78006 -273.27606) (xy 369.109002 -273.27606) (xy 369.112962 -273.227006) (xy 369.124739 -273.179222)
			(xy 369.14403 -273.133946) (xy 369.170333 -273.09235) (xy 369.202968 -273.055513) (xy 369.241089 -273.024388)
			(xy 369.28371 -272.999781) (xy 369.329726 -272.982329) (xy 369.377945 -272.972485) (xy 369.42712 -272.970504)
			(xy 369.475975 -272.976436) (xy 369.523246 -272.990128) (xy 369.567708 -273.011226) (xy 369.608211 -273.039182)
			(xy 369.643704 -273.073274) (xy 369.673269 -273.112618) (xy 369.69614 -273.156195) (xy 369.711724 -273.202876)
			(xy 369.719619 -273.251453) (xy 369.720114 -273.27606) (xy 370.049056 -273.27606) (xy 370.053016 -273.227006)
			(xy 370.064793 -273.179222) (xy 370.084084 -273.133946) (xy 370.110387 -273.09235) (xy 370.143022 -273.055513)
			(xy 370.181143 -273.024388) (xy 370.223764 -272.999781) (xy 370.26978 -272.982329) (xy 370.317999 -272.972485)
			(xy 370.367174 -272.970504) (xy 370.416029 -272.976436) (xy 370.4633 -272.990128) (xy 370.507762 -273.011226)
			(xy 370.548265 -273.039182) (xy 370.583758 -273.073274) (xy 370.613323 -273.112618) (xy 370.636194 -273.156195)
			(xy 370.651778 -273.202876) (xy 370.659673 -273.251453) (xy 370.660168 -273.27606) (xy 370.98911 -273.27606)
			(xy 370.99307 -273.227006) (xy 371.004847 -273.179222) (xy 371.024138 -273.133946) (xy 371.050441 -273.09235)
			(xy 371.083076 -273.055513) (xy 371.121197 -273.024388) (xy 371.163818 -272.999781) (xy 371.209834 -272.982329)
			(xy 371.258053 -272.972485) (xy 371.307228 -272.970504) (xy 371.356083 -272.976436) (xy 371.403354 -272.990128)
			(xy 371.447816 -273.011226) (xy 371.488319 -273.039182) (xy 371.523812 -273.073274) (xy 371.553377 -273.112618)
			(xy 371.576248 -273.156195) (xy 371.591832 -273.202876) (xy 371.599727 -273.251453) (xy 371.600222 -273.27606)
			(xy 371.92891 -273.27606) (xy 371.93287 -273.227006) (xy 371.944647 -273.179222) (xy 371.963938 -273.133946)
			(xy 371.990241 -273.09235) (xy 372.022876 -273.055513) (xy 372.060997 -273.024388) (xy 372.103618 -272.999781)
			(xy 372.149634 -272.982329) (xy 372.197853 -272.972485) (xy 372.247028 -272.970504) (xy 372.295883 -272.976436)
			(xy 372.343154 -272.990128) (xy 372.387616 -273.011226) (xy 372.428119 -273.039182) (xy 372.463612 -273.073274)
			(xy 372.493177 -273.112618) (xy 372.516048 -273.156195) (xy 372.531632 -273.202876) (xy 372.539527 -273.251453)
			(xy 372.540022 -273.27606) (xy 372.539527 -273.300667) (xy 372.531632 -273.349244) (xy 372.516048 -273.395925)
			(xy 372.493177 -273.439502) (xy 372.463612 -273.478846) (xy 372.428119 -273.512938) (xy 372.387616 -273.540894)
			(xy 372.343154 -273.561992) (xy 372.295883 -273.575684) (xy 372.247028 -273.581616) (xy 372.197853 -273.579635)
			(xy 372.149634 -273.569791) (xy 372.103618 -273.552339) (xy 372.060997 -273.527732) (xy 372.022876 -273.496607)
			(xy 371.990241 -273.45977) (xy 371.963938 -273.418174) (xy 371.944647 -273.372898) (xy 371.93287 -273.325114)
			(xy 371.92891 -273.27606) (xy 371.600222 -273.27606) (xy 371.599727 -273.300667) (xy 371.591832 -273.349244)
			(xy 371.576248 -273.395925) (xy 371.553377 -273.439502) (xy 371.523812 -273.478846) (xy 371.488319 -273.512938)
			(xy 371.447816 -273.540894) (xy 371.403354 -273.561992) (xy 371.356083 -273.575684) (xy 371.307228 -273.581616)
			(xy 371.258053 -273.579635) (xy 371.209834 -273.569791) (xy 371.163818 -273.552339) (xy 371.121197 -273.527732)
			(xy 371.083076 -273.496607) (xy 371.050441 -273.45977) (xy 371.024138 -273.418174) (xy 371.004847 -273.372898)
			(xy 370.99307 -273.325114) (xy 370.98911 -273.27606) (xy 370.660168 -273.27606) (xy 370.659673 -273.300667)
			(xy 370.651778 -273.349244) (xy 370.636194 -273.395925) (xy 370.613323 -273.439502) (xy 370.583758 -273.478846)
			(xy 370.548265 -273.512938) (xy 370.507762 -273.540894) (xy 370.4633 -273.561992) (xy 370.416029 -273.575684)
			(xy 370.367174 -273.581616) (xy 370.317999 -273.579635) (xy 370.26978 -273.569791) (xy 370.223764 -273.552339)
			(xy 370.181143 -273.527732) (xy 370.143022 -273.496607) (xy 370.110387 -273.45977) (xy 370.084084 -273.418174)
			(xy 370.064793 -273.372898) (xy 370.053016 -273.325114) (xy 370.049056 -273.27606) (xy 369.720114 -273.27606)
			(xy 369.719619 -273.300667) (xy 369.711724 -273.349244) (xy 369.69614 -273.395925) (xy 369.673269 -273.439502)
			(xy 369.643704 -273.478846) (xy 369.608211 -273.512938) (xy 369.567708 -273.540894) (xy 369.523246 -273.561992)
			(xy 369.475975 -273.575684) (xy 369.42712 -273.581616) (xy 369.377945 -273.579635) (xy 369.329726 -273.569791)
			(xy 369.28371 -273.552339) (xy 369.241089 -273.527732) (xy 369.202968 -273.496607) (xy 369.170333 -273.45977)
			(xy 369.14403 -273.418174) (xy 369.124739 -273.372898) (xy 369.112962 -273.325114) (xy 369.109002 -273.27606)
			(xy 368.78006 -273.27606) (xy 368.779565 -273.300667) (xy 368.77167 -273.349244) (xy 368.756086 -273.395925)
			(xy 368.733215 -273.439502) (xy 368.70365 -273.478846) (xy 368.668157 -273.512938) (xy 368.627654 -273.540894)
			(xy 368.583192 -273.561992) (xy 368.535921 -273.575684) (xy 368.487066 -273.581616) (xy 368.437891 -273.579635)
			(xy 368.389672 -273.569791) (xy 368.343656 -273.552339) (xy 368.301035 -273.527732) (xy 368.262914 -273.496607)
			(xy 368.230279 -273.45977) (xy 368.203976 -273.418174) (xy 368.184685 -273.372898) (xy 368.172908 -273.325114)
			(xy 368.168948 -273.27606) (xy 367.840006 -273.27606) (xy 367.839511 -273.300667) (xy 367.831616 -273.349244)
			(xy 367.816032 -273.395925) (xy 367.793161 -273.439502) (xy 367.763596 -273.478846) (xy 367.728103 -273.512938)
			(xy 367.6876 -273.540894) (xy 367.643138 -273.561992) (xy 367.595867 -273.575684) (xy 367.547012 -273.581616)
			(xy 367.497837 -273.579635) (xy 367.449618 -273.569791) (xy 367.403602 -273.552339) (xy 367.360981 -273.527732)
			(xy 367.32286 -273.496607) (xy 367.290225 -273.45977) (xy 367.263922 -273.418174) (xy 367.244631 -273.372898)
			(xy 367.232854 -273.325114) (xy 367.228894 -273.27606) (xy 366.900206 -273.27606) (xy 366.899711 -273.300667)
			(xy 366.891816 -273.349244) (xy 366.876232 -273.395925) (xy 366.853361 -273.439502) (xy 366.823796 -273.478846)
			(xy 366.788303 -273.512938) (xy 366.7478 -273.540894) (xy 366.703338 -273.561992) (xy 366.656067 -273.575684)
			(xy 366.607212 -273.581616) (xy 366.558037 -273.579635) (xy 366.509818 -273.569791) (xy 366.463802 -273.552339)
			(xy 366.421181 -273.527732) (xy 366.38306 -273.496607) (xy 366.350425 -273.45977) (xy 366.324122 -273.418174)
			(xy 366.304831 -273.372898) (xy 366.293054 -273.325114) (xy 366.289094 -273.27606) (xy 365.960152 -273.27606)
			(xy 365.959657 -273.300667) (xy 365.951762 -273.349244) (xy 365.936178 -273.395925) (xy 365.913307 -273.439502)
			(xy 365.883742 -273.478846) (xy 365.848249 -273.512938) (xy 365.807746 -273.540894) (xy 365.763284 -273.561992)
			(xy 365.716013 -273.575684) (xy 365.667158 -273.581616) (xy 365.617983 -273.579635) (xy 365.569764 -273.569791)
			(xy 365.523748 -273.552339) (xy 365.481127 -273.527732) (xy 365.443006 -273.496607) (xy 365.410371 -273.45977)
			(xy 365.384068 -273.418174) (xy 365.364777 -273.372898) (xy 365.353 -273.325114) (xy 365.34904 -273.27606)
			(xy 365.020098 -273.27606) (xy 365.019603 -273.300667) (xy 365.011708 -273.349244) (xy 364.996124 -273.395925)
			(xy 364.973253 -273.439502) (xy 364.943688 -273.478846) (xy 364.908195 -273.512938) (xy 364.867692 -273.540894)
			(xy 364.82323 -273.561992) (xy 364.775959 -273.575684) (xy 364.727104 -273.581616) (xy 364.677929 -273.579635)
			(xy 364.62971 -273.569791) (xy 364.583694 -273.552339) (xy 364.541073 -273.527732) (xy 364.502952 -273.496607)
			(xy 364.470317 -273.45977) (xy 364.444014 -273.418174) (xy 364.424723 -273.372898) (xy 364.412946 -273.325114)
			(xy 364.408986 -273.27606) (xy 364.080044 -273.27606) (xy 364.079549 -273.300667) (xy 364.071654 -273.349244)
			(xy 364.05607 -273.395925) (xy 364.033199 -273.439502) (xy 364.003634 -273.478846) (xy 363.968141 -273.512938)
			(xy 363.927638 -273.540894) (xy 363.883176 -273.561992) (xy 363.835905 -273.575684) (xy 363.78705 -273.581616)
			(xy 363.737875 -273.579635) (xy 363.689656 -273.569791) (xy 363.64364 -273.552339) (xy 363.601019 -273.527732)
			(xy 363.562898 -273.496607) (xy 363.530263 -273.45977) (xy 363.50396 -273.418174) (xy 363.484669 -273.372898)
			(xy 363.472892 -273.325114) (xy 363.468932 -273.27606) (xy 363.13999 -273.27606) (xy 363.139495 -273.300667)
			(xy 363.1316 -273.349244) (xy 363.116016 -273.395925) (xy 363.093145 -273.439502) (xy 363.06358 -273.478846)
			(xy 363.028087 -273.512938) (xy 362.987584 -273.540894) (xy 362.943122 -273.561992) (xy 362.895851 -273.575684)
			(xy 362.846996 -273.581616) (xy 362.797821 -273.579635) (xy 362.749602 -273.569791) (xy 362.703586 -273.552339)
			(xy 362.660965 -273.527732) (xy 362.622844 -273.496607) (xy 362.590209 -273.45977) (xy 362.563906 -273.418174)
			(xy 362.544615 -273.372898) (xy 362.532838 -273.325114) (xy 362.528878 -273.27606) (xy 362.20019 -273.27606)
			(xy 362.199695 -273.300667) (xy 362.1918 -273.349244) (xy 362.176216 -273.395925) (xy 362.153345 -273.439502)
			(xy 362.12378 -273.478846) (xy 362.088287 -273.512938) (xy 362.047784 -273.540894) (xy 362.003322 -273.561992)
			(xy 361.956051 -273.575684) (xy 361.907196 -273.581616) (xy 361.858021 -273.579635) (xy 361.809802 -273.569791)
			(xy 361.763786 -273.552339) (xy 361.721165 -273.527732) (xy 361.683044 -273.496607) (xy 361.650409 -273.45977)
			(xy 361.624106 -273.418174) (xy 361.604815 -273.372898) (xy 361.593038 -273.325114) (xy 361.589078 -273.27606)
			(xy 358.446324 -273.27606) (xy 358.445829 -273.300667) (xy 358.437934 -273.349244) (xy 358.42235 -273.395925)
			(xy 358.399479 -273.439502) (xy 358.369914 -273.478846) (xy 358.334421 -273.512938) (xy 358.293918 -273.540894)
			(xy 358.249456 -273.561992) (xy 358.202185 -273.575684) (xy 358.15333 -273.581616) (xy 358.104155 -273.579635)
			(xy 358.055936 -273.569791) (xy 358.00992 -273.552339) (xy 357.967299 -273.527732) (xy 357.929178 -273.496607)
			(xy 357.896543 -273.45977) (xy 357.87024 -273.418174) (xy 357.850949 -273.372898) (xy 357.839172 -273.325114)
			(xy 357.835212 -273.27606) (xy 357.506524 -273.27606) (xy 357.506029 -273.300667) (xy 357.498134 -273.349244)
			(xy 357.48255 -273.395925) (xy 357.459679 -273.439502) (xy 357.430114 -273.478846) (xy 357.394621 -273.512938)
			(xy 357.354118 -273.540894) (xy 357.309656 -273.561992) (xy 357.262385 -273.575684) (xy 357.21353 -273.581616)
			(xy 357.164355 -273.579635) (xy 357.116136 -273.569791) (xy 357.07012 -273.552339) (xy 357.027499 -273.527732)
			(xy 356.989378 -273.496607) (xy 356.956743 -273.45977) (xy 356.93044 -273.418174) (xy 356.911149 -273.372898)
			(xy 356.899372 -273.325114) (xy 356.895412 -273.27606) (xy 356.56647 -273.27606) (xy 356.565975 -273.300667)
			(xy 356.55808 -273.349244) (xy 356.542496 -273.395925) (xy 356.519625 -273.439502) (xy 356.49006 -273.478846)
			(xy 356.454567 -273.512938) (xy 356.414064 -273.540894) (xy 356.369602 -273.561992) (xy 356.322331 -273.575684)
			(xy 356.273476 -273.581616) (xy 356.224301 -273.579635) (xy 356.176082 -273.569791) (xy 356.130066 -273.552339)
			(xy 356.087445 -273.527732) (xy 356.049324 -273.496607) (xy 356.016689 -273.45977) (xy 355.990386 -273.418174)
			(xy 355.971095 -273.372898) (xy 355.959318 -273.325114) (xy 355.955358 -273.27606) (xy 355.626416 -273.27606)
			(xy 355.625921 -273.300667) (xy 355.618026 -273.349244) (xy 355.602442 -273.395925) (xy 355.579571 -273.439502)
			(xy 355.550006 -273.478846) (xy 355.514513 -273.512938) (xy 355.47401 -273.540894) (xy 355.429548 -273.561992)
			(xy 355.382277 -273.575684) (xy 355.333422 -273.581616) (xy 355.284247 -273.579635) (xy 355.236028 -273.569791)
			(xy 355.190012 -273.552339) (xy 355.147391 -273.527732) (xy 355.10927 -273.496607) (xy 355.076635 -273.45977)
			(xy 355.050332 -273.418174) (xy 355.031041 -273.372898) (xy 355.019264 -273.325114) (xy 355.015304 -273.27606)
			(xy 354.686362 -273.27606) (xy 354.685867 -273.300667) (xy 354.677972 -273.349244) (xy 354.662388 -273.395925)
			(xy 354.639517 -273.439502) (xy 354.609952 -273.478846) (xy 354.574459 -273.512938) (xy 354.533956 -273.540894)
			(xy 354.489494 -273.561992) (xy 354.442223 -273.575684) (xy 354.393368 -273.581616) (xy 354.344193 -273.579635)
			(xy 354.295974 -273.569791) (xy 354.249958 -273.552339) (xy 354.207337 -273.527732) (xy 354.169216 -273.496607)
			(xy 354.136581 -273.45977) (xy 354.110278 -273.418174) (xy 354.090987 -273.372898) (xy 354.07921 -273.325114)
			(xy 354.07525 -273.27606) (xy 353.746308 -273.27606) (xy 353.745813 -273.300667) (xy 353.737918 -273.349244)
			(xy 353.722334 -273.395925) (xy 353.699463 -273.439502) (xy 353.669898 -273.478846) (xy 353.634405 -273.512938)
			(xy 353.593902 -273.540894) (xy 353.54944 -273.561992) (xy 353.502169 -273.575684) (xy 353.453314 -273.581616)
			(xy 353.404139 -273.579635) (xy 353.35592 -273.569791) (xy 353.309904 -273.552339) (xy 353.267283 -273.527732)
			(xy 353.229162 -273.496607) (xy 353.196527 -273.45977) (xy 353.170224 -273.418174) (xy 353.150933 -273.372898)
			(xy 353.139156 -273.325114) (xy 353.135196 -273.27606) (xy 352.806508 -273.27606) (xy 352.806013 -273.300667)
			(xy 352.798118 -273.349244) (xy 352.782534 -273.395925) (xy 352.759663 -273.439502) (xy 352.730098 -273.478846)
			(xy 352.694605 -273.512938) (xy 352.654102 -273.540894) (xy 352.60964 -273.561992) (xy 352.562369 -273.575684)
			(xy 352.513514 -273.581616) (xy 352.464339 -273.579635) (xy 352.41612 -273.569791) (xy 352.370104 -273.552339)
			(xy 352.327483 -273.527732) (xy 352.289362 -273.496607) (xy 352.256727 -273.45977) (xy 352.230424 -273.418174)
			(xy 352.211133 -273.372898) (xy 352.199356 -273.325114) (xy 352.195396 -273.27606) (xy 351.866454 -273.27606)
			(xy 351.865959 -273.300667) (xy 351.858064 -273.349244) (xy 351.84248 -273.395925) (xy 351.819609 -273.439502)
			(xy 351.790044 -273.478846) (xy 351.754551 -273.512938) (xy 351.714048 -273.540894) (xy 351.669586 -273.561992)
			(xy 351.622315 -273.575684) (xy 351.57346 -273.581616) (xy 351.524285 -273.579635) (xy 351.476066 -273.569791)
			(xy 351.43005 -273.552339) (xy 351.387429 -273.527732) (xy 351.349308 -273.496607) (xy 351.316673 -273.45977)
			(xy 351.29037 -273.418174) (xy 351.271079 -273.372898) (xy 351.259302 -273.325114) (xy 351.255342 -273.27606)
			(xy 350.9264 -273.27606) (xy 350.925905 -273.300667) (xy 350.91801 -273.349244) (xy 350.902426 -273.395925)
			(xy 350.879555 -273.439502) (xy 350.84999 -273.478846) (xy 350.814497 -273.512938) (xy 350.773994 -273.540894)
			(xy 350.729532 -273.561992) (xy 350.682261 -273.575684) (xy 350.633406 -273.581616) (xy 350.584231 -273.579635)
			(xy 350.536012 -273.569791) (xy 350.489996 -273.552339) (xy 350.447375 -273.527732) (xy 350.409254 -273.496607)
			(xy 350.376619 -273.45977) (xy 350.350316 -273.418174) (xy 350.331025 -273.372898) (xy 350.319248 -273.325114)
			(xy 350.315288 -273.27606) (xy 349.986346 -273.27606) (xy 349.985851 -273.300667) (xy 349.977956 -273.349244)
			(xy 349.962372 -273.395925) (xy 349.939501 -273.439502) (xy 349.909936 -273.478846) (xy 349.874443 -273.512938)
			(xy 349.83394 -273.540894) (xy 349.789478 -273.561992) (xy 349.742207 -273.575684) (xy 349.693352 -273.581616)
			(xy 349.644177 -273.579635) (xy 349.595958 -273.569791) (xy 349.549942 -273.552339) (xy 349.507321 -273.527732)
			(xy 349.4692 -273.496607) (xy 349.436565 -273.45977) (xy 349.410262 -273.418174) (xy 349.390971 -273.372898)
			(xy 349.379194 -273.325114) (xy 349.375234 -273.27606) (xy 349.046546 -273.27606) (xy 349.046051 -273.300667)
			(xy 349.038156 -273.349244) (xy 349.022572 -273.395925) (xy 348.999701 -273.439502) (xy 348.970136 -273.478846)
			(xy 348.934643 -273.512938) (xy 348.89414 -273.540894) (xy 348.849678 -273.561992) (xy 348.802407 -273.575684)
			(xy 348.753552 -273.581616) (xy 348.704377 -273.579635) (xy 348.656158 -273.569791) (xy 348.610142 -273.552339)
			(xy 348.567521 -273.527732) (xy 348.5294 -273.496607) (xy 348.496765 -273.45977) (xy 348.470462 -273.418174)
			(xy 348.451171 -273.372898) (xy 348.439394 -273.325114) (xy 348.435434 -273.27606) (xy 348.106492 -273.27606)
			(xy 348.105997 -273.300667) (xy 348.098102 -273.349244) (xy 348.082518 -273.395925) (xy 348.059647 -273.439502)
			(xy 348.030082 -273.478846) (xy 347.994589 -273.512938) (xy 347.954086 -273.540894) (xy 347.909624 -273.561992)
			(xy 347.862353 -273.575684) (xy 347.813498 -273.581616) (xy 347.764323 -273.579635) (xy 347.716104 -273.569791)
			(xy 347.670088 -273.552339) (xy 347.627467 -273.527732) (xy 347.589346 -273.496607) (xy 347.556711 -273.45977)
			(xy 347.530408 -273.418174) (xy 347.511117 -273.372898) (xy 347.49934 -273.325114) (xy 347.49538 -273.27606)
			(xy 347.166438 -273.27606) (xy 347.165943 -273.300667) (xy 347.158048 -273.349244) (xy 347.142464 -273.395925)
			(xy 347.119593 -273.439502) (xy 347.090028 -273.478846) (xy 347.054535 -273.512938) (xy 347.014032 -273.540894)
			(xy 346.96957 -273.561992) (xy 346.922299 -273.575684) (xy 346.873444 -273.581616) (xy 346.824269 -273.579635)
			(xy 346.77605 -273.569791) (xy 346.730034 -273.552339) (xy 346.687413 -273.527732) (xy 346.649292 -273.496607)
			(xy 346.616657 -273.45977) (xy 346.590354 -273.418174) (xy 346.571063 -273.372898) (xy 346.559286 -273.325114)
			(xy 346.555326 -273.27606) (xy 346.226384 -273.27606) (xy 346.225889 -273.300667) (xy 346.217994 -273.349244)
			(xy 346.20241 -273.395925) (xy 346.179539 -273.439502) (xy 346.149974 -273.478846) (xy 346.114481 -273.512938)
			(xy 346.073978 -273.540894) (xy 346.029516 -273.561992) (xy 345.982245 -273.575684) (xy 345.93339 -273.581616)
			(xy 345.884215 -273.579635) (xy 345.835996 -273.569791) (xy 345.78998 -273.552339) (xy 345.747359 -273.527732)
			(xy 345.709238 -273.496607) (xy 345.676603 -273.45977) (xy 345.6503 -273.418174) (xy 345.631009 -273.372898)
			(xy 345.619232 -273.325114) (xy 345.615272 -273.27606) (xy 345.286868 -273.27606) (xy 345.286871 -273.2761)
			(xy 345.282704 -273.326416) (xy 345.270317 -273.375361) (xy 345.250047 -273.421602) (xy 345.222447 -273.463878)
			(xy 345.188268 -273.501038) (xy 345.148442 -273.532069) (xy 345.104054 -273.556127) (xy 345.056313 -273.572554)
			(xy 345.00652 -273.580905) (xy 344.981276 -273.581368) (xy 344.971207 -273.581795) (xy 344.952606 -273.589512)
			(xy 344.945208 -273.596354) (xy 344.895424 -273.646138) (xy 344.888711 -273.653376) (xy 344.881121 -273.671581)
			(xy 344.880692 -273.681444) (xy 344.880692 -274.086066) (xy 345.145372 -274.086066) (xy 345.149332 -274.037012)
			(xy 345.161109 -273.989228) (xy 345.1804 -273.943952) (xy 345.206703 -273.902356) (xy 345.239338 -273.865519)
			(xy 345.277459 -273.834394) (xy 345.32008 -273.809787) (xy 345.366096 -273.792335) (xy 345.414315 -273.782491)
			(xy 345.46349 -273.78051) (xy 345.512345 -273.786442) (xy 345.559616 -273.800134) (xy 345.604078 -273.821232)
			(xy 345.644581 -273.849188) (xy 345.680074 -273.88328) (xy 345.709639 -273.922624) (xy 345.73251 -273.966201)
			(xy 345.748094 -274.012882) (xy 345.755989 -274.061459) (xy 345.756484 -274.086066) (xy 346.085426 -274.086066)
			(xy 346.089386 -274.037012) (xy 346.101163 -273.989228) (xy 346.120454 -273.943952) (xy 346.146757 -273.902356)
			(xy 346.179392 -273.865519) (xy 346.217513 -273.834394) (xy 346.260134 -273.809787) (xy 346.30615 -273.792335)
			(xy 346.354369 -273.782491) (xy 346.403544 -273.78051) (xy 346.452399 -273.786442) (xy 346.49967 -273.800134)
			(xy 346.544132 -273.821232) (xy 346.584635 -273.849188) (xy 346.620128 -273.88328) (xy 346.649693 -273.922624)
			(xy 346.672564 -273.966201) (xy 346.688148 -274.012882) (xy 346.696043 -274.061459) (xy 346.696538 -274.086066)
			(xy 347.025226 -274.086066) (xy 347.029186 -274.037012) (xy 347.040963 -273.989228) (xy 347.060254 -273.943952)
			(xy 347.086557 -273.902356) (xy 347.119192 -273.865519) (xy 347.157313 -273.834394) (xy 347.199934 -273.809787)
			(xy 347.24595 -273.792335) (xy 347.294169 -273.782491) (xy 347.343344 -273.78051) (xy 347.392199 -273.786442)
			(xy 347.43947 -273.800134) (xy 347.483932 -273.821232) (xy 347.524435 -273.849188) (xy 347.559928 -273.88328)
			(xy 347.589493 -273.922624) (xy 347.612364 -273.966201) (xy 347.627948 -274.012882) (xy 347.635843 -274.061459)
			(xy 347.636338 -274.086066) (xy 347.96528 -274.086066) (xy 347.96924 -274.037012) (xy 347.981017 -273.989228)
			(xy 348.000308 -273.943952) (xy 348.026611 -273.902356) (xy 348.059246 -273.865519) (xy 348.097367 -273.834394)
			(xy 348.139988 -273.809787) (xy 348.186004 -273.792335) (xy 348.234223 -273.782491) (xy 348.283398 -273.78051)
			(xy 348.332253 -273.786442) (xy 348.379524 -273.800134) (xy 348.423986 -273.821232) (xy 348.464489 -273.849188)
			(xy 348.499982 -273.88328) (xy 348.529547 -273.922624) (xy 348.552418 -273.966201) (xy 348.568002 -274.012882)
			(xy 348.575897 -274.061459) (xy 348.576392 -274.086066) (xy 348.905334 -274.086066) (xy 348.909294 -274.037012)
			(xy 348.921071 -273.989228) (xy 348.940362 -273.943952) (xy 348.966665 -273.902356) (xy 348.9993 -273.865519)
			(xy 349.037421 -273.834394) (xy 349.080042 -273.809787) (xy 349.126058 -273.792335) (xy 349.174277 -273.782491)
			(xy 349.223452 -273.78051) (xy 349.272307 -273.786442) (xy 349.319578 -273.800134) (xy 349.36404 -273.821232)
			(xy 349.404543 -273.849188) (xy 349.440036 -273.88328) (xy 349.469601 -273.922624) (xy 349.492472 -273.966201)
			(xy 349.508056 -274.012882) (xy 349.515951 -274.061459) (xy 349.516446 -274.086066) (xy 349.845388 -274.086066)
			(xy 349.849348 -274.037012) (xy 349.861125 -273.989228) (xy 349.880416 -273.943952) (xy 349.906719 -273.902356)
			(xy 349.939354 -273.865519) (xy 349.977475 -273.834394) (xy 350.020096 -273.809787) (xy 350.066112 -273.792335)
			(xy 350.114331 -273.782491) (xy 350.163506 -273.78051) (xy 350.212361 -273.786442) (xy 350.259632 -273.800134)
			(xy 350.304094 -273.821232) (xy 350.344597 -273.849188) (xy 350.38009 -273.88328) (xy 350.409655 -273.922624)
			(xy 350.432526 -273.966201) (xy 350.44811 -274.012882) (xy 350.456005 -274.061459) (xy 350.4565 -274.086066)
			(xy 350.785442 -274.086066) (xy 350.789402 -274.037012) (xy 350.801179 -273.989228) (xy 350.82047 -273.943952)
			(xy 350.846773 -273.902356) (xy 350.879408 -273.865519) (xy 350.917529 -273.834394) (xy 350.96015 -273.809787)
			(xy 351.006166 -273.792335) (xy 351.054385 -273.782491) (xy 351.10356 -273.78051) (xy 351.152415 -273.786442)
			(xy 351.199686 -273.800134) (xy 351.244148 -273.821232) (xy 351.284651 -273.849188) (xy 351.320144 -273.88328)
			(xy 351.349709 -273.922624) (xy 351.37258 -273.966201) (xy 351.388164 -274.012882) (xy 351.396059 -274.061459)
			(xy 351.396554 -274.086066) (xy 351.725242 -274.086066) (xy 351.729202 -274.037012) (xy 351.740979 -273.989228)
			(xy 351.76027 -273.943952) (xy 351.786573 -273.902356) (xy 351.819208 -273.865519) (xy 351.857329 -273.834394)
			(xy 351.89995 -273.809787) (xy 351.945966 -273.792335) (xy 351.994185 -273.782491) (xy 352.04336 -273.78051)
			(xy 352.092215 -273.786442) (xy 352.139486 -273.800134) (xy 352.183948 -273.821232) (xy 352.224451 -273.849188)
			(xy 352.259944 -273.88328) (xy 352.289509 -273.922624) (xy 352.31238 -273.966201) (xy 352.327964 -274.012882)
			(xy 352.335859 -274.061459) (xy 352.336354 -274.086066) (xy 352.665296 -274.086066) (xy 352.669256 -274.037012)
			(xy 352.681033 -273.989228) (xy 352.700324 -273.943952) (xy 352.726627 -273.902356) (xy 352.759262 -273.865519)
			(xy 352.797383 -273.834394) (xy 352.840004 -273.809787) (xy 352.88602 -273.792335) (xy 352.934239 -273.782491)
			(xy 352.983414 -273.78051) (xy 353.032269 -273.786442) (xy 353.07954 -273.800134) (xy 353.124002 -273.821232)
			(xy 353.164505 -273.849188) (xy 353.199998 -273.88328) (xy 353.229563 -273.922624) (xy 353.252434 -273.966201)
			(xy 353.268018 -274.012882) (xy 353.275913 -274.061459) (xy 353.276408 -274.086066) (xy 353.60535 -274.086066)
			(xy 353.60931 -274.037012) (xy 353.621087 -273.989228) (xy 353.640378 -273.943952) (xy 353.666681 -273.902356)
			(xy 353.699316 -273.865519) (xy 353.737437 -273.834394) (xy 353.780058 -273.809787) (xy 353.826074 -273.792335)
			(xy 353.874293 -273.782491) (xy 353.923468 -273.78051) (xy 353.972323 -273.786442) (xy 354.019594 -273.800134)
			(xy 354.064056 -273.821232) (xy 354.104559 -273.849188) (xy 354.140052 -273.88328) (xy 354.169617 -273.922624)
			(xy 354.192488 -273.966201) (xy 354.208072 -274.012882) (xy 354.215967 -274.061459) (xy 354.216462 -274.086066)
			(xy 354.545404 -274.086066) (xy 354.549364 -274.037012) (xy 354.561141 -273.989228) (xy 354.580432 -273.943952)
			(xy 354.606735 -273.902356) (xy 354.63937 -273.865519) (xy 354.677491 -273.834394) (xy 354.720112 -273.809787)
			(xy 354.766128 -273.792335) (xy 354.814347 -273.782491) (xy 354.863522 -273.78051) (xy 354.912377 -273.786442)
			(xy 354.959648 -273.800134) (xy 355.00411 -273.821232) (xy 355.044613 -273.849188) (xy 355.080106 -273.88328)
			(xy 355.109671 -273.922624) (xy 355.132542 -273.966201) (xy 355.148126 -274.012882) (xy 355.156021 -274.061459)
			(xy 355.156516 -274.086066) (xy 355.485204 -274.086066) (xy 355.489164 -274.037012) (xy 355.500941 -273.989228)
			(xy 355.520232 -273.943952) (xy 355.546535 -273.902356) (xy 355.57917 -273.865519) (xy 355.617291 -273.834394)
			(xy 355.659912 -273.809787) (xy 355.705928 -273.792335) (xy 355.754147 -273.782491) (xy 355.803322 -273.78051)
			(xy 355.852177 -273.786442) (xy 355.899448 -273.800134) (xy 355.94391 -273.821232) (xy 355.984413 -273.849188)
			(xy 356.019906 -273.88328) (xy 356.049471 -273.922624) (xy 356.072342 -273.966201) (xy 356.087926 -274.012882)
			(xy 356.095821 -274.061459) (xy 356.096316 -274.086066) (xy 356.425258 -274.086066) (xy 356.429218 -274.037012)
			(xy 356.440995 -273.989228) (xy 356.460286 -273.943952) (xy 356.486589 -273.902356) (xy 356.519224 -273.865519)
			(xy 356.557345 -273.834394) (xy 356.599966 -273.809787) (xy 356.645982 -273.792335) (xy 356.694201 -273.782491)
			(xy 356.743376 -273.78051) (xy 356.792231 -273.786442) (xy 356.839502 -273.800134) (xy 356.883964 -273.821232)
			(xy 356.924467 -273.849188) (xy 356.95996 -273.88328) (xy 356.989525 -273.922624) (xy 357.012396 -273.966201)
			(xy 357.02798 -274.012882) (xy 357.035875 -274.061459) (xy 357.03637 -274.086066) (xy 357.365312 -274.086066)
			(xy 357.369272 -274.037012) (xy 357.381049 -273.989228) (xy 357.40034 -273.943952) (xy 357.426643 -273.902356)
			(xy 357.459278 -273.865519) (xy 357.497399 -273.834394) (xy 357.54002 -273.809787) (xy 357.586036 -273.792335)
			(xy 357.634255 -273.782491) (xy 357.68343 -273.78051) (xy 357.732285 -273.786442) (xy 357.779556 -273.800134)
			(xy 357.824018 -273.821232) (xy 357.864521 -273.849188) (xy 357.900014 -273.88328) (xy 357.929579 -273.922624)
			(xy 357.95245 -273.966201) (xy 357.968034 -274.012882) (xy 357.975929 -274.061459) (xy 357.976424 -274.086066)
			(xy 358.305366 -274.086066) (xy 358.309326 -274.037012) (xy 358.321103 -273.989228) (xy 358.340394 -273.943952)
			(xy 358.366697 -273.902356) (xy 358.399332 -273.865519) (xy 358.437453 -273.834394) (xy 358.480074 -273.809787)
			(xy 358.52609 -273.792335) (xy 358.574309 -273.782491) (xy 358.623484 -273.78051) (xy 358.672339 -273.786442)
			(xy 358.71961 -273.800134) (xy 358.764072 -273.821232) (xy 358.804575 -273.849188) (xy 358.840068 -273.88328)
			(xy 358.869633 -273.922624) (xy 358.892504 -273.966201) (xy 358.908088 -274.012882) (xy 358.915983 -274.061459)
			(xy 358.916478 -274.086066) (xy 361.118924 -274.086066) (xy 361.122884 -274.037012) (xy 361.134661 -273.989228)
			(xy 361.153952 -273.943952) (xy 361.180255 -273.902356) (xy 361.21289 -273.865519) (xy 361.251011 -273.834394)
			(xy 361.293632 -273.809787) (xy 361.339648 -273.792335) (xy 361.387867 -273.782491) (xy 361.437042 -273.78051)
			(xy 361.485897 -273.786442) (xy 361.533168 -273.800134) (xy 361.57763 -273.821232) (xy 361.618133 -273.849188)
			(xy 361.653626 -273.88328) (xy 361.683191 -273.922624) (xy 361.706062 -273.966201) (xy 361.721646 -274.012882)
			(xy 361.729541 -274.061459) (xy 361.730036 -274.086066) (xy 362.058978 -274.086066) (xy 362.062938 -274.037012)
			(xy 362.074715 -273.989228) (xy 362.094006 -273.943952) (xy 362.120309 -273.902356) (xy 362.152944 -273.865519)
			(xy 362.191065 -273.834394) (xy 362.233686 -273.809787) (xy 362.279702 -273.792335) (xy 362.327921 -273.782491)
			(xy 362.377096 -273.78051) (xy 362.425951 -273.786442) (xy 362.473222 -273.800134) (xy 362.517684 -273.821232)
			(xy 362.558187 -273.849188) (xy 362.59368 -273.88328) (xy 362.623245 -273.922624) (xy 362.646116 -273.966201)
			(xy 362.6617 -274.012882) (xy 362.669595 -274.061459) (xy 362.67009 -274.086066) (xy 362.999032 -274.086066)
			(xy 363.002992 -274.037012) (xy 363.014769 -273.989228) (xy 363.03406 -273.943952) (xy 363.060363 -273.902356)
			(xy 363.092998 -273.865519) (xy 363.131119 -273.834394) (xy 363.17374 -273.809787) (xy 363.219756 -273.792335)
			(xy 363.267975 -273.782491) (xy 363.31715 -273.78051) (xy 363.366005 -273.786442) (xy 363.413276 -273.800134)
			(xy 363.457738 -273.821232) (xy 363.498241 -273.849188) (xy 363.533734 -273.88328) (xy 363.563299 -273.922624)
			(xy 363.58617 -273.966201) (xy 363.601754 -274.012882) (xy 363.609649 -274.061459) (xy 363.610144 -274.086066)
			(xy 363.939086 -274.086066) (xy 363.943046 -274.037012) (xy 363.954823 -273.989228) (xy 363.974114 -273.943952)
			(xy 364.000417 -273.902356) (xy 364.033052 -273.865519) (xy 364.071173 -273.834394) (xy 364.113794 -273.809787)
			(xy 364.15981 -273.792335) (xy 364.208029 -273.782491) (xy 364.257204 -273.78051) (xy 364.306059 -273.786442)
			(xy 364.35333 -273.800134) (xy 364.397792 -273.821232) (xy 364.438295 -273.849188) (xy 364.473788 -273.88328)
			(xy 364.503353 -273.922624) (xy 364.526224 -273.966201) (xy 364.541808 -274.012882) (xy 364.549703 -274.061459)
			(xy 364.550198 -274.086066) (xy 364.878886 -274.086066) (xy 364.882846 -274.037012) (xy 364.894623 -273.989228)
			(xy 364.913914 -273.943952) (xy 364.940217 -273.902356) (xy 364.972852 -273.865519) (xy 365.010973 -273.834394)
			(xy 365.053594 -273.809787) (xy 365.09961 -273.792335) (xy 365.147829 -273.782491) (xy 365.197004 -273.78051)
			(xy 365.245859 -273.786442) (xy 365.29313 -273.800134) (xy 365.337592 -273.821232) (xy 365.378095 -273.849188)
			(xy 365.413588 -273.88328) (xy 365.443153 -273.922624) (xy 365.466024 -273.966201) (xy 365.481608 -274.012882)
			(xy 365.489503 -274.061459) (xy 365.489998 -274.086066) (xy 365.81894 -274.086066) (xy 365.8229 -274.037012)
			(xy 365.834677 -273.989228) (xy 365.853968 -273.943952) (xy 365.880271 -273.902356) (xy 365.912906 -273.865519)
			(xy 365.951027 -273.834394) (xy 365.993648 -273.809787) (xy 366.039664 -273.792335) (xy 366.087883 -273.782491)
			(xy 366.137058 -273.78051) (xy 366.185913 -273.786442) (xy 366.233184 -273.800134) (xy 366.277646 -273.821232)
			(xy 366.318149 -273.849188) (xy 366.353642 -273.88328) (xy 366.383207 -273.922624) (xy 366.406078 -273.966201)
			(xy 366.421662 -274.012882) (xy 366.429557 -274.061459) (xy 366.430052 -274.086066) (xy 366.758994 -274.086066)
			(xy 366.762954 -274.037012) (xy 366.774731 -273.989228) (xy 366.794022 -273.943952) (xy 366.820325 -273.902356)
			(xy 366.85296 -273.865519) (xy 366.891081 -273.834394) (xy 366.933702 -273.809787) (xy 366.979718 -273.792335)
			(xy 367.027937 -273.782491) (xy 367.077112 -273.78051) (xy 367.125967 -273.786442) (xy 367.173238 -273.800134)
			(xy 367.2177 -273.821232) (xy 367.258203 -273.849188) (xy 367.293696 -273.88328) (xy 367.323261 -273.922624)
			(xy 367.346132 -273.966201) (xy 367.361716 -274.012882) (xy 367.369611 -274.061459) (xy 367.370106 -274.086066)
			(xy 367.699048 -274.086066) (xy 367.703008 -274.037012) (xy 367.714785 -273.989228) (xy 367.734076 -273.943952)
			(xy 367.760379 -273.902356) (xy 367.793014 -273.865519) (xy 367.831135 -273.834394) (xy 367.873756 -273.809787)
			(xy 367.919772 -273.792335) (xy 367.967991 -273.782491) (xy 368.017166 -273.78051) (xy 368.066021 -273.786442)
			(xy 368.113292 -273.800134) (xy 368.157754 -273.821232) (xy 368.198257 -273.849188) (xy 368.23375 -273.88328)
			(xy 368.263315 -273.922624) (xy 368.286186 -273.966201) (xy 368.30177 -274.012882) (xy 368.309665 -274.061459)
			(xy 368.31016 -274.086066) (xy 368.639102 -274.086066) (xy 368.643062 -274.037012) (xy 368.654839 -273.989228)
			(xy 368.67413 -273.943952) (xy 368.700433 -273.902356) (xy 368.733068 -273.865519) (xy 368.771189 -273.834394)
			(xy 368.81381 -273.809787) (xy 368.859826 -273.792335) (xy 368.908045 -273.782491) (xy 368.95722 -273.78051)
			(xy 369.006075 -273.786442) (xy 369.053346 -273.800134) (xy 369.097808 -273.821232) (xy 369.138311 -273.849188)
			(xy 369.173804 -273.88328) (xy 369.203369 -273.922624) (xy 369.22624 -273.966201) (xy 369.241824 -274.012882)
			(xy 369.249719 -274.061459) (xy 369.250214 -274.086066) (xy 369.578902 -274.086066) (xy 369.582862 -274.037012)
			(xy 369.594639 -273.989228) (xy 369.61393 -273.943952) (xy 369.640233 -273.902356) (xy 369.672868 -273.865519)
			(xy 369.710989 -273.834394) (xy 369.75361 -273.809787) (xy 369.799626 -273.792335) (xy 369.847845 -273.782491)
			(xy 369.89702 -273.78051) (xy 369.945875 -273.786442) (xy 369.993146 -273.800134) (xy 370.037608 -273.821232)
			(xy 370.078111 -273.849188) (xy 370.113604 -273.88328) (xy 370.143169 -273.922624) (xy 370.16604 -273.966201)
			(xy 370.181624 -274.012882) (xy 370.189519 -274.061459) (xy 370.190014 -274.086066) (xy 370.518956 -274.086066)
			(xy 370.522916 -274.037012) (xy 370.534693 -273.989228) (xy 370.553984 -273.943952) (xy 370.580287 -273.902356)
			(xy 370.612922 -273.865519) (xy 370.651043 -273.834394) (xy 370.693664 -273.809787) (xy 370.73968 -273.792335)
			(xy 370.787899 -273.782491) (xy 370.837074 -273.78051) (xy 370.885929 -273.786442) (xy 370.9332 -273.800134)
			(xy 370.977662 -273.821232) (xy 371.018165 -273.849188) (xy 371.053658 -273.88328) (xy 371.083223 -273.922624)
			(xy 371.106094 -273.966201) (xy 371.121678 -274.012882) (xy 371.129573 -274.061459) (xy 371.130068 -274.086066)
			(xy 371.45901 -274.086066) (xy 371.46297 -274.037012) (xy 371.474747 -273.989228) (xy 371.494038 -273.943952)
			(xy 371.520341 -273.902356) (xy 371.552976 -273.865519) (xy 371.591097 -273.834394) (xy 371.633718 -273.809787)
			(xy 371.679734 -273.792335) (xy 371.727953 -273.782491) (xy 371.777128 -273.78051) (xy 371.825983 -273.786442)
			(xy 371.873254 -273.800134) (xy 371.917716 -273.821232) (xy 371.958219 -273.849188) (xy 371.993712 -273.88328)
			(xy 372.023277 -273.922624) (xy 372.046148 -273.966201) (xy 372.061732 -274.012882) (xy 372.069627 -274.061459)
			(xy 372.070122 -274.086066) (xy 372.399064 -274.086066) (xy 372.403024 -274.037012) (xy 372.414801 -273.989228)
			(xy 372.434092 -273.943952) (xy 372.460395 -273.902356) (xy 372.49303 -273.865519) (xy 372.531151 -273.834394)
			(xy 372.573772 -273.809787) (xy 372.619788 -273.792335) (xy 372.668007 -273.782491) (xy 372.717182 -273.78051)
			(xy 372.766037 -273.786442) (xy 372.813308 -273.800134) (xy 372.85777 -273.821232) (xy 372.898273 -273.849188)
			(xy 372.933766 -273.88328) (xy 372.963331 -273.922624) (xy 372.986202 -273.966201) (xy 373.001786 -274.012882)
			(xy 373.009681 -274.061459) (xy 373.010176 -274.086066) (xy 373.339118 -274.086066) (xy 373.343078 -274.037012)
			(xy 373.354855 -273.989228) (xy 373.374146 -273.943952) (xy 373.400449 -273.902356) (xy 373.433084 -273.865519)
			(xy 373.471205 -273.834394) (xy 373.513826 -273.809787) (xy 373.559842 -273.792335) (xy 373.608061 -273.782491)
			(xy 373.657236 -273.78051) (xy 373.706091 -273.786442) (xy 373.753362 -273.800134) (xy 373.797824 -273.821232)
			(xy 373.838327 -273.849188) (xy 373.87382 -273.88328) (xy 373.903385 -273.922624) (xy 373.926256 -273.966201)
			(xy 373.94184 -274.012882) (xy 373.949735 -274.061459) (xy 373.95023 -274.086066) (xy 373.949735 -274.110673)
			(xy 373.94184 -274.15925) (xy 373.926256 -274.205931) (xy 373.903385 -274.249508) (xy 373.87382 -274.288852)
			(xy 373.838327 -274.322944) (xy 373.797824 -274.3509) (xy 373.753362 -274.371998) (xy 373.706091 -274.38569)
			(xy 373.657236 -274.391622) (xy 373.608061 -274.389641) (xy 373.559842 -274.379797) (xy 373.513826 -274.362345)
			(xy 373.471205 -274.337738) (xy 373.433084 -274.306613) (xy 373.400449 -274.269776) (xy 373.374146 -274.22818)
			(xy 373.354855 -274.182904) (xy 373.343078 -274.13512) (xy 373.339118 -274.086066) (xy 373.010176 -274.086066)
			(xy 373.009681 -274.110673) (xy 373.001786 -274.15925) (xy 372.986202 -274.205931) (xy 372.963331 -274.249508)
			(xy 372.933766 -274.288852) (xy 372.898273 -274.322944) (xy 372.85777 -274.3509) (xy 372.813308 -274.371998)
			(xy 372.766037 -274.38569) (xy 372.717182 -274.391622) (xy 372.668007 -274.389641) (xy 372.619788 -274.379797)
			(xy 372.573772 -274.362345) (xy 372.531151 -274.337738) (xy 372.49303 -274.306613) (xy 372.460395 -274.269776)
			(xy 372.434092 -274.22818) (xy 372.414801 -274.182904) (xy 372.403024 -274.13512) (xy 372.399064 -274.086066)
			(xy 372.070122 -274.086066) (xy 372.069627 -274.110673) (xy 372.061732 -274.15925) (xy 372.046148 -274.205931)
			(xy 372.023277 -274.249508) (xy 371.993712 -274.288852) (xy 371.958219 -274.322944) (xy 371.917716 -274.3509)
			(xy 371.873254 -274.371998) (xy 371.825983 -274.38569) (xy 371.777128 -274.391622) (xy 371.727953 -274.389641)
			(xy 371.679734 -274.379797) (xy 371.633718 -274.362345) (xy 371.591097 -274.337738) (xy 371.552976 -274.306613)
			(xy 371.520341 -274.269776) (xy 371.494038 -274.22818) (xy 371.474747 -274.182904) (xy 371.46297 -274.13512)
			(xy 371.45901 -274.086066) (xy 371.130068 -274.086066) (xy 371.129573 -274.110673) (xy 371.121678 -274.15925)
			(xy 371.106094 -274.205931) (xy 371.083223 -274.249508) (xy 371.053658 -274.288852) (xy 371.018165 -274.322944)
			(xy 370.977662 -274.3509) (xy 370.9332 -274.371998) (xy 370.885929 -274.38569) (xy 370.837074 -274.391622)
			(xy 370.787899 -274.389641) (xy 370.73968 -274.379797) (xy 370.693664 -274.362345) (xy 370.651043 -274.337738)
			(xy 370.612922 -274.306613) (xy 370.580287 -274.269776) (xy 370.553984 -274.22818) (xy 370.534693 -274.182904)
			(xy 370.522916 -274.13512) (xy 370.518956 -274.086066) (xy 370.190014 -274.086066) (xy 370.189519 -274.110673)
			(xy 370.181624 -274.15925) (xy 370.16604 -274.205931) (xy 370.143169 -274.249508) (xy 370.113604 -274.288852)
			(xy 370.078111 -274.322944) (xy 370.037608 -274.3509) (xy 369.993146 -274.371998) (xy 369.945875 -274.38569)
			(xy 369.89702 -274.391622) (xy 369.847845 -274.389641) (xy 369.799626 -274.379797) (xy 369.75361 -274.362345)
			(xy 369.710989 -274.337738) (xy 369.672868 -274.306613) (xy 369.640233 -274.269776) (xy 369.61393 -274.22818)
			(xy 369.594639 -274.182904) (xy 369.582862 -274.13512) (xy 369.578902 -274.086066) (xy 369.250214 -274.086066)
			(xy 369.249719 -274.110673) (xy 369.241824 -274.15925) (xy 369.22624 -274.205931) (xy 369.203369 -274.249508)
			(xy 369.173804 -274.288852) (xy 369.138311 -274.322944) (xy 369.097808 -274.3509) (xy 369.053346 -274.371998)
			(xy 369.006075 -274.38569) (xy 368.95722 -274.391622) (xy 368.908045 -274.389641) (xy 368.859826 -274.379797)
			(xy 368.81381 -274.362345) (xy 368.771189 -274.337738) (xy 368.733068 -274.306613) (xy 368.700433 -274.269776)
			(xy 368.67413 -274.22818) (xy 368.654839 -274.182904) (xy 368.643062 -274.13512) (xy 368.639102 -274.086066)
			(xy 368.31016 -274.086066) (xy 368.309665 -274.110673) (xy 368.30177 -274.15925) (xy 368.286186 -274.205931)
			(xy 368.263315 -274.249508) (xy 368.23375 -274.288852) (xy 368.198257 -274.322944) (xy 368.157754 -274.3509)
			(xy 368.113292 -274.371998) (xy 368.066021 -274.38569) (xy 368.017166 -274.391622) (xy 367.967991 -274.389641)
			(xy 367.919772 -274.379797) (xy 367.873756 -274.362345) (xy 367.831135 -274.337738) (xy 367.793014 -274.306613)
			(xy 367.760379 -274.269776) (xy 367.734076 -274.22818) (xy 367.714785 -274.182904) (xy 367.703008 -274.13512)
			(xy 367.699048 -274.086066) (xy 367.370106 -274.086066) (xy 367.369611 -274.110673) (xy 367.361716 -274.15925)
			(xy 367.346132 -274.205931) (xy 367.323261 -274.249508) (xy 367.293696 -274.288852) (xy 367.258203 -274.322944)
			(xy 367.2177 -274.3509) (xy 367.173238 -274.371998) (xy 367.125967 -274.38569) (xy 367.077112 -274.391622)
			(xy 367.027937 -274.389641) (xy 366.979718 -274.379797) (xy 366.933702 -274.362345) (xy 366.891081 -274.337738)
			(xy 366.85296 -274.306613) (xy 366.820325 -274.269776) (xy 366.794022 -274.22818) (xy 366.774731 -274.182904)
			(xy 366.762954 -274.13512) (xy 366.758994 -274.086066) (xy 366.430052 -274.086066) (xy 366.429557 -274.110673)
			(xy 366.421662 -274.15925) (xy 366.406078 -274.205931) (xy 366.383207 -274.249508) (xy 366.353642 -274.288852)
			(xy 366.318149 -274.322944) (xy 366.277646 -274.3509) (xy 366.233184 -274.371998) (xy 366.185913 -274.38569)
			(xy 366.137058 -274.391622) (xy 366.087883 -274.389641) (xy 366.039664 -274.379797) (xy 365.993648 -274.362345)
			(xy 365.951027 -274.337738) (xy 365.912906 -274.306613) (xy 365.880271 -274.269776) (xy 365.853968 -274.22818)
			(xy 365.834677 -274.182904) (xy 365.8229 -274.13512) (xy 365.81894 -274.086066) (xy 365.489998 -274.086066)
			(xy 365.489503 -274.110673) (xy 365.481608 -274.15925) (xy 365.466024 -274.205931) (xy 365.443153 -274.249508)
			(xy 365.413588 -274.288852) (xy 365.378095 -274.322944) (xy 365.337592 -274.3509) (xy 365.29313 -274.371998)
			(xy 365.245859 -274.38569) (xy 365.197004 -274.391622) (xy 365.147829 -274.389641) (xy 365.09961 -274.379797)
			(xy 365.053594 -274.362345) (xy 365.010973 -274.337738) (xy 364.972852 -274.306613) (xy 364.940217 -274.269776)
			(xy 364.913914 -274.22818) (xy 364.894623 -274.182904) (xy 364.882846 -274.13512) (xy 364.878886 -274.086066)
			(xy 364.550198 -274.086066) (xy 364.549703 -274.110673) (xy 364.541808 -274.15925) (xy 364.526224 -274.205931)
			(xy 364.503353 -274.249508) (xy 364.473788 -274.288852) (xy 364.438295 -274.322944) (xy 364.397792 -274.3509)
			(xy 364.35333 -274.371998) (xy 364.306059 -274.38569) (xy 364.257204 -274.391622) (xy 364.208029 -274.389641)
			(xy 364.15981 -274.379797) (xy 364.113794 -274.362345) (xy 364.071173 -274.337738) (xy 364.033052 -274.306613)
			(xy 364.000417 -274.269776) (xy 363.974114 -274.22818) (xy 363.954823 -274.182904) (xy 363.943046 -274.13512)
			(xy 363.939086 -274.086066) (xy 363.610144 -274.086066) (xy 363.609649 -274.110673) (xy 363.601754 -274.15925)
			(xy 363.58617 -274.205931) (xy 363.563299 -274.249508) (xy 363.533734 -274.288852) (xy 363.498241 -274.322944)
			(xy 363.457738 -274.3509) (xy 363.413276 -274.371998) (xy 363.366005 -274.38569) (xy 363.31715 -274.391622)
			(xy 363.267975 -274.389641) (xy 363.219756 -274.379797) (xy 363.17374 -274.362345) (xy 363.131119 -274.337738)
			(xy 363.092998 -274.306613) (xy 363.060363 -274.269776) (xy 363.03406 -274.22818) (xy 363.014769 -274.182904)
			(xy 363.002992 -274.13512) (xy 362.999032 -274.086066) (xy 362.67009 -274.086066) (xy 362.669595 -274.110673)
			(xy 362.6617 -274.15925) (xy 362.646116 -274.205931) (xy 362.623245 -274.249508) (xy 362.59368 -274.288852)
			(xy 362.558187 -274.322944) (xy 362.517684 -274.3509) (xy 362.473222 -274.371998) (xy 362.425951 -274.38569)
			(xy 362.377096 -274.391622) (xy 362.327921 -274.389641) (xy 362.279702 -274.379797) (xy 362.233686 -274.362345)
			(xy 362.191065 -274.337738) (xy 362.152944 -274.306613) (xy 362.120309 -274.269776) (xy 362.094006 -274.22818)
			(xy 362.074715 -274.182904) (xy 362.062938 -274.13512) (xy 362.058978 -274.086066) (xy 361.730036 -274.086066)
			(xy 361.729541 -274.110673) (xy 361.721646 -274.15925) (xy 361.706062 -274.205931) (xy 361.683191 -274.249508)
			(xy 361.653626 -274.288852) (xy 361.618133 -274.322944) (xy 361.57763 -274.3509) (xy 361.533168 -274.371998)
			(xy 361.485897 -274.38569) (xy 361.437042 -274.391622) (xy 361.387867 -274.389641) (xy 361.339648 -274.379797)
			(xy 361.293632 -274.362345) (xy 361.251011 -274.337738) (xy 361.21289 -274.306613) (xy 361.180255 -274.269776)
			(xy 361.153952 -274.22818) (xy 361.134661 -274.182904) (xy 361.122884 -274.13512) (xy 361.118924 -274.086066)
			(xy 358.916478 -274.086066) (xy 358.915983 -274.110673) (xy 358.908088 -274.15925) (xy 358.892504 -274.205931)
			(xy 358.869633 -274.249508) (xy 358.840068 -274.288852) (xy 358.804575 -274.322944) (xy 358.764072 -274.3509)
			(xy 358.71961 -274.371998) (xy 358.672339 -274.38569) (xy 358.623484 -274.391622) (xy 358.574309 -274.389641)
			(xy 358.52609 -274.379797) (xy 358.480074 -274.362345) (xy 358.437453 -274.337738) (xy 358.399332 -274.306613)
			(xy 358.366697 -274.269776) (xy 358.340394 -274.22818) (xy 358.321103 -274.182904) (xy 358.309326 -274.13512)
			(xy 358.305366 -274.086066) (xy 357.976424 -274.086066) (xy 357.975929 -274.110673) (xy 357.968034 -274.15925)
			(xy 357.95245 -274.205931) (xy 357.929579 -274.249508) (xy 357.900014 -274.288852) (xy 357.864521 -274.322944)
			(xy 357.824018 -274.3509) (xy 357.779556 -274.371998) (xy 357.732285 -274.38569) (xy 357.68343 -274.391622)
			(xy 357.634255 -274.389641) (xy 357.586036 -274.379797) (xy 357.54002 -274.362345) (xy 357.497399 -274.337738)
			(xy 357.459278 -274.306613) (xy 357.426643 -274.269776) (xy 357.40034 -274.22818) (xy 357.381049 -274.182904)
			(xy 357.369272 -274.13512) (xy 357.365312 -274.086066) (xy 357.03637 -274.086066) (xy 357.035875 -274.110673)
			(xy 357.02798 -274.15925) (xy 357.012396 -274.205931) (xy 356.989525 -274.249508) (xy 356.95996 -274.288852)
			(xy 356.924467 -274.322944) (xy 356.883964 -274.3509) (xy 356.839502 -274.371998) (xy 356.792231 -274.38569)
			(xy 356.743376 -274.391622) (xy 356.694201 -274.389641) (xy 356.645982 -274.379797) (xy 356.599966 -274.362345)
			(xy 356.557345 -274.337738) (xy 356.519224 -274.306613) (xy 356.486589 -274.269776) (xy 356.460286 -274.22818)
			(xy 356.440995 -274.182904) (xy 356.429218 -274.13512) (xy 356.425258 -274.086066) (xy 356.096316 -274.086066)
			(xy 356.095821 -274.110673) (xy 356.087926 -274.15925) (xy 356.072342 -274.205931) (xy 356.049471 -274.249508)
			(xy 356.019906 -274.288852) (xy 355.984413 -274.322944) (xy 355.94391 -274.3509) (xy 355.899448 -274.371998)
			(xy 355.852177 -274.38569) (xy 355.803322 -274.391622) (xy 355.754147 -274.389641) (xy 355.705928 -274.379797)
			(xy 355.659912 -274.362345) (xy 355.617291 -274.337738) (xy 355.57917 -274.306613) (xy 355.546535 -274.269776)
			(xy 355.520232 -274.22818) (xy 355.500941 -274.182904) (xy 355.489164 -274.13512) (xy 355.485204 -274.086066)
			(xy 355.156516 -274.086066) (xy 355.156021 -274.110673) (xy 355.148126 -274.15925) (xy 355.132542 -274.205931)
			(xy 355.109671 -274.249508) (xy 355.080106 -274.288852) (xy 355.044613 -274.322944) (xy 355.00411 -274.3509)
			(xy 354.959648 -274.371998) (xy 354.912377 -274.38569) (xy 354.863522 -274.391622) (xy 354.814347 -274.389641)
			(xy 354.766128 -274.379797) (xy 354.720112 -274.362345) (xy 354.677491 -274.337738) (xy 354.63937 -274.306613)
			(xy 354.606735 -274.269776) (xy 354.580432 -274.22818) (xy 354.561141 -274.182904) (xy 354.549364 -274.13512)
			(xy 354.545404 -274.086066) (xy 354.216462 -274.086066) (xy 354.215967 -274.110673) (xy 354.208072 -274.15925)
			(xy 354.192488 -274.205931) (xy 354.169617 -274.249508) (xy 354.140052 -274.288852) (xy 354.104559 -274.322944)
			(xy 354.064056 -274.3509) (xy 354.019594 -274.371998) (xy 353.972323 -274.38569) (xy 353.923468 -274.391622)
			(xy 353.874293 -274.389641) (xy 353.826074 -274.379797) (xy 353.780058 -274.362345) (xy 353.737437 -274.337738)
			(xy 353.699316 -274.306613) (xy 353.666681 -274.269776) (xy 353.640378 -274.22818) (xy 353.621087 -274.182904)
			(xy 353.60931 -274.13512) (xy 353.60535 -274.086066) (xy 353.276408 -274.086066) (xy 353.275913 -274.110673)
			(xy 353.268018 -274.15925) (xy 353.252434 -274.205931) (xy 353.229563 -274.249508) (xy 353.199998 -274.288852)
			(xy 353.164505 -274.322944) (xy 353.124002 -274.3509) (xy 353.07954 -274.371998) (xy 353.032269 -274.38569)
			(xy 352.983414 -274.391622) (xy 352.934239 -274.389641) (xy 352.88602 -274.379797) (xy 352.840004 -274.362345)
			(xy 352.797383 -274.337738) (xy 352.759262 -274.306613) (xy 352.726627 -274.269776) (xy 352.700324 -274.22818)
			(xy 352.681033 -274.182904) (xy 352.669256 -274.13512) (xy 352.665296 -274.086066) (xy 352.336354 -274.086066)
			(xy 352.335859 -274.110673) (xy 352.327964 -274.15925) (xy 352.31238 -274.205931) (xy 352.289509 -274.249508)
			(xy 352.259944 -274.288852) (xy 352.224451 -274.322944) (xy 352.183948 -274.3509) (xy 352.139486 -274.371998)
			(xy 352.092215 -274.38569) (xy 352.04336 -274.391622) (xy 351.994185 -274.389641) (xy 351.945966 -274.379797)
			(xy 351.89995 -274.362345) (xy 351.857329 -274.337738) (xy 351.819208 -274.306613) (xy 351.786573 -274.269776)
			(xy 351.76027 -274.22818) (xy 351.740979 -274.182904) (xy 351.729202 -274.13512) (xy 351.725242 -274.086066)
			(xy 351.396554 -274.086066) (xy 351.396059 -274.110673) (xy 351.388164 -274.15925) (xy 351.37258 -274.205931)
			(xy 351.349709 -274.249508) (xy 351.320144 -274.288852) (xy 351.284651 -274.322944) (xy 351.244148 -274.3509)
			(xy 351.199686 -274.371998) (xy 351.152415 -274.38569) (xy 351.10356 -274.391622) (xy 351.054385 -274.389641)
			(xy 351.006166 -274.379797) (xy 350.96015 -274.362345) (xy 350.917529 -274.337738) (xy 350.879408 -274.306613)
			(xy 350.846773 -274.269776) (xy 350.82047 -274.22818) (xy 350.801179 -274.182904) (xy 350.789402 -274.13512)
			(xy 350.785442 -274.086066) (xy 350.4565 -274.086066) (xy 350.456005 -274.110673) (xy 350.44811 -274.15925)
			(xy 350.432526 -274.205931) (xy 350.409655 -274.249508) (xy 350.38009 -274.288852) (xy 350.344597 -274.322944)
			(xy 350.304094 -274.3509) (xy 350.259632 -274.371998) (xy 350.212361 -274.38569) (xy 350.163506 -274.391622)
			(xy 350.114331 -274.389641) (xy 350.066112 -274.379797) (xy 350.020096 -274.362345) (xy 349.977475 -274.337738)
			(xy 349.939354 -274.306613) (xy 349.906719 -274.269776) (xy 349.880416 -274.22818) (xy 349.861125 -274.182904)
			(xy 349.849348 -274.13512) (xy 349.845388 -274.086066) (xy 349.516446 -274.086066) (xy 349.515951 -274.110673)
			(xy 349.508056 -274.15925) (xy 349.492472 -274.205931) (xy 349.469601 -274.249508) (xy 349.440036 -274.288852)
			(xy 349.404543 -274.322944) (xy 349.36404 -274.3509) (xy 349.319578 -274.371998) (xy 349.272307 -274.38569)
			(xy 349.223452 -274.391622) (xy 349.174277 -274.389641) (xy 349.126058 -274.379797) (xy 349.080042 -274.362345)
			(xy 349.037421 -274.337738) (xy 348.9993 -274.306613) (xy 348.966665 -274.269776) (xy 348.940362 -274.22818)
			(xy 348.921071 -274.182904) (xy 348.909294 -274.13512) (xy 348.905334 -274.086066) (xy 348.576392 -274.086066)
			(xy 348.575897 -274.110673) (xy 348.568002 -274.15925) (xy 348.552418 -274.205931) (xy 348.529547 -274.249508)
			(xy 348.499982 -274.288852) (xy 348.464489 -274.322944) (xy 348.423986 -274.3509) (xy 348.379524 -274.371998)
			(xy 348.332253 -274.38569) (xy 348.283398 -274.391622) (xy 348.234223 -274.389641) (xy 348.186004 -274.379797)
			(xy 348.139988 -274.362345) (xy 348.097367 -274.337738) (xy 348.059246 -274.306613) (xy 348.026611 -274.269776)
			(xy 348.000308 -274.22818) (xy 347.981017 -274.182904) (xy 347.96924 -274.13512) (xy 347.96528 -274.086066)
			(xy 347.636338 -274.086066) (xy 347.635843 -274.110673) (xy 347.627948 -274.15925) (xy 347.612364 -274.205931)
			(xy 347.589493 -274.249508) (xy 347.559928 -274.288852) (xy 347.524435 -274.322944) (xy 347.483932 -274.3509)
			(xy 347.43947 -274.371998) (xy 347.392199 -274.38569) (xy 347.343344 -274.391622) (xy 347.294169 -274.389641)
			(xy 347.24595 -274.379797) (xy 347.199934 -274.362345) (xy 347.157313 -274.337738) (xy 347.119192 -274.306613)
			(xy 347.086557 -274.269776) (xy 347.060254 -274.22818) (xy 347.040963 -274.182904) (xy 347.029186 -274.13512)
			(xy 347.025226 -274.086066) (xy 346.696538 -274.086066) (xy 346.696043 -274.110673) (xy 346.688148 -274.15925)
			(xy 346.672564 -274.205931) (xy 346.649693 -274.249508) (xy 346.620128 -274.288852) (xy 346.584635 -274.322944)
			(xy 346.544132 -274.3509) (xy 346.49967 -274.371998) (xy 346.452399 -274.38569) (xy 346.403544 -274.391622)
			(xy 346.354369 -274.389641) (xy 346.30615 -274.379797) (xy 346.260134 -274.362345) (xy 346.217513 -274.337738)
			(xy 346.179392 -274.306613) (xy 346.146757 -274.269776) (xy 346.120454 -274.22818) (xy 346.101163 -274.182904)
			(xy 346.089386 -274.13512) (xy 346.085426 -274.086066) (xy 345.756484 -274.086066) (xy 345.755989 -274.110673)
			(xy 345.748094 -274.15925) (xy 345.73251 -274.205931) (xy 345.709639 -274.249508) (xy 345.680074 -274.288852)
			(xy 345.644581 -274.322944) (xy 345.604078 -274.3509) (xy 345.559616 -274.371998) (xy 345.512345 -274.38569)
			(xy 345.46349 -274.391622) (xy 345.414315 -274.389641) (xy 345.366096 -274.379797) (xy 345.32008 -274.362345)
			(xy 345.277459 -274.337738) (xy 345.239338 -274.306613) (xy 345.206703 -274.269776) (xy 345.1804 -274.22818)
			(xy 345.161109 -274.182904) (xy 345.149332 -274.13512) (xy 345.145372 -274.086066) (xy 344.880692 -274.086066)
			(xy 344.880692 -274.49018) (xy 344.881163 -274.500052) (xy 344.888621 -274.518336) (xy 344.89517 -274.52574)
			(xy 344.895424 -274.525994) (xy 344.945208 -274.575778) (xy 344.952606 -274.582625) (xy 344.971204 -274.59036)
			(xy 344.981276 -274.590764) (xy 345.006519 -274.591307) (xy 345.05631 -274.599657) (xy 345.104049 -274.616084)
			(xy 345.148435 -274.640141) (xy 345.18826 -274.671171) (xy 345.222437 -274.708329) (xy 345.250037 -274.750604)
			(xy 345.270306 -274.796843) (xy 345.282692 -274.845786) (xy 345.286857 -274.896072) (xy 345.615272 -274.896072)
			(xy 345.619232 -274.847018) (xy 345.631009 -274.799234) (xy 345.6503 -274.753958) (xy 345.676603 -274.712362)
			(xy 345.709238 -274.675525) (xy 345.747359 -274.6444) (xy 345.78998 -274.619793) (xy 345.835996 -274.602341)
			(xy 345.884215 -274.592497) (xy 345.93339 -274.590516) (xy 345.982245 -274.596448) (xy 346.029516 -274.61014)
			(xy 346.073978 -274.631238) (xy 346.114481 -274.659194) (xy 346.149974 -274.693286) (xy 346.179539 -274.73263)
			(xy 346.20241 -274.776207) (xy 346.217994 -274.822888) (xy 346.225889 -274.871465) (xy 346.226384 -274.896072)
			(xy 346.555326 -274.896072) (xy 346.559286 -274.847018) (xy 346.571063 -274.799234) (xy 346.590354 -274.753958)
			(xy 346.616657 -274.712362) (xy 346.649292 -274.675525) (xy 346.687413 -274.6444) (xy 346.730034 -274.619793)
			(xy 346.77605 -274.602341) (xy 346.824269 -274.592497) (xy 346.873444 -274.590516) (xy 346.922299 -274.596448)
			(xy 346.96957 -274.61014) (xy 347.014032 -274.631238) (xy 347.054535 -274.659194) (xy 347.090028 -274.693286)
			(xy 347.119593 -274.73263) (xy 347.142464 -274.776207) (xy 347.158048 -274.822888) (xy 347.165943 -274.871465)
			(xy 347.166438 -274.896072) (xy 347.49538 -274.896072) (xy 347.49934 -274.847018) (xy 347.511117 -274.799234)
			(xy 347.530408 -274.753958) (xy 347.556711 -274.712362) (xy 347.589346 -274.675525) (xy 347.627467 -274.6444)
			(xy 347.670088 -274.619793) (xy 347.716104 -274.602341) (xy 347.764323 -274.592497) (xy 347.813498 -274.590516)
			(xy 347.862353 -274.596448) (xy 347.909624 -274.61014) (xy 347.954086 -274.631238) (xy 347.994589 -274.659194)
			(xy 348.030082 -274.693286) (xy 348.059647 -274.73263) (xy 348.082518 -274.776207) (xy 348.098102 -274.822888)
			(xy 348.105997 -274.871465) (xy 348.106492 -274.896072) (xy 348.435434 -274.896072) (xy 348.439394 -274.847018)
			(xy 348.451171 -274.799234) (xy 348.470462 -274.753958) (xy 348.496765 -274.712362) (xy 348.5294 -274.675525)
			(xy 348.567521 -274.6444) (xy 348.610142 -274.619793) (xy 348.656158 -274.602341) (xy 348.704377 -274.592497)
			(xy 348.753552 -274.590516) (xy 348.802407 -274.596448) (xy 348.849678 -274.61014) (xy 348.89414 -274.631238)
			(xy 348.934643 -274.659194) (xy 348.970136 -274.693286) (xy 348.999701 -274.73263) (xy 349.022572 -274.776207)
			(xy 349.038156 -274.822888) (xy 349.046051 -274.871465) (xy 349.046546 -274.896072) (xy 349.375234 -274.896072)
			(xy 349.379194 -274.847018) (xy 349.390971 -274.799234) (xy 349.410262 -274.753958) (xy 349.436565 -274.712362)
			(xy 349.4692 -274.675525) (xy 349.507321 -274.6444) (xy 349.549942 -274.619793) (xy 349.595958 -274.602341)
			(xy 349.644177 -274.592497) (xy 349.693352 -274.590516) (xy 349.742207 -274.596448) (xy 349.789478 -274.61014)
			(xy 349.83394 -274.631238) (xy 349.874443 -274.659194) (xy 349.909936 -274.693286) (xy 349.939501 -274.73263)
			(xy 349.962372 -274.776207) (xy 349.977956 -274.822888) (xy 349.985851 -274.871465) (xy 349.986346 -274.896072)
			(xy 350.315288 -274.896072) (xy 350.319248 -274.847018) (xy 350.331025 -274.799234) (xy 350.350316 -274.753958)
			(xy 350.376619 -274.712362) (xy 350.409254 -274.675525) (xy 350.447375 -274.6444) (xy 350.489996 -274.619793)
			(xy 350.536012 -274.602341) (xy 350.584231 -274.592497) (xy 350.633406 -274.590516) (xy 350.682261 -274.596448)
			(xy 350.729532 -274.61014) (xy 350.773994 -274.631238) (xy 350.814497 -274.659194) (xy 350.84999 -274.693286)
			(xy 350.879555 -274.73263) (xy 350.902426 -274.776207) (xy 350.91801 -274.822888) (xy 350.925905 -274.871465)
			(xy 350.9264 -274.896072) (xy 351.255342 -274.896072) (xy 351.259302 -274.847018) (xy 351.271079 -274.799234)
			(xy 351.29037 -274.753958) (xy 351.316673 -274.712362) (xy 351.349308 -274.675525) (xy 351.387429 -274.6444)
			(xy 351.43005 -274.619793) (xy 351.476066 -274.602341) (xy 351.524285 -274.592497) (xy 351.57346 -274.590516)
			(xy 351.622315 -274.596448) (xy 351.669586 -274.61014) (xy 351.714048 -274.631238) (xy 351.754551 -274.659194)
			(xy 351.790044 -274.693286) (xy 351.819609 -274.73263) (xy 351.84248 -274.776207) (xy 351.858064 -274.822888)
			(xy 351.865959 -274.871465) (xy 351.866454 -274.896072) (xy 352.195396 -274.896072) (xy 352.199356 -274.847018)
			(xy 352.211133 -274.799234) (xy 352.230424 -274.753958) (xy 352.256727 -274.712362) (xy 352.289362 -274.675525)
			(xy 352.327483 -274.6444) (xy 352.370104 -274.619793) (xy 352.41612 -274.602341) (xy 352.464339 -274.592497)
			(xy 352.513514 -274.590516) (xy 352.562369 -274.596448) (xy 352.60964 -274.61014) (xy 352.654102 -274.631238)
			(xy 352.694605 -274.659194) (xy 352.730098 -274.693286) (xy 352.759663 -274.73263) (xy 352.782534 -274.776207)
			(xy 352.798118 -274.822888) (xy 352.806013 -274.871465) (xy 352.806508 -274.896072) (xy 353.135196 -274.896072)
			(xy 353.139156 -274.847018) (xy 353.150933 -274.799234) (xy 353.170224 -274.753958) (xy 353.196527 -274.712362)
			(xy 353.229162 -274.675525) (xy 353.267283 -274.6444) (xy 353.309904 -274.619793) (xy 353.35592 -274.602341)
			(xy 353.404139 -274.592497) (xy 353.453314 -274.590516) (xy 353.502169 -274.596448) (xy 353.54944 -274.61014)
			(xy 353.593902 -274.631238) (xy 353.634405 -274.659194) (xy 353.669898 -274.693286) (xy 353.699463 -274.73263)
			(xy 353.722334 -274.776207) (xy 353.737918 -274.822888) (xy 353.745813 -274.871465) (xy 353.746308 -274.896072)
			(xy 354.07525 -274.896072) (xy 354.07921 -274.847018) (xy 354.090987 -274.799234) (xy 354.110278 -274.753958)
			(xy 354.136581 -274.712362) (xy 354.169216 -274.675525) (xy 354.207337 -274.6444) (xy 354.249958 -274.619793)
			(xy 354.295974 -274.602341) (xy 354.344193 -274.592497) (xy 354.393368 -274.590516) (xy 354.442223 -274.596448)
			(xy 354.489494 -274.61014) (xy 354.533956 -274.631238) (xy 354.574459 -274.659194) (xy 354.609952 -274.693286)
			(xy 354.639517 -274.73263) (xy 354.662388 -274.776207) (xy 354.677972 -274.822888) (xy 354.685867 -274.871465)
			(xy 354.686362 -274.896072) (xy 355.015304 -274.896072) (xy 355.019264 -274.847018) (xy 355.031041 -274.799234)
			(xy 355.050332 -274.753958) (xy 355.076635 -274.712362) (xy 355.10927 -274.675525) (xy 355.147391 -274.6444)
			(xy 355.190012 -274.619793) (xy 355.236028 -274.602341) (xy 355.284247 -274.592497) (xy 355.333422 -274.590516)
			(xy 355.382277 -274.596448) (xy 355.429548 -274.61014) (xy 355.47401 -274.631238) (xy 355.514513 -274.659194)
			(xy 355.550006 -274.693286) (xy 355.579571 -274.73263) (xy 355.602442 -274.776207) (xy 355.618026 -274.822888)
			(xy 355.625921 -274.871465) (xy 355.626416 -274.896072) (xy 355.955358 -274.896072) (xy 355.959318 -274.847018)
			(xy 355.971095 -274.799234) (xy 355.990386 -274.753958) (xy 356.016689 -274.712362) (xy 356.049324 -274.675525)
			(xy 356.087445 -274.6444) (xy 356.130066 -274.619793) (xy 356.176082 -274.602341) (xy 356.224301 -274.592497)
			(xy 356.273476 -274.590516) (xy 356.322331 -274.596448) (xy 356.369602 -274.61014) (xy 356.414064 -274.631238)
			(xy 356.454567 -274.659194) (xy 356.49006 -274.693286) (xy 356.519625 -274.73263) (xy 356.542496 -274.776207)
			(xy 356.55808 -274.822888) (xy 356.565975 -274.871465) (xy 356.56647 -274.896072) (xy 363.468932 -274.896072)
			(xy 363.472892 -274.847018) (xy 363.484669 -274.799234) (xy 363.50396 -274.753958) (xy 363.530263 -274.712362)
			(xy 363.562898 -274.675525) (xy 363.601019 -274.6444) (xy 363.64364 -274.619793) (xy 363.689656 -274.602341)
			(xy 363.737875 -274.592497) (xy 363.78705 -274.590516) (xy 363.835905 -274.596448) (xy 363.883176 -274.61014)
			(xy 363.927638 -274.631238) (xy 363.968141 -274.659194) (xy 364.003634 -274.693286) (xy 364.033199 -274.73263)
			(xy 364.05607 -274.776207) (xy 364.071654 -274.822888) (xy 364.079549 -274.871465) (xy 364.080044 -274.896072)
			(xy 364.408986 -274.896072) (xy 364.412946 -274.847018) (xy 364.424723 -274.799234) (xy 364.444014 -274.753958)
			(xy 364.470317 -274.712362) (xy 364.502952 -274.675525) (xy 364.541073 -274.6444) (xy 364.583694 -274.619793)
			(xy 364.62971 -274.602341) (xy 364.677929 -274.592497) (xy 364.727104 -274.590516) (xy 364.775959 -274.596448)
			(xy 364.82323 -274.61014) (xy 364.867692 -274.631238) (xy 364.908195 -274.659194) (xy 364.943688 -274.693286)
			(xy 364.973253 -274.73263) (xy 364.996124 -274.776207) (xy 365.011708 -274.822888) (xy 365.019603 -274.871465)
			(xy 365.020098 -274.896072) (xy 365.34904 -274.896072) (xy 365.353 -274.847018) (xy 365.364777 -274.799234)
			(xy 365.384068 -274.753958) (xy 365.410371 -274.712362) (xy 365.443006 -274.675525) (xy 365.481127 -274.6444)
			(xy 365.523748 -274.619793) (xy 365.569764 -274.602341) (xy 365.617983 -274.592497) (xy 365.667158 -274.590516)
			(xy 365.716013 -274.596448) (xy 365.763284 -274.61014) (xy 365.807746 -274.631238) (xy 365.848249 -274.659194)
			(xy 365.883742 -274.693286) (xy 365.913307 -274.73263) (xy 365.936178 -274.776207) (xy 365.951762 -274.822888)
			(xy 365.959657 -274.871465) (xy 365.960152 -274.896072) (xy 366.289094 -274.896072) (xy 366.293054 -274.847018)
			(xy 366.304831 -274.799234) (xy 366.324122 -274.753958) (xy 366.350425 -274.712362) (xy 366.38306 -274.675525)
			(xy 366.421181 -274.6444) (xy 366.463802 -274.619793) (xy 366.509818 -274.602341) (xy 366.558037 -274.592497)
			(xy 366.607212 -274.590516) (xy 366.656067 -274.596448) (xy 366.703338 -274.61014) (xy 366.7478 -274.631238)
			(xy 366.788303 -274.659194) (xy 366.823796 -274.693286) (xy 366.853361 -274.73263) (xy 366.876232 -274.776207)
			(xy 366.891816 -274.822888) (xy 366.899711 -274.871465) (xy 366.900206 -274.896072) (xy 367.228894 -274.896072)
			(xy 367.232854 -274.847018) (xy 367.244631 -274.799234) (xy 367.263922 -274.753958) (xy 367.290225 -274.712362)
			(xy 367.32286 -274.675525) (xy 367.360981 -274.6444) (xy 367.403602 -274.619793) (xy 367.449618 -274.602341)
			(xy 367.497837 -274.592497) (xy 367.547012 -274.590516) (xy 367.595867 -274.596448) (xy 367.643138 -274.61014)
			(xy 367.6876 -274.631238) (xy 367.728103 -274.659194) (xy 367.763596 -274.693286) (xy 367.793161 -274.73263)
			(xy 367.816032 -274.776207) (xy 367.831616 -274.822888) (xy 367.839511 -274.871465) (xy 367.840006 -274.896072)
			(xy 368.168948 -274.896072) (xy 368.172908 -274.847018) (xy 368.184685 -274.799234) (xy 368.203976 -274.753958)
			(xy 368.230279 -274.712362) (xy 368.262914 -274.675525) (xy 368.301035 -274.6444) (xy 368.343656 -274.619793)
			(xy 368.389672 -274.602341) (xy 368.437891 -274.592497) (xy 368.487066 -274.590516) (xy 368.535921 -274.596448)
			(xy 368.583192 -274.61014) (xy 368.627654 -274.631238) (xy 368.668157 -274.659194) (xy 368.70365 -274.693286)
			(xy 368.733215 -274.73263) (xy 368.756086 -274.776207) (xy 368.77167 -274.822888) (xy 368.779565 -274.871465)
			(xy 368.78006 -274.896072) (xy 369.109002 -274.896072) (xy 369.112962 -274.847018) (xy 369.124739 -274.799234)
			(xy 369.14403 -274.753958) (xy 369.170333 -274.712362) (xy 369.202968 -274.675525) (xy 369.241089 -274.6444)
			(xy 369.28371 -274.619793) (xy 369.329726 -274.602341) (xy 369.377945 -274.592497) (xy 369.42712 -274.590516)
			(xy 369.475975 -274.596448) (xy 369.523246 -274.61014) (xy 369.567708 -274.631238) (xy 369.608211 -274.659194)
			(xy 369.643704 -274.693286) (xy 369.673269 -274.73263) (xy 369.69614 -274.776207) (xy 369.711724 -274.822888)
			(xy 369.719619 -274.871465) (xy 369.720114 -274.896072) (xy 370.049056 -274.896072) (xy 370.053016 -274.847018)
			(xy 370.064793 -274.799234) (xy 370.084084 -274.753958) (xy 370.110387 -274.712362) (xy 370.143022 -274.675525)
			(xy 370.181143 -274.6444) (xy 370.223764 -274.619793) (xy 370.26978 -274.602341) (xy 370.317999 -274.592497)
			(xy 370.367174 -274.590516) (xy 370.416029 -274.596448) (xy 370.4633 -274.61014) (xy 370.507762 -274.631238)
			(xy 370.548265 -274.659194) (xy 370.583758 -274.693286) (xy 370.613323 -274.73263) (xy 370.636194 -274.776207)
			(xy 370.651778 -274.822888) (xy 370.659673 -274.871465) (xy 370.660168 -274.896072) (xy 370.98911 -274.896072)
			(xy 370.99307 -274.847018) (xy 371.004847 -274.799234) (xy 371.024138 -274.753958) (xy 371.050441 -274.712362)
			(xy 371.083076 -274.675525) (xy 371.121197 -274.6444) (xy 371.163818 -274.619793) (xy 371.209834 -274.602341)
			(xy 371.258053 -274.592497) (xy 371.307228 -274.590516) (xy 371.356083 -274.596448) (xy 371.403354 -274.61014)
			(xy 371.447816 -274.631238) (xy 371.488319 -274.659194) (xy 371.523812 -274.693286) (xy 371.553377 -274.73263)
			(xy 371.576248 -274.776207) (xy 371.591832 -274.822888) (xy 371.599727 -274.871465) (xy 371.600222 -274.896072)
			(xy 371.92891 -274.896072) (xy 371.93287 -274.847018) (xy 371.944647 -274.799234) (xy 371.963938 -274.753958)
			(xy 371.990241 -274.712362) (xy 372.022876 -274.675525) (xy 372.060997 -274.6444) (xy 372.103618 -274.619793)
			(xy 372.149634 -274.602341) (xy 372.197853 -274.592497) (xy 372.247028 -274.590516) (xy 372.295883 -274.596448)
			(xy 372.343154 -274.61014) (xy 372.387616 -274.631238) (xy 372.428119 -274.659194) (xy 372.463612 -274.693286)
			(xy 372.493177 -274.73263) (xy 372.516048 -274.776207) (xy 372.531632 -274.822888) (xy 372.539527 -274.871465)
			(xy 372.540022 -274.896072) (xy 372.539527 -274.920679) (xy 372.531632 -274.969256) (xy 372.516048 -275.015937)
			(xy 372.493177 -275.059514) (xy 372.463612 -275.098858) (xy 372.428119 -275.13295) (xy 372.387616 -275.160906)
			(xy 372.343154 -275.182004) (xy 372.295883 -275.195696) (xy 372.247028 -275.201628) (xy 372.197853 -275.199647)
			(xy 372.149634 -275.189803) (xy 372.103618 -275.172351) (xy 372.060997 -275.147744) (xy 372.022876 -275.116619)
			(xy 371.990241 -275.079782) (xy 371.963938 -275.038186) (xy 371.944647 -274.99291) (xy 371.93287 -274.945126)
			(xy 371.92891 -274.896072) (xy 371.600222 -274.896072) (xy 371.599727 -274.920679) (xy 371.591832 -274.969256)
			(xy 371.576248 -275.015937) (xy 371.553377 -275.059514) (xy 371.523812 -275.098858) (xy 371.488319 -275.13295)
			(xy 371.447816 -275.160906) (xy 371.403354 -275.182004) (xy 371.356083 -275.195696) (xy 371.307228 -275.201628)
			(xy 371.258053 -275.199647) (xy 371.209834 -275.189803) (xy 371.163818 -275.172351) (xy 371.121197 -275.147744)
			(xy 371.083076 -275.116619) (xy 371.050441 -275.079782) (xy 371.024138 -275.038186) (xy 371.004847 -274.99291)
			(xy 370.99307 -274.945126) (xy 370.98911 -274.896072) (xy 370.660168 -274.896072) (xy 370.659673 -274.920679)
			(xy 370.651778 -274.969256) (xy 370.636194 -275.015937) (xy 370.613323 -275.059514) (xy 370.583758 -275.098858)
			(xy 370.548265 -275.13295) (xy 370.507762 -275.160906) (xy 370.4633 -275.182004) (xy 370.416029 -275.195696)
			(xy 370.367174 -275.201628) (xy 370.317999 -275.199647) (xy 370.26978 -275.189803) (xy 370.223764 -275.172351)
			(xy 370.181143 -275.147744) (xy 370.143022 -275.116619) (xy 370.110387 -275.079782) (xy 370.084084 -275.038186)
			(xy 370.064793 -274.99291) (xy 370.053016 -274.945126) (xy 370.049056 -274.896072) (xy 369.720114 -274.896072)
			(xy 369.719619 -274.920679) (xy 369.711724 -274.969256) (xy 369.69614 -275.015937) (xy 369.673269 -275.059514)
			(xy 369.643704 -275.098858) (xy 369.608211 -275.13295) (xy 369.567708 -275.160906) (xy 369.523246 -275.182004)
			(xy 369.475975 -275.195696) (xy 369.42712 -275.201628) (xy 369.377945 -275.199647) (xy 369.329726 -275.189803)
			(xy 369.28371 -275.172351) (xy 369.241089 -275.147744) (xy 369.202968 -275.116619) (xy 369.170333 -275.079782)
			(xy 369.14403 -275.038186) (xy 369.124739 -274.99291) (xy 369.112962 -274.945126) (xy 369.109002 -274.896072)
			(xy 368.78006 -274.896072) (xy 368.779565 -274.920679) (xy 368.77167 -274.969256) (xy 368.756086 -275.015937)
			(xy 368.733215 -275.059514) (xy 368.70365 -275.098858) (xy 368.668157 -275.13295) (xy 368.627654 -275.160906)
			(xy 368.583192 -275.182004) (xy 368.535921 -275.195696) (xy 368.487066 -275.201628) (xy 368.437891 -275.199647)
			(xy 368.389672 -275.189803) (xy 368.343656 -275.172351) (xy 368.301035 -275.147744) (xy 368.262914 -275.116619)
			(xy 368.230279 -275.079782) (xy 368.203976 -275.038186) (xy 368.184685 -274.99291) (xy 368.172908 -274.945126)
			(xy 368.168948 -274.896072) (xy 367.840006 -274.896072) (xy 367.839511 -274.920679) (xy 367.831616 -274.969256)
			(xy 367.816032 -275.015937) (xy 367.793161 -275.059514) (xy 367.763596 -275.098858) (xy 367.728103 -275.13295)
			(xy 367.6876 -275.160906) (xy 367.643138 -275.182004) (xy 367.595867 -275.195696) (xy 367.547012 -275.201628)
			(xy 367.497837 -275.199647) (xy 367.449618 -275.189803) (xy 367.403602 -275.172351) (xy 367.360981 -275.147744)
			(xy 367.32286 -275.116619) (xy 367.290225 -275.079782) (xy 367.263922 -275.038186) (xy 367.244631 -274.99291)
			(xy 367.232854 -274.945126) (xy 367.228894 -274.896072) (xy 366.900206 -274.896072) (xy 366.899711 -274.920679)
			(xy 366.891816 -274.969256) (xy 366.876232 -275.015937) (xy 366.853361 -275.059514) (xy 366.823796 -275.098858)
			(xy 366.788303 -275.13295) (xy 366.7478 -275.160906) (xy 366.703338 -275.182004) (xy 366.656067 -275.195696)
			(xy 366.607212 -275.201628) (xy 366.558037 -275.199647) (xy 366.509818 -275.189803) (xy 366.463802 -275.172351)
			(xy 366.421181 -275.147744) (xy 366.38306 -275.116619) (xy 366.350425 -275.079782) (xy 366.324122 -275.038186)
			(xy 366.304831 -274.99291) (xy 366.293054 -274.945126) (xy 366.289094 -274.896072) (xy 365.960152 -274.896072)
			(xy 365.959657 -274.920679) (xy 365.951762 -274.969256) (xy 365.936178 -275.015937) (xy 365.913307 -275.059514)
			(xy 365.883742 -275.098858) (xy 365.848249 -275.13295) (xy 365.807746 -275.160906) (xy 365.763284 -275.182004)
			(xy 365.716013 -275.195696) (xy 365.667158 -275.201628) (xy 365.617983 -275.199647) (xy 365.569764 -275.189803)
			(xy 365.523748 -275.172351) (xy 365.481127 -275.147744) (xy 365.443006 -275.116619) (xy 365.410371 -275.079782)
			(xy 365.384068 -275.038186) (xy 365.364777 -274.99291) (xy 365.353 -274.945126) (xy 365.34904 -274.896072)
			(xy 365.020098 -274.896072) (xy 365.019603 -274.920679) (xy 365.011708 -274.969256) (xy 364.996124 -275.015937)
			(xy 364.973253 -275.059514) (xy 364.943688 -275.098858) (xy 364.908195 -275.13295) (xy 364.867692 -275.160906)
			(xy 364.82323 -275.182004) (xy 364.775959 -275.195696) (xy 364.727104 -275.201628) (xy 364.677929 -275.199647)
			(xy 364.62971 -275.189803) (xy 364.583694 -275.172351) (xy 364.541073 -275.147744) (xy 364.502952 -275.116619)
			(xy 364.470317 -275.079782) (xy 364.444014 -275.038186) (xy 364.424723 -274.99291) (xy 364.412946 -274.945126)
			(xy 364.408986 -274.896072) (xy 364.080044 -274.896072) (xy 364.079549 -274.920679) (xy 364.071654 -274.969256)
			(xy 364.05607 -275.015937) (xy 364.033199 -275.059514) (xy 364.003634 -275.098858) (xy 363.968141 -275.13295)
			(xy 363.927638 -275.160906) (xy 363.883176 -275.182004) (xy 363.835905 -275.195696) (xy 363.78705 -275.201628)
			(xy 363.737875 -275.199647) (xy 363.689656 -275.189803) (xy 363.64364 -275.172351) (xy 363.601019 -275.147744)
			(xy 363.562898 -275.116619) (xy 363.530263 -275.079782) (xy 363.50396 -275.038186) (xy 363.484669 -274.99291)
			(xy 363.472892 -274.945126) (xy 363.468932 -274.896072) (xy 356.56647 -274.896072) (xy 356.565975 -274.920679)
			(xy 356.55808 -274.969256) (xy 356.542496 -275.015937) (xy 356.519625 -275.059514) (xy 356.49006 -275.098858)
			(xy 356.454567 -275.13295) (xy 356.414064 -275.160906) (xy 356.369602 -275.182004) (xy 356.322331 -275.195696)
			(xy 356.273476 -275.201628) (xy 356.224301 -275.199647) (xy 356.176082 -275.189803) (xy 356.130066 -275.172351)
			(xy 356.087445 -275.147744) (xy 356.049324 -275.116619) (xy 356.016689 -275.079782) (xy 355.990386 -275.038186)
			(xy 355.971095 -274.99291) (xy 355.959318 -274.945126) (xy 355.955358 -274.896072) (xy 355.626416 -274.896072)
			(xy 355.625921 -274.920679) (xy 355.618026 -274.969256) (xy 355.602442 -275.015937) (xy 355.579571 -275.059514)
			(xy 355.550006 -275.098858) (xy 355.514513 -275.13295) (xy 355.47401 -275.160906) (xy 355.429548 -275.182004)
			(xy 355.382277 -275.195696) (xy 355.333422 -275.201628) (xy 355.284247 -275.199647) (xy 355.236028 -275.189803)
			(xy 355.190012 -275.172351) (xy 355.147391 -275.147744) (xy 355.10927 -275.116619) (xy 355.076635 -275.079782)
			(xy 355.050332 -275.038186) (xy 355.031041 -274.99291) (xy 355.019264 -274.945126) (xy 355.015304 -274.896072)
			(xy 354.686362 -274.896072) (xy 354.685867 -274.920679) (xy 354.677972 -274.969256) (xy 354.662388 -275.015937)
			(xy 354.639517 -275.059514) (xy 354.609952 -275.098858) (xy 354.574459 -275.13295) (xy 354.533956 -275.160906)
			(xy 354.489494 -275.182004) (xy 354.442223 -275.195696) (xy 354.393368 -275.201628) (xy 354.344193 -275.199647)
			(xy 354.295974 -275.189803) (xy 354.249958 -275.172351) (xy 354.207337 -275.147744) (xy 354.169216 -275.116619)
			(xy 354.136581 -275.079782) (xy 354.110278 -275.038186) (xy 354.090987 -274.99291) (xy 354.07921 -274.945126)
			(xy 354.07525 -274.896072) (xy 353.746308 -274.896072) (xy 353.745813 -274.920679) (xy 353.737918 -274.969256)
			(xy 353.722334 -275.015937) (xy 353.699463 -275.059514) (xy 353.669898 -275.098858) (xy 353.634405 -275.13295)
			(xy 353.593902 -275.160906) (xy 353.54944 -275.182004) (xy 353.502169 -275.195696) (xy 353.453314 -275.201628)
			(xy 353.404139 -275.199647) (xy 353.35592 -275.189803) (xy 353.309904 -275.172351) (xy 353.267283 -275.147744)
			(xy 353.229162 -275.116619) (xy 353.196527 -275.079782) (xy 353.170224 -275.038186) (xy 353.150933 -274.99291)
			(xy 353.139156 -274.945126) (xy 353.135196 -274.896072) (xy 352.806508 -274.896072) (xy 352.806013 -274.920679)
			(xy 352.798118 -274.969256) (xy 352.782534 -275.015937) (xy 352.759663 -275.059514) (xy 352.730098 -275.098858)
			(xy 352.694605 -275.13295) (xy 352.654102 -275.160906) (xy 352.60964 -275.182004) (xy 352.562369 -275.195696)
			(xy 352.513514 -275.201628) (xy 352.464339 -275.199647) (xy 352.41612 -275.189803) (xy 352.370104 -275.172351)
			(xy 352.327483 -275.147744) (xy 352.289362 -275.116619) (xy 352.256727 -275.079782) (xy 352.230424 -275.038186)
			(xy 352.211133 -274.99291) (xy 352.199356 -274.945126) (xy 352.195396 -274.896072) (xy 351.866454 -274.896072)
			(xy 351.865959 -274.920679) (xy 351.858064 -274.969256) (xy 351.84248 -275.015937) (xy 351.819609 -275.059514)
			(xy 351.790044 -275.098858) (xy 351.754551 -275.13295) (xy 351.714048 -275.160906) (xy 351.669586 -275.182004)
			(xy 351.622315 -275.195696) (xy 351.57346 -275.201628) (xy 351.524285 -275.199647) (xy 351.476066 -275.189803)
			(xy 351.43005 -275.172351) (xy 351.387429 -275.147744) (xy 351.349308 -275.116619) (xy 351.316673 -275.079782)
			(xy 351.29037 -275.038186) (xy 351.271079 -274.99291) (xy 351.259302 -274.945126) (xy 351.255342 -274.896072)
			(xy 350.9264 -274.896072) (xy 350.925905 -274.920679) (xy 350.91801 -274.969256) (xy 350.902426 -275.015937)
			(xy 350.879555 -275.059514) (xy 350.84999 -275.098858) (xy 350.814497 -275.13295) (xy 350.773994 -275.160906)
			(xy 350.729532 -275.182004) (xy 350.682261 -275.195696) (xy 350.633406 -275.201628) (xy 350.584231 -275.199647)
			(xy 350.536012 -275.189803) (xy 350.489996 -275.172351) (xy 350.447375 -275.147744) (xy 350.409254 -275.116619)
			(xy 350.376619 -275.079782) (xy 350.350316 -275.038186) (xy 350.331025 -274.99291) (xy 350.319248 -274.945126)
			(xy 350.315288 -274.896072) (xy 349.986346 -274.896072) (xy 349.985851 -274.920679) (xy 349.977956 -274.969256)
			(xy 349.962372 -275.015937) (xy 349.939501 -275.059514) (xy 349.909936 -275.098858) (xy 349.874443 -275.13295)
			(xy 349.83394 -275.160906) (xy 349.789478 -275.182004) (xy 349.742207 -275.195696) (xy 349.693352 -275.201628)
			(xy 349.644177 -275.199647) (xy 349.595958 -275.189803) (xy 349.549942 -275.172351) (xy 349.507321 -275.147744)
			(xy 349.4692 -275.116619) (xy 349.436565 -275.079782) (xy 349.410262 -275.038186) (xy 349.390971 -274.99291)
			(xy 349.379194 -274.945126) (xy 349.375234 -274.896072) (xy 349.046546 -274.896072) (xy 349.046051 -274.920679)
			(xy 349.038156 -274.969256) (xy 349.022572 -275.015937) (xy 348.999701 -275.059514) (xy 348.970136 -275.098858)
			(xy 348.934643 -275.13295) (xy 348.89414 -275.160906) (xy 348.849678 -275.182004) (xy 348.802407 -275.195696)
			(xy 348.753552 -275.201628) (xy 348.704377 -275.199647) (xy 348.656158 -275.189803) (xy 348.610142 -275.172351)
			(xy 348.567521 -275.147744) (xy 348.5294 -275.116619) (xy 348.496765 -275.079782) (xy 348.470462 -275.038186)
			(xy 348.451171 -274.99291) (xy 348.439394 -274.945126) (xy 348.435434 -274.896072) (xy 348.106492 -274.896072)
			(xy 348.105997 -274.920679) (xy 348.098102 -274.969256) (xy 348.082518 -275.015937) (xy 348.059647 -275.059514)
			(xy 348.030082 -275.098858) (xy 347.994589 -275.13295) (xy 347.954086 -275.160906) (xy 347.909624 -275.182004)
			(xy 347.862353 -275.195696) (xy 347.813498 -275.201628) (xy 347.764323 -275.199647) (xy 347.716104 -275.189803)
			(xy 347.670088 -275.172351) (xy 347.627467 -275.147744) (xy 347.589346 -275.116619) (xy 347.556711 -275.079782)
			(xy 347.530408 -275.038186) (xy 347.511117 -274.99291) (xy 347.49934 -274.945126) (xy 347.49538 -274.896072)
			(xy 347.166438 -274.896072) (xy 347.165943 -274.920679) (xy 347.158048 -274.969256) (xy 347.142464 -275.015937)
			(xy 347.119593 -275.059514) (xy 347.090028 -275.098858) (xy 347.054535 -275.13295) (xy 347.014032 -275.160906)
			(xy 346.96957 -275.182004) (xy 346.922299 -275.195696) (xy 346.873444 -275.201628) (xy 346.824269 -275.199647)
			(xy 346.77605 -275.189803) (xy 346.730034 -275.172351) (xy 346.687413 -275.147744) (xy 346.649292 -275.116619)
			(xy 346.616657 -275.079782) (xy 346.590354 -275.038186) (xy 346.571063 -274.99291) (xy 346.559286 -274.945126)
			(xy 346.555326 -274.896072) (xy 346.226384 -274.896072) (xy 346.225889 -274.920679) (xy 346.217994 -274.969256)
			(xy 346.20241 -275.015937) (xy 346.179539 -275.059514) (xy 346.149974 -275.098858) (xy 346.114481 -275.13295)
			(xy 346.073978 -275.160906) (xy 346.029516 -275.182004) (xy 345.982245 -275.195696) (xy 345.93339 -275.201628)
			(xy 345.884215 -275.199647) (xy 345.835996 -275.189803) (xy 345.78998 -275.172351) (xy 345.747359 -275.147744)
			(xy 345.709238 -275.116619) (xy 345.676603 -275.079782) (xy 345.6503 -275.038186) (xy 345.631009 -274.99291)
			(xy 345.619232 -274.945126) (xy 345.615272 -274.896072) (xy 345.286857 -274.896072) (xy 345.286859 -274.8961)
			(xy 345.282692 -274.946414) (xy 345.270306 -274.995357) (xy 345.250037 -275.041596) (xy 345.222437 -275.083871)
			(xy 345.18826 -275.121029) (xy 345.148435 -275.152059) (xy 345.104049 -275.176116) (xy 345.05631 -275.192543)
			(xy 345.006519 -275.200893) (xy 344.981276 -275.20138) (xy 344.971207 -275.201807) (xy 344.952607 -275.209525)
			(xy 344.945208 -275.216366) (xy 344.895424 -275.26615) (xy 344.888713 -275.273388) (xy 344.881127 -275.291594)
			(xy 344.880692 -275.301456) (xy 344.880692 -275.706078) (xy 347.025226 -275.706078) (xy 347.029186 -275.657024)
			(xy 347.040963 -275.60924) (xy 347.060254 -275.563964) (xy 347.086557 -275.522368) (xy 347.119192 -275.485531)
			(xy 347.157313 -275.454406) (xy 347.199934 -275.429799) (xy 347.24595 -275.412347) (xy 347.294169 -275.402503)
			(xy 347.343344 -275.400522) (xy 347.392199 -275.406454) (xy 347.43947 -275.420146) (xy 347.483932 -275.441244)
			(xy 347.524435 -275.4692) (xy 347.559928 -275.503292) (xy 347.589493 -275.542636) (xy 347.612364 -275.586213)
			(xy 347.627948 -275.632894) (xy 347.635843 -275.681471) (xy 347.636338 -275.706078) (xy 349.845388 -275.706078)
			(xy 349.849348 -275.657024) (xy 349.861125 -275.60924) (xy 349.880416 -275.563964) (xy 349.906719 -275.522368)
			(xy 349.939354 -275.485531) (xy 349.977475 -275.454406) (xy 350.020096 -275.429799) (xy 350.066112 -275.412347)
			(xy 350.114331 -275.402503) (xy 350.163506 -275.400522) (xy 350.212361 -275.406454) (xy 350.259632 -275.420146)
			(xy 350.304094 -275.441244) (xy 350.344597 -275.4692) (xy 350.38009 -275.503292) (xy 350.409655 -275.542636)
			(xy 350.432526 -275.586213) (xy 350.44811 -275.632894) (xy 350.456005 -275.681471) (xy 350.4565 -275.706078)
			(xy 352.665296 -275.706078) (xy 352.669256 -275.657024) (xy 352.681033 -275.60924) (xy 352.700324 -275.563964)
			(xy 352.726627 -275.522368) (xy 352.759262 -275.485531) (xy 352.797383 -275.454406) (xy 352.840004 -275.429799)
			(xy 352.88602 -275.412347) (xy 352.934239 -275.402503) (xy 352.983414 -275.400522) (xy 353.032269 -275.406454)
			(xy 353.07954 -275.420146) (xy 353.124002 -275.441244) (xy 353.164505 -275.4692) (xy 353.199998 -275.503292)
			(xy 353.229563 -275.542636) (xy 353.252434 -275.586213) (xy 353.268018 -275.632894) (xy 353.275913 -275.681471)
			(xy 353.276408 -275.706078) (xy 355.485204 -275.706078) (xy 355.489164 -275.657024) (xy 355.500941 -275.60924)
			(xy 355.520232 -275.563964) (xy 355.546535 -275.522368) (xy 355.57917 -275.485531) (xy 355.617291 -275.454406)
			(xy 355.659912 -275.429799) (xy 355.705928 -275.412347) (xy 355.754147 -275.402503) (xy 355.803322 -275.400522)
			(xy 355.852177 -275.406454) (xy 355.899448 -275.420146) (xy 355.94391 -275.441244) (xy 355.984413 -275.4692)
			(xy 356.019906 -275.503292) (xy 356.049471 -275.542636) (xy 356.072342 -275.586213) (xy 356.087926 -275.632894)
			(xy 356.095821 -275.681471) (xy 356.096316 -275.706078) (xy 356.425258 -275.706078) (xy 356.429218 -275.657024)
			(xy 356.440995 -275.60924) (xy 356.460286 -275.563964) (xy 356.486589 -275.522368) (xy 356.519224 -275.485531)
			(xy 356.557345 -275.454406) (xy 356.599966 -275.429799) (xy 356.645982 -275.412347) (xy 356.694201 -275.402503)
			(xy 356.743376 -275.400522) (xy 356.792231 -275.406454) (xy 356.839502 -275.420146) (xy 356.883964 -275.441244)
			(xy 356.924467 -275.4692) (xy 356.95996 -275.503292) (xy 356.989525 -275.542636) (xy 357.012396 -275.586213)
			(xy 357.02798 -275.632894) (xy 357.035875 -275.681471) (xy 357.03637 -275.706078) (xy 357.365312 -275.706078)
			(xy 357.369272 -275.657024) (xy 357.381049 -275.60924) (xy 357.40034 -275.563964) (xy 357.426643 -275.522368)
			(xy 357.459278 -275.485531) (xy 357.497399 -275.454406) (xy 357.54002 -275.429799) (xy 357.586036 -275.412347)
			(xy 357.634255 -275.402503) (xy 357.68343 -275.400522) (xy 357.732285 -275.406454) (xy 357.779556 -275.420146)
			(xy 357.824018 -275.441244) (xy 357.864521 -275.4692) (xy 357.900014 -275.503292) (xy 357.929579 -275.542636)
			(xy 357.95245 -275.586213) (xy 357.968034 -275.632894) (xy 357.975929 -275.681471) (xy 357.976424 -275.706078)
			(xy 358.305366 -275.706078) (xy 358.309326 -275.657024) (xy 358.321103 -275.60924) (xy 358.340394 -275.563964)
			(xy 358.366697 -275.522368) (xy 358.399332 -275.485531) (xy 358.437453 -275.454406) (xy 358.480074 -275.429799)
			(xy 358.52609 -275.412347) (xy 358.574309 -275.402503) (xy 358.623484 -275.400522) (xy 358.672339 -275.406454)
			(xy 358.71961 -275.420146) (xy 358.764072 -275.441244) (xy 358.804575 -275.4692) (xy 358.840068 -275.503292)
			(xy 358.869633 -275.542636) (xy 358.892504 -275.586213) (xy 358.908088 -275.632894) (xy 358.915983 -275.681471)
			(xy 358.916478 -275.706078) (xy 361.118924 -275.706078) (xy 361.122884 -275.657024) (xy 361.134661 -275.60924)
			(xy 361.153952 -275.563964) (xy 361.180255 -275.522368) (xy 361.21289 -275.485531) (xy 361.251011 -275.454406)
			(xy 361.293632 -275.429799) (xy 361.339648 -275.412347) (xy 361.387867 -275.402503) (xy 361.437042 -275.400522)
			(xy 361.485897 -275.406454) (xy 361.533168 -275.420146) (xy 361.57763 -275.441244) (xy 361.618133 -275.4692)
			(xy 361.653626 -275.503292) (xy 361.683191 -275.542636) (xy 361.706062 -275.586213) (xy 361.721646 -275.632894)
			(xy 361.729541 -275.681471) (xy 361.730036 -275.706078) (xy 362.058978 -275.706078) (xy 362.062938 -275.657024)
			(xy 362.074715 -275.60924) (xy 362.094006 -275.563964) (xy 362.120309 -275.522368) (xy 362.152944 -275.485531)
			(xy 362.191065 -275.454406) (xy 362.233686 -275.429799) (xy 362.279702 -275.412347) (xy 362.327921 -275.402503)
			(xy 362.377096 -275.400522) (xy 362.425951 -275.406454) (xy 362.473222 -275.420146) (xy 362.517684 -275.441244)
			(xy 362.558187 -275.4692) (xy 362.59368 -275.503292) (xy 362.623245 -275.542636) (xy 362.646116 -275.586213)
			(xy 362.6617 -275.632894) (xy 362.669595 -275.681471) (xy 362.67009 -275.706078) (xy 362.999032 -275.706078)
			(xy 363.002992 -275.657024) (xy 363.014769 -275.60924) (xy 363.03406 -275.563964) (xy 363.060363 -275.522368)
			(xy 363.092998 -275.485531) (xy 363.131119 -275.454406) (xy 363.17374 -275.429799) (xy 363.219756 -275.412347)
			(xy 363.267975 -275.402503) (xy 363.31715 -275.400522) (xy 363.366005 -275.406454) (xy 363.413276 -275.420146)
			(xy 363.457738 -275.441244) (xy 363.498241 -275.4692) (xy 363.533734 -275.503292) (xy 363.563299 -275.542636)
			(xy 363.58617 -275.586213) (xy 363.601754 -275.632894) (xy 363.609649 -275.681471) (xy 363.610144 -275.706078)
			(xy 363.939086 -275.706078) (xy 363.943046 -275.657024) (xy 363.954823 -275.60924) (xy 363.974114 -275.563964)
			(xy 364.000417 -275.522368) (xy 364.033052 -275.485531) (xy 364.071173 -275.454406) (xy 364.113794 -275.429799)
			(xy 364.15981 -275.412347) (xy 364.208029 -275.402503) (xy 364.257204 -275.400522) (xy 364.306059 -275.406454)
			(xy 364.35333 -275.420146) (xy 364.397792 -275.441244) (xy 364.438295 -275.4692) (xy 364.473788 -275.503292)
			(xy 364.503353 -275.542636) (xy 364.526224 -275.586213) (xy 364.541808 -275.632894) (xy 364.549703 -275.681471)
			(xy 364.550198 -275.706078) (xy 366.758994 -275.706078) (xy 366.762954 -275.657024) (xy 366.774731 -275.60924)
			(xy 366.794022 -275.563964) (xy 366.820325 -275.522368) (xy 366.85296 -275.485531) (xy 366.891081 -275.454406)
			(xy 366.933702 -275.429799) (xy 366.979718 -275.412347) (xy 367.027937 -275.402503) (xy 367.077112 -275.400522)
			(xy 367.125967 -275.406454) (xy 367.173238 -275.420146) (xy 367.2177 -275.441244) (xy 367.258203 -275.4692)
			(xy 367.293696 -275.503292) (xy 367.323261 -275.542636) (xy 367.346132 -275.586213) (xy 367.361716 -275.632894)
			(xy 367.369611 -275.681471) (xy 367.370106 -275.706078) (xy 369.578902 -275.706078) (xy 369.582862 -275.657024)
			(xy 369.594639 -275.60924) (xy 369.61393 -275.563964) (xy 369.640233 -275.522368) (xy 369.672868 -275.485531)
			(xy 369.710989 -275.454406) (xy 369.75361 -275.429799) (xy 369.799626 -275.412347) (xy 369.847845 -275.402503)
			(xy 369.89702 -275.400522) (xy 369.945875 -275.406454) (xy 369.993146 -275.420146) (xy 370.037608 -275.441244)
			(xy 370.078111 -275.4692) (xy 370.113604 -275.503292) (xy 370.143169 -275.542636) (xy 370.16604 -275.586213)
			(xy 370.181624 -275.632894) (xy 370.189519 -275.681471) (xy 370.190014 -275.706078) (xy 372.399064 -275.706078)
			(xy 372.403024 -275.657024) (xy 372.414801 -275.60924) (xy 372.434092 -275.563964) (xy 372.460395 -275.522368)
			(xy 372.49303 -275.485531) (xy 372.531151 -275.454406) (xy 372.573772 -275.429799) (xy 372.619788 -275.412347)
			(xy 372.668007 -275.402503) (xy 372.717182 -275.400522) (xy 372.766037 -275.406454) (xy 372.813308 -275.420146)
			(xy 372.85777 -275.441244) (xy 372.898273 -275.4692) (xy 372.933766 -275.503292) (xy 372.963331 -275.542636)
			(xy 372.986202 -275.586213) (xy 373.001786 -275.632894) (xy 373.009681 -275.681471) (xy 373.010176 -275.706078)
			(xy 373.009681 -275.730685) (xy 373.001786 -275.779262) (xy 372.986202 -275.825943) (xy 372.963331 -275.86952)
			(xy 372.933766 -275.908864) (xy 372.898273 -275.942956) (xy 372.85777 -275.970912) (xy 372.813308 -275.99201)
			(xy 372.766037 -276.005702) (xy 372.717182 -276.011634) (xy 372.668007 -276.009653) (xy 372.619788 -275.999809)
			(xy 372.573772 -275.982357) (xy 372.531151 -275.95775) (xy 372.49303 -275.926625) (xy 372.460395 -275.889788)
			(xy 372.434092 -275.848192) (xy 372.414801 -275.802916) (xy 372.403024 -275.755132) (xy 372.399064 -275.706078)
			(xy 370.190014 -275.706078) (xy 370.189519 -275.730685) (xy 370.181624 -275.779262) (xy 370.16604 -275.825943)
			(xy 370.143169 -275.86952) (xy 370.113604 -275.908864) (xy 370.078111 -275.942956) (xy 370.037608 -275.970912)
			(xy 369.993146 -275.99201) (xy 369.945875 -276.005702) (xy 369.89702 -276.011634) (xy 369.847845 -276.009653)
			(xy 369.799626 -275.999809) (xy 369.75361 -275.982357) (xy 369.710989 -275.95775) (xy 369.672868 -275.926625)
			(xy 369.640233 -275.889788) (xy 369.61393 -275.848192) (xy 369.594639 -275.802916) (xy 369.582862 -275.755132)
			(xy 369.578902 -275.706078) (xy 367.370106 -275.706078) (xy 367.369611 -275.730685) (xy 367.361716 -275.779262)
			(xy 367.346132 -275.825943) (xy 367.323261 -275.86952) (xy 367.293696 -275.908864) (xy 367.258203 -275.942956)
			(xy 367.2177 -275.970912) (xy 367.173238 -275.99201) (xy 367.125967 -276.005702) (xy 367.077112 -276.011634)
			(xy 367.027937 -276.009653) (xy 366.979718 -275.999809) (xy 366.933702 -275.982357) (xy 366.891081 -275.95775)
			(xy 366.85296 -275.926625) (xy 366.820325 -275.889788) (xy 366.794022 -275.848192) (xy 366.774731 -275.802916)
			(xy 366.762954 -275.755132) (xy 366.758994 -275.706078) (xy 364.550198 -275.706078) (xy 364.549703 -275.730685)
			(xy 364.541808 -275.779262) (xy 364.526224 -275.825943) (xy 364.503353 -275.86952) (xy 364.473788 -275.908864)
			(xy 364.438295 -275.942956) (xy 364.397792 -275.970912) (xy 364.35333 -275.99201) (xy 364.306059 -276.005702)
			(xy 364.257204 -276.011634) (xy 364.208029 -276.009653) (xy 364.15981 -275.999809) (xy 364.113794 -275.982357)
			(xy 364.071173 -275.95775) (xy 364.033052 -275.926625) (xy 364.000417 -275.889788) (xy 363.974114 -275.848192)
			(xy 363.954823 -275.802916) (xy 363.943046 -275.755132) (xy 363.939086 -275.706078) (xy 363.610144 -275.706078)
			(xy 363.609649 -275.730685) (xy 363.601754 -275.779262) (xy 363.58617 -275.825943) (xy 363.563299 -275.86952)
			(xy 363.533734 -275.908864) (xy 363.498241 -275.942956) (xy 363.457738 -275.970912) (xy 363.413276 -275.99201)
			(xy 363.366005 -276.005702) (xy 363.31715 -276.011634) (xy 363.267975 -276.009653) (xy 363.219756 -275.999809)
			(xy 363.17374 -275.982357) (xy 363.131119 -275.95775) (xy 363.092998 -275.926625) (xy 363.060363 -275.889788)
			(xy 363.03406 -275.848192) (xy 363.014769 -275.802916) (xy 363.002992 -275.755132) (xy 362.999032 -275.706078)
			(xy 362.67009 -275.706078) (xy 362.669595 -275.730685) (xy 362.6617 -275.779262) (xy 362.646116 -275.825943)
			(xy 362.623245 -275.86952) (xy 362.59368 -275.908864) (xy 362.558187 -275.942956) (xy 362.517684 -275.970912)
			(xy 362.473222 -275.99201) (xy 362.425951 -276.005702) (xy 362.377096 -276.011634) (xy 362.327921 -276.009653)
			(xy 362.279702 -275.999809) (xy 362.233686 -275.982357) (xy 362.191065 -275.95775) (xy 362.152944 -275.926625)
			(xy 362.120309 -275.889788) (xy 362.094006 -275.848192) (xy 362.074715 -275.802916) (xy 362.062938 -275.755132)
			(xy 362.058978 -275.706078) (xy 361.730036 -275.706078) (xy 361.729541 -275.730685) (xy 361.721646 -275.779262)
			(xy 361.706062 -275.825943) (xy 361.683191 -275.86952) (xy 361.653626 -275.908864) (xy 361.618133 -275.942956)
			(xy 361.57763 -275.970912) (xy 361.533168 -275.99201) (xy 361.485897 -276.005702) (xy 361.437042 -276.011634)
			(xy 361.387867 -276.009653) (xy 361.339648 -275.999809) (xy 361.293632 -275.982357) (xy 361.251011 -275.95775)
			(xy 361.21289 -275.926625) (xy 361.180255 -275.889788) (xy 361.153952 -275.848192) (xy 361.134661 -275.802916)
			(xy 361.122884 -275.755132) (xy 361.118924 -275.706078) (xy 358.916478 -275.706078) (xy 358.915983 -275.730685)
			(xy 358.908088 -275.779262) (xy 358.892504 -275.825943) (xy 358.869633 -275.86952) (xy 358.840068 -275.908864)
			(xy 358.804575 -275.942956) (xy 358.764072 -275.970912) (xy 358.71961 -275.99201) (xy 358.672339 -276.005702)
			(xy 358.623484 -276.011634) (xy 358.574309 -276.009653) (xy 358.52609 -275.999809) (xy 358.480074 -275.982357)
			(xy 358.437453 -275.95775) (xy 358.399332 -275.926625) (xy 358.366697 -275.889788) (xy 358.340394 -275.848192)
			(xy 358.321103 -275.802916) (xy 358.309326 -275.755132) (xy 358.305366 -275.706078) (xy 357.976424 -275.706078)
			(xy 357.975929 -275.730685) (xy 357.968034 -275.779262) (xy 357.95245 -275.825943) (xy 357.929579 -275.86952)
			(xy 357.900014 -275.908864) (xy 357.864521 -275.942956) (xy 357.824018 -275.970912) (xy 357.779556 -275.99201)
			(xy 357.732285 -276.005702) (xy 357.68343 -276.011634) (xy 357.634255 -276.009653) (xy 357.586036 -275.999809)
			(xy 357.54002 -275.982357) (xy 357.497399 -275.95775) (xy 357.459278 -275.926625) (xy 357.426643 -275.889788)
			(xy 357.40034 -275.848192) (xy 357.381049 -275.802916) (xy 357.369272 -275.755132) (xy 357.365312 -275.706078)
			(xy 357.03637 -275.706078) (xy 357.035875 -275.730685) (xy 357.02798 -275.779262) (xy 357.012396 -275.825943)
			(xy 356.989525 -275.86952) (xy 356.95996 -275.908864) (xy 356.924467 -275.942956) (xy 356.883964 -275.970912)
			(xy 356.839502 -275.99201) (xy 356.792231 -276.005702) (xy 356.743376 -276.011634) (xy 356.694201 -276.009653)
			(xy 356.645982 -275.999809) (xy 356.599966 -275.982357) (xy 356.557345 -275.95775) (xy 356.519224 -275.926625)
			(xy 356.486589 -275.889788) (xy 356.460286 -275.848192) (xy 356.440995 -275.802916) (xy 356.429218 -275.755132)
			(xy 356.425258 -275.706078) (xy 356.096316 -275.706078) (xy 356.095821 -275.730685) (xy 356.087926 -275.779262)
			(xy 356.072342 -275.825943) (xy 356.049471 -275.86952) (xy 356.019906 -275.908864) (xy 355.984413 -275.942956)
			(xy 355.94391 -275.970912) (xy 355.899448 -275.99201) (xy 355.852177 -276.005702) (xy 355.803322 -276.011634)
			(xy 355.754147 -276.009653) (xy 355.705928 -275.999809) (xy 355.659912 -275.982357) (xy 355.617291 -275.95775)
			(xy 355.57917 -275.926625) (xy 355.546535 -275.889788) (xy 355.520232 -275.848192) (xy 355.500941 -275.802916)
			(xy 355.489164 -275.755132) (xy 355.485204 -275.706078) (xy 353.276408 -275.706078) (xy 353.275913 -275.730685)
			(xy 353.268018 -275.779262) (xy 353.252434 -275.825943) (xy 353.229563 -275.86952) (xy 353.199998 -275.908864)
			(xy 353.164505 -275.942956) (xy 353.124002 -275.970912) (xy 353.07954 -275.99201) (xy 353.032269 -276.005702)
			(xy 352.983414 -276.011634) (xy 352.934239 -276.009653) (xy 352.88602 -275.999809) (xy 352.840004 -275.982357)
			(xy 352.797383 -275.95775) (xy 352.759262 -275.926625) (xy 352.726627 -275.889788) (xy 352.700324 -275.848192)
			(xy 352.681033 -275.802916) (xy 352.669256 -275.755132) (xy 352.665296 -275.706078) (xy 350.4565 -275.706078)
			(xy 350.456005 -275.730685) (xy 350.44811 -275.779262) (xy 350.432526 -275.825943) (xy 350.409655 -275.86952)
			(xy 350.38009 -275.908864) (xy 350.344597 -275.942956) (xy 350.304094 -275.970912) (xy 350.259632 -275.99201)
			(xy 350.212361 -276.005702) (xy 350.163506 -276.011634) (xy 350.114331 -276.009653) (xy 350.066112 -275.999809)
			(xy 350.020096 -275.982357) (xy 349.977475 -275.95775) (xy 349.939354 -275.926625) (xy 349.906719 -275.889788)
			(xy 349.880416 -275.848192) (xy 349.861125 -275.802916) (xy 349.849348 -275.755132) (xy 349.845388 -275.706078)
			(xy 347.636338 -275.706078) (xy 347.635843 -275.730685) (xy 347.627948 -275.779262) (xy 347.612364 -275.825943)
			(xy 347.589493 -275.86952) (xy 347.559928 -275.908864) (xy 347.524435 -275.942956) (xy 347.483932 -275.970912)
			(xy 347.43947 -275.99201) (xy 347.392199 -276.005702) (xy 347.343344 -276.011634) (xy 347.294169 -276.009653)
			(xy 347.24595 -275.999809) (xy 347.199934 -275.982357) (xy 347.157313 -275.95775) (xy 347.119192 -275.926625)
			(xy 347.086557 -275.889788) (xy 347.060254 -275.848192) (xy 347.040963 -275.802916) (xy 347.029186 -275.755132)
			(xy 347.025226 -275.706078) (xy 344.880692 -275.706078) (xy 344.880692 -276.110192) (xy 344.881165 -276.120063)
			(xy 344.888626 -276.138344) (xy 344.89517 -276.145752) (xy 344.895424 -276.146006) (xy 344.945208 -276.19579)
			(xy 344.952607 -276.202636) (xy 344.971205 -276.210369) (xy 344.981276 -276.210776) (xy 345.006518 -276.211319)
			(xy 345.056307 -276.219669) (xy 345.104044 -276.236095) (xy 345.148429 -276.260151) (xy 345.188252 -276.29118)
			(xy 345.222428 -276.328337) (xy 345.250026 -276.37061) (xy 345.270294 -276.416847) (xy 345.282681 -276.465788)
			(xy 345.286846 -276.516084) (xy 345.615272 -276.516084) (xy 345.619232 -276.46703) (xy 345.631009 -276.419246)
			(xy 345.6503 -276.37397) (xy 345.676603 -276.332374) (xy 345.709238 -276.295537) (xy 345.747359 -276.264412)
			(xy 345.78998 -276.239805) (xy 345.835996 -276.222353) (xy 345.884215 -276.212509) (xy 345.93339 -276.210528)
			(xy 345.982245 -276.21646) (xy 346.029516 -276.230152) (xy 346.073978 -276.25125) (xy 346.114481 -276.279206)
			(xy 346.149974 -276.313298) (xy 346.179539 -276.352642) (xy 346.20241 -276.396219) (xy 346.217994 -276.4429)
			(xy 346.225889 -276.491477) (xy 346.226384 -276.516084) (xy 346.555326 -276.516084) (xy 346.559286 -276.46703)
			(xy 346.571063 -276.419246) (xy 346.590354 -276.37397) (xy 346.616657 -276.332374) (xy 346.649292 -276.295537)
			(xy 346.687413 -276.264412) (xy 346.730034 -276.239805) (xy 346.77605 -276.222353) (xy 346.824269 -276.212509)
			(xy 346.873444 -276.210528) (xy 346.922299 -276.21646) (xy 346.96957 -276.230152) (xy 347.014032 -276.25125)
			(xy 347.054535 -276.279206) (xy 347.090028 -276.313298) (xy 347.119593 -276.352642) (xy 347.142464 -276.396219)
			(xy 347.158048 -276.4429) (xy 347.165943 -276.491477) (xy 347.166438 -276.516084) (xy 347.49538 -276.516084)
			(xy 347.49934 -276.46703) (xy 347.511117 -276.419246) (xy 347.530408 -276.37397) (xy 347.556711 -276.332374)
			(xy 347.589346 -276.295537) (xy 347.627467 -276.264412) (xy 347.670088 -276.239805) (xy 347.716104 -276.222353)
			(xy 347.764323 -276.212509) (xy 347.813498 -276.210528) (xy 347.862353 -276.21646) (xy 347.909624 -276.230152)
			(xy 347.954086 -276.25125) (xy 347.994589 -276.279206) (xy 348.030082 -276.313298) (xy 348.059647 -276.352642)
			(xy 348.082518 -276.396219) (xy 348.098102 -276.4429) (xy 348.105997 -276.491477) (xy 348.106492 -276.516084)
			(xy 348.435434 -276.516084) (xy 348.439394 -276.46703) (xy 348.451171 -276.419246) (xy 348.470462 -276.37397)
			(xy 348.496765 -276.332374) (xy 348.5294 -276.295537) (xy 348.567521 -276.264412) (xy 348.610142 -276.239805)
			(xy 348.656158 -276.222353) (xy 348.704377 -276.212509) (xy 348.753552 -276.210528) (xy 348.802407 -276.21646)
			(xy 348.849678 -276.230152) (xy 348.89414 -276.25125) (xy 348.934643 -276.279206) (xy 348.970136 -276.313298)
			(xy 348.999701 -276.352642) (xy 349.022572 -276.396219) (xy 349.038156 -276.4429) (xy 349.046051 -276.491477)
			(xy 349.046546 -276.516084) (xy 349.375234 -276.516084) (xy 349.379194 -276.46703) (xy 349.390971 -276.419246)
			(xy 349.410262 -276.37397) (xy 349.436565 -276.332374) (xy 349.4692 -276.295537) (xy 349.507321 -276.264412)
			(xy 349.549942 -276.239805) (xy 349.595958 -276.222353) (xy 349.644177 -276.212509) (xy 349.693352 -276.210528)
			(xy 349.742207 -276.21646) (xy 349.789478 -276.230152) (xy 349.83394 -276.25125) (xy 349.874443 -276.279206)
			(xy 349.909936 -276.313298) (xy 349.939501 -276.352642) (xy 349.962372 -276.396219) (xy 349.977956 -276.4429)
			(xy 349.985851 -276.491477) (xy 349.986346 -276.516084) (xy 350.315288 -276.516084) (xy 350.319248 -276.46703)
			(xy 350.331025 -276.419246) (xy 350.350316 -276.37397) (xy 350.376619 -276.332374) (xy 350.409254 -276.295537)
			(xy 350.447375 -276.264412) (xy 350.489996 -276.239805) (xy 350.536012 -276.222353) (xy 350.584231 -276.212509)
			(xy 350.633406 -276.210528) (xy 350.682261 -276.21646) (xy 350.729532 -276.230152) (xy 350.773994 -276.25125)
			(xy 350.814497 -276.279206) (xy 350.84999 -276.313298) (xy 350.879555 -276.352642) (xy 350.902426 -276.396219)
			(xy 350.91801 -276.4429) (xy 350.925905 -276.491477) (xy 350.9264 -276.516084) (xy 351.255342 -276.516084)
			(xy 351.259302 -276.46703) (xy 351.271079 -276.419246) (xy 351.29037 -276.37397) (xy 351.316673 -276.332374)
			(xy 351.349308 -276.295537) (xy 351.387429 -276.264412) (xy 351.43005 -276.239805) (xy 351.476066 -276.222353)
			(xy 351.524285 -276.212509) (xy 351.57346 -276.210528) (xy 351.622315 -276.21646) (xy 351.669586 -276.230152)
			(xy 351.714048 -276.25125) (xy 351.754551 -276.279206) (xy 351.790044 -276.313298) (xy 351.819609 -276.352642)
			(xy 351.84248 -276.396219) (xy 351.858064 -276.4429) (xy 351.865959 -276.491477) (xy 351.866454 -276.516084)
			(xy 352.195396 -276.516084) (xy 352.199356 -276.46703) (xy 352.211133 -276.419246) (xy 352.230424 -276.37397)
			(xy 352.256727 -276.332374) (xy 352.289362 -276.295537) (xy 352.327483 -276.264412) (xy 352.370104 -276.239805)
			(xy 352.41612 -276.222353) (xy 352.464339 -276.212509) (xy 352.513514 -276.210528) (xy 352.562369 -276.21646)
			(xy 352.60964 -276.230152) (xy 352.654102 -276.25125) (xy 352.694605 -276.279206) (xy 352.730098 -276.313298)
			(xy 352.759663 -276.352642) (xy 352.782534 -276.396219) (xy 352.798118 -276.4429) (xy 352.806013 -276.491477)
			(xy 352.806508 -276.516084) (xy 353.135196 -276.516084) (xy 353.139156 -276.46703) (xy 353.150933 -276.419246)
			(xy 353.170224 -276.37397) (xy 353.196527 -276.332374) (xy 353.229162 -276.295537) (xy 353.267283 -276.264412)
			(xy 353.309904 -276.239805) (xy 353.35592 -276.222353) (xy 353.404139 -276.212509) (xy 353.453314 -276.210528)
			(xy 353.502169 -276.21646) (xy 353.54944 -276.230152) (xy 353.593902 -276.25125) (xy 353.634405 -276.279206)
			(xy 353.669898 -276.313298) (xy 353.699463 -276.352642) (xy 353.722334 -276.396219) (xy 353.737918 -276.4429)
			(xy 353.745813 -276.491477) (xy 353.746308 -276.516084) (xy 354.07525 -276.516084) (xy 354.07921 -276.46703)
			(xy 354.090987 -276.419246) (xy 354.110278 -276.37397) (xy 354.136581 -276.332374) (xy 354.169216 -276.295537)
			(xy 354.207337 -276.264412) (xy 354.249958 -276.239805) (xy 354.295974 -276.222353) (xy 354.344193 -276.212509)
			(xy 354.393368 -276.210528) (xy 354.442223 -276.21646) (xy 354.489494 -276.230152) (xy 354.533956 -276.25125)
			(xy 354.574459 -276.279206) (xy 354.609952 -276.313298) (xy 354.639517 -276.352642) (xy 354.662388 -276.396219)
			(xy 354.677972 -276.4429) (xy 354.685867 -276.491477) (xy 354.686362 -276.516084) (xy 355.015304 -276.516084)
			(xy 355.019264 -276.46703) (xy 355.031041 -276.419246) (xy 355.050332 -276.37397) (xy 355.076635 -276.332374)
			(xy 355.10927 -276.295537) (xy 355.147391 -276.264412) (xy 355.190012 -276.239805) (xy 355.236028 -276.222353)
			(xy 355.284247 -276.212509) (xy 355.333422 -276.210528) (xy 355.382277 -276.21646) (xy 355.429548 -276.230152)
			(xy 355.47401 -276.25125) (xy 355.514513 -276.279206) (xy 355.550006 -276.313298) (xy 355.579571 -276.352642)
			(xy 355.602442 -276.396219) (xy 355.618026 -276.4429) (xy 355.625921 -276.491477) (xy 355.626416 -276.516084)
			(xy 355.955358 -276.516084) (xy 355.959318 -276.46703) (xy 355.971095 -276.419246) (xy 355.990386 -276.37397)
			(xy 356.016689 -276.332374) (xy 356.049324 -276.295537) (xy 356.087445 -276.264412) (xy 356.130066 -276.239805)
			(xy 356.176082 -276.222353) (xy 356.224301 -276.212509) (xy 356.273476 -276.210528) (xy 356.322331 -276.21646)
			(xy 356.369602 -276.230152) (xy 356.414064 -276.25125) (xy 356.454567 -276.279206) (xy 356.49006 -276.313298)
			(xy 356.519625 -276.352642) (xy 356.542496 -276.396219) (xy 356.55808 -276.4429) (xy 356.565975 -276.491477)
			(xy 356.56647 -276.516084) (xy 356.895412 -276.516084) (xy 356.899372 -276.46703) (xy 356.911149 -276.419246)
			(xy 356.93044 -276.37397) (xy 356.956743 -276.332374) (xy 356.989378 -276.295537) (xy 357.027499 -276.264412)
			(xy 357.07012 -276.239805) (xy 357.116136 -276.222353) (xy 357.164355 -276.212509) (xy 357.21353 -276.210528)
			(xy 357.262385 -276.21646) (xy 357.309656 -276.230152) (xy 357.354118 -276.25125) (xy 357.394621 -276.279206)
			(xy 357.430114 -276.313298) (xy 357.459679 -276.352642) (xy 357.48255 -276.396219) (xy 357.498134 -276.4429)
			(xy 357.506029 -276.491477) (xy 357.506524 -276.516084) (xy 357.835212 -276.516084) (xy 357.839172 -276.46703)
			(xy 357.850949 -276.419246) (xy 357.87024 -276.37397) (xy 357.896543 -276.332374) (xy 357.929178 -276.295537)
			(xy 357.967299 -276.264412) (xy 358.00992 -276.239805) (xy 358.055936 -276.222353) (xy 358.104155 -276.212509)
			(xy 358.15333 -276.210528) (xy 358.202185 -276.21646) (xy 358.249456 -276.230152) (xy 358.293918 -276.25125)
			(xy 358.334421 -276.279206) (xy 358.369914 -276.313298) (xy 358.399479 -276.352642) (xy 358.42235 -276.396219)
			(xy 358.437934 -276.4429) (xy 358.445829 -276.491477) (xy 358.446324 -276.516084) (xy 361.589078 -276.516084)
			(xy 361.593038 -276.46703) (xy 361.604815 -276.419246) (xy 361.624106 -276.37397) (xy 361.650409 -276.332374)
			(xy 361.683044 -276.295537) (xy 361.721165 -276.264412) (xy 361.763786 -276.239805) (xy 361.809802 -276.222353)
			(xy 361.858021 -276.212509) (xy 361.907196 -276.210528) (xy 361.956051 -276.21646) (xy 362.003322 -276.230152)
			(xy 362.047784 -276.25125) (xy 362.088287 -276.279206) (xy 362.12378 -276.313298) (xy 362.153345 -276.352642)
			(xy 362.176216 -276.396219) (xy 362.1918 -276.4429) (xy 362.199695 -276.491477) (xy 362.20019 -276.516084)
			(xy 362.528878 -276.516084) (xy 362.532838 -276.46703) (xy 362.544615 -276.419246) (xy 362.563906 -276.37397)
			(xy 362.590209 -276.332374) (xy 362.622844 -276.295537) (xy 362.660965 -276.264412) (xy 362.703586 -276.239805)
			(xy 362.749602 -276.222353) (xy 362.797821 -276.212509) (xy 362.846996 -276.210528) (xy 362.895851 -276.21646)
			(xy 362.943122 -276.230152) (xy 362.987584 -276.25125) (xy 363.028087 -276.279206) (xy 363.06358 -276.313298)
			(xy 363.093145 -276.352642) (xy 363.116016 -276.396219) (xy 363.1316 -276.4429) (xy 363.139495 -276.491477)
			(xy 363.13999 -276.516084) (xy 363.468932 -276.516084) (xy 363.472892 -276.46703) (xy 363.484669 -276.419246)
			(xy 363.50396 -276.37397) (xy 363.530263 -276.332374) (xy 363.562898 -276.295537) (xy 363.601019 -276.264412)
			(xy 363.64364 -276.239805) (xy 363.689656 -276.222353) (xy 363.737875 -276.212509) (xy 363.78705 -276.210528)
			(xy 363.835905 -276.21646) (xy 363.883176 -276.230152) (xy 363.927638 -276.25125) (xy 363.968141 -276.279206)
			(xy 364.003634 -276.313298) (xy 364.033199 -276.352642) (xy 364.05607 -276.396219) (xy 364.071654 -276.4429)
			(xy 364.079549 -276.491477) (xy 364.080044 -276.516084) (xy 364.408986 -276.516084) (xy 364.412946 -276.46703)
			(xy 364.424723 -276.419246) (xy 364.444014 -276.37397) (xy 364.470317 -276.332374) (xy 364.502952 -276.295537)
			(xy 364.541073 -276.264412) (xy 364.583694 -276.239805) (xy 364.62971 -276.222353) (xy 364.677929 -276.212509)
			(xy 364.727104 -276.210528) (xy 364.775959 -276.21646) (xy 364.82323 -276.230152) (xy 364.867692 -276.25125)
			(xy 364.908195 -276.279206) (xy 364.943688 -276.313298) (xy 364.973253 -276.352642) (xy 364.996124 -276.396219)
			(xy 365.011708 -276.4429) (xy 365.019603 -276.491477) (xy 365.020098 -276.516084) (xy 365.34904 -276.516084)
			(xy 365.353 -276.46703) (xy 365.364777 -276.419246) (xy 365.384068 -276.37397) (xy 365.410371 -276.332374)
			(xy 365.443006 -276.295537) (xy 365.481127 -276.264412) (xy 365.523748 -276.239805) (xy 365.569764 -276.222353)
			(xy 365.617983 -276.212509) (xy 365.667158 -276.210528) (xy 365.716013 -276.21646) (xy 365.763284 -276.230152)
			(xy 365.807746 -276.25125) (xy 365.848249 -276.279206) (xy 365.883742 -276.313298) (xy 365.913307 -276.352642)
			(xy 365.936178 -276.396219) (xy 365.951762 -276.4429) (xy 365.959657 -276.491477) (xy 365.960152 -276.516084)
			(xy 366.289094 -276.516084) (xy 366.293054 -276.46703) (xy 366.304831 -276.419246) (xy 366.324122 -276.37397)
			(xy 366.350425 -276.332374) (xy 366.38306 -276.295537) (xy 366.421181 -276.264412) (xy 366.463802 -276.239805)
			(xy 366.509818 -276.222353) (xy 366.558037 -276.212509) (xy 366.607212 -276.210528) (xy 366.656067 -276.21646)
			(xy 366.703338 -276.230152) (xy 366.7478 -276.25125) (xy 366.788303 -276.279206) (xy 366.823796 -276.313298)
			(xy 366.853361 -276.352642) (xy 366.876232 -276.396219) (xy 366.891816 -276.4429) (xy 366.899711 -276.491477)
			(xy 366.900206 -276.516084) (xy 367.228894 -276.516084) (xy 367.232854 -276.46703) (xy 367.244631 -276.419246)
			(xy 367.263922 -276.37397) (xy 367.290225 -276.332374) (xy 367.32286 -276.295537) (xy 367.360981 -276.264412)
			(xy 367.403602 -276.239805) (xy 367.449618 -276.222353) (xy 367.497837 -276.212509) (xy 367.547012 -276.210528)
			(xy 367.595867 -276.21646) (xy 367.643138 -276.230152) (xy 367.6876 -276.25125) (xy 367.728103 -276.279206)
			(xy 367.763596 -276.313298) (xy 367.793161 -276.352642) (xy 367.816032 -276.396219) (xy 367.831616 -276.4429)
			(xy 367.839511 -276.491477) (xy 367.840006 -276.516084) (xy 368.168948 -276.516084) (xy 368.172908 -276.46703)
			(xy 368.184685 -276.419246) (xy 368.203976 -276.37397) (xy 368.230279 -276.332374) (xy 368.262914 -276.295537)
			(xy 368.301035 -276.264412) (xy 368.343656 -276.239805) (xy 368.389672 -276.222353) (xy 368.437891 -276.212509)
			(xy 368.487066 -276.210528) (xy 368.535921 -276.21646) (xy 368.583192 -276.230152) (xy 368.627654 -276.25125)
			(xy 368.668157 -276.279206) (xy 368.70365 -276.313298) (xy 368.733215 -276.352642) (xy 368.756086 -276.396219)
			(xy 368.77167 -276.4429) (xy 368.779565 -276.491477) (xy 368.78006 -276.516084) (xy 369.109002 -276.516084)
			(xy 369.112962 -276.46703) (xy 369.124739 -276.419246) (xy 369.14403 -276.37397) (xy 369.170333 -276.332374)
			(xy 369.202968 -276.295537) (xy 369.241089 -276.264412) (xy 369.28371 -276.239805) (xy 369.329726 -276.222353)
			(xy 369.377945 -276.212509) (xy 369.42712 -276.210528) (xy 369.475975 -276.21646) (xy 369.523246 -276.230152)
			(xy 369.567708 -276.25125) (xy 369.608211 -276.279206) (xy 369.643704 -276.313298) (xy 369.673269 -276.352642)
			(xy 369.69614 -276.396219) (xy 369.711724 -276.4429) (xy 369.719619 -276.491477) (xy 369.720114 -276.516084)
			(xy 370.049056 -276.516084) (xy 370.053016 -276.46703) (xy 370.064793 -276.419246) (xy 370.084084 -276.37397)
			(xy 370.110387 -276.332374) (xy 370.143022 -276.295537) (xy 370.181143 -276.264412) (xy 370.223764 -276.239805)
			(xy 370.26978 -276.222353) (xy 370.317999 -276.212509) (xy 370.367174 -276.210528) (xy 370.416029 -276.21646)
			(xy 370.4633 -276.230152) (xy 370.507762 -276.25125) (xy 370.548265 -276.279206) (xy 370.583758 -276.313298)
			(xy 370.613323 -276.352642) (xy 370.636194 -276.396219) (xy 370.651778 -276.4429) (xy 370.659673 -276.491477)
			(xy 370.660168 -276.516084) (xy 370.98911 -276.516084) (xy 370.99307 -276.46703) (xy 371.004847 -276.419246)
			(xy 371.024138 -276.37397) (xy 371.050441 -276.332374) (xy 371.083076 -276.295537) (xy 371.121197 -276.264412)
			(xy 371.163818 -276.239805) (xy 371.209834 -276.222353) (xy 371.258053 -276.212509) (xy 371.307228 -276.210528)
			(xy 371.356083 -276.21646) (xy 371.403354 -276.230152) (xy 371.447816 -276.25125) (xy 371.488319 -276.279206)
			(xy 371.523812 -276.313298) (xy 371.553377 -276.352642) (xy 371.576248 -276.396219) (xy 371.591832 -276.4429)
			(xy 371.599727 -276.491477) (xy 371.600222 -276.516084) (xy 371.92891 -276.516084) (xy 371.93287 -276.46703)
			(xy 371.944647 -276.419246) (xy 371.963938 -276.37397) (xy 371.990241 -276.332374) (xy 372.022876 -276.295537)
			(xy 372.060997 -276.264412) (xy 372.103618 -276.239805) (xy 372.149634 -276.222353) (xy 372.197853 -276.212509)
			(xy 372.247028 -276.210528) (xy 372.295883 -276.21646) (xy 372.343154 -276.230152) (xy 372.387616 -276.25125)
			(xy 372.428119 -276.279206) (xy 372.463612 -276.313298) (xy 372.493177 -276.352642) (xy 372.516048 -276.396219)
			(xy 372.531632 -276.4429) (xy 372.539527 -276.491477) (xy 372.540022 -276.516084) (xy 372.539527 -276.540691)
			(xy 372.531632 -276.589268) (xy 372.516048 -276.635949) (xy 372.493177 -276.679526) (xy 372.463612 -276.71887)
			(xy 372.428119 -276.752962) (xy 372.387616 -276.780918) (xy 372.343154 -276.802016) (xy 372.295883 -276.815708)
			(xy 372.247028 -276.82164) (xy 372.197853 -276.819659) (xy 372.149634 -276.809815) (xy 372.103618 -276.792363)
			(xy 372.060997 -276.767756) (xy 372.022876 -276.736631) (xy 371.990241 -276.699794) (xy 371.963938 -276.658198)
			(xy 371.944647 -276.612922) (xy 371.93287 -276.565138) (xy 371.92891 -276.516084) (xy 371.600222 -276.516084)
			(xy 371.599727 -276.540691) (xy 371.591832 -276.589268) (xy 371.576248 -276.635949) (xy 371.553377 -276.679526)
			(xy 371.523812 -276.71887) (xy 371.488319 -276.752962) (xy 371.447816 -276.780918) (xy 371.403354 -276.802016)
			(xy 371.356083 -276.815708) (xy 371.307228 -276.82164) (xy 371.258053 -276.819659) (xy 371.209834 -276.809815)
			(xy 371.163818 -276.792363) (xy 371.121197 -276.767756) (xy 371.083076 -276.736631) (xy 371.050441 -276.699794)
			(xy 371.024138 -276.658198) (xy 371.004847 -276.612922) (xy 370.99307 -276.565138) (xy 370.98911 -276.516084)
			(xy 370.660168 -276.516084) (xy 370.659673 -276.540691) (xy 370.651778 -276.589268) (xy 370.636194 -276.635949)
			(xy 370.613323 -276.679526) (xy 370.583758 -276.71887) (xy 370.548265 -276.752962) (xy 370.507762 -276.780918)
			(xy 370.4633 -276.802016) (xy 370.416029 -276.815708) (xy 370.367174 -276.82164) (xy 370.317999 -276.819659)
			(xy 370.26978 -276.809815) (xy 370.223764 -276.792363) (xy 370.181143 -276.767756) (xy 370.143022 -276.736631)
			(xy 370.110387 -276.699794) (xy 370.084084 -276.658198) (xy 370.064793 -276.612922) (xy 370.053016 -276.565138)
			(xy 370.049056 -276.516084) (xy 369.720114 -276.516084) (xy 369.719619 -276.540691) (xy 369.711724 -276.589268)
			(xy 369.69614 -276.635949) (xy 369.673269 -276.679526) (xy 369.643704 -276.71887) (xy 369.608211 -276.752962)
			(xy 369.567708 -276.780918) (xy 369.523246 -276.802016) (xy 369.475975 -276.815708) (xy 369.42712 -276.82164)
			(xy 369.377945 -276.819659) (xy 369.329726 -276.809815) (xy 369.28371 -276.792363) (xy 369.241089 -276.767756)
			(xy 369.202968 -276.736631) (xy 369.170333 -276.699794) (xy 369.14403 -276.658198) (xy 369.124739 -276.612922)
			(xy 369.112962 -276.565138) (xy 369.109002 -276.516084) (xy 368.78006 -276.516084) (xy 368.779565 -276.540691)
			(xy 368.77167 -276.589268) (xy 368.756086 -276.635949) (xy 368.733215 -276.679526) (xy 368.70365 -276.71887)
			(xy 368.668157 -276.752962) (xy 368.627654 -276.780918) (xy 368.583192 -276.802016) (xy 368.535921 -276.815708)
			(xy 368.487066 -276.82164) (xy 368.437891 -276.819659) (xy 368.389672 -276.809815) (xy 368.343656 -276.792363)
			(xy 368.301035 -276.767756) (xy 368.262914 -276.736631) (xy 368.230279 -276.699794) (xy 368.203976 -276.658198)
			(xy 368.184685 -276.612922) (xy 368.172908 -276.565138) (xy 368.168948 -276.516084) (xy 367.840006 -276.516084)
			(xy 367.839511 -276.540691) (xy 367.831616 -276.589268) (xy 367.816032 -276.635949) (xy 367.793161 -276.679526)
			(xy 367.763596 -276.71887) (xy 367.728103 -276.752962) (xy 367.6876 -276.780918) (xy 367.643138 -276.802016)
			(xy 367.595867 -276.815708) (xy 367.547012 -276.82164) (xy 367.497837 -276.819659) (xy 367.449618 -276.809815)
			(xy 367.403602 -276.792363) (xy 367.360981 -276.767756) (xy 367.32286 -276.736631) (xy 367.290225 -276.699794)
			(xy 367.263922 -276.658198) (xy 367.244631 -276.612922) (xy 367.232854 -276.565138) (xy 367.228894 -276.516084)
			(xy 366.900206 -276.516084) (xy 366.899711 -276.540691) (xy 366.891816 -276.589268) (xy 366.876232 -276.635949)
			(xy 366.853361 -276.679526) (xy 366.823796 -276.71887) (xy 366.788303 -276.752962) (xy 366.7478 -276.780918)
			(xy 366.703338 -276.802016) (xy 366.656067 -276.815708) (xy 366.607212 -276.82164) (xy 366.558037 -276.819659)
			(xy 366.509818 -276.809815) (xy 366.463802 -276.792363) (xy 366.421181 -276.767756) (xy 366.38306 -276.736631)
			(xy 366.350425 -276.699794) (xy 366.324122 -276.658198) (xy 366.304831 -276.612922) (xy 366.293054 -276.565138)
			(xy 366.289094 -276.516084) (xy 365.960152 -276.516084) (xy 365.959657 -276.540691) (xy 365.951762 -276.589268)
			(xy 365.936178 -276.635949) (xy 365.913307 -276.679526) (xy 365.883742 -276.71887) (xy 365.848249 -276.752962)
			(xy 365.807746 -276.780918) (xy 365.763284 -276.802016) (xy 365.716013 -276.815708) (xy 365.667158 -276.82164)
			(xy 365.617983 -276.819659) (xy 365.569764 -276.809815) (xy 365.523748 -276.792363) (xy 365.481127 -276.767756)
			(xy 365.443006 -276.736631) (xy 365.410371 -276.699794) (xy 365.384068 -276.658198) (xy 365.364777 -276.612922)
			(xy 365.353 -276.565138) (xy 365.34904 -276.516084) (xy 365.020098 -276.516084) (xy 365.019603 -276.540691)
			(xy 365.011708 -276.589268) (xy 364.996124 -276.635949) (xy 364.973253 -276.679526) (xy 364.943688 -276.71887)
			(xy 364.908195 -276.752962) (xy 364.867692 -276.780918) (xy 364.82323 -276.802016) (xy 364.775959 -276.815708)
			(xy 364.727104 -276.82164) (xy 364.677929 -276.819659) (xy 364.62971 -276.809815) (xy 364.583694 -276.792363)
			(xy 364.541073 -276.767756) (xy 364.502952 -276.736631) (xy 364.470317 -276.699794) (xy 364.444014 -276.658198)
			(xy 364.424723 -276.612922) (xy 364.412946 -276.565138) (xy 364.408986 -276.516084) (xy 364.080044 -276.516084)
			(xy 364.079549 -276.540691) (xy 364.071654 -276.589268) (xy 364.05607 -276.635949) (xy 364.033199 -276.679526)
			(xy 364.003634 -276.71887) (xy 363.968141 -276.752962) (xy 363.927638 -276.780918) (xy 363.883176 -276.802016)
			(xy 363.835905 -276.815708) (xy 363.78705 -276.82164) (xy 363.737875 -276.819659) (xy 363.689656 -276.809815)
			(xy 363.64364 -276.792363) (xy 363.601019 -276.767756) (xy 363.562898 -276.736631) (xy 363.530263 -276.699794)
			(xy 363.50396 -276.658198) (xy 363.484669 -276.612922) (xy 363.472892 -276.565138) (xy 363.468932 -276.516084)
			(xy 363.13999 -276.516084) (xy 363.139495 -276.540691) (xy 363.1316 -276.589268) (xy 363.116016 -276.635949)
			(xy 363.093145 -276.679526) (xy 363.06358 -276.71887) (xy 363.028087 -276.752962) (xy 362.987584 -276.780918)
			(xy 362.943122 -276.802016) (xy 362.895851 -276.815708) (xy 362.846996 -276.82164) (xy 362.797821 -276.819659)
			(xy 362.749602 -276.809815) (xy 362.703586 -276.792363) (xy 362.660965 -276.767756) (xy 362.622844 -276.736631)
			(xy 362.590209 -276.699794) (xy 362.563906 -276.658198) (xy 362.544615 -276.612922) (xy 362.532838 -276.565138)
			(xy 362.528878 -276.516084) (xy 362.20019 -276.516084) (xy 362.199695 -276.540691) (xy 362.1918 -276.589268)
			(xy 362.176216 -276.635949) (xy 362.153345 -276.679526) (xy 362.12378 -276.71887) (xy 362.088287 -276.752962)
			(xy 362.047784 -276.780918) (xy 362.003322 -276.802016) (xy 361.956051 -276.815708) (xy 361.907196 -276.82164)
			(xy 361.858021 -276.819659) (xy 361.809802 -276.809815) (xy 361.763786 -276.792363) (xy 361.721165 -276.767756)
			(xy 361.683044 -276.736631) (xy 361.650409 -276.699794) (xy 361.624106 -276.658198) (xy 361.604815 -276.612922)
			(xy 361.593038 -276.565138) (xy 361.589078 -276.516084) (xy 358.446324 -276.516084) (xy 358.445829 -276.540691)
			(xy 358.437934 -276.589268) (xy 358.42235 -276.635949) (xy 358.399479 -276.679526) (xy 358.369914 -276.71887)
			(xy 358.334421 -276.752962) (xy 358.293918 -276.780918) (xy 358.249456 -276.802016) (xy 358.202185 -276.815708)
			(xy 358.15333 -276.82164) (xy 358.104155 -276.819659) (xy 358.055936 -276.809815) (xy 358.00992 -276.792363)
			(xy 357.967299 -276.767756) (xy 357.929178 -276.736631) (xy 357.896543 -276.699794) (xy 357.87024 -276.658198)
			(xy 357.850949 -276.612922) (xy 357.839172 -276.565138) (xy 357.835212 -276.516084) (xy 357.506524 -276.516084)
			(xy 357.506029 -276.540691) (xy 357.498134 -276.589268) (xy 357.48255 -276.635949) (xy 357.459679 -276.679526)
			(xy 357.430114 -276.71887) (xy 357.394621 -276.752962) (xy 357.354118 -276.780918) (xy 357.309656 -276.802016)
			(xy 357.262385 -276.815708) (xy 357.21353 -276.82164) (xy 357.164355 -276.819659) (xy 357.116136 -276.809815)
			(xy 357.07012 -276.792363) (xy 357.027499 -276.767756) (xy 356.989378 -276.736631) (xy 356.956743 -276.699794)
			(xy 356.93044 -276.658198) (xy 356.911149 -276.612922) (xy 356.899372 -276.565138) (xy 356.895412 -276.516084)
			(xy 356.56647 -276.516084) (xy 356.565975 -276.540691) (xy 356.55808 -276.589268) (xy 356.542496 -276.635949)
			(xy 356.519625 -276.679526) (xy 356.49006 -276.71887) (xy 356.454567 -276.752962) (xy 356.414064 -276.780918)
			(xy 356.369602 -276.802016) (xy 356.322331 -276.815708) (xy 356.273476 -276.82164) (xy 356.224301 -276.819659)
			(xy 356.176082 -276.809815) (xy 356.130066 -276.792363) (xy 356.087445 -276.767756) (xy 356.049324 -276.736631)
			(xy 356.016689 -276.699794) (xy 355.990386 -276.658198) (xy 355.971095 -276.612922) (xy 355.959318 -276.565138)
			(xy 355.955358 -276.516084) (xy 355.626416 -276.516084) (xy 355.625921 -276.540691) (xy 355.618026 -276.589268)
			(xy 355.602442 -276.635949) (xy 355.579571 -276.679526) (xy 355.550006 -276.71887) (xy 355.514513 -276.752962)
			(xy 355.47401 -276.780918) (xy 355.429548 -276.802016) (xy 355.382277 -276.815708) (xy 355.333422 -276.82164)
			(xy 355.284247 -276.819659) (xy 355.236028 -276.809815) (xy 355.190012 -276.792363) (xy 355.147391 -276.767756)
			(xy 355.10927 -276.736631) (xy 355.076635 -276.699794) (xy 355.050332 -276.658198) (xy 355.031041 -276.612922)
			(xy 355.019264 -276.565138) (xy 355.015304 -276.516084) (xy 354.686362 -276.516084) (xy 354.685867 -276.540691)
			(xy 354.677972 -276.589268) (xy 354.662388 -276.635949) (xy 354.639517 -276.679526) (xy 354.609952 -276.71887)
			(xy 354.574459 -276.752962) (xy 354.533956 -276.780918) (xy 354.489494 -276.802016) (xy 354.442223 -276.815708)
			(xy 354.393368 -276.82164) (xy 354.344193 -276.819659) (xy 354.295974 -276.809815) (xy 354.249958 -276.792363)
			(xy 354.207337 -276.767756) (xy 354.169216 -276.736631) (xy 354.136581 -276.699794) (xy 354.110278 -276.658198)
			(xy 354.090987 -276.612922) (xy 354.07921 -276.565138) (xy 354.07525 -276.516084) (xy 353.746308 -276.516084)
			(xy 353.745813 -276.540691) (xy 353.737918 -276.589268) (xy 353.722334 -276.635949) (xy 353.699463 -276.679526)
			(xy 353.669898 -276.71887) (xy 353.634405 -276.752962) (xy 353.593902 -276.780918) (xy 353.54944 -276.802016)
			(xy 353.502169 -276.815708) (xy 353.453314 -276.82164) (xy 353.404139 -276.819659) (xy 353.35592 -276.809815)
			(xy 353.309904 -276.792363) (xy 353.267283 -276.767756) (xy 353.229162 -276.736631) (xy 353.196527 -276.699794)
			(xy 353.170224 -276.658198) (xy 353.150933 -276.612922) (xy 353.139156 -276.565138) (xy 353.135196 -276.516084)
			(xy 352.806508 -276.516084) (xy 352.806013 -276.540691) (xy 352.798118 -276.589268) (xy 352.782534 -276.635949)
			(xy 352.759663 -276.679526) (xy 352.730098 -276.71887) (xy 352.694605 -276.752962) (xy 352.654102 -276.780918)
			(xy 352.60964 -276.802016) (xy 352.562369 -276.815708) (xy 352.513514 -276.82164) (xy 352.464339 -276.819659)
			(xy 352.41612 -276.809815) (xy 352.370104 -276.792363) (xy 352.327483 -276.767756) (xy 352.289362 -276.736631)
			(xy 352.256727 -276.699794) (xy 352.230424 -276.658198) (xy 352.211133 -276.612922) (xy 352.199356 -276.565138)
			(xy 352.195396 -276.516084) (xy 351.866454 -276.516084) (xy 351.865959 -276.540691) (xy 351.858064 -276.589268)
			(xy 351.84248 -276.635949) (xy 351.819609 -276.679526) (xy 351.790044 -276.71887) (xy 351.754551 -276.752962)
			(xy 351.714048 -276.780918) (xy 351.669586 -276.802016) (xy 351.622315 -276.815708) (xy 351.57346 -276.82164)
			(xy 351.524285 -276.819659) (xy 351.476066 -276.809815) (xy 351.43005 -276.792363) (xy 351.387429 -276.767756)
			(xy 351.349308 -276.736631) (xy 351.316673 -276.699794) (xy 351.29037 -276.658198) (xy 351.271079 -276.612922)
			(xy 351.259302 -276.565138) (xy 351.255342 -276.516084) (xy 350.9264 -276.516084) (xy 350.925905 -276.540691)
			(xy 350.91801 -276.589268) (xy 350.902426 -276.635949) (xy 350.879555 -276.679526) (xy 350.84999 -276.71887)
			(xy 350.814497 -276.752962) (xy 350.773994 -276.780918) (xy 350.729532 -276.802016) (xy 350.682261 -276.815708)
			(xy 350.633406 -276.82164) (xy 350.584231 -276.819659) (xy 350.536012 -276.809815) (xy 350.489996 -276.792363)
			(xy 350.447375 -276.767756) (xy 350.409254 -276.736631) (xy 350.376619 -276.699794) (xy 350.350316 -276.658198)
			(xy 350.331025 -276.612922) (xy 350.319248 -276.565138) (xy 350.315288 -276.516084) (xy 349.986346 -276.516084)
			(xy 349.985851 -276.540691) (xy 349.977956 -276.589268) (xy 349.962372 -276.635949) (xy 349.939501 -276.679526)
			(xy 349.909936 -276.71887) (xy 349.874443 -276.752962) (xy 349.83394 -276.780918) (xy 349.789478 -276.802016)
			(xy 349.742207 -276.815708) (xy 349.693352 -276.82164) (xy 349.644177 -276.819659) (xy 349.595958 -276.809815)
			(xy 349.549942 -276.792363) (xy 349.507321 -276.767756) (xy 349.4692 -276.736631) (xy 349.436565 -276.699794)
			(xy 349.410262 -276.658198) (xy 349.390971 -276.612922) (xy 349.379194 -276.565138) (xy 349.375234 -276.516084)
			(xy 349.046546 -276.516084) (xy 349.046051 -276.540691) (xy 349.038156 -276.589268) (xy 349.022572 -276.635949)
			(xy 348.999701 -276.679526) (xy 348.970136 -276.71887) (xy 348.934643 -276.752962) (xy 348.89414 -276.780918)
			(xy 348.849678 -276.802016) (xy 348.802407 -276.815708) (xy 348.753552 -276.82164) (xy 348.704377 -276.819659)
			(xy 348.656158 -276.809815) (xy 348.610142 -276.792363) (xy 348.567521 -276.767756) (xy 348.5294 -276.736631)
			(xy 348.496765 -276.699794) (xy 348.470462 -276.658198) (xy 348.451171 -276.612922) (xy 348.439394 -276.565138)
			(xy 348.435434 -276.516084) (xy 348.106492 -276.516084) (xy 348.105997 -276.540691) (xy 348.098102 -276.589268)
			(xy 348.082518 -276.635949) (xy 348.059647 -276.679526) (xy 348.030082 -276.71887) (xy 347.994589 -276.752962)
			(xy 347.954086 -276.780918) (xy 347.909624 -276.802016) (xy 347.862353 -276.815708) (xy 347.813498 -276.82164)
			(xy 347.764323 -276.819659) (xy 347.716104 -276.809815) (xy 347.670088 -276.792363) (xy 347.627467 -276.767756)
			(xy 347.589346 -276.736631) (xy 347.556711 -276.699794) (xy 347.530408 -276.658198) (xy 347.511117 -276.612922)
			(xy 347.49934 -276.565138) (xy 347.49538 -276.516084) (xy 347.166438 -276.516084) (xy 347.165943 -276.540691)
			(xy 347.158048 -276.589268) (xy 347.142464 -276.635949) (xy 347.119593 -276.679526) (xy 347.090028 -276.71887)
			(xy 347.054535 -276.752962) (xy 347.014032 -276.780918) (xy 346.96957 -276.802016) (xy 346.922299 -276.815708)
			(xy 346.873444 -276.82164) (xy 346.824269 -276.819659) (xy 346.77605 -276.809815) (xy 346.730034 -276.792363)
			(xy 346.687413 -276.767756) (xy 346.649292 -276.736631) (xy 346.616657 -276.699794) (xy 346.590354 -276.658198)
			(xy 346.571063 -276.612922) (xy 346.559286 -276.565138) (xy 346.555326 -276.516084) (xy 346.226384 -276.516084)
			(xy 346.225889 -276.540691) (xy 346.217994 -276.589268) (xy 346.20241 -276.635949) (xy 346.179539 -276.679526)
			(xy 346.149974 -276.71887) (xy 346.114481 -276.752962) (xy 346.073978 -276.780918) (xy 346.029516 -276.802016)
			(xy 345.982245 -276.815708) (xy 345.93339 -276.82164) (xy 345.884215 -276.819659) (xy 345.835996 -276.809815)
			(xy 345.78998 -276.792363) (xy 345.747359 -276.767756) (xy 345.709238 -276.736631) (xy 345.676603 -276.699794)
			(xy 345.6503 -276.658198) (xy 345.631009 -276.612922) (xy 345.619232 -276.565138) (xy 345.615272 -276.516084)
			(xy 345.286846 -276.516084) (xy 345.286847 -276.5161) (xy 345.282681 -276.566412) (xy 345.270294 -276.615353)
			(xy 345.250026 -276.66159) (xy 345.222428 -276.703863) (xy 345.188252 -276.74102) (xy 345.148429 -276.772049)
			(xy 345.104044 -276.796105) (xy 345.056307 -276.812531) (xy 345.006518 -276.820881) (xy 344.981276 -276.821392)
			(xy 344.971208 -276.821819) (xy 344.952609 -276.829539) (xy 344.945208 -276.836378) (xy 344.895424 -276.886162)
			(xy 344.888699 -276.893396) (xy 344.881081 -276.911601) (xy 344.880692 -276.921468) (xy 344.880692 -277.32609)
			(xy 345.145372 -277.32609) (xy 345.149332 -277.277036) (xy 345.161109 -277.229252) (xy 345.1804 -277.183976)
			(xy 345.206703 -277.14238) (xy 345.239338 -277.105543) (xy 345.277459 -277.074418) (xy 345.32008 -277.049811)
			(xy 345.366096 -277.032359) (xy 345.414315 -277.022515) (xy 345.46349 -277.020534) (xy 345.512345 -277.026466)
			(xy 345.559616 -277.040158) (xy 345.604078 -277.061256) (xy 345.644581 -277.089212) (xy 345.680074 -277.123304)
			(xy 345.709639 -277.162648) (xy 345.73251 -277.206225) (xy 345.748094 -277.252906) (xy 345.755989 -277.301483)
			(xy 345.756484 -277.32609) (xy 346.085426 -277.32609) (xy 346.089386 -277.277036) (xy 346.101163 -277.229252)
			(xy 346.120454 -277.183976) (xy 346.146757 -277.14238) (xy 346.179392 -277.105543) (xy 346.217513 -277.074418)
			(xy 346.260134 -277.049811) (xy 346.30615 -277.032359) (xy 346.354369 -277.022515) (xy 346.403544 -277.020534)
			(xy 346.452399 -277.026466) (xy 346.49967 -277.040158) (xy 346.544132 -277.061256) (xy 346.584635 -277.089212)
			(xy 346.620128 -277.123304) (xy 346.649693 -277.162648) (xy 346.672564 -277.206225) (xy 346.688148 -277.252906)
			(xy 346.696043 -277.301483) (xy 346.696538 -277.32609) (xy 347.025226 -277.32609) (xy 347.029186 -277.277036)
			(xy 347.040963 -277.229252) (xy 347.060254 -277.183976) (xy 347.086557 -277.14238) (xy 347.119192 -277.105543)
			(xy 347.157313 -277.074418) (xy 347.199934 -277.049811) (xy 347.24595 -277.032359) (xy 347.294169 -277.022515)
			(xy 347.343344 -277.020534) (xy 347.392199 -277.026466) (xy 347.43947 -277.040158) (xy 347.483932 -277.061256)
			(xy 347.524435 -277.089212) (xy 347.559928 -277.123304) (xy 347.589493 -277.162648) (xy 347.612364 -277.206225)
			(xy 347.627948 -277.252906) (xy 347.635843 -277.301483) (xy 347.636338 -277.32609) (xy 347.96528 -277.32609)
			(xy 347.96924 -277.277036) (xy 347.981017 -277.229252) (xy 348.000308 -277.183976) (xy 348.026611 -277.14238)
			(xy 348.059246 -277.105543) (xy 348.097367 -277.074418) (xy 348.139988 -277.049811) (xy 348.186004 -277.032359)
			(xy 348.234223 -277.022515) (xy 348.283398 -277.020534) (xy 348.332253 -277.026466) (xy 348.379524 -277.040158)
			(xy 348.423986 -277.061256) (xy 348.464489 -277.089212) (xy 348.499982 -277.123304) (xy 348.529547 -277.162648)
			(xy 348.552418 -277.206225) (xy 348.568002 -277.252906) (xy 348.575897 -277.301483) (xy 348.576392 -277.32609)
			(xy 348.905334 -277.32609) (xy 348.909294 -277.277036) (xy 348.921071 -277.229252) (xy 348.940362 -277.183976)
			(xy 348.966665 -277.14238) (xy 348.9993 -277.105543) (xy 349.037421 -277.074418) (xy 349.080042 -277.049811)
			(xy 349.126058 -277.032359) (xy 349.174277 -277.022515) (xy 349.223452 -277.020534) (xy 349.272307 -277.026466)
			(xy 349.319578 -277.040158) (xy 349.36404 -277.061256) (xy 349.404543 -277.089212) (xy 349.440036 -277.123304)
			(xy 349.469601 -277.162648) (xy 349.492472 -277.206225) (xy 349.508056 -277.252906) (xy 349.515951 -277.301483)
			(xy 349.516446 -277.32609) (xy 349.845388 -277.32609) (xy 349.849348 -277.277036) (xy 349.861125 -277.229252)
			(xy 349.880416 -277.183976) (xy 349.906719 -277.14238) (xy 349.939354 -277.105543) (xy 349.977475 -277.074418)
			(xy 350.020096 -277.049811) (xy 350.066112 -277.032359) (xy 350.114331 -277.022515) (xy 350.163506 -277.020534)
			(xy 350.212361 -277.026466) (xy 350.259632 -277.040158) (xy 350.304094 -277.061256) (xy 350.344597 -277.089212)
			(xy 350.38009 -277.123304) (xy 350.409655 -277.162648) (xy 350.432526 -277.206225) (xy 350.44811 -277.252906)
			(xy 350.456005 -277.301483) (xy 350.4565 -277.32609) (xy 350.785442 -277.32609) (xy 350.789402 -277.277036)
			(xy 350.801179 -277.229252) (xy 350.82047 -277.183976) (xy 350.846773 -277.14238) (xy 350.879408 -277.105543)
			(xy 350.917529 -277.074418) (xy 350.96015 -277.049811) (xy 351.006166 -277.032359) (xy 351.054385 -277.022515)
			(xy 351.10356 -277.020534) (xy 351.152415 -277.026466) (xy 351.199686 -277.040158) (xy 351.244148 -277.061256)
			(xy 351.284651 -277.089212) (xy 351.320144 -277.123304) (xy 351.349709 -277.162648) (xy 351.37258 -277.206225)
			(xy 351.388164 -277.252906) (xy 351.396059 -277.301483) (xy 351.396554 -277.32609) (xy 351.725242 -277.32609)
			(xy 351.729202 -277.277036) (xy 351.740979 -277.229252) (xy 351.76027 -277.183976) (xy 351.786573 -277.14238)
			(xy 351.819208 -277.105543) (xy 351.857329 -277.074418) (xy 351.89995 -277.049811) (xy 351.945966 -277.032359)
			(xy 351.994185 -277.022515) (xy 352.04336 -277.020534) (xy 352.092215 -277.026466) (xy 352.139486 -277.040158)
			(xy 352.183948 -277.061256) (xy 352.224451 -277.089212) (xy 352.259944 -277.123304) (xy 352.289509 -277.162648)
			(xy 352.31238 -277.206225) (xy 352.327964 -277.252906) (xy 352.335859 -277.301483) (xy 352.336354 -277.32609)
			(xy 352.665296 -277.32609) (xy 352.669256 -277.277036) (xy 352.681033 -277.229252) (xy 352.700324 -277.183976)
			(xy 352.726627 -277.14238) (xy 352.759262 -277.105543) (xy 352.797383 -277.074418) (xy 352.840004 -277.049811)
			(xy 352.88602 -277.032359) (xy 352.934239 -277.022515) (xy 352.983414 -277.020534) (xy 353.032269 -277.026466)
			(xy 353.07954 -277.040158) (xy 353.124002 -277.061256) (xy 353.164505 -277.089212) (xy 353.199998 -277.123304)
			(xy 353.229563 -277.162648) (xy 353.252434 -277.206225) (xy 353.268018 -277.252906) (xy 353.275913 -277.301483)
			(xy 353.276408 -277.32609) (xy 353.60535 -277.32609) (xy 353.60931 -277.277036) (xy 353.621087 -277.229252)
			(xy 353.640378 -277.183976) (xy 353.666681 -277.14238) (xy 353.699316 -277.105543) (xy 353.737437 -277.074418)
			(xy 353.780058 -277.049811) (xy 353.826074 -277.032359) (xy 353.874293 -277.022515) (xy 353.923468 -277.020534)
			(xy 353.972323 -277.026466) (xy 354.019594 -277.040158) (xy 354.064056 -277.061256) (xy 354.104559 -277.089212)
			(xy 354.140052 -277.123304) (xy 354.169617 -277.162648) (xy 354.192488 -277.206225) (xy 354.208072 -277.252906)
			(xy 354.215967 -277.301483) (xy 354.216462 -277.32609) (xy 354.545404 -277.32609) (xy 354.549364 -277.277036)
			(xy 354.561141 -277.229252) (xy 354.580432 -277.183976) (xy 354.606735 -277.14238) (xy 354.63937 -277.105543)
			(xy 354.677491 -277.074418) (xy 354.720112 -277.049811) (xy 354.766128 -277.032359) (xy 354.814347 -277.022515)
			(xy 354.863522 -277.020534) (xy 354.912377 -277.026466) (xy 354.959648 -277.040158) (xy 355.00411 -277.061256)
			(xy 355.044613 -277.089212) (xy 355.080106 -277.123304) (xy 355.109671 -277.162648) (xy 355.132542 -277.206225)
			(xy 355.148126 -277.252906) (xy 355.156021 -277.301483) (xy 355.156516 -277.32609) (xy 355.485204 -277.32609)
			(xy 355.489164 -277.277036) (xy 355.500941 -277.229252) (xy 355.520232 -277.183976) (xy 355.546535 -277.14238)
			(xy 355.57917 -277.105543) (xy 355.617291 -277.074418) (xy 355.659912 -277.049811) (xy 355.705928 -277.032359)
			(xy 355.754147 -277.022515) (xy 355.803322 -277.020534) (xy 355.852177 -277.026466) (xy 355.899448 -277.040158)
			(xy 355.94391 -277.061256) (xy 355.984413 -277.089212) (xy 356.019906 -277.123304) (xy 356.049471 -277.162648)
			(xy 356.072342 -277.206225) (xy 356.087926 -277.252906) (xy 356.095821 -277.301483) (xy 356.096316 -277.32609)
			(xy 356.425258 -277.32609) (xy 356.429218 -277.277036) (xy 356.440995 -277.229252) (xy 356.460286 -277.183976)
			(xy 356.486589 -277.14238) (xy 356.519224 -277.105543) (xy 356.557345 -277.074418) (xy 356.599966 -277.049811)
			(xy 356.645982 -277.032359) (xy 356.694201 -277.022515) (xy 356.743376 -277.020534) (xy 356.792231 -277.026466)
			(xy 356.839502 -277.040158) (xy 356.883964 -277.061256) (xy 356.924467 -277.089212) (xy 356.95996 -277.123304)
			(xy 356.989525 -277.162648) (xy 357.012396 -277.206225) (xy 357.02798 -277.252906) (xy 357.035875 -277.301483)
			(xy 357.03637 -277.32609) (xy 357.365312 -277.32609) (xy 357.369272 -277.277036) (xy 357.381049 -277.229252)
			(xy 357.40034 -277.183976) (xy 357.426643 -277.14238) (xy 357.459278 -277.105543) (xy 357.497399 -277.074418)
			(xy 357.54002 -277.049811) (xy 357.586036 -277.032359) (xy 357.634255 -277.022515) (xy 357.68343 -277.020534)
			(xy 357.732285 -277.026466) (xy 357.779556 -277.040158) (xy 357.824018 -277.061256) (xy 357.864521 -277.089212)
			(xy 357.900014 -277.123304) (xy 357.929579 -277.162648) (xy 357.95245 -277.206225) (xy 357.968034 -277.252906)
			(xy 357.975929 -277.301483) (xy 357.976424 -277.32609) (xy 358.305366 -277.32609) (xy 358.309326 -277.277036)
			(xy 358.321103 -277.229252) (xy 358.340394 -277.183976) (xy 358.366697 -277.14238) (xy 358.399332 -277.105543)
			(xy 358.437453 -277.074418) (xy 358.480074 -277.049811) (xy 358.52609 -277.032359) (xy 358.574309 -277.022515)
			(xy 358.623484 -277.020534) (xy 358.672339 -277.026466) (xy 358.71961 -277.040158) (xy 358.764072 -277.061256)
			(xy 358.804575 -277.089212) (xy 358.840068 -277.123304) (xy 358.869633 -277.162648) (xy 358.892504 -277.206225)
			(xy 358.908088 -277.252906) (xy 358.915983 -277.301483) (xy 358.916478 -277.32609) (xy 361.118924 -277.32609)
			(xy 361.122884 -277.277036) (xy 361.134661 -277.229252) (xy 361.153952 -277.183976) (xy 361.180255 -277.14238)
			(xy 361.21289 -277.105543) (xy 361.251011 -277.074418) (xy 361.293632 -277.049811) (xy 361.339648 -277.032359)
			(xy 361.387867 -277.022515) (xy 361.437042 -277.020534) (xy 361.485897 -277.026466) (xy 361.533168 -277.040158)
			(xy 361.57763 -277.061256) (xy 361.618133 -277.089212) (xy 361.653626 -277.123304) (xy 361.683191 -277.162648)
			(xy 361.706062 -277.206225) (xy 361.721646 -277.252906) (xy 361.729541 -277.301483) (xy 361.730036 -277.32609)
			(xy 362.058978 -277.32609) (xy 362.062938 -277.277036) (xy 362.074715 -277.229252) (xy 362.094006 -277.183976)
			(xy 362.120309 -277.14238) (xy 362.152944 -277.105543) (xy 362.191065 -277.074418) (xy 362.233686 -277.049811)
			(xy 362.279702 -277.032359) (xy 362.327921 -277.022515) (xy 362.377096 -277.020534) (xy 362.425951 -277.026466)
			(xy 362.473222 -277.040158) (xy 362.517684 -277.061256) (xy 362.558187 -277.089212) (xy 362.59368 -277.123304)
			(xy 362.623245 -277.162648) (xy 362.646116 -277.206225) (xy 362.6617 -277.252906) (xy 362.669595 -277.301483)
			(xy 362.67009 -277.32609) (xy 362.999032 -277.32609) (xy 363.002992 -277.277036) (xy 363.014769 -277.229252)
			(xy 363.03406 -277.183976) (xy 363.060363 -277.14238) (xy 363.092998 -277.105543) (xy 363.131119 -277.074418)
			(xy 363.17374 -277.049811) (xy 363.219756 -277.032359) (xy 363.267975 -277.022515) (xy 363.31715 -277.020534)
			(xy 363.366005 -277.026466) (xy 363.413276 -277.040158) (xy 363.457738 -277.061256) (xy 363.498241 -277.089212)
			(xy 363.533734 -277.123304) (xy 363.563299 -277.162648) (xy 363.58617 -277.206225) (xy 363.601754 -277.252906)
			(xy 363.609649 -277.301483) (xy 363.610144 -277.32609) (xy 363.939086 -277.32609) (xy 363.943046 -277.277036)
			(xy 363.954823 -277.229252) (xy 363.974114 -277.183976) (xy 364.000417 -277.14238) (xy 364.033052 -277.105543)
			(xy 364.071173 -277.074418) (xy 364.113794 -277.049811) (xy 364.15981 -277.032359) (xy 364.208029 -277.022515)
			(xy 364.257204 -277.020534) (xy 364.306059 -277.026466) (xy 364.35333 -277.040158) (xy 364.397792 -277.061256)
			(xy 364.438295 -277.089212) (xy 364.473788 -277.123304) (xy 364.503353 -277.162648) (xy 364.526224 -277.206225)
			(xy 364.541808 -277.252906) (xy 364.549703 -277.301483) (xy 364.550198 -277.32609) (xy 364.878886 -277.32609)
			(xy 364.882846 -277.277036) (xy 364.894623 -277.229252) (xy 364.913914 -277.183976) (xy 364.940217 -277.14238)
			(xy 364.972852 -277.105543) (xy 365.010973 -277.074418) (xy 365.053594 -277.049811) (xy 365.09961 -277.032359)
			(xy 365.147829 -277.022515) (xy 365.197004 -277.020534) (xy 365.245859 -277.026466) (xy 365.29313 -277.040158)
			(xy 365.337592 -277.061256) (xy 365.378095 -277.089212) (xy 365.413588 -277.123304) (xy 365.443153 -277.162648)
			(xy 365.466024 -277.206225) (xy 365.481608 -277.252906) (xy 365.489503 -277.301483) (xy 365.489998 -277.32609)
			(xy 365.81894 -277.32609) (xy 365.8229 -277.277036) (xy 365.834677 -277.229252) (xy 365.853968 -277.183976)
			(xy 365.880271 -277.14238) (xy 365.912906 -277.105543) (xy 365.951027 -277.074418) (xy 365.993648 -277.049811)
			(xy 366.039664 -277.032359) (xy 366.087883 -277.022515) (xy 366.137058 -277.020534) (xy 366.185913 -277.026466)
			(xy 366.233184 -277.040158) (xy 366.277646 -277.061256) (xy 366.318149 -277.089212) (xy 366.353642 -277.123304)
			(xy 366.383207 -277.162648) (xy 366.406078 -277.206225) (xy 366.421662 -277.252906) (xy 366.429557 -277.301483)
			(xy 366.430052 -277.32609) (xy 366.758994 -277.32609) (xy 366.762954 -277.277036) (xy 366.774731 -277.229252)
			(xy 366.794022 -277.183976) (xy 366.820325 -277.14238) (xy 366.85296 -277.105543) (xy 366.891081 -277.074418)
			(xy 366.933702 -277.049811) (xy 366.979718 -277.032359) (xy 367.027937 -277.022515) (xy 367.077112 -277.020534)
			(xy 367.125967 -277.026466) (xy 367.173238 -277.040158) (xy 367.2177 -277.061256) (xy 367.258203 -277.089212)
			(xy 367.293696 -277.123304) (xy 367.323261 -277.162648) (xy 367.346132 -277.206225) (xy 367.361716 -277.252906)
			(xy 367.369611 -277.301483) (xy 367.370106 -277.32609) (xy 367.699048 -277.32609) (xy 367.703008 -277.277036)
			(xy 367.714785 -277.229252) (xy 367.734076 -277.183976) (xy 367.760379 -277.14238) (xy 367.793014 -277.105543)
			(xy 367.831135 -277.074418) (xy 367.873756 -277.049811) (xy 367.919772 -277.032359) (xy 367.967991 -277.022515)
			(xy 368.017166 -277.020534) (xy 368.066021 -277.026466) (xy 368.113292 -277.040158) (xy 368.157754 -277.061256)
			(xy 368.198257 -277.089212) (xy 368.23375 -277.123304) (xy 368.263315 -277.162648) (xy 368.286186 -277.206225)
			(xy 368.30177 -277.252906) (xy 368.309665 -277.301483) (xy 368.31016 -277.32609) (xy 368.639102 -277.32609)
			(xy 368.643062 -277.277036) (xy 368.654839 -277.229252) (xy 368.67413 -277.183976) (xy 368.700433 -277.14238)
			(xy 368.733068 -277.105543) (xy 368.771189 -277.074418) (xy 368.81381 -277.049811) (xy 368.859826 -277.032359)
			(xy 368.908045 -277.022515) (xy 368.95722 -277.020534) (xy 369.006075 -277.026466) (xy 369.053346 -277.040158)
			(xy 369.097808 -277.061256) (xy 369.138311 -277.089212) (xy 369.173804 -277.123304) (xy 369.203369 -277.162648)
			(xy 369.22624 -277.206225) (xy 369.241824 -277.252906) (xy 369.249719 -277.301483) (xy 369.250214 -277.32609)
			(xy 369.578902 -277.32609) (xy 369.582862 -277.277036) (xy 369.594639 -277.229252) (xy 369.61393 -277.183976)
			(xy 369.640233 -277.14238) (xy 369.672868 -277.105543) (xy 369.710989 -277.074418) (xy 369.75361 -277.049811)
			(xy 369.799626 -277.032359) (xy 369.847845 -277.022515) (xy 369.89702 -277.020534) (xy 369.945875 -277.026466)
			(xy 369.993146 -277.040158) (xy 370.037608 -277.061256) (xy 370.078111 -277.089212) (xy 370.113604 -277.123304)
			(xy 370.143169 -277.162648) (xy 370.16604 -277.206225) (xy 370.181624 -277.252906) (xy 370.189519 -277.301483)
			(xy 370.190014 -277.32609) (xy 370.518956 -277.32609) (xy 370.522916 -277.277036) (xy 370.534693 -277.229252)
			(xy 370.553984 -277.183976) (xy 370.580287 -277.14238) (xy 370.612922 -277.105543) (xy 370.651043 -277.074418)
			(xy 370.693664 -277.049811) (xy 370.73968 -277.032359) (xy 370.787899 -277.022515) (xy 370.837074 -277.020534)
			(xy 370.885929 -277.026466) (xy 370.9332 -277.040158) (xy 370.977662 -277.061256) (xy 371.018165 -277.089212)
			(xy 371.053658 -277.123304) (xy 371.083223 -277.162648) (xy 371.106094 -277.206225) (xy 371.121678 -277.252906)
			(xy 371.129573 -277.301483) (xy 371.130068 -277.32609) (xy 371.45901 -277.32609) (xy 371.46297 -277.277036)
			(xy 371.474747 -277.229252) (xy 371.494038 -277.183976) (xy 371.520341 -277.14238) (xy 371.552976 -277.105543)
			(xy 371.591097 -277.074418) (xy 371.633718 -277.049811) (xy 371.679734 -277.032359) (xy 371.727953 -277.022515)
			(xy 371.777128 -277.020534) (xy 371.825983 -277.026466) (xy 371.873254 -277.040158) (xy 371.917716 -277.061256)
			(xy 371.958219 -277.089212) (xy 371.993712 -277.123304) (xy 372.023277 -277.162648) (xy 372.046148 -277.206225)
			(xy 372.061732 -277.252906) (xy 372.069627 -277.301483) (xy 372.070122 -277.32609) (xy 372.399064 -277.32609)
			(xy 372.403024 -277.277036) (xy 372.414801 -277.229252) (xy 372.434092 -277.183976) (xy 372.460395 -277.14238)
			(xy 372.49303 -277.105543) (xy 372.531151 -277.074418) (xy 372.573772 -277.049811) (xy 372.619788 -277.032359)
			(xy 372.668007 -277.022515) (xy 372.717182 -277.020534) (xy 372.766037 -277.026466) (xy 372.813308 -277.040158)
			(xy 372.85777 -277.061256) (xy 372.898273 -277.089212) (xy 372.933766 -277.123304) (xy 372.963331 -277.162648)
			(xy 372.986202 -277.206225) (xy 373.001786 -277.252906) (xy 373.009681 -277.301483) (xy 373.010176 -277.32609)
			(xy 373.339118 -277.32609) (xy 373.343078 -277.277036) (xy 373.354855 -277.229252) (xy 373.374146 -277.183976)
			(xy 373.400449 -277.14238) (xy 373.433084 -277.105543) (xy 373.471205 -277.074418) (xy 373.513826 -277.049811)
			(xy 373.559842 -277.032359) (xy 373.608061 -277.022515) (xy 373.657236 -277.020534) (xy 373.706091 -277.026466)
			(xy 373.753362 -277.040158) (xy 373.797824 -277.061256) (xy 373.838327 -277.089212) (xy 373.87382 -277.123304)
			(xy 373.903385 -277.162648) (xy 373.926256 -277.206225) (xy 373.94184 -277.252906) (xy 373.949735 -277.301483)
			(xy 373.95023 -277.32609) (xy 373.949735 -277.350697) (xy 373.94184 -277.399274) (xy 373.926256 -277.445955)
			(xy 373.903385 -277.489532) (xy 373.87382 -277.528876) (xy 373.838327 -277.562968) (xy 373.797824 -277.590924)
			(xy 373.753362 -277.612022) (xy 373.706091 -277.625714) (xy 373.657236 -277.631646) (xy 373.608061 -277.629665)
			(xy 373.559842 -277.619821) (xy 373.513826 -277.602369) (xy 373.471205 -277.577762) (xy 373.433084 -277.546637)
			(xy 373.400449 -277.5098) (xy 373.374146 -277.468204) (xy 373.354855 -277.422928) (xy 373.343078 -277.375144)
			(xy 373.339118 -277.32609) (xy 373.010176 -277.32609) (xy 373.009681 -277.350697) (xy 373.001786 -277.399274)
			(xy 372.986202 -277.445955) (xy 372.963331 -277.489532) (xy 372.933766 -277.528876) (xy 372.898273 -277.562968)
			(xy 372.85777 -277.590924) (xy 372.813308 -277.612022) (xy 372.766037 -277.625714) (xy 372.717182 -277.631646)
			(xy 372.668007 -277.629665) (xy 372.619788 -277.619821) (xy 372.573772 -277.602369) (xy 372.531151 -277.577762)
			(xy 372.49303 -277.546637) (xy 372.460395 -277.5098) (xy 372.434092 -277.468204) (xy 372.414801 -277.422928)
			(xy 372.403024 -277.375144) (xy 372.399064 -277.32609) (xy 372.070122 -277.32609) (xy 372.069627 -277.350697)
			(xy 372.061732 -277.399274) (xy 372.046148 -277.445955) (xy 372.023277 -277.489532) (xy 371.993712 -277.528876)
			(xy 371.958219 -277.562968) (xy 371.917716 -277.590924) (xy 371.873254 -277.612022) (xy 371.825983 -277.625714)
			(xy 371.777128 -277.631646) (xy 371.727953 -277.629665) (xy 371.679734 -277.619821) (xy 371.633718 -277.602369)
			(xy 371.591097 -277.577762) (xy 371.552976 -277.546637) (xy 371.520341 -277.5098) (xy 371.494038 -277.468204)
			(xy 371.474747 -277.422928) (xy 371.46297 -277.375144) (xy 371.45901 -277.32609) (xy 371.130068 -277.32609)
			(xy 371.129573 -277.350697) (xy 371.121678 -277.399274) (xy 371.106094 -277.445955) (xy 371.083223 -277.489532)
			(xy 371.053658 -277.528876) (xy 371.018165 -277.562968) (xy 370.977662 -277.590924) (xy 370.9332 -277.612022)
			(xy 370.885929 -277.625714) (xy 370.837074 -277.631646) (xy 370.787899 -277.629665) (xy 370.73968 -277.619821)
			(xy 370.693664 -277.602369) (xy 370.651043 -277.577762) (xy 370.612922 -277.546637) (xy 370.580287 -277.5098)
			(xy 370.553984 -277.468204) (xy 370.534693 -277.422928) (xy 370.522916 -277.375144) (xy 370.518956 -277.32609)
			(xy 370.190014 -277.32609) (xy 370.189519 -277.350697) (xy 370.181624 -277.399274) (xy 370.16604 -277.445955)
			(xy 370.143169 -277.489532) (xy 370.113604 -277.528876) (xy 370.078111 -277.562968) (xy 370.037608 -277.590924)
			(xy 369.993146 -277.612022) (xy 369.945875 -277.625714) (xy 369.89702 -277.631646) (xy 369.847845 -277.629665)
			(xy 369.799626 -277.619821) (xy 369.75361 -277.602369) (xy 369.710989 -277.577762) (xy 369.672868 -277.546637)
			(xy 369.640233 -277.5098) (xy 369.61393 -277.468204) (xy 369.594639 -277.422928) (xy 369.582862 -277.375144)
			(xy 369.578902 -277.32609) (xy 369.250214 -277.32609) (xy 369.249719 -277.350697) (xy 369.241824 -277.399274)
			(xy 369.22624 -277.445955) (xy 369.203369 -277.489532) (xy 369.173804 -277.528876) (xy 369.138311 -277.562968)
			(xy 369.097808 -277.590924) (xy 369.053346 -277.612022) (xy 369.006075 -277.625714) (xy 368.95722 -277.631646)
			(xy 368.908045 -277.629665) (xy 368.859826 -277.619821) (xy 368.81381 -277.602369) (xy 368.771189 -277.577762)
			(xy 368.733068 -277.546637) (xy 368.700433 -277.5098) (xy 368.67413 -277.468204) (xy 368.654839 -277.422928)
			(xy 368.643062 -277.375144) (xy 368.639102 -277.32609) (xy 368.31016 -277.32609) (xy 368.309665 -277.350697)
			(xy 368.30177 -277.399274) (xy 368.286186 -277.445955) (xy 368.263315 -277.489532) (xy 368.23375 -277.528876)
			(xy 368.198257 -277.562968) (xy 368.157754 -277.590924) (xy 368.113292 -277.612022) (xy 368.066021 -277.625714)
			(xy 368.017166 -277.631646) (xy 367.967991 -277.629665) (xy 367.919772 -277.619821) (xy 367.873756 -277.602369)
			(xy 367.831135 -277.577762) (xy 367.793014 -277.546637) (xy 367.760379 -277.5098) (xy 367.734076 -277.468204)
			(xy 367.714785 -277.422928) (xy 367.703008 -277.375144) (xy 367.699048 -277.32609) (xy 367.370106 -277.32609)
			(xy 367.369611 -277.350697) (xy 367.361716 -277.399274) (xy 367.346132 -277.445955) (xy 367.323261 -277.489532)
			(xy 367.293696 -277.528876) (xy 367.258203 -277.562968) (xy 367.2177 -277.590924) (xy 367.173238 -277.612022)
			(xy 367.125967 -277.625714) (xy 367.077112 -277.631646) (xy 367.027937 -277.629665) (xy 366.979718 -277.619821)
			(xy 366.933702 -277.602369) (xy 366.891081 -277.577762) (xy 366.85296 -277.546637) (xy 366.820325 -277.5098)
			(xy 366.794022 -277.468204) (xy 366.774731 -277.422928) (xy 366.762954 -277.375144) (xy 366.758994 -277.32609)
			(xy 366.430052 -277.32609) (xy 366.429557 -277.350697) (xy 366.421662 -277.399274) (xy 366.406078 -277.445955)
			(xy 366.383207 -277.489532) (xy 366.353642 -277.528876) (xy 366.318149 -277.562968) (xy 366.277646 -277.590924)
			(xy 366.233184 -277.612022) (xy 366.185913 -277.625714) (xy 366.137058 -277.631646) (xy 366.087883 -277.629665)
			(xy 366.039664 -277.619821) (xy 365.993648 -277.602369) (xy 365.951027 -277.577762) (xy 365.912906 -277.546637)
			(xy 365.880271 -277.5098) (xy 365.853968 -277.468204) (xy 365.834677 -277.422928) (xy 365.8229 -277.375144)
			(xy 365.81894 -277.32609) (xy 365.489998 -277.32609) (xy 365.489503 -277.350697) (xy 365.481608 -277.399274)
			(xy 365.466024 -277.445955) (xy 365.443153 -277.489532) (xy 365.413588 -277.528876) (xy 365.378095 -277.562968)
			(xy 365.337592 -277.590924) (xy 365.29313 -277.612022) (xy 365.245859 -277.625714) (xy 365.197004 -277.631646)
			(xy 365.147829 -277.629665) (xy 365.09961 -277.619821) (xy 365.053594 -277.602369) (xy 365.010973 -277.577762)
			(xy 364.972852 -277.546637) (xy 364.940217 -277.5098) (xy 364.913914 -277.468204) (xy 364.894623 -277.422928)
			(xy 364.882846 -277.375144) (xy 364.878886 -277.32609) (xy 364.550198 -277.32609) (xy 364.549703 -277.350697)
			(xy 364.541808 -277.399274) (xy 364.526224 -277.445955) (xy 364.503353 -277.489532) (xy 364.473788 -277.528876)
			(xy 364.438295 -277.562968) (xy 364.397792 -277.590924) (xy 364.35333 -277.612022) (xy 364.306059 -277.625714)
			(xy 364.257204 -277.631646) (xy 364.208029 -277.629665) (xy 364.15981 -277.619821) (xy 364.113794 -277.602369)
			(xy 364.071173 -277.577762) (xy 364.033052 -277.546637) (xy 364.000417 -277.5098) (xy 363.974114 -277.468204)
			(xy 363.954823 -277.422928) (xy 363.943046 -277.375144) (xy 363.939086 -277.32609) (xy 363.610144 -277.32609)
			(xy 363.609649 -277.350697) (xy 363.601754 -277.399274) (xy 363.58617 -277.445955) (xy 363.563299 -277.489532)
			(xy 363.533734 -277.528876) (xy 363.498241 -277.562968) (xy 363.457738 -277.590924) (xy 363.413276 -277.612022)
			(xy 363.366005 -277.625714) (xy 363.31715 -277.631646) (xy 363.267975 -277.629665) (xy 363.219756 -277.619821)
			(xy 363.17374 -277.602369) (xy 363.131119 -277.577762) (xy 363.092998 -277.546637) (xy 363.060363 -277.5098)
			(xy 363.03406 -277.468204) (xy 363.014769 -277.422928) (xy 363.002992 -277.375144) (xy 362.999032 -277.32609)
			(xy 362.67009 -277.32609) (xy 362.669595 -277.350697) (xy 362.6617 -277.399274) (xy 362.646116 -277.445955)
			(xy 362.623245 -277.489532) (xy 362.59368 -277.528876) (xy 362.558187 -277.562968) (xy 362.517684 -277.590924)
			(xy 362.473222 -277.612022) (xy 362.425951 -277.625714) (xy 362.377096 -277.631646) (xy 362.327921 -277.629665)
			(xy 362.279702 -277.619821) (xy 362.233686 -277.602369) (xy 362.191065 -277.577762) (xy 362.152944 -277.546637)
			(xy 362.120309 -277.5098) (xy 362.094006 -277.468204) (xy 362.074715 -277.422928) (xy 362.062938 -277.375144)
			(xy 362.058978 -277.32609) (xy 361.730036 -277.32609) (xy 361.729541 -277.350697) (xy 361.721646 -277.399274)
			(xy 361.706062 -277.445955) (xy 361.683191 -277.489532) (xy 361.653626 -277.528876) (xy 361.618133 -277.562968)
			(xy 361.57763 -277.590924) (xy 361.533168 -277.612022) (xy 361.485897 -277.625714) (xy 361.437042 -277.631646)
			(xy 361.387867 -277.629665) (xy 361.339648 -277.619821) (xy 361.293632 -277.602369) (xy 361.251011 -277.577762)
			(xy 361.21289 -277.546637) (xy 361.180255 -277.5098) (xy 361.153952 -277.468204) (xy 361.134661 -277.422928)
			(xy 361.122884 -277.375144) (xy 361.118924 -277.32609) (xy 358.916478 -277.32609) (xy 358.915983 -277.350697)
			(xy 358.908088 -277.399274) (xy 358.892504 -277.445955) (xy 358.869633 -277.489532) (xy 358.840068 -277.528876)
			(xy 358.804575 -277.562968) (xy 358.764072 -277.590924) (xy 358.71961 -277.612022) (xy 358.672339 -277.625714)
			(xy 358.623484 -277.631646) (xy 358.574309 -277.629665) (xy 358.52609 -277.619821) (xy 358.480074 -277.602369)
			(xy 358.437453 -277.577762) (xy 358.399332 -277.546637) (xy 358.366697 -277.5098) (xy 358.340394 -277.468204)
			(xy 358.321103 -277.422928) (xy 358.309326 -277.375144) (xy 358.305366 -277.32609) (xy 357.976424 -277.32609)
			(xy 357.975929 -277.350697) (xy 357.968034 -277.399274) (xy 357.95245 -277.445955) (xy 357.929579 -277.489532)
			(xy 357.900014 -277.528876) (xy 357.864521 -277.562968) (xy 357.824018 -277.590924) (xy 357.779556 -277.612022)
			(xy 357.732285 -277.625714) (xy 357.68343 -277.631646) (xy 357.634255 -277.629665) (xy 357.586036 -277.619821)
			(xy 357.54002 -277.602369) (xy 357.497399 -277.577762) (xy 357.459278 -277.546637) (xy 357.426643 -277.5098)
			(xy 357.40034 -277.468204) (xy 357.381049 -277.422928) (xy 357.369272 -277.375144) (xy 357.365312 -277.32609)
			(xy 357.03637 -277.32609) (xy 357.035875 -277.350697) (xy 357.02798 -277.399274) (xy 357.012396 -277.445955)
			(xy 356.989525 -277.489532) (xy 356.95996 -277.528876) (xy 356.924467 -277.562968) (xy 356.883964 -277.590924)
			(xy 356.839502 -277.612022) (xy 356.792231 -277.625714) (xy 356.743376 -277.631646) (xy 356.694201 -277.629665)
			(xy 356.645982 -277.619821) (xy 356.599966 -277.602369) (xy 356.557345 -277.577762) (xy 356.519224 -277.546637)
			(xy 356.486589 -277.5098) (xy 356.460286 -277.468204) (xy 356.440995 -277.422928) (xy 356.429218 -277.375144)
			(xy 356.425258 -277.32609) (xy 356.096316 -277.32609) (xy 356.095821 -277.350697) (xy 356.087926 -277.399274)
			(xy 356.072342 -277.445955) (xy 356.049471 -277.489532) (xy 356.019906 -277.528876) (xy 355.984413 -277.562968)
			(xy 355.94391 -277.590924) (xy 355.899448 -277.612022) (xy 355.852177 -277.625714) (xy 355.803322 -277.631646)
			(xy 355.754147 -277.629665) (xy 355.705928 -277.619821) (xy 355.659912 -277.602369) (xy 355.617291 -277.577762)
			(xy 355.57917 -277.546637) (xy 355.546535 -277.5098) (xy 355.520232 -277.468204) (xy 355.500941 -277.422928)
			(xy 355.489164 -277.375144) (xy 355.485204 -277.32609) (xy 355.156516 -277.32609) (xy 355.156021 -277.350697)
			(xy 355.148126 -277.399274) (xy 355.132542 -277.445955) (xy 355.109671 -277.489532) (xy 355.080106 -277.528876)
			(xy 355.044613 -277.562968) (xy 355.00411 -277.590924) (xy 354.959648 -277.612022) (xy 354.912377 -277.625714)
			(xy 354.863522 -277.631646) (xy 354.814347 -277.629665) (xy 354.766128 -277.619821) (xy 354.720112 -277.602369)
			(xy 354.677491 -277.577762) (xy 354.63937 -277.546637) (xy 354.606735 -277.5098) (xy 354.580432 -277.468204)
			(xy 354.561141 -277.422928) (xy 354.549364 -277.375144) (xy 354.545404 -277.32609) (xy 354.216462 -277.32609)
			(xy 354.215967 -277.350697) (xy 354.208072 -277.399274) (xy 354.192488 -277.445955) (xy 354.169617 -277.489532)
			(xy 354.140052 -277.528876) (xy 354.104559 -277.562968) (xy 354.064056 -277.590924) (xy 354.019594 -277.612022)
			(xy 353.972323 -277.625714) (xy 353.923468 -277.631646) (xy 353.874293 -277.629665) (xy 353.826074 -277.619821)
			(xy 353.780058 -277.602369) (xy 353.737437 -277.577762) (xy 353.699316 -277.546637) (xy 353.666681 -277.5098)
			(xy 353.640378 -277.468204) (xy 353.621087 -277.422928) (xy 353.60931 -277.375144) (xy 353.60535 -277.32609)
			(xy 353.276408 -277.32609) (xy 353.275913 -277.350697) (xy 353.268018 -277.399274) (xy 353.252434 -277.445955)
			(xy 353.229563 -277.489532) (xy 353.199998 -277.528876) (xy 353.164505 -277.562968) (xy 353.124002 -277.590924)
			(xy 353.07954 -277.612022) (xy 353.032269 -277.625714) (xy 352.983414 -277.631646) (xy 352.934239 -277.629665)
			(xy 352.88602 -277.619821) (xy 352.840004 -277.602369) (xy 352.797383 -277.577762) (xy 352.759262 -277.546637)
			(xy 352.726627 -277.5098) (xy 352.700324 -277.468204) (xy 352.681033 -277.422928) (xy 352.669256 -277.375144)
			(xy 352.665296 -277.32609) (xy 352.336354 -277.32609) (xy 352.335859 -277.350697) (xy 352.327964 -277.399274)
			(xy 352.31238 -277.445955) (xy 352.289509 -277.489532) (xy 352.259944 -277.528876) (xy 352.224451 -277.562968)
			(xy 352.183948 -277.590924) (xy 352.139486 -277.612022) (xy 352.092215 -277.625714) (xy 352.04336 -277.631646)
			(xy 351.994185 -277.629665) (xy 351.945966 -277.619821) (xy 351.89995 -277.602369) (xy 351.857329 -277.577762)
			(xy 351.819208 -277.546637) (xy 351.786573 -277.5098) (xy 351.76027 -277.468204) (xy 351.740979 -277.422928)
			(xy 351.729202 -277.375144) (xy 351.725242 -277.32609) (xy 351.396554 -277.32609) (xy 351.396059 -277.350697)
			(xy 351.388164 -277.399274) (xy 351.37258 -277.445955) (xy 351.349709 -277.489532) (xy 351.320144 -277.528876)
			(xy 351.284651 -277.562968) (xy 351.244148 -277.590924) (xy 351.199686 -277.612022) (xy 351.152415 -277.625714)
			(xy 351.10356 -277.631646) (xy 351.054385 -277.629665) (xy 351.006166 -277.619821) (xy 350.96015 -277.602369)
			(xy 350.917529 -277.577762) (xy 350.879408 -277.546637) (xy 350.846773 -277.5098) (xy 350.82047 -277.468204)
			(xy 350.801179 -277.422928) (xy 350.789402 -277.375144) (xy 350.785442 -277.32609) (xy 350.4565 -277.32609)
			(xy 350.456005 -277.350697) (xy 350.44811 -277.399274) (xy 350.432526 -277.445955) (xy 350.409655 -277.489532)
			(xy 350.38009 -277.528876) (xy 350.344597 -277.562968) (xy 350.304094 -277.590924) (xy 350.259632 -277.612022)
			(xy 350.212361 -277.625714) (xy 350.163506 -277.631646) (xy 350.114331 -277.629665) (xy 350.066112 -277.619821)
			(xy 350.020096 -277.602369) (xy 349.977475 -277.577762) (xy 349.939354 -277.546637) (xy 349.906719 -277.5098)
			(xy 349.880416 -277.468204) (xy 349.861125 -277.422928) (xy 349.849348 -277.375144) (xy 349.845388 -277.32609)
			(xy 349.516446 -277.32609) (xy 349.515951 -277.350697) (xy 349.508056 -277.399274) (xy 349.492472 -277.445955)
			(xy 349.469601 -277.489532) (xy 349.440036 -277.528876) (xy 349.404543 -277.562968) (xy 349.36404 -277.590924)
			(xy 349.319578 -277.612022) (xy 349.272307 -277.625714) (xy 349.223452 -277.631646) (xy 349.174277 -277.629665)
			(xy 349.126058 -277.619821) (xy 349.080042 -277.602369) (xy 349.037421 -277.577762) (xy 348.9993 -277.546637)
			(xy 348.966665 -277.5098) (xy 348.940362 -277.468204) (xy 348.921071 -277.422928) (xy 348.909294 -277.375144)
			(xy 348.905334 -277.32609) (xy 348.576392 -277.32609) (xy 348.575897 -277.350697) (xy 348.568002 -277.399274)
			(xy 348.552418 -277.445955) (xy 348.529547 -277.489532) (xy 348.499982 -277.528876) (xy 348.464489 -277.562968)
			(xy 348.423986 -277.590924) (xy 348.379524 -277.612022) (xy 348.332253 -277.625714) (xy 348.283398 -277.631646)
			(xy 348.234223 -277.629665) (xy 348.186004 -277.619821) (xy 348.139988 -277.602369) (xy 348.097367 -277.577762)
			(xy 348.059246 -277.546637) (xy 348.026611 -277.5098) (xy 348.000308 -277.468204) (xy 347.981017 -277.422928)
			(xy 347.96924 -277.375144) (xy 347.96528 -277.32609) (xy 347.636338 -277.32609) (xy 347.635843 -277.350697)
			(xy 347.627948 -277.399274) (xy 347.612364 -277.445955) (xy 347.589493 -277.489532) (xy 347.559928 -277.528876)
			(xy 347.524435 -277.562968) (xy 347.483932 -277.590924) (xy 347.43947 -277.612022) (xy 347.392199 -277.625714)
			(xy 347.343344 -277.631646) (xy 347.294169 -277.629665) (xy 347.24595 -277.619821) (xy 347.199934 -277.602369)
			(xy 347.157313 -277.577762) (xy 347.119192 -277.546637) (xy 347.086557 -277.5098) (xy 347.060254 -277.468204)
			(xy 347.040963 -277.422928) (xy 347.029186 -277.375144) (xy 347.025226 -277.32609) (xy 346.696538 -277.32609)
			(xy 346.696043 -277.350697) (xy 346.688148 -277.399274) (xy 346.672564 -277.445955) (xy 346.649693 -277.489532)
			(xy 346.620128 -277.528876) (xy 346.584635 -277.562968) (xy 346.544132 -277.590924) (xy 346.49967 -277.612022)
			(xy 346.452399 -277.625714) (xy 346.403544 -277.631646) (xy 346.354369 -277.629665) (xy 346.30615 -277.619821)
			(xy 346.260134 -277.602369) (xy 346.217513 -277.577762) (xy 346.179392 -277.546637) (xy 346.146757 -277.5098)
			(xy 346.120454 -277.468204) (xy 346.101163 -277.422928) (xy 346.089386 -277.375144) (xy 346.085426 -277.32609)
			(xy 345.756484 -277.32609) (xy 345.755989 -277.350697) (xy 345.748094 -277.399274) (xy 345.73251 -277.445955)
			(xy 345.709639 -277.489532) (xy 345.680074 -277.528876) (xy 345.644581 -277.562968) (xy 345.604078 -277.590924)
			(xy 345.559616 -277.612022) (xy 345.512345 -277.625714) (xy 345.46349 -277.631646) (xy 345.414315 -277.629665)
			(xy 345.366096 -277.619821) (xy 345.32008 -277.602369) (xy 345.277459 -277.577762) (xy 345.239338 -277.546637)
			(xy 345.206703 -277.5098) (xy 345.1804 -277.468204) (xy 345.161109 -277.422928) (xy 345.149332 -277.375144)
			(xy 345.145372 -277.32609) (xy 344.880692 -277.32609) (xy 344.880692 -277.730204) (xy 344.881149 -277.740082)
			(xy 344.888588 -277.758385) (xy 344.89517 -277.765764) (xy 344.895424 -277.766018) (xy 344.945208 -277.815802)
			(xy 344.952607 -277.822647) (xy 344.971205 -277.830378) (xy 344.981276 -277.830788) (xy 345.006517 -277.831331)
			(xy 345.056304 -277.839681) (xy 345.104039 -277.856106) (xy 345.148422 -277.880161) (xy 345.188244 -277.911188)
			(xy 345.222418 -277.948344) (xy 345.250016 -277.990615) (xy 345.270283 -278.036851) (xy 345.282669 -278.08579)
			(xy 345.286835 -278.136096) (xy 345.615272 -278.136096) (xy 345.619232 -278.087042) (xy 345.631009 -278.039258)
			(xy 345.6503 -277.993982) (xy 345.676603 -277.952386) (xy 345.709238 -277.915549) (xy 345.747359 -277.884424)
			(xy 345.78998 -277.859817) (xy 345.835996 -277.842365) (xy 345.884215 -277.832521) (xy 345.93339 -277.83054)
			(xy 345.982245 -277.836472) (xy 346.029516 -277.850164) (xy 346.073978 -277.871262) (xy 346.114481 -277.899218)
			(xy 346.149974 -277.93331) (xy 346.179539 -277.972654) (xy 346.20241 -278.016231) (xy 346.217994 -278.062912)
			(xy 346.225889 -278.111489) (xy 346.226384 -278.136096) (xy 346.555326 -278.136096) (xy 346.559286 -278.087042)
			(xy 346.571063 -278.039258) (xy 346.590354 -277.993982) (xy 346.616657 -277.952386) (xy 346.649292 -277.915549)
			(xy 346.687413 -277.884424) (xy 346.730034 -277.859817) (xy 346.77605 -277.842365) (xy 346.824269 -277.832521)
			(xy 346.873444 -277.83054) (xy 346.922299 -277.836472) (xy 346.96957 -277.850164) (xy 347.014032 -277.871262)
			(xy 347.054535 -277.899218) (xy 347.090028 -277.93331) (xy 347.119593 -277.972654) (xy 347.142464 -278.016231)
			(xy 347.158048 -278.062912) (xy 347.165943 -278.111489) (xy 347.166438 -278.136096) (xy 347.49538 -278.136096)
			(xy 347.49934 -278.087042) (xy 347.511117 -278.039258) (xy 347.530408 -277.993982) (xy 347.556711 -277.952386)
			(xy 347.589346 -277.915549) (xy 347.627467 -277.884424) (xy 347.670088 -277.859817) (xy 347.716104 -277.842365)
			(xy 347.764323 -277.832521) (xy 347.813498 -277.83054) (xy 347.862353 -277.836472) (xy 347.909624 -277.850164)
			(xy 347.954086 -277.871262) (xy 347.994589 -277.899218) (xy 348.030082 -277.93331) (xy 348.059647 -277.972654)
			(xy 348.082518 -278.016231) (xy 348.098102 -278.062912) (xy 348.105997 -278.111489) (xy 348.106492 -278.136096)
			(xy 348.435434 -278.136096) (xy 348.439394 -278.087042) (xy 348.451171 -278.039258) (xy 348.470462 -277.993982)
			(xy 348.496765 -277.952386) (xy 348.5294 -277.915549) (xy 348.567521 -277.884424) (xy 348.610142 -277.859817)
			(xy 348.656158 -277.842365) (xy 348.704377 -277.832521) (xy 348.753552 -277.83054) (xy 348.802407 -277.836472)
			(xy 348.849678 -277.850164) (xy 348.89414 -277.871262) (xy 348.934643 -277.899218) (xy 348.970136 -277.93331)
			(xy 348.999701 -277.972654) (xy 349.022572 -278.016231) (xy 349.038156 -278.062912) (xy 349.046051 -278.111489)
			(xy 349.046546 -278.136096) (xy 349.375234 -278.136096) (xy 349.379194 -278.087042) (xy 349.390971 -278.039258)
			(xy 349.410262 -277.993982) (xy 349.436565 -277.952386) (xy 349.4692 -277.915549) (xy 349.507321 -277.884424)
			(xy 349.549942 -277.859817) (xy 349.595958 -277.842365) (xy 349.644177 -277.832521) (xy 349.693352 -277.83054)
			(xy 349.742207 -277.836472) (xy 349.789478 -277.850164) (xy 349.83394 -277.871262) (xy 349.874443 -277.899218)
			(xy 349.909936 -277.93331) (xy 349.939501 -277.972654) (xy 349.962372 -278.016231) (xy 349.977956 -278.062912)
			(xy 349.985851 -278.111489) (xy 349.986346 -278.136096) (xy 350.315288 -278.136096) (xy 350.319248 -278.087042)
			(xy 350.331025 -278.039258) (xy 350.350316 -277.993982) (xy 350.376619 -277.952386) (xy 350.409254 -277.915549)
			(xy 350.447375 -277.884424) (xy 350.489996 -277.859817) (xy 350.536012 -277.842365) (xy 350.584231 -277.832521)
			(xy 350.633406 -277.83054) (xy 350.682261 -277.836472) (xy 350.729532 -277.850164) (xy 350.773994 -277.871262)
			(xy 350.814497 -277.899218) (xy 350.84999 -277.93331) (xy 350.879555 -277.972654) (xy 350.902426 -278.016231)
			(xy 350.91801 -278.062912) (xy 350.925905 -278.111489) (xy 350.9264 -278.136096) (xy 351.255342 -278.136096)
			(xy 351.259302 -278.087042) (xy 351.271079 -278.039258) (xy 351.29037 -277.993982) (xy 351.316673 -277.952386)
			(xy 351.349308 -277.915549) (xy 351.387429 -277.884424) (xy 351.43005 -277.859817) (xy 351.476066 -277.842365)
			(xy 351.524285 -277.832521) (xy 351.57346 -277.83054) (xy 351.622315 -277.836472) (xy 351.669586 -277.850164)
			(xy 351.714048 -277.871262) (xy 351.754551 -277.899218) (xy 351.790044 -277.93331) (xy 351.819609 -277.972654)
			(xy 351.84248 -278.016231) (xy 351.858064 -278.062912) (xy 351.865959 -278.111489) (xy 351.866454 -278.136096)
			(xy 352.195396 -278.136096) (xy 352.199356 -278.087042) (xy 352.211133 -278.039258) (xy 352.230424 -277.993982)
			(xy 352.256727 -277.952386) (xy 352.289362 -277.915549) (xy 352.327483 -277.884424) (xy 352.370104 -277.859817)
			(xy 352.41612 -277.842365) (xy 352.464339 -277.832521) (xy 352.513514 -277.83054) (xy 352.562369 -277.836472)
			(xy 352.60964 -277.850164) (xy 352.654102 -277.871262) (xy 352.694605 -277.899218) (xy 352.730098 -277.93331)
			(xy 352.759663 -277.972654) (xy 352.782534 -278.016231) (xy 352.798118 -278.062912) (xy 352.806013 -278.111489)
			(xy 352.806508 -278.136096) (xy 353.135196 -278.136096) (xy 353.139156 -278.087042) (xy 353.150933 -278.039258)
			(xy 353.170224 -277.993982) (xy 353.196527 -277.952386) (xy 353.229162 -277.915549) (xy 353.267283 -277.884424)
			(xy 353.309904 -277.859817) (xy 353.35592 -277.842365) (xy 353.404139 -277.832521) (xy 353.453314 -277.83054)
			(xy 353.502169 -277.836472) (xy 353.54944 -277.850164) (xy 353.593902 -277.871262) (xy 353.634405 -277.899218)
			(xy 353.669898 -277.93331) (xy 353.699463 -277.972654) (xy 353.722334 -278.016231) (xy 353.737918 -278.062912)
			(xy 353.745813 -278.111489) (xy 353.746308 -278.136096) (xy 354.07525 -278.136096) (xy 354.07921 -278.087042)
			(xy 354.090987 -278.039258) (xy 354.110278 -277.993982) (xy 354.136581 -277.952386) (xy 354.169216 -277.915549)
			(xy 354.207337 -277.884424) (xy 354.249958 -277.859817) (xy 354.295974 -277.842365) (xy 354.344193 -277.832521)
			(xy 354.393368 -277.83054) (xy 354.442223 -277.836472) (xy 354.489494 -277.850164) (xy 354.533956 -277.871262)
			(xy 354.574459 -277.899218) (xy 354.609952 -277.93331) (xy 354.639517 -277.972654) (xy 354.662388 -278.016231)
			(xy 354.677972 -278.062912) (xy 354.685867 -278.111489) (xy 354.686362 -278.136096) (xy 355.015304 -278.136096)
			(xy 355.019264 -278.087042) (xy 355.031041 -278.039258) (xy 355.050332 -277.993982) (xy 355.076635 -277.952386)
			(xy 355.10927 -277.915549) (xy 355.147391 -277.884424) (xy 355.190012 -277.859817) (xy 355.236028 -277.842365)
			(xy 355.284247 -277.832521) (xy 355.333422 -277.83054) (xy 355.382277 -277.836472) (xy 355.429548 -277.850164)
			(xy 355.47401 -277.871262) (xy 355.514513 -277.899218) (xy 355.550006 -277.93331) (xy 355.579571 -277.972654)
			(xy 355.602442 -278.016231) (xy 355.618026 -278.062912) (xy 355.625921 -278.111489) (xy 355.626416 -278.136096)
			(xy 355.955358 -278.136096) (xy 355.959318 -278.087042) (xy 355.971095 -278.039258) (xy 355.990386 -277.993982)
			(xy 356.016689 -277.952386) (xy 356.049324 -277.915549) (xy 356.087445 -277.884424) (xy 356.130066 -277.859817)
			(xy 356.176082 -277.842365) (xy 356.224301 -277.832521) (xy 356.273476 -277.83054) (xy 356.322331 -277.836472)
			(xy 356.369602 -277.850164) (xy 356.414064 -277.871262) (xy 356.454567 -277.899218) (xy 356.49006 -277.93331)
			(xy 356.519625 -277.972654) (xy 356.542496 -278.016231) (xy 356.55808 -278.062912) (xy 356.565975 -278.111489)
			(xy 356.56647 -278.136096) (xy 363.468932 -278.136096) (xy 363.472892 -278.087042) (xy 363.484669 -278.039258)
			(xy 363.50396 -277.993982) (xy 363.530263 -277.952386) (xy 363.562898 -277.915549) (xy 363.601019 -277.884424)
			(xy 363.64364 -277.859817) (xy 363.689656 -277.842365) (xy 363.737875 -277.832521) (xy 363.78705 -277.83054)
			(xy 363.835905 -277.836472) (xy 363.883176 -277.850164) (xy 363.927638 -277.871262) (xy 363.968141 -277.899218)
			(xy 364.003634 -277.93331) (xy 364.033199 -277.972654) (xy 364.05607 -278.016231) (xy 364.071654 -278.062912)
			(xy 364.079549 -278.111489) (xy 364.080044 -278.136096) (xy 364.408986 -278.136096) (xy 364.412946 -278.087042)
			(xy 364.424723 -278.039258) (xy 364.444014 -277.993982) (xy 364.470317 -277.952386) (xy 364.502952 -277.915549)
			(xy 364.541073 -277.884424) (xy 364.583694 -277.859817) (xy 364.62971 -277.842365) (xy 364.677929 -277.832521)
			(xy 364.727104 -277.83054) (xy 364.775959 -277.836472) (xy 364.82323 -277.850164) (xy 364.867692 -277.871262)
			(xy 364.908195 -277.899218) (xy 364.943688 -277.93331) (xy 364.973253 -277.972654) (xy 364.996124 -278.016231)
			(xy 365.011708 -278.062912) (xy 365.019603 -278.111489) (xy 365.020098 -278.136096) (xy 365.34904 -278.136096)
			(xy 365.353 -278.087042) (xy 365.364777 -278.039258) (xy 365.384068 -277.993982) (xy 365.410371 -277.952386)
			(xy 365.443006 -277.915549) (xy 365.481127 -277.884424) (xy 365.523748 -277.859817) (xy 365.569764 -277.842365)
			(xy 365.617983 -277.832521) (xy 365.667158 -277.83054) (xy 365.716013 -277.836472) (xy 365.763284 -277.850164)
			(xy 365.807746 -277.871262) (xy 365.848249 -277.899218) (xy 365.883742 -277.93331) (xy 365.913307 -277.972654)
			(xy 365.936178 -278.016231) (xy 365.951762 -278.062912) (xy 365.959657 -278.111489) (xy 365.960152 -278.136096)
			(xy 366.289094 -278.136096) (xy 366.293054 -278.087042) (xy 366.304831 -278.039258) (xy 366.324122 -277.993982)
			(xy 366.350425 -277.952386) (xy 366.38306 -277.915549) (xy 366.421181 -277.884424) (xy 366.463802 -277.859817)
			(xy 366.509818 -277.842365) (xy 366.558037 -277.832521) (xy 366.607212 -277.83054) (xy 366.656067 -277.836472)
			(xy 366.703338 -277.850164) (xy 366.7478 -277.871262) (xy 366.788303 -277.899218) (xy 366.823796 -277.93331)
			(xy 366.853361 -277.972654) (xy 366.876232 -278.016231) (xy 366.891816 -278.062912) (xy 366.899711 -278.111489)
			(xy 366.900206 -278.136096) (xy 367.228894 -278.136096) (xy 367.232854 -278.087042) (xy 367.244631 -278.039258)
			(xy 367.263922 -277.993982) (xy 367.290225 -277.952386) (xy 367.32286 -277.915549) (xy 367.360981 -277.884424)
			(xy 367.403602 -277.859817) (xy 367.449618 -277.842365) (xy 367.497837 -277.832521) (xy 367.547012 -277.83054)
			(xy 367.595867 -277.836472) (xy 367.643138 -277.850164) (xy 367.6876 -277.871262) (xy 367.728103 -277.899218)
			(xy 367.763596 -277.93331) (xy 367.793161 -277.972654) (xy 367.816032 -278.016231) (xy 367.831616 -278.062912)
			(xy 367.839511 -278.111489) (xy 367.840006 -278.136096) (xy 368.168948 -278.136096) (xy 368.172908 -278.087042)
			(xy 368.184685 -278.039258) (xy 368.203976 -277.993982) (xy 368.230279 -277.952386) (xy 368.262914 -277.915549)
			(xy 368.301035 -277.884424) (xy 368.343656 -277.859817) (xy 368.389672 -277.842365) (xy 368.437891 -277.832521)
			(xy 368.487066 -277.83054) (xy 368.535921 -277.836472) (xy 368.583192 -277.850164) (xy 368.627654 -277.871262)
			(xy 368.668157 -277.899218) (xy 368.70365 -277.93331) (xy 368.733215 -277.972654) (xy 368.756086 -278.016231)
			(xy 368.77167 -278.062912) (xy 368.779565 -278.111489) (xy 368.78006 -278.136096) (xy 369.109002 -278.136096)
			(xy 369.112962 -278.087042) (xy 369.124739 -278.039258) (xy 369.14403 -277.993982) (xy 369.170333 -277.952386)
			(xy 369.202968 -277.915549) (xy 369.241089 -277.884424) (xy 369.28371 -277.859817) (xy 369.329726 -277.842365)
			(xy 369.377945 -277.832521) (xy 369.42712 -277.83054) (xy 369.475975 -277.836472) (xy 369.523246 -277.850164)
			(xy 369.567708 -277.871262) (xy 369.608211 -277.899218) (xy 369.643704 -277.93331) (xy 369.673269 -277.972654)
			(xy 369.69614 -278.016231) (xy 369.711724 -278.062912) (xy 369.719619 -278.111489) (xy 369.720114 -278.136096)
			(xy 370.049056 -278.136096) (xy 370.053016 -278.087042) (xy 370.064793 -278.039258) (xy 370.084084 -277.993982)
			(xy 370.110387 -277.952386) (xy 370.143022 -277.915549) (xy 370.181143 -277.884424) (xy 370.223764 -277.859817)
			(xy 370.26978 -277.842365) (xy 370.317999 -277.832521) (xy 370.367174 -277.83054) (xy 370.416029 -277.836472)
			(xy 370.4633 -277.850164) (xy 370.507762 -277.871262) (xy 370.548265 -277.899218) (xy 370.583758 -277.93331)
			(xy 370.613323 -277.972654) (xy 370.636194 -278.016231) (xy 370.651778 -278.062912) (xy 370.659673 -278.111489)
			(xy 370.660168 -278.136096) (xy 370.98911 -278.136096) (xy 370.99307 -278.087042) (xy 371.004847 -278.039258)
			(xy 371.024138 -277.993982) (xy 371.050441 -277.952386) (xy 371.083076 -277.915549) (xy 371.121197 -277.884424)
			(xy 371.163818 -277.859817) (xy 371.209834 -277.842365) (xy 371.258053 -277.832521) (xy 371.307228 -277.83054)
			(xy 371.356083 -277.836472) (xy 371.403354 -277.850164) (xy 371.447816 -277.871262) (xy 371.488319 -277.899218)
			(xy 371.523812 -277.93331) (xy 371.553377 -277.972654) (xy 371.576248 -278.016231) (xy 371.591832 -278.062912)
			(xy 371.599727 -278.111489) (xy 371.600222 -278.136096) (xy 371.92891 -278.136096) (xy 371.93287 -278.087042)
			(xy 371.944647 -278.039258) (xy 371.963938 -277.993982) (xy 371.990241 -277.952386) (xy 372.022876 -277.915549)
			(xy 372.060997 -277.884424) (xy 372.103618 -277.859817) (xy 372.149634 -277.842365) (xy 372.197853 -277.832521)
			(xy 372.247028 -277.83054) (xy 372.295883 -277.836472) (xy 372.343154 -277.850164) (xy 372.387616 -277.871262)
			(xy 372.428119 -277.899218) (xy 372.463612 -277.93331) (xy 372.493177 -277.972654) (xy 372.516048 -278.016231)
			(xy 372.531632 -278.062912) (xy 372.539527 -278.111489) (xy 372.540022 -278.136096) (xy 372.539527 -278.160703)
			(xy 372.531632 -278.20928) (xy 372.516048 -278.255961) (xy 372.493177 -278.299538) (xy 372.463612 -278.338882)
			(xy 372.428119 -278.372974) (xy 372.387616 -278.40093) (xy 372.343154 -278.422028) (xy 372.295883 -278.43572)
			(xy 372.247028 -278.441652) (xy 372.197853 -278.439671) (xy 372.149634 -278.429827) (xy 372.103618 -278.412375)
			(xy 372.060997 -278.387768) (xy 372.022876 -278.356643) (xy 371.990241 -278.319806) (xy 371.963938 -278.27821)
			(xy 371.944647 -278.232934) (xy 371.93287 -278.18515) (xy 371.92891 -278.136096) (xy 371.600222 -278.136096)
			(xy 371.599727 -278.160703) (xy 371.591832 -278.20928) (xy 371.576248 -278.255961) (xy 371.553377 -278.299538)
			(xy 371.523812 -278.338882) (xy 371.488319 -278.372974) (xy 371.447816 -278.40093) (xy 371.403354 -278.422028)
			(xy 371.356083 -278.43572) (xy 371.307228 -278.441652) (xy 371.258053 -278.439671) (xy 371.209834 -278.429827)
			(xy 371.163818 -278.412375) (xy 371.121197 -278.387768) (xy 371.083076 -278.356643) (xy 371.050441 -278.319806)
			(xy 371.024138 -278.27821) (xy 371.004847 -278.232934) (xy 370.99307 -278.18515) (xy 370.98911 -278.136096)
			(xy 370.660168 -278.136096) (xy 370.659673 -278.160703) (xy 370.651778 -278.20928) (xy 370.636194 -278.255961)
			(xy 370.613323 -278.299538) (xy 370.583758 -278.338882) (xy 370.548265 -278.372974) (xy 370.507762 -278.40093)
			(xy 370.4633 -278.422028) (xy 370.416029 -278.43572) (xy 370.367174 -278.441652) (xy 370.317999 -278.439671)
			(xy 370.26978 -278.429827) (xy 370.223764 -278.412375) (xy 370.181143 -278.387768) (xy 370.143022 -278.356643)
			(xy 370.110387 -278.319806) (xy 370.084084 -278.27821) (xy 370.064793 -278.232934) (xy 370.053016 -278.18515)
			(xy 370.049056 -278.136096) (xy 369.720114 -278.136096) (xy 369.719619 -278.160703) (xy 369.711724 -278.20928)
			(xy 369.69614 -278.255961) (xy 369.673269 -278.299538) (xy 369.643704 -278.338882) (xy 369.608211 -278.372974)
			(xy 369.567708 -278.40093) (xy 369.523246 -278.422028) (xy 369.475975 -278.43572) (xy 369.42712 -278.441652)
			(xy 369.377945 -278.439671) (xy 369.329726 -278.429827) (xy 369.28371 -278.412375) (xy 369.241089 -278.387768)
			(xy 369.202968 -278.356643) (xy 369.170333 -278.319806) (xy 369.14403 -278.27821) (xy 369.124739 -278.232934)
			(xy 369.112962 -278.18515) (xy 369.109002 -278.136096) (xy 368.78006 -278.136096) (xy 368.779565 -278.160703)
			(xy 368.77167 -278.20928) (xy 368.756086 -278.255961) (xy 368.733215 -278.299538) (xy 368.70365 -278.338882)
			(xy 368.668157 -278.372974) (xy 368.627654 -278.40093) (xy 368.583192 -278.422028) (xy 368.535921 -278.43572)
			(xy 368.487066 -278.441652) (xy 368.437891 -278.439671) (xy 368.389672 -278.429827) (xy 368.343656 -278.412375)
			(xy 368.301035 -278.387768) (xy 368.262914 -278.356643) (xy 368.230279 -278.319806) (xy 368.203976 -278.27821)
			(xy 368.184685 -278.232934) (xy 368.172908 -278.18515) (xy 368.168948 -278.136096) (xy 367.840006 -278.136096)
			(xy 367.839511 -278.160703) (xy 367.831616 -278.20928) (xy 367.816032 -278.255961) (xy 367.793161 -278.299538)
			(xy 367.763596 -278.338882) (xy 367.728103 -278.372974) (xy 367.6876 -278.40093) (xy 367.643138 -278.422028)
			(xy 367.595867 -278.43572) (xy 367.547012 -278.441652) (xy 367.497837 -278.439671) (xy 367.449618 -278.429827)
			(xy 367.403602 -278.412375) (xy 367.360981 -278.387768) (xy 367.32286 -278.356643) (xy 367.290225 -278.319806)
			(xy 367.263922 -278.27821) (xy 367.244631 -278.232934) (xy 367.232854 -278.18515) (xy 367.228894 -278.136096)
			(xy 366.900206 -278.136096) (xy 366.899711 -278.160703) (xy 366.891816 -278.20928) (xy 366.876232 -278.255961)
			(xy 366.853361 -278.299538) (xy 366.823796 -278.338882) (xy 366.788303 -278.372974) (xy 366.7478 -278.40093)
			(xy 366.703338 -278.422028) (xy 366.656067 -278.43572) (xy 366.607212 -278.441652) (xy 366.558037 -278.439671)
			(xy 366.509818 -278.429827) (xy 366.463802 -278.412375) (xy 366.421181 -278.387768) (xy 366.38306 -278.356643)
			(xy 366.350425 -278.319806) (xy 366.324122 -278.27821) (xy 366.304831 -278.232934) (xy 366.293054 -278.18515)
			(xy 366.289094 -278.136096) (xy 365.960152 -278.136096) (xy 365.959657 -278.160703) (xy 365.951762 -278.20928)
			(xy 365.936178 -278.255961) (xy 365.913307 -278.299538) (xy 365.883742 -278.338882) (xy 365.848249 -278.372974)
			(xy 365.807746 -278.40093) (xy 365.763284 -278.422028) (xy 365.716013 -278.43572) (xy 365.667158 -278.441652)
			(xy 365.617983 -278.439671) (xy 365.569764 -278.429827) (xy 365.523748 -278.412375) (xy 365.481127 -278.387768)
			(xy 365.443006 -278.356643) (xy 365.410371 -278.319806) (xy 365.384068 -278.27821) (xy 365.364777 -278.232934)
			(xy 365.353 -278.18515) (xy 365.34904 -278.136096) (xy 365.020098 -278.136096) (xy 365.019603 -278.160703)
			(xy 365.011708 -278.20928) (xy 364.996124 -278.255961) (xy 364.973253 -278.299538) (xy 364.943688 -278.338882)
			(xy 364.908195 -278.372974) (xy 364.867692 -278.40093) (xy 364.82323 -278.422028) (xy 364.775959 -278.43572)
			(xy 364.727104 -278.441652) (xy 364.677929 -278.439671) (xy 364.62971 -278.429827) (xy 364.583694 -278.412375)
			(xy 364.541073 -278.387768) (xy 364.502952 -278.356643) (xy 364.470317 -278.319806) (xy 364.444014 -278.27821)
			(xy 364.424723 -278.232934) (xy 364.412946 -278.18515) (xy 364.408986 -278.136096) (xy 364.080044 -278.136096)
			(xy 364.079549 -278.160703) (xy 364.071654 -278.20928) (xy 364.05607 -278.255961) (xy 364.033199 -278.299538)
			(xy 364.003634 -278.338882) (xy 363.968141 -278.372974) (xy 363.927638 -278.40093) (xy 363.883176 -278.422028)
			(xy 363.835905 -278.43572) (xy 363.78705 -278.441652) (xy 363.737875 -278.439671) (xy 363.689656 -278.429827)
			(xy 363.64364 -278.412375) (xy 363.601019 -278.387768) (xy 363.562898 -278.356643) (xy 363.530263 -278.319806)
			(xy 363.50396 -278.27821) (xy 363.484669 -278.232934) (xy 363.472892 -278.18515) (xy 363.468932 -278.136096)
			(xy 356.56647 -278.136096) (xy 356.565975 -278.160703) (xy 356.55808 -278.20928) (xy 356.542496 -278.255961)
			(xy 356.519625 -278.299538) (xy 356.49006 -278.338882) (xy 356.454567 -278.372974) (xy 356.414064 -278.40093)
			(xy 356.369602 -278.422028) (xy 356.322331 -278.43572) (xy 356.273476 -278.441652) (xy 356.224301 -278.439671)
			(xy 356.176082 -278.429827) (xy 356.130066 -278.412375) (xy 356.087445 -278.387768) (xy 356.049324 -278.356643)
			(xy 356.016689 -278.319806) (xy 355.990386 -278.27821) (xy 355.971095 -278.232934) (xy 355.959318 -278.18515)
			(xy 355.955358 -278.136096) (xy 355.626416 -278.136096) (xy 355.625921 -278.160703) (xy 355.618026 -278.20928)
			(xy 355.602442 -278.255961) (xy 355.579571 -278.299538) (xy 355.550006 -278.338882) (xy 355.514513 -278.372974)
			(xy 355.47401 -278.40093) (xy 355.429548 -278.422028) (xy 355.382277 -278.43572) (xy 355.333422 -278.441652)
			(xy 355.284247 -278.439671) (xy 355.236028 -278.429827) (xy 355.190012 -278.412375) (xy 355.147391 -278.387768)
			(xy 355.10927 -278.356643) (xy 355.076635 -278.319806) (xy 355.050332 -278.27821) (xy 355.031041 -278.232934)
			(xy 355.019264 -278.18515) (xy 355.015304 -278.136096) (xy 354.686362 -278.136096) (xy 354.685867 -278.160703)
			(xy 354.677972 -278.20928) (xy 354.662388 -278.255961) (xy 354.639517 -278.299538) (xy 354.609952 -278.338882)
			(xy 354.574459 -278.372974) (xy 354.533956 -278.40093) (xy 354.489494 -278.422028) (xy 354.442223 -278.43572)
			(xy 354.393368 -278.441652) (xy 354.344193 -278.439671) (xy 354.295974 -278.429827) (xy 354.249958 -278.412375)
			(xy 354.207337 -278.387768) (xy 354.169216 -278.356643) (xy 354.136581 -278.319806) (xy 354.110278 -278.27821)
			(xy 354.090987 -278.232934) (xy 354.07921 -278.18515) (xy 354.07525 -278.136096) (xy 353.746308 -278.136096)
			(xy 353.745813 -278.160703) (xy 353.737918 -278.20928) (xy 353.722334 -278.255961) (xy 353.699463 -278.299538)
			(xy 353.669898 -278.338882) (xy 353.634405 -278.372974) (xy 353.593902 -278.40093) (xy 353.54944 -278.422028)
			(xy 353.502169 -278.43572) (xy 353.453314 -278.441652) (xy 353.404139 -278.439671) (xy 353.35592 -278.429827)
			(xy 353.309904 -278.412375) (xy 353.267283 -278.387768) (xy 353.229162 -278.356643) (xy 353.196527 -278.319806)
			(xy 353.170224 -278.27821) (xy 353.150933 -278.232934) (xy 353.139156 -278.18515) (xy 353.135196 -278.136096)
			(xy 352.806508 -278.136096) (xy 352.806013 -278.160703) (xy 352.798118 -278.20928) (xy 352.782534 -278.255961)
			(xy 352.759663 -278.299538) (xy 352.730098 -278.338882) (xy 352.694605 -278.372974) (xy 352.654102 -278.40093)
			(xy 352.60964 -278.422028) (xy 352.562369 -278.43572) (xy 352.513514 -278.441652) (xy 352.464339 -278.439671)
			(xy 352.41612 -278.429827) (xy 352.370104 -278.412375) (xy 352.327483 -278.387768) (xy 352.289362 -278.356643)
			(xy 352.256727 -278.319806) (xy 352.230424 -278.27821) (xy 352.211133 -278.232934) (xy 352.199356 -278.18515)
			(xy 352.195396 -278.136096) (xy 351.866454 -278.136096) (xy 351.865959 -278.160703) (xy 351.858064 -278.20928)
			(xy 351.84248 -278.255961) (xy 351.819609 -278.299538) (xy 351.790044 -278.338882) (xy 351.754551 -278.372974)
			(xy 351.714048 -278.40093) (xy 351.669586 -278.422028) (xy 351.622315 -278.43572) (xy 351.57346 -278.441652)
			(xy 351.524285 -278.439671) (xy 351.476066 -278.429827) (xy 351.43005 -278.412375) (xy 351.387429 -278.387768)
			(xy 351.349308 -278.356643) (xy 351.316673 -278.319806) (xy 351.29037 -278.27821) (xy 351.271079 -278.232934)
			(xy 351.259302 -278.18515) (xy 351.255342 -278.136096) (xy 350.9264 -278.136096) (xy 350.925905 -278.160703)
			(xy 350.91801 -278.20928) (xy 350.902426 -278.255961) (xy 350.879555 -278.299538) (xy 350.84999 -278.338882)
			(xy 350.814497 -278.372974) (xy 350.773994 -278.40093) (xy 350.729532 -278.422028) (xy 350.682261 -278.43572)
			(xy 350.633406 -278.441652) (xy 350.584231 -278.439671) (xy 350.536012 -278.429827) (xy 350.489996 -278.412375)
			(xy 350.447375 -278.387768) (xy 350.409254 -278.356643) (xy 350.376619 -278.319806) (xy 350.350316 -278.27821)
			(xy 350.331025 -278.232934) (xy 350.319248 -278.18515) (xy 350.315288 -278.136096) (xy 349.986346 -278.136096)
			(xy 349.985851 -278.160703) (xy 349.977956 -278.20928) (xy 349.962372 -278.255961) (xy 349.939501 -278.299538)
			(xy 349.909936 -278.338882) (xy 349.874443 -278.372974) (xy 349.83394 -278.40093) (xy 349.789478 -278.422028)
			(xy 349.742207 -278.43572) (xy 349.693352 -278.441652) (xy 349.644177 -278.439671) (xy 349.595958 -278.429827)
			(xy 349.549942 -278.412375) (xy 349.507321 -278.387768) (xy 349.4692 -278.356643) (xy 349.436565 -278.319806)
			(xy 349.410262 -278.27821) (xy 349.390971 -278.232934) (xy 349.379194 -278.18515) (xy 349.375234 -278.136096)
			(xy 349.046546 -278.136096) (xy 349.046051 -278.160703) (xy 349.038156 -278.20928) (xy 349.022572 -278.255961)
			(xy 348.999701 -278.299538) (xy 348.970136 -278.338882) (xy 348.934643 -278.372974) (xy 348.89414 -278.40093)
			(xy 348.849678 -278.422028) (xy 348.802407 -278.43572) (xy 348.753552 -278.441652) (xy 348.704377 -278.439671)
			(xy 348.656158 -278.429827) (xy 348.610142 -278.412375) (xy 348.567521 -278.387768) (xy 348.5294 -278.356643)
			(xy 348.496765 -278.319806) (xy 348.470462 -278.27821) (xy 348.451171 -278.232934) (xy 348.439394 -278.18515)
			(xy 348.435434 -278.136096) (xy 348.106492 -278.136096) (xy 348.105997 -278.160703) (xy 348.098102 -278.20928)
			(xy 348.082518 -278.255961) (xy 348.059647 -278.299538) (xy 348.030082 -278.338882) (xy 347.994589 -278.372974)
			(xy 347.954086 -278.40093) (xy 347.909624 -278.422028) (xy 347.862353 -278.43572) (xy 347.813498 -278.441652)
			(xy 347.764323 -278.439671) (xy 347.716104 -278.429827) (xy 347.670088 -278.412375) (xy 347.627467 -278.387768)
			(xy 347.589346 -278.356643) (xy 347.556711 -278.319806) (xy 347.530408 -278.27821) (xy 347.511117 -278.232934)
			(xy 347.49934 -278.18515) (xy 347.49538 -278.136096) (xy 347.166438 -278.136096) (xy 347.165943 -278.160703)
			(xy 347.158048 -278.20928) (xy 347.142464 -278.255961) (xy 347.119593 -278.299538) (xy 347.090028 -278.338882)
			(xy 347.054535 -278.372974) (xy 347.014032 -278.40093) (xy 346.96957 -278.422028) (xy 346.922299 -278.43572)
			(xy 346.873444 -278.441652) (xy 346.824269 -278.439671) (xy 346.77605 -278.429827) (xy 346.730034 -278.412375)
			(xy 346.687413 -278.387768) (xy 346.649292 -278.356643) (xy 346.616657 -278.319806) (xy 346.590354 -278.27821)
			(xy 346.571063 -278.232934) (xy 346.559286 -278.18515) (xy 346.555326 -278.136096) (xy 346.226384 -278.136096)
			(xy 346.225889 -278.160703) (xy 346.217994 -278.20928) (xy 346.20241 -278.255961) (xy 346.179539 -278.299538)
			(xy 346.149974 -278.338882) (xy 346.114481 -278.372974) (xy 346.073978 -278.40093) (xy 346.029516 -278.422028)
			(xy 345.982245 -278.43572) (xy 345.93339 -278.441652) (xy 345.884215 -278.439671) (xy 345.835996 -278.429827)
			(xy 345.78998 -278.412375) (xy 345.747359 -278.387768) (xy 345.709238 -278.356643) (xy 345.676603 -278.319806)
			(xy 345.6503 -278.27821) (xy 345.631009 -278.232934) (xy 345.619232 -278.18515) (xy 345.615272 -278.136096)
			(xy 345.286835 -278.136096) (xy 345.286835 -278.1361) (xy 345.282669 -278.18641) (xy 345.270283 -278.235349)
			(xy 345.250016 -278.281585) (xy 345.222418 -278.323856) (xy 345.188244 -278.361012) (xy 345.148422 -278.392039)
			(xy 345.104039 -278.416094) (xy 345.056304 -278.432519) (xy 345.006517 -278.440869) (xy 344.981276 -278.441404)
			(xy 344.971208 -278.441832) (xy 344.95261 -278.449553) (xy 344.945208 -278.45639) (xy 344.895424 -278.506174)
			(xy 344.888701 -278.513408) (xy 344.881087 -278.531614) (xy 344.880692 -278.54148) (xy 344.880692 -278.946102)
			(xy 347.025226 -278.946102) (xy 347.029186 -278.897048) (xy 347.040963 -278.849264) (xy 347.060254 -278.803988)
			(xy 347.086557 -278.762392) (xy 347.119192 -278.725555) (xy 347.157313 -278.69443) (xy 347.199934 -278.669823)
			(xy 347.24595 -278.652371) (xy 347.294169 -278.642527) (xy 347.343344 -278.640546) (xy 347.392199 -278.646478)
			(xy 347.43947 -278.66017) (xy 347.483932 -278.681268) (xy 347.524435 -278.709224) (xy 347.559928 -278.743316)
			(xy 347.589493 -278.78266) (xy 347.612364 -278.826237) (xy 347.627948 -278.872918) (xy 347.635843 -278.921495)
			(xy 347.636338 -278.946102) (xy 349.845388 -278.946102) (xy 349.849348 -278.897048) (xy 349.861125 -278.849264)
			(xy 349.880416 -278.803988) (xy 349.906719 -278.762392) (xy 349.939354 -278.725555) (xy 349.977475 -278.69443)
			(xy 350.020096 -278.669823) (xy 350.066112 -278.652371) (xy 350.114331 -278.642527) (xy 350.163506 -278.640546)
			(xy 350.212361 -278.646478) (xy 350.259632 -278.66017) (xy 350.304094 -278.681268) (xy 350.344597 -278.709224)
			(xy 350.38009 -278.743316) (xy 350.409655 -278.78266) (xy 350.432526 -278.826237) (xy 350.44811 -278.872918)
			(xy 350.456005 -278.921495) (xy 350.4565 -278.946102) (xy 352.665296 -278.946102) (xy 352.669256 -278.897048)
			(xy 352.681033 -278.849264) (xy 352.700324 -278.803988) (xy 352.726627 -278.762392) (xy 352.759262 -278.725555)
			(xy 352.797383 -278.69443) (xy 352.840004 -278.669823) (xy 352.88602 -278.652371) (xy 352.934239 -278.642527)
			(xy 352.983414 -278.640546) (xy 353.032269 -278.646478) (xy 353.07954 -278.66017) (xy 353.124002 -278.681268)
			(xy 353.164505 -278.709224) (xy 353.199998 -278.743316) (xy 353.229563 -278.78266) (xy 353.252434 -278.826237)
			(xy 353.268018 -278.872918) (xy 353.275913 -278.921495) (xy 353.276408 -278.946102) (xy 355.485204 -278.946102)
			(xy 355.489164 -278.897048) (xy 355.500941 -278.849264) (xy 355.520232 -278.803988) (xy 355.546535 -278.762392)
			(xy 355.57917 -278.725555) (xy 355.617291 -278.69443) (xy 355.659912 -278.669823) (xy 355.705928 -278.652371)
			(xy 355.754147 -278.642527) (xy 355.803322 -278.640546) (xy 355.852177 -278.646478) (xy 355.899448 -278.66017)
			(xy 355.94391 -278.681268) (xy 355.984413 -278.709224) (xy 356.019906 -278.743316) (xy 356.049471 -278.78266)
			(xy 356.072342 -278.826237) (xy 356.087926 -278.872918) (xy 356.095821 -278.921495) (xy 356.096316 -278.946102)
			(xy 356.425258 -278.946102) (xy 356.429218 -278.897048) (xy 356.440995 -278.849264) (xy 356.460286 -278.803988)
			(xy 356.486589 -278.762392) (xy 356.519224 -278.725555) (xy 356.557345 -278.69443) (xy 356.599966 -278.669823)
			(xy 356.645982 -278.652371) (xy 356.694201 -278.642527) (xy 356.743376 -278.640546) (xy 356.792231 -278.646478)
			(xy 356.839502 -278.66017) (xy 356.883964 -278.681268) (xy 356.924467 -278.709224) (xy 356.95996 -278.743316)
			(xy 356.989525 -278.78266) (xy 357.012396 -278.826237) (xy 357.02798 -278.872918) (xy 357.035875 -278.921495)
			(xy 357.03637 -278.946102) (xy 357.365312 -278.946102) (xy 357.369272 -278.897048) (xy 357.381049 -278.849264)
			(xy 357.40034 -278.803988) (xy 357.426643 -278.762392) (xy 357.459278 -278.725555) (xy 357.497399 -278.69443)
			(xy 357.54002 -278.669823) (xy 357.586036 -278.652371) (xy 357.634255 -278.642527) (xy 357.68343 -278.640546)
			(xy 357.732285 -278.646478) (xy 357.779556 -278.66017) (xy 357.824018 -278.681268) (xy 357.864521 -278.709224)
			(xy 357.900014 -278.743316) (xy 357.929579 -278.78266) (xy 357.95245 -278.826237) (xy 357.968034 -278.872918)
			(xy 357.975929 -278.921495) (xy 357.976424 -278.946102) (xy 358.305366 -278.946102) (xy 358.309326 -278.897048)
			(xy 358.321103 -278.849264) (xy 358.340394 -278.803988) (xy 358.366697 -278.762392) (xy 358.399332 -278.725555)
			(xy 358.437453 -278.69443) (xy 358.480074 -278.669823) (xy 358.52609 -278.652371) (xy 358.574309 -278.642527)
			(xy 358.623484 -278.640546) (xy 358.672339 -278.646478) (xy 358.71961 -278.66017) (xy 358.764072 -278.681268)
			(xy 358.804575 -278.709224) (xy 358.840068 -278.743316) (xy 358.869633 -278.78266) (xy 358.892504 -278.826237)
			(xy 358.908088 -278.872918) (xy 358.915983 -278.921495) (xy 358.916478 -278.946102) (xy 361.118924 -278.946102)
			(xy 361.122884 -278.897048) (xy 361.134661 -278.849264) (xy 361.153952 -278.803988) (xy 361.180255 -278.762392)
			(xy 361.21289 -278.725555) (xy 361.251011 -278.69443) (xy 361.293632 -278.669823) (xy 361.339648 -278.652371)
			(xy 361.387867 -278.642527) (xy 361.437042 -278.640546) (xy 361.485897 -278.646478) (xy 361.533168 -278.66017)
			(xy 361.57763 -278.681268) (xy 361.618133 -278.709224) (xy 361.653626 -278.743316) (xy 361.683191 -278.78266)
			(xy 361.706062 -278.826237) (xy 361.721646 -278.872918) (xy 361.729541 -278.921495) (xy 361.730036 -278.946102)
			(xy 362.058978 -278.946102) (xy 362.062938 -278.897048) (xy 362.074715 -278.849264) (xy 362.094006 -278.803988)
			(xy 362.120309 -278.762392) (xy 362.152944 -278.725555) (xy 362.191065 -278.69443) (xy 362.233686 -278.669823)
			(xy 362.279702 -278.652371) (xy 362.327921 -278.642527) (xy 362.377096 -278.640546) (xy 362.425951 -278.646478)
			(xy 362.473222 -278.66017) (xy 362.517684 -278.681268) (xy 362.558187 -278.709224) (xy 362.59368 -278.743316)
			(xy 362.623245 -278.78266) (xy 362.646116 -278.826237) (xy 362.6617 -278.872918) (xy 362.669595 -278.921495)
			(xy 362.67009 -278.946102) (xy 362.999032 -278.946102) (xy 363.002992 -278.897048) (xy 363.014769 -278.849264)
			(xy 363.03406 -278.803988) (xy 363.060363 -278.762392) (xy 363.092998 -278.725555) (xy 363.131119 -278.69443)
			(xy 363.17374 -278.669823) (xy 363.219756 -278.652371) (xy 363.267975 -278.642527) (xy 363.31715 -278.640546)
			(xy 363.366005 -278.646478) (xy 363.413276 -278.66017) (xy 363.457738 -278.681268) (xy 363.498241 -278.709224)
			(xy 363.533734 -278.743316) (xy 363.563299 -278.78266) (xy 363.58617 -278.826237) (xy 363.601754 -278.872918)
			(xy 363.609649 -278.921495) (xy 363.610144 -278.946102) (xy 363.939086 -278.946102) (xy 363.943046 -278.897048)
			(xy 363.954823 -278.849264) (xy 363.974114 -278.803988) (xy 364.000417 -278.762392) (xy 364.033052 -278.725555)
			(xy 364.071173 -278.69443) (xy 364.113794 -278.669823) (xy 364.15981 -278.652371) (xy 364.208029 -278.642527)
			(xy 364.257204 -278.640546) (xy 364.306059 -278.646478) (xy 364.35333 -278.66017) (xy 364.397792 -278.681268)
			(xy 364.438295 -278.709224) (xy 364.473788 -278.743316) (xy 364.503353 -278.78266) (xy 364.526224 -278.826237)
			(xy 364.541808 -278.872918) (xy 364.549703 -278.921495) (xy 364.550198 -278.946102) (xy 366.758994 -278.946102)
			(xy 366.762954 -278.897048) (xy 366.774731 -278.849264) (xy 366.794022 -278.803988) (xy 366.820325 -278.762392)
			(xy 366.85296 -278.725555) (xy 366.891081 -278.69443) (xy 366.933702 -278.669823) (xy 366.979718 -278.652371)
			(xy 367.027937 -278.642527) (xy 367.077112 -278.640546) (xy 367.125967 -278.646478) (xy 367.173238 -278.66017)
			(xy 367.2177 -278.681268) (xy 367.258203 -278.709224) (xy 367.293696 -278.743316) (xy 367.323261 -278.78266)
			(xy 367.346132 -278.826237) (xy 367.361716 -278.872918) (xy 367.369611 -278.921495) (xy 367.370106 -278.946102)
			(xy 369.578902 -278.946102) (xy 369.582862 -278.897048) (xy 369.594639 -278.849264) (xy 369.61393 -278.803988)
			(xy 369.640233 -278.762392) (xy 369.672868 -278.725555) (xy 369.710989 -278.69443) (xy 369.75361 -278.669823)
			(xy 369.799626 -278.652371) (xy 369.847845 -278.642527) (xy 369.89702 -278.640546) (xy 369.945875 -278.646478)
			(xy 369.993146 -278.66017) (xy 370.037608 -278.681268) (xy 370.078111 -278.709224) (xy 370.113604 -278.743316)
			(xy 370.143169 -278.78266) (xy 370.16604 -278.826237) (xy 370.181624 -278.872918) (xy 370.189519 -278.921495)
			(xy 370.190014 -278.946102) (xy 372.399064 -278.946102) (xy 372.403024 -278.897048) (xy 372.414801 -278.849264)
			(xy 372.434092 -278.803988) (xy 372.460395 -278.762392) (xy 372.49303 -278.725555) (xy 372.531151 -278.69443)
			(xy 372.573772 -278.669823) (xy 372.619788 -278.652371) (xy 372.668007 -278.642527) (xy 372.717182 -278.640546)
			(xy 372.766037 -278.646478) (xy 372.813308 -278.66017) (xy 372.85777 -278.681268) (xy 372.898273 -278.709224)
			(xy 372.933766 -278.743316) (xy 372.963331 -278.78266) (xy 372.986202 -278.826237) (xy 373.001786 -278.872918)
			(xy 373.009681 -278.921495) (xy 373.010176 -278.946102) (xy 373.009681 -278.970709) (xy 373.001786 -279.019286)
			(xy 372.986202 -279.065967) (xy 372.963331 -279.109544) (xy 372.933766 -279.148888) (xy 372.898273 -279.18298)
			(xy 372.85777 -279.210936) (xy 372.813308 -279.232034) (xy 372.766037 -279.245726) (xy 372.717182 -279.251658)
			(xy 372.668007 -279.249677) (xy 372.619788 -279.239833) (xy 372.573772 -279.222381) (xy 372.531151 -279.197774)
			(xy 372.49303 -279.166649) (xy 372.460395 -279.129812) (xy 372.434092 -279.088216) (xy 372.414801 -279.04294)
			(xy 372.403024 -278.995156) (xy 372.399064 -278.946102) (xy 370.190014 -278.946102) (xy 370.189519 -278.970709)
			(xy 370.181624 -279.019286) (xy 370.16604 -279.065967) (xy 370.143169 -279.109544) (xy 370.113604 -279.148888)
			(xy 370.078111 -279.18298) (xy 370.037608 -279.210936) (xy 369.993146 -279.232034) (xy 369.945875 -279.245726)
			(xy 369.89702 -279.251658) (xy 369.847845 -279.249677) (xy 369.799626 -279.239833) (xy 369.75361 -279.222381)
			(xy 369.710989 -279.197774) (xy 369.672868 -279.166649) (xy 369.640233 -279.129812) (xy 369.61393 -279.088216)
			(xy 369.594639 -279.04294) (xy 369.582862 -278.995156) (xy 369.578902 -278.946102) (xy 367.370106 -278.946102)
			(xy 367.369611 -278.970709) (xy 367.361716 -279.019286) (xy 367.346132 -279.065967) (xy 367.323261 -279.109544)
			(xy 367.293696 -279.148888) (xy 367.258203 -279.18298) (xy 367.2177 -279.210936) (xy 367.173238 -279.232034)
			(xy 367.125967 -279.245726) (xy 367.077112 -279.251658) (xy 367.027937 -279.249677) (xy 366.979718 -279.239833)
			(xy 366.933702 -279.222381) (xy 366.891081 -279.197774) (xy 366.85296 -279.166649) (xy 366.820325 -279.129812)
			(xy 366.794022 -279.088216) (xy 366.774731 -279.04294) (xy 366.762954 -278.995156) (xy 366.758994 -278.946102)
			(xy 364.550198 -278.946102) (xy 364.549703 -278.970709) (xy 364.541808 -279.019286) (xy 364.526224 -279.065967)
			(xy 364.503353 -279.109544) (xy 364.473788 -279.148888) (xy 364.438295 -279.18298) (xy 364.397792 -279.210936)
			(xy 364.35333 -279.232034) (xy 364.306059 -279.245726) (xy 364.257204 -279.251658) (xy 364.208029 -279.249677)
			(xy 364.15981 -279.239833) (xy 364.113794 -279.222381) (xy 364.071173 -279.197774) (xy 364.033052 -279.166649)
			(xy 364.000417 -279.129812) (xy 363.974114 -279.088216) (xy 363.954823 -279.04294) (xy 363.943046 -278.995156)
			(xy 363.939086 -278.946102) (xy 363.610144 -278.946102) (xy 363.609649 -278.970709) (xy 363.601754 -279.019286)
			(xy 363.58617 -279.065967) (xy 363.563299 -279.109544) (xy 363.533734 -279.148888) (xy 363.498241 -279.18298)
			(xy 363.457738 -279.210936) (xy 363.413276 -279.232034) (xy 363.366005 -279.245726) (xy 363.31715 -279.251658)
			(xy 363.267975 -279.249677) (xy 363.219756 -279.239833) (xy 363.17374 -279.222381) (xy 363.131119 -279.197774)
			(xy 363.092998 -279.166649) (xy 363.060363 -279.129812) (xy 363.03406 -279.088216) (xy 363.014769 -279.04294)
			(xy 363.002992 -278.995156) (xy 362.999032 -278.946102) (xy 362.67009 -278.946102) (xy 362.669595 -278.970709)
			(xy 362.6617 -279.019286) (xy 362.646116 -279.065967) (xy 362.623245 -279.109544) (xy 362.59368 -279.148888)
			(xy 362.558187 -279.18298) (xy 362.517684 -279.210936) (xy 362.473222 -279.232034) (xy 362.425951 -279.245726)
			(xy 362.377096 -279.251658) (xy 362.327921 -279.249677) (xy 362.279702 -279.239833) (xy 362.233686 -279.222381)
			(xy 362.191065 -279.197774) (xy 362.152944 -279.166649) (xy 362.120309 -279.129812) (xy 362.094006 -279.088216)
			(xy 362.074715 -279.04294) (xy 362.062938 -278.995156) (xy 362.058978 -278.946102) (xy 361.730036 -278.946102)
			(xy 361.729541 -278.970709) (xy 361.721646 -279.019286) (xy 361.706062 -279.065967) (xy 361.683191 -279.109544)
			(xy 361.653626 -279.148888) (xy 361.618133 -279.18298) (xy 361.57763 -279.210936) (xy 361.533168 -279.232034)
			(xy 361.485897 -279.245726) (xy 361.437042 -279.251658) (xy 361.387867 -279.249677) (xy 361.339648 -279.239833)
			(xy 361.293632 -279.222381) (xy 361.251011 -279.197774) (xy 361.21289 -279.166649) (xy 361.180255 -279.129812)
			(xy 361.153952 -279.088216) (xy 361.134661 -279.04294) (xy 361.122884 -278.995156) (xy 361.118924 -278.946102)
			(xy 358.916478 -278.946102) (xy 358.915983 -278.970709) (xy 358.908088 -279.019286) (xy 358.892504 -279.065967)
			(xy 358.869633 -279.109544) (xy 358.840068 -279.148888) (xy 358.804575 -279.18298) (xy 358.764072 -279.210936)
			(xy 358.71961 -279.232034) (xy 358.672339 -279.245726) (xy 358.623484 -279.251658) (xy 358.574309 -279.249677)
			(xy 358.52609 -279.239833) (xy 358.480074 -279.222381) (xy 358.437453 -279.197774) (xy 358.399332 -279.166649)
			(xy 358.366697 -279.129812) (xy 358.340394 -279.088216) (xy 358.321103 -279.04294) (xy 358.309326 -278.995156)
			(xy 358.305366 -278.946102) (xy 357.976424 -278.946102) (xy 357.975929 -278.970709) (xy 357.968034 -279.019286)
			(xy 357.95245 -279.065967) (xy 357.929579 -279.109544) (xy 357.900014 -279.148888) (xy 357.864521 -279.18298)
			(xy 357.824018 -279.210936) (xy 357.779556 -279.232034) (xy 357.732285 -279.245726) (xy 357.68343 -279.251658)
			(xy 357.634255 -279.249677) (xy 357.586036 -279.239833) (xy 357.54002 -279.222381) (xy 357.497399 -279.197774)
			(xy 357.459278 -279.166649) (xy 357.426643 -279.129812) (xy 357.40034 -279.088216) (xy 357.381049 -279.04294)
			(xy 357.369272 -278.995156) (xy 357.365312 -278.946102) (xy 357.03637 -278.946102) (xy 357.035875 -278.970709)
			(xy 357.02798 -279.019286) (xy 357.012396 -279.065967) (xy 356.989525 -279.109544) (xy 356.95996 -279.148888)
			(xy 356.924467 -279.18298) (xy 356.883964 -279.210936) (xy 356.839502 -279.232034) (xy 356.792231 -279.245726)
			(xy 356.743376 -279.251658) (xy 356.694201 -279.249677) (xy 356.645982 -279.239833) (xy 356.599966 -279.222381)
			(xy 356.557345 -279.197774) (xy 356.519224 -279.166649) (xy 356.486589 -279.129812) (xy 356.460286 -279.088216)
			(xy 356.440995 -279.04294) (xy 356.429218 -278.995156) (xy 356.425258 -278.946102) (xy 356.096316 -278.946102)
			(xy 356.095821 -278.970709) (xy 356.087926 -279.019286) (xy 356.072342 -279.065967) (xy 356.049471 -279.109544)
			(xy 356.019906 -279.148888) (xy 355.984413 -279.18298) (xy 355.94391 -279.210936) (xy 355.899448 -279.232034)
			(xy 355.852177 -279.245726) (xy 355.803322 -279.251658) (xy 355.754147 -279.249677) (xy 355.705928 -279.239833)
			(xy 355.659912 -279.222381) (xy 355.617291 -279.197774) (xy 355.57917 -279.166649) (xy 355.546535 -279.129812)
			(xy 355.520232 -279.088216) (xy 355.500941 -279.04294) (xy 355.489164 -278.995156) (xy 355.485204 -278.946102)
			(xy 353.276408 -278.946102) (xy 353.275913 -278.970709) (xy 353.268018 -279.019286) (xy 353.252434 -279.065967)
			(xy 353.229563 -279.109544) (xy 353.199998 -279.148888) (xy 353.164505 -279.18298) (xy 353.124002 -279.210936)
			(xy 353.07954 -279.232034) (xy 353.032269 -279.245726) (xy 352.983414 -279.251658) (xy 352.934239 -279.249677)
			(xy 352.88602 -279.239833) (xy 352.840004 -279.222381) (xy 352.797383 -279.197774) (xy 352.759262 -279.166649)
			(xy 352.726627 -279.129812) (xy 352.700324 -279.088216) (xy 352.681033 -279.04294) (xy 352.669256 -278.995156)
			(xy 352.665296 -278.946102) (xy 350.4565 -278.946102) (xy 350.456005 -278.970709) (xy 350.44811 -279.019286)
			(xy 350.432526 -279.065967) (xy 350.409655 -279.109544) (xy 350.38009 -279.148888) (xy 350.344597 -279.18298)
			(xy 350.304094 -279.210936) (xy 350.259632 -279.232034) (xy 350.212361 -279.245726) (xy 350.163506 -279.251658)
			(xy 350.114331 -279.249677) (xy 350.066112 -279.239833) (xy 350.020096 -279.222381) (xy 349.977475 -279.197774)
			(xy 349.939354 -279.166649) (xy 349.906719 -279.129812) (xy 349.880416 -279.088216) (xy 349.861125 -279.04294)
			(xy 349.849348 -278.995156) (xy 349.845388 -278.946102) (xy 347.636338 -278.946102) (xy 347.635843 -278.970709)
			(xy 347.627948 -279.019286) (xy 347.612364 -279.065967) (xy 347.589493 -279.109544) (xy 347.559928 -279.148888)
			(xy 347.524435 -279.18298) (xy 347.483932 -279.210936) (xy 347.43947 -279.232034) (xy 347.392199 -279.245726)
			(xy 347.343344 -279.251658) (xy 347.294169 -279.249677) (xy 347.24595 -279.239833) (xy 347.199934 -279.222381)
			(xy 347.157313 -279.197774) (xy 347.119192 -279.166649) (xy 347.086557 -279.129812) (xy 347.060254 -279.088216)
			(xy 347.040963 -279.04294) (xy 347.029186 -278.995156) (xy 347.025226 -278.946102) (xy 344.880692 -278.946102)
			(xy 344.880692 -279.350216) (xy 344.881152 -279.360093) (xy 344.888593 -279.378393) (xy 344.89517 -279.385776)
			(xy 344.895424 -279.38603) (xy 344.945208 -279.435814) (xy 344.952603 -279.442668) (xy 344.971202 -279.450414)
			(xy 344.981276 -279.4508) (xy 345.006516 -279.451343) (xy 345.056301 -279.459692) (xy 345.104034 -279.476117)
			(xy 345.148416 -279.500171) (xy 345.188235 -279.531197) (xy 345.222409 -279.568351) (xy 345.250005 -279.610621)
			(xy 345.270272 -279.656854) (xy 345.282657 -279.705792) (xy 345.286823 -279.7561) (xy 345.286822 -279.756108)
			(xy 345.615272 -279.756108) (xy 345.619232 -279.707054) (xy 345.631009 -279.65927) (xy 345.6503 -279.613994)
			(xy 345.676603 -279.572398) (xy 345.709238 -279.535561) (xy 345.747359 -279.504436) (xy 345.78998 -279.479829)
			(xy 345.835996 -279.462377) (xy 345.884215 -279.452533) (xy 345.93339 -279.450552) (xy 345.982245 -279.456484)
			(xy 346.029516 -279.470176) (xy 346.073978 -279.491274) (xy 346.114481 -279.51923) (xy 346.149974 -279.553322)
			(xy 346.179539 -279.592666) (xy 346.20241 -279.636243) (xy 346.217994 -279.682924) (xy 346.225889 -279.731501)
			(xy 346.226384 -279.756108) (xy 346.555326 -279.756108) (xy 346.559286 -279.707054) (xy 346.571063 -279.65927)
			(xy 346.590354 -279.613994) (xy 346.616657 -279.572398) (xy 346.649292 -279.535561) (xy 346.687413 -279.504436)
			(xy 346.730034 -279.479829) (xy 346.77605 -279.462377) (xy 346.824269 -279.452533) (xy 346.873444 -279.450552)
			(xy 346.922299 -279.456484) (xy 346.96957 -279.470176) (xy 347.014032 -279.491274) (xy 347.054535 -279.51923)
			(xy 347.090028 -279.553322) (xy 347.119593 -279.592666) (xy 347.142464 -279.636243) (xy 347.158048 -279.682924)
			(xy 347.165943 -279.731501) (xy 347.166438 -279.756108) (xy 347.49538 -279.756108) (xy 347.49934 -279.707054)
			(xy 347.511117 -279.65927) (xy 347.530408 -279.613994) (xy 347.556711 -279.572398) (xy 347.589346 -279.535561)
			(xy 347.627467 -279.504436) (xy 347.670088 -279.479829) (xy 347.716104 -279.462377) (xy 347.764323 -279.452533)
			(xy 347.813498 -279.450552) (xy 347.862353 -279.456484) (xy 347.909624 -279.470176) (xy 347.954086 -279.491274)
			(xy 347.994589 -279.51923) (xy 348.030082 -279.553322) (xy 348.059647 -279.592666) (xy 348.082518 -279.636243)
			(xy 348.098102 -279.682924) (xy 348.105997 -279.731501) (xy 348.106492 -279.756108) (xy 348.435434 -279.756108)
			(xy 348.439394 -279.707054) (xy 348.451171 -279.65927) (xy 348.470462 -279.613994) (xy 348.496765 -279.572398)
			(xy 348.5294 -279.535561) (xy 348.567521 -279.504436) (xy 348.610142 -279.479829) (xy 348.656158 -279.462377)
			(xy 348.704377 -279.452533) (xy 348.753552 -279.450552) (xy 348.802407 -279.456484) (xy 348.849678 -279.470176)
			(xy 348.89414 -279.491274) (xy 348.934643 -279.51923) (xy 348.970136 -279.553322) (xy 348.999701 -279.592666)
			(xy 349.022572 -279.636243) (xy 349.038156 -279.682924) (xy 349.046051 -279.731501) (xy 349.046546 -279.756108)
			(xy 349.375234 -279.756108) (xy 349.379194 -279.707054) (xy 349.390971 -279.65927) (xy 349.410262 -279.613994)
			(xy 349.436565 -279.572398) (xy 349.4692 -279.535561) (xy 349.507321 -279.504436) (xy 349.549942 -279.479829)
			(xy 349.595958 -279.462377) (xy 349.644177 -279.452533) (xy 349.693352 -279.450552) (xy 349.742207 -279.456484)
			(xy 349.789478 -279.470176) (xy 349.83394 -279.491274) (xy 349.874443 -279.51923) (xy 349.909936 -279.553322)
			(xy 349.939501 -279.592666) (xy 349.962372 -279.636243) (xy 349.977956 -279.682924) (xy 349.985851 -279.731501)
			(xy 349.986346 -279.756108) (xy 350.315288 -279.756108) (xy 350.319248 -279.707054) (xy 350.331025 -279.65927)
			(xy 350.350316 -279.613994) (xy 350.376619 -279.572398) (xy 350.409254 -279.535561) (xy 350.447375 -279.504436)
			(xy 350.489996 -279.479829) (xy 350.536012 -279.462377) (xy 350.584231 -279.452533) (xy 350.633406 -279.450552)
			(xy 350.682261 -279.456484) (xy 350.729532 -279.470176) (xy 350.773994 -279.491274) (xy 350.814497 -279.51923)
			(xy 350.84999 -279.553322) (xy 350.879555 -279.592666) (xy 350.902426 -279.636243) (xy 350.91801 -279.682924)
			(xy 350.925905 -279.731501) (xy 350.9264 -279.756108) (xy 351.255342 -279.756108) (xy 351.259302 -279.707054)
			(xy 351.271079 -279.65927) (xy 351.29037 -279.613994) (xy 351.316673 -279.572398) (xy 351.349308 -279.535561)
			(xy 351.387429 -279.504436) (xy 351.43005 -279.479829) (xy 351.476066 -279.462377) (xy 351.524285 -279.452533)
			(xy 351.57346 -279.450552) (xy 351.622315 -279.456484) (xy 351.669586 -279.470176) (xy 351.714048 -279.491274)
			(xy 351.754551 -279.51923) (xy 351.790044 -279.553322) (xy 351.819609 -279.592666) (xy 351.84248 -279.636243)
			(xy 351.858064 -279.682924) (xy 351.865959 -279.731501) (xy 351.866454 -279.756108) (xy 352.195396 -279.756108)
			(xy 352.199356 -279.707054) (xy 352.211133 -279.65927) (xy 352.230424 -279.613994) (xy 352.256727 -279.572398)
			(xy 352.289362 -279.535561) (xy 352.327483 -279.504436) (xy 352.370104 -279.479829) (xy 352.41612 -279.462377)
			(xy 352.464339 -279.452533) (xy 352.513514 -279.450552) (xy 352.562369 -279.456484) (xy 352.60964 -279.470176)
			(xy 352.654102 -279.491274) (xy 352.694605 -279.51923) (xy 352.730098 -279.553322) (xy 352.759663 -279.592666)
			(xy 352.782534 -279.636243) (xy 352.798118 -279.682924) (xy 352.806013 -279.731501) (xy 352.806508 -279.756108)
			(xy 353.135196 -279.756108) (xy 353.139156 -279.707054) (xy 353.150933 -279.65927) (xy 353.170224 -279.613994)
			(xy 353.196527 -279.572398) (xy 353.229162 -279.535561) (xy 353.267283 -279.504436) (xy 353.309904 -279.479829)
			(xy 353.35592 -279.462377) (xy 353.404139 -279.452533) (xy 353.453314 -279.450552) (xy 353.502169 -279.456484)
			(xy 353.54944 -279.470176) (xy 353.593902 -279.491274) (xy 353.634405 -279.51923) (xy 353.669898 -279.553322)
			(xy 353.699463 -279.592666) (xy 353.722334 -279.636243) (xy 353.737918 -279.682924) (xy 353.745813 -279.731501)
			(xy 353.746308 -279.756108) (xy 354.07525 -279.756108) (xy 354.07921 -279.707054) (xy 354.090987 -279.65927)
			(xy 354.110278 -279.613994) (xy 354.136581 -279.572398) (xy 354.169216 -279.535561) (xy 354.207337 -279.504436)
			(xy 354.249958 -279.479829) (xy 354.295974 -279.462377) (xy 354.344193 -279.452533) (xy 354.393368 -279.450552)
			(xy 354.442223 -279.456484) (xy 354.489494 -279.470176) (xy 354.533956 -279.491274) (xy 354.574459 -279.51923)
			(xy 354.609952 -279.553322) (xy 354.639517 -279.592666) (xy 354.662388 -279.636243) (xy 354.677972 -279.682924)
			(xy 354.685867 -279.731501) (xy 354.686362 -279.756108) (xy 355.015304 -279.756108) (xy 355.019264 -279.707054)
			(xy 355.031041 -279.65927) (xy 355.050332 -279.613994) (xy 355.076635 -279.572398) (xy 355.10927 -279.535561)
			(xy 355.147391 -279.504436) (xy 355.190012 -279.479829) (xy 355.236028 -279.462377) (xy 355.284247 -279.452533)
			(xy 355.333422 -279.450552) (xy 355.382277 -279.456484) (xy 355.429548 -279.470176) (xy 355.47401 -279.491274)
			(xy 355.514513 -279.51923) (xy 355.550006 -279.553322) (xy 355.579571 -279.592666) (xy 355.602442 -279.636243)
			(xy 355.618026 -279.682924) (xy 355.625921 -279.731501) (xy 355.626416 -279.756108) (xy 355.955358 -279.756108)
			(xy 355.959318 -279.707054) (xy 355.971095 -279.65927) (xy 355.990386 -279.613994) (xy 356.016689 -279.572398)
			(xy 356.049324 -279.535561) (xy 356.087445 -279.504436) (xy 356.130066 -279.479829) (xy 356.176082 -279.462377)
			(xy 356.224301 -279.452533) (xy 356.273476 -279.450552) (xy 356.322331 -279.456484) (xy 356.369602 -279.470176)
			(xy 356.414064 -279.491274) (xy 356.454567 -279.51923) (xy 356.49006 -279.553322) (xy 356.519625 -279.592666)
			(xy 356.542496 -279.636243) (xy 356.55808 -279.682924) (xy 356.565975 -279.731501) (xy 356.56647 -279.756108)
			(xy 356.895412 -279.756108) (xy 356.899372 -279.707054) (xy 356.911149 -279.65927) (xy 356.93044 -279.613994)
			(xy 356.956743 -279.572398) (xy 356.989378 -279.535561) (xy 357.027499 -279.504436) (xy 357.07012 -279.479829)
			(xy 357.116136 -279.462377) (xy 357.164355 -279.452533) (xy 357.21353 -279.450552) (xy 357.262385 -279.456484)
			(xy 357.309656 -279.470176) (xy 357.354118 -279.491274) (xy 357.394621 -279.51923) (xy 357.430114 -279.553322)
			(xy 357.459679 -279.592666) (xy 357.48255 -279.636243) (xy 357.498134 -279.682924) (xy 357.506029 -279.731501)
			(xy 357.506524 -279.756108) (xy 357.835212 -279.756108) (xy 357.839172 -279.707054) (xy 357.850949 -279.65927)
			(xy 357.87024 -279.613994) (xy 357.896543 -279.572398) (xy 357.929178 -279.535561) (xy 357.967299 -279.504436)
			(xy 358.00992 -279.479829) (xy 358.055936 -279.462377) (xy 358.104155 -279.452533) (xy 358.15333 -279.450552)
			(xy 358.202185 -279.456484) (xy 358.249456 -279.470176) (xy 358.293918 -279.491274) (xy 358.334421 -279.51923)
			(xy 358.369914 -279.553322) (xy 358.399479 -279.592666) (xy 358.42235 -279.636243) (xy 358.437934 -279.682924)
			(xy 358.445829 -279.731501) (xy 358.446324 -279.756108) (xy 361.589078 -279.756108) (xy 361.593038 -279.707054)
			(xy 361.604815 -279.65927) (xy 361.624106 -279.613994) (xy 361.650409 -279.572398) (xy 361.683044 -279.535561)
			(xy 361.721165 -279.504436) (xy 361.763786 -279.479829) (xy 361.809802 -279.462377) (xy 361.858021 -279.452533)
			(xy 361.907196 -279.450552) (xy 361.956051 -279.456484) (xy 362.003322 -279.470176) (xy 362.047784 -279.491274)
			(xy 362.088287 -279.51923) (xy 362.12378 -279.553322) (xy 362.153345 -279.592666) (xy 362.176216 -279.636243)
			(xy 362.1918 -279.682924) (xy 362.199695 -279.731501) (xy 362.20019 -279.756108) (xy 362.528878 -279.756108)
			(xy 362.532838 -279.707054) (xy 362.544615 -279.65927) (xy 362.563906 -279.613994) (xy 362.590209 -279.572398)
			(xy 362.622844 -279.535561) (xy 362.660965 -279.504436) (xy 362.703586 -279.479829) (xy 362.749602 -279.462377)
			(xy 362.797821 -279.452533) (xy 362.846996 -279.450552) (xy 362.895851 -279.456484) (xy 362.943122 -279.470176)
			(xy 362.987584 -279.491274) (xy 363.028087 -279.51923) (xy 363.06358 -279.553322) (xy 363.093145 -279.592666)
			(xy 363.116016 -279.636243) (xy 363.1316 -279.682924) (xy 363.139495 -279.731501) (xy 363.13999 -279.756108)
			(xy 363.468932 -279.756108) (xy 363.472892 -279.707054) (xy 363.484669 -279.65927) (xy 363.50396 -279.613994)
			(xy 363.530263 -279.572398) (xy 363.562898 -279.535561) (xy 363.601019 -279.504436) (xy 363.64364 -279.479829)
			(xy 363.689656 -279.462377) (xy 363.737875 -279.452533) (xy 363.78705 -279.450552) (xy 363.835905 -279.456484)
			(xy 363.883176 -279.470176) (xy 363.927638 -279.491274) (xy 363.968141 -279.51923) (xy 364.003634 -279.553322)
			(xy 364.033199 -279.592666) (xy 364.05607 -279.636243) (xy 364.071654 -279.682924) (xy 364.079549 -279.731501)
			(xy 364.080044 -279.756108) (xy 364.408986 -279.756108) (xy 364.412946 -279.707054) (xy 364.424723 -279.65927)
			(xy 364.444014 -279.613994) (xy 364.470317 -279.572398) (xy 364.502952 -279.535561) (xy 364.541073 -279.504436)
			(xy 364.583694 -279.479829) (xy 364.62971 -279.462377) (xy 364.677929 -279.452533) (xy 364.727104 -279.450552)
			(xy 364.775959 -279.456484) (xy 364.82323 -279.470176) (xy 364.867692 -279.491274) (xy 364.908195 -279.51923)
			(xy 364.943688 -279.553322) (xy 364.973253 -279.592666) (xy 364.996124 -279.636243) (xy 365.011708 -279.682924)
			(xy 365.019603 -279.731501) (xy 365.020098 -279.756108) (xy 365.34904 -279.756108) (xy 365.353 -279.707054)
			(xy 365.364777 -279.65927) (xy 365.384068 -279.613994) (xy 365.410371 -279.572398) (xy 365.443006 -279.535561)
			(xy 365.481127 -279.504436) (xy 365.523748 -279.479829) (xy 365.569764 -279.462377) (xy 365.617983 -279.452533)
			(xy 365.667158 -279.450552) (xy 365.716013 -279.456484) (xy 365.763284 -279.470176) (xy 365.807746 -279.491274)
			(xy 365.848249 -279.51923) (xy 365.883742 -279.553322) (xy 365.913307 -279.592666) (xy 365.936178 -279.636243)
			(xy 365.951762 -279.682924) (xy 365.959657 -279.731501) (xy 365.960152 -279.756108) (xy 366.289094 -279.756108)
			(xy 366.293054 -279.707054) (xy 366.304831 -279.65927) (xy 366.324122 -279.613994) (xy 366.350425 -279.572398)
			(xy 366.38306 -279.535561) (xy 366.421181 -279.504436) (xy 366.463802 -279.479829) (xy 366.509818 -279.462377)
			(xy 366.558037 -279.452533) (xy 366.607212 -279.450552) (xy 366.656067 -279.456484) (xy 366.703338 -279.470176)
			(xy 366.7478 -279.491274) (xy 366.788303 -279.51923) (xy 366.823796 -279.553322) (xy 366.853361 -279.592666)
			(xy 366.876232 -279.636243) (xy 366.891816 -279.682924) (xy 366.899711 -279.731501) (xy 366.900206 -279.756108)
			(xy 367.228894 -279.756108) (xy 367.232854 -279.707054) (xy 367.244631 -279.65927) (xy 367.263922 -279.613994)
			(xy 367.290225 -279.572398) (xy 367.32286 -279.535561) (xy 367.360981 -279.504436) (xy 367.403602 -279.479829)
			(xy 367.449618 -279.462377) (xy 367.497837 -279.452533) (xy 367.547012 -279.450552) (xy 367.595867 -279.456484)
			(xy 367.643138 -279.470176) (xy 367.6876 -279.491274) (xy 367.728103 -279.51923) (xy 367.763596 -279.553322)
			(xy 367.793161 -279.592666) (xy 367.816032 -279.636243) (xy 367.831616 -279.682924) (xy 367.839511 -279.731501)
			(xy 367.840006 -279.756108) (xy 368.168948 -279.756108) (xy 368.172908 -279.707054) (xy 368.184685 -279.65927)
			(xy 368.203976 -279.613994) (xy 368.230279 -279.572398) (xy 368.262914 -279.535561) (xy 368.301035 -279.504436)
			(xy 368.343656 -279.479829) (xy 368.389672 -279.462377) (xy 368.437891 -279.452533) (xy 368.487066 -279.450552)
			(xy 368.535921 -279.456484) (xy 368.583192 -279.470176) (xy 368.627654 -279.491274) (xy 368.668157 -279.51923)
			(xy 368.70365 -279.553322) (xy 368.733215 -279.592666) (xy 368.756086 -279.636243) (xy 368.77167 -279.682924)
			(xy 368.779565 -279.731501) (xy 368.78006 -279.756108) (xy 369.109002 -279.756108) (xy 369.112962 -279.707054)
			(xy 369.124739 -279.65927) (xy 369.14403 -279.613994) (xy 369.170333 -279.572398) (xy 369.202968 -279.535561)
			(xy 369.241089 -279.504436) (xy 369.28371 -279.479829) (xy 369.329726 -279.462377) (xy 369.377945 -279.452533)
			(xy 369.42712 -279.450552) (xy 369.475975 -279.456484) (xy 369.523246 -279.470176) (xy 369.567708 -279.491274)
			(xy 369.608211 -279.51923) (xy 369.643704 -279.553322) (xy 369.673269 -279.592666) (xy 369.69614 -279.636243)
			(xy 369.711724 -279.682924) (xy 369.719619 -279.731501) (xy 369.720114 -279.756108) (xy 370.049056 -279.756108)
			(xy 370.053016 -279.707054) (xy 370.064793 -279.65927) (xy 370.084084 -279.613994) (xy 370.110387 -279.572398)
			(xy 370.143022 -279.535561) (xy 370.181143 -279.504436) (xy 370.223764 -279.479829) (xy 370.26978 -279.462377)
			(xy 370.317999 -279.452533) (xy 370.367174 -279.450552) (xy 370.416029 -279.456484) (xy 370.4633 -279.470176)
			(xy 370.507762 -279.491274) (xy 370.548265 -279.51923) (xy 370.583758 -279.553322) (xy 370.613323 -279.592666)
			(xy 370.636194 -279.636243) (xy 370.651778 -279.682924) (xy 370.659673 -279.731501) (xy 370.660168 -279.756108)
			(xy 370.98911 -279.756108) (xy 370.99307 -279.707054) (xy 371.004847 -279.65927) (xy 371.024138 -279.613994)
			(xy 371.050441 -279.572398) (xy 371.083076 -279.535561) (xy 371.121197 -279.504436) (xy 371.163818 -279.479829)
			(xy 371.209834 -279.462377) (xy 371.258053 -279.452533) (xy 371.307228 -279.450552) (xy 371.356083 -279.456484)
			(xy 371.403354 -279.470176) (xy 371.447816 -279.491274) (xy 371.488319 -279.51923) (xy 371.523812 -279.553322)
			(xy 371.553377 -279.592666) (xy 371.576248 -279.636243) (xy 371.591832 -279.682924) (xy 371.599727 -279.731501)
			(xy 371.600222 -279.756108) (xy 371.92891 -279.756108) (xy 371.93287 -279.707054) (xy 371.944647 -279.65927)
			(xy 371.963938 -279.613994) (xy 371.990241 -279.572398) (xy 372.022876 -279.535561) (xy 372.060997 -279.504436)
			(xy 372.103618 -279.479829) (xy 372.149634 -279.462377) (xy 372.197853 -279.452533) (xy 372.247028 -279.450552)
			(xy 372.295883 -279.456484) (xy 372.343154 -279.470176) (xy 372.387616 -279.491274) (xy 372.428119 -279.51923)
			(xy 372.463612 -279.553322) (xy 372.493177 -279.592666) (xy 372.516048 -279.636243) (xy 372.531632 -279.682924)
			(xy 372.539527 -279.731501) (xy 372.540022 -279.756108) (xy 372.868964 -279.756108) (xy 372.872924 -279.707054)
			(xy 372.884701 -279.65927) (xy 372.903992 -279.613994) (xy 372.930295 -279.572398) (xy 372.96293 -279.535561)
			(xy 373.001051 -279.504436) (xy 373.043672 -279.479829) (xy 373.089688 -279.462377) (xy 373.137907 -279.452533)
			(xy 373.187082 -279.450552) (xy 373.235937 -279.456484) (xy 373.283208 -279.470176) (xy 373.32767 -279.491274)
			(xy 373.368173 -279.51923) (xy 373.403666 -279.553322) (xy 373.433231 -279.592666) (xy 373.456102 -279.636243)
			(xy 373.471686 -279.682924) (xy 373.479581 -279.731501) (xy 373.480076 -279.756108) (xy 373.479581 -279.780715)
			(xy 373.471686 -279.829292) (xy 373.456102 -279.875973) (xy 373.433231 -279.91955) (xy 373.403666 -279.958894)
			(xy 373.368173 -279.992986) (xy 373.32767 -280.020942) (xy 373.283208 -280.04204) (xy 373.235937 -280.055732)
			(xy 373.187082 -280.061664) (xy 373.137907 -280.059683) (xy 373.089688 -280.049839) (xy 373.043672 -280.032387)
			(xy 373.001051 -280.00778) (xy 372.96293 -279.976655) (xy 372.930295 -279.939818) (xy 372.903992 -279.898222)
			(xy 372.884701 -279.852946) (xy 372.872924 -279.805162) (xy 372.868964 -279.756108) (xy 372.540022 -279.756108)
			(xy 372.539527 -279.780715) (xy 372.531632 -279.829292) (xy 372.516048 -279.875973) (xy 372.493177 -279.91955)
			(xy 372.463612 -279.958894) (xy 372.428119 -279.992986) (xy 372.387616 -280.020942) (xy 372.343154 -280.04204)
			(xy 372.295883 -280.055732) (xy 372.247028 -280.061664) (xy 372.197853 -280.059683) (xy 372.149634 -280.049839)
			(xy 372.103618 -280.032387) (xy 372.060997 -280.00778) (xy 372.022876 -279.976655) (xy 371.990241 -279.939818)
			(xy 371.963938 -279.898222) (xy 371.944647 -279.852946) (xy 371.93287 -279.805162) (xy 371.92891 -279.756108)
			(xy 371.600222 -279.756108) (xy 371.599727 -279.780715) (xy 371.591832 -279.829292) (xy 371.576248 -279.875973)
			(xy 371.553377 -279.91955) (xy 371.523812 -279.958894) (xy 371.488319 -279.992986) (xy 371.447816 -280.020942)
			(xy 371.403354 -280.04204) (xy 371.356083 -280.055732) (xy 371.307228 -280.061664) (xy 371.258053 -280.059683)
			(xy 371.209834 -280.049839) (xy 371.163818 -280.032387) (xy 371.121197 -280.00778) (xy 371.083076 -279.976655)
			(xy 371.050441 -279.939818) (xy 371.024138 -279.898222) (xy 371.004847 -279.852946) (xy 370.99307 -279.805162)
			(xy 370.98911 -279.756108) (xy 370.660168 -279.756108) (xy 370.659673 -279.780715) (xy 370.651778 -279.829292)
			(xy 370.636194 -279.875973) (xy 370.613323 -279.91955) (xy 370.583758 -279.958894) (xy 370.548265 -279.992986)
			(xy 370.507762 -280.020942) (xy 370.4633 -280.04204) (xy 370.416029 -280.055732) (xy 370.367174 -280.061664)
			(xy 370.317999 -280.059683) (xy 370.26978 -280.049839) (xy 370.223764 -280.032387) (xy 370.181143 -280.00778)
			(xy 370.143022 -279.976655) (xy 370.110387 -279.939818) (xy 370.084084 -279.898222) (xy 370.064793 -279.852946)
			(xy 370.053016 -279.805162) (xy 370.049056 -279.756108) (xy 369.720114 -279.756108) (xy 369.719619 -279.780715)
			(xy 369.711724 -279.829292) (xy 369.69614 -279.875973) (xy 369.673269 -279.91955) (xy 369.643704 -279.958894)
			(xy 369.608211 -279.992986) (xy 369.567708 -280.020942) (xy 369.523246 -280.04204) (xy 369.475975 -280.055732)
			(xy 369.42712 -280.061664) (xy 369.377945 -280.059683) (xy 369.329726 -280.049839) (xy 369.28371 -280.032387)
			(xy 369.241089 -280.00778) (xy 369.202968 -279.976655) (xy 369.170333 -279.939818) (xy 369.14403 -279.898222)
			(xy 369.124739 -279.852946) (xy 369.112962 -279.805162) (xy 369.109002 -279.756108) (xy 368.78006 -279.756108)
			(xy 368.779565 -279.780715) (xy 368.77167 -279.829292) (xy 368.756086 -279.875973) (xy 368.733215 -279.91955)
			(xy 368.70365 -279.958894) (xy 368.668157 -279.992986) (xy 368.627654 -280.020942) (xy 368.583192 -280.04204)
			(xy 368.535921 -280.055732) (xy 368.487066 -280.061664) (xy 368.437891 -280.059683) (xy 368.389672 -280.049839)
			(xy 368.343656 -280.032387) (xy 368.301035 -280.00778) (xy 368.262914 -279.976655) (xy 368.230279 -279.939818)
			(xy 368.203976 -279.898222) (xy 368.184685 -279.852946) (xy 368.172908 -279.805162) (xy 368.168948 -279.756108)
			(xy 367.840006 -279.756108) (xy 367.839511 -279.780715) (xy 367.831616 -279.829292) (xy 367.816032 -279.875973)
			(xy 367.793161 -279.91955) (xy 367.763596 -279.958894) (xy 367.728103 -279.992986) (xy 367.6876 -280.020942)
			(xy 367.643138 -280.04204) (xy 367.595867 -280.055732) (xy 367.547012 -280.061664) (xy 367.497837 -280.059683)
			(xy 367.449618 -280.049839) (xy 367.403602 -280.032387) (xy 367.360981 -280.00778) (xy 367.32286 -279.976655)
			(xy 367.290225 -279.939818) (xy 367.263922 -279.898222) (xy 367.244631 -279.852946) (xy 367.232854 -279.805162)
			(xy 367.228894 -279.756108) (xy 366.900206 -279.756108) (xy 366.899711 -279.780715) (xy 366.891816 -279.829292)
			(xy 366.876232 -279.875973) (xy 366.853361 -279.91955) (xy 366.823796 -279.958894) (xy 366.788303 -279.992986)
			(xy 366.7478 -280.020942) (xy 366.703338 -280.04204) (xy 366.656067 -280.055732) (xy 366.607212 -280.061664)
			(xy 366.558037 -280.059683) (xy 366.509818 -280.049839) (xy 366.463802 -280.032387) (xy 366.421181 -280.00778)
			(xy 366.38306 -279.976655) (xy 366.350425 -279.939818) (xy 366.324122 -279.898222) (xy 366.304831 -279.852946)
			(xy 366.293054 -279.805162) (xy 366.289094 -279.756108) (xy 365.960152 -279.756108) (xy 365.959657 -279.780715)
			(xy 365.951762 -279.829292) (xy 365.936178 -279.875973) (xy 365.913307 -279.91955) (xy 365.883742 -279.958894)
			(xy 365.848249 -279.992986) (xy 365.807746 -280.020942) (xy 365.763284 -280.04204) (xy 365.716013 -280.055732)
			(xy 365.667158 -280.061664) (xy 365.617983 -280.059683) (xy 365.569764 -280.049839) (xy 365.523748 -280.032387)
			(xy 365.481127 -280.00778) (xy 365.443006 -279.976655) (xy 365.410371 -279.939818) (xy 365.384068 -279.898222)
			(xy 365.364777 -279.852946) (xy 365.353 -279.805162) (xy 365.34904 -279.756108) (xy 365.020098 -279.756108)
			(xy 365.019603 -279.780715) (xy 365.011708 -279.829292) (xy 364.996124 -279.875973) (xy 364.973253 -279.91955)
			(xy 364.943688 -279.958894) (xy 364.908195 -279.992986) (xy 364.867692 -280.020942) (xy 364.82323 -280.04204)
			(xy 364.775959 -280.055732) (xy 364.727104 -280.061664) (xy 364.677929 -280.059683) (xy 364.62971 -280.049839)
			(xy 364.583694 -280.032387) (xy 364.541073 -280.00778) (xy 364.502952 -279.976655) (xy 364.470317 -279.939818)
			(xy 364.444014 -279.898222) (xy 364.424723 -279.852946) (xy 364.412946 -279.805162) (xy 364.408986 -279.756108)
			(xy 364.080044 -279.756108) (xy 364.079549 -279.780715) (xy 364.071654 -279.829292) (xy 364.05607 -279.875973)
			(xy 364.033199 -279.91955) (xy 364.003634 -279.958894) (xy 363.968141 -279.992986) (xy 363.927638 -280.020942)
			(xy 363.883176 -280.04204) (xy 363.835905 -280.055732) (xy 363.78705 -280.061664) (xy 363.737875 -280.059683)
			(xy 363.689656 -280.049839) (xy 363.64364 -280.032387) (xy 363.601019 -280.00778) (xy 363.562898 -279.976655)
			(xy 363.530263 -279.939818) (xy 363.50396 -279.898222) (xy 363.484669 -279.852946) (xy 363.472892 -279.805162)
			(xy 363.468932 -279.756108) (xy 363.13999 -279.756108) (xy 363.139495 -279.780715) (xy 363.1316 -279.829292)
			(xy 363.116016 -279.875973) (xy 363.093145 -279.91955) (xy 363.06358 -279.958894) (xy 363.028087 -279.992986)
			(xy 362.987584 -280.020942) (xy 362.943122 -280.04204) (xy 362.895851 -280.055732) (xy 362.846996 -280.061664)
			(xy 362.797821 -280.059683) (xy 362.749602 -280.049839) (xy 362.703586 -280.032387) (xy 362.660965 -280.00778)
			(xy 362.622844 -279.976655) (xy 362.590209 -279.939818) (xy 362.563906 -279.898222) (xy 362.544615 -279.852946)
			(xy 362.532838 -279.805162) (xy 362.528878 -279.756108) (xy 362.20019 -279.756108) (xy 362.199695 -279.780715)
			(xy 362.1918 -279.829292) (xy 362.176216 -279.875973) (xy 362.153345 -279.91955) (xy 362.12378 -279.958894)
			(xy 362.088287 -279.992986) (xy 362.047784 -280.020942) (xy 362.003322 -280.04204) (xy 361.956051 -280.055732)
			(xy 361.907196 -280.061664) (xy 361.858021 -280.059683) (xy 361.809802 -280.049839) (xy 361.763786 -280.032387)
			(xy 361.721165 -280.00778) (xy 361.683044 -279.976655) (xy 361.650409 -279.939818) (xy 361.624106 -279.898222)
			(xy 361.604815 -279.852946) (xy 361.593038 -279.805162) (xy 361.589078 -279.756108) (xy 358.446324 -279.756108)
			(xy 358.445829 -279.780715) (xy 358.437934 -279.829292) (xy 358.42235 -279.875973) (xy 358.399479 -279.91955)
			(xy 358.369914 -279.958894) (xy 358.334421 -279.992986) (xy 358.293918 -280.020942) (xy 358.249456 -280.04204)
			(xy 358.202185 -280.055732) (xy 358.15333 -280.061664) (xy 358.104155 -280.059683) (xy 358.055936 -280.049839)
			(xy 358.00992 -280.032387) (xy 357.967299 -280.00778) (xy 357.929178 -279.976655) (xy 357.896543 -279.939818)
			(xy 357.87024 -279.898222) (xy 357.850949 -279.852946) (xy 357.839172 -279.805162) (xy 357.835212 -279.756108)
			(xy 357.506524 -279.756108) (xy 357.506029 -279.780715) (xy 357.498134 -279.829292) (xy 357.48255 -279.875973)
			(xy 357.459679 -279.91955) (xy 357.430114 -279.958894) (xy 357.394621 -279.992986) (xy 357.354118 -280.020942)
			(xy 357.309656 -280.04204) (xy 357.262385 -280.055732) (xy 357.21353 -280.061664) (xy 357.164355 -280.059683)
			(xy 357.116136 -280.049839) (xy 357.07012 -280.032387) (xy 357.027499 -280.00778) (xy 356.989378 -279.976655)
			(xy 356.956743 -279.939818) (xy 356.93044 -279.898222) (xy 356.911149 -279.852946) (xy 356.899372 -279.805162)
			(xy 356.895412 -279.756108) (xy 356.56647 -279.756108) (xy 356.565975 -279.780715) (xy 356.55808 -279.829292)
			(xy 356.542496 -279.875973) (xy 356.519625 -279.91955) (xy 356.49006 -279.958894) (xy 356.454567 -279.992986)
			(xy 356.414064 -280.020942) (xy 356.369602 -280.04204) (xy 356.322331 -280.055732) (xy 356.273476 -280.061664)
			(xy 356.224301 -280.059683) (xy 356.176082 -280.049839) (xy 356.130066 -280.032387) (xy 356.087445 -280.00778)
			(xy 356.049324 -279.976655) (xy 356.016689 -279.939818) (xy 355.990386 -279.898222) (xy 355.971095 -279.852946)
			(xy 355.959318 -279.805162) (xy 355.955358 -279.756108) (xy 355.626416 -279.756108) (xy 355.625921 -279.780715)
			(xy 355.618026 -279.829292) (xy 355.602442 -279.875973) (xy 355.579571 -279.91955) (xy 355.550006 -279.958894)
			(xy 355.514513 -279.992986) (xy 355.47401 -280.020942) (xy 355.429548 -280.04204) (xy 355.382277 -280.055732)
			(xy 355.333422 -280.061664) (xy 355.284247 -280.059683) (xy 355.236028 -280.049839) (xy 355.190012 -280.032387)
			(xy 355.147391 -280.00778) (xy 355.10927 -279.976655) (xy 355.076635 -279.939818) (xy 355.050332 -279.898222)
			(xy 355.031041 -279.852946) (xy 355.019264 -279.805162) (xy 355.015304 -279.756108) (xy 354.686362 -279.756108)
			(xy 354.685867 -279.780715) (xy 354.677972 -279.829292) (xy 354.662388 -279.875973) (xy 354.639517 -279.91955)
			(xy 354.609952 -279.958894) (xy 354.574459 -279.992986) (xy 354.533956 -280.020942) (xy 354.489494 -280.04204)
			(xy 354.442223 -280.055732) (xy 354.393368 -280.061664) (xy 354.344193 -280.059683) (xy 354.295974 -280.049839)
			(xy 354.249958 -280.032387) (xy 354.207337 -280.00778) (xy 354.169216 -279.976655) (xy 354.136581 -279.939818)
			(xy 354.110278 -279.898222) (xy 354.090987 -279.852946) (xy 354.07921 -279.805162) (xy 354.07525 -279.756108)
			(xy 353.746308 -279.756108) (xy 353.745813 -279.780715) (xy 353.737918 -279.829292) (xy 353.722334 -279.875973)
			(xy 353.699463 -279.91955) (xy 353.669898 -279.958894) (xy 353.634405 -279.992986) (xy 353.593902 -280.020942)
			(xy 353.54944 -280.04204) (xy 353.502169 -280.055732) (xy 353.453314 -280.061664) (xy 353.404139 -280.059683)
			(xy 353.35592 -280.049839) (xy 353.309904 -280.032387) (xy 353.267283 -280.00778) (xy 353.229162 -279.976655)
			(xy 353.196527 -279.939818) (xy 353.170224 -279.898222) (xy 353.150933 -279.852946) (xy 353.139156 -279.805162)
			(xy 353.135196 -279.756108) (xy 352.806508 -279.756108) (xy 352.806013 -279.780715) (xy 352.798118 -279.829292)
			(xy 352.782534 -279.875973) (xy 352.759663 -279.91955) (xy 352.730098 -279.958894) (xy 352.694605 -279.992986)
			(xy 352.654102 -280.020942) (xy 352.60964 -280.04204) (xy 352.562369 -280.055732) (xy 352.513514 -280.061664)
			(xy 352.464339 -280.059683) (xy 352.41612 -280.049839) (xy 352.370104 -280.032387) (xy 352.327483 -280.00778)
			(xy 352.289362 -279.976655) (xy 352.256727 -279.939818) (xy 352.230424 -279.898222) (xy 352.211133 -279.852946)
			(xy 352.199356 -279.805162) (xy 352.195396 -279.756108) (xy 351.866454 -279.756108) (xy 351.865959 -279.780715)
			(xy 351.858064 -279.829292) (xy 351.84248 -279.875973) (xy 351.819609 -279.91955) (xy 351.790044 -279.958894)
			(xy 351.754551 -279.992986) (xy 351.714048 -280.020942) (xy 351.669586 -280.04204) (xy 351.622315 -280.055732)
			(xy 351.57346 -280.061664) (xy 351.524285 -280.059683) (xy 351.476066 -280.049839) (xy 351.43005 -280.032387)
			(xy 351.387429 -280.00778) (xy 351.349308 -279.976655) (xy 351.316673 -279.939818) (xy 351.29037 -279.898222)
			(xy 351.271079 -279.852946) (xy 351.259302 -279.805162) (xy 351.255342 -279.756108) (xy 350.9264 -279.756108)
			(xy 350.925905 -279.780715) (xy 350.91801 -279.829292) (xy 350.902426 -279.875973) (xy 350.879555 -279.91955)
			(xy 350.84999 -279.958894) (xy 350.814497 -279.992986) (xy 350.773994 -280.020942) (xy 350.729532 -280.04204)
			(xy 350.682261 -280.055732) (xy 350.633406 -280.061664) (xy 350.584231 -280.059683) (xy 350.536012 -280.049839)
			(xy 350.489996 -280.032387) (xy 350.447375 -280.00778) (xy 350.409254 -279.976655) (xy 350.376619 -279.939818)
			(xy 350.350316 -279.898222) (xy 350.331025 -279.852946) (xy 350.319248 -279.805162) (xy 350.315288 -279.756108)
			(xy 349.986346 -279.756108) (xy 349.985851 -279.780715) (xy 349.977956 -279.829292) (xy 349.962372 -279.875973)
			(xy 349.939501 -279.91955) (xy 349.909936 -279.958894) (xy 349.874443 -279.992986) (xy 349.83394 -280.020942)
			(xy 349.789478 -280.04204) (xy 349.742207 -280.055732) (xy 349.693352 -280.061664) (xy 349.644177 -280.059683)
			(xy 349.595958 -280.049839) (xy 349.549942 -280.032387) (xy 349.507321 -280.00778) (xy 349.4692 -279.976655)
			(xy 349.436565 -279.939818) (xy 349.410262 -279.898222) (xy 349.390971 -279.852946) (xy 349.379194 -279.805162)
			(xy 349.375234 -279.756108) (xy 349.046546 -279.756108) (xy 349.046051 -279.780715) (xy 349.038156 -279.829292)
			(xy 349.022572 -279.875973) (xy 348.999701 -279.91955) (xy 348.970136 -279.958894) (xy 348.934643 -279.992986)
			(xy 348.89414 -280.020942) (xy 348.849678 -280.04204) (xy 348.802407 -280.055732) (xy 348.753552 -280.061664)
			(xy 348.704377 -280.059683) (xy 348.656158 -280.049839) (xy 348.610142 -280.032387) (xy 348.567521 -280.00778)
			(xy 348.5294 -279.976655) (xy 348.496765 -279.939818) (xy 348.470462 -279.898222) (xy 348.451171 -279.852946)
			(xy 348.439394 -279.805162) (xy 348.435434 -279.756108) (xy 348.106492 -279.756108) (xy 348.105997 -279.780715)
			(xy 348.098102 -279.829292) (xy 348.082518 -279.875973) (xy 348.059647 -279.91955) (xy 348.030082 -279.958894)
			(xy 347.994589 -279.992986) (xy 347.954086 -280.020942) (xy 347.909624 -280.04204) (xy 347.862353 -280.055732)
			(xy 347.813498 -280.061664) (xy 347.764323 -280.059683) (xy 347.716104 -280.049839) (xy 347.670088 -280.032387)
			(xy 347.627467 -280.00778) (xy 347.589346 -279.976655) (xy 347.556711 -279.939818) (xy 347.530408 -279.898222)
			(xy 347.511117 -279.852946) (xy 347.49934 -279.805162) (xy 347.49538 -279.756108) (xy 347.166438 -279.756108)
			(xy 347.165943 -279.780715) (xy 347.158048 -279.829292) (xy 347.142464 -279.875973) (xy 347.119593 -279.91955)
			(xy 347.090028 -279.958894) (xy 347.054535 -279.992986) (xy 347.014032 -280.020942) (xy 346.96957 -280.04204)
			(xy 346.922299 -280.055732) (xy 346.873444 -280.061664) (xy 346.824269 -280.059683) (xy 346.77605 -280.049839)
			(xy 346.730034 -280.032387) (xy 346.687413 -280.00778) (xy 346.649292 -279.976655) (xy 346.616657 -279.939818)
			(xy 346.590354 -279.898222) (xy 346.571063 -279.852946) (xy 346.559286 -279.805162) (xy 346.555326 -279.756108)
			(xy 346.226384 -279.756108) (xy 346.225889 -279.780715) (xy 346.217994 -279.829292) (xy 346.20241 -279.875973)
			(xy 346.179539 -279.91955) (xy 346.149974 -279.958894) (xy 346.114481 -279.992986) (xy 346.073978 -280.020942)
			(xy 346.029516 -280.04204) (xy 345.982245 -280.055732) (xy 345.93339 -280.061664) (xy 345.884215 -280.059683)
			(xy 345.835996 -280.049839) (xy 345.78998 -280.032387) (xy 345.747359 -280.00778) (xy 345.709238 -279.976655)
			(xy 345.676603 -279.939818) (xy 345.6503 -279.898222) (xy 345.631009 -279.852946) (xy 345.619232 -279.805162)
			(xy 345.615272 -279.756108) (xy 345.286822 -279.756108) (xy 345.282657 -279.806408) (xy 345.270272 -279.855346)
			(xy 345.250005 -279.901579) (xy 345.222409 -279.943849) (xy 345.188235 -279.981003) (xy 345.148416 -280.012029)
			(xy 345.104034 -280.036083) (xy 345.056301 -280.052508) (xy 345.006516 -280.060857) (xy 344.981276 -280.061416)
			(xy 344.971208 -280.061844) (xy 344.952611 -280.069566) (xy 344.945208 -280.076402) (xy 344.895424 -280.126186)
			(xy 344.888703 -280.133421) (xy 344.881094 -280.151626) (xy 344.880692 -280.161492) (xy 344.880692 -280.566114)
			(xy 345.145372 -280.566114) (xy 345.149332 -280.51706) (xy 345.161109 -280.469276) (xy 345.1804 -280.424)
			(xy 345.206703 -280.382404) (xy 345.239338 -280.345567) (xy 345.277459 -280.314442) (xy 345.32008 -280.289835)
			(xy 345.366096 -280.272383) (xy 345.414315 -280.262539) (xy 345.46349 -280.260558) (xy 345.512345 -280.26649)
			(xy 345.559616 -280.280182) (xy 345.604078 -280.30128) (xy 345.644581 -280.329236) (xy 345.680074 -280.363328)
			(xy 345.709639 -280.402672) (xy 345.73251 -280.446249) (xy 345.748094 -280.49293) (xy 345.755989 -280.541507)
			(xy 345.756484 -280.566114) (xy 346.085426 -280.566114) (xy 346.089386 -280.51706) (xy 346.101163 -280.469276)
			(xy 346.120454 -280.424) (xy 346.146757 -280.382404) (xy 346.179392 -280.345567) (xy 346.217513 -280.314442)
			(xy 346.260134 -280.289835) (xy 346.30615 -280.272383) (xy 346.354369 -280.262539) (xy 346.403544 -280.260558)
			(xy 346.452399 -280.26649) (xy 346.49967 -280.280182) (xy 346.544132 -280.30128) (xy 346.584635 -280.329236)
			(xy 346.620128 -280.363328) (xy 346.649693 -280.402672) (xy 346.672564 -280.446249) (xy 346.688148 -280.49293)
			(xy 346.696043 -280.541507) (xy 346.696538 -280.566114) (xy 347.025226 -280.566114) (xy 347.029186 -280.51706)
			(xy 347.040963 -280.469276) (xy 347.060254 -280.424) (xy 347.086557 -280.382404) (xy 347.119192 -280.345567)
			(xy 347.157313 -280.314442) (xy 347.199934 -280.289835) (xy 347.24595 -280.272383) (xy 347.294169 -280.262539)
			(xy 347.343344 -280.260558) (xy 347.392199 -280.26649) (xy 347.43947 -280.280182) (xy 347.483932 -280.30128)
			(xy 347.524435 -280.329236) (xy 347.559928 -280.363328) (xy 347.589493 -280.402672) (xy 347.612364 -280.446249)
			(xy 347.627948 -280.49293) (xy 347.635843 -280.541507) (xy 347.636338 -280.566114) (xy 347.96528 -280.566114)
			(xy 347.96924 -280.51706) (xy 347.981017 -280.469276) (xy 348.000308 -280.424) (xy 348.026611 -280.382404)
			(xy 348.059246 -280.345567) (xy 348.097367 -280.314442) (xy 348.139988 -280.289835) (xy 348.186004 -280.272383)
			(xy 348.234223 -280.262539) (xy 348.283398 -280.260558) (xy 348.332253 -280.26649) (xy 348.379524 -280.280182)
			(xy 348.423986 -280.30128) (xy 348.464489 -280.329236) (xy 348.499982 -280.363328) (xy 348.529547 -280.402672)
			(xy 348.552418 -280.446249) (xy 348.568002 -280.49293) (xy 348.575897 -280.541507) (xy 348.576392 -280.566114)
			(xy 348.905334 -280.566114) (xy 348.909294 -280.51706) (xy 348.921071 -280.469276) (xy 348.940362 -280.424)
			(xy 348.966665 -280.382404) (xy 348.9993 -280.345567) (xy 349.037421 -280.314442) (xy 349.080042 -280.289835)
			(xy 349.126058 -280.272383) (xy 349.174277 -280.262539) (xy 349.223452 -280.260558) (xy 349.272307 -280.26649)
			(xy 349.319578 -280.280182) (xy 349.36404 -280.30128) (xy 349.404543 -280.329236) (xy 349.440036 -280.363328)
			(xy 349.469601 -280.402672) (xy 349.492472 -280.446249) (xy 349.508056 -280.49293) (xy 349.515951 -280.541507)
			(xy 349.516446 -280.566114) (xy 349.845388 -280.566114) (xy 349.849348 -280.51706) (xy 349.861125 -280.469276)
			(xy 349.880416 -280.424) (xy 349.906719 -280.382404) (xy 349.939354 -280.345567) (xy 349.977475 -280.314442)
			(xy 350.020096 -280.289835) (xy 350.066112 -280.272383) (xy 350.114331 -280.262539) (xy 350.163506 -280.260558)
			(xy 350.212361 -280.26649) (xy 350.259632 -280.280182) (xy 350.304094 -280.30128) (xy 350.344597 -280.329236)
			(xy 350.38009 -280.363328) (xy 350.409655 -280.402672) (xy 350.432526 -280.446249) (xy 350.44811 -280.49293)
			(xy 350.456005 -280.541507) (xy 350.4565 -280.566114) (xy 350.785442 -280.566114) (xy 350.789402 -280.51706)
			(xy 350.801179 -280.469276) (xy 350.82047 -280.424) (xy 350.846773 -280.382404) (xy 350.879408 -280.345567)
			(xy 350.917529 -280.314442) (xy 350.96015 -280.289835) (xy 351.006166 -280.272383) (xy 351.054385 -280.262539)
			(xy 351.10356 -280.260558) (xy 351.152415 -280.26649) (xy 351.199686 -280.280182) (xy 351.244148 -280.30128)
			(xy 351.284651 -280.329236) (xy 351.320144 -280.363328) (xy 351.349709 -280.402672) (xy 351.37258 -280.446249)
			(xy 351.388164 -280.49293) (xy 351.396059 -280.541507) (xy 351.396554 -280.566114) (xy 351.725242 -280.566114)
			(xy 351.729202 -280.51706) (xy 351.740979 -280.469276) (xy 351.76027 -280.424) (xy 351.786573 -280.382404)
			(xy 351.819208 -280.345567) (xy 351.857329 -280.314442) (xy 351.89995 -280.289835) (xy 351.945966 -280.272383)
			(xy 351.994185 -280.262539) (xy 352.04336 -280.260558) (xy 352.092215 -280.26649) (xy 352.139486 -280.280182)
			(xy 352.183948 -280.30128) (xy 352.224451 -280.329236) (xy 352.259944 -280.363328) (xy 352.289509 -280.402672)
			(xy 352.31238 -280.446249) (xy 352.327964 -280.49293) (xy 352.335859 -280.541507) (xy 352.336354 -280.566114)
			(xy 352.665296 -280.566114) (xy 352.669256 -280.51706) (xy 352.681033 -280.469276) (xy 352.700324 -280.424)
			(xy 352.726627 -280.382404) (xy 352.759262 -280.345567) (xy 352.797383 -280.314442) (xy 352.840004 -280.289835)
			(xy 352.88602 -280.272383) (xy 352.934239 -280.262539) (xy 352.983414 -280.260558) (xy 353.032269 -280.26649)
			(xy 353.07954 -280.280182) (xy 353.124002 -280.30128) (xy 353.164505 -280.329236) (xy 353.199998 -280.363328)
			(xy 353.229563 -280.402672) (xy 353.252434 -280.446249) (xy 353.268018 -280.49293) (xy 353.275913 -280.541507)
			(xy 353.276408 -280.566114) (xy 353.60535 -280.566114) (xy 353.60931 -280.51706) (xy 353.621087 -280.469276)
			(xy 353.640378 -280.424) (xy 353.666681 -280.382404) (xy 353.699316 -280.345567) (xy 353.737437 -280.314442)
			(xy 353.780058 -280.289835) (xy 353.826074 -280.272383) (xy 353.874293 -280.262539) (xy 353.923468 -280.260558)
			(xy 353.972323 -280.26649) (xy 354.019594 -280.280182) (xy 354.064056 -280.30128) (xy 354.104559 -280.329236)
			(xy 354.140052 -280.363328) (xy 354.169617 -280.402672) (xy 354.192488 -280.446249) (xy 354.208072 -280.49293)
			(xy 354.215967 -280.541507) (xy 354.216462 -280.566114) (xy 354.545404 -280.566114) (xy 354.549364 -280.51706)
			(xy 354.561141 -280.469276) (xy 354.580432 -280.424) (xy 354.606735 -280.382404) (xy 354.63937 -280.345567)
			(xy 354.677491 -280.314442) (xy 354.720112 -280.289835) (xy 354.766128 -280.272383) (xy 354.814347 -280.262539)
			(xy 354.863522 -280.260558) (xy 354.912377 -280.26649) (xy 354.959648 -280.280182) (xy 355.00411 -280.30128)
			(xy 355.044613 -280.329236) (xy 355.080106 -280.363328) (xy 355.109671 -280.402672) (xy 355.132542 -280.446249)
			(xy 355.148126 -280.49293) (xy 355.156021 -280.541507) (xy 355.156516 -280.566114) (xy 355.485204 -280.566114)
			(xy 355.489164 -280.51706) (xy 355.500941 -280.469276) (xy 355.520232 -280.424) (xy 355.546535 -280.382404)
			(xy 355.57917 -280.345567) (xy 355.617291 -280.314442) (xy 355.659912 -280.289835) (xy 355.705928 -280.272383)
			(xy 355.754147 -280.262539) (xy 355.803322 -280.260558) (xy 355.852177 -280.26649) (xy 355.899448 -280.280182)
			(xy 355.94391 -280.30128) (xy 355.984413 -280.329236) (xy 356.019906 -280.363328) (xy 356.049471 -280.402672)
			(xy 356.072342 -280.446249) (xy 356.087926 -280.49293) (xy 356.095821 -280.541507) (xy 356.096316 -280.566114)
			(xy 358.305366 -280.566114) (xy 358.309326 -280.51706) (xy 358.321103 -280.469276) (xy 358.340394 -280.424)
			(xy 358.366697 -280.382404) (xy 358.399332 -280.345567) (xy 358.437453 -280.314442) (xy 358.480074 -280.289835)
			(xy 358.52609 -280.272383) (xy 358.574309 -280.262539) (xy 358.623484 -280.260558) (xy 358.672339 -280.26649)
			(xy 358.71961 -280.280182) (xy 358.764072 -280.30128) (xy 358.804575 -280.329236) (xy 358.840068 -280.363328)
			(xy 358.869633 -280.402672) (xy 358.892504 -280.446249) (xy 358.908088 -280.49293) (xy 358.915983 -280.541507)
			(xy 358.916478 -280.566114) (xy 361.118924 -280.566114) (xy 361.122884 -280.51706) (xy 361.134661 -280.469276)
			(xy 361.153952 -280.424) (xy 361.180255 -280.382404) (xy 361.21289 -280.345567) (xy 361.251011 -280.314442)
			(xy 361.293632 -280.289835) (xy 361.339648 -280.272383) (xy 361.387867 -280.262539) (xy 361.437042 -280.260558)
			(xy 361.485897 -280.26649) (xy 361.533168 -280.280182) (xy 361.57763 -280.30128) (xy 361.618133 -280.329236)
			(xy 361.653626 -280.363328) (xy 361.683191 -280.402672) (xy 361.706062 -280.446249) (xy 361.721646 -280.49293)
			(xy 361.729541 -280.541507) (xy 361.730036 -280.566114) (xy 363.939086 -280.566114) (xy 363.943046 -280.51706)
			(xy 363.954823 -280.469276) (xy 363.974114 -280.424) (xy 364.000417 -280.382404) (xy 364.033052 -280.345567)
			(xy 364.071173 -280.314442) (xy 364.113794 -280.289835) (xy 364.15981 -280.272383) (xy 364.208029 -280.262539)
			(xy 364.257204 -280.260558) (xy 364.306059 -280.26649) (xy 364.35333 -280.280182) (xy 364.397792 -280.30128)
			(xy 364.438295 -280.329236) (xy 364.473788 -280.363328) (xy 364.503353 -280.402672) (xy 364.526224 -280.446249)
			(xy 364.541808 -280.49293) (xy 364.549703 -280.541507) (xy 364.550198 -280.566114) (xy 364.878886 -280.566114)
			(xy 364.882846 -280.51706) (xy 364.894623 -280.469276) (xy 364.913914 -280.424) (xy 364.940217 -280.382404)
			(xy 364.972852 -280.345567) (xy 365.010973 -280.314442) (xy 365.053594 -280.289835) (xy 365.09961 -280.272383)
			(xy 365.147829 -280.262539) (xy 365.197004 -280.260558) (xy 365.245859 -280.26649) (xy 365.29313 -280.280182)
			(xy 365.337592 -280.30128) (xy 365.378095 -280.329236) (xy 365.413588 -280.363328) (xy 365.443153 -280.402672)
			(xy 365.466024 -280.446249) (xy 365.481608 -280.49293) (xy 365.489503 -280.541507) (xy 365.489998 -280.566114)
			(xy 365.81894 -280.566114) (xy 365.8229 -280.51706) (xy 365.834677 -280.469276) (xy 365.853968 -280.424)
			(xy 365.880271 -280.382404) (xy 365.912906 -280.345567) (xy 365.951027 -280.314442) (xy 365.993648 -280.289835)
			(xy 366.039664 -280.272383) (xy 366.087883 -280.262539) (xy 366.137058 -280.260558) (xy 366.185913 -280.26649)
			(xy 366.233184 -280.280182) (xy 366.277646 -280.30128) (xy 366.318149 -280.329236) (xy 366.353642 -280.363328)
			(xy 366.383207 -280.402672) (xy 366.406078 -280.446249) (xy 366.421662 -280.49293) (xy 366.429557 -280.541507)
			(xy 366.430052 -280.566114) (xy 366.758994 -280.566114) (xy 366.762954 -280.51706) (xy 366.774731 -280.469276)
			(xy 366.794022 -280.424) (xy 366.820325 -280.382404) (xy 366.85296 -280.345567) (xy 366.891081 -280.314442)
			(xy 366.933702 -280.289835) (xy 366.979718 -280.272383) (xy 367.027937 -280.262539) (xy 367.077112 -280.260558)
			(xy 367.125967 -280.26649) (xy 367.173238 -280.280182) (xy 367.2177 -280.30128) (xy 367.258203 -280.329236)
			(xy 367.293696 -280.363328) (xy 367.323261 -280.402672) (xy 367.346132 -280.446249) (xy 367.361716 -280.49293)
			(xy 367.369611 -280.541507) (xy 367.370106 -280.566114) (xy 367.699048 -280.566114) (xy 367.703008 -280.51706)
			(xy 367.714785 -280.469276) (xy 367.734076 -280.424) (xy 367.760379 -280.382404) (xy 367.793014 -280.345567)
			(xy 367.831135 -280.314442) (xy 367.873756 -280.289835) (xy 367.919772 -280.272383) (xy 367.967991 -280.262539)
			(xy 368.017166 -280.260558) (xy 368.066021 -280.26649) (xy 368.113292 -280.280182) (xy 368.157754 -280.30128)
			(xy 368.198257 -280.329236) (xy 368.23375 -280.363328) (xy 368.263315 -280.402672) (xy 368.286186 -280.446249)
			(xy 368.30177 -280.49293) (xy 368.309665 -280.541507) (xy 368.31016 -280.566114) (xy 368.639102 -280.566114)
			(xy 368.643062 -280.51706) (xy 368.654839 -280.469276) (xy 368.67413 -280.424) (xy 368.700433 -280.382404)
			(xy 368.733068 -280.345567) (xy 368.771189 -280.314442) (xy 368.81381 -280.289835) (xy 368.859826 -280.272383)
			(xy 368.908045 -280.262539) (xy 368.95722 -280.260558) (xy 369.006075 -280.26649) (xy 369.053346 -280.280182)
			(xy 369.097808 -280.30128) (xy 369.138311 -280.329236) (xy 369.173804 -280.363328) (xy 369.203369 -280.402672)
			(xy 369.22624 -280.446249) (xy 369.241824 -280.49293) (xy 369.249719 -280.541507) (xy 369.250214 -280.566114)
			(xy 369.578902 -280.566114) (xy 369.582862 -280.51706) (xy 369.594639 -280.469276) (xy 369.61393 -280.424)
			(xy 369.640233 -280.382404) (xy 369.672868 -280.345567) (xy 369.710989 -280.314442) (xy 369.75361 -280.289835)
			(xy 369.799626 -280.272383) (xy 369.847845 -280.262539) (xy 369.89702 -280.260558) (xy 369.945875 -280.26649)
			(xy 369.993146 -280.280182) (xy 370.037608 -280.30128) (xy 370.078111 -280.329236) (xy 370.113604 -280.363328)
			(xy 370.143169 -280.402672) (xy 370.16604 -280.446249) (xy 370.181624 -280.49293) (xy 370.189519 -280.541507)
			(xy 370.190014 -280.566114) (xy 370.518956 -280.566114) (xy 370.522916 -280.51706) (xy 370.534693 -280.469276)
			(xy 370.553984 -280.424) (xy 370.580287 -280.382404) (xy 370.612922 -280.345567) (xy 370.651043 -280.314442)
			(xy 370.693664 -280.289835) (xy 370.73968 -280.272383) (xy 370.787899 -280.262539) (xy 370.837074 -280.260558)
			(xy 370.885929 -280.26649) (xy 370.9332 -280.280182) (xy 370.977662 -280.30128) (xy 371.018165 -280.329236)
			(xy 371.053658 -280.363328) (xy 371.083223 -280.402672) (xy 371.106094 -280.446249) (xy 371.121678 -280.49293)
			(xy 371.129573 -280.541507) (xy 371.130068 -280.566114) (xy 371.45901 -280.566114) (xy 371.46297 -280.51706)
			(xy 371.474747 -280.469276) (xy 371.494038 -280.424) (xy 371.520341 -280.382404) (xy 371.552976 -280.345567)
			(xy 371.591097 -280.314442) (xy 371.633718 -280.289835) (xy 371.679734 -280.272383) (xy 371.727953 -280.262539)
			(xy 371.777128 -280.260558) (xy 371.825983 -280.26649) (xy 371.873254 -280.280182) (xy 371.917716 -280.30128)
			(xy 371.958219 -280.329236) (xy 371.993712 -280.363328) (xy 372.023277 -280.402672) (xy 372.046148 -280.446249)
			(xy 372.061732 -280.49293) (xy 372.069627 -280.541507) (xy 372.070122 -280.566114) (xy 372.399064 -280.566114)
			(xy 372.403024 -280.51706) (xy 372.414801 -280.469276) (xy 372.434092 -280.424) (xy 372.460395 -280.382404)
			(xy 372.49303 -280.345567) (xy 372.531151 -280.314442) (xy 372.573772 -280.289835) (xy 372.619788 -280.272383)
			(xy 372.668007 -280.262539) (xy 372.717182 -280.260558) (xy 372.766037 -280.26649) (xy 372.813308 -280.280182)
			(xy 372.85777 -280.30128) (xy 372.898273 -280.329236) (xy 372.933766 -280.363328) (xy 372.963331 -280.402672)
			(xy 372.986202 -280.446249) (xy 373.001786 -280.49293) (xy 373.009681 -280.541507) (xy 373.010176 -280.566114)
			(xy 373.339118 -280.566114) (xy 373.343078 -280.51706) (xy 373.354855 -280.469276) (xy 373.374146 -280.424)
			(xy 373.400449 -280.382404) (xy 373.433084 -280.345567) (xy 373.471205 -280.314442) (xy 373.513826 -280.289835)
			(xy 373.559842 -280.272383) (xy 373.608061 -280.262539) (xy 373.657236 -280.260558) (xy 373.706091 -280.26649)
			(xy 373.753362 -280.280182) (xy 373.797824 -280.30128) (xy 373.838327 -280.329236) (xy 373.87382 -280.363328)
			(xy 373.903385 -280.402672) (xy 373.926256 -280.446249) (xy 373.94184 -280.49293) (xy 373.949735 -280.541507)
			(xy 373.95023 -280.566114) (xy 373.949735 -280.590721) (xy 373.94184 -280.639298) (xy 373.926256 -280.685979)
			(xy 373.903385 -280.729556) (xy 373.87382 -280.7689) (xy 373.838327 -280.802992) (xy 373.797824 -280.830948)
			(xy 373.753362 -280.852046) (xy 373.706091 -280.865738) (xy 373.657236 -280.87167) (xy 373.608061 -280.869689)
			(xy 373.559842 -280.859845) (xy 373.513826 -280.842393) (xy 373.471205 -280.817786) (xy 373.433084 -280.786661)
			(xy 373.400449 -280.749824) (xy 373.374146 -280.708228) (xy 373.354855 -280.662952) (xy 373.343078 -280.615168)
			(xy 373.339118 -280.566114) (xy 373.010176 -280.566114) (xy 373.009681 -280.590721) (xy 373.001786 -280.639298)
			(xy 372.986202 -280.685979) (xy 372.963331 -280.729556) (xy 372.933766 -280.7689) (xy 372.898273 -280.802992)
			(xy 372.85777 -280.830948) (xy 372.813308 -280.852046) (xy 372.766037 -280.865738) (xy 372.717182 -280.87167)
			(xy 372.668007 -280.869689) (xy 372.619788 -280.859845) (xy 372.573772 -280.842393) (xy 372.531151 -280.817786)
			(xy 372.49303 -280.786661) (xy 372.460395 -280.749824) (xy 372.434092 -280.708228) (xy 372.414801 -280.662952)
			(xy 372.403024 -280.615168) (xy 372.399064 -280.566114) (xy 372.070122 -280.566114) (xy 372.069627 -280.590721)
			(xy 372.061732 -280.639298) (xy 372.046148 -280.685979) (xy 372.023277 -280.729556) (xy 371.993712 -280.7689)
			(xy 371.958219 -280.802992) (xy 371.917716 -280.830948) (xy 371.873254 -280.852046) (xy 371.825983 -280.865738)
			(xy 371.777128 -280.87167) (xy 371.727953 -280.869689) (xy 371.679734 -280.859845) (xy 371.633718 -280.842393)
			(xy 371.591097 -280.817786) (xy 371.552976 -280.786661) (xy 371.520341 -280.749824) (xy 371.494038 -280.708228)
			(xy 371.474747 -280.662952) (xy 371.46297 -280.615168) (xy 371.45901 -280.566114) (xy 371.130068 -280.566114)
			(xy 371.129573 -280.590721) (xy 371.121678 -280.639298) (xy 371.106094 -280.685979) (xy 371.083223 -280.729556)
			(xy 371.053658 -280.7689) (xy 371.018165 -280.802992) (xy 370.977662 -280.830948) (xy 370.9332 -280.852046)
			(xy 370.885929 -280.865738) (xy 370.837074 -280.87167) (xy 370.787899 -280.869689) (xy 370.73968 -280.859845)
			(xy 370.693664 -280.842393) (xy 370.651043 -280.817786) (xy 370.612922 -280.786661) (xy 370.580287 -280.749824)
			(xy 370.553984 -280.708228) (xy 370.534693 -280.662952) (xy 370.522916 -280.615168) (xy 370.518956 -280.566114)
			(xy 370.190014 -280.566114) (xy 370.189519 -280.590721) (xy 370.181624 -280.639298) (xy 370.16604 -280.685979)
			(xy 370.143169 -280.729556) (xy 370.113604 -280.7689) (xy 370.078111 -280.802992) (xy 370.037608 -280.830948)
			(xy 369.993146 -280.852046) (xy 369.945875 -280.865738) (xy 369.89702 -280.87167) (xy 369.847845 -280.869689)
			(xy 369.799626 -280.859845) (xy 369.75361 -280.842393) (xy 369.710989 -280.817786) (xy 369.672868 -280.786661)
			(xy 369.640233 -280.749824) (xy 369.61393 -280.708228) (xy 369.594639 -280.662952) (xy 369.582862 -280.615168)
			(xy 369.578902 -280.566114) (xy 369.250214 -280.566114) (xy 369.249719 -280.590721) (xy 369.241824 -280.639298)
			(xy 369.22624 -280.685979) (xy 369.203369 -280.729556) (xy 369.173804 -280.7689) (xy 369.138311 -280.802992)
			(xy 369.097808 -280.830948) (xy 369.053346 -280.852046) (xy 369.006075 -280.865738) (xy 368.95722 -280.87167)
			(xy 368.908045 -280.869689) (xy 368.859826 -280.859845) (xy 368.81381 -280.842393) (xy 368.771189 -280.817786)
			(xy 368.733068 -280.786661) (xy 368.700433 -280.749824) (xy 368.67413 -280.708228) (xy 368.654839 -280.662952)
			(xy 368.643062 -280.615168) (xy 368.639102 -280.566114) (xy 368.31016 -280.566114) (xy 368.309665 -280.590721)
			(xy 368.30177 -280.639298) (xy 368.286186 -280.685979) (xy 368.263315 -280.729556) (xy 368.23375 -280.7689)
			(xy 368.198257 -280.802992) (xy 368.157754 -280.830948) (xy 368.113292 -280.852046) (xy 368.066021 -280.865738)
			(xy 368.017166 -280.87167) (xy 367.967991 -280.869689) (xy 367.919772 -280.859845) (xy 367.873756 -280.842393)
			(xy 367.831135 -280.817786) (xy 367.793014 -280.786661) (xy 367.760379 -280.749824) (xy 367.734076 -280.708228)
			(xy 367.714785 -280.662952) (xy 367.703008 -280.615168) (xy 367.699048 -280.566114) (xy 367.370106 -280.566114)
			(xy 367.369611 -280.590721) (xy 367.361716 -280.639298) (xy 367.346132 -280.685979) (xy 367.323261 -280.729556)
			(xy 367.293696 -280.7689) (xy 367.258203 -280.802992) (xy 367.2177 -280.830948) (xy 367.173238 -280.852046)
			(xy 367.125967 -280.865738) (xy 367.077112 -280.87167) (xy 367.027937 -280.869689) (xy 366.979718 -280.859845)
			(xy 366.933702 -280.842393) (xy 366.891081 -280.817786) (xy 366.85296 -280.786661) (xy 366.820325 -280.749824)
			(xy 366.794022 -280.708228) (xy 366.774731 -280.662952) (xy 366.762954 -280.615168) (xy 366.758994 -280.566114)
			(xy 366.430052 -280.566114) (xy 366.429557 -280.590721) (xy 366.421662 -280.639298) (xy 366.406078 -280.685979)
			(xy 366.383207 -280.729556) (xy 366.353642 -280.7689) (xy 366.318149 -280.802992) (xy 366.277646 -280.830948)
			(xy 366.233184 -280.852046) (xy 366.185913 -280.865738) (xy 366.137058 -280.87167) (xy 366.087883 -280.869689)
			(xy 366.039664 -280.859845) (xy 365.993648 -280.842393) (xy 365.951027 -280.817786) (xy 365.912906 -280.786661)
			(xy 365.880271 -280.749824) (xy 365.853968 -280.708228) (xy 365.834677 -280.662952) (xy 365.8229 -280.615168)
			(xy 365.81894 -280.566114) (xy 365.489998 -280.566114) (xy 365.489503 -280.590721) (xy 365.481608 -280.639298)
			(xy 365.466024 -280.685979) (xy 365.443153 -280.729556) (xy 365.413588 -280.7689) (xy 365.378095 -280.802992)
			(xy 365.337592 -280.830948) (xy 365.29313 -280.852046) (xy 365.245859 -280.865738) (xy 365.197004 -280.87167)
			(xy 365.147829 -280.869689) (xy 365.09961 -280.859845) (xy 365.053594 -280.842393) (xy 365.010973 -280.817786)
			(xy 364.972852 -280.786661) (xy 364.940217 -280.749824) (xy 364.913914 -280.708228) (xy 364.894623 -280.662952)
			(xy 364.882846 -280.615168) (xy 364.878886 -280.566114) (xy 364.550198 -280.566114) (xy 364.549703 -280.590721)
			(xy 364.541808 -280.639298) (xy 364.526224 -280.685979) (xy 364.503353 -280.729556) (xy 364.473788 -280.7689)
			(xy 364.438295 -280.802992) (xy 364.397792 -280.830948) (xy 364.35333 -280.852046) (xy 364.306059 -280.865738)
			(xy 364.257204 -280.87167) (xy 364.208029 -280.869689) (xy 364.15981 -280.859845) (xy 364.113794 -280.842393)
			(xy 364.071173 -280.817786) (xy 364.033052 -280.786661) (xy 364.000417 -280.749824) (xy 363.974114 -280.708228)
			(xy 363.954823 -280.662952) (xy 363.943046 -280.615168) (xy 363.939086 -280.566114) (xy 361.730036 -280.566114)
			(xy 361.729541 -280.590721) (xy 361.721646 -280.639298) (xy 361.706062 -280.685979) (xy 361.683191 -280.729556)
			(xy 361.653626 -280.7689) (xy 361.618133 -280.802992) (xy 361.57763 -280.830948) (xy 361.533168 -280.852046)
			(xy 361.485897 -280.865738) (xy 361.437042 -280.87167) (xy 361.387867 -280.869689) (xy 361.339648 -280.859845)
			(xy 361.293632 -280.842393) (xy 361.251011 -280.817786) (xy 361.21289 -280.786661) (xy 361.180255 -280.749824)
			(xy 361.153952 -280.708228) (xy 361.134661 -280.662952) (xy 361.122884 -280.615168) (xy 361.118924 -280.566114)
			(xy 358.916478 -280.566114) (xy 358.915983 -280.590721) (xy 358.908088 -280.639298) (xy 358.892504 -280.685979)
			(xy 358.869633 -280.729556) (xy 358.840068 -280.7689) (xy 358.804575 -280.802992) (xy 358.764072 -280.830948)
			(xy 358.71961 -280.852046) (xy 358.672339 -280.865738) (xy 358.623484 -280.87167) (xy 358.574309 -280.869689)
			(xy 358.52609 -280.859845) (xy 358.480074 -280.842393) (xy 358.437453 -280.817786) (xy 358.399332 -280.786661)
			(xy 358.366697 -280.749824) (xy 358.340394 -280.708228) (xy 358.321103 -280.662952) (xy 358.309326 -280.615168)
			(xy 358.305366 -280.566114) (xy 356.096316 -280.566114) (xy 356.095821 -280.590721) (xy 356.087926 -280.639298)
			(xy 356.072342 -280.685979) (xy 356.049471 -280.729556) (xy 356.019906 -280.7689) (xy 355.984413 -280.802992)
			(xy 355.94391 -280.830948) (xy 355.899448 -280.852046) (xy 355.852177 -280.865738) (xy 355.803322 -280.87167)
			(xy 355.754147 -280.869689) (xy 355.705928 -280.859845) (xy 355.659912 -280.842393) (xy 355.617291 -280.817786)
			(xy 355.57917 -280.786661) (xy 355.546535 -280.749824) (xy 355.520232 -280.708228) (xy 355.500941 -280.662952)
			(xy 355.489164 -280.615168) (xy 355.485204 -280.566114) (xy 355.156516 -280.566114) (xy 355.156021 -280.590721)
			(xy 355.148126 -280.639298) (xy 355.132542 -280.685979) (xy 355.109671 -280.729556) (xy 355.080106 -280.7689)
			(xy 355.044613 -280.802992) (xy 355.00411 -280.830948) (xy 354.959648 -280.852046) (xy 354.912377 -280.865738)
			(xy 354.863522 -280.87167) (xy 354.814347 -280.869689) (xy 354.766128 -280.859845) (xy 354.720112 -280.842393)
			(xy 354.677491 -280.817786) (xy 354.63937 -280.786661) (xy 354.606735 -280.749824) (xy 354.580432 -280.708228)
			(xy 354.561141 -280.662952) (xy 354.549364 -280.615168) (xy 354.545404 -280.566114) (xy 354.216462 -280.566114)
			(xy 354.215967 -280.590721) (xy 354.208072 -280.639298) (xy 354.192488 -280.685979) (xy 354.169617 -280.729556)
			(xy 354.140052 -280.7689) (xy 354.104559 -280.802992) (xy 354.064056 -280.830948) (xy 354.019594 -280.852046)
			(xy 353.972323 -280.865738) (xy 353.923468 -280.87167) (xy 353.874293 -280.869689) (xy 353.826074 -280.859845)
			(xy 353.780058 -280.842393) (xy 353.737437 -280.817786) (xy 353.699316 -280.786661) (xy 353.666681 -280.749824)
			(xy 353.640378 -280.708228) (xy 353.621087 -280.662952) (xy 353.60931 -280.615168) (xy 353.60535 -280.566114)
			(xy 353.276408 -280.566114) (xy 353.275913 -280.590721) (xy 353.268018 -280.639298) (xy 353.252434 -280.685979)
			(xy 353.229563 -280.729556) (xy 353.199998 -280.7689) (xy 353.164505 -280.802992) (xy 353.124002 -280.830948)
			(xy 353.07954 -280.852046) (xy 353.032269 -280.865738) (xy 352.983414 -280.87167) (xy 352.934239 -280.869689)
			(xy 352.88602 -280.859845) (xy 352.840004 -280.842393) (xy 352.797383 -280.817786) (xy 352.759262 -280.786661)
			(xy 352.726627 -280.749824) (xy 352.700324 -280.708228) (xy 352.681033 -280.662952) (xy 352.669256 -280.615168)
			(xy 352.665296 -280.566114) (xy 352.336354 -280.566114) (xy 352.335859 -280.590721) (xy 352.327964 -280.639298)
			(xy 352.31238 -280.685979) (xy 352.289509 -280.729556) (xy 352.259944 -280.7689) (xy 352.224451 -280.802992)
			(xy 352.183948 -280.830948) (xy 352.139486 -280.852046) (xy 352.092215 -280.865738) (xy 352.04336 -280.87167)
			(xy 351.994185 -280.869689) (xy 351.945966 -280.859845) (xy 351.89995 -280.842393) (xy 351.857329 -280.817786)
			(xy 351.819208 -280.786661) (xy 351.786573 -280.749824) (xy 351.76027 -280.708228) (xy 351.740979 -280.662952)
			(xy 351.729202 -280.615168) (xy 351.725242 -280.566114) (xy 351.396554 -280.566114) (xy 351.396059 -280.590721)
			(xy 351.388164 -280.639298) (xy 351.37258 -280.685979) (xy 351.349709 -280.729556) (xy 351.320144 -280.7689)
			(xy 351.284651 -280.802992) (xy 351.244148 -280.830948) (xy 351.199686 -280.852046) (xy 351.152415 -280.865738)
			(xy 351.10356 -280.87167) (xy 351.054385 -280.869689) (xy 351.006166 -280.859845) (xy 350.96015 -280.842393)
			(xy 350.917529 -280.817786) (xy 350.879408 -280.786661) (xy 350.846773 -280.749824) (xy 350.82047 -280.708228)
			(xy 350.801179 -280.662952) (xy 350.789402 -280.615168) (xy 350.785442 -280.566114) (xy 350.4565 -280.566114)
			(xy 350.456005 -280.590721) (xy 350.44811 -280.639298) (xy 350.432526 -280.685979) (xy 350.409655 -280.729556)
			(xy 350.38009 -280.7689) (xy 350.344597 -280.802992) (xy 350.304094 -280.830948) (xy 350.259632 -280.852046)
			(xy 350.212361 -280.865738) (xy 350.163506 -280.87167) (xy 350.114331 -280.869689) (xy 350.066112 -280.859845)
			(xy 350.020096 -280.842393) (xy 349.977475 -280.817786) (xy 349.939354 -280.786661) (xy 349.906719 -280.749824)
			(xy 349.880416 -280.708228) (xy 349.861125 -280.662952) (xy 349.849348 -280.615168) (xy 349.845388 -280.566114)
			(xy 349.516446 -280.566114) (xy 349.515951 -280.590721) (xy 349.508056 -280.639298) (xy 349.492472 -280.685979)
			(xy 349.469601 -280.729556) (xy 349.440036 -280.7689) (xy 349.404543 -280.802992) (xy 349.36404 -280.830948)
			(xy 349.319578 -280.852046) (xy 349.272307 -280.865738) (xy 349.223452 -280.87167) (xy 349.174277 -280.869689)
			(xy 349.126058 -280.859845) (xy 349.080042 -280.842393) (xy 349.037421 -280.817786) (xy 348.9993 -280.786661)
			(xy 348.966665 -280.749824) (xy 348.940362 -280.708228) (xy 348.921071 -280.662952) (xy 348.909294 -280.615168)
			(xy 348.905334 -280.566114) (xy 348.576392 -280.566114) (xy 348.575897 -280.590721) (xy 348.568002 -280.639298)
			(xy 348.552418 -280.685979) (xy 348.529547 -280.729556) (xy 348.499982 -280.7689) (xy 348.464489 -280.802992)
			(xy 348.423986 -280.830948) (xy 348.379524 -280.852046) (xy 348.332253 -280.865738) (xy 348.283398 -280.87167)
			(xy 348.234223 -280.869689) (xy 348.186004 -280.859845) (xy 348.139988 -280.842393) (xy 348.097367 -280.817786)
			(xy 348.059246 -280.786661) (xy 348.026611 -280.749824) (xy 348.000308 -280.708228) (xy 347.981017 -280.662952)
			(xy 347.96924 -280.615168) (xy 347.96528 -280.566114) (xy 347.636338 -280.566114) (xy 347.635843 -280.590721)
			(xy 347.627948 -280.639298) (xy 347.612364 -280.685979) (xy 347.589493 -280.729556) (xy 347.559928 -280.7689)
			(xy 347.524435 -280.802992) (xy 347.483932 -280.830948) (xy 347.43947 -280.852046) (xy 347.392199 -280.865738)
			(xy 347.343344 -280.87167) (xy 347.294169 -280.869689) (xy 347.24595 -280.859845) (xy 347.199934 -280.842393)
			(xy 347.157313 -280.817786) (xy 347.119192 -280.786661) (xy 347.086557 -280.749824) (xy 347.060254 -280.708228)
			(xy 347.040963 -280.662952) (xy 347.029186 -280.615168) (xy 347.025226 -280.566114) (xy 346.696538 -280.566114)
			(xy 346.696043 -280.590721) (xy 346.688148 -280.639298) (xy 346.672564 -280.685979) (xy 346.649693 -280.729556)
			(xy 346.620128 -280.7689) (xy 346.584635 -280.802992) (xy 346.544132 -280.830948) (xy 346.49967 -280.852046)
			(xy 346.452399 -280.865738) (xy 346.403544 -280.87167) (xy 346.354369 -280.869689) (xy 346.30615 -280.859845)
			(xy 346.260134 -280.842393) (xy 346.217513 -280.817786) (xy 346.179392 -280.786661) (xy 346.146757 -280.749824)
			(xy 346.120454 -280.708228) (xy 346.101163 -280.662952) (xy 346.089386 -280.615168) (xy 346.085426 -280.566114)
			(xy 345.756484 -280.566114) (xy 345.755989 -280.590721) (xy 345.748094 -280.639298) (xy 345.73251 -280.685979)
			(xy 345.709639 -280.729556) (xy 345.680074 -280.7689) (xy 345.644581 -280.802992) (xy 345.604078 -280.830948)
			(xy 345.559616 -280.852046) (xy 345.512345 -280.865738) (xy 345.46349 -280.87167) (xy 345.414315 -280.869689)
			(xy 345.366096 -280.859845) (xy 345.32008 -280.842393) (xy 345.277459 -280.817786) (xy 345.239338 -280.786661)
			(xy 345.206703 -280.749824) (xy 345.1804 -280.708228) (xy 345.161109 -280.662952) (xy 345.149332 -280.615168)
			(xy 345.145372 -280.566114) (xy 344.880692 -280.566114) (xy 344.880692 -280.970228) (xy 344.881154 -280.980104)
			(xy 344.888599 -280.998401) (xy 344.89517 -281.005788) (xy 344.895424 -281.006042) (xy 344.945208 -281.055826)
			(xy 344.952603 -281.062679) (xy 344.971202 -281.070422) (xy 344.981276 -281.070812) (xy 345.006515 -281.071355)
			(xy 345.056298 -281.079704) (xy 345.104029 -281.096128) (xy 345.148409 -281.120181) (xy 345.188227 -281.151206)
			(xy 345.222399 -281.188359) (xy 345.249994 -281.230627) (xy 345.27026 -281.276858) (xy 345.282645 -281.325794)
			(xy 345.286811 -281.3761) (xy 345.615289 -281.3761) (xy 345.619459 -281.325768) (xy 345.631857 -281.276808)
			(xy 345.652144 -281.230557) (xy 345.679766 -281.188275) (xy 345.713971 -281.151116) (xy 345.753825 -281.120094)
			(xy 345.798241 -281.096054) (xy 345.846008 -281.079652) (xy 345.895824 -281.071335) (xy 345.921076 -281.070812)
			(xy 346.86113 -281.070812) (xy 346.886385 -281.071296) (xy 346.936207 -281.079614) (xy 346.983979 -281.096019)
			(xy 347.028401 -281.120062) (xy 347.068259 -281.151089) (xy 347.102467 -281.188252) (xy 347.130092 -281.230539)
			(xy 347.150381 -281.276796) (xy 347.16278 -281.325762) (xy 347.166951 -281.3761) (xy 347.166949 -281.37612)
			(xy 347.49538 -281.37612) (xy 347.49934 -281.327066) (xy 347.511117 -281.279282) (xy 347.530408 -281.234006)
			(xy 347.556711 -281.19241) (xy 347.589346 -281.155573) (xy 347.627467 -281.124448) (xy 347.670088 -281.099841)
			(xy 347.716104 -281.082389) (xy 347.764323 -281.072545) (xy 347.813498 -281.070564) (xy 347.862353 -281.076496)
			(xy 347.909624 -281.090188) (xy 347.954086 -281.111286) (xy 347.994589 -281.139242) (xy 348.030082 -281.173334)
			(xy 348.059647 -281.212678) (xy 348.082518 -281.256255) (xy 348.098102 -281.302936) (xy 348.105997 -281.351513)
			(xy 348.106492 -281.3761) (xy 348.43536 -281.3761) (xy 348.439532 -281.325756) (xy 348.451934 -281.276786)
			(xy 348.472227 -281.230526) (xy 348.499859 -281.188237) (xy 348.534075 -281.151073) (xy 348.573942 -281.120048)
			(xy 348.618371 -281.096009) (xy 348.666152 -281.079611) (xy 348.71598 -281.071302) (xy 348.741238 -281.070812)
			(xy 349.681292 -281.070812) (xy 349.706552 -281.071264) (xy 349.756383 -281.079578) (xy 349.804165 -281.095981)
			(xy 349.848596 -281.120025) (xy 349.888464 -281.151054) (xy 349.92268 -281.188222) (xy 349.950312 -281.230515)
			(xy 349.970606 -281.276779) (xy 349.983008 -281.325753) (xy 349.98718 -281.3761) (xy 349.987178 -281.37612)
			(xy 350.315288 -281.37612) (xy 350.319248 -281.327066) (xy 350.331025 -281.279282) (xy 350.350316 -281.234006)
			(xy 350.376619 -281.19241) (xy 350.409254 -281.155573) (xy 350.447375 -281.124448) (xy 350.489996 -281.099841)
			(xy 350.536012 -281.082389) (xy 350.584231 -281.072545) (xy 350.633406 -281.070564) (xy 350.682261 -281.076496)
			(xy 350.729532 -281.090188) (xy 350.773994 -281.111286) (xy 350.814497 -281.139242) (xy 350.84999 -281.173334)
			(xy 350.879555 -281.212678) (xy 350.902426 -281.256255) (xy 350.91801 -281.302936) (xy 350.925905 -281.351513)
			(xy 350.9264 -281.37612) (xy 353.135196 -281.37612) (xy 353.139156 -281.327066) (xy 353.150933 -281.279282)
			(xy 353.170224 -281.234006) (xy 353.196527 -281.19241) (xy 353.229162 -281.155573) (xy 353.267283 -281.124448)
			(xy 353.309904 -281.099841) (xy 353.35592 -281.082389) (xy 353.404139 -281.072545) (xy 353.453314 -281.070564)
			(xy 353.502169 -281.076496) (xy 353.54944 -281.090188) (xy 353.593902 -281.111286) (xy 353.634405 -281.139242)
			(xy 353.669898 -281.173334) (xy 353.699463 -281.212678) (xy 353.722334 -281.256255) (xy 353.737918 -281.302936)
			(xy 353.745813 -281.351513) (xy 353.746308 -281.37612) (xy 355.955358 -281.37612) (xy 355.959318 -281.327066)
			(xy 355.971095 -281.279282) (xy 355.990386 -281.234006) (xy 356.016689 -281.19241) (xy 356.049324 -281.155573)
			(xy 356.087445 -281.124448) (xy 356.130066 -281.099841) (xy 356.176082 -281.082389) (xy 356.224301 -281.072545)
			(xy 356.273476 -281.070564) (xy 356.322331 -281.076496) (xy 356.369602 -281.090188) (xy 356.414064 -281.111286)
			(xy 356.454567 -281.139242) (xy 356.49006 -281.173334) (xy 356.519625 -281.212678) (xy 356.542496 -281.256255)
			(xy 356.55808 -281.302936) (xy 356.565975 -281.351513) (xy 356.56647 -281.37612) (xy 356.895412 -281.37612)
			(xy 356.899372 -281.327066) (xy 356.911149 -281.279282) (xy 356.93044 -281.234006) (xy 356.956743 -281.19241)
			(xy 356.989378 -281.155573) (xy 357.027499 -281.124448) (xy 357.07012 -281.099841) (xy 357.116136 -281.082389)
			(xy 357.164355 -281.072545) (xy 357.21353 -281.070564) (xy 357.262385 -281.076496) (xy 357.309656 -281.090188)
			(xy 357.354118 -281.111286) (xy 357.394621 -281.139242) (xy 357.430114 -281.173334) (xy 357.459679 -281.212678)
			(xy 357.48255 -281.256255) (xy 357.498134 -281.302936) (xy 357.506029 -281.351513) (xy 357.506524 -281.37612)
			(xy 357.835212 -281.37612) (xy 357.839172 -281.327066) (xy 357.850949 -281.279282) (xy 357.87024 -281.234006)
			(xy 357.896543 -281.19241) (xy 357.929178 -281.155573) (xy 357.967299 -281.124448) (xy 358.00992 -281.099841)
			(xy 358.055936 -281.082389) (xy 358.104155 -281.072545) (xy 358.15333 -281.070564) (xy 358.202185 -281.076496)
			(xy 358.249456 -281.090188) (xy 358.293918 -281.111286) (xy 358.334421 -281.139242) (xy 358.369914 -281.173334)
			(xy 358.399479 -281.212678) (xy 358.42235 -281.256255) (xy 358.437934 -281.302936) (xy 358.445829 -281.351513)
			(xy 358.446324 -281.37612) (xy 361.589078 -281.37612) (xy 361.593038 -281.327066) (xy 361.604815 -281.279282)
			(xy 361.624106 -281.234006) (xy 361.650409 -281.19241) (xy 361.683044 -281.155573) (xy 361.721165 -281.124448)
			(xy 361.763786 -281.099841) (xy 361.809802 -281.082389) (xy 361.858021 -281.072545) (xy 361.907196 -281.070564)
			(xy 361.956051 -281.076496) (xy 362.003322 -281.090188) (xy 362.047784 -281.111286) (xy 362.088287 -281.139242)
			(xy 362.12378 -281.173334) (xy 362.153345 -281.212678) (xy 362.176216 -281.256255) (xy 362.1918 -281.302936)
			(xy 362.199695 -281.351513) (xy 362.20019 -281.37612) (xy 362.528878 -281.37612) (xy 362.532838 -281.327066)
			(xy 362.544615 -281.279282) (xy 362.563906 -281.234006) (xy 362.590209 -281.19241) (xy 362.622844 -281.155573)
			(xy 362.660965 -281.124448) (xy 362.703586 -281.099841) (xy 362.749602 -281.082389) (xy 362.797821 -281.072545)
			(xy 362.846996 -281.070564) (xy 362.895851 -281.076496) (xy 362.943122 -281.090188) (xy 362.987584 -281.111286)
			(xy 363.028087 -281.139242) (xy 363.06358 -281.173334) (xy 363.093145 -281.212678) (xy 363.116016 -281.256255)
			(xy 363.1316 -281.302936) (xy 363.139495 -281.351513) (xy 363.13999 -281.37612) (xy 363.468932 -281.37612)
			(xy 363.472892 -281.327066) (xy 363.484669 -281.279282) (xy 363.50396 -281.234006) (xy 363.530263 -281.19241)
			(xy 363.562898 -281.155573) (xy 363.601019 -281.124448) (xy 363.64364 -281.099841) (xy 363.689656 -281.082389)
			(xy 363.737875 -281.072545) (xy 363.78705 -281.070564) (xy 363.835905 -281.076496) (xy 363.883176 -281.090188)
			(xy 363.927638 -281.111286) (xy 363.968141 -281.139242) (xy 364.003634 -281.173334) (xy 364.033199 -281.212678)
			(xy 364.05607 -281.256255) (xy 364.071654 -281.302936) (xy 364.079549 -281.351513) (xy 364.080044 -281.37612)
			(xy 366.289094 -281.37612) (xy 366.293054 -281.327066) (xy 366.304831 -281.279282) (xy 366.324122 -281.234006)
			(xy 366.350425 -281.19241) (xy 366.38306 -281.155573) (xy 366.421181 -281.124448) (xy 366.463802 -281.099841)
			(xy 366.509818 -281.082389) (xy 366.558037 -281.072545) (xy 366.607212 -281.070564) (xy 366.656067 -281.076496)
			(xy 366.703338 -281.090188) (xy 366.7478 -281.111286) (xy 366.788303 -281.139242) (xy 366.823796 -281.173334)
			(xy 366.853361 -281.212678) (xy 366.876232 -281.256255) (xy 366.891816 -281.302936) (xy 366.899711 -281.351513)
			(xy 366.900206 -281.37612) (xy 369.109002 -281.37612) (xy 369.112962 -281.327066) (xy 369.124739 -281.279282)
			(xy 369.14403 -281.234006) (xy 369.170333 -281.19241) (xy 369.202968 -281.155573) (xy 369.241089 -281.124448)
			(xy 369.28371 -281.099841) (xy 369.329726 -281.082389) (xy 369.377945 -281.072545) (xy 369.42712 -281.070564)
			(xy 369.475975 -281.076496) (xy 369.523246 -281.090188) (xy 369.567708 -281.111286) (xy 369.608211 -281.139242)
			(xy 369.643704 -281.173334) (xy 369.673269 -281.212678) (xy 369.69614 -281.256255) (xy 369.711724 -281.302936)
			(xy 369.719619 -281.351513) (xy 369.720114 -281.3761) (xy 370.049089 -281.3761) (xy 370.053259 -281.325769)
			(xy 370.065656 -281.276811) (xy 370.085941 -281.230561) (xy 370.113562 -281.18828) (xy 370.147764 -281.151122)
			(xy 370.187616 -281.120099) (xy 370.23203 -281.096058) (xy 370.279795 -281.079655) (xy 370.329608 -281.071337)
			(xy 370.35486 -281.070812) (xy 371.294914 -281.070812) (xy 371.32017 -281.071295) (xy 371.369993 -281.079611)
			(xy 371.417768 -281.096014) (xy 371.462192 -281.120057) (xy 371.502053 -281.151083) (xy 371.536263 -281.188247)
			(xy 371.56389 -281.230535) (xy 371.58418 -281.276793) (xy 371.59658 -281.32576) (xy 371.600751 -281.3761)
			(xy 371.600749 -281.37612) (xy 371.92891 -281.37612) (xy 371.93287 -281.327066) (xy 371.944647 -281.279282)
			(xy 371.963938 -281.234006) (xy 371.990241 -281.19241) (xy 372.022876 -281.155573) (xy 372.060997 -281.124448)
			(xy 372.103618 -281.099841) (xy 372.149634 -281.082389) (xy 372.197853 -281.072545) (xy 372.247028 -281.070564)
			(xy 372.295883 -281.076496) (xy 372.343154 -281.090188) (xy 372.387616 -281.111286) (xy 372.428119 -281.139242)
			(xy 372.463612 -281.173334) (xy 372.493177 -281.212678) (xy 372.516048 -281.256255) (xy 372.531632 -281.302936)
			(xy 372.539527 -281.351513) (xy 372.540022 -281.37612) (xy 372.539527 -281.400727) (xy 372.531632 -281.449304)
			(xy 372.516048 -281.495985) (xy 372.493177 -281.539562) (xy 372.463612 -281.578906) (xy 372.428119 -281.612998)
			(xy 372.387616 -281.640954) (xy 372.343154 -281.662052) (xy 372.295883 -281.675744) (xy 372.247028 -281.681676)
			(xy 372.197853 -281.679695) (xy 372.149634 -281.669851) (xy 372.103618 -281.652399) (xy 372.060997 -281.627792)
			(xy 372.022876 -281.596667) (xy 371.990241 -281.55983) (xy 371.963938 -281.518234) (xy 371.944647 -281.472958)
			(xy 371.93287 -281.425174) (xy 371.92891 -281.37612) (xy 371.600749 -281.37612) (xy 371.59658 -281.42644)
			(xy 371.58418 -281.475407) (xy 371.56389 -281.521665) (xy 371.536263 -281.563953) (xy 371.502053 -281.601117)
			(xy 371.462192 -281.632143) (xy 371.417768 -281.656186) (xy 371.369993 -281.672589) (xy 371.32017 -281.680905)
			(xy 371.294914 -281.681428) (xy 370.35486 -281.681428) (xy 370.329609 -281.680863) (xy 370.279795 -281.672545)
			(xy 370.23203 -281.656142) (xy 370.187616 -281.632101) (xy 370.147764 -281.601078) (xy 370.113562 -281.56392)
			(xy 370.085941 -281.521639) (xy 370.065656 -281.475389) (xy 370.053259 -281.426431) (xy 370.049089 -281.3761)
			(xy 369.720114 -281.3761) (xy 369.720114 -281.37612) (xy 369.719619 -281.400727) (xy 369.711724 -281.449304)
			(xy 369.69614 -281.495985) (xy 369.673269 -281.539562) (xy 369.643704 -281.578906) (xy 369.608211 -281.612998)
			(xy 369.567708 -281.640954) (xy 369.523246 -281.662052) (xy 369.475975 -281.675744) (xy 369.42712 -281.681676)
			(xy 369.377945 -281.679695) (xy 369.329726 -281.669851) (xy 369.28371 -281.652399) (xy 369.241089 -281.627792)
			(xy 369.202968 -281.596667) (xy 369.170333 -281.55983) (xy 369.14403 -281.518234) (xy 369.124739 -281.472958)
			(xy 369.112962 -281.425174) (xy 369.109002 -281.37612) (xy 366.900206 -281.37612) (xy 366.899711 -281.400727)
			(xy 366.891816 -281.449304) (xy 366.876232 -281.495985) (xy 366.853361 -281.539562) (xy 366.823796 -281.578906)
			(xy 366.788303 -281.612998) (xy 366.7478 -281.640954) (xy 366.703338 -281.662052) (xy 366.656067 -281.675744)
			(xy 366.607212 -281.681676) (xy 366.558037 -281.679695) (xy 366.509818 -281.669851) (xy 366.463802 -281.652399)
			(xy 366.421181 -281.627792) (xy 366.38306 -281.596667) (xy 366.350425 -281.55983) (xy 366.324122 -281.518234)
			(xy 366.304831 -281.472958) (xy 366.293054 -281.425174) (xy 366.289094 -281.37612) (xy 364.080044 -281.37612)
			(xy 364.079549 -281.400727) (xy 364.071654 -281.449304) (xy 364.05607 -281.495985) (xy 364.033199 -281.539562)
			(xy 364.003634 -281.578906) (xy 363.968141 -281.612998) (xy 363.927638 -281.640954) (xy 363.883176 -281.662052)
			(xy 363.835905 -281.675744) (xy 363.78705 -281.681676) (xy 363.737875 -281.679695) (xy 363.689656 -281.669851)
			(xy 363.64364 -281.652399) (xy 363.601019 -281.627792) (xy 363.562898 -281.596667) (xy 363.530263 -281.55983)
			(xy 363.50396 -281.518234) (xy 363.484669 -281.472958) (xy 363.472892 -281.425174) (xy 363.468932 -281.37612)
			(xy 363.13999 -281.37612) (xy 363.139495 -281.400727) (xy 363.1316 -281.449304) (xy 363.116016 -281.495985)
			(xy 363.093145 -281.539562) (xy 363.06358 -281.578906) (xy 363.028087 -281.612998) (xy 362.987584 -281.640954)
			(xy 362.943122 -281.662052) (xy 362.895851 -281.675744) (xy 362.846996 -281.681676) (xy 362.797821 -281.679695)
			(xy 362.749602 -281.669851) (xy 362.703586 -281.652399) (xy 362.660965 -281.627792) (xy 362.622844 -281.596667)
			(xy 362.590209 -281.55983) (xy 362.563906 -281.518234) (xy 362.544615 -281.472958) (xy 362.532838 -281.425174)
			(xy 362.528878 -281.37612) (xy 362.20019 -281.37612) (xy 362.199695 -281.400727) (xy 362.1918 -281.449304)
			(xy 362.176216 -281.495985) (xy 362.153345 -281.539562) (xy 362.12378 -281.578906) (xy 362.088287 -281.612998)
			(xy 362.047784 -281.640954) (xy 362.003322 -281.662052) (xy 361.956051 -281.675744) (xy 361.907196 -281.681676)
			(xy 361.858021 -281.679695) (xy 361.809802 -281.669851) (xy 361.763786 -281.652399) (xy 361.721165 -281.627792)
			(xy 361.683044 -281.596667) (xy 361.650409 -281.55983) (xy 361.624106 -281.518234) (xy 361.604815 -281.472958)
			(xy 361.593038 -281.425174) (xy 361.589078 -281.37612) (xy 358.446324 -281.37612) (xy 358.445829 -281.400727)
			(xy 358.437934 -281.449304) (xy 358.42235 -281.495985) (xy 358.399479 -281.539562) (xy 358.369914 -281.578906)
			(xy 358.334421 -281.612998) (xy 358.293918 -281.640954) (xy 358.249456 -281.662052) (xy 358.202185 -281.675744)
			(xy 358.15333 -281.681676) (xy 358.104155 -281.679695) (xy 358.055936 -281.669851) (xy 358.00992 -281.652399)
			(xy 357.967299 -281.627792) (xy 357.929178 -281.596667) (xy 357.896543 -281.55983) (xy 357.87024 -281.518234)
			(xy 357.850949 -281.472958) (xy 357.839172 -281.425174) (xy 357.835212 -281.37612) (xy 357.506524 -281.37612)
			(xy 357.506029 -281.400727) (xy 357.498134 -281.449304) (xy 357.48255 -281.495985) (xy 357.459679 -281.539562)
			(xy 357.430114 -281.578906) (xy 357.394621 -281.612998) (xy 357.354118 -281.640954) (xy 357.309656 -281.662052)
			(xy 357.262385 -281.675744) (xy 357.21353 -281.681676) (xy 357.164355 -281.679695) (xy 357.116136 -281.669851)
			(xy 357.07012 -281.652399) (xy 357.027499 -281.627792) (xy 356.989378 -281.596667) (xy 356.956743 -281.55983)
			(xy 356.93044 -281.518234) (xy 356.911149 -281.472958) (xy 356.899372 -281.425174) (xy 356.895412 -281.37612)
			(xy 356.56647 -281.37612) (xy 356.565975 -281.400727) (xy 356.55808 -281.449304) (xy 356.542496 -281.495985)
			(xy 356.519625 -281.539562) (xy 356.49006 -281.578906) (xy 356.454567 -281.612998) (xy 356.414064 -281.640954)
			(xy 356.369602 -281.662052) (xy 356.322331 -281.675744) (xy 356.273476 -281.681676) (xy 356.224301 -281.679695)
			(xy 356.176082 -281.669851) (xy 356.130066 -281.652399) (xy 356.087445 -281.627792) (xy 356.049324 -281.596667)
			(xy 356.016689 -281.55983) (xy 355.990386 -281.518234) (xy 355.971095 -281.472958) (xy 355.959318 -281.425174)
			(xy 355.955358 -281.37612) (xy 353.746308 -281.37612) (xy 353.745813 -281.400727) (xy 353.737918 -281.449304)
			(xy 353.722334 -281.495985) (xy 353.699463 -281.539562) (xy 353.669898 -281.578906) (xy 353.634405 -281.612998)
			(xy 353.593902 -281.640954) (xy 353.54944 -281.662052) (xy 353.502169 -281.675744) (xy 353.453314 -281.681676)
			(xy 353.404139 -281.679695) (xy 353.35592 -281.669851) (xy 353.309904 -281.652399) (xy 353.267283 -281.627792)
			(xy 353.229162 -281.596667) (xy 353.196527 -281.55983) (xy 353.170224 -281.518234) (xy 353.150933 -281.472958)
			(xy 353.139156 -281.425174) (xy 353.135196 -281.37612) (xy 350.9264 -281.37612) (xy 350.925905 -281.400727)
			(xy 350.91801 -281.449304) (xy 350.902426 -281.495985) (xy 350.879555 -281.539562) (xy 350.84999 -281.578906)
			(xy 350.814497 -281.612998) (xy 350.773994 -281.640954) (xy 350.729532 -281.662052) (xy 350.682261 -281.675744)
			(xy 350.633406 -281.681676) (xy 350.584231 -281.679695) (xy 350.536012 -281.669851) (xy 350.489996 -281.652399)
			(xy 350.447375 -281.627792) (xy 350.409254 -281.596667) (xy 350.376619 -281.55983) (xy 350.350316 -281.518234)
			(xy 350.331025 -281.472958) (xy 350.319248 -281.425174) (xy 350.315288 -281.37612) (xy 349.987178 -281.37612)
			(xy 349.983008 -281.426447) (xy 349.970606 -281.475421) (xy 349.950312 -281.521685) (xy 349.92268 -281.563978)
			(xy 349.888464 -281.601146) (xy 349.848596 -281.632175) (xy 349.804165 -281.656219) (xy 349.756383 -281.672622)
			(xy 349.706552 -281.680936) (xy 349.681292 -281.681428) (xy 348.741238 -281.681428) (xy 348.71598 -281.680898)
			(xy 348.666152 -281.672589) (xy 348.618371 -281.656191) (xy 348.573941 -281.632152) (xy 348.534075 -281.601127)
			(xy 348.499859 -281.563963) (xy 348.472227 -281.521674) (xy 348.451934 -281.475414) (xy 348.439532 -281.426444)
			(xy 348.43536 -281.3761) (xy 348.106492 -281.3761) (xy 348.106492 -281.37612) (xy 348.105997 -281.400727)
			(xy 348.098102 -281.449304) (xy 348.082518 -281.495985) (xy 348.059647 -281.539562) (xy 348.030082 -281.578906)
			(xy 347.994589 -281.612998) (xy 347.954086 -281.640954) (xy 347.909624 -281.662052) (xy 347.862353 -281.675744)
			(xy 347.813498 -281.681676) (xy 347.764323 -281.679695) (xy 347.716104 -281.669851) (xy 347.670088 -281.652399)
			(xy 347.627467 -281.627792) (xy 347.589346 -281.596667) (xy 347.556711 -281.55983) (xy 347.530408 -281.518234)
			(xy 347.511117 -281.472958) (xy 347.49934 -281.425174) (xy 347.49538 -281.37612) (xy 347.166949 -281.37612)
			(xy 347.16278 -281.426438) (xy 347.150381 -281.475404) (xy 347.130092 -281.521661) (xy 347.102467 -281.563948)
			(xy 347.068259 -281.601111) (xy 347.028401 -281.632138) (xy 346.983979 -281.656181) (xy 346.936207 -281.672586)
			(xy 346.886385 -281.680904) (xy 346.86113 -281.681428) (xy 345.921076 -281.681428) (xy 345.895824 -281.680865)
			(xy 345.846008 -281.672548) (xy 345.798241 -281.656146) (xy 345.753825 -281.632106) (xy 345.713971 -281.601084)
			(xy 345.679766 -281.563925) (xy 345.652144 -281.521643) (xy 345.631857 -281.475392) (xy 345.619459 -281.426432)
			(xy 345.615289 -281.3761) (xy 345.286811 -281.3761) (xy 345.282645 -281.426406) (xy 345.27026 -281.475342)
			(xy 345.249994 -281.521573) (xy 345.222399 -281.563841) (xy 345.188227 -281.600994) (xy 345.148409 -281.632019)
			(xy 345.104029 -281.656072) (xy 345.056298 -281.672496) (xy 345.006515 -281.680845) (xy 344.981276 -281.681428)
			(xy 344.971208 -281.681856) (xy 344.952613 -281.68958) (xy 344.945208 -281.696414) (xy 344.895424 -281.746198)
			(xy 344.888705 -281.753433) (xy 344.8811 -281.771639) (xy 344.880692 -281.781504) (xy 344.880692 -282.186126)
			(xy 345.145372 -282.186126) (xy 345.149332 -282.137072) (xy 345.161109 -282.089288) (xy 345.1804 -282.044012)
			(xy 345.206703 -282.002416) (xy 345.239338 -281.965579) (xy 345.277459 -281.934454) (xy 345.32008 -281.909847)
			(xy 345.366096 -281.892395) (xy 345.414315 -281.882551) (xy 345.46349 -281.88057) (xy 345.512345 -281.886502)
			(xy 345.559616 -281.900194) (xy 345.604078 -281.921292) (xy 345.644581 -281.949248) (xy 345.680074 -281.98334)
			(xy 345.709639 -282.022684) (xy 345.73251 -282.066261) (xy 345.748094 -282.112942) (xy 345.755989 -282.161519)
			(xy 345.756484 -282.186126) (xy 346.085426 -282.186126) (xy 346.089386 -282.137072) (xy 346.101163 -282.089288)
			(xy 346.120454 -282.044012) (xy 346.146757 -282.002416) (xy 346.179392 -281.965579) (xy 346.217513 -281.934454)
			(xy 346.260134 -281.909847) (xy 346.30615 -281.892395) (xy 346.354369 -281.882551) (xy 346.403544 -281.88057)
			(xy 346.452399 -281.886502) (xy 346.49967 -281.900194) (xy 346.544132 -281.921292) (xy 346.584635 -281.949248)
			(xy 346.620128 -281.98334) (xy 346.649693 -282.022684) (xy 346.672564 -282.066261) (xy 346.688148 -282.112942)
			(xy 346.696043 -282.161519) (xy 346.696538 -282.186126) (xy 347.025226 -282.186126) (xy 347.029186 -282.137072)
			(xy 347.040963 -282.089288) (xy 347.060254 -282.044012) (xy 347.086557 -282.002416) (xy 347.119192 -281.965579)
			(xy 347.157313 -281.934454) (xy 347.199934 -281.909847) (xy 347.24595 -281.892395) (xy 347.294169 -281.882551)
			(xy 347.343344 -281.88057) (xy 347.392199 -281.886502) (xy 347.43947 -281.900194) (xy 347.483932 -281.921292)
			(xy 347.524435 -281.949248) (xy 347.559928 -281.98334) (xy 347.589493 -282.022684) (xy 347.612364 -282.066261)
			(xy 347.627948 -282.112942) (xy 347.635843 -282.161519) (xy 347.636338 -282.186126) (xy 347.96528 -282.186126)
			(xy 347.96924 -282.137072) (xy 347.981017 -282.089288) (xy 348.000308 -282.044012) (xy 348.026611 -282.002416)
			(xy 348.059246 -281.965579) (xy 348.097367 -281.934454) (xy 348.139988 -281.909847) (xy 348.186004 -281.892395)
			(xy 348.234223 -281.882551) (xy 348.283398 -281.88057) (xy 348.332253 -281.886502) (xy 348.379524 -281.900194)
			(xy 348.423986 -281.921292) (xy 348.464489 -281.949248) (xy 348.499982 -281.98334) (xy 348.529547 -282.022684)
			(xy 348.552418 -282.066261) (xy 348.568002 -282.112942) (xy 348.575897 -282.161519) (xy 348.576392 -282.186126)
			(xy 348.905334 -282.186126) (xy 348.909294 -282.137072) (xy 348.921071 -282.089288) (xy 348.940362 -282.044012)
			(xy 348.966665 -282.002416) (xy 348.9993 -281.965579) (xy 349.037421 -281.934454) (xy 349.080042 -281.909847)
			(xy 349.126058 -281.892395) (xy 349.174277 -281.882551) (xy 349.223452 -281.88057) (xy 349.272307 -281.886502)
			(xy 349.319578 -281.900194) (xy 349.36404 -281.921292) (xy 349.404543 -281.949248) (xy 349.440036 -281.98334)
			(xy 349.469601 -282.022684) (xy 349.492472 -282.066261) (xy 349.508056 -282.112942) (xy 349.515951 -282.161519)
			(xy 349.516446 -282.186126) (xy 349.845388 -282.186126) (xy 349.849348 -282.137072) (xy 349.861125 -282.089288)
			(xy 349.880416 -282.044012) (xy 349.906719 -282.002416) (xy 349.939354 -281.965579) (xy 349.977475 -281.934454)
			(xy 350.020096 -281.909847) (xy 350.066112 -281.892395) (xy 350.114331 -281.882551) (xy 350.163506 -281.88057)
			(xy 350.212361 -281.886502) (xy 350.259632 -281.900194) (xy 350.304094 -281.921292) (xy 350.344597 -281.949248)
			(xy 350.38009 -281.98334) (xy 350.409655 -282.022684) (xy 350.432526 -282.066261) (xy 350.44811 -282.112942)
			(xy 350.456005 -282.161519) (xy 350.4565 -282.186126) (xy 350.785442 -282.186126) (xy 350.789402 -282.137072)
			(xy 350.801179 -282.089288) (xy 350.82047 -282.044012) (xy 350.846773 -282.002416) (xy 350.879408 -281.965579)
			(xy 350.917529 -281.934454) (xy 350.96015 -281.909847) (xy 351.006166 -281.892395) (xy 351.054385 -281.882551)
			(xy 351.10356 -281.88057) (xy 351.152415 -281.886502) (xy 351.199686 -281.900194) (xy 351.244148 -281.921292)
			(xy 351.284651 -281.949248) (xy 351.320144 -281.98334) (xy 351.349709 -282.022684) (xy 351.37258 -282.066261)
			(xy 351.388164 -282.112942) (xy 351.396059 -282.161519) (xy 351.396554 -282.186126) (xy 351.725242 -282.186126)
			(xy 351.729202 -282.137072) (xy 351.740979 -282.089288) (xy 351.76027 -282.044012) (xy 351.786573 -282.002416)
			(xy 351.819208 -281.965579) (xy 351.857329 -281.934454) (xy 351.89995 -281.909847) (xy 351.945966 -281.892395)
			(xy 351.994185 -281.882551) (xy 352.04336 -281.88057) (xy 352.092215 -281.886502) (xy 352.139486 -281.900194)
			(xy 352.183948 -281.921292) (xy 352.224451 -281.949248) (xy 352.259944 -281.98334) (xy 352.289509 -282.022684)
			(xy 352.31238 -282.066261) (xy 352.327964 -282.112942) (xy 352.335859 -282.161519) (xy 352.336354 -282.186126)
			(xy 352.665296 -282.186126) (xy 352.669256 -282.137072) (xy 352.681033 -282.089288) (xy 352.700324 -282.044012)
			(xy 352.726627 -282.002416) (xy 352.759262 -281.965579) (xy 352.797383 -281.934454) (xy 352.840004 -281.909847)
			(xy 352.88602 -281.892395) (xy 352.934239 -281.882551) (xy 352.983414 -281.88057) (xy 353.032269 -281.886502)
			(xy 353.07954 -281.900194) (xy 353.124002 -281.921292) (xy 353.164505 -281.949248) (xy 353.199998 -281.98334)
			(xy 353.229563 -282.022684) (xy 353.252434 -282.066261) (xy 353.268018 -282.112942) (xy 353.275913 -282.161519)
			(xy 353.276408 -282.186126) (xy 353.60535 -282.186126) (xy 353.60931 -282.137072) (xy 353.621087 -282.089288)
			(xy 353.640378 -282.044012) (xy 353.666681 -282.002416) (xy 353.699316 -281.965579) (xy 353.737437 -281.934454)
			(xy 353.780058 -281.909847) (xy 353.826074 -281.892395) (xy 353.874293 -281.882551) (xy 353.923468 -281.88057)
			(xy 353.972323 -281.886502) (xy 354.019594 -281.900194) (xy 354.064056 -281.921292) (xy 354.104559 -281.949248)
			(xy 354.140052 -281.98334) (xy 354.169617 -282.022684) (xy 354.192488 -282.066261) (xy 354.208072 -282.112942)
			(xy 354.215967 -282.161519) (xy 354.216462 -282.186126) (xy 354.545404 -282.186126) (xy 354.549364 -282.137072)
			(xy 354.561141 -282.089288) (xy 354.580432 -282.044012) (xy 354.606735 -282.002416) (xy 354.63937 -281.965579)
			(xy 354.677491 -281.934454) (xy 354.720112 -281.909847) (xy 354.766128 -281.892395) (xy 354.814347 -281.882551)
			(xy 354.863522 -281.88057) (xy 354.912377 -281.886502) (xy 354.959648 -281.900194) (xy 355.00411 -281.921292)
			(xy 355.044613 -281.949248) (xy 355.080106 -281.98334) (xy 355.109671 -282.022684) (xy 355.132542 -282.066261)
			(xy 355.148126 -282.112942) (xy 355.156021 -282.161519) (xy 355.156516 -282.186126) (xy 355.485204 -282.186126)
			(xy 355.489164 -282.137072) (xy 355.500941 -282.089288) (xy 355.520232 -282.044012) (xy 355.546535 -282.002416)
			(xy 355.57917 -281.965579) (xy 355.617291 -281.934454) (xy 355.659912 -281.909847) (xy 355.705928 -281.892395)
			(xy 355.754147 -281.882551) (xy 355.803322 -281.88057) (xy 355.852177 -281.886502) (xy 355.899448 -281.900194)
			(xy 355.94391 -281.921292) (xy 355.984413 -281.949248) (xy 356.019906 -281.98334) (xy 356.049471 -282.022684)
			(xy 356.072342 -282.066261) (xy 356.087926 -282.112942) (xy 356.095821 -282.161519) (xy 356.096315 -282.1861)
			(xy 356.42504 -282.1861) (xy 356.429214 -282.135728) (xy 356.441621 -282.08673) (xy 356.461923 -282.040442)
			(xy 356.489566 -281.998127) (xy 356.523797 -281.960938) (xy 356.563681 -281.92989) (xy 356.608132 -281.90583)
			(xy 356.655936 -281.889414) (xy 356.70579 -281.881089) (xy 356.731062 -281.880564) (xy 357.671116 -281.880564)
			(xy 357.696394 -281.881035) (xy 357.746259 -281.889359) (xy 357.794074 -281.905776) (xy 357.838536 -281.929839)
			(xy 357.87843 -281.960892) (xy 357.912669 -281.998088) (xy 357.940319 -282.040411) (xy 357.960627 -282.086709)
			(xy 357.973037 -282.135717) (xy 357.977212 -282.1861) (xy 357.97721 -282.186126) (xy 358.305366 -282.186126)
			(xy 358.309326 -282.137072) (xy 358.321103 -282.089288) (xy 358.340394 -282.044012) (xy 358.366697 -282.002416)
			(xy 358.399332 -281.965579) (xy 358.437453 -281.934454) (xy 358.480074 -281.909847) (xy 358.52609 -281.892395)
			(xy 358.574309 -281.882551) (xy 358.623484 -281.88057) (xy 358.672339 -281.886502) (xy 358.71961 -281.900194)
			(xy 358.764072 -281.921292) (xy 358.804575 -281.949248) (xy 358.840068 -281.98334) (xy 358.869633 -282.022684)
			(xy 358.892504 -282.066261) (xy 358.908088 -282.112942) (xy 358.915983 -282.161519) (xy 358.916478 -282.186126)
			(xy 361.118924 -282.186126) (xy 361.122884 -282.137072) (xy 361.134661 -282.089288) (xy 361.153952 -282.044012)
			(xy 361.180255 -282.002416) (xy 361.21289 -281.965579) (xy 361.251011 -281.934454) (xy 361.293632 -281.909847)
			(xy 361.339648 -281.892395) (xy 361.387867 -281.882551) (xy 361.437042 -281.88057) (xy 361.485897 -281.886502)
			(xy 361.533168 -281.900194) (xy 361.57763 -281.921292) (xy 361.618133 -281.949248) (xy 361.653626 -281.98334)
			(xy 361.683191 -282.022684) (xy 361.706062 -282.066261) (xy 361.721646 -282.112942) (xy 361.729541 -282.161519)
			(xy 361.730035 -282.1861) (xy 362.05874 -282.1861) (xy 362.062914 -282.135726) (xy 362.075322 -282.086726)
			(xy 362.095626 -282.040437) (xy 362.123271 -281.99812) (xy 362.157505 -281.960931) (xy 362.197392 -281.929883)
			(xy 362.241845 -281.905824) (xy 362.289652 -281.88941) (xy 362.339509 -281.881087) (xy 362.364782 -281.880564)
			(xy 363.304836 -281.880564) (xy 363.330113 -281.881037) (xy 363.379975 -281.889363) (xy 363.427788 -281.905782)
			(xy 363.472246 -281.929846) (xy 363.512138 -281.960899) (xy 363.546374 -281.998094) (xy 363.574022 -282.040417)
			(xy 363.594328 -282.086713) (xy 363.606737 -282.135719) (xy 363.610912 -282.1861) (xy 363.61091 -282.186126)
			(xy 363.939086 -282.186126) (xy 363.943046 -282.137072) (xy 363.954823 -282.089288) (xy 363.974114 -282.044012)
			(xy 364.000417 -282.002416) (xy 364.033052 -281.965579) (xy 364.071173 -281.934454) (xy 364.113794 -281.909847)
			(xy 364.15981 -281.892395) (xy 364.208029 -281.882551) (xy 364.257204 -281.88057) (xy 364.306059 -281.886502)
			(xy 364.35333 -281.900194) (xy 364.397792 -281.921292) (xy 364.438295 -281.949248) (xy 364.473788 -281.98334)
			(xy 364.503353 -282.022684) (xy 364.526224 -282.066261) (xy 364.541808 -282.112942) (xy 364.549703 -282.161519)
			(xy 364.550198 -282.186126) (xy 364.878886 -282.186126) (xy 364.882846 -282.137072) (xy 364.894623 -282.089288)
			(xy 364.913914 -282.044012) (xy 364.940217 -282.002416) (xy 364.972852 -281.965579) (xy 365.010973 -281.934454)
			(xy 365.053594 -281.909847) (xy 365.09961 -281.892395) (xy 365.147829 -281.882551) (xy 365.197004 -281.88057)
			(xy 365.245859 -281.886502) (xy 365.29313 -281.900194) (xy 365.337592 -281.921292) (xy 365.378095 -281.949248)
			(xy 365.413588 -281.98334) (xy 365.443153 -282.022684) (xy 365.466024 -282.066261) (xy 365.481608 -282.112942)
			(xy 365.489503 -282.161519) (xy 365.489998 -282.186126) (xy 365.81894 -282.186126) (xy 365.8229 -282.137072)
			(xy 365.834677 -282.089288) (xy 365.853968 -282.044012) (xy 365.880271 -282.002416) (xy 365.912906 -281.965579)
			(xy 365.951027 -281.934454) (xy 365.993648 -281.909847) (xy 366.039664 -281.892395) (xy 366.087883 -281.882551)
			(xy 366.137058 -281.88057) (xy 366.185913 -281.886502) (xy 366.233184 -281.900194) (xy 366.277646 -281.921292)
			(xy 366.318149 -281.949248) (xy 366.353642 -281.98334) (xy 366.383207 -282.022684) (xy 366.406078 -282.066261)
			(xy 366.421662 -282.112942) (xy 366.429557 -282.161519) (xy 366.430052 -282.186126) (xy 366.758994 -282.186126)
			(xy 366.762954 -282.137072) (xy 366.774731 -282.089288) (xy 366.794022 -282.044012) (xy 366.820325 -282.002416)
			(xy 366.85296 -281.965579) (xy 366.891081 -281.934454) (xy 366.933702 -281.909847) (xy 366.979718 -281.892395)
			(xy 367.027937 -281.882551) (xy 367.077112 -281.88057) (xy 367.125967 -281.886502) (xy 367.173238 -281.900194)
			(xy 367.2177 -281.921292) (xy 367.258203 -281.949248) (xy 367.293696 -281.98334) (xy 367.323261 -282.022684)
			(xy 367.346132 -282.066261) (xy 367.361716 -282.112942) (xy 367.369611 -282.161519) (xy 367.370106 -282.186126)
			(xy 367.699048 -282.186126) (xy 367.703008 -282.137072) (xy 367.714785 -282.089288) (xy 367.734076 -282.044012)
			(xy 367.760379 -282.002416) (xy 367.793014 -281.965579) (xy 367.831135 -281.934454) (xy 367.873756 -281.909847)
			(xy 367.919772 -281.892395) (xy 367.967991 -281.882551) (xy 368.017166 -281.88057) (xy 368.066021 -281.886502)
			(xy 368.113292 -281.900194) (xy 368.157754 -281.921292) (xy 368.198257 -281.949248) (xy 368.23375 -281.98334)
			(xy 368.263315 -282.022684) (xy 368.286186 -282.066261) (xy 368.30177 -282.112942) (xy 368.309665 -282.161519)
			(xy 368.31016 -282.186126) (xy 368.639102 -282.186126) (xy 368.643062 -282.137072) (xy 368.654839 -282.089288)
			(xy 368.67413 -282.044012) (xy 368.700433 -282.002416) (xy 368.733068 -281.965579) (xy 368.771189 -281.934454)
			(xy 368.81381 -281.909847) (xy 368.859826 -281.892395) (xy 368.908045 -281.882551) (xy 368.95722 -281.88057)
			(xy 369.006075 -281.886502) (xy 369.053346 -281.900194) (xy 369.097808 -281.921292) (xy 369.138311 -281.949248)
			(xy 369.173804 -281.98334) (xy 369.203369 -282.022684) (xy 369.22624 -282.066261) (xy 369.241824 -282.112942)
			(xy 369.249719 -282.161519) (xy 369.250214 -282.186126) (xy 369.578902 -282.186126) (xy 369.582862 -282.137072)
			(xy 369.594639 -282.089288) (xy 369.61393 -282.044012) (xy 369.640233 -282.002416) (xy 369.672868 -281.965579)
			(xy 369.710989 -281.934454) (xy 369.75361 -281.909847) (xy 369.799626 -281.892395) (xy 369.847845 -281.882551)
			(xy 369.89702 -281.88057) (xy 369.945875 -281.886502) (xy 369.993146 -281.900194) (xy 370.037608 -281.921292)
			(xy 370.078111 -281.949248) (xy 370.113604 -281.98334) (xy 370.143169 -282.022684) (xy 370.16604 -282.066261)
			(xy 370.181624 -282.112942) (xy 370.189519 -282.161519) (xy 370.190014 -282.186126) (xy 370.518956 -282.186126)
			(xy 370.522916 -282.137072) (xy 370.534693 -282.089288) (xy 370.553984 -282.044012) (xy 370.580287 -282.002416)
			(xy 370.612922 -281.965579) (xy 370.651043 -281.934454) (xy 370.693664 -281.909847) (xy 370.73968 -281.892395)
			(xy 370.787899 -281.882551) (xy 370.837074 -281.88057) (xy 370.885929 -281.886502) (xy 370.9332 -281.900194)
			(xy 370.977662 -281.921292) (xy 371.018165 -281.949248) (xy 371.053658 -281.98334) (xy 371.083223 -282.022684)
			(xy 371.106094 -282.066261) (xy 371.121678 -282.112942) (xy 371.129573 -282.161519) (xy 371.130068 -282.186126)
			(xy 371.45901 -282.186126) (xy 371.46297 -282.137072) (xy 371.474747 -282.089288) (xy 371.494038 -282.044012)
			(xy 371.520341 -282.002416) (xy 371.552976 -281.965579) (xy 371.591097 -281.934454) (xy 371.633718 -281.909847)
			(xy 371.679734 -281.892395) (xy 371.727953 -281.882551) (xy 371.777128 -281.88057) (xy 371.825983 -281.886502)
			(xy 371.873254 -281.900194) (xy 371.917716 -281.921292) (xy 371.958219 -281.949248) (xy 371.993712 -281.98334)
			(xy 372.023277 -282.022684) (xy 372.046148 -282.066261) (xy 372.061732 -282.112942) (xy 372.069627 -282.161519)
			(xy 372.070122 -282.186126) (xy 372.399064 -282.186126) (xy 372.403024 -282.137072) (xy 372.414801 -282.089288)
			(xy 372.434092 -282.044012) (xy 372.460395 -282.002416) (xy 372.49303 -281.965579) (xy 372.531151 -281.934454)
			(xy 372.573772 -281.909847) (xy 372.619788 -281.892395) (xy 372.668007 -281.882551) (xy 372.717182 -281.88057)
			(xy 372.766037 -281.886502) (xy 372.813308 -281.900194) (xy 372.85777 -281.921292) (xy 372.898273 -281.949248)
			(xy 372.933766 -281.98334) (xy 372.963331 -282.022684) (xy 372.986202 -282.066261) (xy 373.001786 -282.112942)
			(xy 373.009681 -282.161519) (xy 373.010176 -282.186126) (xy 373.339118 -282.186126) (xy 373.343078 -282.137072)
			(xy 373.354855 -282.089288) (xy 373.374146 -282.044012) (xy 373.400449 -282.002416) (xy 373.433084 -281.965579)
			(xy 373.471205 -281.934454) (xy 373.513826 -281.909847) (xy 373.559842 -281.892395) (xy 373.608061 -281.882551)
			(xy 373.657236 -281.88057) (xy 373.706091 -281.886502) (xy 373.753362 -281.900194) (xy 373.797824 -281.921292)
			(xy 373.838327 -281.949248) (xy 373.87382 -281.98334) (xy 373.903385 -282.022684) (xy 373.926256 -282.066261)
			(xy 373.94184 -282.112942) (xy 373.949735 -282.161519) (xy 373.95023 -282.186126) (xy 373.949735 -282.210733)
			(xy 373.94184 -282.25931) (xy 373.926256 -282.305991) (xy 373.903385 -282.349568) (xy 373.87382 -282.388912)
			(xy 373.838327 -282.423004) (xy 373.797824 -282.45096) (xy 373.753362 -282.472058) (xy 373.706091 -282.48575)
			(xy 373.657236 -282.491682) (xy 373.608061 -282.489701) (xy 373.559842 -282.479857) (xy 373.513826 -282.462405)
			(xy 373.471205 -282.437798) (xy 373.433084 -282.406673) (xy 373.400449 -282.369836) (xy 373.374146 -282.32824)
			(xy 373.354855 -282.282964) (xy 373.343078 -282.23518) (xy 373.339118 -282.186126) (xy 373.010176 -282.186126)
			(xy 373.009681 -282.210733) (xy 373.001786 -282.25931) (xy 372.986202 -282.305991) (xy 372.963331 -282.349568)
			(xy 372.933766 -282.388912) (xy 372.898273 -282.423004) (xy 372.85777 -282.45096) (xy 372.813308 -282.472058)
			(xy 372.766037 -282.48575) (xy 372.717182 -282.491682) (xy 372.668007 -282.489701) (xy 372.619788 -282.479857)
			(xy 372.573772 -282.462405) (xy 372.531151 -282.437798) (xy 372.49303 -282.406673) (xy 372.460395 -282.369836)
			(xy 372.434092 -282.32824) (xy 372.414801 -282.282964) (xy 372.403024 -282.23518) (xy 372.399064 -282.186126)
			(xy 372.070122 -282.186126) (xy 372.069627 -282.210733) (xy 372.061732 -282.25931) (xy 372.046148 -282.305991)
			(xy 372.023277 -282.349568) (xy 371.993712 -282.388912) (xy 371.958219 -282.423004) (xy 371.917716 -282.45096)
			(xy 371.873254 -282.472058) (xy 371.825983 -282.48575) (xy 371.777128 -282.491682) (xy 371.727953 -282.489701)
			(xy 371.679734 -282.479857) (xy 371.633718 -282.462405) (xy 371.591097 -282.437798) (xy 371.552976 -282.406673)
			(xy 371.520341 -282.369836) (xy 371.494038 -282.32824) (xy 371.474747 -282.282964) (xy 371.46297 -282.23518)
			(xy 371.45901 -282.186126) (xy 371.130068 -282.186126) (xy 371.129573 -282.210733) (xy 371.121678 -282.25931)
			(xy 371.106094 -282.305991) (xy 371.083223 -282.349568) (xy 371.053658 -282.388912) (xy 371.018165 -282.423004)
			(xy 370.977662 -282.45096) (xy 370.9332 -282.472058) (xy 370.885929 -282.48575) (xy 370.837074 -282.491682)
			(xy 370.787899 -282.489701) (xy 370.73968 -282.479857) (xy 370.693664 -282.462405) (xy 370.651043 -282.437798)
			(xy 370.612922 -282.406673) (xy 370.580287 -282.369836) (xy 370.553984 -282.32824) (xy 370.534693 -282.282964)
			(xy 370.522916 -282.23518) (xy 370.518956 -282.186126) (xy 370.190014 -282.186126) (xy 370.189519 -282.210733)
			(xy 370.181624 -282.25931) (xy 370.16604 -282.305991) (xy 370.143169 -282.349568) (xy 370.113604 -282.388912)
			(xy 370.078111 -282.423004) (xy 370.037608 -282.45096) (xy 369.993146 -282.472058) (xy 369.945875 -282.48575)
			(xy 369.89702 -282.491682) (xy 369.847845 -282.489701) (xy 369.799626 -282.479857) (xy 369.75361 -282.462405)
			(xy 369.710989 -282.437798) (xy 369.672868 -282.406673) (xy 369.640233 -282.369836) (xy 369.61393 -282.32824)
			(xy 369.594639 -282.282964) (xy 369.582862 -282.23518) (xy 369.578902 -282.186126) (xy 369.250214 -282.186126)
			(xy 369.249719 -282.210733) (xy 369.241824 -282.25931) (xy 369.22624 -282.305991) (xy 369.203369 -282.349568)
			(xy 369.173804 -282.388912) (xy 369.138311 -282.423004) (xy 369.097808 -282.45096) (xy 369.053346 -282.472058)
			(xy 369.006075 -282.48575) (xy 368.95722 -282.491682) (xy 368.908045 -282.489701) (xy 368.859826 -282.479857)
			(xy 368.81381 -282.462405) (xy 368.771189 -282.437798) (xy 368.733068 -282.406673) (xy 368.700433 -282.369836)
			(xy 368.67413 -282.32824) (xy 368.654839 -282.282964) (xy 368.643062 -282.23518) (xy 368.639102 -282.186126)
			(xy 368.31016 -282.186126) (xy 368.309665 -282.210733) (xy 368.30177 -282.25931) (xy 368.286186 -282.305991)
			(xy 368.263315 -282.349568) (xy 368.23375 -282.388912) (xy 368.198257 -282.423004) (xy 368.157754 -282.45096)
			(xy 368.113292 -282.472058) (xy 368.066021 -282.48575) (xy 368.017166 -282.491682) (xy 367.967991 -282.489701)
			(xy 367.919772 -282.479857) (xy 367.873756 -282.462405) (xy 367.831135 -282.437798) (xy 367.793014 -282.406673)
			(xy 367.760379 -282.369836) (xy 367.734076 -282.32824) (xy 367.714785 -282.282964) (xy 367.703008 -282.23518)
			(xy 367.699048 -282.186126) (xy 367.370106 -282.186126) (xy 367.369611 -282.210733) (xy 367.361716 -282.25931)
			(xy 367.346132 -282.305991) (xy 367.323261 -282.349568) (xy 367.293696 -282.388912) (xy 367.258203 -282.423004)
			(xy 367.2177 -282.45096) (xy 367.173238 -282.472058) (xy 367.125967 -282.48575) (xy 367.077112 -282.491682)
			(xy 367.027937 -282.489701) (xy 366.979718 -282.479857) (xy 366.933702 -282.462405) (xy 366.891081 -282.437798)
			(xy 366.85296 -282.406673) (xy 366.820325 -282.369836) (xy 366.794022 -282.32824) (xy 366.774731 -282.282964)
			(xy 366.762954 -282.23518) (xy 366.758994 -282.186126) (xy 366.430052 -282.186126) (xy 366.429557 -282.210733)
			(xy 366.421662 -282.25931) (xy 366.406078 -282.305991) (xy 366.383207 -282.349568) (xy 366.353642 -282.388912)
			(xy 366.318149 -282.423004) (xy 366.277646 -282.45096) (xy 366.233184 -282.472058) (xy 366.185913 -282.48575)
			(xy 366.137058 -282.491682) (xy 366.087883 -282.489701) (xy 366.039664 -282.479857) (xy 365.993648 -282.462405)
			(xy 365.951027 -282.437798) (xy 365.912906 -282.406673) (xy 365.880271 -282.369836) (xy 365.853968 -282.32824)
			(xy 365.834677 -282.282964) (xy 365.8229 -282.23518) (xy 365.81894 -282.186126) (xy 365.489998 -282.186126)
			(xy 365.489503 -282.210733) (xy 365.481608 -282.25931) (xy 365.466024 -282.305991) (xy 365.443153 -282.349568)
			(xy 365.413588 -282.388912) (xy 365.378095 -282.423004) (xy 365.337592 -282.45096) (xy 365.29313 -282.472058)
			(xy 365.245859 -282.48575) (xy 365.197004 -282.491682) (xy 365.147829 -282.489701) (xy 365.09961 -282.479857)
			(xy 365.053594 -282.462405) (xy 365.010973 -282.437798) (xy 364.972852 -282.406673) (xy 364.940217 -282.369836)
			(xy 364.913914 -282.32824) (xy 364.894623 -282.282964) (xy 364.882846 -282.23518) (xy 364.878886 -282.186126)
			(xy 364.550198 -282.186126) (xy 364.549703 -282.210733) (xy 364.541808 -282.25931) (xy 364.526224 -282.305991)
			(xy 364.503353 -282.349568) (xy 364.473788 -282.388912) (xy 364.438295 -282.423004) (xy 364.397792 -282.45096)
			(xy 364.35333 -282.472058) (xy 364.306059 -282.48575) (xy 364.257204 -282.491682) (xy 364.208029 -282.489701)
			(xy 364.15981 -282.479857) (xy 364.113794 -282.462405) (xy 364.071173 -282.437798) (xy 364.033052 -282.406673)
			(xy 364.000417 -282.369836) (xy 363.974114 -282.32824) (xy 363.954823 -282.282964) (xy 363.943046 -282.23518)
			(xy 363.939086 -282.186126) (xy 363.61091 -282.186126) (xy 363.606737 -282.236481) (xy 363.594328 -282.285487)
			(xy 363.574022 -282.331783) (xy 363.546374 -282.374106) (xy 363.512138 -282.411301) (xy 363.472246 -282.442354)
			(xy 363.427788 -282.466418) (xy 363.379975 -282.482837) (xy 363.330113 -282.491163) (xy 363.304836 -282.491688)
			(xy 362.364782 -282.491688) (xy 362.339509 -282.491113) (xy 362.289652 -282.48279) (xy 362.241845 -282.466376)
			(xy 362.197392 -282.442317) (xy 362.157505 -282.411269) (xy 362.123271 -282.37408) (xy 362.095626 -282.331763)
			(xy 362.075322 -282.285474) (xy 362.062914 -282.236474) (xy 362.05874 -282.1861) (xy 361.730035 -282.1861)
			(xy 361.730036 -282.186126) (xy 361.729541 -282.210733) (xy 361.721646 -282.25931) (xy 361.706062 -282.305991)
			(xy 361.683191 -282.349568) (xy 361.653626 -282.388912) (xy 361.618133 -282.423004) (xy 361.57763 -282.45096)
			(xy 361.533168 -282.472058) (xy 361.485897 -282.48575) (xy 361.437042 -282.491682) (xy 361.387867 -282.489701)
			(xy 361.339648 -282.479857) (xy 361.293632 -282.462405) (xy 361.251011 -282.437798) (xy 361.21289 -282.406673)
			(xy 361.180255 -282.369836) (xy 361.153952 -282.32824) (xy 361.134661 -282.282964) (xy 361.122884 -282.23518)
			(xy 361.118924 -282.186126) (xy 358.916478 -282.186126) (xy 358.915983 -282.210733) (xy 358.908088 -282.25931)
			(xy 358.892504 -282.305991) (xy 358.869633 -282.349568) (xy 358.840068 -282.388912) (xy 358.804575 -282.423004)
			(xy 358.764072 -282.45096) (xy 358.71961 -282.472058) (xy 358.672339 -282.48575) (xy 358.623484 -282.491682)
			(xy 358.574309 -282.489701) (xy 358.52609 -282.479857) (xy 358.480074 -282.462405) (xy 358.437453 -282.437798)
			(xy 358.399332 -282.406673) (xy 358.366697 -282.369836) (xy 358.340394 -282.32824) (xy 358.321103 -282.282964)
			(xy 358.309326 -282.23518) (xy 358.305366 -282.186126) (xy 357.97721 -282.186126) (xy 357.973037 -282.236483)
			(xy 357.960627 -282.285491) (xy 357.940319 -282.331789) (xy 357.912669 -282.374112) (xy 357.87843 -282.411308)
			(xy 357.838536 -282.442361) (xy 357.794074 -282.466424) (xy 357.746259 -282.482841) (xy 357.696394 -282.491165)
			(xy 357.671116 -282.491688) (xy 356.731062 -282.491688) (xy 356.70579 -282.491111) (xy 356.655936 -282.482786)
			(xy 356.608132 -282.46637) (xy 356.563681 -282.44231) (xy 356.523797 -282.411262) (xy 356.489566 -282.374073)
			(xy 356.461923 -282.331758) (xy 356.441621 -282.28547) (xy 356.429214 -282.236472) (xy 356.42504 -282.1861)
			(xy 356.096315 -282.1861) (xy 356.096316 -282.186126) (xy 356.095821 -282.210733) (xy 356.087926 -282.25931)
			(xy 356.072342 -282.305991) (xy 356.049471 -282.349568) (xy 356.019906 -282.388912) (xy 355.984413 -282.423004)
			(xy 355.94391 -282.45096) (xy 355.899448 -282.472058) (xy 355.852177 -282.48575) (xy 355.803322 -282.491682)
			(xy 355.754147 -282.489701) (xy 355.705928 -282.479857) (xy 355.659912 -282.462405) (xy 355.617291 -282.437798)
			(xy 355.57917 -282.406673) (xy 355.546535 -282.369836) (xy 355.520232 -282.32824) (xy 355.500941 -282.282964)
			(xy 355.489164 -282.23518) (xy 355.485204 -282.186126) (xy 355.156516 -282.186126) (xy 355.156021 -282.210733)
			(xy 355.148126 -282.25931) (xy 355.132542 -282.305991) (xy 355.109671 -282.349568) (xy 355.080106 -282.388912)
			(xy 355.044613 -282.423004) (xy 355.00411 -282.45096) (xy 354.959648 -282.472058) (xy 354.912377 -282.48575)
			(xy 354.863522 -282.491682) (xy 354.814347 -282.489701) (xy 354.766128 -282.479857) (xy 354.720112 -282.462405)
			(xy 354.677491 -282.437798) (xy 354.63937 -282.406673) (xy 354.606735 -282.369836) (xy 354.580432 -282.32824)
			(xy 354.561141 -282.282964) (xy 354.549364 -282.23518) (xy 354.545404 -282.186126) (xy 354.216462 -282.186126)
			(xy 354.215967 -282.210733) (xy 354.208072 -282.25931) (xy 354.192488 -282.305991) (xy 354.169617 -282.349568)
			(xy 354.140052 -282.388912) (xy 354.104559 -282.423004) (xy 354.064056 -282.45096) (xy 354.019594 -282.472058)
			(xy 353.972323 -282.48575) (xy 353.923468 -282.491682) (xy 353.874293 -282.489701) (xy 353.826074 -282.479857)
			(xy 353.780058 -282.462405) (xy 353.737437 -282.437798) (xy 353.699316 -282.406673) (xy 353.666681 -282.369836)
			(xy 353.640378 -282.32824) (xy 353.621087 -282.282964) (xy 353.60931 -282.23518) (xy 353.60535 -282.186126)
			(xy 353.276408 -282.186126) (xy 353.275913 -282.210733) (xy 353.268018 -282.25931) (xy 353.252434 -282.305991)
			(xy 353.229563 -282.349568) (xy 353.199998 -282.388912) (xy 353.164505 -282.423004) (xy 353.124002 -282.45096)
			(xy 353.07954 -282.472058) (xy 353.032269 -282.48575) (xy 352.983414 -282.491682) (xy 352.934239 -282.489701)
			(xy 352.88602 -282.479857) (xy 352.840004 -282.462405) (xy 352.797383 -282.437798) (xy 352.759262 -282.406673)
			(xy 352.726627 -282.369836) (xy 352.700324 -282.32824) (xy 352.681033 -282.282964) (xy 352.669256 -282.23518)
			(xy 352.665296 -282.186126) (xy 352.336354 -282.186126) (xy 352.335859 -282.210733) (xy 352.327964 -282.25931)
			(xy 352.31238 -282.305991) (xy 352.289509 -282.349568) (xy 352.259944 -282.388912) (xy 352.224451 -282.423004)
			(xy 352.183948 -282.45096) (xy 352.139486 -282.472058) (xy 352.092215 -282.48575) (xy 352.04336 -282.491682)
			(xy 351.994185 -282.489701) (xy 351.945966 -282.479857) (xy 351.89995 -282.462405) (xy 351.857329 -282.437798)
			(xy 351.819208 -282.406673) (xy 351.786573 -282.369836) (xy 351.76027 -282.32824) (xy 351.740979 -282.282964)
			(xy 351.729202 -282.23518) (xy 351.725242 -282.186126) (xy 351.396554 -282.186126) (xy 351.396059 -282.210733)
			(xy 351.388164 -282.25931) (xy 351.37258 -282.305991) (xy 351.349709 -282.349568) (xy 351.320144 -282.388912)
			(xy 351.284651 -282.423004) (xy 351.244148 -282.45096) (xy 351.199686 -282.472058) (xy 351.152415 -282.48575)
			(xy 351.10356 -282.491682) (xy 351.054385 -282.489701) (xy 351.006166 -282.479857) (xy 350.96015 -282.462405)
			(xy 350.917529 -282.437798) (xy 350.879408 -282.406673) (xy 350.846773 -282.369836) (xy 350.82047 -282.32824)
			(xy 350.801179 -282.282964) (xy 350.789402 -282.23518) (xy 350.785442 -282.186126) (xy 350.4565 -282.186126)
			(xy 350.456005 -282.210733) (xy 350.44811 -282.25931) (xy 350.432526 -282.305991) (xy 350.409655 -282.349568)
			(xy 350.38009 -282.388912) (xy 350.344597 -282.423004) (xy 350.304094 -282.45096) (xy 350.259632 -282.472058)
			(xy 350.212361 -282.48575) (xy 350.163506 -282.491682) (xy 350.114331 -282.489701) (xy 350.066112 -282.479857)
			(xy 350.020096 -282.462405) (xy 349.977475 -282.437798) (xy 349.939354 -282.406673) (xy 349.906719 -282.369836)
			(xy 349.880416 -282.32824) (xy 349.861125 -282.282964) (xy 349.849348 -282.23518) (xy 349.845388 -282.186126)
			(xy 349.516446 -282.186126) (xy 349.515951 -282.210733) (xy 349.508056 -282.25931) (xy 349.492472 -282.305991)
			(xy 349.469601 -282.349568) (xy 349.440036 -282.388912) (xy 349.404543 -282.423004) (xy 349.36404 -282.45096)
			(xy 349.319578 -282.472058) (xy 349.272307 -282.48575) (xy 349.223452 -282.491682) (xy 349.174277 -282.489701)
			(xy 349.126058 -282.479857) (xy 349.080042 -282.462405) (xy 349.037421 -282.437798) (xy 348.9993 -282.406673)
			(xy 348.966665 -282.369836) (xy 348.940362 -282.32824) (xy 348.921071 -282.282964) (xy 348.909294 -282.23518)
			(xy 348.905334 -282.186126) (xy 348.576392 -282.186126) (xy 348.575897 -282.210733) (xy 348.568002 -282.25931)
			(xy 348.552418 -282.305991) (xy 348.529547 -282.349568) (xy 348.499982 -282.388912) (xy 348.464489 -282.423004)
			(xy 348.423986 -282.45096) (xy 348.379524 -282.472058) (xy 348.332253 -282.48575) (xy 348.283398 -282.491682)
			(xy 348.234223 -282.489701) (xy 348.186004 -282.479857) (xy 348.139988 -282.462405) (xy 348.097367 -282.437798)
			(xy 348.059246 -282.406673) (xy 348.026611 -282.369836) (xy 348.000308 -282.32824) (xy 347.981017 -282.282964)
			(xy 347.96924 -282.23518) (xy 347.96528 -282.186126) (xy 347.636338 -282.186126) (xy 347.635843 -282.210733)
			(xy 347.627948 -282.25931) (xy 347.612364 -282.305991) (xy 347.589493 -282.349568) (xy 347.559928 -282.388912)
			(xy 347.524435 -282.423004) (xy 347.483932 -282.45096) (xy 347.43947 -282.472058) (xy 347.392199 -282.48575)
			(xy 347.343344 -282.491682) (xy 347.294169 -282.489701) (xy 347.24595 -282.479857) (xy 347.199934 -282.462405)
			(xy 347.157313 -282.437798) (xy 347.119192 -282.406673) (xy 347.086557 -282.369836) (xy 347.060254 -282.32824)
			(xy 347.040963 -282.282964) (xy 347.029186 -282.23518) (xy 347.025226 -282.186126) (xy 346.696538 -282.186126)
			(xy 346.696043 -282.210733) (xy 346.688148 -282.25931) (xy 346.672564 -282.305991) (xy 346.649693 -282.349568)
			(xy 346.620128 -282.388912) (xy 346.584635 -282.423004) (xy 346.544132 -282.45096) (xy 346.49967 -282.472058)
			(xy 346.452399 -282.48575) (xy 346.403544 -282.491682) (xy 346.354369 -282.489701) (xy 346.30615 -282.479857)
			(xy 346.260134 -282.462405) (xy 346.217513 -282.437798) (xy 346.179392 -282.406673) (xy 346.146757 -282.369836)
			(xy 346.120454 -282.32824) (xy 346.101163 -282.282964) (xy 346.089386 -282.23518) (xy 346.085426 -282.186126)
			(xy 345.756484 -282.186126) (xy 345.755989 -282.210733) (xy 345.748094 -282.25931) (xy 345.73251 -282.305991)
			(xy 345.709639 -282.349568) (xy 345.680074 -282.388912) (xy 345.644581 -282.423004) (xy 345.604078 -282.45096)
			(xy 345.559616 -282.472058) (xy 345.512345 -282.48575) (xy 345.46349 -282.491682) (xy 345.414315 -282.489701)
			(xy 345.366096 -282.479857) (xy 345.32008 -282.462405) (xy 345.277459 -282.437798) (xy 345.239338 -282.406673)
			(xy 345.206703 -282.369836) (xy 345.1804 -282.32824) (xy 345.161109 -282.282964) (xy 345.149332 -282.23518)
			(xy 345.145372 -282.186126) (xy 344.880692 -282.186126) (xy 344.880692 -282.59024) (xy 344.881156 -282.600115)
			(xy 344.888604 -282.618409) (xy 344.89517 -282.6258) (xy 344.895424 -282.626054) (xy 344.945208 -282.675838)
			(xy 344.952604 -282.68269) (xy 344.971203 -282.690431) (xy 344.981276 -282.690824) (xy 345.006514 -282.691367)
			(xy 345.056295 -282.699715) (xy 345.104025 -282.716139) (xy 345.148402 -282.740191) (xy 345.188219 -282.771215)
			(xy 345.22239 -282.808366) (xy 345.249984 -282.850633) (xy 345.270249 -282.896862) (xy 345.282633 -282.945796)
			(xy 345.286799 -282.9961) (xy 345.615301 -282.9961) (xy 345.619471 -282.94577) (xy 345.631868 -282.896812)
			(xy 345.652154 -282.850562) (xy 345.679775 -282.808282) (xy 345.713979 -282.771125) (xy 345.753831 -282.740104)
			(xy 345.798246 -282.716065) (xy 345.846011 -282.699663) (xy 345.895825 -282.691347) (xy 345.921076 -282.690824)
			(xy 346.86113 -282.690824) (xy 346.886386 -282.691284) (xy 346.936209 -282.699603) (xy 346.983984 -282.716008)
			(xy 347.028407 -282.740052) (xy 347.068267 -282.77108) (xy 347.102477 -282.808245) (xy 347.130103 -282.850534)
			(xy 347.150393 -282.896792) (xy 347.162792 -282.94576) (xy 347.166963 -282.9961) (xy 347.16696 -282.996132)
			(xy 347.49538 -282.996132) (xy 347.49934 -282.947078) (xy 347.511117 -282.899294) (xy 347.530408 -282.854018)
			(xy 347.556711 -282.812422) (xy 347.589346 -282.775585) (xy 347.627467 -282.74446) (xy 347.670088 -282.719853)
			(xy 347.716104 -282.702401) (xy 347.764323 -282.692557) (xy 347.813498 -282.690576) (xy 347.862353 -282.696508)
			(xy 347.909624 -282.7102) (xy 347.954086 -282.731298) (xy 347.994589 -282.759254) (xy 348.030082 -282.793346)
			(xy 348.059647 -282.83269) (xy 348.082518 -282.876267) (xy 348.098102 -282.922948) (xy 348.105997 -282.971525)
			(xy 348.106491 -282.9961) (xy 348.435372 -282.9961) (xy 348.439544 -282.945758) (xy 348.451945 -282.89679)
			(xy 348.472238 -282.850531) (xy 348.499869 -282.808244) (xy 348.534083 -282.771081) (xy 348.573948 -282.740058)
			(xy 348.618376 -282.71602) (xy 348.666155 -282.699622) (xy 348.715981 -282.691314) (xy 348.741238 -282.690824)
			(xy 349.681292 -282.690824) (xy 349.706553 -282.691252) (xy 349.756386 -282.699567) (xy 349.80417 -282.71597)
			(xy 349.848603 -282.740015) (xy 349.888472 -282.771045) (xy 349.92269 -282.808215) (xy 349.950323 -282.850509)
			(xy 349.970617 -282.896775) (xy 349.98302 -282.945751) (xy 349.987192 -282.9961) (xy 349.987189 -282.996132)
			(xy 350.315288 -282.996132) (xy 350.319248 -282.947078) (xy 350.331025 -282.899294) (xy 350.350316 -282.854018)
			(xy 350.376619 -282.812422) (xy 350.409254 -282.775585) (xy 350.447375 -282.74446) (xy 350.489996 -282.719853)
			(xy 350.536012 -282.702401) (xy 350.584231 -282.692557) (xy 350.633406 -282.690576) (xy 350.682261 -282.696508)
			(xy 350.729532 -282.7102) (xy 350.773994 -282.731298) (xy 350.814497 -282.759254) (xy 350.84999 -282.793346)
			(xy 350.879555 -282.83269) (xy 350.902426 -282.876267) (xy 350.91801 -282.922948) (xy 350.925905 -282.971525)
			(xy 350.926399 -282.9961) (xy 351.255272 -282.9961) (xy 351.259444 -282.945758) (xy 351.271846 -282.896789)
			(xy 351.292139 -282.850529) (xy 351.319771 -282.808241) (xy 351.353986 -282.771079) (xy 351.393852 -282.740055)
			(xy 351.438281 -282.716017) (xy 351.486061 -282.699621) (xy 351.535888 -282.691313) (xy 351.561146 -282.690824)
			(xy 352.5012 -282.690824) (xy 352.526458 -282.691282) (xy 352.576285 -282.699596) (xy 352.624064 -282.715999)
			(xy 352.668491 -282.740042) (xy 352.708355 -282.771069) (xy 352.742569 -282.808235) (xy 352.770198 -282.850525)
			(xy 352.79049 -282.896786) (xy 352.802891 -282.945757) (xy 352.807063 -282.9961) (xy 352.80706 -282.996132)
			(xy 353.135196 -282.996132) (xy 353.139156 -282.947078) (xy 353.150933 -282.899294) (xy 353.170224 -282.854018)
			(xy 353.196527 -282.812422) (xy 353.229162 -282.775585) (xy 353.267283 -282.74446) (xy 353.309904 -282.719853)
			(xy 353.35592 -282.702401) (xy 353.404139 -282.692557) (xy 353.453314 -282.690576) (xy 353.502169 -282.696508)
			(xy 353.54944 -282.7102) (xy 353.593902 -282.731298) (xy 353.634405 -282.759254) (xy 353.669898 -282.793346)
			(xy 353.699463 -282.83269) (xy 353.722334 -282.876267) (xy 353.737918 -282.922948) (xy 353.745813 -282.971525)
			(xy 353.746307 -282.9961) (xy 354.075301 -282.9961) (xy 354.079471 -282.945772) (xy 354.091867 -282.896816)
			(xy 354.112151 -282.850569) (xy 354.13977 -282.80829) (xy 354.17397 -282.771133) (xy 354.213819 -282.740111)
			(xy 354.258231 -282.716071) (xy 354.305993 -282.699668) (xy 354.355804 -282.691349) (xy 354.381054 -282.690824)
			(xy 355.321108 -282.690824) (xy 355.346366 -282.691282) (xy 355.396191 -282.699598) (xy 355.443969 -282.716001)
			(xy 355.488395 -282.740045) (xy 355.528258 -282.771072) (xy 355.562471 -282.808238) (xy 355.5901 -282.850528)
			(xy 355.610391 -282.896788) (xy 355.622792 -282.945757) (xy 355.626963 -282.9961) (xy 355.62696 -282.996132)
			(xy 355.955358 -282.996132) (xy 355.959318 -282.947078) (xy 355.971095 -282.899294) (xy 355.990386 -282.854018)
			(xy 356.016689 -282.812422) (xy 356.049324 -282.775585) (xy 356.087445 -282.74446) (xy 356.130066 -282.719853)
			(xy 356.176082 -282.702401) (xy 356.224301 -282.692557) (xy 356.273476 -282.690576) (xy 356.322331 -282.696508)
			(xy 356.369602 -282.7102) (xy 356.414064 -282.731298) (xy 356.454567 -282.759254) (xy 356.49006 -282.793346)
			(xy 356.519625 -282.83269) (xy 356.542496 -282.876267) (xy 356.55808 -282.922948) (xy 356.565975 -282.971525)
			(xy 356.56647 -282.996132) (xy 363.468932 -282.996132) (xy 363.472892 -282.947078) (xy 363.484669 -282.899294)
			(xy 363.50396 -282.854018) (xy 363.530263 -282.812422) (xy 363.562898 -282.775585) (xy 363.601019 -282.74446)
			(xy 363.64364 -282.719853) (xy 363.689656 -282.702401) (xy 363.737875 -282.692557) (xy 363.78705 -282.690576)
			(xy 363.835905 -282.696508) (xy 363.883176 -282.7102) (xy 363.927638 -282.731298) (xy 363.968141 -282.759254)
			(xy 364.003634 -282.793346) (xy 364.033199 -282.83269) (xy 364.05607 -282.876267) (xy 364.071654 -282.922948)
			(xy 364.079549 -282.971525) (xy 364.080043 -282.9961) (xy 364.409001 -282.9961) (xy 364.413172 -282.945768)
			(xy 364.425569 -282.896809) (xy 364.445856 -282.850559) (xy 364.473479 -282.808278) (xy 364.507684 -282.77112)
			(xy 364.547539 -282.740099) (xy 364.591955 -282.71606) (xy 364.639723 -282.69966) (xy 364.689538 -282.691346)
			(xy 364.71479 -282.690824) (xy 365.654844 -282.690824) (xy 365.6801 -282.691285) (xy 365.729921 -282.699605)
			(xy 365.777694 -282.716012) (xy 365.822115 -282.740057) (xy 365.861972 -282.771085) (xy 365.89618 -282.80825)
			(xy 365.923805 -282.850538) (xy 365.944094 -282.896795) (xy 365.956492 -282.945761) (xy 365.960663 -282.9961)
			(xy 365.96066 -282.996132) (xy 366.289094 -282.996132) (xy 366.293054 -282.947078) (xy 366.304831 -282.899294)
			(xy 366.324122 -282.854018) (xy 366.350425 -282.812422) (xy 366.38306 -282.775585) (xy 366.421181 -282.74446)
			(xy 366.463802 -282.719853) (xy 366.509818 -282.702401) (xy 366.558037 -282.692557) (xy 366.607212 -282.690576)
			(xy 366.656067 -282.696508) (xy 366.703338 -282.7102) (xy 366.7478 -282.731298) (xy 366.788303 -282.759254)
			(xy 366.823796 -282.793346) (xy 366.853361 -282.83269) (xy 366.876232 -282.876267) (xy 366.891816 -282.922948)
			(xy 366.899711 -282.971525) (xy 366.900205 -282.9961) (xy 367.228901 -282.9961) (xy 367.233072 -282.945767)
			(xy 367.24547 -282.896808) (xy 367.265758 -282.850556) (xy 367.293381 -282.808275) (xy 367.327587 -282.771117)
			(xy 367.367443 -282.740096) (xy 367.411861 -282.716058) (xy 367.459629 -282.699659) (xy 367.509445 -282.691346)
			(xy 367.534698 -282.690824) (xy 368.474752 -282.690824) (xy 368.500015 -282.691249) (xy 368.549853 -282.699558)
			(xy 368.597643 -282.715958) (xy 368.642082 -282.740001) (xy 368.681956 -282.771031) (xy 368.716179 -282.808201)
			(xy 368.743817 -282.850498) (xy 368.764115 -282.896767) (xy 368.776519 -282.945747) (xy 368.780692 -282.9961)
			(xy 368.780689 -282.996132) (xy 369.109002 -282.996132) (xy 369.112962 -282.947078) (xy 369.124739 -282.899294)
			(xy 369.14403 -282.854018) (xy 369.170333 -282.812422) (xy 369.202968 -282.775585) (xy 369.241089 -282.74446)
			(xy 369.28371 -282.719853) (xy 369.329726 -282.702401) (xy 369.377945 -282.692557) (xy 369.42712 -282.690576)
			(xy 369.475975 -282.696508) (xy 369.523246 -282.7102) (xy 369.567708 -282.731298) (xy 369.608211 -282.759254)
			(xy 369.643704 -282.793346) (xy 369.673269 -282.83269) (xy 369.69614 -282.876267) (xy 369.711724 -282.922948)
			(xy 369.719619 -282.971525) (xy 369.720113 -282.9961) (xy 370.049101 -282.9961) (xy 370.053271 -282.945771)
			(xy 370.065667 -282.896815) (xy 370.085952 -282.850567) (xy 370.113571 -282.808288) (xy 370.147772 -282.771131)
			(xy 370.187623 -282.740109) (xy 370.232035 -282.716069) (xy 370.279798 -282.699667) (xy 370.329609 -282.691349)
			(xy 370.35486 -282.690824) (xy 371.294914 -282.690824) (xy 371.320171 -282.691283) (xy 371.369996 -282.699599)
			(xy 371.417773 -282.716003) (xy 371.462199 -282.740047) (xy 371.502061 -282.771074) (xy 371.536273 -282.80824)
			(xy 371.563901 -282.850529) (xy 371.584191 -282.896789) (xy 371.596592 -282.945758) (xy 371.600763 -282.9961)
			(xy 371.60076 -282.996132) (xy 371.92891 -282.996132) (xy 371.93287 -282.947078) (xy 371.944647 -282.899294)
			(xy 371.963938 -282.854018) (xy 371.990241 -282.812422) (xy 372.022876 -282.775585) (xy 372.060997 -282.74446)
			(xy 372.103618 -282.719853) (xy 372.149634 -282.702401) (xy 372.197853 -282.692557) (xy 372.247028 -282.690576)
			(xy 372.295883 -282.696508) (xy 372.343154 -282.7102) (xy 372.387616 -282.731298) (xy 372.428119 -282.759254)
			(xy 372.463612 -282.793346) (xy 372.493177 -282.83269) (xy 372.516048 -282.876267) (xy 372.531632 -282.922948)
			(xy 372.539527 -282.971525) (xy 372.540022 -282.996132) (xy 372.539527 -283.020739) (xy 372.531632 -283.069316)
			(xy 372.516048 -283.115997) (xy 372.493177 -283.159574) (xy 372.463612 -283.198918) (xy 372.428119 -283.23301)
			(xy 372.387616 -283.260966) (xy 372.343154 -283.282064) (xy 372.295883 -283.295756) (xy 372.247028 -283.301688)
			(xy 372.197853 -283.299707) (xy 372.149634 -283.289863) (xy 372.103618 -283.272411) (xy 372.060997 -283.247804)
			(xy 372.022876 -283.216679) (xy 371.990241 -283.179842) (xy 371.963938 -283.138246) (xy 371.944647 -283.09297)
			(xy 371.93287 -283.045186) (xy 371.92891 -282.996132) (xy 371.60076 -282.996132) (xy 371.596592 -283.046442)
			(xy 371.584191 -283.095411) (xy 371.563901 -283.141671) (xy 371.536273 -283.18396) (xy 371.502061 -283.221126)
			(xy 371.462199 -283.252153) (xy 371.417773 -283.276197) (xy 371.369996 -283.292601) (xy 371.320171 -283.300917)
			(xy 371.294914 -283.30144) (xy 370.35486 -283.30144) (xy 370.329609 -283.300851) (xy 370.279798 -283.292533)
			(xy 370.232035 -283.276131) (xy 370.187623 -283.252091) (xy 370.147772 -283.221069) (xy 370.113571 -283.183912)
			(xy 370.085952 -283.141633) (xy 370.065667 -283.095385) (xy 370.053271 -283.046429) (xy 370.049101 -282.9961)
			(xy 369.720113 -282.9961) (xy 369.720114 -282.996132) (xy 369.719619 -283.020739) (xy 369.711724 -283.069316)
			(xy 369.69614 -283.115997) (xy 369.673269 -283.159574) (xy 369.643704 -283.198918) (xy 369.608211 -283.23301)
			(xy 369.567708 -283.260966) (xy 369.523246 -283.282064) (xy 369.475975 -283.295756) (xy 369.42712 -283.301688)
			(xy 369.377945 -283.299707) (xy 369.329726 -283.289863) (xy 369.28371 -283.272411) (xy 369.241089 -283.247804)
			(xy 369.202968 -283.216679) (xy 369.170333 -283.179842) (xy 369.14403 -283.138246) (xy 369.124739 -283.09297)
			(xy 369.112962 -283.045186) (xy 369.109002 -282.996132) (xy 368.780689 -282.996132) (xy 368.776519 -283.046453)
			(xy 368.764115 -283.095433) (xy 368.743817 -283.141702) (xy 368.716179 -283.183999) (xy 368.681956 -283.221169)
			(xy 368.642082 -283.252199) (xy 368.597643 -283.276242) (xy 368.549853 -283.292642) (xy 368.500015 -283.300951)
			(xy 368.474752 -283.30144) (xy 367.534698 -283.30144) (xy 367.509445 -283.300854) (xy 367.459629 -283.292541)
			(xy 367.411861 -283.276142) (xy 367.367443 -283.252104) (xy 367.327587 -283.221083) (xy 367.293381 -283.183925)
			(xy 367.265758 -283.141644) (xy 367.24547 -283.095392) (xy 367.233072 -283.046433) (xy 367.228901 -282.9961)
			(xy 366.900205 -282.9961) (xy 366.900206 -282.996132) (xy 366.899711 -283.020739) (xy 366.891816 -283.069316)
			(xy 366.876232 -283.115997) (xy 366.853361 -283.159574) (xy 366.823796 -283.198918) (xy 366.788303 -283.23301)
			(xy 366.7478 -283.260966) (xy 366.703338 -283.282064) (xy 366.656067 -283.295756) (xy 366.607212 -283.301688)
			(xy 366.558037 -283.299707) (xy 366.509818 -283.289863) (xy 366.463802 -283.272411) (xy 366.421181 -283.247804)
			(xy 366.38306 -283.216679) (xy 366.350425 -283.179842) (xy 366.324122 -283.138246) (xy 366.304831 -283.09297)
			(xy 366.293054 -283.045186) (xy 366.289094 -282.996132) (xy 365.96066 -282.996132) (xy 365.956492 -283.046439)
			(xy 365.944094 -283.095405) (xy 365.923805 -283.141662) (xy 365.89618 -283.18395) (xy 365.861972 -283.221115)
			(xy 365.822115 -283.252143) (xy 365.777694 -283.276188) (xy 365.729921 -283.292595) (xy 365.6801 -283.300915)
			(xy 365.654844 -283.30144) (xy 364.71479 -283.30144) (xy 364.689538 -283.300854) (xy 364.639723 -283.29254)
			(xy 364.591955 -283.27614) (xy 364.547539 -283.252101) (xy 364.507684 -283.22108) (xy 364.473479 -283.183922)
			(xy 364.445856 -283.141641) (xy 364.425569 -283.095391) (xy 364.413172 -283.046432) (xy 364.409001 -282.9961)
			(xy 364.080043 -282.9961) (xy 364.080044 -282.996132) (xy 364.079549 -283.020739) (xy 364.071654 -283.069316)
			(xy 364.05607 -283.115997) (xy 364.033199 -283.159574) (xy 364.003634 -283.198918) (xy 363.968141 -283.23301)
			(xy 363.927638 -283.260966) (xy 363.883176 -283.282064) (xy 363.835905 -283.295756) (xy 363.78705 -283.301688)
			(xy 363.737875 -283.299707) (xy 363.689656 -283.289863) (xy 363.64364 -283.272411) (xy 363.601019 -283.247804)
			(xy 363.562898 -283.216679) (xy 363.530263 -283.179842) (xy 363.50396 -283.138246) (xy 363.484669 -283.09297)
			(xy 363.472892 -283.045186) (xy 363.468932 -282.996132) (xy 356.56647 -282.996132) (xy 356.565975 -283.020739)
			(xy 356.55808 -283.069316) (xy 356.542496 -283.115997) (xy 356.519625 -283.159574) (xy 356.49006 -283.198918)
			(xy 356.454567 -283.23301) (xy 356.414064 -283.260966) (xy 356.369602 -283.282064) (xy 356.322331 -283.295756)
			(xy 356.273476 -283.301688) (xy 356.224301 -283.299707) (xy 356.176082 -283.289863) (xy 356.130066 -283.272411)
			(xy 356.087445 -283.247804) (xy 356.049324 -283.216679) (xy 356.016689 -283.179842) (xy 355.990386 -283.138246)
			(xy 355.971095 -283.09297) (xy 355.959318 -283.045186) (xy 355.955358 -282.996132) (xy 355.62696 -282.996132)
			(xy 355.622792 -283.046443) (xy 355.610391 -283.095412) (xy 355.5901 -283.141672) (xy 355.562471 -283.183962)
			(xy 355.528258 -283.221128) (xy 355.488395 -283.252155) (xy 355.443969 -283.276199) (xy 355.396191 -283.292602)
			(xy 355.346366 -283.300918) (xy 355.321108 -283.30144) (xy 354.381054 -283.30144) (xy 354.355804 -283.300851)
			(xy 354.305993 -283.292532) (xy 354.258231 -283.276129) (xy 354.213819 -283.252089) (xy 354.17397 -283.221067)
			(xy 354.13977 -283.18391) (xy 354.112151 -283.141631) (xy 354.091867 -283.095384) (xy 354.079471 -283.046428)
			(xy 354.075301 -282.9961) (xy 353.746307 -282.9961) (xy 353.746308 -282.996132) (xy 353.745813 -283.020739)
			(xy 353.737918 -283.069316) (xy 353.722334 -283.115997) (xy 353.699463 -283.159574) (xy 353.669898 -283.198918)
			(xy 353.634405 -283.23301) (xy 353.593902 -283.260966) (xy 353.54944 -283.282064) (xy 353.502169 -283.295756)
			(xy 353.453314 -283.301688) (xy 353.404139 -283.299707) (xy 353.35592 -283.289863) (xy 353.309904 -283.272411)
			(xy 353.267283 -283.247804) (xy 353.229162 -283.216679) (xy 353.196527 -283.179842) (xy 353.170224 -283.138246)
			(xy 353.150933 -283.09297) (xy 353.139156 -283.045186) (xy 353.135196 -282.996132) (xy 352.80706 -282.996132)
			(xy 352.802891 -283.046443) (xy 352.79049 -283.095414) (xy 352.770198 -283.141675) (xy 352.742569 -283.183965)
			(xy 352.708355 -283.221131) (xy 352.668491 -283.252158) (xy 352.624064 -283.276201) (xy 352.576285 -283.292604)
			(xy 352.526458 -283.300918) (xy 352.5012 -283.30144) (xy 351.561146 -283.30144) (xy 351.535888 -283.300887)
			(xy 351.486061 -283.292579) (xy 351.438281 -283.276183) (xy 351.393852 -283.252145) (xy 351.353986 -283.221121)
			(xy 351.319771 -283.183959) (xy 351.292139 -283.141671) (xy 351.271846 -283.095411) (xy 351.259444 -283.046442)
			(xy 351.255272 -282.9961) (xy 350.926399 -282.9961) (xy 350.9264 -282.996132) (xy 350.925905 -283.020739)
			(xy 350.91801 -283.069316) (xy 350.902426 -283.115997) (xy 350.879555 -283.159574) (xy 350.84999 -283.198918)
			(xy 350.814497 -283.23301) (xy 350.773994 -283.260966) (xy 350.729532 -283.282064) (xy 350.682261 -283.295756)
			(xy 350.633406 -283.301688) (xy 350.584231 -283.299707) (xy 350.536012 -283.289863) (xy 350.489996 -283.272411)
			(xy 350.447375 -283.247804) (xy 350.409254 -283.216679) (xy 350.376619 -283.179842) (xy 350.350316 -283.138246)
			(xy 350.331025 -283.09297) (xy 350.319248 -283.045186) (xy 350.315288 -282.996132) (xy 349.987189 -282.996132)
			(xy 349.98302 -283.046449) (xy 349.970617 -283.095425) (xy 349.950323 -283.141691) (xy 349.92269 -283.183985)
			(xy 349.888472 -283.221155) (xy 349.848603 -283.252185) (xy 349.80417 -283.27623) (xy 349.756386 -283.292633)
			(xy 349.706553 -283.300948) (xy 349.681292 -283.30144) (xy 348.741238 -283.30144) (xy 348.715981 -283.300886)
			(xy 348.666155 -283.292578) (xy 348.618376 -283.27618) (xy 348.573948 -283.252142) (xy 348.534083 -283.221119)
			(xy 348.499869 -283.183956) (xy 348.472238 -283.141669) (xy 348.451945 -283.09541) (xy 348.439544 -283.046442)
			(xy 348.435372 -282.9961) (xy 348.106491 -282.9961) (xy 348.106492 -282.996132) (xy 348.105997 -283.020739)
			(xy 348.098102 -283.069316) (xy 348.082518 -283.115997) (xy 348.059647 -283.159574) (xy 348.030082 -283.198918)
			(xy 347.994589 -283.23301) (xy 347.954086 -283.260966) (xy 347.909624 -283.282064) (xy 347.862353 -283.295756)
			(xy 347.813498 -283.301688) (xy 347.764323 -283.299707) (xy 347.716104 -283.289863) (xy 347.670088 -283.272411)
			(xy 347.627467 -283.247804) (xy 347.589346 -283.216679) (xy 347.556711 -283.179842) (xy 347.530408 -283.138246)
			(xy 347.511117 -283.09297) (xy 347.49934 -283.045186) (xy 347.49538 -282.996132) (xy 347.16696 -282.996132)
			(xy 347.162792 -283.04644) (xy 347.150393 -283.095408) (xy 347.130103 -283.141666) (xy 347.102477 -283.183955)
			(xy 347.068267 -283.22112) (xy 347.028407 -283.252148) (xy 346.983984 -283.276192) (xy 346.936209 -283.292597)
			(xy 346.886386 -283.300916) (xy 346.86113 -283.30144) (xy 345.921076 -283.30144) (xy 345.895825 -283.300853)
			(xy 345.846011 -283.292537) (xy 345.798246 -283.276135) (xy 345.753831 -283.252096) (xy 345.713979 -283.221075)
			(xy 345.679775 -283.183918) (xy 345.652154 -283.141638) (xy 345.631868 -283.095388) (xy 345.619471 -283.04643)
			(xy 345.615301 -282.9961) (xy 345.286799 -282.9961) (xy 345.282633 -283.046404) (xy 345.270249 -283.095338)
			(xy 345.249984 -283.141568) (xy 345.22239 -283.183834) (xy 345.188219 -283.220985) (xy 345.148402 -283.252009)
			(xy 345.104025 -283.276061) (xy 345.056295 -283.292485) (xy 345.006514 -283.300833) (xy 344.981276 -283.30144)
			(xy 344.971209 -283.301869) (xy 344.952614 -283.309594) (xy 344.945208 -283.316426) (xy 344.895424 -283.36621)
			(xy 344.888707 -283.373446) (xy 344.881106 -283.391652) (xy 344.880692 -283.401516) (xy 344.880692 -283.806138)
			(xy 347.025226 -283.806138) (xy 347.029186 -283.757084) (xy 347.040963 -283.7093) (xy 347.060254 -283.664024)
			(xy 347.086557 -283.622428) (xy 347.119192 -283.585591) (xy 347.157313 -283.554466) (xy 347.199934 -283.529859)
			(xy 347.24595 -283.512407) (xy 347.294169 -283.502563) (xy 347.343344 -283.500582) (xy 347.392199 -283.506514)
			(xy 347.43947 -283.520206) (xy 347.483932 -283.541304) (xy 347.524435 -283.56926) (xy 347.559928 -283.603352)
			(xy 347.589493 -283.642696) (xy 347.612364 -283.686273) (xy 347.627948 -283.732954) (xy 347.635843 -283.781531)
			(xy 347.636338 -283.806138) (xy 349.845388 -283.806138) (xy 349.849348 -283.757084) (xy 349.861125 -283.7093)
			(xy 349.880416 -283.664024) (xy 349.906719 -283.622428) (xy 349.939354 -283.585591) (xy 349.977475 -283.554466)
			(xy 350.020096 -283.529859) (xy 350.066112 -283.512407) (xy 350.114331 -283.502563) (xy 350.163506 -283.500582)
			(xy 350.212361 -283.506514) (xy 350.259632 -283.520206) (xy 350.304094 -283.541304) (xy 350.344597 -283.56926)
			(xy 350.38009 -283.603352) (xy 350.409655 -283.642696) (xy 350.432526 -283.686273) (xy 350.44811 -283.732954)
			(xy 350.456005 -283.781531) (xy 350.4565 -283.806138) (xy 352.665296 -283.806138) (xy 352.669256 -283.757084)
			(xy 352.681033 -283.7093) (xy 352.700324 -283.664024) (xy 352.726627 -283.622428) (xy 352.759262 -283.585591)
			(xy 352.797383 -283.554466) (xy 352.840004 -283.529859) (xy 352.88602 -283.512407) (xy 352.934239 -283.502563)
			(xy 352.983414 -283.500582) (xy 353.032269 -283.506514) (xy 353.07954 -283.520206) (xy 353.124002 -283.541304)
			(xy 353.164505 -283.56926) (xy 353.199998 -283.603352) (xy 353.229563 -283.642696) (xy 353.252434 -283.686273)
			(xy 353.268018 -283.732954) (xy 353.275913 -283.781531) (xy 353.276408 -283.806138) (xy 355.485204 -283.806138)
			(xy 355.489164 -283.757084) (xy 355.500941 -283.7093) (xy 355.520232 -283.664024) (xy 355.546535 -283.622428)
			(xy 355.57917 -283.585591) (xy 355.617291 -283.554466) (xy 355.659912 -283.529859) (xy 355.705928 -283.512407)
			(xy 355.754147 -283.502563) (xy 355.803322 -283.500582) (xy 355.852177 -283.506514) (xy 355.899448 -283.520206)
			(xy 355.94391 -283.541304) (xy 355.984413 -283.56926) (xy 356.019906 -283.603352) (xy 356.049471 -283.642696)
			(xy 356.072342 -283.686273) (xy 356.087926 -283.732954) (xy 356.095821 -283.781531) (xy 356.096315 -283.8061)
			(xy 356.425052 -283.8061) (xy 356.429226 -283.75573) (xy 356.441632 -283.706734) (xy 356.461934 -283.660448)
			(xy 356.489576 -283.618134) (xy 356.523805 -283.580947) (xy 356.563688 -283.5499) (xy 356.608136 -283.525841)
			(xy 356.655939 -283.509425) (xy 356.705791 -283.501101) (xy 356.731062 -283.500576) (xy 357.671116 -283.500576)
			(xy 357.696395 -283.501023) (xy 357.746262 -283.509347) (xy 357.794079 -283.525765) (xy 357.838542 -283.549829)
			(xy 357.878438 -283.580883) (xy 357.912679 -283.61808) (xy 357.94033 -283.660406) (xy 357.960638 -283.706705)
			(xy 357.973049 -283.755715) (xy 357.977224 -283.8061) (xy 357.977221 -283.806138) (xy 358.305366 -283.806138)
			(xy 358.309326 -283.757084) (xy 358.321103 -283.7093) (xy 358.340394 -283.664024) (xy 358.366697 -283.622428)
			(xy 358.399332 -283.585591) (xy 358.437453 -283.554466) (xy 358.480074 -283.529859) (xy 358.52609 -283.512407)
			(xy 358.574309 -283.502563) (xy 358.623484 -283.500582) (xy 358.672339 -283.506514) (xy 358.71961 -283.520206)
			(xy 358.764072 -283.541304) (xy 358.804575 -283.56926) (xy 358.840068 -283.603352) (xy 358.869633 -283.642696)
			(xy 358.892504 -283.686273) (xy 358.908088 -283.732954) (xy 358.915983 -283.781531) (xy 358.916478 -283.806138)
			(xy 361.118924 -283.806138) (xy 361.122884 -283.757084) (xy 361.134661 -283.7093) (xy 361.153952 -283.664024)
			(xy 361.180255 -283.622428) (xy 361.21289 -283.585591) (xy 361.251011 -283.554466) (xy 361.293632 -283.529859)
			(xy 361.339648 -283.512407) (xy 361.387867 -283.502563) (xy 361.437042 -283.500582) (xy 361.485897 -283.506514)
			(xy 361.533168 -283.520206) (xy 361.57763 -283.541304) (xy 361.618133 -283.56926) (xy 361.653626 -283.603352)
			(xy 361.683191 -283.642696) (xy 361.706062 -283.686273) (xy 361.721646 -283.732954) (xy 361.729541 -283.781531)
			(xy 361.730035 -283.8061) (xy 362.058752 -283.8061) (xy 362.062926 -283.755728) (xy 362.075334 -283.70673)
			(xy 362.095637 -283.660442) (xy 362.123281 -283.618128) (xy 362.157513 -283.58094) (xy 362.197398 -283.549894)
			(xy 362.24185 -283.525835) (xy 362.289655 -283.509421) (xy 362.33951 -283.501099) (xy 362.364782 -283.500576)
			(xy 363.304836 -283.500576) (xy 363.330114 -283.501025) (xy 363.379978 -283.509351) (xy 363.427793 -283.525771)
			(xy 363.472253 -283.549836) (xy 363.512146 -283.58089) (xy 363.546384 -283.618087) (xy 363.574033 -283.660411)
			(xy 363.594339 -283.706709) (xy 363.606749 -283.755717) (xy 363.610924 -283.8061) (xy 363.610921 -283.806138)
			(xy 363.939086 -283.806138) (xy 363.943046 -283.757084) (xy 363.954823 -283.7093) (xy 363.974114 -283.664024)
			(xy 364.000417 -283.622428) (xy 364.033052 -283.585591) (xy 364.071173 -283.554466) (xy 364.113794 -283.529859)
			(xy 364.15981 -283.512407) (xy 364.208029 -283.502563) (xy 364.257204 -283.500582) (xy 364.306059 -283.506514)
			(xy 364.35333 -283.520206) (xy 364.397792 -283.541304) (xy 364.438295 -283.56926) (xy 364.473788 -283.603352)
			(xy 364.503353 -283.642696) (xy 364.526224 -283.686273) (xy 364.541808 -283.732954) (xy 364.549703 -283.781531)
			(xy 364.550198 -283.806138) (xy 366.758994 -283.806138) (xy 366.762954 -283.757084) (xy 366.774731 -283.7093)
			(xy 366.794022 -283.664024) (xy 366.820325 -283.622428) (xy 366.85296 -283.585591) (xy 366.891081 -283.554466)
			(xy 366.933702 -283.529859) (xy 366.979718 -283.512407) (xy 367.027937 -283.502563) (xy 367.077112 -283.500582)
			(xy 367.125967 -283.506514) (xy 367.173238 -283.520206) (xy 367.2177 -283.541304) (xy 367.258203 -283.56926)
			(xy 367.293696 -283.603352) (xy 367.323261 -283.642696) (xy 367.346132 -283.686273) (xy 367.361716 -283.732954)
			(xy 367.369611 -283.781531) (xy 367.370106 -283.806138) (xy 369.578902 -283.806138) (xy 369.582862 -283.757084)
			(xy 369.594639 -283.7093) (xy 369.61393 -283.664024) (xy 369.640233 -283.622428) (xy 369.672868 -283.585591)
			(xy 369.710989 -283.554466) (xy 369.75361 -283.529859) (xy 369.799626 -283.512407) (xy 369.847845 -283.502563)
			(xy 369.89702 -283.500582) (xy 369.945875 -283.506514) (xy 369.993146 -283.520206) (xy 370.037608 -283.541304)
			(xy 370.078111 -283.56926) (xy 370.113604 -283.603352) (xy 370.143169 -283.642696) (xy 370.16604 -283.686273)
			(xy 370.181624 -283.732954) (xy 370.189519 -283.781531) (xy 370.190014 -283.806138) (xy 372.399064 -283.806138)
			(xy 372.403024 -283.757084) (xy 372.414801 -283.7093) (xy 372.434092 -283.664024) (xy 372.460395 -283.622428)
			(xy 372.49303 -283.585591) (xy 372.531151 -283.554466) (xy 372.573772 -283.529859) (xy 372.619788 -283.512407)
			(xy 372.668007 -283.502563) (xy 372.717182 -283.500582) (xy 372.766037 -283.506514) (xy 372.813308 -283.520206)
			(xy 372.85777 -283.541304) (xy 372.898273 -283.56926) (xy 372.933766 -283.603352) (xy 372.963331 -283.642696)
			(xy 372.986202 -283.686273) (xy 373.001786 -283.732954) (xy 373.009681 -283.781531) (xy 373.010176 -283.806138)
			(xy 373.009681 -283.830745) (xy 373.001786 -283.879322) (xy 372.986202 -283.926003) (xy 372.963331 -283.96958)
			(xy 372.933766 -284.008924) (xy 372.898273 -284.043016) (xy 372.85777 -284.070972) (xy 372.813308 -284.09207)
			(xy 372.766037 -284.105762) (xy 372.717182 -284.111694) (xy 372.668007 -284.109713) (xy 372.619788 -284.099869)
			(xy 372.573772 -284.082417) (xy 372.531151 -284.05781) (xy 372.49303 -284.026685) (xy 372.460395 -283.989848)
			(xy 372.434092 -283.948252) (xy 372.414801 -283.902976) (xy 372.403024 -283.855192) (xy 372.399064 -283.806138)
			(xy 370.190014 -283.806138) (xy 370.189519 -283.830745) (xy 370.181624 -283.879322) (xy 370.16604 -283.926003)
			(xy 370.143169 -283.96958) (xy 370.113604 -284.008924) (xy 370.078111 -284.043016) (xy 370.037608 -284.070972)
			(xy 369.993146 -284.09207) (xy 369.945875 -284.105762) (xy 369.89702 -284.111694) (xy 369.847845 -284.109713)
			(xy 369.799626 -284.099869) (xy 369.75361 -284.082417) (xy 369.710989 -284.05781) (xy 369.672868 -284.026685)
			(xy 369.640233 -283.989848) (xy 369.61393 -283.948252) (xy 369.594639 -283.902976) (xy 369.582862 -283.855192)
			(xy 369.578902 -283.806138) (xy 367.370106 -283.806138) (xy 367.369611 -283.830745) (xy 367.361716 -283.879322)
			(xy 367.346132 -283.926003) (xy 367.323261 -283.96958) (xy 367.293696 -284.008924) (xy 367.258203 -284.043016)
			(xy 367.2177 -284.070972) (xy 367.173238 -284.09207) (xy 367.125967 -284.105762) (xy 367.077112 -284.111694)
			(xy 367.027937 -284.109713) (xy 366.979718 -284.099869) (xy 366.933702 -284.082417) (xy 366.891081 -284.05781)
			(xy 366.85296 -284.026685) (xy 366.820325 -283.989848) (xy 366.794022 -283.948252) (xy 366.774731 -283.902976)
			(xy 366.762954 -283.855192) (xy 366.758994 -283.806138) (xy 364.550198 -283.806138) (xy 364.549703 -283.830745)
			(xy 364.541808 -283.879322) (xy 364.526224 -283.926003) (xy 364.503353 -283.96958) (xy 364.473788 -284.008924)
			(xy 364.438295 -284.043016) (xy 364.397792 -284.070972) (xy 364.35333 -284.09207) (xy 364.306059 -284.105762)
			(xy 364.257204 -284.111694) (xy 364.208029 -284.109713) (xy 364.15981 -284.099869) (xy 364.113794 -284.082417)
			(xy 364.071173 -284.05781) (xy 364.033052 -284.026685) (xy 364.000417 -283.989848) (xy 363.974114 -283.948252)
			(xy 363.954823 -283.902976) (xy 363.943046 -283.855192) (xy 363.939086 -283.806138) (xy 363.610921 -283.806138)
			(xy 363.606749 -283.856483) (xy 363.594339 -283.905491) (xy 363.574033 -283.951789) (xy 363.546384 -283.994113)
			(xy 363.512146 -284.03131) (xy 363.472253 -284.062364) (xy 363.427793 -284.086429) (xy 363.379978 -284.102849)
			(xy 363.330114 -284.111175) (xy 363.304836 -284.1117) (xy 362.364782 -284.1117) (xy 362.33951 -284.111101)
			(xy 362.289655 -284.102779) (xy 362.24185 -284.086365) (xy 362.197398 -284.062306) (xy 362.157513 -284.03126)
			(xy 362.123281 -283.994072) (xy 362.095637 -283.951758) (xy 362.075334 -283.90547) (xy 362.062926 -283.856472)
			(xy 362.058752 -283.8061) (xy 361.730035 -283.8061) (xy 361.730036 -283.806138) (xy 361.729541 -283.830745)
			(xy 361.721646 -283.879322) (xy 361.706062 -283.926003) (xy 361.683191 -283.96958) (xy 361.653626 -284.008924)
			(xy 361.618133 -284.043016) (xy 361.57763 -284.070972) (xy 361.533168 -284.09207) (xy 361.485897 -284.105762)
			(xy 361.437042 -284.111694) (xy 361.387867 -284.109713) (xy 361.339648 -284.099869) (xy 361.293632 -284.082417)
			(xy 361.251011 -284.05781) (xy 361.21289 -284.026685) (xy 361.180255 -283.989848) (xy 361.153952 -283.948252)
			(xy 361.134661 -283.902976) (xy 361.122884 -283.855192) (xy 361.118924 -283.806138) (xy 358.916478 -283.806138)
			(xy 358.915983 -283.830745) (xy 358.908088 -283.879322) (xy 358.892504 -283.926003) (xy 358.869633 -283.96958)
			(xy 358.840068 -284.008924) (xy 358.804575 -284.043016) (xy 358.764072 -284.070972) (xy 358.71961 -284.09207)
			(xy 358.672339 -284.105762) (xy 358.623484 -284.111694) (xy 358.574309 -284.109713) (xy 358.52609 -284.099869)
			(xy 358.480074 -284.082417) (xy 358.437453 -284.05781) (xy 358.399332 -284.026685) (xy 358.366697 -283.989848)
			(xy 358.340394 -283.948252) (xy 358.321103 -283.902976) (xy 358.309326 -283.855192) (xy 358.305366 -283.806138)
			(xy 357.977221 -283.806138) (xy 357.973049 -283.856485) (xy 357.960638 -283.905495) (xy 357.94033 -283.951794)
			(xy 357.912679 -283.99412) (xy 357.878438 -284.031317) (xy 357.838542 -284.062371) (xy 357.794079 -284.086435)
			(xy 357.746262 -284.102853) (xy 357.696395 -284.111177) (xy 357.671116 -284.1117) (xy 356.731062 -284.1117)
			(xy 356.705791 -284.111099) (xy 356.655939 -284.102775) (xy 356.608136 -284.086359) (xy 356.563688 -284.0623)
			(xy 356.523805 -284.031253) (xy 356.489576 -283.994066) (xy 356.461934 -283.951752) (xy 356.441632 -283.905466)
			(xy 356.429226 -283.85647) (xy 356.425052 -283.8061) (xy 356.096315 -283.8061) (xy 356.096316 -283.806138)
			(xy 356.095821 -283.830745) (xy 356.087926 -283.879322) (xy 356.072342 -283.926003) (xy 356.049471 -283.96958)
			(xy 356.019906 -284.008924) (xy 355.984413 -284.043016) (xy 355.94391 -284.070972) (xy 355.899448 -284.09207)
			(xy 355.852177 -284.105762) (xy 355.803322 -284.111694) (xy 355.754147 -284.109713) (xy 355.705928 -284.099869)
			(xy 355.659912 -284.082417) (xy 355.617291 -284.05781) (xy 355.57917 -284.026685) (xy 355.546535 -283.989848)
			(xy 355.520232 -283.948252) (xy 355.500941 -283.902976) (xy 355.489164 -283.855192) (xy 355.485204 -283.806138)
			(xy 353.276408 -283.806138) (xy 353.275913 -283.830745) (xy 353.268018 -283.879322) (xy 353.252434 -283.926003)
			(xy 353.229563 -283.96958) (xy 353.199998 -284.008924) (xy 353.164505 -284.043016) (xy 353.124002 -284.070972)
			(xy 353.07954 -284.09207) (xy 353.032269 -284.105762) (xy 352.983414 -284.111694) (xy 352.934239 -284.109713)
			(xy 352.88602 -284.099869) (xy 352.840004 -284.082417) (xy 352.797383 -284.05781) (xy 352.759262 -284.026685)
			(xy 352.726627 -283.989848) (xy 352.700324 -283.948252) (xy 352.681033 -283.902976) (xy 352.669256 -283.855192)
			(xy 352.665296 -283.806138) (xy 350.4565 -283.806138) (xy 350.456005 -283.830745) (xy 350.44811 -283.879322)
			(xy 350.432526 -283.926003) (xy 350.409655 -283.96958) (xy 350.38009 -284.008924) (xy 350.344597 -284.043016)
			(xy 350.304094 -284.070972) (xy 350.259632 -284.09207) (xy 350.212361 -284.105762) (xy 350.163506 -284.111694)
			(xy 350.114331 -284.109713) (xy 350.066112 -284.099869) (xy 350.020096 -284.082417) (xy 349.977475 -284.05781)
			(xy 349.939354 -284.026685) (xy 349.906719 -283.989848) (xy 349.880416 -283.948252) (xy 349.861125 -283.902976)
			(xy 349.849348 -283.855192) (xy 349.845388 -283.806138) (xy 347.636338 -283.806138) (xy 347.635843 -283.830745)
			(xy 347.627948 -283.879322) (xy 347.612364 -283.926003) (xy 347.589493 -283.96958) (xy 347.559928 -284.008924)
			(xy 347.524435 -284.043016) (xy 347.483932 -284.070972) (xy 347.43947 -284.09207) (xy 347.392199 -284.105762)
			(xy 347.343344 -284.111694) (xy 347.294169 -284.109713) (xy 347.24595 -284.099869) (xy 347.199934 -284.082417)
			(xy 347.157313 -284.05781) (xy 347.119192 -284.026685) (xy 347.086557 -283.989848) (xy 347.060254 -283.948252)
			(xy 347.040963 -283.902976) (xy 347.029186 -283.855192) (xy 347.025226 -283.806138) (xy 344.880692 -283.806138)
			(xy 344.880692 -284.209236) (xy 344.881173 -284.219201) (xy 344.888752 -284.237634) (xy 344.895424 -284.24505)
			(xy 344.94597 -284.29585) (xy 344.95337 -284.302691) (xy 344.971969 -284.310408) (xy 344.982038 -284.310836)
			(xy 345.007233 -284.311439) (xy 345.056915 -284.319884) (xy 345.104535 -284.336375) (xy 345.1488 -284.360464)
			(xy 345.188507 -284.391495) (xy 345.222579 -284.428626) (xy 345.250089 -284.47085) (xy 345.270291 -284.517018)
			(xy 345.282636 -284.565877) (xy 345.286789 -284.6161) (xy 345.615313 -284.6161) (xy 345.619483 -284.565772)
			(xy 345.63188 -284.516816) (xy 345.652165 -284.470568) (xy 345.679785 -284.42829) (xy 345.713987 -284.391134)
			(xy 345.753838 -284.360114) (xy 345.798251 -284.336076) (xy 345.846014 -284.319675) (xy 345.895826 -284.311359)
			(xy 345.921076 -284.310836) (xy 346.86113 -284.310836) (xy 346.886387 -284.311272) (xy 346.936213 -284.31959)
			(xy 346.983989 -284.335996) (xy 347.028414 -284.360042) (xy 347.068275 -284.391071) (xy 347.102487 -284.428237)
			(xy 347.130114 -284.470528) (xy 347.150404 -284.516788) (xy 347.162804 -284.565758) (xy 347.166976 -284.6161)
			(xy 347.166972 -284.616144) (xy 347.49538 -284.616144) (xy 347.49934 -284.56709) (xy 347.511117 -284.519306)
			(xy 347.530408 -284.47403) (xy 347.556711 -284.432434) (xy 347.589346 -284.395597) (xy 347.627467 -284.364472)
			(xy 347.670088 -284.339865) (xy 347.716104 -284.322413) (xy 347.764323 -284.312569) (xy 347.813498 -284.310588)
			(xy 347.862353 -284.31652) (xy 347.909624 -284.330212) (xy 347.954086 -284.35131) (xy 347.994589 -284.379266)
			(xy 348.030082 -284.413358) (xy 348.059647 -284.452702) (xy 348.082518 -284.496279) (xy 348.098102 -284.54296)
			(xy 348.105997 -284.591537) (xy 348.106491 -284.6161) (xy 348.435384 -284.6161) (xy 348.439556 -284.56576)
			(xy 348.451957 -284.516794) (xy 348.472249 -284.470537) (xy 348.499878 -284.428251) (xy 348.534091 -284.39109)
			(xy 348.573955 -284.360068) (xy 348.618381 -284.336031) (xy 348.666158 -284.319634) (xy 348.715982 -284.311326)
			(xy 348.741238 -284.310836) (xy 349.681292 -284.310836) (xy 349.706554 -284.31124) (xy 349.756388 -284.319555)
			(xy 349.804175 -284.335959) (xy 349.848609 -284.360005) (xy 349.88848 -284.391036) (xy 349.922699 -284.428207)
			(xy 349.950333 -284.470504) (xy 349.970629 -284.516772) (xy 349.983032 -284.565749) (xy 349.987204 -284.6161)
			(xy 349.9872 -284.616144) (xy 350.315288 -284.616144) (xy 350.319248 -284.56709) (xy 350.331025 -284.519306)
			(xy 350.350316 -284.47403) (xy 350.376619 -284.432434) (xy 350.409254 -284.395597) (xy 350.447375 -284.364472)
			(xy 350.489996 -284.339865) (xy 350.536012 -284.322413) (xy 350.584231 -284.312569) (xy 350.633406 -284.310588)
			(xy 350.682261 -284.31652) (xy 350.729532 -284.330212) (xy 350.773994 -284.35131) (xy 350.814497 -284.379266)
			(xy 350.84999 -284.413358) (xy 350.879555 -284.452702) (xy 350.902426 -284.496279) (xy 350.91801 -284.54296)
			(xy 350.925905 -284.591537) (xy 350.926399 -284.6161) (xy 351.255284 -284.6161) (xy 351.259456 -284.56576)
			(xy 351.271857 -284.516793) (xy 351.29215 -284.470535) (xy 351.31978 -284.428249) (xy 351.353994 -284.391087)
			(xy 351.393859 -284.360065) (xy 351.438286 -284.336028) (xy 351.486064 -284.319632) (xy 351.535889 -284.311325)
			(xy 351.561146 -284.310836) (xy 352.5012 -284.310836) (xy 352.526459 -284.311269) (xy 352.576288 -284.319584)
			(xy 352.624069 -284.335987) (xy 352.668498 -284.360031) (xy 352.708364 -284.39106) (xy 352.742579 -284.428227)
			(xy 352.770209 -284.470519) (xy 352.790502 -284.516782) (xy 352.802904 -284.565755) (xy 352.807076 -284.6161)
			(xy 352.807072 -284.616144) (xy 353.135196 -284.616144) (xy 353.139156 -284.56709) (xy 353.150933 -284.519306)
			(xy 353.170224 -284.47403) (xy 353.196527 -284.432434) (xy 353.229162 -284.395597) (xy 353.267283 -284.364472)
			(xy 353.309904 -284.339865) (xy 353.35592 -284.322413) (xy 353.404139 -284.312569) (xy 353.453314 -284.310588)
			(xy 353.502169 -284.31652) (xy 353.54944 -284.330212) (xy 353.593902 -284.35131) (xy 353.634405 -284.379266)
			(xy 353.669898 -284.413358) (xy 353.699463 -284.452702) (xy 353.722334 -284.496279) (xy 353.737918 -284.54296)
			(xy 353.745813 -284.591537) (xy 353.746307 -284.6161) (xy 354.075313 -284.6161) (xy 354.079483 -284.565774)
			(xy 354.091878 -284.51682) (xy 354.112161 -284.470574) (xy 354.139779 -284.428297) (xy 354.173978 -284.391142)
			(xy 354.213826 -284.360121) (xy 354.258236 -284.336082) (xy 354.305996 -284.31968) (xy 354.355805 -284.311361)
			(xy 354.381054 -284.310836) (xy 355.321108 -284.310836) (xy 355.346367 -284.31127) (xy 355.396195 -284.319586)
			(xy 355.443974 -284.33599) (xy 355.488402 -284.360034) (xy 355.528267 -284.391063) (xy 355.562481 -284.42823)
			(xy 355.590111 -284.470522) (xy 355.610403 -284.516784) (xy 355.622804 -284.565755) (xy 355.626976 -284.6161)
			(xy 355.626972 -284.616144) (xy 355.955358 -284.616144) (xy 355.959318 -284.56709) (xy 355.971095 -284.519306)
			(xy 355.990386 -284.47403) (xy 356.016689 -284.432434) (xy 356.049324 -284.395597) (xy 356.087445 -284.364472)
			(xy 356.130066 -284.339865) (xy 356.176082 -284.322413) (xy 356.224301 -284.312569) (xy 356.273476 -284.310588)
			(xy 356.322331 -284.31652) (xy 356.369602 -284.330212) (xy 356.414064 -284.35131) (xy 356.454567 -284.379266)
			(xy 356.49006 -284.413358) (xy 356.519625 -284.452702) (xy 356.542496 -284.496279) (xy 356.55808 -284.54296)
			(xy 356.565975 -284.591537) (xy 356.56647 -284.616144) (xy 356.895412 -284.616144) (xy 356.899372 -284.56709)
			(xy 356.911149 -284.519306) (xy 356.93044 -284.47403) (xy 356.956743 -284.432434) (xy 356.989378 -284.395597)
			(xy 357.027499 -284.364472) (xy 357.07012 -284.339865) (xy 357.116136 -284.322413) (xy 357.164355 -284.312569)
			(xy 357.21353 -284.310588) (xy 357.262385 -284.31652) (xy 357.309656 -284.330212) (xy 357.354118 -284.35131)
			(xy 357.394621 -284.379266) (xy 357.430114 -284.413358) (xy 357.459679 -284.452702) (xy 357.48255 -284.496279)
			(xy 357.498134 -284.54296) (xy 357.506029 -284.591537) (xy 357.506524 -284.616144) (xy 357.835212 -284.616144)
			(xy 357.839172 -284.56709) (xy 357.850949 -284.519306) (xy 357.87024 -284.47403) (xy 357.896543 -284.432434)
			(xy 357.929178 -284.395597) (xy 357.967299 -284.364472) (xy 358.00992 -284.339865) (xy 358.055936 -284.322413)
			(xy 358.104155 -284.312569) (xy 358.15333 -284.310588) (xy 358.202185 -284.31652) (xy 358.249456 -284.330212)
			(xy 358.293918 -284.35131) (xy 358.334421 -284.379266) (xy 358.369914 -284.413358) (xy 358.399479 -284.452702)
			(xy 358.42235 -284.496279) (xy 358.437934 -284.54296) (xy 358.445829 -284.591537) (xy 358.446324 -284.616144)
			(xy 361.589078 -284.616144) (xy 361.593038 -284.56709) (xy 361.604815 -284.519306) (xy 361.624106 -284.47403)
			(xy 361.650409 -284.432434) (xy 361.683044 -284.395597) (xy 361.721165 -284.364472) (xy 361.763786 -284.339865)
			(xy 361.809802 -284.322413) (xy 361.858021 -284.312569) (xy 361.907196 -284.310588) (xy 361.956051 -284.31652)
			(xy 362.003322 -284.330212) (xy 362.047784 -284.35131) (xy 362.088287 -284.379266) (xy 362.12378 -284.413358)
			(xy 362.153345 -284.452702) (xy 362.176216 -284.496279) (xy 362.1918 -284.54296) (xy 362.199695 -284.591537)
			(xy 362.20019 -284.616144) (xy 362.528878 -284.616144) (xy 362.532838 -284.56709) (xy 362.544615 -284.519306)
			(xy 362.563906 -284.47403) (xy 362.590209 -284.432434) (xy 362.622844 -284.395597) (xy 362.660965 -284.364472)
			(xy 362.703586 -284.339865) (xy 362.749602 -284.322413) (xy 362.797821 -284.312569) (xy 362.846996 -284.310588)
			(xy 362.895851 -284.31652) (xy 362.943122 -284.330212) (xy 362.987584 -284.35131) (xy 363.028087 -284.379266)
			(xy 363.06358 -284.413358) (xy 363.093145 -284.452702) (xy 363.116016 -284.496279) (xy 363.1316 -284.54296)
			(xy 363.139495 -284.591537) (xy 363.13999 -284.616144) (xy 363.468932 -284.616144) (xy 363.472892 -284.56709)
			(xy 363.484669 -284.519306) (xy 363.50396 -284.47403) (xy 363.530263 -284.432434) (xy 363.562898 -284.395597)
			(xy 363.601019 -284.364472) (xy 363.64364 -284.339865) (xy 363.689656 -284.322413) (xy 363.737875 -284.312569)
			(xy 363.78705 -284.310588) (xy 363.835905 -284.31652) (xy 363.883176 -284.330212) (xy 363.927638 -284.35131)
			(xy 363.968141 -284.379266) (xy 364.003634 -284.413358) (xy 364.033199 -284.452702) (xy 364.05607 -284.496279)
			(xy 364.071654 -284.54296) (xy 364.079549 -284.591537) (xy 364.080043 -284.6161) (xy 364.409013 -284.6161)
			(xy 364.413183 -284.56577) (xy 364.425581 -284.516813) (xy 364.445867 -284.470564) (xy 364.473488 -284.428285)
			(xy 364.507692 -284.391129) (xy 364.547545 -284.360109) (xy 364.59196 -284.336071) (xy 364.639726 -284.319672)
			(xy 364.689539 -284.311358) (xy 364.71479 -284.310836) (xy 365.654844 -284.310836) (xy 365.680101 -284.311273)
			(xy 365.729924 -284.319593) (xy 365.777699 -284.336) (xy 365.822121 -284.360047) (xy 365.861981 -284.391076)
			(xy 365.89619 -284.428242) (xy 365.923816 -284.470532) (xy 365.944105 -284.516791) (xy 365.956505 -284.565759)
			(xy 365.960676 -284.6161) (xy 365.960672 -284.616144) (xy 366.289094 -284.616144) (xy 366.293054 -284.56709)
			(xy 366.304831 -284.519306) (xy 366.324122 -284.47403) (xy 366.350425 -284.432434) (xy 366.38306 -284.395597)
			(xy 366.421181 -284.364472) (xy 366.463802 -284.339865) (xy 366.509818 -284.322413) (xy 366.558037 -284.312569)
			(xy 366.607212 -284.310588) (xy 366.656067 -284.31652) (xy 366.703338 -284.330212) (xy 366.7478 -284.35131)
			(xy 366.788303 -284.379266) (xy 366.823796 -284.413358) (xy 366.853361 -284.452702) (xy 366.876232 -284.496279)
			(xy 366.891816 -284.54296) (xy 366.899711 -284.591537) (xy 366.900205 -284.6161) (xy 367.228913 -284.6161)
			(xy 367.233084 -284.565769) (xy 367.245481 -284.516812) (xy 367.265768 -284.470562) (xy 367.293391 -284.428282)
			(xy 367.327595 -284.391126) (xy 367.367449 -284.360106) (xy 367.411865 -284.336069) (xy 367.459632 -284.31967)
			(xy 367.509446 -284.311358) (xy 367.534698 -284.310836) (xy 368.474752 -284.310836) (xy 368.500016 -284.311237)
			(xy 368.549856 -284.319547) (xy 368.597648 -284.335947) (xy 368.642088 -284.359991) (xy 368.681965 -284.391022)
			(xy 368.716189 -284.428194) (xy 368.743827 -284.470492) (xy 368.764126 -284.516764) (xy 368.776531 -284.565745)
			(xy 368.780704 -284.6161) (xy 368.7807 -284.616144) (xy 369.109002 -284.616144) (xy 369.112962 -284.56709)
			(xy 369.124739 -284.519306) (xy 369.14403 -284.47403) (xy 369.170333 -284.432434) (xy 369.202968 -284.395597)
			(xy 369.241089 -284.364472) (xy 369.28371 -284.339865) (xy 369.329726 -284.322413) (xy 369.377945 -284.312569)
			(xy 369.42712 -284.310588) (xy 369.475975 -284.31652) (xy 369.523246 -284.330212) (xy 369.567708 -284.35131)
			(xy 369.608211 -284.379266) (xy 369.643704 -284.413358) (xy 369.673269 -284.452702) (xy 369.69614 -284.496279)
			(xy 369.711724 -284.54296) (xy 369.719619 -284.591537) (xy 369.720113 -284.6161) (xy 370.049113 -284.6161)
			(xy 370.053283 -284.565773) (xy 370.065679 -284.516819) (xy 370.085962 -284.470573) (xy 370.113581 -284.428295)
			(xy 370.147781 -284.391139) (xy 370.187629 -284.360119) (xy 370.23204 -284.33608) (xy 370.279801 -284.319678)
			(xy 370.32961 -284.311361) (xy 370.35486 -284.310836) (xy 371.294914 -284.310836) (xy 371.320172 -284.31127)
			(xy 371.369999 -284.319587) (xy 371.417778 -284.335992) (xy 371.462205 -284.360036) (xy 371.502069 -284.391065)
			(xy 371.536282 -284.428232) (xy 371.563912 -284.470523) (xy 371.584203 -284.516785) (xy 371.596604 -284.565756)
			(xy 371.600776 -284.6161) (xy 371.600772 -284.616144) (xy 371.92891 -284.616144) (xy 371.93287 -284.56709)
			(xy 371.944647 -284.519306) (xy 371.963938 -284.47403) (xy 371.990241 -284.432434) (xy 372.022876 -284.395597)
			(xy 372.060997 -284.364472) (xy 372.103618 -284.339865) (xy 372.149634 -284.322413) (xy 372.197853 -284.312569)
			(xy 372.247028 -284.310588) (xy 372.295883 -284.31652) (xy 372.343154 -284.330212) (xy 372.387616 -284.35131)
			(xy 372.428119 -284.379266) (xy 372.463612 -284.413358) (xy 372.493177 -284.452702) (xy 372.516048 -284.496279)
			(xy 372.531632 -284.54296) (xy 372.539527 -284.591537) (xy 372.540022 -284.616144) (xy 372.539527 -284.640751)
			(xy 372.531632 -284.689328) (xy 372.516048 -284.736009) (xy 372.493177 -284.779586) (xy 372.463612 -284.81893)
			(xy 372.428119 -284.853022) (xy 372.387616 -284.880978) (xy 372.343154 -284.902076) (xy 372.295883 -284.915768)
			(xy 372.247028 -284.9217) (xy 372.197853 -284.919719) (xy 372.149634 -284.909875) (xy 372.103618 -284.892423)
			(xy 372.060997 -284.867816) (xy 372.022876 -284.836691) (xy 371.990241 -284.799854) (xy 371.963938 -284.758258)
			(xy 371.944647 -284.712982) (xy 371.93287 -284.665198) (xy 371.92891 -284.616144) (xy 371.600772 -284.616144)
			(xy 371.596604 -284.666444) (xy 371.584203 -284.715415) (xy 371.563912 -284.761677) (xy 371.536282 -284.803968)
			(xy 371.502069 -284.841135) (xy 371.462205 -284.872164) (xy 371.417778 -284.896208) (xy 371.369999 -284.912613)
			(xy 371.320172 -284.92093) (xy 371.294914 -284.921452) (xy 370.35486 -284.921452) (xy 370.32961 -284.920839)
			(xy 370.279801 -284.912522) (xy 370.23204 -284.89612) (xy 370.187629 -284.872081) (xy 370.147781 -284.841061)
			(xy 370.113581 -284.803905) (xy 370.085962 -284.761627) (xy 370.065679 -284.715381) (xy 370.053283 -284.666427)
			(xy 370.049113 -284.6161) (xy 369.720113 -284.6161) (xy 369.720114 -284.616144) (xy 369.719619 -284.640751)
			(xy 369.711724 -284.689328) (xy 369.69614 -284.736009) (xy 369.673269 -284.779586) (xy 369.643704 -284.81893)
			(xy 369.608211 -284.853022) (xy 369.567708 -284.880978) (xy 369.523246 -284.902076) (xy 369.475975 -284.915768)
			(xy 369.42712 -284.9217) (xy 369.377945 -284.919719) (xy 369.329726 -284.909875) (xy 369.28371 -284.892423)
			(xy 369.241089 -284.867816) (xy 369.202968 -284.836691) (xy 369.170333 -284.799854) (xy 369.14403 -284.758258)
			(xy 369.124739 -284.712982) (xy 369.112962 -284.665198) (xy 369.109002 -284.616144) (xy 368.7807 -284.616144)
			(xy 368.776531 -284.666455) (xy 368.764126 -284.715436) (xy 368.743827 -284.761708) (xy 368.716189 -284.804006)
			(xy 368.681965 -284.841178) (xy 368.642088 -284.872209) (xy 368.597648 -284.896253) (xy 368.549856 -284.912653)
			(xy 368.500016 -284.920963) (xy 368.474752 -284.921452) (xy 367.534698 -284.921452) (xy 367.509446 -284.920842)
			(xy 367.459632 -284.91253) (xy 367.411865 -284.896131) (xy 367.367449 -284.872094) (xy 367.327595 -284.841074)
			(xy 367.293391 -284.803918) (xy 367.265768 -284.761638) (xy 367.245481 -284.715388) (xy 367.233084 -284.666431)
			(xy 367.228913 -284.6161) (xy 366.900205 -284.6161) (xy 366.900206 -284.616144) (xy 366.899711 -284.640751)
			(xy 366.891816 -284.689328) (xy 366.876232 -284.736009) (xy 366.853361 -284.779586) (xy 366.823796 -284.81893)
			(xy 366.788303 -284.853022) (xy 366.7478 -284.880978) (xy 366.703338 -284.902076) (xy 366.656067 -284.915768)
			(xy 366.607212 -284.9217) (xy 366.558037 -284.919719) (xy 366.509818 -284.909875) (xy 366.463802 -284.892423)
			(xy 366.421181 -284.867816) (xy 366.38306 -284.836691) (xy 366.350425 -284.799854) (xy 366.324122 -284.758258)
			(xy 366.304831 -284.712982) (xy 366.293054 -284.665198) (xy 366.289094 -284.616144) (xy 365.960672 -284.616144)
			(xy 365.956505 -284.666441) (xy 365.944105 -284.715409) (xy 365.923816 -284.761668) (xy 365.89619 -284.803958)
			(xy 365.861981 -284.841124) (xy 365.822121 -284.872153) (xy 365.777699 -284.8962) (xy 365.729924 -284.912607)
			(xy 365.680101 -284.920927) (xy 365.654844 -284.921452) (xy 364.71479 -284.921452) (xy 364.689539 -284.920842)
			(xy 364.639726 -284.912528) (xy 364.59196 -284.896129) (xy 364.547545 -284.872091) (xy 364.507692 -284.841071)
			(xy 364.473489 -284.803915) (xy 364.445867 -284.761636) (xy 364.425581 -284.715387) (xy 364.413183 -284.66643)
			(xy 364.409013 -284.6161) (xy 364.080043 -284.6161) (xy 364.080044 -284.616144) (xy 364.079549 -284.640751)
			(xy 364.071654 -284.689328) (xy 364.05607 -284.736009) (xy 364.033199 -284.779586) (xy 364.003634 -284.81893)
			(xy 363.968141 -284.853022) (xy 363.927638 -284.880978) (xy 363.883176 -284.902076) (xy 363.835905 -284.915768)
			(xy 363.78705 -284.9217) (xy 363.737875 -284.919719) (xy 363.689656 -284.909875) (xy 363.64364 -284.892423)
			(xy 363.601019 -284.867816) (xy 363.562898 -284.836691) (xy 363.530263 -284.799854) (xy 363.50396 -284.758258)
			(xy 363.484669 -284.712982) (xy 363.472892 -284.665198) (xy 363.468932 -284.616144) (xy 363.13999 -284.616144)
			(xy 363.139495 -284.640751) (xy 363.1316 -284.689328) (xy 363.116016 -284.736009) (xy 363.093145 -284.779586)
			(xy 363.06358 -284.81893) (xy 363.028087 -284.853022) (xy 362.987584 -284.880978) (xy 362.943122 -284.902076)
			(xy 362.895851 -284.915768) (xy 362.846996 -284.9217) (xy 362.797821 -284.919719) (xy 362.749602 -284.909875)
			(xy 362.703586 -284.892423) (xy 362.660965 -284.867816) (xy 362.622844 -284.836691) (xy 362.590209 -284.799854)
			(xy 362.563906 -284.758258) (xy 362.544615 -284.712982) (xy 362.532838 -284.665198) (xy 362.528878 -284.616144)
			(xy 362.20019 -284.616144) (xy 362.199695 -284.640751) (xy 362.1918 -284.689328) (xy 362.176216 -284.736009)
			(xy 362.153345 -284.779586) (xy 362.12378 -284.81893) (xy 362.088287 -284.853022) (xy 362.047784 -284.880978)
			(xy 362.003322 -284.902076) (xy 361.956051 -284.915768) (xy 361.907196 -284.9217) (xy 361.858021 -284.919719)
			(xy 361.809802 -284.909875) (xy 361.763786 -284.892423) (xy 361.721165 -284.867816) (xy 361.683044 -284.836691)
			(xy 361.650409 -284.799854) (xy 361.624106 -284.758258) (xy 361.604815 -284.712982) (xy 361.593038 -284.665198)
			(xy 361.589078 -284.616144) (xy 358.446324 -284.616144) (xy 358.445829 -284.640751) (xy 358.437934 -284.689328)
			(xy 358.42235 -284.736009) (xy 358.399479 -284.779586) (xy 358.369914 -284.81893) (xy 358.334421 -284.853022)
			(xy 358.293918 -284.880978) (xy 358.249456 -284.902076) (xy 358.202185 -284.915768) (xy 358.15333 -284.9217)
			(xy 358.104155 -284.919719) (xy 358.055936 -284.909875) (xy 358.00992 -284.892423) (xy 357.967299 -284.867816)
			(xy 357.929178 -284.836691) (xy 357.896543 -284.799854) (xy 357.87024 -284.758258) (xy 357.850949 -284.712982)
			(xy 357.839172 -284.665198) (xy 357.835212 -284.616144) (xy 357.506524 -284.616144) (xy 357.506029 -284.640751)
			(xy 357.498134 -284.689328) (xy 357.48255 -284.736009) (xy 357.459679 -284.779586) (xy 357.430114 -284.81893)
			(xy 357.394621 -284.853022) (xy 357.354118 -284.880978) (xy 357.309656 -284.902076) (xy 357.262385 -284.915768)
			(xy 357.21353 -284.9217) (xy 357.164355 -284.919719) (xy 357.116136 -284.909875) (xy 357.07012 -284.892423)
			(xy 357.027499 -284.867816) (xy 356.989378 -284.836691) (xy 356.956743 -284.799854) (xy 356.93044 -284.758258)
			(xy 356.911149 -284.712982) (xy 356.899372 -284.665198) (xy 356.895412 -284.616144) (xy 356.56647 -284.616144)
			(xy 356.565975 -284.640751) (xy 356.55808 -284.689328) (xy 356.542496 -284.736009) (xy 356.519625 -284.779586)
			(xy 356.49006 -284.81893) (xy 356.454567 -284.853022) (xy 356.414064 -284.880978) (xy 356.369602 -284.902076)
			(xy 356.322331 -284.915768) (xy 356.273476 -284.9217) (xy 356.224301 -284.919719) (xy 356.176082 -284.909875)
			(xy 356.130066 -284.892423) (xy 356.087445 -284.867816) (xy 356.049324 -284.836691) (xy 356.016689 -284.799854)
			(xy 355.990386 -284.758258) (xy 355.971095 -284.712982) (xy 355.959318 -284.665198) (xy 355.955358 -284.616144)
			(xy 355.626972 -284.616144) (xy 355.622804 -284.666445) (xy 355.610403 -284.715416) (xy 355.590111 -284.761678)
			(xy 355.562481 -284.80397) (xy 355.528267 -284.841137) (xy 355.488402 -284.872166) (xy 355.443974 -284.89621)
			(xy 355.396195 -284.912614) (xy 355.346367 -284.92093) (xy 355.321108 -284.921452) (xy 354.381054 -284.921452)
			(xy 354.355805 -284.920839) (xy 354.305996 -284.91252) (xy 354.258236 -284.896118) (xy 354.213826 -284.872079)
			(xy 354.173978 -284.841058) (xy 354.139779 -284.803903) (xy 354.112161 -284.761626) (xy 354.091878 -284.71538)
			(xy 354.079483 -284.666426) (xy 354.075313 -284.6161) (xy 353.746307 -284.6161) (xy 353.746308 -284.616144)
			(xy 353.745813 -284.640751) (xy 353.737918 -284.689328) (xy 353.722334 -284.736009) (xy 353.699463 -284.779586)
			(xy 353.669898 -284.81893) (xy 353.634405 -284.853022) (xy 353.593902 -284.880978) (xy 353.54944 -284.902076)
			(xy 353.502169 -284.915768) (xy 353.453314 -284.9217) (xy 353.404139 -284.919719) (xy 353.35592 -284.909875)
			(xy 353.309904 -284.892423) (xy 353.267283 -284.867816) (xy 353.229162 -284.836691) (xy 353.196527 -284.799854)
			(xy 353.170224 -284.758258) (xy 353.150933 -284.712982) (xy 353.139156 -284.665198) (xy 353.135196 -284.616144)
			(xy 352.807072 -284.616144) (xy 352.802904 -284.666445) (xy 352.790502 -284.715418) (xy 352.770209 -284.761681)
			(xy 352.742579 -284.803973) (xy 352.708364 -284.84114) (xy 352.668498 -284.872169) (xy 352.624069 -284.896213)
			(xy 352.576288 -284.912616) (xy 352.526459 -284.920931) (xy 352.5012 -284.921452) (xy 351.561146 -284.921452)
			(xy 351.535889 -284.920875) (xy 351.486064 -284.912568) (xy 351.438286 -284.896172) (xy 351.393859 -284.872135)
			(xy 351.353994 -284.841113) (xy 351.31978 -284.803951) (xy 351.29215 -284.761665) (xy 351.271857 -284.715407)
			(xy 351.259456 -284.66644) (xy 351.255284 -284.6161) (xy 350.926399 -284.6161) (xy 350.9264 -284.616144)
			(xy 350.925905 -284.640751) (xy 350.91801 -284.689328) (xy 350.902426 -284.736009) (xy 350.879555 -284.779586)
			(xy 350.84999 -284.81893) (xy 350.814497 -284.853022) (xy 350.773994 -284.880978) (xy 350.729532 -284.902076)
			(xy 350.682261 -284.915768) (xy 350.633406 -284.9217) (xy 350.584231 -284.919719) (xy 350.536012 -284.909875)
			(xy 350.489996 -284.892423) (xy 350.447375 -284.867816) (xy 350.409254 -284.836691) (xy 350.376619 -284.799854)
			(xy 350.350316 -284.758258) (xy 350.331025 -284.712982) (xy 350.319248 -284.665198) (xy 350.315288 -284.616144)
			(xy 349.9872 -284.616144) (xy 349.983032 -284.666451) (xy 349.970629 -284.715428) (xy 349.950333 -284.761696)
			(xy 349.922699 -284.803993) (xy 349.88848 -284.841164) (xy 349.848609 -284.872195) (xy 349.804175 -284.896241)
			(xy 349.756388 -284.912645) (xy 349.706554 -284.92096) (xy 349.681292 -284.921452) (xy 348.741238 -284.921452)
			(xy 348.715982 -284.920874) (xy 348.666158 -284.912566) (xy 348.618381 -284.896169) (xy 348.573955 -284.872132)
			(xy 348.534091 -284.84111) (xy 348.499878 -284.803949) (xy 348.472249 -284.761663) (xy 348.451957 -284.715406)
			(xy 348.439556 -284.66644) (xy 348.435384 -284.6161) (xy 348.106491 -284.6161) (xy 348.106492 -284.616144)
			(xy 348.105997 -284.640751) (xy 348.098102 -284.689328) (xy 348.082518 -284.736009) (xy 348.059647 -284.779586)
			(xy 348.030082 -284.81893) (xy 347.994589 -284.853022) (xy 347.954086 -284.880978) (xy 347.909624 -284.902076)
			(xy 347.862353 -284.915768) (xy 347.813498 -284.9217) (xy 347.764323 -284.919719) (xy 347.716104 -284.909875)
			(xy 347.670088 -284.892423) (xy 347.627467 -284.867816) (xy 347.589346 -284.836691) (xy 347.556711 -284.799854)
			(xy 347.530408 -284.758258) (xy 347.511117 -284.712982) (xy 347.49934 -284.665198) (xy 347.49538 -284.616144)
			(xy 347.166972 -284.616144) (xy 347.162804 -284.666442) (xy 347.150404 -284.715412) (xy 347.130114 -284.761672)
			(xy 347.102487 -284.803963) (xy 347.068275 -284.841129) (xy 347.028414 -284.872158) (xy 346.983989 -284.896204)
			(xy 346.936213 -284.91261) (xy 346.886387 -284.920928) (xy 346.86113 -284.921452) (xy 345.921076 -284.921452)
			(xy 345.895826 -284.920841) (xy 345.846014 -284.912525) (xy 345.798251 -284.896124) (xy 345.753838 -284.872086)
			(xy 345.713987 -284.841066) (xy 345.679785 -284.80391) (xy 345.652165 -284.761632) (xy 345.63188 -284.715384)
			(xy 345.619483 -284.666428) (xy 345.615313 -284.6161) (xy 345.286789 -284.6161) (xy 345.282636 -284.666323)
			(xy 345.270291 -284.715183) (xy 345.250089 -284.761351) (xy 345.222579 -284.803574) (xy 345.188507 -284.840705)
			(xy 345.1488 -284.871736) (xy 345.104535 -284.895825) (xy 345.056915 -284.912316) (xy 345.007233 -284.920761)
			(xy 344.982038 -284.921452) (xy 344.971974 -284.921888) (xy 344.953391 -284.929624) (xy 344.94597 -284.936438)
			(xy 344.895424 -284.987238) (xy 344.888685 -284.99461) (xy 344.881103 -285.013072) (xy 344.880692 -285.023052)
			(xy 344.880692 -285.42615) (xy 345.145372 -285.42615) (xy 345.149332 -285.377096) (xy 345.161109 -285.329312)
			(xy 345.1804 -285.284036) (xy 345.206703 -285.24244) (xy 345.239338 -285.205603) (xy 345.277459 -285.174478)
			(xy 345.32008 -285.149871) (xy 345.366096 -285.132419) (xy 345.414315 -285.122575) (xy 345.46349 -285.120594)
			(xy 345.512345 -285.126526) (xy 345.559616 -285.140218) (xy 345.604078 -285.161316) (xy 345.644581 -285.189272)
			(xy 345.680074 -285.223364) (xy 345.709639 -285.262708) (xy 345.73251 -285.306285) (xy 345.748094 -285.352966)
			(xy 345.755989 -285.401543) (xy 345.756484 -285.42615) (xy 346.085426 -285.42615) (xy 346.089386 -285.377096)
			(xy 346.101163 -285.329312) (xy 346.120454 -285.284036) (xy 346.146757 -285.24244) (xy 346.179392 -285.205603)
			(xy 346.217513 -285.174478) (xy 346.260134 -285.149871) (xy 346.30615 -285.132419) (xy 346.354369 -285.122575)
			(xy 346.403544 -285.120594) (xy 346.452399 -285.126526) (xy 346.49967 -285.140218) (xy 346.544132 -285.161316)
			(xy 346.584635 -285.189272) (xy 346.620128 -285.223364) (xy 346.649693 -285.262708) (xy 346.672564 -285.306285)
			(xy 346.688148 -285.352966) (xy 346.696043 -285.401543) (xy 346.696538 -285.42615) (xy 347.025226 -285.42615)
			(xy 347.029186 -285.377096) (xy 347.040963 -285.329312) (xy 347.060254 -285.284036) (xy 347.086557 -285.24244)
			(xy 347.119192 -285.205603) (xy 347.157313 -285.174478) (xy 347.199934 -285.149871) (xy 347.24595 -285.132419)
			(xy 347.294169 -285.122575) (xy 347.343344 -285.120594) (xy 347.392199 -285.126526) (xy 347.43947 -285.140218)
			(xy 347.483932 -285.161316) (xy 347.524435 -285.189272) (xy 347.559928 -285.223364) (xy 347.589493 -285.262708)
			(xy 347.612364 -285.306285) (xy 347.627948 -285.352966) (xy 347.635843 -285.401543) (xy 347.636338 -285.42615)
			(xy 347.96528 -285.42615) (xy 347.96924 -285.377096) (xy 347.981017 -285.329312) (xy 348.000308 -285.284036)
			(xy 348.026611 -285.24244) (xy 348.059246 -285.205603) (xy 348.097367 -285.174478) (xy 348.139988 -285.149871)
			(xy 348.186004 -285.132419) (xy 348.234223 -285.122575) (xy 348.283398 -285.120594) (xy 348.332253 -285.126526)
			(xy 348.379524 -285.140218) (xy 348.423986 -285.161316) (xy 348.464489 -285.189272) (xy 348.499982 -285.223364)
			(xy 348.529547 -285.262708) (xy 348.552418 -285.306285) (xy 348.568002 -285.352966) (xy 348.575897 -285.401543)
			(xy 348.576392 -285.42615) (xy 348.905334 -285.42615) (xy 348.909294 -285.377096) (xy 348.921071 -285.329312)
			(xy 348.940362 -285.284036) (xy 348.966665 -285.24244) (xy 348.9993 -285.205603) (xy 349.037421 -285.174478)
			(xy 349.080042 -285.149871) (xy 349.126058 -285.132419) (xy 349.174277 -285.122575) (xy 349.223452 -285.120594)
			(xy 349.272307 -285.126526) (xy 349.319578 -285.140218) (xy 349.36404 -285.161316) (xy 349.404543 -285.189272)
			(xy 349.440036 -285.223364) (xy 349.469601 -285.262708) (xy 349.492472 -285.306285) (xy 349.508056 -285.352966)
			(xy 349.515951 -285.401543) (xy 349.516446 -285.42615) (xy 349.845388 -285.42615) (xy 349.849348 -285.377096)
			(xy 349.861125 -285.329312) (xy 349.880416 -285.284036) (xy 349.906719 -285.24244) (xy 349.939354 -285.205603)
			(xy 349.977475 -285.174478) (xy 350.020096 -285.149871) (xy 350.066112 -285.132419) (xy 350.114331 -285.122575)
			(xy 350.163506 -285.120594) (xy 350.212361 -285.126526) (xy 350.259632 -285.140218) (xy 350.304094 -285.161316)
			(xy 350.344597 -285.189272) (xy 350.38009 -285.223364) (xy 350.409655 -285.262708) (xy 350.432526 -285.306285)
			(xy 350.44811 -285.352966) (xy 350.456005 -285.401543) (xy 350.4565 -285.42615) (xy 350.785442 -285.42615)
			(xy 350.789402 -285.377096) (xy 350.801179 -285.329312) (xy 350.82047 -285.284036) (xy 350.846773 -285.24244)
			(xy 350.879408 -285.205603) (xy 350.917529 -285.174478) (xy 350.96015 -285.149871) (xy 351.006166 -285.132419)
			(xy 351.054385 -285.122575) (xy 351.10356 -285.120594) (xy 351.152415 -285.126526) (xy 351.199686 -285.140218)
			(xy 351.244148 -285.161316) (xy 351.284651 -285.189272) (xy 351.320144 -285.223364) (xy 351.349709 -285.262708)
			(xy 351.37258 -285.306285) (xy 351.388164 -285.352966) (xy 351.396059 -285.401543) (xy 351.396554 -285.42615)
			(xy 351.725242 -285.42615) (xy 351.729202 -285.377096) (xy 351.740979 -285.329312) (xy 351.76027 -285.284036)
			(xy 351.786573 -285.24244) (xy 351.819208 -285.205603) (xy 351.857329 -285.174478) (xy 351.89995 -285.149871)
			(xy 351.945966 -285.132419) (xy 351.994185 -285.122575) (xy 352.04336 -285.120594) (xy 352.092215 -285.126526)
			(xy 352.139486 -285.140218) (xy 352.183948 -285.161316) (xy 352.224451 -285.189272) (xy 352.259944 -285.223364)
			(xy 352.289509 -285.262708) (xy 352.31238 -285.306285) (xy 352.327964 -285.352966) (xy 352.335859 -285.401543)
			(xy 352.336354 -285.42615) (xy 352.665296 -285.42615) (xy 352.669256 -285.377096) (xy 352.681033 -285.329312)
			(xy 352.700324 -285.284036) (xy 352.726627 -285.24244) (xy 352.759262 -285.205603) (xy 352.797383 -285.174478)
			(xy 352.840004 -285.149871) (xy 352.88602 -285.132419) (xy 352.934239 -285.122575) (xy 352.983414 -285.120594)
			(xy 353.032269 -285.126526) (xy 353.07954 -285.140218) (xy 353.124002 -285.161316) (xy 353.164505 -285.189272)
			(xy 353.199998 -285.223364) (xy 353.229563 -285.262708) (xy 353.252434 -285.306285) (xy 353.268018 -285.352966)
			(xy 353.275913 -285.401543) (xy 353.276408 -285.42615) (xy 353.60535 -285.42615) (xy 353.60931 -285.377096)
			(xy 353.621087 -285.329312) (xy 353.640378 -285.284036) (xy 353.666681 -285.24244) (xy 353.699316 -285.205603)
			(xy 353.737437 -285.174478) (xy 353.780058 -285.149871) (xy 353.826074 -285.132419) (xy 353.874293 -285.122575)
			(xy 353.923468 -285.120594) (xy 353.972323 -285.126526) (xy 354.019594 -285.140218) (xy 354.064056 -285.161316)
			(xy 354.104559 -285.189272) (xy 354.140052 -285.223364) (xy 354.169617 -285.262708) (xy 354.192488 -285.306285)
			(xy 354.208072 -285.352966) (xy 354.215967 -285.401543) (xy 354.216462 -285.42615) (xy 354.545404 -285.42615)
			(xy 354.549364 -285.377096) (xy 354.561141 -285.329312) (xy 354.580432 -285.284036) (xy 354.606735 -285.24244)
			(xy 354.63937 -285.205603) (xy 354.677491 -285.174478) (xy 354.720112 -285.149871) (xy 354.766128 -285.132419)
			(xy 354.814347 -285.122575) (xy 354.863522 -285.120594) (xy 354.912377 -285.126526) (xy 354.959648 -285.140218)
			(xy 355.00411 -285.161316) (xy 355.044613 -285.189272) (xy 355.080106 -285.223364) (xy 355.109671 -285.262708)
			(xy 355.132542 -285.306285) (xy 355.148126 -285.352966) (xy 355.156021 -285.401543) (xy 355.156516 -285.42615)
			(xy 355.485204 -285.42615) (xy 355.489164 -285.377096) (xy 355.500941 -285.329312) (xy 355.520232 -285.284036)
			(xy 355.546535 -285.24244) (xy 355.57917 -285.205603) (xy 355.617291 -285.174478) (xy 355.659912 -285.149871)
			(xy 355.705928 -285.132419) (xy 355.754147 -285.122575) (xy 355.803322 -285.120594) (xy 355.852177 -285.126526)
			(xy 355.899448 -285.140218) (xy 355.94391 -285.161316) (xy 355.984413 -285.189272) (xy 356.019906 -285.223364)
			(xy 356.049471 -285.262708) (xy 356.072342 -285.306285) (xy 356.087926 -285.352966) (xy 356.095821 -285.401543)
			(xy 356.096315 -285.4261) (xy 356.425064 -285.4261) (xy 356.429238 -285.375732) (xy 356.441644 -285.326738)
			(xy 356.461944 -285.280454) (xy 356.489585 -285.238142) (xy 356.523813 -285.200956) (xy 356.563694 -285.16991)
			(xy 356.608141 -285.145852) (xy 356.655942 -285.129437) (xy 356.705792 -285.121113) (xy 356.731062 -285.120588)
			(xy 357.671116 -285.120588) (xy 357.696396 -285.121011) (xy 357.746265 -285.129335) (xy 357.794084 -285.145754)
			(xy 357.838549 -285.169819) (xy 357.878446 -285.200875) (xy 357.912688 -285.238073) (xy 357.940341 -285.2804)
			(xy 357.960649 -285.326701) (xy 357.97306 -285.375713) (xy 357.977236 -285.4261) (xy 357.977232 -285.42615)
			(xy 358.305366 -285.42615) (xy 358.309326 -285.377096) (xy 358.321103 -285.329312) (xy 358.340394 -285.284036)
			(xy 358.366697 -285.24244) (xy 358.399332 -285.205603) (xy 358.437453 -285.174478) (xy 358.480074 -285.149871)
			(xy 358.52609 -285.132419) (xy 358.574309 -285.122575) (xy 358.623484 -285.120594) (xy 358.672339 -285.126526)
			(xy 358.71961 -285.140218) (xy 358.764072 -285.161316) (xy 358.804575 -285.189272) (xy 358.840068 -285.223364)
			(xy 358.869633 -285.262708) (xy 358.892504 -285.306285) (xy 358.908088 -285.352966) (xy 358.915983 -285.401543)
			(xy 358.916478 -285.42615) (xy 361.118924 -285.42615) (xy 361.122884 -285.377096) (xy 361.134661 -285.329312)
			(xy 361.153952 -285.284036) (xy 361.180255 -285.24244) (xy 361.21289 -285.205603) (xy 361.251011 -285.174478)
			(xy 361.293632 -285.149871) (xy 361.339648 -285.132419) (xy 361.387867 -285.122575) (xy 361.437042 -285.120594)
			(xy 361.485897 -285.126526) (xy 361.533168 -285.140218) (xy 361.57763 -285.161316) (xy 361.618133 -285.189272)
			(xy 361.653626 -285.223364) (xy 361.683191 -285.262708) (xy 361.706062 -285.306285) (xy 361.721646 -285.352966)
			(xy 361.729541 -285.401543) (xy 361.730035 -285.4261) (xy 362.058764 -285.4261) (xy 362.062938 -285.37573)
			(xy 362.075345 -285.326734) (xy 362.095647 -285.280448) (xy 362.12329 -285.238135) (xy 362.157521 -285.200949)
			(xy 362.197405 -285.169904) (xy 362.241855 -285.145846) (xy 362.289658 -285.129433) (xy 362.339511 -285.121111)
			(xy 362.364782 -285.120588) (xy 363.304836 -285.120588) (xy 363.330115 -285.121013) (xy 363.379981 -285.12934)
			(xy 363.427798 -285.14576) (xy 363.472259 -285.169826) (xy 363.512154 -285.200882) (xy 363.546393 -285.23808)
			(xy 363.574044 -285.280406) (xy 363.594351 -285.326705) (xy 363.606761 -285.375716) (xy 363.610936 -285.4261)
			(xy 363.610932 -285.42615) (xy 363.939086 -285.42615) (xy 363.943046 -285.377096) (xy 363.954823 -285.329312)
			(xy 363.974114 -285.284036) (xy 364.000417 -285.24244) (xy 364.033052 -285.205603) (xy 364.071173 -285.174478)
			(xy 364.113794 -285.149871) (xy 364.15981 -285.132419) (xy 364.208029 -285.122575) (xy 364.257204 -285.120594)
			(xy 364.306059 -285.126526) (xy 364.35333 -285.140218) (xy 364.397792 -285.161316) (xy 364.438295 -285.189272)
			(xy 364.473788 -285.223364) (xy 364.503353 -285.262708) (xy 364.526224 -285.306285) (xy 364.541808 -285.352966)
			(xy 364.549703 -285.401543) (xy 364.550198 -285.42615) (xy 364.878886 -285.42615) (xy 364.882846 -285.377096)
			(xy 364.894623 -285.329312) (xy 364.913914 -285.284036) (xy 364.940217 -285.24244) (xy 364.972852 -285.205603)
			(xy 365.010973 -285.174478) (xy 365.053594 -285.149871) (xy 365.09961 -285.132419) (xy 365.147829 -285.122575)
			(xy 365.197004 -285.120594) (xy 365.245859 -285.126526) (xy 365.29313 -285.140218) (xy 365.337592 -285.161316)
			(xy 365.378095 -285.189272) (xy 365.413588 -285.223364) (xy 365.443153 -285.262708) (xy 365.466024 -285.306285)
			(xy 365.481608 -285.352966) (xy 365.489503 -285.401543) (xy 365.489998 -285.42615) (xy 365.81894 -285.42615)
			(xy 365.8229 -285.377096) (xy 365.834677 -285.329312) (xy 365.853968 -285.284036) (xy 365.880271 -285.24244)
			(xy 365.912906 -285.205603) (xy 365.951027 -285.174478) (xy 365.993648 -285.149871) (xy 366.039664 -285.132419)
			(xy 366.087883 -285.122575) (xy 366.137058 -285.120594) (xy 366.185913 -285.126526) (xy 366.233184 -285.140218)
			(xy 366.277646 -285.161316) (xy 366.318149 -285.189272) (xy 366.353642 -285.223364) (xy 366.383207 -285.262708)
			(xy 366.406078 -285.306285) (xy 366.421662 -285.352966) (xy 366.429557 -285.401543) (xy 366.430052 -285.42615)
			(xy 366.758994 -285.42615) (xy 366.762954 -285.377096) (xy 366.774731 -285.329312) (xy 366.794022 -285.284036)
			(xy 366.820325 -285.24244) (xy 366.85296 -285.205603) (xy 366.891081 -285.174478) (xy 366.933702 -285.149871)
			(xy 366.979718 -285.132419) (xy 367.027937 -285.122575) (xy 367.077112 -285.120594) (xy 367.125967 -285.126526)
			(xy 367.173238 -285.140218) (xy 367.2177 -285.161316) (xy 367.258203 -285.189272) (xy 367.293696 -285.223364)
			(xy 367.323261 -285.262708) (xy 367.346132 -285.306285) (xy 367.361716 -285.352966) (xy 367.369611 -285.401543)
			(xy 367.370106 -285.42615) (xy 367.699048 -285.42615) (xy 367.703008 -285.377096) (xy 367.714785 -285.329312)
			(xy 367.734076 -285.284036) (xy 367.760379 -285.24244) (xy 367.793014 -285.205603) (xy 367.831135 -285.174478)
			(xy 367.873756 -285.149871) (xy 367.919772 -285.132419) (xy 367.967991 -285.122575) (xy 368.017166 -285.120594)
			(xy 368.066021 -285.126526) (xy 368.113292 -285.140218) (xy 368.157754 -285.161316) (xy 368.198257 -285.189272)
			(xy 368.23375 -285.223364) (xy 368.263315 -285.262708) (xy 368.286186 -285.306285) (xy 368.30177 -285.352966)
			(xy 368.309665 -285.401543) (xy 368.31016 -285.42615) (xy 368.639102 -285.42615) (xy 368.643062 -285.377096)
			(xy 368.654839 -285.329312) (xy 368.67413 -285.284036) (xy 368.700433 -285.24244) (xy 368.733068 -285.205603)
			(xy 368.771189 -285.174478) (xy 368.81381 -285.149871) (xy 368.859826 -285.132419) (xy 368.908045 -285.122575)
			(xy 368.95722 -285.120594) (xy 369.006075 -285.126526) (xy 369.053346 -285.140218) (xy 369.097808 -285.161316)
			(xy 369.138311 -285.189272) (xy 369.173804 -285.223364) (xy 369.203369 -285.262708) (xy 369.22624 -285.306285)
			(xy 369.241824 -285.352966) (xy 369.249719 -285.401543) (xy 369.250214 -285.42615) (xy 369.578902 -285.42615)
			(xy 369.582862 -285.377096) (xy 369.594639 -285.329312) (xy 369.61393 -285.284036) (xy 369.640233 -285.24244)
			(xy 369.672868 -285.205603) (xy 369.710989 -285.174478) (xy 369.75361 -285.149871) (xy 369.799626 -285.132419)
			(xy 369.847845 -285.122575) (xy 369.89702 -285.120594) (xy 369.945875 -285.126526) (xy 369.993146 -285.140218)
			(xy 370.037608 -285.161316) (xy 370.078111 -285.189272) (xy 370.113604 -285.223364) (xy 370.143169 -285.262708)
			(xy 370.16604 -285.306285) (xy 370.181624 -285.352966) (xy 370.189519 -285.401543) (xy 370.190014 -285.42615)
			(xy 370.518956 -285.42615) (xy 370.522916 -285.377096) (xy 370.534693 -285.329312) (xy 370.553984 -285.284036)
			(xy 370.580287 -285.24244) (xy 370.612922 -285.205603) (xy 370.651043 -285.174478) (xy 370.693664 -285.149871)
			(xy 370.73968 -285.132419) (xy 370.787899 -285.122575) (xy 370.837074 -285.120594) (xy 370.885929 -285.126526)
			(xy 370.9332 -285.140218) (xy 370.977662 -285.161316) (xy 371.018165 -285.189272) (xy 371.053658 -285.223364)
			(xy 371.083223 -285.262708) (xy 371.106094 -285.306285) (xy 371.121678 -285.352966) (xy 371.129573 -285.401543)
			(xy 371.130068 -285.42615) (xy 371.45901 -285.42615) (xy 371.46297 -285.377096) (xy 371.474747 -285.329312)
			(xy 371.494038 -285.284036) (xy 371.520341 -285.24244) (xy 371.552976 -285.205603) (xy 371.591097 -285.174478)
			(xy 371.633718 -285.149871) (xy 371.679734 -285.132419) (xy 371.727953 -285.122575) (xy 371.777128 -285.120594)
			(xy 371.825983 -285.126526) (xy 371.873254 -285.140218) (xy 371.917716 -285.161316) (xy 371.958219 -285.189272)
			(xy 371.993712 -285.223364) (xy 372.023277 -285.262708) (xy 372.046148 -285.306285) (xy 372.061732 -285.352966)
			(xy 372.069627 -285.401543) (xy 372.070122 -285.42615) (xy 372.399064 -285.42615) (xy 372.403024 -285.377096)
			(xy 372.414801 -285.329312) (xy 372.434092 -285.284036) (xy 372.460395 -285.24244) (xy 372.49303 -285.205603)
			(xy 372.531151 -285.174478) (xy 372.573772 -285.149871) (xy 372.619788 -285.132419) (xy 372.668007 -285.122575)
			(xy 372.717182 -285.120594) (xy 372.766037 -285.126526) (xy 372.813308 -285.140218) (xy 372.85777 -285.161316)
			(xy 372.898273 -285.189272) (xy 372.933766 -285.223364) (xy 372.963331 -285.262708) (xy 372.986202 -285.306285)
			(xy 373.001786 -285.352966) (xy 373.009681 -285.401543) (xy 373.010176 -285.42615) (xy 373.339118 -285.42615)
			(xy 373.343078 -285.377096) (xy 373.354855 -285.329312) (xy 373.374146 -285.284036) (xy 373.400449 -285.24244)
			(xy 373.433084 -285.205603) (xy 373.471205 -285.174478) (xy 373.513826 -285.149871) (xy 373.559842 -285.132419)
			(xy 373.608061 -285.122575) (xy 373.657236 -285.120594) (xy 373.706091 -285.126526) (xy 373.753362 -285.140218)
			(xy 373.797824 -285.161316) (xy 373.838327 -285.189272) (xy 373.87382 -285.223364) (xy 373.903385 -285.262708)
			(xy 373.926256 -285.306285) (xy 373.94184 -285.352966) (xy 373.949735 -285.401543) (xy 373.95023 -285.42615)
			(xy 373.949735 -285.450757) (xy 373.94184 -285.499334) (xy 373.926256 -285.546015) (xy 373.903385 -285.589592)
			(xy 373.87382 -285.628936) (xy 373.838327 -285.663028) (xy 373.797824 -285.690984) (xy 373.753362 -285.712082)
			(xy 373.706091 -285.725774) (xy 373.657236 -285.731706) (xy 373.608061 -285.729725) (xy 373.559842 -285.719881)
			(xy 373.513826 -285.702429) (xy 373.471205 -285.677822) (xy 373.433084 -285.646697) (xy 373.400449 -285.60986)
			(xy 373.374146 -285.568264) (xy 373.354855 -285.522988) (xy 373.343078 -285.475204) (xy 373.339118 -285.42615)
			(xy 373.010176 -285.42615) (xy 373.009681 -285.450757) (xy 373.001786 -285.499334) (xy 372.986202 -285.546015)
			(xy 372.963331 -285.589592) (xy 372.933766 -285.628936) (xy 372.898273 -285.663028) (xy 372.85777 -285.690984)
			(xy 372.813308 -285.712082) (xy 372.766037 -285.725774) (xy 372.717182 -285.731706) (xy 372.668007 -285.729725)
			(xy 372.619788 -285.719881) (xy 372.573772 -285.702429) (xy 372.531151 -285.677822) (xy 372.49303 -285.646697)
			(xy 372.460395 -285.60986) (xy 372.434092 -285.568264) (xy 372.414801 -285.522988) (xy 372.403024 -285.475204)
			(xy 372.399064 -285.42615) (xy 372.070122 -285.42615) (xy 372.069627 -285.450757) (xy 372.061732 -285.499334)
			(xy 372.046148 -285.546015) (xy 372.023277 -285.589592) (xy 371.993712 -285.628936) (xy 371.958219 -285.663028)
			(xy 371.917716 -285.690984) (xy 371.873254 -285.712082) (xy 371.825983 -285.725774) (xy 371.777128 -285.731706)
			(xy 371.727953 -285.729725) (xy 371.679734 -285.719881) (xy 371.633718 -285.702429) (xy 371.591097 -285.677822)
			(xy 371.552976 -285.646697) (xy 371.520341 -285.60986) (xy 371.494038 -285.568264) (xy 371.474747 -285.522988)
			(xy 371.46297 -285.475204) (xy 371.45901 -285.42615) (xy 371.130068 -285.42615) (xy 371.129573 -285.450757)
			(xy 371.121678 -285.499334) (xy 371.106094 -285.546015) (xy 371.083223 -285.589592) (xy 371.053658 -285.628936)
			(xy 371.018165 -285.663028) (xy 370.977662 -285.690984) (xy 370.9332 -285.712082) (xy 370.885929 -285.725774)
			(xy 370.837074 -285.731706) (xy 370.787899 -285.729725) (xy 370.73968 -285.719881) (xy 370.693664 -285.702429)
			(xy 370.651043 -285.677822) (xy 370.612922 -285.646697) (xy 370.580287 -285.60986) (xy 370.553984 -285.568264)
			(xy 370.534693 -285.522988) (xy 370.522916 -285.475204) (xy 370.518956 -285.42615) (xy 370.190014 -285.42615)
			(xy 370.189519 -285.450757) (xy 370.181624 -285.499334) (xy 370.16604 -285.546015) (xy 370.143169 -285.589592)
			(xy 370.113604 -285.628936) (xy 370.078111 -285.663028) (xy 370.037608 -285.690984) (xy 369.993146 -285.712082)
			(xy 369.945875 -285.725774) (xy 369.89702 -285.731706) (xy 369.847845 -285.729725) (xy 369.799626 -285.719881)
			(xy 369.75361 -285.702429) (xy 369.710989 -285.677822) (xy 369.672868 -285.646697) (xy 369.640233 -285.60986)
			(xy 369.61393 -285.568264) (xy 369.594639 -285.522988) (xy 369.582862 -285.475204) (xy 369.578902 -285.42615)
			(xy 369.250214 -285.42615) (xy 369.249719 -285.450757) (xy 369.241824 -285.499334) (xy 369.22624 -285.546015)
			(xy 369.203369 -285.589592) (xy 369.173804 -285.628936) (xy 369.138311 -285.663028) (xy 369.097808 -285.690984)
			(xy 369.053346 -285.712082) (xy 369.006075 -285.725774) (xy 368.95722 -285.731706) (xy 368.908045 -285.729725)
			(xy 368.859826 -285.719881) (xy 368.81381 -285.702429) (xy 368.771189 -285.677822) (xy 368.733068 -285.646697)
			(xy 368.700433 -285.60986) (xy 368.67413 -285.568264) (xy 368.654839 -285.522988) (xy 368.643062 -285.475204)
			(xy 368.639102 -285.42615) (xy 368.31016 -285.42615) (xy 368.309665 -285.450757) (xy 368.30177 -285.499334)
			(xy 368.286186 -285.546015) (xy 368.263315 -285.589592) (xy 368.23375 -285.628936) (xy 368.198257 -285.663028)
			(xy 368.157754 -285.690984) (xy 368.113292 -285.712082) (xy 368.066021 -285.725774) (xy 368.017166 -285.731706)
			(xy 367.967991 -285.729725) (xy 367.919772 -285.719881) (xy 367.873756 -285.702429) (xy 367.831135 -285.677822)
			(xy 367.793014 -285.646697) (xy 367.760379 -285.60986) (xy 367.734076 -285.568264) (xy 367.714785 -285.522988)
			(xy 367.703008 -285.475204) (xy 367.699048 -285.42615) (xy 367.370106 -285.42615) (xy 367.369611 -285.450757)
			(xy 367.361716 -285.499334) (xy 367.346132 -285.546015) (xy 367.323261 -285.589592) (xy 367.293696 -285.628936)
			(xy 367.258203 -285.663028) (xy 367.2177 -285.690984) (xy 367.173238 -285.712082) (xy 367.125967 -285.725774)
			(xy 367.077112 -285.731706) (xy 367.027937 -285.729725) (xy 366.979718 -285.719881) (xy 366.933702 -285.702429)
			(xy 366.891081 -285.677822) (xy 366.85296 -285.646697) (xy 366.820325 -285.60986) (xy 366.794022 -285.568264)
			(xy 366.774731 -285.522988) (xy 366.762954 -285.475204) (xy 366.758994 -285.42615) (xy 366.430052 -285.42615)
			(xy 366.429557 -285.450757) (xy 366.421662 -285.499334) (xy 366.406078 -285.546015) (xy 366.383207 -285.589592)
			(xy 366.353642 -285.628936) (xy 366.318149 -285.663028) (xy 366.277646 -285.690984) (xy 366.233184 -285.712082)
			(xy 366.185913 -285.725774) (xy 366.137058 -285.731706) (xy 366.087883 -285.729725) (xy 366.039664 -285.719881)
			(xy 365.993648 -285.702429) (xy 365.951027 -285.677822) (xy 365.912906 -285.646697) (xy 365.880271 -285.60986)
			(xy 365.853968 -285.568264) (xy 365.834677 -285.522988) (xy 365.8229 -285.475204) (xy 365.81894 -285.42615)
			(xy 365.489998 -285.42615) (xy 365.489503 -285.450757) (xy 365.481608 -285.499334) (xy 365.466024 -285.546015)
			(xy 365.443153 -285.589592) (xy 365.413588 -285.628936) (xy 365.378095 -285.663028) (xy 365.337592 -285.690984)
			(xy 365.29313 -285.712082) (xy 365.245859 -285.725774) (xy 365.197004 -285.731706) (xy 365.147829 -285.729725)
			(xy 365.09961 -285.719881) (xy 365.053594 -285.702429) (xy 365.010973 -285.677822) (xy 364.972852 -285.646697)
			(xy 364.940217 -285.60986) (xy 364.913914 -285.568264) (xy 364.894623 -285.522988) (xy 364.882846 -285.475204)
			(xy 364.878886 -285.42615) (xy 364.550198 -285.42615) (xy 364.549703 -285.450757) (xy 364.541808 -285.499334)
			(xy 364.526224 -285.546015) (xy 364.503353 -285.589592) (xy 364.473788 -285.628936) (xy 364.438295 -285.663028)
			(xy 364.397792 -285.690984) (xy 364.35333 -285.712082) (xy 364.306059 -285.725774) (xy 364.257204 -285.731706)
			(xy 364.208029 -285.729725) (xy 364.15981 -285.719881) (xy 364.113794 -285.702429) (xy 364.071173 -285.677822)
			(xy 364.033052 -285.646697) (xy 364.000417 -285.60986) (xy 363.974114 -285.568264) (xy 363.954823 -285.522988)
			(xy 363.943046 -285.475204) (xy 363.939086 -285.42615) (xy 363.610932 -285.42615) (xy 363.606761 -285.476485)
			(xy 363.594351 -285.525495) (xy 363.574044 -285.571794) (xy 363.546393 -285.61412) (xy 363.512154 -285.651318)
			(xy 363.472259 -285.682374) (xy 363.427798 -285.70644) (xy 363.379981 -285.72286) (xy 363.330115 -285.731187)
			(xy 363.304836 -285.731712) (xy 362.364782 -285.731712) (xy 362.339511 -285.731089) (xy 362.289658 -285.722767)
			(xy 362.241855 -285.706354) (xy 362.197405 -285.682296) (xy 362.157521 -285.651251) (xy 362.12329 -285.614065)
			(xy 362.095647 -285.571752) (xy 362.075345 -285.525466) (xy 362.062938 -285.47647) (xy 362.058764 -285.4261)
			(xy 361.730035 -285.4261) (xy 361.730036 -285.42615) (xy 361.729541 -285.450757) (xy 361.721646 -285.499334)
			(xy 361.706062 -285.546015) (xy 361.683191 -285.589592) (xy 361.653626 -285.628936) (xy 361.618133 -285.663028)
			(xy 361.57763 -285.690984) (xy 361.533168 -285.712082) (xy 361.485897 -285.725774) (xy 361.437042 -285.731706)
			(xy 361.387867 -285.729725) (xy 361.339648 -285.719881) (xy 361.293632 -285.702429) (xy 361.251011 -285.677822)
			(xy 361.21289 -285.646697) (xy 361.180255 -285.60986) (xy 361.153952 -285.568264) (xy 361.134661 -285.522988)
			(xy 361.122884 -285.475204) (xy 361.118924 -285.42615) (xy 358.916478 -285.42615) (xy 358.915983 -285.450757)
			(xy 358.908088 -285.499334) (xy 358.892504 -285.546015) (xy 358.869633 -285.589592) (xy 358.840068 -285.628936)
			(xy 358.804575 -285.663028) (xy 358.764072 -285.690984) (xy 358.71961 -285.712082) (xy 358.672339 -285.725774)
			(xy 358.623484 -285.731706) (xy 358.574309 -285.729725) (xy 358.52609 -285.719881) (xy 358.480074 -285.702429)
			(xy 358.437453 -285.677822) (xy 358.399332 -285.646697) (xy 358.366697 -285.60986) (xy 358.340394 -285.568264)
			(xy 358.321103 -285.522988) (xy 358.309326 -285.475204) (xy 358.305366 -285.42615) (xy 357.977232 -285.42615)
			(xy 357.97306 -285.476487) (xy 357.960649 -285.525499) (xy 357.940341 -285.5718) (xy 357.912688 -285.614127)
			(xy 357.878446 -285.651325) (xy 357.838549 -285.682381) (xy 357.794084 -285.706446) (xy 357.746265 -285.722865)
			(xy 357.696396 -285.731189) (xy 357.671116 -285.731712) (xy 356.731062 -285.731712) (xy 356.705792 -285.731087)
			(xy 356.655942 -285.722763) (xy 356.608141 -285.706348) (xy 356.563694 -285.68229) (xy 356.523813 -285.651244)
			(xy 356.489585 -285.614058) (xy 356.461944 -285.571746) (xy 356.441644 -285.525462) (xy 356.429238 -285.476468)
			(xy 356.425064 -285.4261) (xy 356.096315 -285.4261) (xy 356.096316 -285.42615) (xy 356.095821 -285.450757)
			(xy 356.087926 -285.499334) (xy 356.072342 -285.546015) (xy 356.049471 -285.589592) (xy 356.019906 -285.628936)
			(xy 355.984413 -285.663028) (xy 355.94391 -285.690984) (xy 355.899448 -285.712082) (xy 355.852177 -285.725774)
			(xy 355.803322 -285.731706) (xy 355.754147 -285.729725) (xy 355.705928 -285.719881) (xy 355.659912 -285.702429)
			(xy 355.617291 -285.677822) (xy 355.57917 -285.646697) (xy 355.546535 -285.60986) (xy 355.520232 -285.568264)
			(xy 355.500941 -285.522988) (xy 355.489164 -285.475204) (xy 355.485204 -285.42615) (xy 355.156516 -285.42615)
			(xy 355.156021 -285.450757) (xy 355.148126 -285.499334) (xy 355.132542 -285.546015) (xy 355.109671 -285.589592)
			(xy 355.080106 -285.628936) (xy 355.044613 -285.663028) (xy 355.00411 -285.690984) (xy 354.959648 -285.712082)
			(xy 354.912377 -285.725774) (xy 354.863522 -285.731706) (xy 354.814347 -285.729725) (xy 354.766128 -285.719881)
			(xy 354.720112 -285.702429) (xy 354.677491 -285.677822) (xy 354.63937 -285.646697) (xy 354.606735 -285.60986)
			(xy 354.580432 -285.568264) (xy 354.561141 -285.522988) (xy 354.549364 -285.475204) (xy 354.545404 -285.42615)
			(xy 354.216462 -285.42615) (xy 354.215967 -285.450757) (xy 354.208072 -285.499334) (xy 354.192488 -285.546015)
			(xy 354.169617 -285.589592) (xy 354.140052 -285.628936) (xy 354.104559 -285.663028) (xy 354.064056 -285.690984)
			(xy 354.019594 -285.712082) (xy 353.972323 -285.725774) (xy 353.923468 -285.731706) (xy 353.874293 -285.729725)
			(xy 353.826074 -285.719881) (xy 353.780058 -285.702429) (xy 353.737437 -285.677822) (xy 353.699316 -285.646697)
			(xy 353.666681 -285.60986) (xy 353.640378 -285.568264) (xy 353.621087 -285.522988) (xy 353.60931 -285.475204)
			(xy 353.60535 -285.42615) (xy 353.276408 -285.42615) (xy 353.275913 -285.450757) (xy 353.268018 -285.499334)
			(xy 353.252434 -285.546015) (xy 353.229563 -285.589592) (xy 353.199998 -285.628936) (xy 353.164505 -285.663028)
			(xy 353.124002 -285.690984) (xy 353.07954 -285.712082) (xy 353.032269 -285.725774) (xy 352.983414 -285.731706)
			(xy 352.934239 -285.729725) (xy 352.88602 -285.719881) (xy 352.840004 -285.702429) (xy 352.797383 -285.677822)
			(xy 352.759262 -285.646697) (xy 352.726627 -285.60986) (xy 352.700324 -285.568264) (xy 352.681033 -285.522988)
			(xy 352.669256 -285.475204) (xy 352.665296 -285.42615) (xy 352.336354 -285.42615) (xy 352.335859 -285.450757)
			(xy 352.327964 -285.499334) (xy 352.31238 -285.546015) (xy 352.289509 -285.589592) (xy 352.259944 -285.628936)
			(xy 352.224451 -285.663028) (xy 352.183948 -285.690984) (xy 352.139486 -285.712082) (xy 352.092215 -285.725774)
			(xy 352.04336 -285.731706) (xy 351.994185 -285.729725) (xy 351.945966 -285.719881) (xy 351.89995 -285.702429)
			(xy 351.857329 -285.677822) (xy 351.819208 -285.646697) (xy 351.786573 -285.60986) (xy 351.76027 -285.568264)
			(xy 351.740979 -285.522988) (xy 351.729202 -285.475204) (xy 351.725242 -285.42615) (xy 351.396554 -285.42615)
			(xy 351.396059 -285.450757) (xy 351.388164 -285.499334) (xy 351.37258 -285.546015) (xy 351.349709 -285.589592)
			(xy 351.320144 -285.628936) (xy 351.284651 -285.663028) (xy 351.244148 -285.690984) (xy 351.199686 -285.712082)
			(xy 351.152415 -285.725774) (xy 351.10356 -285.731706) (xy 351.054385 -285.729725) (xy 351.006166 -285.719881)
			(xy 350.96015 -285.702429) (xy 350.917529 -285.677822) (xy 350.879408 -285.646697) (xy 350.846773 -285.60986)
			(xy 350.82047 -285.568264) (xy 350.801179 -285.522988) (xy 350.789402 -285.475204) (xy 350.785442 -285.42615)
			(xy 350.4565 -285.42615) (xy 350.456005 -285.450757) (xy 350.44811 -285.499334) (xy 350.432526 -285.546015)
			(xy 350.409655 -285.589592) (xy 350.38009 -285.628936) (xy 350.344597 -285.663028) (xy 350.304094 -285.690984)
			(xy 350.259632 -285.712082) (xy 350.212361 -285.725774) (xy 350.163506 -285.731706) (xy 350.114331 -285.729725)
			(xy 350.066112 -285.719881) (xy 350.020096 -285.702429) (xy 349.977475 -285.677822) (xy 349.939354 -285.646697)
			(xy 349.906719 -285.60986) (xy 349.880416 -285.568264) (xy 349.861125 -285.522988) (xy 349.849348 -285.475204)
			(xy 349.845388 -285.42615) (xy 349.516446 -285.42615) (xy 349.515951 -285.450757) (xy 349.508056 -285.499334)
			(xy 349.492472 -285.546015) (xy 349.469601 -285.589592) (xy 349.440036 -285.628936) (xy 349.404543 -285.663028)
			(xy 349.36404 -285.690984) (xy 349.319578 -285.712082) (xy 349.272307 -285.725774) (xy 349.223452 -285.731706)
			(xy 349.174277 -285.729725) (xy 349.126058 -285.719881) (xy 349.080042 -285.702429) (xy 349.037421 -285.677822)
			(xy 348.9993 -285.646697) (xy 348.966665 -285.60986) (xy 348.940362 -285.568264) (xy 348.921071 -285.522988)
			(xy 348.909294 -285.475204) (xy 348.905334 -285.42615) (xy 348.576392 -285.42615) (xy 348.575897 -285.450757)
			(xy 348.568002 -285.499334) (xy 348.552418 -285.546015) (xy 348.529547 -285.589592) (xy 348.499982 -285.628936)
			(xy 348.464489 -285.663028) (xy 348.423986 -285.690984) (xy 348.379524 -285.712082) (xy 348.332253 -285.725774)
			(xy 348.283398 -285.731706) (xy 348.234223 -285.729725) (xy 348.186004 -285.719881) (xy 348.139988 -285.702429)
			(xy 348.097367 -285.677822) (xy 348.059246 -285.646697) (xy 348.026611 -285.60986) (xy 348.000308 -285.568264)
			(xy 347.981017 -285.522988) (xy 347.96924 -285.475204) (xy 347.96528 -285.42615) (xy 347.636338 -285.42615)
			(xy 347.635843 -285.450757) (xy 347.627948 -285.499334) (xy 347.612364 -285.546015) (xy 347.589493 -285.589592)
			(xy 347.559928 -285.628936) (xy 347.524435 -285.663028) (xy 347.483932 -285.690984) (xy 347.43947 -285.712082)
			(xy 347.392199 -285.725774) (xy 347.343344 -285.731706) (xy 347.294169 -285.729725) (xy 347.24595 -285.719881)
			(xy 347.199934 -285.702429) (xy 347.157313 -285.677822) (xy 347.119192 -285.646697) (xy 347.086557 -285.60986)
			(xy 347.060254 -285.568264) (xy 347.040963 -285.522988) (xy 347.029186 -285.475204) (xy 347.025226 -285.42615)
			(xy 346.696538 -285.42615) (xy 346.696043 -285.450757) (xy 346.688148 -285.499334) (xy 346.672564 -285.546015)
			(xy 346.649693 -285.589592) (xy 346.620128 -285.628936) (xy 346.584635 -285.663028) (xy 346.544132 -285.690984)
			(xy 346.49967 -285.712082) (xy 346.452399 -285.725774) (xy 346.403544 -285.731706) (xy 346.354369 -285.729725)
			(xy 346.30615 -285.719881) (xy 346.260134 -285.702429) (xy 346.217513 -285.677822) (xy 346.179392 -285.646697)
			(xy 346.146757 -285.60986) (xy 346.120454 -285.568264) (xy 346.101163 -285.522988) (xy 346.089386 -285.475204)
			(xy 346.085426 -285.42615) (xy 345.756484 -285.42615) (xy 345.755989 -285.450757) (xy 345.748094 -285.499334)
			(xy 345.73251 -285.546015) (xy 345.709639 -285.589592) (xy 345.680074 -285.628936) (xy 345.644581 -285.663028)
			(xy 345.604078 -285.690984) (xy 345.559616 -285.712082) (xy 345.512345 -285.725774) (xy 345.46349 -285.731706)
			(xy 345.414315 -285.729725) (xy 345.366096 -285.719881) (xy 345.32008 -285.702429) (xy 345.277459 -285.677822)
			(xy 345.239338 -285.646697) (xy 345.206703 -285.60986) (xy 345.1804 -285.568264) (xy 345.161109 -285.522988)
			(xy 345.149332 -285.475204) (xy 345.145372 -285.42615) (xy 344.880692 -285.42615) (xy 344.880692 -285.829248)
			(xy 344.881175 -285.839212) (xy 344.888757 -285.857642) (xy 344.895424 -285.865062) (xy 344.94597 -285.915862)
			(xy 344.95337 -285.922702) (xy 344.971969 -285.930416) (xy 344.982038 -285.930848) (xy 345.007241 -285.93145)
			(xy 345.056937 -285.939899) (xy 345.104571 -285.956394) (xy 345.148848 -285.98049) (xy 345.188567 -286.01153)
			(xy 345.222649 -286.048672) (xy 345.250167 -286.090907) (xy 345.270375 -286.137089) (xy 345.282723 -286.185962)
			(xy 345.286877 -286.2362) (xy 345.615224 -286.2362) (xy 345.619396 -286.185857) (xy 345.631796 -286.136887)
			(xy 345.652087 -286.090626) (xy 345.679715 -286.048335) (xy 345.713927 -286.011169) (xy 345.753789 -285.98014)
			(xy 345.798215 -285.956094) (xy 345.845992 -285.939689) (xy 345.895818 -285.931371) (xy 345.921076 -285.930848)
			(xy 346.86113 -285.930848) (xy 346.88638 -285.93146) (xy 346.936191 -285.939776) (xy 346.983954 -285.956177)
			(xy 347.028366 -285.980216) (xy 347.068216 -286.011236) (xy 347.102417 -286.048392) (xy 347.130036 -286.09067)
			(xy 347.150321 -286.136917) (xy 347.162717 -286.185872) (xy 347.166883 -286.236156) (xy 347.49538 -286.236156)
			(xy 347.49934 -286.187102) (xy 347.511117 -286.139318) (xy 347.530408 -286.094042) (xy 347.556711 -286.052446)
			(xy 347.589346 -286.015609) (xy 347.627467 -285.984484) (xy 347.670088 -285.959877) (xy 347.716104 -285.942425)
			(xy 347.764323 -285.932581) (xy 347.813498 -285.9306) (xy 347.862353 -285.936532) (xy 347.909624 -285.950224)
			(xy 347.954086 -285.971322) (xy 347.994589 -285.999278) (xy 348.030082 -286.03337) (xy 348.059647 -286.072714)
			(xy 348.082518 -286.116291) (xy 348.098102 -286.162972) (xy 348.105997 -286.211549) (xy 348.106492 -286.236156)
			(xy 348.106491 -286.2362) (xy 348.435296 -286.2362) (xy 348.439469 -286.185846) (xy 348.451873 -286.136866)
			(xy 348.472171 -286.090595) (xy 348.499809 -286.048297) (xy 348.534032 -286.011126) (xy 348.573906 -285.980094)
			(xy 348.618345 -285.95605) (xy 348.666136 -285.939649) (xy 348.715975 -285.931338) (xy 348.741238 -285.930848)
			(xy 349.681292 -285.930848) (xy 349.706547 -285.931428) (xy 349.756367 -285.93974) (xy 349.804139 -285.956139)
			(xy 349.848561 -285.980178) (xy 349.88842 -286.011201) (xy 349.92263 -286.048361) (xy 349.950256 -286.090645)
			(xy 349.970545 -286.1369) (xy 349.982945 -286.185864) (xy 349.987112 -286.236156) (xy 350.315288 -286.236156)
			(xy 350.319248 -286.187102) (xy 350.331025 -286.139318) (xy 350.350316 -286.094042) (xy 350.376619 -286.052446)
			(xy 350.409254 -286.015609) (xy 350.447375 -285.984484) (xy 350.489996 -285.959877) (xy 350.536012 -285.942425)
			(xy 350.584231 -285.932581) (xy 350.633406 -285.9306) (xy 350.682261 -285.936532) (xy 350.729532 -285.950224)
			(xy 350.773994 -285.971322) (xy 350.814497 -285.999278) (xy 350.84999 -286.03337) (xy 350.879555 -286.072714)
			(xy 350.902426 -286.116291) (xy 350.91801 -286.162972) (xy 350.925905 -286.211549) (xy 350.9264 -286.236156)
			(xy 350.926399 -286.2362) (xy 351.255196 -286.2362) (xy 351.259369 -286.185845) (xy 351.271774 -286.136864)
			(xy 351.292072 -286.090593) (xy 351.319711 -286.048295) (xy 351.353935 -286.011123) (xy 351.393811 -285.980092)
			(xy 351.438251 -285.956048) (xy 351.486043 -285.939647) (xy 351.535882 -285.931337) (xy 351.561146 -285.930848)
			(xy 352.5012 -285.930848) (xy 352.526452 -285.931457) (xy 352.576266 -285.93977) (xy 352.624033 -285.956168)
			(xy 352.66845 -285.980205) (xy 352.708304 -286.011225) (xy 352.742509 -286.048382) (xy 352.770132 -286.090661)
			(xy 352.790419 -286.136911) (xy 352.802816 -286.185869) (xy 352.806983 -286.236156) (xy 353.135196 -286.236156)
			(xy 353.139156 -286.187102) (xy 353.150933 -286.139318) (xy 353.170224 -286.094042) (xy 353.196527 -286.052446)
			(xy 353.229162 -286.015609) (xy 353.267283 -285.984484) (xy 353.309904 -285.959877) (xy 353.35592 -285.942425)
			(xy 353.404139 -285.932581) (xy 353.453314 -285.9306) (xy 353.502169 -285.936532) (xy 353.54944 -285.950224)
			(xy 353.593902 -285.971322) (xy 353.634405 -285.999278) (xy 353.669898 -286.03337) (xy 353.699463 -286.072714)
			(xy 353.722334 -286.116291) (xy 353.737918 -286.162972) (xy 353.745813 -286.211549) (xy 353.746308 -286.236156)
			(xy 353.746307 -286.2362) (xy 354.075224 -286.2362) (xy 354.079395 -286.185859) (xy 354.091795 -286.136892)
			(xy 354.112084 -286.090632) (xy 354.139709 -286.048343) (xy 354.173918 -286.011177) (xy 354.213778 -285.980147)
			(xy 354.2582 -285.956101) (xy 354.305974 -285.939694) (xy 354.355797 -285.931373) (xy 354.381054 -285.930848)
			(xy 355.321108 -285.930848) (xy 355.346359 -285.931458) (xy 355.396173 -285.939772) (xy 355.443939 -285.956171)
			(xy 355.488354 -285.980208) (xy 355.528207 -286.011228) (xy 355.562411 -286.048384) (xy 355.590033 -286.090664)
			(xy 355.610319 -286.136913) (xy 355.622717 -286.18587) (xy 355.626883 -286.236156) (xy 355.955358 -286.236156)
			(xy 355.959318 -286.187102) (xy 355.971095 -286.139318) (xy 355.990386 -286.094042) (xy 356.016689 -286.052446)
			(xy 356.049324 -286.015609) (xy 356.087445 -285.984484) (xy 356.130066 -285.959877) (xy 356.176082 -285.942425)
			(xy 356.224301 -285.932581) (xy 356.273476 -285.9306) (xy 356.322331 -285.936532) (xy 356.369602 -285.950224)
			(xy 356.414064 -285.971322) (xy 356.454567 -285.999278) (xy 356.49006 -286.03337) (xy 356.519625 -286.072714)
			(xy 356.542496 -286.116291) (xy 356.55808 -286.162972) (xy 356.565975 -286.211549) (xy 356.56647 -286.236156)
			(xy 363.468932 -286.236156) (xy 363.472892 -286.187102) (xy 363.484669 -286.139318) (xy 363.50396 -286.094042)
			(xy 363.530263 -286.052446) (xy 363.562898 -286.015609) (xy 363.601019 -285.984484) (xy 363.64364 -285.959877)
			(xy 363.689656 -285.942425) (xy 363.737875 -285.932581) (xy 363.78705 -285.9306) (xy 363.835905 -285.936532)
			(xy 363.883176 -285.950224) (xy 363.927638 -285.971322) (xy 363.968141 -285.999278) (xy 364.003634 -286.03337)
			(xy 364.033199 -286.072714) (xy 364.05607 -286.116291) (xy 364.071654 -286.162972) (xy 364.079549 -286.211549)
			(xy 364.080044 -286.236156) (xy 364.080043 -286.2362) (xy 364.408924 -286.2362) (xy 364.413096 -286.185856)
			(xy 364.425497 -286.136884) (xy 364.445789 -286.090622) (xy 364.473419 -286.048331) (xy 364.507632 -286.011164)
			(xy 364.547497 -285.980135) (xy 364.591924 -285.95609) (xy 364.639704 -285.939686) (xy 364.689532 -285.93137)
			(xy 364.71479 -285.930848) (xy 365.654844 -285.930848) (xy 365.680093 -285.931461) (xy 365.729902 -285.939779)
			(xy 365.777663 -285.956181) (xy 365.822073 -285.980221) (xy 365.861921 -286.011241) (xy 365.89612 -286.048396)
			(xy 365.923738 -286.090674) (xy 365.944022 -286.13692) (xy 365.956417 -286.185874) (xy 365.960583 -286.236156)
			(xy 366.289094 -286.236156) (xy 366.293054 -286.187102) (xy 366.304831 -286.139318) (xy 366.324122 -286.094042)
			(xy 366.350425 -286.052446) (xy 366.38306 -286.015609) (xy 366.421181 -285.984484) (xy 366.463802 -285.959877)
			(xy 366.509818 -285.942425) (xy 366.558037 -285.932581) (xy 366.607212 -285.9306) (xy 366.656067 -285.936532)
			(xy 366.703338 -285.950224) (xy 366.7478 -285.971322) (xy 366.788303 -285.999278) (xy 366.823796 -286.03337)
			(xy 366.853361 -286.072714) (xy 366.876232 -286.116291) (xy 366.891816 -286.162972) (xy 366.899711 -286.211549)
			(xy 366.900206 -286.236156) (xy 366.900205 -286.2362) (xy 367.228824 -286.2362) (xy 367.232996 -286.185855)
			(xy 367.245398 -286.136883) (xy 367.26569 -286.09062) (xy 367.293321 -286.048328) (xy 367.327535 -286.011161)
			(xy 367.367401 -285.980132) (xy 367.41183 -285.956088) (xy 367.45961 -285.939685) (xy 367.509439 -285.931369)
			(xy 367.534698 -285.930848) (xy 368.474752 -285.930848) (xy 368.500009 -285.931425) (xy 368.549834 -285.939732)
			(xy 368.597612 -285.956128) (xy 368.64204 -285.980164) (xy 368.681905 -286.011187) (xy 368.716119 -286.048348)
			(xy 368.74375 -286.090634) (xy 368.764043 -286.136892) (xy 368.776444 -286.185859) (xy 368.780612 -286.236156)
			(xy 369.109002 -286.236156) (xy 369.112962 -286.187102) (xy 369.124739 -286.139318) (xy 369.14403 -286.094042)
			(xy 369.170333 -286.052446) (xy 369.202968 -286.015609) (xy 369.241089 -285.984484) (xy 369.28371 -285.959877)
			(xy 369.329726 -285.942425) (xy 369.377945 -285.932581) (xy 369.42712 -285.9306) (xy 369.475975 -285.936532)
			(xy 369.523246 -285.950224) (xy 369.567708 -285.971322) (xy 369.608211 -285.999278) (xy 369.643704 -286.03337)
			(xy 369.673269 -286.072714) (xy 369.69614 -286.116291) (xy 369.711724 -286.162972) (xy 369.719619 -286.211549)
			(xy 369.720114 -286.236156) (xy 369.720113 -286.2362) (xy 370.049024 -286.2362) (xy 370.053196 -286.185859)
			(xy 370.065595 -286.13689) (xy 370.085885 -286.09063) (xy 370.113511 -286.048341) (xy 370.147721 -286.011174)
			(xy 370.187581 -285.980145) (xy 370.232004 -285.956099) (xy 370.279779 -285.939692) (xy 370.329603 -285.931372)
			(xy 370.35486 -285.930848) (xy 371.294914 -285.930848) (xy 371.320165 -285.931459) (xy 371.369978 -285.939773)
			(xy 371.417743 -285.956173) (xy 371.462157 -285.98021) (xy 371.502009 -286.01123) (xy 371.536213 -286.048386)
			(xy 371.563834 -286.090665) (xy 371.58412 -286.136914) (xy 371.596517 -286.185871) (xy 371.600683 -286.236156)
			(xy 371.92891 -286.236156) (xy 371.93287 -286.187102) (xy 371.944647 -286.139318) (xy 371.963938 -286.094042)
			(xy 371.990241 -286.052446) (xy 372.022876 -286.015609) (xy 372.060997 -285.984484) (xy 372.103618 -285.959877)
			(xy 372.149634 -285.942425) (xy 372.197853 -285.932581) (xy 372.247028 -285.9306) (xy 372.295883 -285.936532)
			(xy 372.343154 -285.950224) (xy 372.387616 -285.971322) (xy 372.428119 -285.999278) (xy 372.463612 -286.03337)
			(xy 372.493177 -286.072714) (xy 372.516048 -286.116291) (xy 372.531632 -286.162972) (xy 372.539527 -286.211549)
			(xy 372.540022 -286.236156) (xy 372.539527 -286.260763) (xy 372.531632 -286.30934) (xy 372.516048 -286.356021)
			(xy 372.493177 -286.399598) (xy 372.463612 -286.438942) (xy 372.428119 -286.473034) (xy 372.387616 -286.50099)
			(xy 372.343154 -286.522088) (xy 372.295883 -286.53578) (xy 372.247028 -286.541712) (xy 372.197853 -286.539731)
			(xy 372.149634 -286.529887) (xy 372.103618 -286.512435) (xy 372.060997 -286.487828) (xy 372.022876 -286.456703)
			(xy 371.990241 -286.419866) (xy 371.963938 -286.37827) (xy 371.944647 -286.332994) (xy 371.93287 -286.28521)
			(xy 371.92891 -286.236156) (xy 371.600683 -286.236156) (xy 371.600687 -286.2362) (xy 371.596517 -286.286529)
			(xy 371.58412 -286.335486) (xy 371.563834 -286.381735) (xy 371.536213 -286.424014) (xy 371.502009 -286.46117)
			(xy 371.462157 -286.49219) (xy 371.417743 -286.516227) (xy 371.369978 -286.532627) (xy 371.320165 -286.540941)
			(xy 371.294914 -286.541464) (xy 370.35486 -286.541464) (xy 370.329603 -286.541028) (xy 370.279779 -286.532708)
			(xy 370.232004 -286.516301) (xy 370.187581 -286.492255) (xy 370.147721 -286.461226) (xy 370.113511 -286.424059)
			(xy 370.085884 -286.38177) (xy 370.065595 -286.33551) (xy 370.053196 -286.286541) (xy 370.049024 -286.2362)
			(xy 369.720113 -286.2362) (xy 369.719619 -286.260763) (xy 369.711724 -286.30934) (xy 369.69614 -286.356021)
			(xy 369.673269 -286.399598) (xy 369.643704 -286.438942) (xy 369.608211 -286.473034) (xy 369.567708 -286.50099)
			(xy 369.523246 -286.522088) (xy 369.475975 -286.53578) (xy 369.42712 -286.541712) (xy 369.377945 -286.539731)
			(xy 369.329726 -286.529887) (xy 369.28371 -286.512435) (xy 369.241089 -286.487828) (xy 369.202968 -286.456703)
			(xy 369.170333 -286.419866) (xy 369.14403 -286.37827) (xy 369.124739 -286.332994) (xy 369.112962 -286.28521)
			(xy 369.109002 -286.236156) (xy 368.780612 -286.236156) (xy 368.780616 -286.2362) (xy 368.776444 -286.286541)
			(xy 368.764043 -286.335508) (xy 368.74375 -286.381766) (xy 368.716119 -286.424052) (xy 368.681905 -286.461213)
			(xy 368.64204 -286.492236) (xy 368.597612 -286.516272) (xy 368.549834 -286.532668) (xy 368.500009 -286.540975)
			(xy 368.474752 -286.541464) (xy 367.534698 -286.541464) (xy 367.509439 -286.541031) (xy 367.45961 -286.532715)
			(xy 367.41183 -286.516312) (xy 367.367401 -286.492268) (xy 367.327535 -286.461239) (xy 367.293321 -286.424072)
			(xy 367.26569 -286.38178) (xy 367.245398 -286.335517) (xy 367.232996 -286.286545) (xy 367.228824 -286.2362)
			(xy 366.900205 -286.2362) (xy 366.899711 -286.260763) (xy 366.891816 -286.30934) (xy 366.876232 -286.356021)
			(xy 366.853361 -286.399598) (xy 366.823796 -286.438942) (xy 366.788303 -286.473034) (xy 366.7478 -286.50099)
			(xy 366.703338 -286.522088) (xy 366.656067 -286.53578) (xy 366.607212 -286.541712) (xy 366.558037 -286.539731)
			(xy 366.509818 -286.529887) (xy 366.463802 -286.512435) (xy 366.421181 -286.487828) (xy 366.38306 -286.456703)
			(xy 366.350425 -286.419866) (xy 366.324122 -286.37827) (xy 366.304831 -286.332994) (xy 366.293054 -286.28521)
			(xy 366.289094 -286.236156) (xy 365.960583 -286.236156) (xy 365.960587 -286.2362) (xy 365.956417 -286.286526)
			(xy 365.944022 -286.33548) (xy 365.923738 -286.381726) (xy 365.89612 -286.424004) (xy 365.861921 -286.461159)
			(xy 365.822073 -286.492179) (xy 365.777663 -286.516219) (xy 365.729902 -286.532621) (xy 365.680093 -286.540939)
			(xy 365.654844 -286.541464) (xy 364.71479 -286.541464) (xy 364.689532 -286.54103) (xy 364.639704 -286.532714)
			(xy 364.591924 -286.51631) (xy 364.547497 -286.492265) (xy 364.507632 -286.461236) (xy 364.473419 -286.424069)
			(xy 364.445789 -286.381778) (xy 364.425497 -286.335516) (xy 364.413096 -286.286544) (xy 364.408924 -286.2362)
			(xy 364.080043 -286.2362) (xy 364.079549 -286.260763) (xy 364.071654 -286.30934) (xy 364.05607 -286.356021)
			(xy 364.033199 -286.399598) (xy 364.003634 -286.438942) (xy 363.968141 -286.473034) (xy 363.927638 -286.50099)
			(xy 363.883176 -286.522088) (xy 363.835905 -286.53578) (xy 363.78705 -286.541712) (xy 363.737875 -286.539731)
			(xy 363.689656 -286.529887) (xy 363.64364 -286.512435) (xy 363.601019 -286.487828) (xy 363.562898 -286.456703)
			(xy 363.530263 -286.419866) (xy 363.50396 -286.37827) (xy 363.484669 -286.332994) (xy 363.472892 -286.28521)
			(xy 363.468932 -286.236156) (xy 356.56647 -286.236156) (xy 356.565975 -286.260763) (xy 356.55808 -286.30934)
			(xy 356.542496 -286.356021) (xy 356.519625 -286.399598) (xy 356.49006 -286.438942) (xy 356.454567 -286.473034)
			(xy 356.414064 -286.50099) (xy 356.369602 -286.522088) (xy 356.322331 -286.53578) (xy 356.273476 -286.541712)
			(xy 356.224301 -286.539731) (xy 356.176082 -286.529887) (xy 356.130066 -286.512435) (xy 356.087445 -286.487828)
			(xy 356.049324 -286.456703) (xy 356.016689 -286.419866) (xy 355.990386 -286.37827) (xy 355.971095 -286.332994)
			(xy 355.959318 -286.28521) (xy 355.955358 -286.236156) (xy 355.626883 -286.236156) (xy 355.626887 -286.2362)
			(xy 355.622717 -286.28653) (xy 355.610319 -286.335487) (xy 355.590033 -286.381736) (xy 355.562411 -286.424016)
			(xy 355.528207 -286.461172) (xy 355.488354 -286.492192) (xy 355.443939 -286.516229) (xy 355.396173 -286.532628)
			(xy 355.346359 -286.540942) (xy 355.321108 -286.541464) (xy 354.381054 -286.541464) (xy 354.355797 -286.541027)
			(xy 354.305974 -286.532706) (xy 354.2582 -286.516299) (xy 354.213778 -286.492253) (xy 354.173918 -286.461223)
			(xy 354.139709 -286.424057) (xy 354.112084 -286.381768) (xy 354.091795 -286.335508) (xy 354.079395 -286.286541)
			(xy 354.075224 -286.2362) (xy 353.746307 -286.2362) (xy 353.745813 -286.260763) (xy 353.737918 -286.30934)
			(xy 353.722334 -286.356021) (xy 353.699463 -286.399598) (xy 353.669898 -286.438942) (xy 353.634405 -286.473034)
			(xy 353.593902 -286.50099) (xy 353.54944 -286.522088) (xy 353.502169 -286.53578) (xy 353.453314 -286.541712)
			(xy 353.404139 -286.539731) (xy 353.35592 -286.529887) (xy 353.309904 -286.512435) (xy 353.267283 -286.487828)
			(xy 353.229162 -286.456703) (xy 353.196527 -286.419866) (xy 353.170224 -286.37827) (xy 353.150933 -286.332994)
			(xy 353.139156 -286.28521) (xy 353.135196 -286.236156) (xy 352.806983 -286.236156) (xy 352.806987 -286.2362)
			(xy 352.802816 -286.286531) (xy 352.790419 -286.335489) (xy 352.770132 -286.381739) (xy 352.742509 -286.424018)
			(xy 352.708304 -286.461175) (xy 352.66845 -286.492195) (xy 352.624033 -286.516232) (xy 352.576266 -286.53263)
			(xy 352.526452 -286.540943) (xy 352.5012 -286.541464) (xy 351.561146 -286.541464) (xy 351.535882 -286.541063)
			(xy 351.486043 -286.532753) (xy 351.438251 -286.516352) (xy 351.393811 -286.492309) (xy 351.353935 -286.461277)
			(xy 351.319711 -286.424105) (xy 351.292072 -286.381807) (xy 351.271774 -286.335536) (xy 351.259369 -286.286555)
			(xy 351.255196 -286.2362) (xy 350.926399 -286.2362) (xy 350.925905 -286.260763) (xy 350.91801 -286.30934)
			(xy 350.902426 -286.356021) (xy 350.879555 -286.399598) (xy 350.84999 -286.438942) (xy 350.814497 -286.473034)
			(xy 350.773994 -286.50099) (xy 350.729532 -286.522088) (xy 350.682261 -286.53578) (xy 350.633406 -286.541712)
			(xy 350.584231 -286.539731) (xy 350.536012 -286.529887) (xy 350.489996 -286.512435) (xy 350.447375 -286.487828)
			(xy 350.409254 -286.456703) (xy 350.376619 -286.419866) (xy 350.350316 -286.37827) (xy 350.331025 -286.332994)
			(xy 350.319248 -286.28521) (xy 350.315288 -286.236156) (xy 349.987112 -286.236156) (xy 349.987116 -286.2362)
			(xy 349.982945 -286.286536) (xy 349.970545 -286.3355) (xy 349.950256 -286.381755) (xy 349.92263 -286.424039)
			(xy 349.88842 -286.461199) (xy 349.848561 -286.492222) (xy 349.804139 -286.516261) (xy 349.756367 -286.53266)
			(xy 349.706547 -286.540972) (xy 349.681292 -286.541464) (xy 348.741238 -286.541464) (xy 348.715975 -286.541062)
			(xy 348.666136 -286.532751) (xy 348.618345 -286.51635) (xy 348.573907 -286.492306) (xy 348.534032 -286.461274)
			(xy 348.499809 -286.424103) (xy 348.472171 -286.381805) (xy 348.451873 -286.335534) (xy 348.439469 -286.286554)
			(xy 348.435296 -286.2362) (xy 348.106491 -286.2362) (xy 348.105997 -286.260763) (xy 348.098102 -286.30934)
			(xy 348.082518 -286.356021) (xy 348.059647 -286.399598) (xy 348.030082 -286.438942) (xy 347.994589 -286.473034)
			(xy 347.954086 -286.50099) (xy 347.909624 -286.522088) (xy 347.862353 -286.53578) (xy 347.813498 -286.541712)
			(xy 347.764323 -286.539731) (xy 347.716104 -286.529887) (xy 347.670088 -286.512435) (xy 347.627467 -286.487828)
			(xy 347.589346 -286.456703) (xy 347.556711 -286.419866) (xy 347.530408 -286.37827) (xy 347.511117 -286.332994)
			(xy 347.49934 -286.28521) (xy 347.49538 -286.236156) (xy 347.166883 -286.236156) (xy 347.166887 -286.2362)
			(xy 347.162717 -286.286528) (xy 347.150321 -286.335483) (xy 347.130036 -286.38173) (xy 347.102417 -286.424008)
			(xy 347.068216 -286.461164) (xy 347.028366 -286.492184) (xy 346.983954 -286.516223) (xy 346.936191 -286.532624)
			(xy 346.88638 -286.54094) (xy 346.86113 -286.541464) (xy 345.921076 -286.541464) (xy 345.895818 -286.541029)
			(xy 345.845992 -286.532711) (xy 345.798215 -286.516306) (xy 345.753789 -286.49226) (xy 345.713927 -286.461231)
			(xy 345.679715 -286.424065) (xy 345.652087 -286.381774) (xy 345.631796 -286.335513) (xy 345.619396 -286.286543)
			(xy 345.615224 -286.2362) (xy 345.286877 -286.2362) (xy 345.282724 -286.286438) (xy 345.270375 -286.335311)
			(xy 345.250167 -286.381492) (xy 345.222649 -286.423728) (xy 345.188567 -286.46087) (xy 345.148849 -286.49191)
			(xy 345.104571 -286.516005) (xy 345.056937 -286.532501) (xy 345.007241 -286.54095) (xy 344.982038 -286.541464)
			(xy 344.971974 -286.5419) (xy 344.953392 -286.549638) (xy 344.94597 -286.55645) (xy 344.895424 -286.60725)
			(xy 344.888729 -286.614656) (xy 344.881126 -286.633092) (xy 344.880692 -286.643064) (xy 344.880692 -287.046162)
			(xy 347.025226 -287.046162) (xy 347.029186 -286.997108) (xy 347.040963 -286.949324) (xy 347.060254 -286.904048)
			(xy 347.086557 -286.862452) (xy 347.119192 -286.825615) (xy 347.157313 -286.79449) (xy 347.199934 -286.769883)
			(xy 347.24595 -286.752431) (xy 347.294169 -286.742587) (xy 347.343344 -286.740606) (xy 347.392199 -286.746538)
			(xy 347.43947 -286.76023) (xy 347.483932 -286.781328) (xy 347.524435 -286.809284) (xy 347.559928 -286.843376)
			(xy 347.589493 -286.88272) (xy 347.612364 -286.926297) (xy 347.627948 -286.972978) (xy 347.635843 -287.021555)
			(xy 347.636333 -287.045908) (xy 349.845388 -287.045908) (xy 349.849348 -286.996854) (xy 349.861125 -286.94907)
			(xy 349.880416 -286.903794) (xy 349.906719 -286.862198) (xy 349.939354 -286.825361) (xy 349.977475 -286.794236)
			(xy 350.020096 -286.769629) (xy 350.066112 -286.752177) (xy 350.114331 -286.742333) (xy 350.163506 -286.740352)
			(xy 350.212361 -286.746284) (xy 350.259632 -286.759976) (xy 350.304094 -286.781074) (xy 350.344597 -286.80903)
			(xy 350.38009 -286.843122) (xy 350.409655 -286.882466) (xy 350.432526 -286.926043) (xy 350.44811 -286.972724)
			(xy 350.456005 -287.021301) (xy 350.4565 -287.045908) (xy 352.665296 -287.045908) (xy 352.669256 -286.996854)
			(xy 352.681033 -286.94907) (xy 352.700324 -286.903794) (xy 352.726627 -286.862198) (xy 352.759262 -286.825361)
			(xy 352.797383 -286.794236) (xy 352.840004 -286.769629) (xy 352.88602 -286.752177) (xy 352.934239 -286.742333)
			(xy 352.983414 -286.740352) (xy 353.032269 -286.746284) (xy 353.07954 -286.759976) (xy 353.124002 -286.781074)
			(xy 353.164505 -286.80903) (xy 353.199998 -286.843122) (xy 353.229563 -286.882466) (xy 353.252434 -286.926043)
			(xy 353.268018 -286.972724) (xy 353.275913 -287.021301) (xy 353.276408 -287.045908) (xy 353.276403 -287.046162)
			(xy 355.485204 -287.046162) (xy 355.489164 -286.997108) (xy 355.500941 -286.949324) (xy 355.520232 -286.904048)
			(xy 355.546535 -286.862452) (xy 355.57917 -286.825615) (xy 355.617291 -286.79449) (xy 355.659912 -286.769883)
			(xy 355.705928 -286.752431) (xy 355.754147 -286.742587) (xy 355.803322 -286.740606) (xy 355.852177 -286.746538)
			(xy 355.899448 -286.76023) (xy 355.94391 -286.781328) (xy 355.984413 -286.809284) (xy 356.019906 -286.843376)
			(xy 356.049471 -286.88272) (xy 356.072342 -286.926297) (xy 356.087926 -286.972978) (xy 356.095821 -287.021555)
			(xy 356.096311 -287.0459) (xy 356.425277 -287.0459) (xy 356.429447 -286.995567) (xy 356.441845 -286.946607)
			(xy 356.462131 -286.900355) (xy 356.489753 -286.858072) (xy 356.523957 -286.820912) (xy 356.563811 -286.789888)
			(xy 356.608227 -286.765847) (xy 356.655994 -286.749443) (xy 356.705809 -286.741125) (xy 356.731062 -286.7406)
			(xy 357.671116 -286.7406) (xy 357.696371 -286.741107) (xy 357.746192 -286.749423) (xy 357.793965 -286.765826)
			(xy 357.838387 -286.789867) (xy 357.878245 -286.820893) (xy 357.912454 -286.858055) (xy 357.94008 -286.900341)
			(xy 357.960369 -286.946597) (xy 357.972768 -286.995562) (xy 357.976939 -287.0459) (xy 357.976938 -287.045908)
			(xy 358.305366 -287.045908) (xy 358.309326 -286.996854) (xy 358.321103 -286.94907) (xy 358.340394 -286.903794)
			(xy 358.366697 -286.862198) (xy 358.399332 -286.825361) (xy 358.437453 -286.794236) (xy 358.480074 -286.769629)
			(xy 358.52609 -286.752177) (xy 358.574309 -286.742333) (xy 358.623484 -286.740352) (xy 358.672339 -286.746284)
			(xy 358.71961 -286.759976) (xy 358.764072 -286.781074) (xy 358.804575 -286.80903) (xy 358.840068 -286.843122)
			(xy 358.869633 -286.882466) (xy 358.892504 -286.926043) (xy 358.908088 -286.972724) (xy 358.915983 -287.021301)
			(xy 358.916478 -287.045908) (xy 361.118924 -287.045908) (xy 361.122884 -286.996854) (xy 361.134661 -286.94907)
			(xy 361.153952 -286.903794) (xy 361.180255 -286.862198) (xy 361.21289 -286.825361) (xy 361.251011 -286.794236)
			(xy 361.293632 -286.769629) (xy 361.339648 -286.752177) (xy 361.387867 -286.742333) (xy 361.437042 -286.740352)
			(xy 361.485897 -286.746284) (xy 361.533168 -286.759976) (xy 361.57763 -286.781074) (xy 361.618133 -286.80903)
			(xy 361.653626 -286.843122) (xy 361.683191 -286.882466) (xy 361.706062 -286.926043) (xy 361.721646 -286.972724)
			(xy 361.729541 -287.021301) (xy 361.730036 -287.0459) (xy 362.058977 -287.0459) (xy 362.063148 -286.995565)
			(xy 362.075546 -286.946603) (xy 362.095834 -286.900349) (xy 362.123458 -286.858066) (xy 362.157665 -286.820905)
			(xy 362.197521 -286.789881) (xy 362.24194 -286.765841) (xy 362.28971 -286.749439) (xy 362.339528 -286.741123)
			(xy 362.364782 -286.7406) (xy 363.304836 -286.7406) (xy 363.33009 -286.741108) (xy 363.379908 -286.749427)
			(xy 363.427678 -286.765831) (xy 363.472097 -286.789874) (xy 363.511953 -286.8209) (xy 363.546159 -286.858062)
			(xy 363.573783 -286.900347) (xy 363.59407 -286.946601) (xy 363.606468 -286.995564) (xy 363.610639 -287.0459)
			(xy 363.610617 -287.046162) (xy 363.939086 -287.046162) (xy 363.943046 -286.997108) (xy 363.954823 -286.949324)
			(xy 363.974114 -286.904048) (xy 364.000417 -286.862452) (xy 364.033052 -286.825615) (xy 364.071173 -286.79449)
			(xy 364.113794 -286.769883) (xy 364.15981 -286.752431) (xy 364.208029 -286.742587) (xy 364.257204 -286.740606)
			(xy 364.306059 -286.746538) (xy 364.35333 -286.76023) (xy 364.397792 -286.781328) (xy 364.438295 -286.809284)
			(xy 364.473788 -286.843376) (xy 364.503353 -286.88272) (xy 364.526224 -286.926297) (xy 364.541808 -286.972978)
			(xy 364.549703 -287.021555) (xy 364.550193 -287.045908) (xy 366.758994 -287.045908) (xy 366.762954 -286.996854)
			(xy 366.774731 -286.94907) (xy 366.794022 -286.903794) (xy 366.820325 -286.862198) (xy 366.85296 -286.825361)
			(xy 366.891081 -286.794236) (xy 366.933702 -286.769629) (xy 366.979718 -286.752177) (xy 367.027937 -286.742333)
			(xy 367.077112 -286.740352) (xy 367.125967 -286.746284) (xy 367.173238 -286.759976) (xy 367.2177 -286.781074)
			(xy 367.258203 -286.80903) (xy 367.293696 -286.843122) (xy 367.323261 -286.882466) (xy 367.346132 -286.926043)
			(xy 367.361716 -286.972724) (xy 367.369611 -287.021301) (xy 367.370106 -287.045908) (xy 369.578902 -287.045908)
			(xy 369.582862 -286.996854) (xy 369.594639 -286.94907) (xy 369.61393 -286.903794) (xy 369.640233 -286.862198)
			(xy 369.672868 -286.825361) (xy 369.710989 -286.794236) (xy 369.75361 -286.769629) (xy 369.799626 -286.752177)
			(xy 369.847845 -286.742333) (xy 369.89702 -286.740352) (xy 369.945875 -286.746284) (xy 369.993146 -286.759976)
			(xy 370.037608 -286.781074) (xy 370.078111 -286.80903) (xy 370.113604 -286.843122) (xy 370.143169 -286.882466)
			(xy 370.16604 -286.926043) (xy 370.181624 -286.972724) (xy 370.189519 -287.021301) (xy 370.190014 -287.045908)
			(xy 372.399064 -287.045908) (xy 372.403024 -286.996854) (xy 372.414801 -286.94907) (xy 372.434092 -286.903794)
			(xy 372.460395 -286.862198) (xy 372.49303 -286.825361) (xy 372.531151 -286.794236) (xy 372.573772 -286.769629)
			(xy 372.619788 -286.752177) (xy 372.668007 -286.742333) (xy 372.717182 -286.740352) (xy 372.766037 -286.746284)
			(xy 372.813308 -286.759976) (xy 372.85777 -286.781074) (xy 372.898273 -286.80903) (xy 372.933766 -286.843122)
			(xy 372.963331 -286.882466) (xy 372.986202 -286.926043) (xy 373.001786 -286.972724) (xy 373.009681 -287.021301)
			(xy 373.010176 -287.045908) (xy 373.009681 -287.070515) (xy 373.001786 -287.119092) (xy 372.986202 -287.165773)
			(xy 372.963331 -287.20935) (xy 372.933766 -287.248694) (xy 372.898273 -287.282786) (xy 372.85777 -287.310742)
			(xy 372.813308 -287.33184) (xy 372.766037 -287.345532) (xy 372.717182 -287.351464) (xy 372.668007 -287.349483)
			(xy 372.619788 -287.339639) (xy 372.573772 -287.322187) (xy 372.531151 -287.29758) (xy 372.49303 -287.266455)
			(xy 372.460395 -287.229618) (xy 372.434092 -287.188022) (xy 372.414801 -287.142746) (xy 372.403024 -287.094962)
			(xy 372.399064 -287.045908) (xy 370.190014 -287.045908) (xy 370.189519 -287.070515) (xy 370.181624 -287.119092)
			(xy 370.16604 -287.165773) (xy 370.143169 -287.20935) (xy 370.113604 -287.248694) (xy 370.078111 -287.282786)
			(xy 370.037608 -287.310742) (xy 369.993146 -287.33184) (xy 369.945875 -287.345532) (xy 369.89702 -287.351464)
			(xy 369.847845 -287.349483) (xy 369.799626 -287.339639) (xy 369.75361 -287.322187) (xy 369.710989 -287.29758)
			(xy 369.672868 -287.266455) (xy 369.640233 -287.229618) (xy 369.61393 -287.188022) (xy 369.594639 -287.142746)
			(xy 369.582862 -287.094962) (xy 369.578902 -287.045908) (xy 367.370106 -287.045908) (xy 367.369611 -287.070515)
			(xy 367.361716 -287.119092) (xy 367.346132 -287.165773) (xy 367.323261 -287.20935) (xy 367.293696 -287.248694)
			(xy 367.258203 -287.282786) (xy 367.2177 -287.310742) (xy 367.173238 -287.33184) (xy 367.125967 -287.345532)
			(xy 367.077112 -287.351464) (xy 367.027937 -287.349483) (xy 366.979718 -287.339639) (xy 366.933702 -287.322187)
			(xy 366.891081 -287.29758) (xy 366.85296 -287.266455) (xy 366.820325 -287.229618) (xy 366.794022 -287.188022)
			(xy 366.774731 -287.142746) (xy 366.762954 -287.094962) (xy 366.758994 -287.045908) (xy 364.550193 -287.045908)
			(xy 364.550198 -287.046162) (xy 364.549703 -287.070769) (xy 364.541808 -287.119346) (xy 364.526224 -287.166027)
			(xy 364.503353 -287.209604) (xy 364.473788 -287.248948) (xy 364.438295 -287.28304) (xy 364.397792 -287.310996)
			(xy 364.35333 -287.332094) (xy 364.306059 -287.345786) (xy 364.257204 -287.351718) (xy 364.208029 -287.349737)
			(xy 364.15981 -287.339893) (xy 364.113794 -287.322441) (xy 364.071173 -287.297834) (xy 364.033052 -287.266709)
			(xy 364.000417 -287.229872) (xy 363.974114 -287.188276) (xy 363.954823 -287.143) (xy 363.943046 -287.095216)
			(xy 363.939086 -287.046162) (xy 363.610617 -287.046162) (xy 363.606468 -287.096236) (xy 363.59407 -287.145199)
			(xy 363.573783 -287.191453) (xy 363.546159 -287.233738) (xy 363.511953 -287.2709) (xy 363.472097 -287.301926)
			(xy 363.427678 -287.325969) (xy 363.379908 -287.342373) (xy 363.33009 -287.350692) (xy 363.304836 -287.351216)
			(xy 362.364782 -287.351216) (xy 362.339528 -287.350677) (xy 362.28971 -287.342361) (xy 362.24194 -287.325959)
			(xy 362.197521 -287.301919) (xy 362.157665 -287.270895) (xy 362.123458 -287.233734) (xy 362.095834 -287.191451)
			(xy 362.075546 -287.145197) (xy 362.063148 -287.096235) (xy 362.058977 -287.0459) (xy 361.730036 -287.0459)
			(xy 361.730036 -287.045908) (xy 361.729541 -287.070515) (xy 361.721646 -287.119092) (xy 361.706062 -287.165773)
			(xy 361.683191 -287.20935) (xy 361.653626 -287.248694) (xy 361.618133 -287.282786) (xy 361.57763 -287.310742)
			(xy 361.533168 -287.33184) (xy 361.485897 -287.345532) (xy 361.437042 -287.351464) (xy 361.387867 -287.349483)
			(xy 361.339648 -287.339639) (xy 361.293632 -287.322187) (xy 361.251011 -287.29758) (xy 361.21289 -287.266455)
			(xy 361.180255 -287.229618) (xy 361.153952 -287.188022) (xy 361.134661 -287.142746) (xy 361.122884 -287.094962)
			(xy 361.118924 -287.045908) (xy 358.916478 -287.045908) (xy 358.915983 -287.070515) (xy 358.908088 -287.119092)
			(xy 358.892504 -287.165773) (xy 358.869633 -287.20935) (xy 358.840068 -287.248694) (xy 358.804575 -287.282786)
			(xy 358.764072 -287.310742) (xy 358.71961 -287.33184) (xy 358.672339 -287.345532) (xy 358.623484 -287.351464)
			(xy 358.574309 -287.349483) (xy 358.52609 -287.339639) (xy 358.480074 -287.322187) (xy 358.437453 -287.29758)
			(xy 358.399332 -287.266455) (xy 358.366697 -287.229618) (xy 358.340394 -287.188022) (xy 358.321103 -287.142746)
			(xy 358.309326 -287.094962) (xy 358.305366 -287.045908) (xy 357.976938 -287.045908) (xy 357.972768 -287.096238)
			(xy 357.960369 -287.145203) (xy 357.94008 -287.191459) (xy 357.912454 -287.233745) (xy 357.878245 -287.270907)
			(xy 357.838387 -287.301933) (xy 357.793965 -287.325974) (xy 357.746192 -287.342377) (xy 357.696371 -287.350693)
			(xy 357.671116 -287.351216) (xy 356.731062 -287.351216) (xy 356.705809 -287.350675) (xy 356.655994 -287.342357)
			(xy 356.608227 -287.325953) (xy 356.563811 -287.301912) (xy 356.523957 -287.270888) (xy 356.489753 -287.233728)
			(xy 356.462131 -287.191445) (xy 356.441845 -287.145193) (xy 356.429447 -287.096233) (xy 356.425277 -287.0459)
			(xy 356.096311 -287.0459) (xy 356.096316 -287.046162) (xy 356.095821 -287.070769) (xy 356.087926 -287.119346)
			(xy 356.072342 -287.166027) (xy 356.049471 -287.209604) (xy 356.019906 -287.248948) (xy 355.984413 -287.28304)
			(xy 355.94391 -287.310996) (xy 355.899448 -287.332094) (xy 355.852177 -287.345786) (xy 355.803322 -287.351718)
			(xy 355.754147 -287.349737) (xy 355.705928 -287.339893) (xy 355.659912 -287.322441) (xy 355.617291 -287.297834)
			(xy 355.57917 -287.266709) (xy 355.546535 -287.229872) (xy 355.520232 -287.188276) (xy 355.500941 -287.143)
			(xy 355.489164 -287.095216) (xy 355.485204 -287.046162) (xy 353.276403 -287.046162) (xy 353.275913 -287.070515)
			(xy 353.268018 -287.119092) (xy 353.252434 -287.165773) (xy 353.229563 -287.20935) (xy 353.199998 -287.248694)
			(xy 353.164505 -287.282786) (xy 353.124002 -287.310742) (xy 353.07954 -287.33184) (xy 353.032269 -287.345532)
			(xy 352.983414 -287.351464) (xy 352.934239 -287.349483) (xy 352.88602 -287.339639) (xy 352.840004 -287.322187)
			(xy 352.797383 -287.29758) (xy 352.759262 -287.266455) (xy 352.726627 -287.229618) (xy 352.700324 -287.188022)
			(xy 352.681033 -287.142746) (xy 352.669256 -287.094962) (xy 352.665296 -287.045908) (xy 350.4565 -287.045908)
			(xy 350.456005 -287.070515) (xy 350.44811 -287.119092) (xy 350.432526 -287.165773) (xy 350.409655 -287.20935)
			(xy 350.38009 -287.248694) (xy 350.344597 -287.282786) (xy 350.304094 -287.310742) (xy 350.259632 -287.33184)
			(xy 350.212361 -287.345532) (xy 350.163506 -287.351464) (xy 350.114331 -287.349483) (xy 350.066112 -287.339639)
			(xy 350.020096 -287.322187) (xy 349.977475 -287.29758) (xy 349.939354 -287.266455) (xy 349.906719 -287.229618)
			(xy 349.880416 -287.188022) (xy 349.861125 -287.142746) (xy 349.849348 -287.094962) (xy 349.845388 -287.045908)
			(xy 347.636333 -287.045908) (xy 347.636338 -287.046162) (xy 347.635843 -287.070769) (xy 347.627948 -287.119346)
			(xy 347.612364 -287.166027) (xy 347.589493 -287.209604) (xy 347.559928 -287.248948) (xy 347.524435 -287.28304)
			(xy 347.483932 -287.310996) (xy 347.43947 -287.332094) (xy 347.392199 -287.345786) (xy 347.343344 -287.351718)
			(xy 347.294169 -287.349737) (xy 347.24595 -287.339893) (xy 347.199934 -287.322441) (xy 347.157313 -287.297834)
			(xy 347.119192 -287.266709) (xy 347.086557 -287.229872) (xy 347.060254 -287.188276) (xy 347.040963 -287.143)
			(xy 347.029186 -287.095216) (xy 347.025226 -287.046162) (xy 344.880692 -287.046162) (xy 344.880692 -287.44926)
			(xy 344.881177 -287.459223) (xy 344.888762 -287.477649) (xy 344.895424 -287.485074) (xy 344.94597 -287.535874)
			(xy 344.953371 -287.542712) (xy 344.97197 -287.550425) (xy 344.982038 -287.55086) (xy 345.00724 -287.551463)
			(xy 345.056934 -287.559911) (xy 345.104566 -287.576406) (xy 345.148842 -287.6005) (xy 345.188559 -287.631539)
			(xy 345.222639 -287.66868) (xy 345.250156 -287.710913) (xy 345.270363 -287.757093) (xy 345.282711 -287.805964)
			(xy 345.286865 -287.8562) (xy 345.615237 -287.8562) (xy 345.619408 -287.805859) (xy 345.631808 -287.756891)
			(xy 345.652098 -287.710632) (xy 345.679725 -287.668343) (xy 345.713935 -287.631178) (xy 345.753796 -287.60015)
			(xy 345.79822 -287.576106) (xy 345.845995 -287.559701) (xy 345.895819 -287.551384) (xy 345.921076 -287.55086)
			(xy 346.86113 -287.55086) (xy 346.886381 -287.551448) (xy 346.936194 -287.559765) (xy 346.983958 -287.576166)
			(xy 347.028372 -287.600206) (xy 347.068224 -287.631227) (xy 347.102426 -287.668384) (xy 347.130047 -287.710664)
			(xy 347.150332 -287.756913) (xy 347.162729 -287.80587) (xy 347.166896 -287.856168) (xy 347.49538 -287.856168)
			(xy 347.49934 -287.807114) (xy 347.511117 -287.75933) (xy 347.530408 -287.714054) (xy 347.556711 -287.672458)
			(xy 347.589346 -287.635621) (xy 347.627467 -287.604496) (xy 347.670088 -287.579889) (xy 347.716104 -287.562437)
			(xy 347.764323 -287.552593) (xy 347.813498 -287.550612) (xy 347.862353 -287.556544) (xy 347.909624 -287.570236)
			(xy 347.954086 -287.591334) (xy 347.994589 -287.61929) (xy 348.030082 -287.653382) (xy 348.059647 -287.692726)
			(xy 348.082518 -287.736303) (xy 348.098102 -287.782984) (xy 348.105997 -287.831561) (xy 348.106492 -287.856168)
			(xy 348.106491 -287.8562) (xy 348.435308 -287.8562) (xy 348.439481 -287.805848) (xy 348.451885 -287.756869)
			(xy 348.472182 -287.710601) (xy 348.499818 -287.668305) (xy 348.53404 -287.631134) (xy 348.573913 -287.600104)
			(xy 348.61835 -287.576061) (xy 348.666139 -287.55966) (xy 348.715976 -287.55135) (xy 348.741238 -287.55086)
			(xy 349.681292 -287.55086) (xy 349.706548 -287.551416) (xy 349.75637 -287.559729) (xy 349.804144 -287.576129)
			(xy 349.848568 -287.600168) (xy 349.888429 -287.631192) (xy 349.922639 -287.668354) (xy 349.950266 -287.71064)
			(xy 349.970557 -287.756896) (xy 349.982957 -287.805862) (xy 349.987125 -287.856168) (xy 350.315288 -287.856168)
			(xy 350.319248 -287.807114) (xy 350.331025 -287.75933) (xy 350.350316 -287.714054) (xy 350.376619 -287.672458)
			(xy 350.409254 -287.635621) (xy 350.447375 -287.604496) (xy 350.489996 -287.579889) (xy 350.536012 -287.562437)
			(xy 350.584231 -287.552593) (xy 350.633406 -287.550612) (xy 350.682261 -287.556544) (xy 350.729532 -287.570236)
			(xy 350.773994 -287.591334) (xy 350.814497 -287.61929) (xy 350.84999 -287.653382) (xy 350.879555 -287.692726)
			(xy 350.902426 -287.736303) (xy 350.91801 -287.782984) (xy 350.925905 -287.831561) (xy 350.9264 -287.856168)
			(xy 350.926399 -287.8562) (xy 351.255208 -287.8562) (xy 351.259381 -287.805847) (xy 351.271785 -287.756868)
			(xy 351.292083 -287.710599) (xy 351.31972 -287.668302) (xy 351.353943 -287.631132) (xy 351.393817 -287.600102)
			(xy 351.438256 -287.576059) (xy 351.486046 -287.559659) (xy 351.535883 -287.551349) (xy 351.561146 -287.55086)
			(xy 352.5012 -287.55086) (xy 352.526453 -287.551445) (xy 352.576269 -287.559758) (xy 352.624038 -287.576157)
			(xy 352.668456 -287.600195) (xy 352.708312 -287.631216) (xy 352.742518 -287.668374) (xy 352.770142 -287.710656)
			(xy 352.79043 -287.756907) (xy 352.802828 -287.805867) (xy 352.806996 -287.856168) (xy 353.135196 -287.856168)
			(xy 353.139156 -287.807114) (xy 353.150933 -287.75933) (xy 353.170224 -287.714054) (xy 353.196527 -287.672458)
			(xy 353.229162 -287.635621) (xy 353.267283 -287.604496) (xy 353.309904 -287.579889) (xy 353.35592 -287.562437)
			(xy 353.404139 -287.552593) (xy 353.453314 -287.550612) (xy 353.502169 -287.556544) (xy 353.54944 -287.570236)
			(xy 353.593902 -287.591334) (xy 353.634405 -287.61929) (xy 353.669898 -287.653382) (xy 353.699463 -287.692726)
			(xy 353.722334 -287.736303) (xy 353.737918 -287.782984) (xy 353.745813 -287.831561) (xy 353.746308 -287.856168)
			(xy 353.746307 -287.8562) (xy 354.075237 -287.8562) (xy 354.079408 -287.805861) (xy 354.091806 -287.756896)
			(xy 354.112095 -287.710638) (xy 354.139719 -287.66835) (xy 354.173927 -287.631186) (xy 354.213784 -287.600158)
			(xy 354.258205 -287.576112) (xy 354.305977 -287.559706) (xy 354.355799 -287.551385) (xy 354.381054 -287.55086)
			(xy 355.321108 -287.55086) (xy 355.34636 -287.551446) (xy 355.396176 -287.55976) (xy 355.443943 -287.57616)
			(xy 355.48836 -287.600198) (xy 355.528215 -287.631219) (xy 355.56242 -287.668377) (xy 355.590043 -287.710658)
			(xy 355.610331 -287.756909) (xy 355.622728 -287.805868) (xy 355.626896 -287.856168) (xy 355.955358 -287.856168)
			(xy 355.959318 -287.807114) (xy 355.971095 -287.75933) (xy 355.990386 -287.714054) (xy 356.016689 -287.672458)
			(xy 356.049324 -287.635621) (xy 356.087445 -287.604496) (xy 356.130066 -287.579889) (xy 356.176082 -287.562437)
			(xy 356.224301 -287.552593) (xy 356.273476 -287.550612) (xy 356.322331 -287.556544) (xy 356.369602 -287.570236)
			(xy 356.414064 -287.591334) (xy 356.454567 -287.61929) (xy 356.49006 -287.653382) (xy 356.519625 -287.692726)
			(xy 356.542496 -287.736303) (xy 356.55808 -287.782984) (xy 356.565975 -287.831561) (xy 356.56647 -287.856168)
			(xy 356.895412 -287.856168) (xy 356.899372 -287.807114) (xy 356.911149 -287.75933) (xy 356.93044 -287.714054)
			(xy 356.956743 -287.672458) (xy 356.989378 -287.635621) (xy 357.027499 -287.604496) (xy 357.07012 -287.579889)
			(xy 357.116136 -287.562437) (xy 357.164355 -287.552593) (xy 357.21353 -287.550612) (xy 357.262385 -287.556544)
			(xy 357.309656 -287.570236) (xy 357.354118 -287.591334) (xy 357.394621 -287.61929) (xy 357.430114 -287.653382)
			(xy 357.459679 -287.692726) (xy 357.48255 -287.736303) (xy 357.498134 -287.782984) (xy 357.506029 -287.831561)
			(xy 357.506524 -287.856168) (xy 357.835212 -287.856168) (xy 357.839172 -287.807114) (xy 357.850949 -287.75933)
			(xy 357.87024 -287.714054) (xy 357.896543 -287.672458) (xy 357.929178 -287.635621) (xy 357.967299 -287.604496)
			(xy 358.00992 -287.579889) (xy 358.055936 -287.562437) (xy 358.104155 -287.552593) (xy 358.15333 -287.550612)
			(xy 358.202185 -287.556544) (xy 358.249456 -287.570236) (xy 358.293918 -287.591334) (xy 358.334421 -287.61929)
			(xy 358.369914 -287.653382) (xy 358.399479 -287.692726) (xy 358.42235 -287.736303) (xy 358.437934 -287.782984)
			(xy 358.445829 -287.831561) (xy 358.446324 -287.856168) (xy 361.589078 -287.856168) (xy 361.593038 -287.807114)
			(xy 361.604815 -287.75933) (xy 361.624106 -287.714054) (xy 361.650409 -287.672458) (xy 361.683044 -287.635621)
			(xy 361.721165 -287.604496) (xy 361.763786 -287.579889) (xy 361.809802 -287.562437) (xy 361.858021 -287.552593)
			(xy 361.907196 -287.550612) (xy 361.956051 -287.556544) (xy 362.003322 -287.570236) (xy 362.047784 -287.591334)
			(xy 362.088287 -287.61929) (xy 362.12378 -287.653382) (xy 362.153345 -287.692726) (xy 362.176216 -287.736303)
			(xy 362.1918 -287.782984) (xy 362.199695 -287.831561) (xy 362.20019 -287.856168) (xy 362.528878 -287.856168)
			(xy 362.532838 -287.807114) (xy 362.544615 -287.75933) (xy 362.563906 -287.714054) (xy 362.590209 -287.672458)
			(xy 362.622844 -287.635621) (xy 362.660965 -287.604496) (xy 362.703586 -287.579889) (xy 362.749602 -287.562437)
			(xy 362.797821 -287.552593) (xy 362.846996 -287.550612) (xy 362.895851 -287.556544) (xy 362.943122 -287.570236)
			(xy 362.987584 -287.591334) (xy 363.028087 -287.61929) (xy 363.06358 -287.653382) (xy 363.093145 -287.692726)
			(xy 363.116016 -287.736303) (xy 363.1316 -287.782984) (xy 363.139495 -287.831561) (xy 363.13999 -287.856168)
			(xy 363.468932 -287.856168) (xy 363.472892 -287.807114) (xy 363.484669 -287.75933) (xy 363.50396 -287.714054)
			(xy 363.530263 -287.672458) (xy 363.562898 -287.635621) (xy 363.601019 -287.604496) (xy 363.64364 -287.579889)
			(xy 363.689656 -287.562437) (xy 363.737875 -287.552593) (xy 363.78705 -287.550612) (xy 363.835905 -287.556544)
			(xy 363.883176 -287.570236) (xy 363.927638 -287.591334) (xy 363.968141 -287.61929) (xy 364.003634 -287.653382)
			(xy 364.033199 -287.692726) (xy 364.05607 -287.736303) (xy 364.071654 -287.782984) (xy 364.079549 -287.831561)
			(xy 364.080044 -287.856168) (xy 364.080043 -287.8562) (xy 364.408937 -287.8562) (xy 364.413108 -287.805858)
			(xy 364.425509 -287.756888) (xy 364.4458 -287.710628) (xy 364.473429 -287.668338) (xy 364.507641 -287.631173)
			(xy 364.547503 -287.600145) (xy 364.591929 -287.576102) (xy 364.639707 -287.559698) (xy 364.689533 -287.551382)
			(xy 364.71479 -287.55086) (xy 365.654844 -287.55086) (xy 365.680094 -287.551449) (xy 365.729905 -287.559767)
			(xy 365.777668 -287.57617) (xy 365.822079 -287.600211) (xy 365.861929 -287.631232) (xy 365.89613 -287.668389)
			(xy 365.923749 -287.710668) (xy 365.944033 -287.756916) (xy 365.956429 -287.805872) (xy 365.960596 -287.856168)
			(xy 366.289094 -287.856168) (xy 366.293054 -287.807114) (xy 366.304831 -287.75933) (xy 366.324122 -287.714054)
			(xy 366.350425 -287.672458) (xy 366.38306 -287.635621) (xy 366.421181 -287.604496) (xy 366.463802 -287.579889)
			(xy 366.509818 -287.562437) (xy 366.558037 -287.552593) (xy 366.607212 -287.550612) (xy 366.656067 -287.556544)
			(xy 366.703338 -287.570236) (xy 366.7478 -287.591334) (xy 366.788303 -287.61929) (xy 366.823796 -287.653382)
			(xy 366.853361 -287.692726) (xy 366.876232 -287.736303) (xy 366.891816 -287.782984) (xy 366.899711 -287.831561)
			(xy 366.900206 -287.856168) (xy 366.900205 -287.8562) (xy 367.228837 -287.8562) (xy 367.233009 -287.805857)
			(xy 367.245409 -287.756887) (xy 367.265701 -287.710626) (xy 367.293331 -287.668336) (xy 367.327544 -287.63117)
			(xy 367.367408 -287.600142) (xy 367.411835 -287.576099) (xy 367.459613 -287.559697) (xy 367.50944 -287.551382)
			(xy 367.534698 -287.55086) (xy 368.474752 -287.55086) (xy 368.50001 -287.551413) (xy 368.549837 -287.55972)
			(xy 368.597617 -287.576117) (xy 368.642047 -287.600154) (xy 368.681913 -287.631178) (xy 368.716129 -287.668341)
			(xy 368.74376 -287.710629) (xy 368.764054 -287.756888) (xy 368.776456 -287.805857) (xy 368.780625 -287.856168)
			(xy 369.109002 -287.856168) (xy 369.112962 -287.807114) (xy 369.124739 -287.75933) (xy 369.14403 -287.714054)
			(xy 369.170333 -287.672458) (xy 369.202968 -287.635621) (xy 369.241089 -287.604496) (xy 369.28371 -287.579889)
			(xy 369.329726 -287.562437) (xy 369.377945 -287.552593) (xy 369.42712 -287.550612) (xy 369.475975 -287.556544)
			(xy 369.523246 -287.570236) (xy 369.567708 -287.591334) (xy 369.608211 -287.61929) (xy 369.643704 -287.653382)
			(xy 369.673269 -287.692726) (xy 369.69614 -287.736303) (xy 369.711724 -287.782984) (xy 369.719619 -287.831561)
			(xy 369.720114 -287.856168) (xy 369.720113 -287.8562) (xy 370.049037 -287.8562) (xy 370.053208 -287.805861)
			(xy 370.065607 -287.756894) (xy 370.085895 -287.710636) (xy 370.113521 -287.668348) (xy 370.147729 -287.631184)
			(xy 370.187588 -287.600156) (xy 370.232009 -287.576111) (xy 370.279782 -287.559705) (xy 370.329604 -287.551385)
			(xy 370.35486 -287.55086) (xy 371.294914 -287.55086) (xy 371.320166 -287.551447) (xy 371.369981 -287.559761)
			(xy 371.417748 -287.576162) (xy 371.462164 -287.6002) (xy 371.502017 -287.631221) (xy 371.536222 -287.668379)
			(xy 371.563844 -287.71066) (xy 371.584131 -287.75691) (xy 371.596529 -287.805869) (xy 371.600696 -287.856168)
			(xy 371.92891 -287.856168) (xy 371.93287 -287.807114) (xy 371.944647 -287.75933) (xy 371.963938 -287.714054)
			(xy 371.990241 -287.672458) (xy 372.022876 -287.635621) (xy 372.060997 -287.604496) (xy 372.103618 -287.579889)
			(xy 372.149634 -287.562437) (xy 372.197853 -287.552593) (xy 372.247028 -287.550612) (xy 372.295883 -287.556544)
			(xy 372.343154 -287.570236) (xy 372.387616 -287.591334) (xy 372.428119 -287.61929) (xy 372.463612 -287.653382)
			(xy 372.493177 -287.692726) (xy 372.516048 -287.736303) (xy 372.531632 -287.782984) (xy 372.539527 -287.831561)
			(xy 372.540022 -287.856168) (xy 372.539527 -287.880775) (xy 372.531632 -287.929352) (xy 372.516048 -287.976033)
			(xy 372.493177 -288.01961) (xy 372.463612 -288.058954) (xy 372.428119 -288.093046) (xy 372.387616 -288.121002)
			(xy 372.343154 -288.1421) (xy 372.295883 -288.155792) (xy 372.247028 -288.161724) (xy 372.197853 -288.159743)
			(xy 372.149634 -288.149899) (xy 372.103618 -288.132447) (xy 372.060997 -288.10784) (xy 372.022876 -288.076715)
			(xy 371.990241 -288.039878) (xy 371.963938 -287.998282) (xy 371.944647 -287.953006) (xy 371.93287 -287.905222)
			(xy 371.92891 -287.856168) (xy 371.600696 -287.856168) (xy 371.600699 -287.8562) (xy 371.596529 -287.906531)
			(xy 371.584131 -287.95549) (xy 371.563844 -288.00174) (xy 371.536222 -288.044021) (xy 371.502017 -288.081179)
			(xy 371.462164 -288.1122) (xy 371.417748 -288.136238) (xy 371.369981 -288.152639) (xy 371.320166 -288.160953)
			(xy 371.294914 -288.161476) (xy 370.35486 -288.161476) (xy 370.329604 -288.161015) (xy 370.279782 -288.152695)
			(xy 370.232009 -288.136289) (xy 370.187588 -288.112244) (xy 370.147729 -288.081216) (xy 370.113521 -288.044052)
			(xy 370.085895 -288.001764) (xy 370.065607 -287.955506) (xy 370.053208 -287.906539) (xy 370.049037 -287.8562)
			(xy 369.720113 -287.8562) (xy 369.719619 -287.880775) (xy 369.711724 -287.929352) (xy 369.69614 -287.976033)
			(xy 369.673269 -288.01961) (xy 369.643704 -288.058954) (xy 369.608211 -288.093046) (xy 369.567708 -288.121002)
			(xy 369.523246 -288.1421) (xy 369.475975 -288.155792) (xy 369.42712 -288.161724) (xy 369.377945 -288.159743)
			(xy 369.329726 -288.149899) (xy 369.28371 -288.132447) (xy 369.241089 -288.10784) (xy 369.202968 -288.076715)
			(xy 369.170333 -288.039878) (xy 369.14403 -287.998282) (xy 369.124739 -287.953006) (xy 369.112962 -287.905222)
			(xy 369.109002 -287.856168) (xy 368.780625 -287.856168) (xy 368.780628 -287.8562) (xy 368.776456 -287.906543)
			(xy 368.764054 -287.955512) (xy 368.74376 -288.001771) (xy 368.716129 -288.044059) (xy 368.681913 -288.081222)
			(xy 368.642047 -288.112246) (xy 368.597617 -288.136283) (xy 368.549837 -288.15268) (xy 368.50001 -288.160987)
			(xy 368.474752 -288.161476) (xy 367.534698 -288.161476) (xy 367.50944 -288.161018) (xy 367.459613 -288.152703)
			(xy 367.411835 -288.136301) (xy 367.367408 -288.112258) (xy 367.327544 -288.08123) (xy 367.293331 -288.044064)
			(xy 367.265701 -288.001774) (xy 367.245409 -287.955513) (xy 367.233009 -287.906543) (xy 367.228837 -287.8562)
			(xy 366.900205 -287.8562) (xy 366.899711 -287.880775) (xy 366.891816 -287.929352) (xy 366.876232 -287.976033)
			(xy 366.853361 -288.01961) (xy 366.823796 -288.058954) (xy 366.788303 -288.093046) (xy 366.7478 -288.121002)
			(xy 366.703338 -288.1421) (xy 366.656067 -288.155792) (xy 366.607212 -288.161724) (xy 366.558037 -288.159743)
			(xy 366.509818 -288.149899) (xy 366.463802 -288.132447) (xy 366.421181 -288.10784) (xy 366.38306 -288.076715)
			(xy 366.350425 -288.039878) (xy 366.324122 -287.998282) (xy 366.304831 -287.953006) (xy 366.293054 -287.905222)
			(xy 366.289094 -287.856168) (xy 365.960596 -287.856168) (xy 365.960599 -287.8562) (xy 365.956429 -287.906528)
			(xy 365.944033 -287.955484) (xy 365.923749 -288.001732) (xy 365.89613 -288.044011) (xy 365.861929 -288.081168)
			(xy 365.82208 -288.112189) (xy 365.777668 -288.13623) (xy 365.729905 -288.152633) (xy 365.680094 -288.160951)
			(xy 365.654844 -288.161476) (xy 364.71479 -288.161476) (xy 364.689533 -288.161018) (xy 364.639707 -288.152702)
			(xy 364.591929 -288.136298) (xy 364.547503 -288.112255) (xy 364.507641 -288.081227) (xy 364.473429 -288.044062)
			(xy 364.4458 -288.001772) (xy 364.425509 -287.955512) (xy 364.413108 -287.906542) (xy 364.408937 -287.8562)
			(xy 364.080043 -287.8562) (xy 364.079549 -287.880775) (xy 364.071654 -287.929352) (xy 364.05607 -287.976033)
			(xy 364.033199 -288.01961) (xy 364.003634 -288.058954) (xy 363.968141 -288.093046) (xy 363.927638 -288.121002)
			(xy 363.883176 -288.1421) (xy 363.835905 -288.155792) (xy 363.78705 -288.161724) (xy 363.737875 -288.159743)
			(xy 363.689656 -288.149899) (xy 363.64364 -288.132447) (xy 363.601019 -288.10784) (xy 363.562898 -288.076715)
			(xy 363.530263 -288.039878) (xy 363.50396 -287.998282) (xy 363.484669 -287.953006) (xy 363.472892 -287.905222)
			(xy 363.468932 -287.856168) (xy 363.13999 -287.856168) (xy 363.139495 -287.880775) (xy 363.1316 -287.929352)
			(xy 363.116016 -287.976033) (xy 363.093145 -288.01961) (xy 363.06358 -288.058954) (xy 363.028087 -288.093046)
			(xy 362.987584 -288.121002) (xy 362.943122 -288.1421) (xy 362.895851 -288.155792) (xy 362.846996 -288.161724)
			(xy 362.797821 -288.159743) (xy 362.749602 -288.149899) (xy 362.703586 -288.132447) (xy 362.660965 -288.10784)
			(xy 362.622844 -288.076715) (xy 362.590209 -288.039878) (xy 362.563906 -287.998282) (xy 362.544615 -287.953006)
			(xy 362.532838 -287.905222) (xy 362.528878 -287.856168) (xy 362.20019 -287.856168) (xy 362.199695 -287.880775)
			(xy 362.1918 -287.929352) (xy 362.176216 -287.976033) (xy 362.153345 -288.01961) (xy 362.12378 -288.058954)
			(xy 362.088287 -288.093046) (xy 362.047784 -288.121002) (xy 362.003322 -288.1421) (xy 361.956051 -288.155792)
			(xy 361.907196 -288.161724) (xy 361.858021 -288.159743) (xy 361.809802 -288.149899) (xy 361.763786 -288.132447)
			(xy 361.721165 -288.10784) (xy 361.683044 -288.076715) (xy 361.650409 -288.039878) (xy 361.624106 -287.998282)
			(xy 361.604815 -287.953006) (xy 361.593038 -287.905222) (xy 361.589078 -287.856168) (xy 358.446324 -287.856168)
			(xy 358.445829 -287.880775) (xy 358.437934 -287.929352) (xy 358.42235 -287.976033) (xy 358.399479 -288.01961)
			(xy 358.369914 -288.058954) (xy 358.334421 -288.093046) (xy 358.293918 -288.121002) (xy 358.249456 -288.1421)
			(xy 358.202185 -288.155792) (xy 358.15333 -288.161724) (xy 358.104155 -288.159743) (xy 358.055936 -288.149899)
			(xy 358.00992 -288.132447) (xy 357.967299 -288.10784) (xy 357.929178 -288.076715) (xy 357.896543 -288.039878)
			(xy 357.87024 -287.998282) (xy 357.850949 -287.953006) (xy 357.839172 -287.905222) (xy 357.835212 -287.856168)
			(xy 357.506524 -287.856168) (xy 357.506029 -287.880775) (xy 357.498134 -287.929352) (xy 357.48255 -287.976033)
			(xy 357.459679 -288.01961) (xy 357.430114 -288.058954) (xy 357.394621 -288.093046) (xy 357.354118 -288.121002)
			(xy 357.309656 -288.1421) (xy 357.262385 -288.155792) (xy 357.21353 -288.161724) (xy 357.164355 -288.159743)
			(xy 357.116136 -288.149899) (xy 357.07012 -288.132447) (xy 357.027499 -288.10784) (xy 356.989378 -288.076715)
			(xy 356.956743 -288.039878) (xy 356.93044 -287.998282) (xy 356.911149 -287.953006) (xy 356.899372 -287.905222)
			(xy 356.895412 -287.856168) (xy 356.56647 -287.856168) (xy 356.565975 -287.880775) (xy 356.55808 -287.929352)
			(xy 356.542496 -287.976033) (xy 356.519625 -288.01961) (xy 356.49006 -288.058954) (xy 356.454567 -288.093046)
			(xy 356.414064 -288.121002) (xy 356.369602 -288.1421) (xy 356.322331 -288.155792) (xy 356.273476 -288.161724)
			(xy 356.224301 -288.159743) (xy 356.176082 -288.149899) (xy 356.130066 -288.132447) (xy 356.087445 -288.10784)
			(xy 356.049324 -288.076715) (xy 356.016689 -288.039878) (xy 355.990386 -287.998282) (xy 355.971095 -287.953006)
			(xy 355.959318 -287.905222) (xy 355.955358 -287.856168) (xy 355.626896 -287.856168) (xy 355.626899 -287.8562)
			(xy 355.622728 -287.906532) (xy 355.610331 -287.955491) (xy 355.590043 -288.001742) (xy 355.56242 -288.044023)
			(xy 355.528215 -288.081181) (xy 355.48836 -288.112202) (xy 355.443943 -288.13624) (xy 355.396176 -288.15264)
			(xy 355.34636 -288.160954) (xy 355.321108 -288.161476) (xy 354.381054 -288.161476) (xy 354.355799 -288.161015)
			(xy 354.305977 -288.152694) (xy 354.258205 -288.136288) (xy 354.213784 -288.112242) (xy 354.173927 -288.081214)
			(xy 354.139719 -288.04405) (xy 354.112095 -288.001762) (xy 354.091806 -287.955504) (xy 354.079408 -287.906539)
			(xy 354.075237 -287.8562) (xy 353.746307 -287.8562) (xy 353.745813 -287.880775) (xy 353.737918 -287.929352)
			(xy 353.722334 -287.976033) (xy 353.699463 -288.01961) (xy 353.669898 -288.058954) (xy 353.634405 -288.093046)
			(xy 353.593902 -288.121002) (xy 353.54944 -288.1421) (xy 353.502169 -288.155792) (xy 353.453314 -288.161724)
			(xy 353.404139 -288.159743) (xy 353.35592 -288.149899) (xy 353.309904 -288.132447) (xy 353.267283 -288.10784)
			(xy 353.229162 -288.076715) (xy 353.196527 -288.039878) (xy 353.170224 -287.998282) (xy 353.150933 -287.953006)
			(xy 353.139156 -287.905222) (xy 353.135196 -287.856168) (xy 352.806996 -287.856168) (xy 352.806999 -287.8562)
			(xy 352.802828 -287.906533) (xy 352.79043 -287.955493) (xy 352.770142 -288.001744) (xy 352.742518 -288.044026)
			(xy 352.708312 -288.081184) (xy 352.668456 -288.112205) (xy 352.624038 -288.136243) (xy 352.576269 -288.152642)
			(xy 352.526453 -288.160955) (xy 352.5012 -288.161476) (xy 351.561146 -288.161476) (xy 351.535883 -288.161051)
			(xy 351.486046 -288.152741) (xy 351.438256 -288.136341) (xy 351.393817 -288.112298) (xy 351.353943 -288.081268)
			(xy 351.31972 -288.044098) (xy 351.292083 -288.001801) (xy 351.271785 -287.955532) (xy 351.259381 -287.906553)
			(xy 351.255208 -287.8562) (xy 350.926399 -287.8562) (xy 350.925905 -287.880775) (xy 350.91801 -287.929352)
			(xy 350.902426 -287.976033) (xy 350.879555 -288.01961) (xy 350.84999 -288.058954) (xy 350.814497 -288.093046)
			(xy 350.773994 -288.121002) (xy 350.729532 -288.1421) (xy 350.682261 -288.155792) (xy 350.633406 -288.161724)
			(xy 350.584231 -288.159743) (xy 350.536012 -288.149899) (xy 350.489996 -288.132447) (xy 350.447375 -288.10784)
			(xy 350.409254 -288.076715) (xy 350.376619 -288.039878) (xy 350.350316 -287.998282) (xy 350.331025 -287.953006)
			(xy 350.319248 -287.905222) (xy 350.315288 -287.856168) (xy 349.987125 -287.856168) (xy 349.987128 -287.8562)
			(xy 349.982957 -287.906538) (xy 349.970557 -287.955504) (xy 349.950266 -288.00176) (xy 349.922639 -288.044046)
			(xy 349.888429 -288.081208) (xy 349.848568 -288.112232) (xy 349.804144 -288.136271) (xy 349.75637 -288.152671)
			(xy 349.706548 -288.160984) (xy 349.681292 -288.161476) (xy 348.741238 -288.161476) (xy 348.715976 -288.16105)
			(xy 348.666139 -288.15274) (xy 348.61835 -288.136339) (xy 348.573913 -288.112296) (xy 348.53404 -288.081266)
			(xy 348.499818 -288.044095) (xy 348.472182 -288.001799) (xy 348.451885 -287.955531) (xy 348.439481 -287.906552)
			(xy 348.435308 -287.8562) (xy 348.106491 -287.8562) (xy 348.105997 -287.880775) (xy 348.098102 -287.929352)
			(xy 348.082518 -287.976033) (xy 348.059647 -288.01961) (xy 348.030082 -288.058954) (xy 347.994589 -288.093046)
			(xy 347.954086 -288.121002) (xy 347.909624 -288.1421) (xy 347.862353 -288.155792) (xy 347.813498 -288.161724)
			(xy 347.764323 -288.159743) (xy 347.716104 -288.149899) (xy 347.670088 -288.132447) (xy 347.627467 -288.10784)
			(xy 347.589346 -288.076715) (xy 347.556711 -288.039878) (xy 347.530408 -287.998282) (xy 347.511117 -287.953006)
			(xy 347.49934 -287.905222) (xy 347.49538 -287.856168) (xy 347.166896 -287.856168) (xy 347.166899 -287.8562)
			(xy 347.162729 -287.90653) (xy 347.150332 -287.955487) (xy 347.130047 -288.001736) (xy 347.102426 -288.044016)
			(xy 347.068224 -288.081173) (xy 347.028372 -288.112194) (xy 346.983958 -288.136234) (xy 346.936194 -288.152635)
			(xy 346.886381 -288.160952) (xy 346.86113 -288.161476) (xy 345.921076 -288.161476) (xy 345.895819 -288.161016)
			(xy 345.845995 -288.152699) (xy 345.79822 -288.136294) (xy 345.753796 -288.11225) (xy 345.713935 -288.081222)
			(xy 345.679725 -288.044057) (xy 345.652098 -288.001768) (xy 345.631808 -287.955509) (xy 345.619408 -287.906541)
			(xy 345.615237 -287.8562) (xy 345.286865 -287.8562) (xy 345.282711 -287.906436) (xy 345.270363 -287.955307)
			(xy 345.250156 -288.001487) (xy 345.222639 -288.04372) (xy 345.188559 -288.080861) (xy 345.148842 -288.1119)
			(xy 345.104566 -288.135994) (xy 345.056934 -288.152489) (xy 345.00724 -288.160937) (xy 344.982038 -288.161476)
			(xy 344.971972 -288.16191) (xy 344.953382 -288.169637) (xy 344.94597 -288.176462) (xy 344.895424 -288.227262)
			(xy 344.888731 -288.234668) (xy 344.881132 -288.253105) (xy 344.880692 -288.263076) (xy 344.880692 -288.66592)
			(xy 345.145372 -288.66592) (xy 345.149332 -288.616866) (xy 345.161109 -288.569082) (xy 345.1804 -288.523806)
			(xy 345.206703 -288.48221) (xy 345.239338 -288.445373) (xy 345.277459 -288.414248) (xy 345.32008 -288.389641)
			(xy 345.366096 -288.372189) (xy 345.414315 -288.362345) (xy 345.46349 -288.360364) (xy 345.512345 -288.366296)
			(xy 345.559616 -288.379988) (xy 345.604078 -288.401086) (xy 345.644581 -288.429042) (xy 345.680074 -288.463134)
			(xy 345.709639 -288.502478) (xy 345.73251 -288.546055) (xy 345.748094 -288.592736) (xy 345.755989 -288.641313)
			(xy 345.756484 -288.66592) (xy 346.085426 -288.66592) (xy 346.089386 -288.616866) (xy 346.101163 -288.569082)
			(xy 346.120454 -288.523806) (xy 346.146757 -288.48221) (xy 346.179392 -288.445373) (xy 346.217513 -288.414248)
			(xy 346.260134 -288.389641) (xy 346.30615 -288.372189) (xy 346.354369 -288.362345) (xy 346.403544 -288.360364)
			(xy 346.452399 -288.366296) (xy 346.49967 -288.379988) (xy 346.544132 -288.401086) (xy 346.584635 -288.429042)
			(xy 346.620128 -288.463134) (xy 346.649693 -288.502478) (xy 346.672564 -288.546055) (xy 346.688148 -288.592736)
			(xy 346.696043 -288.641313) (xy 346.696538 -288.66592) (xy 347.025226 -288.66592) (xy 347.029186 -288.616866)
			(xy 347.040963 -288.569082) (xy 347.060254 -288.523806) (xy 347.086557 -288.48221) (xy 347.119192 -288.445373)
			(xy 347.157313 -288.414248) (xy 347.199934 -288.389641) (xy 347.24595 -288.372189) (xy 347.294169 -288.362345)
			(xy 347.343344 -288.360364) (xy 347.392199 -288.366296) (xy 347.43947 -288.379988) (xy 347.483932 -288.401086)
			(xy 347.524435 -288.429042) (xy 347.559928 -288.463134) (xy 347.589493 -288.502478) (xy 347.612364 -288.546055)
			(xy 347.627948 -288.592736) (xy 347.635843 -288.641313) (xy 347.636338 -288.66592) (xy 347.96528 -288.66592)
			(xy 347.96924 -288.616866) (xy 347.981017 -288.569082) (xy 348.000308 -288.523806) (xy 348.026611 -288.48221)
			(xy 348.059246 -288.445373) (xy 348.097367 -288.414248) (xy 348.139988 -288.389641) (xy 348.186004 -288.372189)
			(xy 348.234223 -288.362345) (xy 348.283398 -288.360364) (xy 348.332253 -288.366296) (xy 348.379524 -288.379988)
			(xy 348.423986 -288.401086) (xy 348.464489 -288.429042) (xy 348.499982 -288.463134) (xy 348.529547 -288.502478)
			(xy 348.552418 -288.546055) (xy 348.568002 -288.592736) (xy 348.575897 -288.641313) (xy 348.576392 -288.66592)
			(xy 348.905334 -288.66592) (xy 348.909294 -288.616866) (xy 348.921071 -288.569082) (xy 348.940362 -288.523806)
			(xy 348.966665 -288.48221) (xy 348.9993 -288.445373) (xy 349.037421 -288.414248) (xy 349.080042 -288.389641)
			(xy 349.126058 -288.372189) (xy 349.174277 -288.362345) (xy 349.223452 -288.360364) (xy 349.272307 -288.366296)
			(xy 349.319578 -288.379988) (xy 349.36404 -288.401086) (xy 349.404543 -288.429042) (xy 349.440036 -288.463134)
			(xy 349.469601 -288.502478) (xy 349.492472 -288.546055) (xy 349.508056 -288.592736) (xy 349.515951 -288.641313)
			(xy 349.516446 -288.66592) (xy 349.845388 -288.66592) (xy 349.849348 -288.616866) (xy 349.861125 -288.569082)
			(xy 349.880416 -288.523806) (xy 349.906719 -288.48221) (xy 349.939354 -288.445373) (xy 349.977475 -288.414248)
			(xy 350.020096 -288.389641) (xy 350.066112 -288.372189) (xy 350.114331 -288.362345) (xy 350.163506 -288.360364)
			(xy 350.212361 -288.366296) (xy 350.259632 -288.379988) (xy 350.304094 -288.401086) (xy 350.344597 -288.429042)
			(xy 350.38009 -288.463134) (xy 350.409655 -288.502478) (xy 350.432526 -288.546055) (xy 350.44811 -288.592736)
			(xy 350.456005 -288.641313) (xy 350.4565 -288.66592) (xy 350.785442 -288.66592) (xy 350.789402 -288.616866)
			(xy 350.801179 -288.569082) (xy 350.82047 -288.523806) (xy 350.846773 -288.48221) (xy 350.879408 -288.445373)
			(xy 350.917529 -288.414248) (xy 350.96015 -288.389641) (xy 351.006166 -288.372189) (xy 351.054385 -288.362345)
			(xy 351.10356 -288.360364) (xy 351.152415 -288.366296) (xy 351.199686 -288.379988) (xy 351.244148 -288.401086)
			(xy 351.284651 -288.429042) (xy 351.320144 -288.463134) (xy 351.349709 -288.502478) (xy 351.37258 -288.546055)
			(xy 351.388164 -288.592736) (xy 351.396059 -288.641313) (xy 351.396554 -288.66592) (xy 351.725242 -288.66592)
			(xy 351.729202 -288.616866) (xy 351.740979 -288.569082) (xy 351.76027 -288.523806) (xy 351.786573 -288.48221)
			(xy 351.819208 -288.445373) (xy 351.857329 -288.414248) (xy 351.89995 -288.389641) (xy 351.945966 -288.372189)
			(xy 351.994185 -288.362345) (xy 352.04336 -288.360364) (xy 352.092215 -288.366296) (xy 352.139486 -288.379988)
			(xy 352.183948 -288.401086) (xy 352.224451 -288.429042) (xy 352.259944 -288.463134) (xy 352.289509 -288.502478)
			(xy 352.31238 -288.546055) (xy 352.327964 -288.592736) (xy 352.335859 -288.641313) (xy 352.336354 -288.66592)
			(xy 352.665296 -288.66592) (xy 352.669256 -288.616866) (xy 352.681033 -288.569082) (xy 352.700324 -288.523806)
			(xy 352.726627 -288.48221) (xy 352.759262 -288.445373) (xy 352.797383 -288.414248) (xy 352.840004 -288.389641)
			(xy 352.88602 -288.372189) (xy 352.934239 -288.362345) (xy 352.983414 -288.360364) (xy 353.032269 -288.366296)
			(xy 353.07954 -288.379988) (xy 353.124002 -288.401086) (xy 353.164505 -288.429042) (xy 353.199998 -288.463134)
			(xy 353.229563 -288.502478) (xy 353.252434 -288.546055) (xy 353.268018 -288.592736) (xy 353.275913 -288.641313)
			(xy 353.276408 -288.66592) (xy 353.60535 -288.66592) (xy 353.60931 -288.616866) (xy 353.621087 -288.569082)
			(xy 353.640378 -288.523806) (xy 353.666681 -288.48221) (xy 353.699316 -288.445373) (xy 353.737437 -288.414248)
			(xy 353.780058 -288.389641) (xy 353.826074 -288.372189) (xy 353.874293 -288.362345) (xy 353.923468 -288.360364)
			(xy 353.972323 -288.366296) (xy 354.019594 -288.379988) (xy 354.064056 -288.401086) (xy 354.104559 -288.429042)
			(xy 354.140052 -288.463134) (xy 354.169617 -288.502478) (xy 354.192488 -288.546055) (xy 354.208072 -288.592736)
			(xy 354.215967 -288.641313) (xy 354.216462 -288.66592) (xy 354.545404 -288.66592) (xy 354.549364 -288.616866)
			(xy 354.561141 -288.569082) (xy 354.580432 -288.523806) (xy 354.606735 -288.48221) (xy 354.63937 -288.445373)
			(xy 354.677491 -288.414248) (xy 354.720112 -288.389641) (xy 354.766128 -288.372189) (xy 354.814347 -288.362345)
			(xy 354.863522 -288.360364) (xy 354.912377 -288.366296) (xy 354.959648 -288.379988) (xy 355.00411 -288.401086)
			(xy 355.044613 -288.429042) (xy 355.080106 -288.463134) (xy 355.109671 -288.502478) (xy 355.132542 -288.546055)
			(xy 355.148126 -288.592736) (xy 355.156021 -288.641313) (xy 355.156516 -288.66592) (xy 355.485204 -288.66592)
			(xy 355.489164 -288.616866) (xy 355.500941 -288.569082) (xy 355.520232 -288.523806) (xy 355.546535 -288.48221)
			(xy 355.57917 -288.445373) (xy 355.617291 -288.414248) (xy 355.659912 -288.389641) (xy 355.705928 -288.372189)
			(xy 355.754147 -288.362345) (xy 355.803322 -288.360364) (xy 355.852177 -288.366296) (xy 355.899448 -288.379988)
			(xy 355.94391 -288.401086) (xy 355.984413 -288.429042) (xy 356.019906 -288.463134) (xy 356.049471 -288.502478)
			(xy 356.072342 -288.546055) (xy 356.087926 -288.592736) (xy 356.095821 -288.641313) (xy 356.096316 -288.6659)
			(xy 356.425289 -288.6659) (xy 356.429459 -288.615569) (xy 356.441856 -288.566611) (xy 356.462142 -288.520361)
			(xy 356.489762 -288.47808) (xy 356.523965 -288.440921) (xy 356.563817 -288.409898) (xy 356.608231 -288.385858)
			(xy 356.655997 -288.369455) (xy 356.70581 -288.361136) (xy 356.731062 -288.360612) (xy 357.671116 -288.360612)
			(xy 357.696372 -288.361095) (xy 357.746195 -288.369411) (xy 357.79397 -288.385815) (xy 357.838393 -288.409857)
			(xy 357.878253 -288.440884) (xy 357.912464 -288.478048) (xy 357.94009 -288.520335) (xy 357.96038 -288.566594)
			(xy 357.97278 -288.61556) (xy 357.976951 -288.6659) (xy 357.976949 -288.66592) (xy 358.305366 -288.66592)
			(xy 358.309326 -288.616866) (xy 358.321103 -288.569082) (xy 358.340394 -288.523806) (xy 358.366697 -288.48221)
			(xy 358.399332 -288.445373) (xy 358.437453 -288.414248) (xy 358.480074 -288.389641) (xy 358.52609 -288.372189)
			(xy 358.574309 -288.362345) (xy 358.623484 -288.360364) (xy 358.672339 -288.366296) (xy 358.71961 -288.379988)
			(xy 358.764072 -288.401086) (xy 358.804575 -288.429042) (xy 358.840068 -288.463134) (xy 358.869633 -288.502478)
			(xy 358.892504 -288.546055) (xy 358.908088 -288.592736) (xy 358.915983 -288.641313) (xy 358.916478 -288.66592)
			(xy 361.118924 -288.66592) (xy 361.122884 -288.616866) (xy 361.134661 -288.569082) (xy 361.153952 -288.523806)
			(xy 361.180255 -288.48221) (xy 361.21289 -288.445373) (xy 361.251011 -288.414248) (xy 361.293632 -288.389641)
			(xy 361.339648 -288.372189) (xy 361.387867 -288.362345) (xy 361.437042 -288.360364) (xy 361.485897 -288.366296)
			(xy 361.533168 -288.379988) (xy 361.57763 -288.401086) (xy 361.618133 -288.429042) (xy 361.653626 -288.463134)
			(xy 361.683191 -288.502478) (xy 361.706062 -288.546055) (xy 361.721646 -288.592736) (xy 361.729541 -288.641313)
			(xy 361.730036 -288.6659) (xy 362.058989 -288.6659) (xy 362.06316 -288.615567) (xy 362.075557 -288.566607)
			(xy 362.095845 -288.520355) (xy 362.123467 -288.478073) (xy 362.157673 -288.440914) (xy 362.197528 -288.409892)
			(xy 362.241945 -288.385852) (xy 362.289713 -288.36945) (xy 362.339529 -288.361135) (xy 362.364782 -288.360612)
			(xy 363.304836 -288.360612) (xy 363.330091 -288.361096) (xy 363.379911 -288.369415) (xy 363.427683 -288.38582)
			(xy 363.472104 -288.409864) (xy 363.511961 -288.440891) (xy 363.546169 -288.478054) (xy 363.573793 -288.520341)
			(xy 363.594082 -288.566598) (xy 363.60648 -288.615562) (xy 363.610651 -288.6659) (xy 363.610649 -288.66592)
			(xy 363.939086 -288.66592) (xy 363.943046 -288.616866) (xy 363.954823 -288.569082) (xy 363.974114 -288.523806)
			(xy 364.000417 -288.48221) (xy 364.033052 -288.445373) (xy 364.071173 -288.414248) (xy 364.113794 -288.389641)
			(xy 364.15981 -288.372189) (xy 364.208029 -288.362345) (xy 364.257204 -288.360364) (xy 364.306059 -288.366296)
			(xy 364.35333 -288.379988) (xy 364.397792 -288.401086) (xy 364.438295 -288.429042) (xy 364.473788 -288.463134)
			(xy 364.503353 -288.502478) (xy 364.526224 -288.546055) (xy 364.541808 -288.592736) (xy 364.549703 -288.641313)
			(xy 364.550198 -288.66592) (xy 364.878886 -288.66592) (xy 364.882846 -288.616866) (xy 364.894623 -288.569082)
			(xy 364.913914 -288.523806) (xy 364.940217 -288.48221) (xy 364.972852 -288.445373) (xy 365.010973 -288.414248)
			(xy 365.053594 -288.389641) (xy 365.09961 -288.372189) (xy 365.147829 -288.362345) (xy 365.197004 -288.360364)
			(xy 365.245859 -288.366296) (xy 365.29313 -288.379988) (xy 365.337592 -288.401086) (xy 365.378095 -288.429042)
			(xy 365.413588 -288.463134) (xy 365.443153 -288.502478) (xy 365.466024 -288.546055) (xy 365.481608 -288.592736)
			(xy 365.489503 -288.641313) (xy 365.489998 -288.66592) (xy 365.81894 -288.66592) (xy 365.8229 -288.616866)
			(xy 365.834677 -288.569082) (xy 365.853968 -288.523806) (xy 365.880271 -288.48221) (xy 365.912906 -288.445373)
			(xy 365.951027 -288.414248) (xy 365.993648 -288.389641) (xy 366.039664 -288.372189) (xy 366.087883 -288.362345)
			(xy 366.137058 -288.360364) (xy 366.185913 -288.366296) (xy 366.233184 -288.379988) (xy 366.277646 -288.401086)
			(xy 366.318149 -288.429042) (xy 366.353642 -288.463134) (xy 366.383207 -288.502478) (xy 366.406078 -288.546055)
			(xy 366.421662 -288.592736) (xy 366.429557 -288.641313) (xy 366.430052 -288.66592) (xy 366.758994 -288.66592)
			(xy 366.762954 -288.616866) (xy 366.774731 -288.569082) (xy 366.794022 -288.523806) (xy 366.820325 -288.48221)
			(xy 366.85296 -288.445373) (xy 366.891081 -288.414248) (xy 366.933702 -288.389641) (xy 366.979718 -288.372189)
			(xy 367.027937 -288.362345) (xy 367.077112 -288.360364) (xy 367.125967 -288.366296) (xy 367.173238 -288.379988)
			(xy 367.2177 -288.401086) (xy 367.258203 -288.429042) (xy 367.293696 -288.463134) (xy 367.323261 -288.502478)
			(xy 367.346132 -288.546055) (xy 367.361716 -288.592736) (xy 367.369611 -288.641313) (xy 367.370106 -288.66592)
			(xy 367.699048 -288.66592) (xy 367.703008 -288.616866) (xy 367.714785 -288.569082) (xy 367.734076 -288.523806)
			(xy 367.760379 -288.48221) (xy 367.793014 -288.445373) (xy 367.831135 -288.414248) (xy 367.873756 -288.389641)
			(xy 367.919772 -288.372189) (xy 367.967991 -288.362345) (xy 368.017166 -288.360364) (xy 368.066021 -288.366296)
			(xy 368.113292 -288.379988) (xy 368.157754 -288.401086) (xy 368.198257 -288.429042) (xy 368.23375 -288.463134)
			(xy 368.263315 -288.502478) (xy 368.286186 -288.546055) (xy 368.30177 -288.592736) (xy 368.309665 -288.641313)
			(xy 368.31016 -288.66592) (xy 368.639102 -288.66592) (xy 368.643062 -288.616866) (xy 368.654839 -288.569082)
			(xy 368.67413 -288.523806) (xy 368.700433 -288.48221) (xy 368.733068 -288.445373) (xy 368.771189 -288.414248)
			(xy 368.81381 -288.389641) (xy 368.859826 -288.372189) (xy 368.908045 -288.362345) (xy 368.95722 -288.360364)
			(xy 369.006075 -288.366296) (xy 369.053346 -288.379988) (xy 369.097808 -288.401086) (xy 369.138311 -288.429042)
			(xy 369.173804 -288.463134) (xy 369.203369 -288.502478) (xy 369.22624 -288.546055) (xy 369.241824 -288.592736)
			(xy 369.249719 -288.641313) (xy 369.250214 -288.66592) (xy 369.578902 -288.66592) (xy 369.582862 -288.616866)
			(xy 369.594639 -288.569082) (xy 369.61393 -288.523806) (xy 369.640233 -288.48221) (xy 369.672868 -288.445373)
			(xy 369.710989 -288.414248) (xy 369.75361 -288.389641) (xy 369.799626 -288.372189) (xy 369.847845 -288.362345)
			(xy 369.89702 -288.360364) (xy 369.945875 -288.366296) (xy 369.993146 -288.379988) (xy 370.037608 -288.401086)
			(xy 370.078111 -288.429042) (xy 370.113604 -288.463134) (xy 370.143169 -288.502478) (xy 370.16604 -288.546055)
			(xy 370.181624 -288.592736) (xy 370.189519 -288.641313) (xy 370.190014 -288.66592) (xy 370.518956 -288.66592)
			(xy 370.522916 -288.616866) (xy 370.534693 -288.569082) (xy 370.553984 -288.523806) (xy 370.580287 -288.48221)
			(xy 370.612922 -288.445373) (xy 370.651043 -288.414248) (xy 370.693664 -288.389641) (xy 370.73968 -288.372189)
			(xy 370.787899 -288.362345) (xy 370.837074 -288.360364) (xy 370.885929 -288.366296) (xy 370.9332 -288.379988)
			(xy 370.977662 -288.401086) (xy 371.018165 -288.429042) (xy 371.053658 -288.463134) (xy 371.083223 -288.502478)
			(xy 371.106094 -288.546055) (xy 371.121678 -288.592736) (xy 371.129573 -288.641313) (xy 371.130068 -288.66592)
			(xy 371.45901 -288.66592) (xy 371.46297 -288.616866) (xy 371.474747 -288.569082) (xy 371.494038 -288.523806)
			(xy 371.520341 -288.48221) (xy 371.552976 -288.445373) (xy 371.591097 -288.414248) (xy 371.633718 -288.389641)
			(xy 371.679734 -288.372189) (xy 371.727953 -288.362345) (xy 371.777128 -288.360364) (xy 371.825983 -288.366296)
			(xy 371.873254 -288.379988) (xy 371.917716 -288.401086) (xy 371.958219 -288.429042) (xy 371.993712 -288.463134)
			(xy 372.023277 -288.502478) (xy 372.046148 -288.546055) (xy 372.061732 -288.592736) (xy 372.069627 -288.641313)
			(xy 372.070122 -288.66592) (xy 372.399064 -288.66592) (xy 372.403024 -288.616866) (xy 372.414801 -288.569082)
			(xy 372.434092 -288.523806) (xy 372.460395 -288.48221) (xy 372.49303 -288.445373) (xy 372.531151 -288.414248)
			(xy 372.573772 -288.389641) (xy 372.619788 -288.372189) (xy 372.668007 -288.362345) (xy 372.717182 -288.360364)
			(xy 372.766037 -288.366296) (xy 372.813308 -288.379988) (xy 372.85777 -288.401086) (xy 372.898273 -288.429042)
			(xy 372.933766 -288.463134) (xy 372.963331 -288.502478) (xy 372.986202 -288.546055) (xy 373.001786 -288.592736)
			(xy 373.009681 -288.641313) (xy 373.010176 -288.66592) (xy 373.339118 -288.66592) (xy 373.343078 -288.616866)
			(xy 373.354855 -288.569082) (xy 373.374146 -288.523806) (xy 373.400449 -288.48221) (xy 373.433084 -288.445373)
			(xy 373.471205 -288.414248) (xy 373.513826 -288.389641) (xy 373.559842 -288.372189) (xy 373.608061 -288.362345)
			(xy 373.657236 -288.360364) (xy 373.706091 -288.366296) (xy 373.753362 -288.379988) (xy 373.797824 -288.401086)
			(xy 373.838327 -288.429042) (xy 373.87382 -288.463134) (xy 373.903385 -288.502478) (xy 373.926256 -288.546055)
			(xy 373.94184 -288.592736) (xy 373.949735 -288.641313) (xy 373.95023 -288.66592) (xy 373.949735 -288.690527)
			(xy 373.94184 -288.739104) (xy 373.926256 -288.785785) (xy 373.903385 -288.829362) (xy 373.87382 -288.868706)
			(xy 373.838327 -288.902798) (xy 373.797824 -288.930754) (xy 373.753362 -288.951852) (xy 373.706091 -288.965544)
			(xy 373.657236 -288.971476) (xy 373.608061 -288.969495) (xy 373.559842 -288.959651) (xy 373.513826 -288.942199)
			(xy 373.471205 -288.917592) (xy 373.433084 -288.886467) (xy 373.400449 -288.84963) (xy 373.374146 -288.808034)
			(xy 373.354855 -288.762758) (xy 373.343078 -288.714974) (xy 373.339118 -288.66592) (xy 373.010176 -288.66592)
			(xy 373.009681 -288.690527) (xy 373.001786 -288.739104) (xy 372.986202 -288.785785) (xy 372.963331 -288.829362)
			(xy 372.933766 -288.868706) (xy 372.898273 -288.902798) (xy 372.85777 -288.930754) (xy 372.813308 -288.951852)
			(xy 372.766037 -288.965544) (xy 372.717182 -288.971476) (xy 372.668007 -288.969495) (xy 372.619788 -288.959651)
			(xy 372.573772 -288.942199) (xy 372.531151 -288.917592) (xy 372.49303 -288.886467) (xy 372.460395 -288.84963)
			(xy 372.434092 -288.808034) (xy 372.414801 -288.762758) (xy 372.403024 -288.714974) (xy 372.399064 -288.66592)
			(xy 372.070122 -288.66592) (xy 372.069627 -288.690527) (xy 372.061732 -288.739104) (xy 372.046148 -288.785785)
			(xy 372.023277 -288.829362) (xy 371.993712 -288.868706) (xy 371.958219 -288.902798) (xy 371.917716 -288.930754)
			(xy 371.873254 -288.951852) (xy 371.825983 -288.965544) (xy 371.777128 -288.971476) (xy 371.727953 -288.969495)
			(xy 371.679734 -288.959651) (xy 371.633718 -288.942199) (xy 371.591097 -288.917592) (xy 371.552976 -288.886467)
			(xy 371.520341 -288.84963) (xy 371.494038 -288.808034) (xy 371.474747 -288.762758) (xy 371.46297 -288.714974)
			(xy 371.45901 -288.66592) (xy 371.130068 -288.66592) (xy 371.129573 -288.690527) (xy 371.121678 -288.739104)
			(xy 371.106094 -288.785785) (xy 371.083223 -288.829362) (xy 371.053658 -288.868706) (xy 371.018165 -288.902798)
			(xy 370.977662 -288.930754) (xy 370.9332 -288.951852) (xy 370.885929 -288.965544) (xy 370.837074 -288.971476)
			(xy 370.787899 -288.969495) (xy 370.73968 -288.959651) (xy 370.693664 -288.942199) (xy 370.651043 -288.917592)
			(xy 370.612922 -288.886467) (xy 370.580287 -288.84963) (xy 370.553984 -288.808034) (xy 370.534693 -288.762758)
			(xy 370.522916 -288.714974) (xy 370.518956 -288.66592) (xy 370.190014 -288.66592) (xy 370.189519 -288.690527)
			(xy 370.181624 -288.739104) (xy 370.16604 -288.785785) (xy 370.143169 -288.829362) (xy 370.113604 -288.868706)
			(xy 370.078111 -288.902798) (xy 370.037608 -288.930754) (xy 369.993146 -288.951852) (xy 369.945875 -288.965544)
			(xy 369.89702 -288.971476) (xy 369.847845 -288.969495) (xy 369.799626 -288.959651) (xy 369.75361 -288.942199)
			(xy 369.710989 -288.917592) (xy 369.672868 -288.886467) (xy 369.640233 -288.84963) (xy 369.61393 -288.808034)
			(xy 369.594639 -288.762758) (xy 369.582862 -288.714974) (xy 369.578902 -288.66592) (xy 369.250214 -288.66592)
			(xy 369.249719 -288.690527) (xy 369.241824 -288.739104) (xy 369.22624 -288.785785) (xy 369.203369 -288.829362)
			(xy 369.173804 -288.868706) (xy 369.138311 -288.902798) (xy 369.097808 -288.930754) (xy 369.053346 -288.951852)
			(xy 369.006075 -288.965544) (xy 368.95722 -288.971476) (xy 368.908045 -288.969495) (xy 368.859826 -288.959651)
			(xy 368.81381 -288.942199) (xy 368.771189 -288.917592) (xy 368.733068 -288.886467) (xy 368.700433 -288.84963)
			(xy 368.67413 -288.808034) (xy 368.654839 -288.762758) (xy 368.643062 -288.714974) (xy 368.639102 -288.66592)
			(xy 368.31016 -288.66592) (xy 368.309665 -288.690527) (xy 368.30177 -288.739104) (xy 368.286186 -288.785785)
			(xy 368.263315 -288.829362) (xy 368.23375 -288.868706) (xy 368.198257 -288.902798) (xy 368.157754 -288.930754)
			(xy 368.113292 -288.951852) (xy 368.066021 -288.965544) (xy 368.017166 -288.971476) (xy 367.967991 -288.969495)
			(xy 367.919772 -288.959651) (xy 367.873756 -288.942199) (xy 367.831135 -288.917592) (xy 367.793014 -288.886467)
			(xy 367.760379 -288.84963) (xy 367.734076 -288.808034) (xy 367.714785 -288.762758) (xy 367.703008 -288.714974)
			(xy 367.699048 -288.66592) (xy 367.370106 -288.66592) (xy 367.369611 -288.690527) (xy 367.361716 -288.739104)
			(xy 367.346132 -288.785785) (xy 367.323261 -288.829362) (xy 367.293696 -288.868706) (xy 367.258203 -288.902798)
			(xy 367.2177 -288.930754) (xy 367.173238 -288.951852) (xy 367.125967 -288.965544) (xy 367.077112 -288.971476)
			(xy 367.027937 -288.969495) (xy 366.979718 -288.959651) (xy 366.933702 -288.942199) (xy 366.891081 -288.917592)
			(xy 366.85296 -288.886467) (xy 366.820325 -288.84963) (xy 366.794022 -288.808034) (xy 366.774731 -288.762758)
			(xy 366.762954 -288.714974) (xy 366.758994 -288.66592) (xy 366.430052 -288.66592) (xy 366.429557 -288.690527)
			(xy 366.421662 -288.739104) (xy 366.406078 -288.785785) (xy 366.383207 -288.829362) (xy 366.353642 -288.868706)
			(xy 366.318149 -288.902798) (xy 366.277646 -288.930754) (xy 366.233184 -288.951852) (xy 366.185913 -288.965544)
			(xy 366.137058 -288.971476) (xy 366.087883 -288.969495) (xy 366.039664 -288.959651) (xy 365.993648 -288.942199)
			(xy 365.951027 -288.917592) (xy 365.912906 -288.886467) (xy 365.880271 -288.84963) (xy 365.853968 -288.808034)
			(xy 365.834677 -288.762758) (xy 365.8229 -288.714974) (xy 365.81894 -288.66592) (xy 365.489998 -288.66592)
			(xy 365.489503 -288.690527) (xy 365.481608 -288.739104) (xy 365.466024 -288.785785) (xy 365.443153 -288.829362)
			(xy 365.413588 -288.868706) (xy 365.378095 -288.902798) (xy 365.337592 -288.930754) (xy 365.29313 -288.951852)
			(xy 365.245859 -288.965544) (xy 365.197004 -288.971476) (xy 365.147829 -288.969495) (xy 365.09961 -288.959651)
			(xy 365.053594 -288.942199) (xy 365.010973 -288.917592) (xy 364.972852 -288.886467) (xy 364.940217 -288.84963)
			(xy 364.913914 -288.808034) (xy 364.894623 -288.762758) (xy 364.882846 -288.714974) (xy 364.878886 -288.66592)
			(xy 364.550198 -288.66592) (xy 364.549703 -288.690527) (xy 364.541808 -288.739104) (xy 364.526224 -288.785785)
			(xy 364.503353 -288.829362) (xy 364.473788 -288.868706) (xy 364.438295 -288.902798) (xy 364.397792 -288.930754)
			(xy 364.35333 -288.951852) (xy 364.306059 -288.965544) (xy 364.257204 -288.971476) (xy 364.208029 -288.969495)
			(xy 364.15981 -288.959651) (xy 364.113794 -288.942199) (xy 364.071173 -288.917592) (xy 364.033052 -288.886467)
			(xy 364.000417 -288.84963) (xy 363.974114 -288.808034) (xy 363.954823 -288.762758) (xy 363.943046 -288.714974)
			(xy 363.939086 -288.66592) (xy 363.610649 -288.66592) (xy 363.60648 -288.716238) (xy 363.594082 -288.765202)
			(xy 363.573793 -288.811459) (xy 363.546169 -288.853746) (xy 363.511961 -288.890909) (xy 363.472104 -288.921936)
			(xy 363.427683 -288.94598) (xy 363.379911 -288.962385) (xy 363.330091 -288.970704) (xy 363.304836 -288.971228)
			(xy 362.364782 -288.971228) (xy 362.339529 -288.970665) (xy 362.289713 -288.96235) (xy 362.241945 -288.945948)
			(xy 362.197528 -288.921908) (xy 362.157673 -288.890886) (xy 362.123467 -288.853727) (xy 362.095845 -288.811445)
			(xy 362.075557 -288.765193) (xy 362.06316 -288.716233) (xy 362.058989 -288.6659) (xy 361.730036 -288.6659)
			(xy 361.730036 -288.66592) (xy 361.729541 -288.690527) (xy 361.721646 -288.739104) (xy 361.706062 -288.785785)
			(xy 361.683191 -288.829362) (xy 361.653626 -288.868706) (xy 361.618133 -288.902798) (xy 361.57763 -288.930754)
			(xy 361.533168 -288.951852) (xy 361.485897 -288.965544) (xy 361.437042 -288.971476) (xy 361.387867 -288.969495)
			(xy 361.339648 -288.959651) (xy 361.293632 -288.942199) (xy 361.251011 -288.917592) (xy 361.21289 -288.886467)
			(xy 361.180255 -288.84963) (xy 361.153952 -288.808034) (xy 361.134661 -288.762758) (xy 361.122884 -288.714974)
			(xy 361.118924 -288.66592) (xy 358.916478 -288.66592) (xy 358.915983 -288.690527) (xy 358.908088 -288.739104)
			(xy 358.892504 -288.785785) (xy 358.869633 -288.829362) (xy 358.840068 -288.868706) (xy 358.804575 -288.902798)
			(xy 358.764072 -288.930754) (xy 358.71961 -288.951852) (xy 358.672339 -288.965544) (xy 358.623484 -288.971476)
			(xy 358.574309 -288.969495) (xy 358.52609 -288.959651) (xy 358.480074 -288.942199) (xy 358.437453 -288.917592)
			(xy 358.399332 -288.886467) (xy 358.366697 -288.84963) (xy 358.340394 -288.808034) (xy 358.321103 -288.762758)
			(xy 358.309326 -288.714974) (xy 358.305366 -288.66592) (xy 357.976949 -288.66592) (xy 357.97278 -288.71624)
			(xy 357.96038 -288.765206) (xy 357.94009 -288.811465) (xy 357.912464 -288.853752) (xy 357.878253 -288.890916)
			(xy 357.838393 -288.921943) (xy 357.79397 -288.945985) (xy 357.746195 -288.962389) (xy 357.696372 -288.970705)
			(xy 357.671116 -288.971228) (xy 356.731062 -288.971228) (xy 356.70581 -288.970664) (xy 356.655997 -288.962345)
			(xy 356.608231 -288.945942) (xy 356.563817 -288.921902) (xy 356.523965 -288.890879) (xy 356.489762 -288.85372)
			(xy 356.462142 -288.811439) (xy 356.441856 -288.765189) (xy 356.429459 -288.716231) (xy 356.425289 -288.6659)
			(xy 356.096316 -288.6659) (xy 356.096316 -288.66592) (xy 356.095821 -288.690527) (xy 356.087926 -288.739104)
			(xy 356.072342 -288.785785) (xy 356.049471 -288.829362) (xy 356.019906 -288.868706) (xy 355.984413 -288.902798)
			(xy 355.94391 -288.930754) (xy 355.899448 -288.951852) (xy 355.852177 -288.965544) (xy 355.803322 -288.971476)
			(xy 355.754147 -288.969495) (xy 355.705928 -288.959651) (xy 355.659912 -288.942199) (xy 355.617291 -288.917592)
			(xy 355.57917 -288.886467) (xy 355.546535 -288.84963) (xy 355.520232 -288.808034) (xy 355.500941 -288.762758)
			(xy 355.489164 -288.714974) (xy 355.485204 -288.66592) (xy 355.156516 -288.66592) (xy 355.156021 -288.690527)
			(xy 355.148126 -288.739104) (xy 355.132542 -288.785785) (xy 355.109671 -288.829362) (xy 355.080106 -288.868706)
			(xy 355.044613 -288.902798) (xy 355.00411 -288.930754) (xy 354.959648 -288.951852) (xy 354.912377 -288.965544)
			(xy 354.863522 -288.971476) (xy 354.814347 -288.969495) (xy 354.766128 -288.959651) (xy 354.720112 -288.942199)
			(xy 354.677491 -288.917592) (xy 354.63937 -288.886467) (xy 354.606735 -288.84963) (xy 354.580432 -288.808034)
			(xy 354.561141 -288.762758) (xy 354.549364 -288.714974) (xy 354.545404 -288.66592) (xy 354.216462 -288.66592)
			(xy 354.215967 -288.690527) (xy 354.208072 -288.739104) (xy 354.192488 -288.785785) (xy 354.169617 -288.829362)
			(xy 354.140052 -288.868706) (xy 354.104559 -288.902798) (xy 354.064056 -288.930754) (xy 354.019594 -288.951852)
			(xy 353.972323 -288.965544) (xy 353.923468 -288.971476) (xy 353.874293 -288.969495) (xy 353.826074 -288.959651)
			(xy 353.780058 -288.942199) (xy 353.737437 -288.917592) (xy 353.699316 -288.886467) (xy 353.666681 -288.84963)
			(xy 353.640378 -288.808034) (xy 353.621087 -288.762758) (xy 353.60931 -288.714974) (xy 353.60535 -288.66592)
			(xy 353.276408 -288.66592) (xy 353.275913 -288.690527) (xy 353.268018 -288.739104) (xy 353.252434 -288.785785)
			(xy 353.229563 -288.829362) (xy 353.199998 -288.868706) (xy 353.164505 -288.902798) (xy 353.124002 -288.930754)
			(xy 353.07954 -288.951852) (xy 353.032269 -288.965544) (xy 352.983414 -288.971476) (xy 352.934239 -288.969495)
			(xy 352.88602 -288.959651) (xy 352.840004 -288.942199) (xy 352.797383 -288.917592) (xy 352.759262 -288.886467)
			(xy 352.726627 -288.84963) (xy 352.700324 -288.808034) (xy 352.681033 -288.762758) (xy 352.669256 -288.714974)
			(xy 352.665296 -288.66592) (xy 352.336354 -288.66592) (xy 352.335859 -288.690527) (xy 352.327964 -288.739104)
			(xy 352.31238 -288.785785) (xy 352.289509 -288.829362) (xy 352.259944 -288.868706) (xy 352.224451 -288.902798)
			(xy 352.183948 -288.930754) (xy 352.139486 -288.951852) (xy 352.092215 -288.965544) (xy 352.04336 -288.971476)
			(xy 351.994185 -288.969495) (xy 351.945966 -288.959651) (xy 351.89995 -288.942199) (xy 351.857329 -288.917592)
			(xy 351.819208 -288.886467) (xy 351.786573 -288.84963) (xy 351.76027 -288.808034) (xy 351.740979 -288.762758)
			(xy 351.729202 -288.714974) (xy 351.725242 -288.66592) (xy 351.396554 -288.66592) (xy 351.396059 -288.690527)
			(xy 351.388164 -288.739104) (xy 351.37258 -288.785785) (xy 351.349709 -288.829362) (xy 351.320144 -288.868706)
			(xy 351.284651 -288.902798) (xy 351.244148 -288.930754) (xy 351.199686 -288.951852) (xy 351.152415 -288.965544)
			(xy 351.10356 -288.971476) (xy 351.054385 -288.969495) (xy 351.006166 -288.959651) (xy 350.96015 -288.942199)
			(xy 350.917529 -288.917592) (xy 350.879408 -288.886467) (xy 350.846773 -288.84963) (xy 350.82047 -288.808034)
			(xy 350.801179 -288.762758) (xy 350.789402 -288.714974) (xy 350.785442 -288.66592) (xy 350.4565 -288.66592)
			(xy 350.456005 -288.690527) (xy 350.44811 -288.739104) (xy 350.432526 -288.785785) (xy 350.409655 -288.829362)
			(xy 350.38009 -288.868706) (xy 350.344597 -288.902798) (xy 350.304094 -288.930754) (xy 350.259632 -288.951852)
			(xy 350.212361 -288.965544) (xy 350.163506 -288.971476) (xy 350.114331 -288.969495) (xy 350.066112 -288.959651)
			(xy 350.020096 -288.942199) (xy 349.977475 -288.917592) (xy 349.939354 -288.886467) (xy 349.906719 -288.84963)
			(xy 349.880416 -288.808034) (xy 349.861125 -288.762758) (xy 349.849348 -288.714974) (xy 349.845388 -288.66592)
			(xy 349.516446 -288.66592) (xy 349.515951 -288.690527) (xy 349.508056 -288.739104) (xy 349.492472 -288.785785)
			(xy 349.469601 -288.829362) (xy 349.440036 -288.868706) (xy 349.404543 -288.902798) (xy 349.36404 -288.930754)
			(xy 349.319578 -288.951852) (xy 349.272307 -288.965544) (xy 349.223452 -288.971476) (xy 349.174277 -288.969495)
			(xy 349.126058 -288.959651) (xy 349.080042 -288.942199) (xy 349.037421 -288.917592) (xy 348.9993 -288.886467)
			(xy 348.966665 -288.84963) (xy 348.940362 -288.808034) (xy 348.921071 -288.762758) (xy 348.909294 -288.714974)
			(xy 348.905334 -288.66592) (xy 348.576392 -288.66592) (xy 348.575897 -288.690527) (xy 348.568002 -288.739104)
			(xy 348.552418 -288.785785) (xy 348.529547 -288.829362) (xy 348.499982 -288.868706) (xy 348.464489 -288.902798)
			(xy 348.423986 -288.930754) (xy 348.379524 -288.951852) (xy 348.332253 -288.965544) (xy 348.283398 -288.971476)
			(xy 348.234223 -288.969495) (xy 348.186004 -288.959651) (xy 348.139988 -288.942199) (xy 348.097367 -288.917592)
			(xy 348.059246 -288.886467) (xy 348.026611 -288.84963) (xy 348.000308 -288.808034) (xy 347.981017 -288.762758)
			(xy 347.96924 -288.714974) (xy 347.96528 -288.66592) (xy 347.636338 -288.66592) (xy 347.635843 -288.690527)
			(xy 347.627948 -288.739104) (xy 347.612364 -288.785785) (xy 347.589493 -288.829362) (xy 347.559928 -288.868706)
			(xy 347.524435 -288.902798) (xy 347.483932 -288.930754) (xy 347.43947 -288.951852) (xy 347.392199 -288.965544)
			(xy 347.343344 -288.971476) (xy 347.294169 -288.969495) (xy 347.24595 -288.959651) (xy 347.199934 -288.942199)
			(xy 347.157313 -288.917592) (xy 347.119192 -288.886467) (xy 347.086557 -288.84963) (xy 347.060254 -288.808034)
			(xy 347.040963 -288.762758) (xy 347.029186 -288.714974) (xy 347.025226 -288.66592) (xy 346.696538 -288.66592)
			(xy 346.696043 -288.690527) (xy 346.688148 -288.739104) (xy 346.672564 -288.785785) (xy 346.649693 -288.829362)
			(xy 346.620128 -288.868706) (xy 346.584635 -288.902798) (xy 346.544132 -288.930754) (xy 346.49967 -288.951852)
			(xy 346.452399 -288.965544) (xy 346.403544 -288.971476) (xy 346.354369 -288.969495) (xy 346.30615 -288.959651)
			(xy 346.260134 -288.942199) (xy 346.217513 -288.917592) (xy 346.179392 -288.886467) (xy 346.146757 -288.84963)
			(xy 346.120454 -288.808034) (xy 346.101163 -288.762758) (xy 346.089386 -288.714974) (xy 346.085426 -288.66592)
			(xy 345.756484 -288.66592) (xy 345.755989 -288.690527) (xy 345.748094 -288.739104) (xy 345.73251 -288.785785)
			(xy 345.709639 -288.829362) (xy 345.680074 -288.868706) (xy 345.644581 -288.902798) (xy 345.604078 -288.930754)
			(xy 345.559616 -288.951852) (xy 345.512345 -288.965544) (xy 345.46349 -288.971476) (xy 345.414315 -288.969495)
			(xy 345.366096 -288.959651) (xy 345.32008 -288.942199) (xy 345.277459 -288.917592) (xy 345.239338 -288.886467)
			(xy 345.206703 -288.84963) (xy 345.1804 -288.808034) (xy 345.161109 -288.762758) (xy 345.149332 -288.714974)
			(xy 345.145372 -288.66592) (xy 344.880692 -288.66592) (xy 344.880692 -289.069018) (xy 344.881169 -289.078984)
			(xy 344.888744 -289.097422) (xy 344.895424 -289.104832) (xy 344.94597 -289.155632) (xy 344.953369 -289.162475)
			(xy 344.971968 -289.170194) (xy 344.982038 -289.170618) (xy 345.007235 -289.171221) (xy 345.05692 -289.179667)
			(xy 345.104542 -289.196159) (xy 345.14881 -289.220249) (xy 345.18852 -289.251282) (xy 345.222593 -289.288415)
			(xy 345.250105 -289.330641) (xy 345.270308 -289.376812) (xy 345.282654 -289.425674) (xy 345.286807 -289.4759)
			(xy 345.61504 -289.4759) (xy 345.619214 -289.425527) (xy 345.631622 -289.376527) (xy 345.651925 -289.330238)
			(xy 345.67957 -289.287922) (xy 345.713802 -289.250733) (xy 345.753689 -289.219686) (xy 345.798141 -289.195626)
			(xy 345.845947 -289.179211) (xy 345.895803 -289.170888) (xy 345.921076 -289.170364) (xy 346.86113 -289.170364)
			(xy 346.886407 -289.170836) (xy 346.93627 -289.179162) (xy 346.984084 -289.19558) (xy 347.028543 -289.219644)
			(xy 347.068435 -289.250697) (xy 347.102673 -289.287892) (xy 347.130322 -289.330215) (xy 347.150628 -289.376512)
			(xy 347.163037 -289.425519) (xy 347.167212 -289.4759) (xy 347.16721 -289.475926) (xy 347.49538 -289.475926)
			(xy 347.49934 -289.426872) (xy 347.511117 -289.379088) (xy 347.530408 -289.333812) (xy 347.556711 -289.292216)
			(xy 347.589346 -289.255379) (xy 347.627467 -289.224254) (xy 347.670088 -289.199647) (xy 347.716104 -289.182195)
			(xy 347.764323 -289.172351) (xy 347.813498 -289.17037) (xy 347.862353 -289.176302) (xy 347.909624 -289.189994)
			(xy 347.954086 -289.211092) (xy 347.994589 -289.239048) (xy 348.030082 -289.27314) (xy 348.059647 -289.312484)
			(xy 348.082518 -289.356061) (xy 348.098102 -289.402742) (xy 348.105997 -289.451319) (xy 348.106491 -289.4759)
			(xy 348.435111 -289.4759) (xy 348.439287 -289.425516) (xy 348.451699 -289.376506) (xy 348.472009 -289.330207)
			(xy 348.499663 -289.287884) (xy 348.533907 -289.25069) (xy 348.573806 -289.21964) (xy 348.618271 -289.195581)
			(xy 348.666091 -289.17917) (xy 348.715959 -289.170854) (xy 348.741238 -289.170364) (xy 349.681292 -289.170364)
			(xy 349.706573 -289.170804) (xy 349.756447 -289.179126) (xy 349.80427 -289.195542) (xy 349.848739 -289.219607)
			(xy 349.88864 -289.250662) (xy 349.922886 -289.287862) (xy 349.950541 -289.330191) (xy 349.970852 -289.376495)
			(xy 349.983265 -289.42551) (xy 349.987441 -289.4759) (xy 349.987439 -289.475926) (xy 350.315288 -289.475926)
			(xy 350.319248 -289.426872) (xy 350.331025 -289.379088) (xy 350.350316 -289.333812) (xy 350.376619 -289.292216)
			(xy 350.409254 -289.255379) (xy 350.447375 -289.224254) (xy 350.489996 -289.199647) (xy 350.536012 -289.182195)
			(xy 350.584231 -289.172351) (xy 350.633406 -289.17037) (xy 350.682261 -289.176302) (xy 350.729532 -289.189994)
			(xy 350.773994 -289.211092) (xy 350.814497 -289.239048) (xy 350.84999 -289.27314) (xy 350.879555 -289.312484)
			(xy 350.902426 -289.356061) (xy 350.91801 -289.402742) (xy 350.925905 -289.451319) (xy 350.926399 -289.4759)
			(xy 351.255011 -289.4759) (xy 351.259187 -289.425515) (xy 351.271599 -289.376504) (xy 351.29191 -289.330205)
			(xy 351.319565 -289.287881) (xy 351.35381 -289.250687) (xy 351.39371 -289.219637) (xy 351.438177 -289.195579)
			(xy 351.485997 -289.179168) (xy 351.535867 -289.170853) (xy 351.561146 -289.170364) (xy 352.5012 -289.170364)
			(xy 352.526478 -289.170834) (xy 352.576346 -289.179155) (xy 352.624164 -289.195571) (xy 352.668627 -289.219634)
			(xy 352.708524 -289.250686) (xy 352.742765 -289.287882) (xy 352.770417 -289.330207) (xy 352.790726 -289.376506)
			(xy 352.803137 -289.425516) (xy 352.807312 -289.4759) (xy 352.80731 -289.475926) (xy 353.135196 -289.475926)
			(xy 353.139156 -289.426872) (xy 353.150933 -289.379088) (xy 353.170224 -289.333812) (xy 353.196527 -289.292216)
			(xy 353.229162 -289.255379) (xy 353.267283 -289.224254) (xy 353.309904 -289.199647) (xy 353.35592 -289.182195)
			(xy 353.404139 -289.172351) (xy 353.453314 -289.17037) (xy 353.502169 -289.176302) (xy 353.54944 -289.189994)
			(xy 353.593902 -289.211092) (xy 353.634405 -289.239048) (xy 353.669898 -289.27314) (xy 353.699463 -289.312484)
			(xy 353.722334 -289.356061) (xy 353.737918 -289.402742) (xy 353.745813 -289.451319) (xy 353.746307 -289.4759)
			(xy 354.07504 -289.4759) (xy 354.079214 -289.425529) (xy 354.09162 -289.376532) (xy 354.111922 -289.330245)
			(xy 354.139564 -289.28793) (xy 354.173794 -289.250741) (xy 354.213677 -289.219693) (xy 354.258126 -289.195633)
			(xy 354.305929 -289.179215) (xy 354.355782 -289.170889) (xy 354.381054 -289.170364) (xy 355.321108 -289.170364)
			(xy 355.346386 -289.170835) (xy 355.396252 -289.179157) (xy 355.444069 -289.195574) (xy 355.488531 -289.219636)
			(xy 355.528427 -289.250689) (xy 355.562667 -289.287885) (xy 355.590318 -289.330209) (xy 355.610626 -289.376507)
			(xy 355.623037 -289.425517) (xy 355.627212 -289.4759) (xy 355.62721 -289.475926) (xy 355.955358 -289.475926)
			(xy 355.959318 -289.426872) (xy 355.971095 -289.379088) (xy 355.990386 -289.333812) (xy 356.016689 -289.292216)
			(xy 356.049324 -289.255379) (xy 356.087445 -289.224254) (xy 356.130066 -289.199647) (xy 356.176082 -289.182195)
			(xy 356.224301 -289.172351) (xy 356.273476 -289.17037) (xy 356.322331 -289.176302) (xy 356.369602 -289.189994)
			(xy 356.414064 -289.211092) (xy 356.454567 -289.239048) (xy 356.49006 -289.27314) (xy 356.519625 -289.312484)
			(xy 356.542496 -289.356061) (xy 356.55808 -289.402742) (xy 356.565975 -289.451319) (xy 356.56647 -289.475926)
			(xy 363.468932 -289.475926) (xy 363.472892 -289.426872) (xy 363.484669 -289.379088) (xy 363.50396 -289.333812)
			(xy 363.530263 -289.292216) (xy 363.562898 -289.255379) (xy 363.601019 -289.224254) (xy 363.64364 -289.199647)
			(xy 363.689656 -289.182195) (xy 363.737875 -289.172351) (xy 363.78705 -289.17037) (xy 363.835905 -289.176302)
			(xy 363.883176 -289.189994) (xy 363.927638 -289.211092) (xy 363.968141 -289.239048) (xy 364.003634 -289.27314)
			(xy 364.033199 -289.312484) (xy 364.05607 -289.356061) (xy 364.071654 -289.402742) (xy 364.079549 -289.451319)
			(xy 364.080043 -289.4759) (xy 364.40874 -289.4759) (xy 364.412915 -289.425525) (xy 364.425323 -289.376525)
			(xy 364.445627 -289.330235) (xy 364.473273 -289.287918) (xy 364.507508 -289.250728) (xy 364.547396 -289.219681)
			(xy 364.591851 -289.195622) (xy 364.639659 -289.179208) (xy 364.689516 -289.170887) (xy 364.71479 -289.170364)
			(xy 365.654844 -289.170364) (xy 365.68012 -289.170837) (xy 365.729982 -289.179165) (xy 365.777793 -289.195584)
			(xy 365.82225 -289.219649) (xy 365.862141 -289.250702) (xy 365.896376 -289.287897) (xy 365.924024 -289.330219)
			(xy 365.944329 -289.376515) (xy 365.956737 -289.42552) (xy 365.960912 -289.4759) (xy 365.96091 -289.475926)
			(xy 366.289094 -289.475926) (xy 366.293054 -289.426872) (xy 366.304831 -289.379088) (xy 366.324122 -289.333812)
			(xy 366.350425 -289.292216) (xy 366.38306 -289.255379) (xy 366.421181 -289.224254) (xy 366.463802 -289.199647)
			(xy 366.509818 -289.182195) (xy 366.558037 -289.172351) (xy 366.607212 -289.17037) (xy 366.656067 -289.176302)
			(xy 366.703338 -289.189994) (xy 366.7478 -289.211092) (xy 366.788303 -289.239048) (xy 366.823796 -289.27314)
			(xy 366.853361 -289.312484) (xy 366.876232 -289.356061) (xy 366.891816 -289.402742) (xy 366.899711 -289.451319)
			(xy 366.900205 -289.4759) (xy 367.22864 -289.4759) (xy 367.232815 -289.425524) (xy 367.245224 -289.376523)
			(xy 367.265528 -289.330232) (xy 367.293176 -289.287915) (xy 367.327411 -289.250725) (xy 367.3673 -289.219678)
			(xy 367.411756 -289.195619) (xy 367.459565 -289.179206) (xy 367.509424 -289.170886) (xy 367.534698 -289.170364)
			(xy 368.474752 -289.170364) (xy 368.500035 -289.170801) (xy 368.549914 -289.179117) (xy 368.597743 -289.19553)
			(xy 368.642218 -289.219593) (xy 368.682125 -289.250648) (xy 368.716375 -289.287849) (xy 368.744035 -289.33018)
			(xy 368.76435 -289.376487) (xy 368.776764 -289.425506) (xy 368.780941 -289.4759) (xy 368.780939 -289.475926)
			(xy 369.109002 -289.475926) (xy 369.112962 -289.426872) (xy 369.124739 -289.379088) (xy 369.14403 -289.333812)
			(xy 369.170333 -289.292216) (xy 369.202968 -289.255379) (xy 369.241089 -289.224254) (xy 369.28371 -289.199647)
			(xy 369.329726 -289.182195) (xy 369.377945 -289.172351) (xy 369.42712 -289.17037) (xy 369.475975 -289.176302)
			(xy 369.523246 -289.189994) (xy 369.567708 -289.211092) (xy 369.608211 -289.239048) (xy 369.643704 -289.27314)
			(xy 369.673269 -289.312484) (xy 369.69614 -289.356061) (xy 369.711724 -289.402742) (xy 369.719619 -289.451319)
			(xy 369.720113 -289.4759) (xy 370.04884 -289.4759) (xy 370.053014 -289.425528) (xy 370.065421 -289.376531)
			(xy 370.085723 -289.330243) (xy 370.113366 -289.287928) (xy 370.147596 -289.250739) (xy 370.18748 -289.219691)
			(xy 370.23193 -289.195631) (xy 370.279734 -289.179214) (xy 370.329588 -289.170889) (xy 370.35486 -289.170364)
			(xy 371.294914 -289.170364) (xy 371.320192 -289.170835) (xy 371.370057 -289.179158) (xy 371.417873 -289.195575)
			(xy 371.462335 -289.219639) (xy 371.502229 -289.250691) (xy 371.536469 -289.287887) (xy 371.564119 -289.330211)
			(xy 371.584426 -289.376509) (xy 371.596837 -289.425517) (xy 371.601012 -289.4759) (xy 371.60101 -289.475926)
			(xy 371.92891 -289.475926) (xy 371.93287 -289.426872) (xy 371.944647 -289.379088) (xy 371.963938 -289.333812)
			(xy 371.990241 -289.292216) (xy 372.022876 -289.255379) (xy 372.060997 -289.224254) (xy 372.103618 -289.199647)
			(xy 372.149634 -289.182195) (xy 372.197853 -289.172351) (xy 372.247028 -289.17037) (xy 372.295883 -289.176302)
			(xy 372.343154 -289.189994) (xy 372.387616 -289.211092) (xy 372.428119 -289.239048) (xy 372.463612 -289.27314)
			(xy 372.493177 -289.312484) (xy 372.516048 -289.356061) (xy 372.531632 -289.402742) (xy 372.539527 -289.451319)
			(xy 372.540022 -289.475926) (xy 372.539527 -289.500533) (xy 372.531632 -289.54911) (xy 372.516048 -289.595791)
			(xy 372.493177 -289.639368) (xy 372.463612 -289.678712) (xy 372.428119 -289.712804) (xy 372.387616 -289.74076)
			(xy 372.343154 -289.761858) (xy 372.295883 -289.77555) (xy 372.247028 -289.781482) (xy 372.197853 -289.779501)
			(xy 372.149634 -289.769657) (xy 372.103618 -289.752205) (xy 372.060997 -289.727598) (xy 372.022876 -289.696473)
			(xy 371.990241 -289.659636) (xy 371.963938 -289.61804) (xy 371.944647 -289.572764) (xy 371.93287 -289.52498)
			(xy 371.92891 -289.475926) (xy 371.60101 -289.475926) (xy 371.596837 -289.526283) (xy 371.584426 -289.575291)
			(xy 371.564119 -289.621589) (xy 371.536469 -289.663913) (xy 371.502229 -289.701109) (xy 371.462335 -289.732161)
			(xy 371.417873 -289.756225) (xy 371.370057 -289.772642) (xy 371.320192 -289.780965) (xy 371.294914 -289.781488)
			(xy 370.35486 -289.781488) (xy 370.329588 -289.780911) (xy 370.279734 -289.772586) (xy 370.23193 -289.756169)
			(xy 370.18748 -289.732109) (xy 370.147596 -289.701061) (xy 370.113366 -289.663872) (xy 370.085723 -289.621557)
			(xy 370.065421 -289.575269) (xy 370.053014 -289.526272) (xy 370.04884 -289.4759) (xy 369.720113 -289.4759)
			(xy 369.720114 -289.475926) (xy 369.719619 -289.500533) (xy 369.711724 -289.54911) (xy 369.69614 -289.595791)
			(xy 369.673269 -289.639368) (xy 369.643704 -289.678712) (xy 369.608211 -289.712804) (xy 369.567708 -289.74076)
			(xy 369.523246 -289.761858) (xy 369.475975 -289.77555) (xy 369.42712 -289.781482) (xy 369.377945 -289.779501)
			(xy 369.329726 -289.769657) (xy 369.28371 -289.752205) (xy 369.241089 -289.727598) (xy 369.202968 -289.696473)
			(xy 369.170333 -289.659636) (xy 369.14403 -289.61804) (xy 369.124739 -289.572764) (xy 369.112962 -289.52498)
			(xy 369.109002 -289.475926) (xy 368.780939 -289.475926) (xy 368.776764 -289.526294) (xy 368.76435 -289.575313)
			(xy 368.744035 -289.62162) (xy 368.716375 -289.663951) (xy 368.682125 -289.701152) (xy 368.642218 -289.732207)
			(xy 368.597743 -289.75627) (xy 368.549914 -289.772683) (xy 368.500035 -289.780999) (xy 368.474752 -289.781488)
			(xy 367.534698 -289.781488) (xy 367.509424 -289.780914) (xy 367.459565 -289.772594) (xy 367.411756 -289.756181)
			(xy 367.3673 -289.732122) (xy 367.327411 -289.701075) (xy 367.293176 -289.663885) (xy 367.265528 -289.621568)
			(xy 367.245224 -289.575277) (xy 367.232815 -289.526276) (xy 367.22864 -289.4759) (xy 366.900205 -289.4759)
			(xy 366.900206 -289.475926) (xy 366.899711 -289.500533) (xy 366.891816 -289.54911) (xy 366.876232 -289.595791)
			(xy 366.853361 -289.639368) (xy 366.823796 -289.678712) (xy 366.788303 -289.712804) (xy 366.7478 -289.74076)
			(xy 366.703338 -289.761858) (xy 366.656067 -289.77555) (xy 366.607212 -289.781482) (xy 366.558037 -289.779501)
			(xy 366.509818 -289.769657) (xy 366.463802 -289.752205) (xy 366.421181 -289.727598) (xy 366.38306 -289.696473)
			(xy 366.350425 -289.659636) (xy 366.324122 -289.61804) (xy 366.304831 -289.572764) (xy 366.293054 -289.52498)
			(xy 366.289094 -289.475926) (xy 365.96091 -289.475926) (xy 365.956737 -289.52628) (xy 365.944329 -289.575285)
			(xy 365.924024 -289.621581) (xy 365.896376 -289.663903) (xy 365.862141 -289.701098) (xy 365.82225 -289.732151)
			(xy 365.777793 -289.756216) (xy 365.729982 -289.772635) (xy 365.68012 -289.780963) (xy 365.654844 -289.781488)
			(xy 364.71479 -289.781488) (xy 364.689516 -289.780913) (xy 364.639659 -289.772592) (xy 364.591851 -289.756178)
			(xy 364.547396 -289.732119) (xy 364.507508 -289.701072) (xy 364.473273 -289.663882) (xy 364.445627 -289.621565)
			(xy 364.425323 -289.575275) (xy 364.412915 -289.526275) (xy 364.40874 -289.4759) (xy 364.080043 -289.4759)
			(xy 364.080044 -289.475926) (xy 364.079549 -289.500533) (xy 364.071654 -289.54911) (xy 364.05607 -289.595791)
			(xy 364.033199 -289.639368) (xy 364.003634 -289.678712) (xy 363.968141 -289.712804) (xy 363.927638 -289.74076)
			(xy 363.883176 -289.761858) (xy 363.835905 -289.77555) (xy 363.78705 -289.781482) (xy 363.737875 -289.779501)
			(xy 363.689656 -289.769657) (xy 363.64364 -289.752205) (xy 363.601019 -289.727598) (xy 363.562898 -289.696473)
			(xy 363.530263 -289.659636) (xy 363.50396 -289.61804) (xy 363.484669 -289.572764) (xy 363.472892 -289.52498)
			(xy 363.468932 -289.475926) (xy 356.56647 -289.475926) (xy 356.565975 -289.500533) (xy 356.55808 -289.54911)
			(xy 356.542496 -289.595791) (xy 356.519625 -289.639368) (xy 356.49006 -289.678712) (xy 356.454567 -289.712804)
			(xy 356.414064 -289.74076) (xy 356.369602 -289.761858) (xy 356.322331 -289.77555) (xy 356.273476 -289.781482)
			(xy 356.224301 -289.779501) (xy 356.176082 -289.769657) (xy 356.130066 -289.752205) (xy 356.087445 -289.727598)
			(xy 356.049324 -289.696473) (xy 356.016689 -289.659636) (xy 355.990386 -289.61804) (xy 355.971095 -289.572764)
			(xy 355.959318 -289.52498) (xy 355.955358 -289.475926) (xy 355.62721 -289.475926) (xy 355.623037 -289.526283)
			(xy 355.610626 -289.575293) (xy 355.590318 -289.621591) (xy 355.562667 -289.663915) (xy 355.528427 -289.701111)
			(xy 355.488531 -289.732164) (xy 355.444069 -289.756226) (xy 355.396252 -289.772643) (xy 355.346386 -289.780965)
			(xy 355.321108 -289.781488) (xy 354.381054 -289.781488) (xy 354.355782 -289.780911) (xy 354.305929 -289.772585)
			(xy 354.258126 -289.756167) (xy 354.213677 -289.732107) (xy 354.173794 -289.701059) (xy 354.139564 -289.66387)
			(xy 354.111922 -289.621555) (xy 354.09162 -289.575268) (xy 354.079214 -289.526271) (xy 354.07504 -289.4759)
			(xy 353.746307 -289.4759) (xy 353.746308 -289.475926) (xy 353.745813 -289.500533) (xy 353.737918 -289.54911)
			(xy 353.722334 -289.595791) (xy 353.699463 -289.639368) (xy 353.669898 -289.678712) (xy 353.634405 -289.712804)
			(xy 353.593902 -289.74076) (xy 353.54944 -289.761858) (xy 353.502169 -289.77555) (xy 353.453314 -289.781482)
			(xy 353.404139 -289.779501) (xy 353.35592 -289.769657) (xy 353.309904 -289.752205) (xy 353.267283 -289.727598)
			(xy 353.229162 -289.696473) (xy 353.196527 -289.659636) (xy 353.170224 -289.61804) (xy 353.150933 -289.572764)
			(xy 353.139156 -289.52498) (xy 353.135196 -289.475926) (xy 352.80731 -289.475926) (xy 352.803137 -289.526284)
			(xy 352.790726 -289.575294) (xy 352.770417 -289.621593) (xy 352.742765 -289.663918) (xy 352.708524 -289.701114)
			(xy 352.668627 -289.732166) (xy 352.624164 -289.756229) (xy 352.576346 -289.772645) (xy 352.526478 -289.780966)
			(xy 352.5012 -289.781488) (xy 351.561146 -289.781488) (xy 351.535867 -289.780947) (xy 351.485997 -289.772632)
			(xy 351.438177 -289.756221) (xy 351.39371 -289.732163) (xy 351.35381 -289.701113) (xy 351.319565 -289.663919)
			(xy 351.29191 -289.621595) (xy 351.271599 -289.575296) (xy 351.259187 -289.526285) (xy 351.255011 -289.4759)
			(xy 350.926399 -289.4759) (xy 350.9264 -289.475926) (xy 350.925905 -289.500533) (xy 350.91801 -289.54911)
			(xy 350.902426 -289.595791) (xy 350.879555 -289.639368) (xy 350.84999 -289.678712) (xy 350.814497 -289.712804)
			(xy 350.773994 -289.74076) (xy 350.729532 -289.761858) (xy 350.682261 -289.77555) (xy 350.633406 -289.781482)
			(xy 350.584231 -289.779501) (xy 350.536012 -289.769657) (xy 350.489996 -289.752205) (xy 350.447375 -289.727598)
			(xy 350.409254 -289.696473) (xy 350.376619 -289.659636) (xy 350.350316 -289.61804) (xy 350.331025 -289.572764)
			(xy 350.319248 -289.52498) (xy 350.315288 -289.475926) (xy 349.987439 -289.475926) (xy 349.983265 -289.52629)
			(xy 349.970852 -289.575305) (xy 349.950541 -289.621609) (xy 349.922886 -289.663938) (xy 349.88864 -289.701138)
			(xy 349.848739 -289.732193) (xy 349.80427 -289.756258) (xy 349.756447 -289.772674) (xy 349.706573 -289.780996)
			(xy 349.681292 -289.781488) (xy 348.741238 -289.781488) (xy 348.715959 -289.780946) (xy 348.666091 -289.77263)
			(xy 348.618271 -289.756219) (xy 348.573806 -289.73216) (xy 348.533907 -289.70111) (xy 348.499663 -289.663916)
			(xy 348.472009 -289.621593) (xy 348.451699 -289.575294) (xy 348.439287 -289.526284) (xy 348.435111 -289.4759)
			(xy 348.106491 -289.4759) (xy 348.106492 -289.475926) (xy 348.105997 -289.500533) (xy 348.098102 -289.54911)
			(xy 348.082518 -289.595791) (xy 348.059647 -289.639368) (xy 348.030082 -289.678712) (xy 347.994589 -289.712804)
			(xy 347.954086 -289.74076) (xy 347.909624 -289.761858) (xy 347.862353 -289.77555) (xy 347.813498 -289.781482)
			(xy 347.764323 -289.779501) (xy 347.716104 -289.769657) (xy 347.670088 -289.752205) (xy 347.627467 -289.727598)
			(xy 347.589346 -289.696473) (xy 347.556711 -289.659636) (xy 347.530408 -289.61804) (xy 347.511117 -289.572764)
			(xy 347.49934 -289.52498) (xy 347.49538 -289.475926) (xy 347.16721 -289.475926) (xy 347.163037 -289.526281)
			(xy 347.150628 -289.575288) (xy 347.130322 -289.621585) (xy 347.102673 -289.663908) (xy 347.068435 -289.701103)
			(xy 347.028543 -289.732156) (xy 346.984084 -289.75622) (xy 346.93627 -289.772638) (xy 346.886407 -289.780964)
			(xy 346.86113 -289.781488) (xy 345.921076 -289.781488) (xy 345.895803 -289.780912) (xy 345.845947 -289.772589)
			(xy 345.798141 -289.756174) (xy 345.753689 -289.732114) (xy 345.713802 -289.701067) (xy 345.67957 -289.663878)
			(xy 345.651925 -289.621562) (xy 345.631622 -289.575273) (xy 345.619214 -289.526273) (xy 345.61504 -289.4759)
			(xy 345.286807 -289.4759) (xy 345.282654 -289.526126) (xy 345.270308 -289.574988) (xy 345.250105 -289.621159)
			(xy 345.222593 -289.663385) (xy 345.188519 -289.700518) (xy 345.14881 -289.731551) (xy 345.104542 -289.755641)
			(xy 345.056919 -289.772133) (xy 345.007235 -289.780579) (xy 344.982038 -289.781234) (xy 344.971974 -289.781669)
			(xy 344.953389 -289.789403) (xy 344.94597 -289.79622) (xy 344.895424 -289.84702) (xy 344.88874 -289.85443)
			(xy 344.881162 -289.872866) (xy 344.880692 -289.882834) (xy 344.880692 -290.285932) (xy 347.025226 -290.285932)
			(xy 347.029186 -290.236878) (xy 347.040963 -290.189094) (xy 347.060254 -290.143818) (xy 347.086557 -290.102222)
			(xy 347.119192 -290.065385) (xy 347.157313 -290.03426) (xy 347.199934 -290.009653) (xy 347.24595 -289.992201)
			(xy 347.294169 -289.982357) (xy 347.343344 -289.980376) (xy 347.392199 -289.986308) (xy 347.43947 -290)
			(xy 347.483932 -290.021098) (xy 347.524435 -290.049054) (xy 347.559928 -290.083146) (xy 347.589493 -290.12249)
			(xy 347.612364 -290.166067) (xy 347.627948 -290.212748) (xy 347.635843 -290.261325) (xy 347.636338 -290.285932)
			(xy 349.845388 -290.285932) (xy 349.849348 -290.236878) (xy 349.861125 -290.189094) (xy 349.880416 -290.143818)
			(xy 349.906719 -290.102222) (xy 349.939354 -290.065385) (xy 349.977475 -290.03426) (xy 350.020096 -290.009653)
			(xy 350.066112 -289.992201) (xy 350.114331 -289.982357) (xy 350.163506 -289.980376) (xy 350.212361 -289.986308)
			(xy 350.259632 -290) (xy 350.304094 -290.021098) (xy 350.344597 -290.049054) (xy 350.38009 -290.083146)
			(xy 350.409655 -290.12249) (xy 350.432526 -290.166067) (xy 350.44811 -290.212748) (xy 350.456005 -290.261325)
			(xy 350.4565 -290.285932) (xy 352.665296 -290.285932) (xy 352.669256 -290.236878) (xy 352.681033 -290.189094)
			(xy 352.700324 -290.143818) (xy 352.726627 -290.102222) (xy 352.759262 -290.065385) (xy 352.797383 -290.03426)
			(xy 352.840004 -290.009653) (xy 352.88602 -289.992201) (xy 352.934239 -289.982357) (xy 352.983414 -289.980376)
			(xy 353.032269 -289.986308) (xy 353.07954 -290) (xy 353.124002 -290.021098) (xy 353.164505 -290.049054)
			(xy 353.199998 -290.083146) (xy 353.229563 -290.12249) (xy 353.252434 -290.166067) (xy 353.268018 -290.212748)
			(xy 353.275913 -290.261325) (xy 353.276408 -290.285932) (xy 355.485204 -290.285932) (xy 355.489164 -290.236878)
			(xy 355.500941 -290.189094) (xy 355.520232 -290.143818) (xy 355.546535 -290.102222) (xy 355.57917 -290.065385)
			(xy 355.617291 -290.03426) (xy 355.659912 -290.009653) (xy 355.705928 -289.992201) (xy 355.754147 -289.982357)
			(xy 355.803322 -289.980376) (xy 355.852177 -289.986308) (xy 355.899448 -290) (xy 355.94391 -290.021098)
			(xy 355.984413 -290.049054) (xy 356.019906 -290.083146) (xy 356.049471 -290.12249) (xy 356.072342 -290.166067)
			(xy 356.087926 -290.212748) (xy 356.095821 -290.261325) (xy 356.096315 -290.2859) (xy 356.425301 -290.2859)
			(xy 356.429471 -290.235571) (xy 356.441867 -290.186615) (xy 356.462152 -290.140366) (xy 356.489772 -290.098087)
			(xy 356.523973 -290.06093) (xy 356.563824 -290.029908) (xy 356.608236 -290.005869) (xy 356.656 -289.989466)
			(xy 356.705811 -289.981148) (xy 356.731062 -289.980624) (xy 357.671116 -289.980624) (xy 357.696373 -289.981083)
			(xy 357.746198 -289.9894) (xy 357.793975 -290.005804) (xy 357.8384 -290.029847) (xy 357.878262 -290.060875)
			(xy 357.912473 -290.09804) (xy 357.940101 -290.14033) (xy 357.960392 -290.18659) (xy 357.972792 -290.235558)
			(xy 357.976963 -290.2859) (xy 357.97696 -290.285932) (xy 358.305366 -290.285932) (xy 358.309326 -290.236878)
			(xy 358.321103 -290.189094) (xy 358.340394 -290.143818) (xy 358.366697 -290.102222) (xy 358.399332 -290.065385)
			(xy 358.437453 -290.03426) (xy 358.480074 -290.009653) (xy 358.52609 -289.992201) (xy 358.574309 -289.982357)
			(xy 358.623484 -289.980376) (xy 358.672339 -289.986308) (xy 358.71961 -290) (xy 358.764072 -290.021098)
			(xy 358.804575 -290.049054) (xy 358.840068 -290.083146) (xy 358.869633 -290.12249) (xy 358.892504 -290.166067)
			(xy 358.908088 -290.212748) (xy 358.915983 -290.261325) (xy 358.916478 -290.285932) (xy 361.118924 -290.285932)
			(xy 361.122884 -290.236878) (xy 361.134661 -290.189094) (xy 361.153952 -290.143818) (xy 361.180255 -290.102222)
			(xy 361.21289 -290.065385) (xy 361.251011 -290.03426) (xy 361.293632 -290.009653) (xy 361.339648 -289.992201)
			(xy 361.387867 -289.982357) (xy 361.437042 -289.980376) (xy 361.485897 -289.986308) (xy 361.533168 -290)
			(xy 361.57763 -290.021098) (xy 361.618133 -290.049054) (xy 361.653626 -290.083146) (xy 361.683191 -290.12249)
			(xy 361.706062 -290.166067) (xy 361.721646 -290.212748) (xy 361.729541 -290.261325) (xy 361.730035 -290.2859)
			(xy 362.059001 -290.2859) (xy 362.063171 -290.235569) (xy 362.075569 -290.186611) (xy 362.095855 -290.140361)
			(xy 362.123477 -290.09808) (xy 362.157681 -290.060923) (xy 362.197534 -290.029902) (xy 362.24195 -290.005863)
			(xy 362.289716 -289.989462) (xy 362.33953 -289.981147) (xy 362.364782 -289.980624) (xy 363.304836 -289.980624)
			(xy 363.330092 -289.981084) (xy 363.379914 -289.989404) (xy 363.427688 -290.005809) (xy 363.47211 -290.029854)
			(xy 363.511969 -290.060882) (xy 363.546178 -290.098047) (xy 363.573804 -290.140335) (xy 363.594093 -290.186594)
			(xy 363.606492 -290.23556) (xy 363.610663 -290.2859) (xy 363.61066 -290.285932) (xy 363.939086 -290.285932)
			(xy 363.943046 -290.236878) (xy 363.954823 -290.189094) (xy 363.974114 -290.143818) (xy 364.000417 -290.102222)
			(xy 364.033052 -290.065385) (xy 364.071173 -290.03426) (xy 364.113794 -290.009653) (xy 364.15981 -289.992201)
			(xy 364.208029 -289.982357) (xy 364.257204 -289.980376) (xy 364.306059 -289.986308) (xy 364.35333 -290)
			(xy 364.397792 -290.021098) (xy 364.438295 -290.049054) (xy 364.473788 -290.083146) (xy 364.503353 -290.12249)
			(xy 364.526224 -290.166067) (xy 364.541808 -290.212748) (xy 364.549703 -290.261325) (xy 364.550198 -290.285932)
			(xy 366.758994 -290.285932) (xy 366.762954 -290.236878) (xy 366.774731 -290.189094) (xy 366.794022 -290.143818)
			(xy 366.820325 -290.102222) (xy 366.85296 -290.065385) (xy 366.891081 -290.03426) (xy 366.933702 -290.009653)
			(xy 366.979718 -289.992201) (xy 367.027937 -289.982357) (xy 367.077112 -289.980376) (xy 367.125967 -289.986308)
			(xy 367.173238 -290) (xy 367.2177 -290.021098) (xy 367.258203 -290.049054) (xy 367.293696 -290.083146)
			(xy 367.323261 -290.12249) (xy 367.346132 -290.166067) (xy 367.361716 -290.212748) (xy 367.369611 -290.261325)
			(xy 367.370106 -290.285932) (xy 369.578902 -290.285932) (xy 369.582862 -290.236878) (xy 369.594639 -290.189094)
			(xy 369.61393 -290.143818) (xy 369.640233 -290.102222) (xy 369.672868 -290.065385) (xy 369.710989 -290.03426)
			(xy 369.75361 -290.009653) (xy 369.799626 -289.992201) (xy 369.847845 -289.982357) (xy 369.89702 -289.980376)
			(xy 369.945875 -289.986308) (xy 369.993146 -290) (xy 370.037608 -290.021098) (xy 370.078111 -290.049054)
			(xy 370.113604 -290.083146) (xy 370.143169 -290.12249) (xy 370.16604 -290.166067) (xy 370.181624 -290.212748)
			(xy 370.189519 -290.261325) (xy 370.190014 -290.285932) (xy 372.399064 -290.285932) (xy 372.403024 -290.236878)
			(xy 372.414801 -290.189094) (xy 372.434092 -290.143818) (xy 372.460395 -290.102222) (xy 372.49303 -290.065385)
			(xy 372.531151 -290.03426) (xy 372.573772 -290.009653) (xy 372.619788 -289.992201) (xy 372.668007 -289.982357)
			(xy 372.717182 -289.980376) (xy 372.766037 -289.986308) (xy 372.813308 -290) (xy 372.85777 -290.021098)
			(xy 372.898273 -290.049054) (xy 372.933766 -290.083146) (xy 372.963331 -290.12249) (xy 372.986202 -290.166067)
			(xy 373.001786 -290.212748) (xy 373.009681 -290.261325) (xy 373.010176 -290.285932) (xy 373.009681 -290.310539)
			(xy 373.001786 -290.359116) (xy 372.986202 -290.405797) (xy 372.963331 -290.449374) (xy 372.933766 -290.488718)
			(xy 372.898273 -290.52281) (xy 372.85777 -290.550766) (xy 372.813308 -290.571864) (xy 372.766037 -290.585556)
			(xy 372.717182 -290.591488) (xy 372.668007 -290.589507) (xy 372.619788 -290.579663) (xy 372.573772 -290.562211)
			(xy 372.531151 -290.537604) (xy 372.49303 -290.506479) (xy 372.460395 -290.469642) (xy 372.434092 -290.428046)
			(xy 372.414801 -290.38277) (xy 372.403024 -290.334986) (xy 372.399064 -290.285932) (xy 370.190014 -290.285932)
			(xy 370.189519 -290.310539) (xy 370.181624 -290.359116) (xy 370.16604 -290.405797) (xy 370.143169 -290.449374)
			(xy 370.113604 -290.488718) (xy 370.078111 -290.52281) (xy 370.037608 -290.550766) (xy 369.993146 -290.571864)
			(xy 369.945875 -290.585556) (xy 369.89702 -290.591488) (xy 369.847845 -290.589507) (xy 369.799626 -290.579663)
			(xy 369.75361 -290.562211) (xy 369.710989 -290.537604) (xy 369.672868 -290.506479) (xy 369.640233 -290.469642)
			(xy 369.61393 -290.428046) (xy 369.594639 -290.38277) (xy 369.582862 -290.334986) (xy 369.578902 -290.285932)
			(xy 367.370106 -290.285932) (xy 367.369611 -290.310539) (xy 367.361716 -290.359116) (xy 367.346132 -290.405797)
			(xy 367.323261 -290.449374) (xy 367.293696 -290.488718) (xy 367.258203 -290.52281) (xy 367.2177 -290.550766)
			(xy 367.173238 -290.571864) (xy 367.125967 -290.585556) (xy 367.077112 -290.591488) (xy 367.027937 -290.589507)
			(xy 366.979718 -290.579663) (xy 366.933702 -290.562211) (xy 366.891081 -290.537604) (xy 366.85296 -290.506479)
			(xy 366.820325 -290.469642) (xy 366.794022 -290.428046) (xy 366.774731 -290.38277) (xy 366.762954 -290.334986)
			(xy 366.758994 -290.285932) (xy 364.550198 -290.285932) (xy 364.549703 -290.310539) (xy 364.541808 -290.359116)
			(xy 364.526224 -290.405797) (xy 364.503353 -290.449374) (xy 364.473788 -290.488718) (xy 364.438295 -290.52281)
			(xy 364.397792 -290.550766) (xy 364.35333 -290.571864) (xy 364.306059 -290.585556) (xy 364.257204 -290.591488)
			(xy 364.208029 -290.589507) (xy 364.15981 -290.579663) (xy 364.113794 -290.562211) (xy 364.071173 -290.537604)
			(xy 364.033052 -290.506479) (xy 364.000417 -290.469642) (xy 363.974114 -290.428046) (xy 363.954823 -290.38277)
			(xy 363.943046 -290.334986) (xy 363.939086 -290.285932) (xy 363.61066 -290.285932) (xy 363.606492 -290.33624)
			(xy 363.594093 -290.385206) (xy 363.573804 -290.431465) (xy 363.546178 -290.473753) (xy 363.511969 -290.510918)
			(xy 363.47211 -290.541946) (xy 363.427688 -290.565991) (xy 363.379914 -290.582396) (xy 363.330092 -290.590716)
			(xy 363.304836 -290.59124) (xy 362.364782 -290.59124) (xy 362.33953 -290.590653) (xy 362.289716 -290.582338)
			(xy 362.24195 -290.565937) (xy 362.197534 -290.541898) (xy 362.157681 -290.510877) (xy 362.123477 -290.47372)
			(xy 362.095855 -290.431439) (xy 362.075569 -290.385189) (xy 362.063171 -290.336231) (xy 362.059001 -290.2859)
			(xy 361.730035 -290.2859) (xy 361.730036 -290.285932) (xy 361.729541 -290.310539) (xy 361.721646 -290.359116)
			(xy 361.706062 -290.405797) (xy 361.683191 -290.449374) (xy 361.653626 -290.488718) (xy 361.618133 -290.52281)
			(xy 361.57763 -290.550766) (xy 361.533168 -290.571864) (xy 361.485897 -290.585556) (xy 361.437042 -290.591488)
			(xy 361.387867 -290.589507) (xy 361.339648 -290.579663) (xy 361.293632 -290.562211) (xy 361.251011 -290.537604)
			(xy 361.21289 -290.506479) (xy 361.180255 -290.469642) (xy 361.153952 -290.428046) (xy 361.134661 -290.38277)
			(xy 361.122884 -290.334986) (xy 361.118924 -290.285932) (xy 358.916478 -290.285932) (xy 358.915983 -290.310539)
			(xy 358.908088 -290.359116) (xy 358.892504 -290.405797) (xy 358.869633 -290.449374) (xy 358.840068 -290.488718)
			(xy 358.804575 -290.52281) (xy 358.764072 -290.550766) (xy 358.71961 -290.571864) (xy 358.672339 -290.585556)
			(xy 358.623484 -290.591488) (xy 358.574309 -290.589507) (xy 358.52609 -290.579663) (xy 358.480074 -290.562211)
			(xy 358.437453 -290.537604) (xy 358.399332 -290.506479) (xy 358.366697 -290.469642) (xy 358.340394 -290.428046)
			(xy 358.321103 -290.38277) (xy 358.309326 -290.334986) (xy 358.305366 -290.285932) (xy 357.97696 -290.285932)
			(xy 357.972792 -290.336242) (xy 357.960392 -290.38521) (xy 357.940101 -290.43147) (xy 357.912473 -290.47376)
			(xy 357.878262 -290.510925) (xy 357.8384 -290.541953) (xy 357.793975 -290.565996) (xy 357.746198 -290.5824)
			(xy 357.696373 -290.590717) (xy 357.671116 -290.59124) (xy 356.731062 -290.59124) (xy 356.705811 -290.590652)
			(xy 356.656 -290.582334) (xy 356.608236 -290.565931) (xy 356.563824 -290.541892) (xy 356.523973 -290.51087)
			(xy 356.489772 -290.473713) (xy 356.462152 -290.431434) (xy 356.441867 -290.385185) (xy 356.429471 -290.336229)
			(xy 356.425301 -290.2859) (xy 356.096315 -290.2859) (xy 356.096316 -290.285932) (xy 356.095821 -290.310539)
			(xy 356.087926 -290.359116) (xy 356.072342 -290.405797) (xy 356.049471 -290.449374) (xy 356.019906 -290.488718)
			(xy 355.984413 -290.52281) (xy 355.94391 -290.550766) (xy 355.899448 -290.571864) (xy 355.852177 -290.585556)
			(xy 355.803322 -290.591488) (xy 355.754147 -290.589507) (xy 355.705928 -290.579663) (xy 355.659912 -290.562211)
			(xy 355.617291 -290.537604) (xy 355.57917 -290.506479) (xy 355.546535 -290.469642) (xy 355.520232 -290.428046)
			(xy 355.500941 -290.38277) (xy 355.489164 -290.334986) (xy 355.485204 -290.285932) (xy 353.276408 -290.285932)
			(xy 353.275913 -290.310539) (xy 353.268018 -290.359116) (xy 353.252434 -290.405797) (xy 353.229563 -290.449374)
			(xy 353.199998 -290.488718) (xy 353.164505 -290.52281) (xy 353.124002 -290.550766) (xy 353.07954 -290.571864)
			(xy 353.032269 -290.585556) (xy 352.983414 -290.591488) (xy 352.934239 -290.589507) (xy 352.88602 -290.579663)
			(xy 352.840004 -290.562211) (xy 352.797383 -290.537604) (xy 352.759262 -290.506479) (xy 352.726627 -290.469642)
			(xy 352.700324 -290.428046) (xy 352.681033 -290.38277) (xy 352.669256 -290.334986) (xy 352.665296 -290.285932)
			(xy 350.4565 -290.285932) (xy 350.456005 -290.310539) (xy 350.44811 -290.359116) (xy 350.432526 -290.405797)
			(xy 350.409655 -290.449374) (xy 350.38009 -290.488718) (xy 350.344597 -290.52281) (xy 350.304094 -290.550766)
			(xy 350.259632 -290.571864) (xy 350.212361 -290.585556) (xy 350.163506 -290.591488) (xy 350.114331 -290.589507)
			(xy 350.066112 -290.579663) (xy 350.020096 -290.562211) (xy 349.977475 -290.537604) (xy 349.939354 -290.506479)
			(xy 349.906719 -290.469642) (xy 349.880416 -290.428046) (xy 349.861125 -290.38277) (xy 349.849348 -290.334986)
			(xy 349.845388 -290.285932) (xy 347.636338 -290.285932) (xy 347.635843 -290.310539) (xy 347.627948 -290.359116)
			(xy 347.612364 -290.405797) (xy 347.589493 -290.449374) (xy 347.559928 -290.488718) (xy 347.524435 -290.52281)
			(xy 347.483932 -290.550766) (xy 347.43947 -290.571864) (xy 347.392199 -290.585556) (xy 347.343344 -290.591488)
			(xy 347.294169 -290.589507) (xy 347.24595 -290.579663) (xy 347.199934 -290.562211) (xy 347.157313 -290.537604)
			(xy 347.119192 -290.506479) (xy 347.086557 -290.469642) (xy 347.060254 -290.428046) (xy 347.040963 -290.38277)
			(xy 347.029186 -290.334986) (xy 347.025226 -290.285932) (xy 344.880692 -290.285932) (xy 344.880692 -290.68903)
			(xy 344.881172 -290.698995) (xy 344.888749 -290.71743) (xy 344.895424 -290.724844) (xy 344.94597 -290.775644)
			(xy 344.953369 -290.782486) (xy 344.971968 -290.790203) (xy 344.982038 -290.79063) (xy 345.007234 -290.791233)
			(xy 345.056917 -290.799679) (xy 345.104538 -290.81617) (xy 345.148803 -290.840259) (xy 345.188511 -290.871291)
			(xy 345.222584 -290.908423) (xy 345.250095 -290.950647) (xy 345.270297 -290.996816) (xy 345.282642 -291.045676)
			(xy 345.286795 -291.0959) (xy 345.615052 -291.0959) (xy 345.619226 -291.045529) (xy 345.631633 -290.996531)
			(xy 345.651936 -290.950244) (xy 345.679579 -290.90793) (xy 345.71381 -290.870742) (xy 345.753695 -290.839696)
			(xy 345.798146 -290.815637) (xy 345.84595 -290.799222) (xy 345.895804 -290.7909) (xy 345.921076 -290.790376)
			(xy 346.86113 -290.790376) (xy 346.886408 -290.790824) (xy 346.936273 -290.79915) (xy 346.984089 -290.815569)
			(xy 347.02855 -290.839634) (xy 347.068443 -290.870688) (xy 347.102682 -290.907885) (xy 347.130332 -290.95021)
			(xy 347.150639 -290.996508) (xy 347.163049 -291.045517) (xy 347.167224 -291.0959) (xy 347.167221 -291.095938)
			(xy 347.49538 -291.095938) (xy 347.49934 -291.046884) (xy 347.511117 -290.9991) (xy 347.530408 -290.953824)
			(xy 347.556711 -290.912228) (xy 347.589346 -290.875391) (xy 347.627467 -290.844266) (xy 347.670088 -290.819659)
			(xy 347.716104 -290.802207) (xy 347.764323 -290.792363) (xy 347.813498 -290.790382) (xy 347.862353 -290.796314)
			(xy 347.909624 -290.810006) (xy 347.954086 -290.831104) (xy 347.994589 -290.85906) (xy 348.030082 -290.893152)
			(xy 348.059647 -290.932496) (xy 348.082518 -290.976073) (xy 348.098102 -291.022754) (xy 348.105997 -291.071331)
			(xy 348.106491 -291.0959) (xy 348.435123 -291.0959) (xy 348.439299 -291.045518) (xy 348.45171 -290.99651)
			(xy 348.472019 -290.950213) (xy 348.499672 -290.907891) (xy 348.533915 -290.870699) (xy 348.573812 -290.83965)
			(xy 348.618276 -290.815592) (xy 348.666094 -290.799181) (xy 348.71596 -290.790866) (xy 348.741238 -290.790376)
			(xy 349.681292 -290.790376) (xy 349.706574 -290.790793) (xy 349.756449 -290.799114) (xy 349.804275 -290.815531)
			(xy 349.848745 -290.839597) (xy 349.888648 -290.870653) (xy 349.922895 -290.907855) (xy 349.950552 -290.950185)
			(xy 349.970864 -290.996491) (xy 349.983277 -291.045508) (xy 349.987453 -291.0959) (xy 349.98745 -291.095938)
			(xy 350.315288 -291.095938) (xy 350.319248 -291.046884) (xy 350.331025 -290.9991) (xy 350.350316 -290.953824)
			(xy 350.376619 -290.912228) (xy 350.409254 -290.875391) (xy 350.447375 -290.844266) (xy 350.489996 -290.819659)
			(xy 350.536012 -290.802207) (xy 350.584231 -290.792363) (xy 350.633406 -290.790382) (xy 350.682261 -290.796314)
			(xy 350.729532 -290.810006) (xy 350.773994 -290.831104) (xy 350.814497 -290.85906) (xy 350.84999 -290.893152)
			(xy 350.879555 -290.932496) (xy 350.902426 -290.976073) (xy 350.91801 -291.022754) (xy 350.925905 -291.071331)
			(xy 350.926399 -291.0959) (xy 351.255023 -291.0959) (xy 351.259199 -291.045517) (xy 351.271611 -290.996508)
			(xy 351.291921 -290.950211) (xy 351.319575 -290.907889) (xy 351.353818 -290.870696) (xy 351.393716 -290.839647)
			(xy 351.438182 -290.81559) (xy 351.486 -290.79918) (xy 351.535868 -290.790865) (xy 351.561146 -290.790376)
			(xy 352.5012 -290.790376) (xy 352.526479 -290.790822) (xy 352.576349 -290.799144) (xy 352.624168 -290.81556)
			(xy 352.668634 -290.839624) (xy 352.708532 -290.870678) (xy 352.742774 -290.907875) (xy 352.770428 -290.950201)
			(xy 352.790737 -290.996502) (xy 352.803148 -291.045514) (xy 352.807324 -291.0959) (xy 352.807321 -291.095938)
			(xy 353.135196 -291.095938) (xy 353.139156 -291.046884) (xy 353.150933 -290.9991) (xy 353.170224 -290.953824)
			(xy 353.196527 -290.912228) (xy 353.229162 -290.875391) (xy 353.267283 -290.844266) (xy 353.309904 -290.819659)
			(xy 353.35592 -290.802207) (xy 353.404139 -290.792363) (xy 353.453314 -290.790382) (xy 353.502169 -290.796314)
			(xy 353.54944 -290.810006) (xy 353.593902 -290.831104) (xy 353.634405 -290.85906) (xy 353.669898 -290.893152)
			(xy 353.699463 -290.932496) (xy 353.722334 -290.976073) (xy 353.737918 -291.022754) (xy 353.745813 -291.071331)
			(xy 353.746307 -291.0959) (xy 354.075052 -291.0959) (xy 354.079226 -291.045531) (xy 354.091632 -290.996536)
			(xy 354.111932 -290.95025) (xy 354.139574 -290.907937) (xy 354.173802 -290.87075) (xy 354.213684 -290.839703)
			(xy 354.258131 -290.815644) (xy 354.305932 -290.799227) (xy 354.355783 -290.790901) (xy 354.381054 -290.790376)
			(xy 355.321108 -290.790376) (xy 355.346387 -290.790823) (xy 355.396255 -290.799145) (xy 355.444074 -290.815563)
			(xy 355.488538 -290.839626) (xy 355.528435 -290.87068) (xy 355.562677 -290.907878) (xy 355.590329 -290.950204)
			(xy 355.610637 -290.996503) (xy 355.623049 -291.045515) (xy 355.627224 -291.0959) (xy 355.627221 -291.095938)
			(xy 355.955358 -291.095938) (xy 355.959318 -291.046884) (xy 355.971095 -290.9991) (xy 355.990386 -290.953824)
			(xy 356.016689 -290.912228) (xy 356.049324 -290.875391) (xy 356.087445 -290.844266) (xy 356.130066 -290.819659)
			(xy 356.176082 -290.802207) (xy 356.224301 -290.792363) (xy 356.273476 -290.790382) (xy 356.322331 -290.796314)
			(xy 356.369602 -290.810006) (xy 356.414064 -290.831104) (xy 356.454567 -290.85906) (xy 356.49006 -290.893152)
			(xy 356.519625 -290.932496) (xy 356.542496 -290.976073) (xy 356.55808 -291.022754) (xy 356.565975 -291.071331)
			(xy 356.56647 -291.095938) (xy 363.468932 -291.095938) (xy 363.472892 -291.046884) (xy 363.484669 -290.9991)
			(xy 363.50396 -290.953824) (xy 363.530263 -290.912228) (xy 363.562898 -290.875391) (xy 363.601019 -290.844266)
			(xy 363.64364 -290.819659) (xy 363.689656 -290.802207) (xy 363.737875 -290.792363) (xy 363.78705 -290.790382)
			(xy 363.835905 -290.796314) (xy 363.883176 -290.810006) (xy 363.927638 -290.831104) (xy 363.968141 -290.85906)
			(xy 364.003634 -290.893152) (xy 364.033199 -290.932496) (xy 364.05607 -290.976073) (xy 364.071654 -291.022754)
			(xy 364.079549 -291.071331) (xy 364.080043 -291.0959) (xy 364.408752 -291.0959) (xy 364.412926 -291.045527)
			(xy 364.425334 -290.996529) (xy 364.445638 -290.95024) (xy 364.473283 -290.907925) (xy 364.507516 -290.870737)
			(xy 364.547403 -290.839691) (xy 364.591855 -290.815633) (xy 364.639662 -290.79922) (xy 364.689517 -290.790899)
			(xy 364.71479 -290.790376) (xy 365.654844 -290.790376) (xy 365.680121 -290.790826) (xy 365.729985 -290.799153)
			(xy 365.777798 -290.815573) (xy 365.822257 -290.839639) (xy 365.862149 -290.870693) (xy 365.896386 -290.90789)
			(xy 365.924034 -290.950214) (xy 365.94434 -290.996511) (xy 365.956749 -291.045518) (xy 365.960924 -291.0959)
			(xy 365.960921 -291.095938) (xy 366.289094 -291.095938) (xy 366.293054 -291.046884) (xy 366.304831 -290.9991)
			(xy 366.324122 -290.953824) (xy 366.350425 -290.912228) (xy 366.38306 -290.875391) (xy 366.421181 -290.844266)
			(xy 366.463802 -290.819659) (xy 366.509818 -290.802207) (xy 366.558037 -290.792363) (xy 366.607212 -290.790382)
			(xy 366.656067 -290.796314) (xy 366.703338 -290.810006) (xy 366.7478 -290.831104) (xy 366.788303 -290.85906)
			(xy 366.823796 -290.893152) (xy 366.853361 -290.932496) (xy 366.876232 -290.976073) (xy 366.891816 -291.022754)
			(xy 366.899711 -291.071331) (xy 366.900205 -291.0959) (xy 367.228652 -291.0959) (xy 367.232827 -291.045526)
			(xy 367.245235 -290.996527) (xy 367.265539 -290.950238) (xy 367.293185 -290.907922) (xy 367.327419 -290.870734)
			(xy 367.367307 -290.839688) (xy 367.411761 -290.81563) (xy 367.459568 -290.799218) (xy 367.509425 -290.790898)
			(xy 367.534698 -290.790376) (xy 368.474752 -290.790376) (xy 368.500036 -290.790789) (xy 368.549917 -290.799106)
			(xy 368.597748 -290.815519) (xy 368.642224 -290.839583) (xy 368.682133 -290.870639) (xy 368.716385 -290.907841)
			(xy 368.744046 -290.950174) (xy 368.764361 -290.996483) (xy 368.776776 -291.045504) (xy 368.780953 -291.0959)
			(xy 368.78095 -291.095938) (xy 369.109002 -291.095938) (xy 369.112962 -291.046884) (xy 369.124739 -290.9991)
			(xy 369.14403 -290.953824) (xy 369.170333 -290.912228) (xy 369.202968 -290.875391) (xy 369.241089 -290.844266)
			(xy 369.28371 -290.819659) (xy 369.329726 -290.802207) (xy 369.377945 -290.792363) (xy 369.42712 -290.790382)
			(xy 369.475975 -290.796314) (xy 369.523246 -290.810006) (xy 369.567708 -290.831104) (xy 369.608211 -290.85906)
			(xy 369.643704 -290.893152) (xy 369.673269 -290.932496) (xy 369.69614 -290.976073) (xy 369.711724 -291.022754)
			(xy 369.719619 -291.071331) (xy 369.720113 -291.0959) (xy 370.048852 -291.0959) (xy 370.053026 -291.04553)
			(xy 370.065432 -290.996535) (xy 370.085733 -290.950249) (xy 370.113375 -290.907935) (xy 370.147604 -290.870748)
			(xy 370.187487 -290.839701) (xy 370.231935 -290.815642) (xy 370.279737 -290.799226) (xy 370.329589 -290.790901)
			(xy 370.35486 -290.790376) (xy 371.294914 -290.790376) (xy 371.320193 -290.790823) (xy 371.37006 -290.799147)
			(xy 371.417878 -290.815564) (xy 371.462341 -290.839629) (xy 371.502237 -290.870683) (xy 371.536478 -290.90788)
			(xy 371.56413 -290.950205) (xy 371.584438 -290.996505) (xy 371.596849 -291.045515) (xy 371.601024 -291.0959)
			(xy 371.601021 -291.095938) (xy 371.92891 -291.095938) (xy 371.93287 -291.046884) (xy 371.944647 -290.9991)
			(xy 371.963938 -290.953824) (xy 371.990241 -290.912228) (xy 372.022876 -290.875391) (xy 372.060997 -290.844266)
			(xy 372.103618 -290.819659) (xy 372.149634 -290.802207) (xy 372.197853 -290.792363) (xy 372.247028 -290.790382)
			(xy 372.295883 -290.796314) (xy 372.343154 -290.810006) (xy 372.387616 -290.831104) (xy 372.428119 -290.85906)
			(xy 372.463612 -290.893152) (xy 372.493177 -290.932496) (xy 372.516048 -290.976073) (xy 372.531632 -291.022754)
			(xy 372.539527 -291.071331) (xy 372.540022 -291.095938) (xy 372.539527 -291.120545) (xy 372.531632 -291.169122)
			(xy 372.516048 -291.215803) (xy 372.493177 -291.25938) (xy 372.463612 -291.298724) (xy 372.428119 -291.332816)
			(xy 372.387616 -291.360772) (xy 372.343154 -291.38187) (xy 372.295883 -291.395562) (xy 372.247028 -291.401494)
			(xy 372.197853 -291.399513) (xy 372.149634 -291.389669) (xy 372.103618 -291.372217) (xy 372.060997 -291.34761)
			(xy 372.022876 -291.316485) (xy 371.990241 -291.279648) (xy 371.963938 -291.238052) (xy 371.944647 -291.192776)
			(xy 371.93287 -291.144992) (xy 371.92891 -291.095938) (xy 371.601021 -291.095938) (xy 371.596849 -291.146285)
			(xy 371.584438 -291.195295) (xy 371.56413 -291.241595) (xy 371.536478 -291.28392) (xy 371.502237 -291.321117)
			(xy 371.462341 -291.352171) (xy 371.417878 -291.376236) (xy 371.37006 -291.392653) (xy 371.320193 -291.400977)
			(xy 371.294914 -291.4015) (xy 370.35486 -291.4015) (xy 370.329589 -291.400899) (xy 370.279737 -291.392574)
			(xy 370.231935 -291.376158) (xy 370.187487 -291.352099) (xy 370.147604 -291.321052) (xy 370.113375 -291.283865)
			(xy 370.085733 -291.241551) (xy 370.065432 -291.195265) (xy 370.053026 -291.14627) (xy 370.048852 -291.0959)
			(xy 369.720113 -291.0959) (xy 369.720114 -291.095938) (xy 369.719619 -291.120545) (xy 369.711724 -291.169122)
			(xy 369.69614 -291.215803) (xy 369.673269 -291.25938) (xy 369.643704 -291.298724) (xy 369.608211 -291.332816)
			(xy 369.567708 -291.360772) (xy 369.523246 -291.38187) (xy 369.475975 -291.395562) (xy 369.42712 -291.401494)
			(xy 369.377945 -291.399513) (xy 369.329726 -291.389669) (xy 369.28371 -291.372217) (xy 369.241089 -291.34761)
			(xy 369.202968 -291.316485) (xy 369.170333 -291.279648) (xy 369.14403 -291.238052) (xy 369.124739 -291.192776)
			(xy 369.112962 -291.144992) (xy 369.109002 -291.095938) (xy 368.78095 -291.095938) (xy 368.776776 -291.146296)
			(xy 368.764361 -291.195317) (xy 368.744046 -291.241626) (xy 368.716385 -291.283959) (xy 368.682133 -291.321161)
			(xy 368.642224 -291.352217) (xy 368.597748 -291.376281) (xy 368.549917 -291.392694) (xy 368.500036 -291.401011)
			(xy 368.474752 -291.4015) (xy 367.534698 -291.4015) (xy 367.509425 -291.400902) (xy 367.459568 -291.392582)
			(xy 367.411761 -291.37617) (xy 367.367307 -291.352112) (xy 367.327419 -291.321066) (xy 367.293185 -291.283878)
			(xy 367.265539 -291.241562) (xy 367.245235 -291.195273) (xy 367.232827 -291.146274) (xy 367.228652 -291.0959)
			(xy 366.900205 -291.0959) (xy 366.900206 -291.095938) (xy 366.899711 -291.120545) (xy 366.891816 -291.169122)
			(xy 366.876232 -291.215803) (xy 366.853361 -291.25938) (xy 366.823796 -291.298724) (xy 366.788303 -291.332816)
			(xy 366.7478 -291.360772) (xy 366.703338 -291.38187) (xy 366.656067 -291.395562) (xy 366.607212 -291.401494)
			(xy 366.558037 -291.399513) (xy 366.509818 -291.389669) (xy 366.463802 -291.372217) (xy 366.421181 -291.34761)
			(xy 366.38306 -291.316485) (xy 366.350425 -291.279648) (xy 366.324122 -291.238052) (xy 366.304831 -291.192776)
			(xy 366.293054 -291.144992) (xy 366.289094 -291.095938) (xy 365.960921 -291.095938) (xy 365.956749 -291.146282)
			(xy 365.94434 -291.195289) (xy 365.924034 -291.241586) (xy 365.896386 -291.28391) (xy 365.862149 -291.321107)
			(xy 365.822257 -291.352161) (xy 365.777798 -291.376227) (xy 365.729985 -291.392647) (xy 365.680121 -291.400974)
			(xy 365.654844 -291.4015) (xy 364.71479 -291.4015) (xy 364.689517 -291.400901) (xy 364.639662 -291.39258)
			(xy 364.591855 -291.376167) (xy 364.547403 -291.352109) (xy 364.507516 -291.321063) (xy 364.473283 -291.283875)
			(xy 364.445638 -291.24156) (xy 364.425334 -291.195271) (xy 364.412926 -291.146273) (xy 364.408752 -291.0959)
			(xy 364.080043 -291.0959) (xy 364.080044 -291.095938) (xy 364.079549 -291.120545) (xy 364.071654 -291.169122)
			(xy 364.05607 -291.215803) (xy 364.033199 -291.25938) (xy 364.003634 -291.298724) (xy 363.968141 -291.332816)
			(xy 363.927638 -291.360772) (xy 363.883176 -291.38187) (xy 363.835905 -291.395562) (xy 363.78705 -291.401494)
			(xy 363.737875 -291.399513) (xy 363.689656 -291.389669) (xy 363.64364 -291.372217) (xy 363.601019 -291.34761)
			(xy 363.562898 -291.316485) (xy 363.530263 -291.279648) (xy 363.50396 -291.238052) (xy 363.484669 -291.192776)
			(xy 363.472892 -291.144992) (xy 363.468932 -291.095938) (xy 356.56647 -291.095938) (xy 356.565975 -291.120545)
			(xy 356.55808 -291.169122) (xy 356.542496 -291.215803) (xy 356.519625 -291.25938) (xy 356.49006 -291.298724)
			(xy 356.454567 -291.332816) (xy 356.414064 -291.360772) (xy 356.369602 -291.38187) (xy 356.322331 -291.395562)
			(xy 356.273476 -291.401494) (xy 356.224301 -291.399513) (xy 356.176082 -291.389669) (xy 356.130066 -291.372217)
			(xy 356.087445 -291.34761) (xy 356.049324 -291.316485) (xy 356.016689 -291.279648) (xy 355.990386 -291.238052)
			(xy 355.971095 -291.192776) (xy 355.959318 -291.144992) (xy 355.955358 -291.095938) (xy 355.627221 -291.095938)
			(xy 355.623049 -291.146285) (xy 355.610637 -291.195297) (xy 355.590329 -291.241596) (xy 355.562677 -291.283922)
			(xy 355.528435 -291.32112) (xy 355.488538 -291.352174) (xy 355.444074 -291.376237) (xy 355.396255 -291.392655)
			(xy 355.346387 -291.400977) (xy 355.321108 -291.4015) (xy 354.381054 -291.4015) (xy 354.355783 -291.400899)
			(xy 354.305932 -291.392573) (xy 354.258131 -291.376157) (xy 354.213684 -291.352097) (xy 354.173802 -291.32105)
			(xy 354.139574 -291.283863) (xy 354.111932 -291.24155) (xy 354.091632 -291.195264) (xy 354.079226 -291.146269)
			(xy 354.075052 -291.0959) (xy 353.746307 -291.0959) (xy 353.746308 -291.095938) (xy 353.745813 -291.120545)
			(xy 353.737918 -291.169122) (xy 353.722334 -291.215803) (xy 353.699463 -291.25938) (xy 353.669898 -291.298724)
			(xy 353.634405 -291.332816) (xy 353.593902 -291.360772) (xy 353.54944 -291.38187) (xy 353.502169 -291.395562)
			(xy 353.453314 -291.401494) (xy 353.404139 -291.399513) (xy 353.35592 -291.389669) (xy 353.309904 -291.372217)
			(xy 353.267283 -291.34761) (xy 353.229162 -291.316485) (xy 353.196527 -291.279648) (xy 353.170224 -291.238052)
			(xy 353.150933 -291.192776) (xy 353.139156 -291.144992) (xy 353.135196 -291.095938) (xy 352.807321 -291.095938)
			(xy 352.803148 -291.146286) (xy 352.790737 -291.195298) (xy 352.770428 -291.241599) (xy 352.742774 -291.283925)
			(xy 352.708532 -291.321122) (xy 352.668634 -291.352176) (xy 352.624168 -291.37624) (xy 352.576349 -291.392656)
			(xy 352.526479 -291.400978) (xy 352.5012 -291.4015) (xy 351.561146 -291.4015) (xy 351.535868 -291.400935)
			(xy 351.486 -291.39262) (xy 351.438182 -291.37621) (xy 351.393716 -291.352153) (xy 351.353818 -291.321104)
			(xy 351.319575 -291.283911) (xy 351.291921 -291.241589) (xy 351.271611 -291.195292) (xy 351.259199 -291.146283)
			(xy 351.255023 -291.0959) (xy 350.926399 -291.0959) (xy 350.9264 -291.095938) (xy 350.925905 -291.120545)
			(xy 350.91801 -291.169122) (xy 350.902426 -291.215803) (xy 350.879555 -291.25938) (xy 350.84999 -291.298724)
			(xy 350.814497 -291.332816) (xy 350.773994 -291.360772) (xy 350.729532 -291.38187) (xy 350.682261 -291.395562)
			(xy 350.633406 -291.401494) (xy 350.584231 -291.399513) (xy 350.536012 -291.389669) (xy 350.489996 -291.372217)
			(xy 350.447375 -291.34761) (xy 350.409254 -291.316485) (xy 350.376619 -291.279648) (xy 350.350316 -291.238052)
			(xy 350.331025 -291.192776) (xy 350.319248 -291.144992) (xy 350.315288 -291.095938) (xy 349.98745 -291.095938)
			(xy 349.983277 -291.146292) (xy 349.970864 -291.195309) (xy 349.950552 -291.241615) (xy 349.922895 -291.283945)
			(xy 349.888648 -291.321147) (xy 349.848745 -291.352203) (xy 349.804275 -291.376269) (xy 349.756449 -291.392686)
			(xy 349.706574 -291.401007) (xy 349.681292 -291.4015) (xy 348.741238 -291.4015) (xy 348.71596 -291.400934)
			(xy 348.666094 -291.392619) (xy 348.618276 -291.376208) (xy 348.573812 -291.35215) (xy 348.533915 -291.321101)
			(xy 348.499672 -291.283909) (xy 348.472019 -291.241587) (xy 348.45171 -291.19529) (xy 348.439299 -291.146282)
			(xy 348.435123 -291.0959) (xy 348.106491 -291.0959) (xy 348.106492 -291.095938) (xy 348.105997 -291.120545)
			(xy 348.098102 -291.169122) (xy 348.082518 -291.215803) (xy 348.059647 -291.25938) (xy 348.030082 -291.298724)
			(xy 347.994589 -291.332816) (xy 347.954086 -291.360772) (xy 347.909624 -291.38187) (xy 347.862353 -291.395562)
			(xy 347.813498 -291.401494) (xy 347.764323 -291.399513) (xy 347.716104 -291.389669) (xy 347.670088 -291.372217)
			(xy 347.627467 -291.34761) (xy 347.589346 -291.316485) (xy 347.556711 -291.279648) (xy 347.530408 -291.238052)
			(xy 347.511117 -291.192776) (xy 347.49934 -291.144992) (xy 347.49538 -291.095938) (xy 347.167221 -291.095938)
			(xy 347.163049 -291.146283) (xy 347.150639 -291.195292) (xy 347.130332 -291.24159) (xy 347.102682 -291.283915)
			(xy 347.068443 -291.321112) (xy 347.02855 -291.352166) (xy 346.984089 -291.376231) (xy 346.936273 -291.39265)
			(xy 346.886408 -291.400976) (xy 346.86113 -291.4015) (xy 345.921076 -291.4015) (xy 345.895804 -291.4009)
			(xy 345.84595 -291.392578) (xy 345.798146 -291.376163) (xy 345.753695 -291.352104) (xy 345.71381 -291.321058)
			(xy 345.679579 -291.28387) (xy 345.651936 -291.241556) (xy 345.631633 -291.195269) (xy 345.619226 -291.146271)
			(xy 345.615052 -291.0959) (xy 345.286795 -291.0959) (xy 345.282642 -291.146124) (xy 345.270297 -291.194984)
			(xy 345.250095 -291.241154) (xy 345.222584 -291.283377) (xy 345.188511 -291.32051) (xy 345.148803 -291.351541)
			(xy 345.104537 -291.37563) (xy 345.056916 -291.392121) (xy 345.007234 -291.400567) (xy 344.982038 -291.401246)
			(xy 344.971974 -291.401682) (xy 344.95339 -291.409417) (xy 344.94597 -291.416232) (xy 344.895424 -291.467032)
			(xy 344.888742 -291.474442) (xy 344.881168 -291.492879) (xy 344.880692 -291.502846) (xy 344.880692 -292.265862)
			(xy 344.881105 -292.275889) (xy 344.888768 -292.29442) (xy 344.902941 -292.308606) (xy 344.921465 -292.316286)
			(xy 344.931492 -292.316662) (xy 345.499944 -292.316662) (xy 345.509555 -292.316253) (xy 345.527441 -292.30921)
			(xy 345.534742 -292.302946) (xy 345.543378 -292.295072) (xy 345.551172 -292.287376) (xy 345.559906 -292.267314)
			(xy 345.559503 -292.245436) (xy 345.550035 -292.225709) (xy 345.533219 -292.211709) (xy 345.512103 -292.205974)
			(xy 345.501214 -292.207188) (xy 345.488793 -292.209096) (xy 345.463742 -292.211132) (xy 345.451176 -292.211252)
			(xy 345.426351 -292.210764) (xy 345.377356 -292.202728) (xy 345.330307 -292.186871) (xy 345.286443 -292.163611)
			(xy 345.24692 -292.133561) (xy 345.212779 -292.097512) (xy 345.18492 -292.056415) (xy 345.164077 -292.011353)
			(xy 345.150799 -291.963511) (xy 345.145436 -291.914152) (xy 345.148129 -291.864576) (xy 345.158807 -291.816088)
			(xy 345.177189 -291.769967) (xy 345.202791 -291.727427) (xy 345.234937 -291.689589) (xy 345.272782 -291.657451)
			(xy 345.315328 -291.631859) (xy 345.361453 -291.613487) (xy 345.409943 -291.60282) (xy 345.45952 -291.600138)
			(xy 345.508878 -291.605512) (xy 345.556717 -291.618801) (xy 345.601775 -291.639654) (xy 345.642865 -291.667522)
			(xy 345.678906 -291.701671) (xy 345.708948 -291.7412) (xy 345.732198 -291.78507) (xy 345.748045 -291.832122)
			(xy 345.75607 -291.881119) (xy 345.756484 -291.905944) (xy 345.755836 -291.934644) (xy 345.745102 -291.991032)
			(xy 345.735148 -292.017958) (xy 345.730322 -292.030658) (xy 345.734132 -292.057074) (xy 345.805252 -292.147498)
			(xy 345.830144 -292.157658) (xy 345.843606 -292.155626) (xy 345.862876 -292.153127) (xy 345.901645 -292.150455)
			(xy 345.921076 -292.150292) (xy 346.01023 -292.150292) (xy 346.022556 -292.149699) (xy 346.044386 -292.138249)
			(xy 346.051886 -292.128448) (xy 346.10675 -292.049454) (xy 346.109798 -292.02507) (xy 346.10548 -292.013132)
			(xy 346.096415 -291.987264) (xy 346.086585 -291.933346) (xy 346.085922 -291.905944) (xy 346.086444 -291.880689)
			(xy 346.094757 -291.830867) (xy 346.111158 -291.783093) (xy 346.135199 -291.73867) (xy 346.166223 -291.69881)
			(xy 346.203385 -291.6646) (xy 346.245671 -291.636974) (xy 346.291927 -291.616684) (xy 346.340892 -291.604284)
			(xy 346.39123 -291.600113) (xy 346.441568 -291.604284) (xy 346.490533 -291.616684) (xy 346.536789 -291.636974)
			(xy 346.579075 -291.6646) (xy 346.616237 -291.69881) (xy 346.647261 -291.73867) (xy 346.671302 -291.783093)
			(xy 346.687703 -291.830867) (xy 346.696016 -291.880689) (xy 346.696538 -291.905944) (xy 346.695944 -291.933353)
			(xy 346.686112 -291.987283) (xy 346.67698 -292.013132) (xy 346.672662 -292.02507) (xy 346.67571 -292.049454)
			(xy 346.730574 -292.128448) (xy 346.738186 -292.138117) (xy 346.759948 -292.149523) (xy 346.77223 -292.150292)
			(xy 346.86113 -292.150292) (xy 346.896586 -292.150864) (xy 346.966939 -292.159763) (xy 347.035628 -292.177381)
			(xy 347.101579 -292.203441) (xy 347.163758 -292.237536) (xy 347.221191 -292.27913) (xy 347.247464 -292.302946)
			(xy 347.254752 -292.309237) (xy 347.272642 -292.316307) (xy 347.282262 -292.316662) (xy 348.320106 -292.316662)
			(xy 348.329713 -292.316242) (xy 348.347584 -292.309183) (xy 348.354904 -292.302946) (xy 348.36354 -292.295072)
			(xy 348.371372 -292.287382) (xy 348.380171 -292.267298) (xy 348.379794 -292.245375) (xy 348.37031 -292.225606)
			(xy 348.353446 -292.211592) (xy 348.332275 -292.205886) (xy 348.321376 -292.207188) (xy 348.308894 -292.209121)
			(xy 348.283715 -292.211153) (xy 348.271084 -292.211252) (xy 348.246259 -292.210765) (xy 348.197264 -292.20273)
			(xy 348.150214 -292.186874) (xy 348.106349 -292.163615) (xy 348.066825 -292.133565) (xy 348.032683 -292.097517)
			(xy 348.004823 -292.056421) (xy 347.983979 -292.011358) (xy 347.9707 -291.963517) (xy 347.965336 -291.914158)
			(xy 347.968028 -291.864581) (xy 347.978706 -291.816093) (xy 347.997087 -291.769971) (xy 348.022688 -291.72743)
			(xy 348.054835 -291.689592) (xy 348.092679 -291.657453) (xy 348.135225 -291.63186) (xy 348.18135 -291.613488)
			(xy 348.22984 -291.60282) (xy 348.279418 -291.600138) (xy 348.328776 -291.605511) (xy 348.376615 -291.6188)
			(xy 348.421673 -291.639653) (xy 348.462764 -291.667521) (xy 348.498805 -291.70167) (xy 348.528847 -291.7412)
			(xy 348.552098 -291.785069) (xy 348.567944 -291.832122) (xy 348.57597 -291.881119) (xy 348.576392 -291.905944)
			(xy 348.575744 -291.934644) (xy 348.565011 -291.991032) (xy 348.555056 -292.017958) (xy 348.55023 -292.030658)
			(xy 348.55404 -292.057074) (xy 348.62516 -292.147498) (xy 348.650052 -292.157658) (xy 348.663514 -292.15588)
			(xy 348.682844 -292.153316) (xy 348.72174 -292.150521) (xy 348.741238 -292.150292) (xy 348.830138 -292.150292)
			(xy 348.842463 -292.149698) (xy 348.86429 -292.138245) (xy 348.871794 -292.128448) (xy 348.926658 -292.049454)
			(xy 348.929706 -292.02507) (xy 348.925388 -292.013132) (xy 348.916323 -291.987264) (xy 348.906493 -291.933346)
			(xy 348.90583 -291.905944) (xy 348.906352 -291.880689) (xy 348.914665 -291.830867) (xy 348.931066 -291.783093)
			(xy 348.955107 -291.73867) (xy 348.986131 -291.69881) (xy 349.023293 -291.6646) (xy 349.065579 -291.636974)
			(xy 349.111835 -291.616684) (xy 349.1608 -291.604284) (xy 349.211138 -291.600113) (xy 349.261476 -291.604284)
			(xy 349.310441 -291.616684) (xy 349.356697 -291.636974) (xy 349.398983 -291.6646) (xy 349.436145 -291.69881)
			(xy 349.467169 -291.73867) (xy 349.49121 -291.783093) (xy 349.507611 -291.830867) (xy 349.515924 -291.880689)
			(xy 349.516446 -291.905944) (xy 349.515852 -291.933353) (xy 349.50602 -291.987283) (xy 349.496888 -292.013132)
			(xy 349.49257 -292.02507) (xy 349.495618 -292.049454) (xy 349.550482 -292.128448) (xy 349.558094 -292.138116)
			(xy 349.579856 -292.149518) (xy 349.592138 -292.150292) (xy 349.681038 -292.150292) (xy 349.716494 -292.150864)
			(xy 349.786846 -292.159764) (xy 349.855535 -292.177383) (xy 349.921485 -292.203444) (xy 349.983663 -292.237539)
			(xy 350.041095 -292.279134) (xy 350.067372 -292.302946) (xy 350.07466 -292.309236) (xy 350.092551 -292.316303)
			(xy 350.10217 -292.316662) (xy 351.140014 -292.316662) (xy 351.14962 -292.316241) (xy 351.167489 -292.30918)
			(xy 351.174812 -292.302946) (xy 351.183448 -292.295072) (xy 351.191244 -292.287379) (xy 351.199984 -292.267319)
			(xy 351.199583 -292.245441) (xy 351.190114 -292.225716) (xy 351.173294 -292.21172) (xy 351.152176 -292.205994)
			(xy 351.141284 -292.207188) (xy 351.128863 -292.209095) (xy 351.103812 -292.211128) (xy 351.091246 -292.211252)
			(xy 351.06642 -292.21077) (xy 351.017421 -292.202744) (xy 350.970366 -292.186896) (xy 350.926495 -292.163644)
			(xy 350.886964 -292.1336) (xy 350.852815 -292.097557) (xy 350.824947 -292.056463) (xy 350.804095 -292.011401)
			(xy 350.790808 -291.96356) (xy 350.785437 -291.914199) (xy 350.788123 -291.86462) (xy 350.798795 -291.816129)
			(xy 350.817171 -291.770002) (xy 350.842769 -291.727457) (xy 350.874913 -291.689614) (xy 350.912756 -291.65747)
			(xy 350.955301 -291.631872) (xy 351.001427 -291.613495) (xy 351.049918 -291.602823) (xy 351.099497 -291.600137)
			(xy 351.148858 -291.605508) (xy 351.1967 -291.618794) (xy 351.241761 -291.639646) (xy 351.282855 -291.667513)
			(xy 351.318899 -291.701662) (xy 351.348943 -291.741193) (xy 351.372196 -291.785064) (xy 351.388044 -291.832119)
			(xy 351.39607 -291.881118) (xy 351.396554 -291.905944) (xy 351.395906 -291.934644) (xy 351.385171 -291.991031)
			(xy 351.375218 -292.017958) (xy 351.370392 -292.030658) (xy 351.374202 -292.057074) (xy 351.445322 -292.147498)
			(xy 351.470214 -292.157658) (xy 351.483676 -292.155626) (xy 351.502946 -292.15313) (xy 351.541716 -292.150463)
			(xy 351.561146 -292.150292) (xy 351.650046 -292.150292) (xy 351.66237 -292.149696) (xy 351.684194 -292.138241)
			(xy 351.691702 -292.128448) (xy 351.746566 -292.049454) (xy 351.749614 -292.02507) (xy 351.745296 -292.013132)
			(xy 351.736231 -291.987264) (xy 351.7264 -291.933346) (xy 351.725738 -291.905944) (xy 351.72626 -291.880689)
			(xy 351.734573 -291.830867) (xy 351.750974 -291.783093) (xy 351.775015 -291.73867) (xy 351.806039 -291.69881)
			(xy 351.843201 -291.6646) (xy 351.885487 -291.636974) (xy 351.931743 -291.616684) (xy 351.980708 -291.604284)
			(xy 352.031046 -291.600113) (xy 352.081384 -291.604284) (xy 352.130349 -291.616684) (xy 352.176605 -291.636974)
			(xy 352.218891 -291.6646) (xy 352.256053 -291.69881) (xy 352.287077 -291.73867) (xy 352.311118 -291.783093)
			(xy 352.327519 -291.830867) (xy 352.335832 -291.880689) (xy 352.336354 -291.905944) (xy 352.33576 -291.933353)
			(xy 352.325929 -291.987283) (xy 352.316796 -292.013132) (xy 352.312478 -292.02507) (xy 352.315526 -292.049454)
			(xy 352.37039 -292.128448) (xy 352.377996 -292.138131) (xy 352.399757 -292.149572) (xy 352.412046 -292.150292)
			(xy 352.5012 -292.150292) (xy 352.536657 -292.150862) (xy 352.607011 -292.159758) (xy 352.675703 -292.177373)
			(xy 352.741656 -292.20343) (xy 352.803838 -292.237523) (xy 352.861273 -292.279116) (xy 352.887534 -292.302946)
			(xy 352.894825 -292.309226) (xy 352.912716 -292.316271) (xy 352.922332 -292.316662) (xy 353.959922 -292.316662)
			(xy 353.969527 -292.316239) (xy 353.987395 -292.309176) (xy 353.99472 -292.302946) (xy 354.003356 -292.295072)
			(xy 354.011152 -292.287378) (xy 354.01989 -292.267317) (xy 354.019489 -292.24544) (xy 354.01002 -292.225714)
			(xy 353.993201 -292.211717) (xy 353.972083 -292.205989) (xy 353.961192 -292.207188) (xy 353.948771 -292.209095)
			(xy 353.92372 -292.211129) (xy 353.911154 -292.211252) (xy 353.88633 -292.210763) (xy 353.837336 -292.202723)
			(xy 353.790289 -292.186863) (xy 353.746427 -292.163601) (xy 353.706906 -292.133548) (xy 353.672768 -292.097498)
			(xy 353.644912 -292.0564) (xy 353.624071 -292.011337) (xy 353.610796 -291.963496) (xy 353.605435 -291.914138)
			(xy 353.608131 -291.864562) (xy 353.618811 -291.816075) (xy 353.637195 -291.769955) (xy 353.662798 -291.727417)
			(xy 353.694945 -291.689581) (xy 353.73279 -291.657445) (xy 353.775336 -291.631855) (xy 353.821462 -291.613484)
			(xy 353.869951 -291.602819) (xy 353.919528 -291.600138) (xy 353.968885 -291.605513) (xy 354.016722 -291.618803)
			(xy 354.061779 -291.639656) (xy 354.102869 -291.667524) (xy 354.138909 -291.701673) (xy 354.168949 -291.741203)
			(xy 354.192199 -291.785071) (xy 354.208045 -291.832124) (xy 354.21607 -291.88112) (xy 354.216462 -291.905944)
			(xy 354.215814 -291.934644) (xy 354.20508 -291.991032) (xy 354.195126 -292.017958) (xy 354.1903 -292.030658)
			(xy 354.19411 -292.057074) (xy 354.26523 -292.147498) (xy 354.290122 -292.157658) (xy 354.303584 -292.155626)
			(xy 354.322854 -292.15313) (xy 354.361624 -292.150463) (xy 354.381054 -292.150292) (xy 354.470208 -292.150292)
			(xy 354.482537 -292.149704) (xy 354.504375 -292.138259) (xy 354.511864 -292.128448) (xy 354.566728 -292.049454)
			(xy 354.569776 -292.02507) (xy 354.565458 -292.013132) (xy 354.556391 -291.987265) (xy 354.546558 -291.933347)
			(xy 354.5459 -291.905944) (xy 354.546422 -291.880689) (xy 354.554735 -291.830867) (xy 354.571136 -291.783093)
			(xy 354.595177 -291.73867) (xy 354.626201 -291.69881) (xy 354.663363 -291.6646) (xy 354.705649 -291.636974)
			(xy 354.751905 -291.616684) (xy 354.80087 -291.604284) (xy 354.851208 -291.600113) (xy 354.901546 -291.604284)
			(xy 354.950511 -291.616684) (xy 354.996767 -291.636974) (xy 355.039053 -291.6646) (xy 355.076215 -291.69881)
			(xy 355.107239 -291.73867) (xy 355.13128 -291.783093) (xy 355.147681 -291.830867) (xy 355.155994 -291.880689)
			(xy 355.156516 -291.905944) (xy 356.425258 -291.905944) (xy 356.429218 -291.85689) (xy 356.440995 -291.809106)
			(xy 356.460286 -291.76383) (xy 356.486589 -291.722234) (xy 356.519224 -291.685397) (xy 356.557345 -291.654272)
			(xy 356.599966 -291.629665) (xy 356.645982 -291.612213) (xy 356.694201 -291.602369) (xy 356.743376 -291.600388)
			(xy 356.792231 -291.60632) (xy 356.839502 -291.620012) (xy 356.883964 -291.64111) (xy 356.924467 -291.669066)
			(xy 356.95996 -291.703158) (xy 356.989525 -291.742502) (xy 357.012396 -291.786079) (xy 357.02798 -291.83276)
			(xy 357.035875 -291.881337) (xy 357.03637 -291.905944) (xy 357.365312 -291.905944) (xy 357.369272 -291.85689)
			(xy 357.381049 -291.809106) (xy 357.40034 -291.76383) (xy 357.426643 -291.722234) (xy 357.459278 -291.685397)
			(xy 357.497399 -291.654272) (xy 357.54002 -291.629665) (xy 357.586036 -291.612213) (xy 357.634255 -291.602369)
			(xy 357.68343 -291.600388) (xy 357.732285 -291.60632) (xy 357.779556 -291.620012) (xy 357.824018 -291.64111)
			(xy 357.864521 -291.669066) (xy 357.900014 -291.703158) (xy 357.929579 -291.742502) (xy 357.95245 -291.786079)
			(xy 357.968034 -291.83276) (xy 357.975929 -291.881337) (xy 357.976424 -291.905944) (xy 358.305366 -291.905944)
			(xy 358.309326 -291.85689) (xy 358.321103 -291.809106) (xy 358.340394 -291.76383) (xy 358.366697 -291.722234)
			(xy 358.399332 -291.685397) (xy 358.437453 -291.654272) (xy 358.480074 -291.629665) (xy 358.52609 -291.612213)
			(xy 358.574309 -291.602369) (xy 358.623484 -291.600388) (xy 358.672339 -291.60632) (xy 358.71961 -291.620012)
			(xy 358.764072 -291.64111) (xy 358.804575 -291.669066) (xy 358.840068 -291.703158) (xy 358.869633 -291.742502)
			(xy 358.892504 -291.786079) (xy 358.908088 -291.83276) (xy 358.915983 -291.881337) (xy 358.916478 -291.905944)
			(xy 361.118924 -291.905944) (xy 361.122884 -291.85689) (xy 361.134661 -291.809106) (xy 361.153952 -291.76383)
			(xy 361.180255 -291.722234) (xy 361.21289 -291.685397) (xy 361.251011 -291.654272) (xy 361.293632 -291.629665)
			(xy 361.339648 -291.612213) (xy 361.387867 -291.602369) (xy 361.437042 -291.600388) (xy 361.485897 -291.60632)
			(xy 361.533168 -291.620012) (xy 361.57763 -291.64111) (xy 361.618133 -291.669066) (xy 361.653626 -291.703158)
			(xy 361.683191 -291.742502) (xy 361.706062 -291.786079) (xy 361.721646 -291.83276) (xy 361.729541 -291.881337)
			(xy 361.730036 -291.905944) (xy 362.058978 -291.905944) (xy 362.062938 -291.85689) (xy 362.074715 -291.809106)
			(xy 362.094006 -291.76383) (xy 362.120309 -291.722234) (xy 362.152944 -291.685397) (xy 362.191065 -291.654272)
			(xy 362.233686 -291.629665) (xy 362.279702 -291.612213) (xy 362.327921 -291.602369) (xy 362.377096 -291.600388)
			(xy 362.425951 -291.60632) (xy 362.473222 -291.620012) (xy 362.517684 -291.64111) (xy 362.558187 -291.669066)
			(xy 362.59368 -291.703158) (xy 362.623245 -291.742502) (xy 362.646116 -291.786079) (xy 362.6617 -291.83276)
			(xy 362.669595 -291.881337) (xy 362.67009 -291.905944) (xy 362.999032 -291.905944) (xy 363.002992 -291.85689)
			(xy 363.014769 -291.809106) (xy 363.03406 -291.76383) (xy 363.060363 -291.722234) (xy 363.092998 -291.685397)
			(xy 363.131119 -291.654272) (xy 363.17374 -291.629665) (xy 363.219756 -291.612213) (xy 363.267975 -291.602369)
			(xy 363.31715 -291.600388) (xy 363.366005 -291.60632) (xy 363.413276 -291.620012) (xy 363.457738 -291.64111)
			(xy 363.498241 -291.669066) (xy 363.533734 -291.703158) (xy 363.563299 -291.742502) (xy 363.58617 -291.786079)
			(xy 363.601754 -291.83276) (xy 363.609649 -291.881337) (xy 363.610144 -291.905944) (xy 364.878886 -291.905944)
			(xy 364.882846 -291.85689) (xy 364.894623 -291.809106) (xy 364.913914 -291.76383) (xy 364.940217 -291.722234)
			(xy 364.972852 -291.685397) (xy 365.010973 -291.654272) (xy 365.053594 -291.629665) (xy 365.09961 -291.612213)
			(xy 365.147829 -291.602369) (xy 365.197004 -291.600388) (xy 365.245859 -291.60632) (xy 365.29313 -291.620012)
			(xy 365.337592 -291.64111) (xy 365.378095 -291.669066) (xy 365.413588 -291.703158) (xy 365.443153 -291.742502)
			(xy 365.466024 -291.786079) (xy 365.481608 -291.83276) (xy 365.489503 -291.881337) (xy 365.489998 -291.905944)
			(xy 365.81894 -291.905944) (xy 365.8229 -291.85689) (xy 365.834677 -291.809106) (xy 365.853968 -291.76383)
			(xy 365.880271 -291.722234) (xy 365.912906 -291.685397) (xy 365.951027 -291.654272) (xy 365.993648 -291.629665)
			(xy 366.039664 -291.612213) (xy 366.087883 -291.602369) (xy 366.137058 -291.600388) (xy 366.185913 -291.60632)
			(xy 366.233184 -291.620012) (xy 366.277646 -291.64111) (xy 366.318149 -291.669066) (xy 366.353642 -291.703158)
			(xy 366.383207 -291.742502) (xy 366.406078 -291.786079) (xy 366.421662 -291.83276) (xy 366.429557 -291.881337)
			(xy 366.430052 -291.905944) (xy 367.699048 -291.905944) (xy 367.703008 -291.85689) (xy 367.714785 -291.809106)
			(xy 367.734076 -291.76383) (xy 367.760379 -291.722234) (xy 367.793014 -291.685397) (xy 367.831135 -291.654272)
			(xy 367.873756 -291.629665) (xy 367.919772 -291.612213) (xy 367.967991 -291.602369) (xy 368.017166 -291.600388)
			(xy 368.066021 -291.60632) (xy 368.113292 -291.620012) (xy 368.157754 -291.64111) (xy 368.198257 -291.669066)
			(xy 368.23375 -291.703158) (xy 368.263315 -291.742502) (xy 368.286186 -291.786079) (xy 368.30177 -291.83276)
			(xy 368.309665 -291.881337) (xy 368.31016 -291.905944) (xy 368.639102 -291.905944) (xy 368.643062 -291.85689)
			(xy 368.654839 -291.809106) (xy 368.67413 -291.76383) (xy 368.700433 -291.722234) (xy 368.733068 -291.685397)
			(xy 368.771189 -291.654272) (xy 368.81381 -291.629665) (xy 368.859826 -291.612213) (xy 368.908045 -291.602369)
			(xy 368.95722 -291.600388) (xy 369.006075 -291.60632) (xy 369.053346 -291.620012) (xy 369.097808 -291.64111)
			(xy 369.138311 -291.669066) (xy 369.173804 -291.703158) (xy 369.203369 -291.742502) (xy 369.22624 -291.786079)
			(xy 369.241824 -291.83276) (xy 369.249719 -291.881337) (xy 369.250214 -291.905944) (xy 370.518956 -291.905944)
			(xy 370.522916 -291.85689) (xy 370.534693 -291.809106) (xy 370.553984 -291.76383) (xy 370.580287 -291.722234)
			(xy 370.612922 -291.685397) (xy 370.651043 -291.654272) (xy 370.693664 -291.629665) (xy 370.73968 -291.612213)
			(xy 370.787899 -291.602369) (xy 370.837074 -291.600388) (xy 370.885929 -291.60632) (xy 370.9332 -291.620012)
			(xy 370.977662 -291.64111) (xy 371.018165 -291.669066) (xy 371.053658 -291.703158) (xy 371.083223 -291.742502)
			(xy 371.106094 -291.786079) (xy 371.121678 -291.83276) (xy 371.129573 -291.881337) (xy 371.130068 -291.905944)
			(xy 371.45901 -291.905944) (xy 371.46297 -291.85689) (xy 371.474747 -291.809106) (xy 371.494038 -291.76383)
			(xy 371.520341 -291.722234) (xy 371.552976 -291.685397) (xy 371.591097 -291.654272) (xy 371.633718 -291.629665)
			(xy 371.679734 -291.612213) (xy 371.727953 -291.602369) (xy 371.777128 -291.600388) (xy 371.825983 -291.60632)
			(xy 371.873254 -291.620012) (xy 371.917716 -291.64111) (xy 371.958219 -291.669066) (xy 371.993712 -291.703158)
			(xy 372.023277 -291.742502) (xy 372.046148 -291.786079) (xy 372.061732 -291.83276) (xy 372.069627 -291.881337)
			(xy 372.070122 -291.905944) (xy 373.339118 -291.905944) (xy 373.343078 -291.85689) (xy 373.354855 -291.809106)
			(xy 373.374146 -291.76383) (xy 373.400449 -291.722234) (xy 373.433084 -291.685397) (xy 373.471205 -291.654272)
			(xy 373.513826 -291.629665) (xy 373.559842 -291.612213) (xy 373.608061 -291.602369) (xy 373.657236 -291.600388)
			(xy 373.706091 -291.60632) (xy 373.753362 -291.620012) (xy 373.797824 -291.64111) (xy 373.838327 -291.669066)
			(xy 373.87382 -291.703158) (xy 373.903385 -291.742502) (xy 373.926256 -291.786079) (xy 373.94184 -291.83276)
			(xy 373.949735 -291.881337) (xy 373.95023 -291.905944) (xy 373.949735 -291.930551) (xy 373.94184 -291.979128)
			(xy 373.926256 -292.025809) (xy 373.903385 -292.069386) (xy 373.87382 -292.10873) (xy 373.838327 -292.142822)
			(xy 373.797824 -292.170778) (xy 373.753362 -292.191876) (xy 373.706091 -292.205568) (xy 373.657236 -292.2115)
			(xy 373.608061 -292.209519) (xy 373.559842 -292.199675) (xy 373.513826 -292.182223) (xy 373.471205 -292.157616)
			(xy 373.433084 -292.126491) (xy 373.400449 -292.089654) (xy 373.374146 -292.048058) (xy 373.354855 -292.002782)
			(xy 373.343078 -291.954998) (xy 373.339118 -291.905944) (xy 372.070122 -291.905944) (xy 372.069627 -291.930551)
			(xy 372.061732 -291.979128) (xy 372.046148 -292.025809) (xy 372.023277 -292.069386) (xy 371.993712 -292.10873)
			(xy 371.958219 -292.142822) (xy 371.917716 -292.170778) (xy 371.873254 -292.191876) (xy 371.825983 -292.205568)
			(xy 371.777128 -292.2115) (xy 371.727953 -292.209519) (xy 371.679734 -292.199675) (xy 371.633718 -292.182223)
			(xy 371.591097 -292.157616) (xy 371.552976 -292.126491) (xy 371.520341 -292.089654) (xy 371.494038 -292.048058)
			(xy 371.474747 -292.002782) (xy 371.46297 -291.954998) (xy 371.45901 -291.905944) (xy 371.130068 -291.905944)
			(xy 371.129573 -291.930551) (xy 371.121678 -291.979128) (xy 371.106094 -292.025809) (xy 371.083223 -292.069386)
			(xy 371.053658 -292.10873) (xy 371.018165 -292.142822) (xy 370.977662 -292.170778) (xy 370.9332 -292.191876)
			(xy 370.885929 -292.205568) (xy 370.837074 -292.2115) (xy 370.787899 -292.209519) (xy 370.73968 -292.199675)
			(xy 370.693664 -292.182223) (xy 370.651043 -292.157616) (xy 370.612922 -292.126491) (xy 370.580287 -292.089654)
			(xy 370.553984 -292.048058) (xy 370.534693 -292.002782) (xy 370.522916 -291.954998) (xy 370.518956 -291.905944)
			(xy 369.250214 -291.905944) (xy 369.249719 -291.930551) (xy 369.241824 -291.979128) (xy 369.22624 -292.025809)
			(xy 369.203369 -292.069386) (xy 369.173804 -292.10873) (xy 369.138311 -292.142822) (xy 369.097808 -292.170778)
			(xy 369.053346 -292.191876) (xy 369.006075 -292.205568) (xy 368.95722 -292.2115) (xy 368.908045 -292.209519)
			(xy 368.859826 -292.199675) (xy 368.81381 -292.182223) (xy 368.771189 -292.157616) (xy 368.733068 -292.126491)
			(xy 368.700433 -292.089654) (xy 368.67413 -292.048058) (xy 368.654839 -292.002782) (xy 368.643062 -291.954998)
			(xy 368.639102 -291.905944) (xy 368.31016 -291.905944) (xy 368.309665 -291.930551) (xy 368.30177 -291.979128)
			(xy 368.286186 -292.025809) (xy 368.263315 -292.069386) (xy 368.23375 -292.10873) (xy 368.198257 -292.142822)
			(xy 368.157754 -292.170778) (xy 368.113292 -292.191876) (xy 368.066021 -292.205568) (xy 368.017166 -292.2115)
			(xy 367.967991 -292.209519) (xy 367.919772 -292.199675) (xy 367.873756 -292.182223) (xy 367.831135 -292.157616)
			(xy 367.793014 -292.126491) (xy 367.760379 -292.089654) (xy 367.734076 -292.048058) (xy 367.714785 -292.002782)
			(xy 367.703008 -291.954998) (xy 367.699048 -291.905944) (xy 366.430052 -291.905944) (xy 366.429557 -291.930551)
			(xy 366.421662 -291.979128) (xy 366.406078 -292.025809) (xy 366.383207 -292.069386) (xy 366.353642 -292.10873)
			(xy 366.318149 -292.142822) (xy 366.277646 -292.170778) (xy 366.233184 -292.191876) (xy 366.185913 -292.205568)
			(xy 366.137058 -292.2115) (xy 366.087883 -292.209519) (xy 366.039664 -292.199675) (xy 365.993648 -292.182223)
			(xy 365.951027 -292.157616) (xy 365.912906 -292.126491) (xy 365.880271 -292.089654) (xy 365.853968 -292.048058)
			(xy 365.834677 -292.002782) (xy 365.8229 -291.954998) (xy 365.81894 -291.905944) (xy 365.489998 -291.905944)
			(xy 365.489503 -291.930551) (xy 365.481608 -291.979128) (xy 365.466024 -292.025809) (xy 365.443153 -292.069386)
			(xy 365.413588 -292.10873) (xy 365.378095 -292.142822) (xy 365.337592 -292.170778) (xy 365.29313 -292.191876)
			(xy 365.245859 -292.205568) (xy 365.197004 -292.2115) (xy 365.147829 -292.209519) (xy 365.09961 -292.199675)
			(xy 365.053594 -292.182223) (xy 365.010973 -292.157616) (xy 364.972852 -292.126491) (xy 364.940217 -292.089654)
			(xy 364.913914 -292.048058) (xy 364.894623 -292.002782) (xy 364.882846 -291.954998) (xy 364.878886 -291.905944)
			(xy 363.610144 -291.905944) (xy 363.609649 -291.930551) (xy 363.601754 -291.979128) (xy 363.58617 -292.025809)
			(xy 363.563299 -292.069386) (xy 363.533734 -292.10873) (xy 363.498241 -292.142822) (xy 363.457738 -292.170778)
			(xy 363.413276 -292.191876) (xy 363.366005 -292.205568) (xy 363.31715 -292.2115) (xy 363.267975 -292.209519)
			(xy 363.219756 -292.199675) (xy 363.17374 -292.182223) (xy 363.131119 -292.157616) (xy 363.092998 -292.126491)
			(xy 363.060363 -292.089654) (xy 363.03406 -292.048058) (xy 363.014769 -292.002782) (xy 363.002992 -291.954998)
			(xy 362.999032 -291.905944) (xy 362.67009 -291.905944) (xy 362.669595 -291.930551) (xy 362.6617 -291.979128)
			(xy 362.646116 -292.025809) (xy 362.623245 -292.069386) (xy 362.59368 -292.10873) (xy 362.558187 -292.142822)
			(xy 362.517684 -292.170778) (xy 362.473222 -292.191876) (xy 362.425951 -292.205568) (xy 362.377096 -292.2115)
			(xy 362.327921 -292.209519) (xy 362.279702 -292.199675) (xy 362.233686 -292.182223) (xy 362.191065 -292.157616)
			(xy 362.152944 -292.126491) (xy 362.120309 -292.089654) (xy 362.094006 -292.048058) (xy 362.074715 -292.002782)
			(xy 362.062938 -291.954998) (xy 362.058978 -291.905944) (xy 361.730036 -291.905944) (xy 361.729541 -291.930551)
			(xy 361.721646 -291.979128) (xy 361.706062 -292.025809) (xy 361.683191 -292.069386) (xy 361.653626 -292.10873)
			(xy 361.618133 -292.142822) (xy 361.57763 -292.170778) (xy 361.533168 -292.191876) (xy 361.485897 -292.205568)
			(xy 361.437042 -292.2115) (xy 361.387867 -292.209519) (xy 361.339648 -292.199675) (xy 361.293632 -292.182223)
			(xy 361.251011 -292.157616) (xy 361.21289 -292.126491) (xy 361.180255 -292.089654) (xy 361.153952 -292.048058)
			(xy 361.134661 -292.002782) (xy 361.122884 -291.954998) (xy 361.118924 -291.905944) (xy 358.916478 -291.905944)
			(xy 358.915983 -291.930551) (xy 358.908088 -291.979128) (xy 358.892504 -292.025809) (xy 358.869633 -292.069386)
			(xy 358.840068 -292.10873) (xy 358.804575 -292.142822) (xy 358.764072 -292.170778) (xy 358.71961 -292.191876)
			(xy 358.672339 -292.205568) (xy 358.623484 -292.2115) (xy 358.574309 -292.209519) (xy 358.52609 -292.199675)
			(xy 358.480074 -292.182223) (xy 358.437453 -292.157616) (xy 358.399332 -292.126491) (xy 358.366697 -292.089654)
			(xy 358.340394 -292.048058) (xy 358.321103 -292.002782) (xy 358.309326 -291.954998) (xy 358.305366 -291.905944)
			(xy 357.976424 -291.905944) (xy 357.975929 -291.930551) (xy 357.968034 -291.979128) (xy 357.95245 -292.025809)
			(xy 357.929579 -292.069386) (xy 357.900014 -292.10873) (xy 357.864521 -292.142822) (xy 357.824018 -292.170778)
			(xy 357.779556 -292.191876) (xy 357.732285 -292.205568) (xy 357.68343 -292.2115) (xy 357.634255 -292.209519)
			(xy 357.586036 -292.199675) (xy 357.54002 -292.182223) (xy 357.497399 -292.157616) (xy 357.459278 -292.126491)
			(xy 357.426643 -292.089654) (xy 357.40034 -292.048058) (xy 357.381049 -292.002782) (xy 357.369272 -291.954998)
			(xy 357.365312 -291.905944) (xy 357.03637 -291.905944) (xy 357.035875 -291.930551) (xy 357.02798 -291.979128)
			(xy 357.012396 -292.025809) (xy 356.989525 -292.069386) (xy 356.95996 -292.10873) (xy 356.924467 -292.142822)
			(xy 356.883964 -292.170778) (xy 356.839502 -292.191876) (xy 356.792231 -292.205568) (xy 356.743376 -292.2115)
			(xy 356.694201 -292.209519) (xy 356.645982 -292.199675) (xy 356.599966 -292.182223) (xy 356.557345 -292.157616)
			(xy 356.519224 -292.126491) (xy 356.486589 -292.089654) (xy 356.460286 -292.048058) (xy 356.440995 -292.002782)
			(xy 356.429218 -291.954998) (xy 356.425258 -291.905944) (xy 355.156516 -291.905944) (xy 355.155922 -291.933353)
			(xy 355.146089 -291.987282) (xy 355.136958 -292.013132) (xy 355.13264 -292.02507) (xy 355.135688 -292.049454)
			(xy 355.190552 -292.128448) (xy 355.198162 -292.138121) (xy 355.219924 -292.149536) (xy 355.232208 -292.150292)
			(xy 355.321108 -292.150292) (xy 355.356565 -292.150862) (xy 355.426918 -292.159759) (xy 355.49561 -292.177375)
			(xy 355.561562 -292.203433) (xy 355.623743 -292.237526) (xy 355.681178 -292.27912) (xy 355.707442 -292.302946)
			(xy 355.714734 -292.309225) (xy 355.732625 -292.316267) (xy 355.74224 -292.316662) (xy 355.926898 -292.316662)
			(xy 355.936967 -292.317086) (xy 355.955566 -292.324807) (xy 355.962966 -292.331648) (xy 356.058216 -292.426898)
			(xy 356.091236 -292.431724) (xy 356.105968 -292.42385) (xy 356.130004 -292.411674) (xy 356.181053 -292.394446)
			(xy 356.234223 -292.385746) (xy 356.261162 -292.385242) (xy 356.287152 -292.385722) (xy 356.338492 -292.393849)
			(xy 356.387928 -292.409909) (xy 356.434243 -292.433505) (xy 356.476296 -292.464058) (xy 356.51305 -292.500813)
			(xy 356.543601 -292.542867) (xy 356.567196 -292.589183) (xy 356.583254 -292.63862) (xy 356.591379 -292.68996)
			(xy 356.59187 -292.71595) (xy 357.835212 -292.71595) (xy 357.839172 -292.666896) (xy 357.850949 -292.619112)
			(xy 357.87024 -292.573836) (xy 357.896543 -292.53224) (xy 357.929178 -292.495403) (xy 357.967299 -292.464278)
			(xy 358.00992 -292.439671) (xy 358.055936 -292.422219) (xy 358.104155 -292.412375) (xy 358.15333 -292.410394)
			(xy 358.202185 -292.416326) (xy 358.249456 -292.430018) (xy 358.293918 -292.451116) (xy 358.334421 -292.479072)
			(xy 358.369914 -292.513164) (xy 358.399479 -292.552508) (xy 358.42235 -292.596085) (xy 358.437934 -292.642766)
			(xy 358.445829 -292.691343) (xy 358.446324 -292.71595) (xy 361.589078 -292.71595) (xy 361.593038 -292.666896)
			(xy 361.604815 -292.619112) (xy 361.624106 -292.573836) (xy 361.650409 -292.53224) (xy 361.683044 -292.495403)
			(xy 361.721165 -292.464278) (xy 361.763786 -292.439671) (xy 361.809802 -292.422219) (xy 361.858021 -292.412375)
			(xy 361.907196 -292.410394) (xy 361.956051 -292.416326) (xy 362.003322 -292.430018) (xy 362.047784 -292.451116)
			(xy 362.088287 -292.479072) (xy 362.12378 -292.513164) (xy 362.153345 -292.552508) (xy 362.176216 -292.596085)
			(xy 362.1918 -292.642766) (xy 362.199695 -292.691343) (xy 362.20019 -292.71595) (xy 364.408986 -292.71595)
			(xy 364.412946 -292.666896) (xy 364.424723 -292.619112) (xy 364.444014 -292.573836) (xy 364.470317 -292.53224)
			(xy 364.502952 -292.495403) (xy 364.541073 -292.464278) (xy 364.583694 -292.439671) (xy 364.62971 -292.422219)
			(xy 364.677929 -292.412375) (xy 364.727104 -292.410394) (xy 364.775959 -292.416326) (xy 364.82323 -292.430018)
			(xy 364.867692 -292.451116) (xy 364.908195 -292.479072) (xy 364.943688 -292.513164) (xy 364.973253 -292.552508)
			(xy 364.996124 -292.596085) (xy 365.011708 -292.642766) (xy 365.019603 -292.691343) (xy 365.020098 -292.71595)
			(xy 365.34904 -292.71595) (xy 365.353 -292.666896) (xy 365.364777 -292.619112) (xy 365.384068 -292.573836)
			(xy 365.410371 -292.53224) (xy 365.443006 -292.495403) (xy 365.481127 -292.464278) (xy 365.523748 -292.439671)
			(xy 365.569764 -292.422219) (xy 365.617983 -292.412375) (xy 365.667158 -292.410394) (xy 365.716013 -292.416326)
			(xy 365.763284 -292.430018) (xy 365.807746 -292.451116) (xy 365.848249 -292.479072) (xy 365.883742 -292.513164)
			(xy 365.913307 -292.552508) (xy 365.936178 -292.596085) (xy 365.951762 -292.642766) (xy 365.959657 -292.691343)
			(xy 365.960152 -292.71595) (xy 367.228894 -292.71595) (xy 367.232854 -292.666896) (xy 367.244631 -292.619112)
			(xy 367.263922 -292.573836) (xy 367.290225 -292.53224) (xy 367.32286 -292.495403) (xy 367.360981 -292.464278)
			(xy 367.403602 -292.439671) (xy 367.449618 -292.422219) (xy 367.497837 -292.412375) (xy 367.547012 -292.410394)
			(xy 367.595867 -292.416326) (xy 367.643138 -292.430018) (xy 367.6876 -292.451116) (xy 367.728103 -292.479072)
			(xy 367.763596 -292.513164) (xy 367.793161 -292.552508) (xy 367.816032 -292.596085) (xy 367.831616 -292.642766)
			(xy 367.839511 -292.691343) (xy 367.840006 -292.71595) (xy 368.168948 -292.71595) (xy 368.172908 -292.666896)
			(xy 368.184685 -292.619112) (xy 368.203976 -292.573836) (xy 368.230279 -292.53224) (xy 368.262914 -292.495403)
			(xy 368.301035 -292.464278) (xy 368.343656 -292.439671) (xy 368.389672 -292.422219) (xy 368.437891 -292.412375)
			(xy 368.487066 -292.410394) (xy 368.535921 -292.416326) (xy 368.583192 -292.430018) (xy 368.627654 -292.451116)
			(xy 368.668157 -292.479072) (xy 368.70365 -292.513164) (xy 368.733215 -292.552508) (xy 368.756086 -292.596085)
			(xy 368.77167 -292.642766) (xy 368.779565 -292.691343) (xy 368.78006 -292.71595) (xy 370.049056 -292.71595)
			(xy 370.053016 -292.666896) (xy 370.064793 -292.619112) (xy 370.084084 -292.573836) (xy 370.110387 -292.53224)
			(xy 370.143022 -292.495403) (xy 370.181143 -292.464278) (xy 370.223764 -292.439671) (xy 370.26978 -292.422219)
			(xy 370.317999 -292.412375) (xy 370.367174 -292.410394) (xy 370.416029 -292.416326) (xy 370.4633 -292.430018)
			(xy 370.507762 -292.451116) (xy 370.548265 -292.479072) (xy 370.583758 -292.513164) (xy 370.613323 -292.552508)
			(xy 370.636194 -292.596085) (xy 370.651778 -292.642766) (xy 370.659673 -292.691343) (xy 370.660168 -292.71595)
			(xy 370.98911 -292.71595) (xy 370.99307 -292.666896) (xy 371.004847 -292.619112) (xy 371.024138 -292.573836)
			(xy 371.050441 -292.53224) (xy 371.083076 -292.495403) (xy 371.121197 -292.464278) (xy 371.163818 -292.439671)
			(xy 371.209834 -292.422219) (xy 371.258053 -292.412375) (xy 371.307228 -292.410394) (xy 371.356083 -292.416326)
			(xy 371.403354 -292.430018) (xy 371.447816 -292.451116) (xy 371.488319 -292.479072) (xy 371.523812 -292.513164)
			(xy 371.553377 -292.552508) (xy 371.576248 -292.596085) (xy 371.591832 -292.642766) (xy 371.599727 -292.691343)
			(xy 371.600222 -292.71595) (xy 372.868964 -292.71595) (xy 372.872924 -292.666896) (xy 372.884701 -292.619112)
			(xy 372.903992 -292.573836) (xy 372.930295 -292.53224) (xy 372.96293 -292.495403) (xy 373.001051 -292.464278)
			(xy 373.043672 -292.439671) (xy 373.089688 -292.422219) (xy 373.137907 -292.412375) (xy 373.187082 -292.410394)
			(xy 373.235937 -292.416326) (xy 373.283208 -292.430018) (xy 373.32767 -292.451116) (xy 373.368173 -292.479072)
			(xy 373.403666 -292.513164) (xy 373.433231 -292.552508) (xy 373.456102 -292.596085) (xy 373.471686 -292.642766)
			(xy 373.479581 -292.691343) (xy 373.480076 -292.71595) (xy 373.479581 -292.740557) (xy 373.471686 -292.789134)
			(xy 373.456102 -292.835815) (xy 373.433231 -292.879392) (xy 373.403666 -292.918736) (xy 373.368173 -292.952828)
			(xy 373.32767 -292.980784) (xy 373.283208 -293.001882) (xy 373.235937 -293.015574) (xy 373.187082 -293.021506)
			(xy 373.137907 -293.019525) (xy 373.089688 -293.009681) (xy 373.043672 -292.992229) (xy 373.001051 -292.967622)
			(xy 372.96293 -292.936497) (xy 372.930295 -292.89966) (xy 372.903992 -292.858064) (xy 372.884701 -292.812788)
			(xy 372.872924 -292.765004) (xy 372.868964 -292.71595) (xy 371.600222 -292.71595) (xy 371.599727 -292.740557)
			(xy 371.591832 -292.789134) (xy 371.576248 -292.835815) (xy 371.553377 -292.879392) (xy 371.523812 -292.918736)
			(xy 371.488319 -292.952828) (xy 371.447816 -292.980784) (xy 371.403354 -293.001882) (xy 371.356083 -293.015574)
			(xy 371.307228 -293.021506) (xy 371.258053 -293.019525) (xy 371.209834 -293.009681) (xy 371.163818 -292.992229)
			(xy 371.121197 -292.967622) (xy 371.083076 -292.936497) (xy 371.050441 -292.89966) (xy 371.024138 -292.858064)
			(xy 371.004847 -292.812788) (xy 370.99307 -292.765004) (xy 370.98911 -292.71595) (xy 370.660168 -292.71595)
			(xy 370.659673 -292.740557) (xy 370.651778 -292.789134) (xy 370.636194 -292.835815) (xy 370.613323 -292.879392)
			(xy 370.583758 -292.918736) (xy 370.548265 -292.952828) (xy 370.507762 -292.980784) (xy 370.4633 -293.001882)
			(xy 370.416029 -293.015574) (xy 370.367174 -293.021506) (xy 370.317999 -293.019525) (xy 370.26978 -293.009681)
			(xy 370.223764 -292.992229) (xy 370.181143 -292.967622) (xy 370.143022 -292.936497) (xy 370.110387 -292.89966)
			(xy 370.084084 -292.858064) (xy 370.064793 -292.812788) (xy 370.053016 -292.765004) (xy 370.049056 -292.71595)
			(xy 368.78006 -292.71595) (xy 368.779565 -292.740557) (xy 368.77167 -292.789134) (xy 368.756086 -292.835815)
			(xy 368.733215 -292.879392) (xy 368.70365 -292.918736) (xy 368.668157 -292.952828) (xy 368.627654 -292.980784)
			(xy 368.583192 -293.001882) (xy 368.535921 -293.015574) (xy 368.487066 -293.021506) (xy 368.437891 -293.019525)
			(xy 368.389672 -293.009681) (xy 368.343656 -292.992229) (xy 368.301035 -292.967622) (xy 368.262914 -292.936497)
			(xy 368.230279 -292.89966) (xy 368.203976 -292.858064) (xy 368.184685 -292.812788) (xy 368.172908 -292.765004)
			(xy 368.168948 -292.71595) (xy 367.840006 -292.71595) (xy 367.839511 -292.740557) (xy 367.831616 -292.789134)
			(xy 367.816032 -292.835815) (xy 367.793161 -292.879392) (xy 367.763596 -292.918736) (xy 367.728103 -292.952828)
			(xy 367.6876 -292.980784) (xy 367.643138 -293.001882) (xy 367.595867 -293.015574) (xy 367.547012 -293.021506)
			(xy 367.497837 -293.019525) (xy 367.449618 -293.009681) (xy 367.403602 -292.992229) (xy 367.360981 -292.967622)
			(xy 367.32286 -292.936497) (xy 367.290225 -292.89966) (xy 367.263922 -292.858064) (xy 367.244631 -292.812788)
			(xy 367.232854 -292.765004) (xy 367.228894 -292.71595) (xy 365.960152 -292.71595) (xy 365.959657 -292.740557)
			(xy 365.951762 -292.789134) (xy 365.936178 -292.835815) (xy 365.913307 -292.879392) (xy 365.883742 -292.918736)
			(xy 365.848249 -292.952828) (xy 365.807746 -292.980784) (xy 365.763284 -293.001882) (xy 365.716013 -293.015574)
			(xy 365.667158 -293.021506) (xy 365.617983 -293.019525) (xy 365.569764 -293.009681) (xy 365.523748 -292.992229)
			(xy 365.481127 -292.967622) (xy 365.443006 -292.936497) (xy 365.410371 -292.89966) (xy 365.384068 -292.858064)
			(xy 365.364777 -292.812788) (xy 365.353 -292.765004) (xy 365.34904 -292.71595) (xy 365.020098 -292.71595)
			(xy 365.019603 -292.740557) (xy 365.011708 -292.789134) (xy 364.996124 -292.835815) (xy 364.973253 -292.879392)
			(xy 364.943688 -292.918736) (xy 364.908195 -292.952828) (xy 364.867692 -292.980784) (xy 364.82323 -293.001882)
			(xy 364.775959 -293.015574) (xy 364.727104 -293.021506) (xy 364.677929 -293.019525) (xy 364.62971 -293.009681)
			(xy 364.583694 -292.992229) (xy 364.541073 -292.967622) (xy 364.502952 -292.936497) (xy 364.470317 -292.89966)
			(xy 364.444014 -292.858064) (xy 364.424723 -292.812788) (xy 364.412946 -292.765004) (xy 364.408986 -292.71595)
			(xy 362.20019 -292.71595) (xy 362.199695 -292.740557) (xy 362.1918 -292.789134) (xy 362.176216 -292.835815)
			(xy 362.153345 -292.879392) (xy 362.12378 -292.918736) (xy 362.088287 -292.952828) (xy 362.047784 -292.980784)
			(xy 362.003322 -293.001882) (xy 361.956051 -293.015574) (xy 361.907196 -293.021506) (xy 361.858021 -293.019525)
			(xy 361.809802 -293.009681) (xy 361.763786 -292.992229) (xy 361.721165 -292.967622) (xy 361.683044 -292.936497)
			(xy 361.650409 -292.89966) (xy 361.624106 -292.858064) (xy 361.604815 -292.812788) (xy 361.593038 -292.765004)
			(xy 361.589078 -292.71595) (xy 358.446324 -292.71595) (xy 358.445829 -292.740557) (xy 358.437934 -292.789134)
			(xy 358.42235 -292.835815) (xy 358.399479 -292.879392) (xy 358.369914 -292.918736) (xy 358.334421 -292.952828)
			(xy 358.293918 -292.980784) (xy 358.249456 -293.001882) (xy 358.202185 -293.015574) (xy 358.15333 -293.021506)
			(xy 358.104155 -293.019525) (xy 358.055936 -293.009681) (xy 358.00992 -292.992229) (xy 357.967299 -292.967622)
			(xy 357.929178 -292.936497) (xy 357.896543 -292.89966) (xy 357.87024 -292.858064) (xy 357.850949 -292.812788)
			(xy 357.839172 -292.765004) (xy 357.835212 -292.71595) (xy 356.59187 -292.71595) (xy 356.591403 -292.741329)
			(xy 356.583634 -292.791489) (xy 356.568287 -292.839872) (xy 356.545722 -292.885339) (xy 356.51647 -292.926821)
			(xy 356.48122 -292.963342) (xy 356.461314 -292.979094) (xy 356.452289 -292.986737) (xy 356.441836 -293.007921)
			(xy 356.441248 -293.019734) (xy 356.441248 -293.525956) (xy 357.365312 -293.525956) (xy 357.369272 -293.476902)
			(xy 357.381049 -293.429118) (xy 357.40034 -293.383842) (xy 357.426643 -293.342246) (xy 357.459278 -293.305409)
			(xy 357.497399 -293.274284) (xy 357.54002 -293.249677) (xy 357.586036 -293.232225) (xy 357.634255 -293.222381)
			(xy 357.68343 -293.2204) (xy 357.732285 -293.226332) (xy 357.779556 -293.240024) (xy 357.824018 -293.261122)
			(xy 357.864521 -293.289078) (xy 357.900014 -293.32317) (xy 357.929579 -293.362514) (xy 357.95245 -293.406091)
			(xy 357.968034 -293.452772) (xy 357.975929 -293.501349) (xy 357.976424 -293.525956) (xy 358.305366 -293.525956)
			(xy 358.309326 -293.476902) (xy 358.321103 -293.429118) (xy 358.340394 -293.383842) (xy 358.366697 -293.342246)
			(xy 358.399332 -293.305409) (xy 358.437453 -293.274284) (xy 358.480074 -293.249677) (xy 358.52609 -293.232225)
			(xy 358.574309 -293.222381) (xy 358.623484 -293.2204) (xy 358.672339 -293.226332) (xy 358.71961 -293.240024)
			(xy 358.764072 -293.261122) (xy 358.804575 -293.289078) (xy 358.840068 -293.32317) (xy 358.869633 -293.362514)
			(xy 358.892504 -293.406091) (xy 358.908088 -293.452772) (xy 358.915983 -293.501349) (xy 358.916478 -293.525956)
			(xy 361.118924 -293.525956) (xy 361.122884 -293.476902) (xy 361.134661 -293.429118) (xy 361.153952 -293.383842)
			(xy 361.180255 -293.342246) (xy 361.21289 -293.305409) (xy 361.251011 -293.274284) (xy 361.293632 -293.249677)
			(xy 361.339648 -293.232225) (xy 361.387867 -293.222381) (xy 361.437042 -293.2204) (xy 361.485897 -293.226332)
			(xy 361.533168 -293.240024) (xy 361.57763 -293.261122) (xy 361.618133 -293.289078) (xy 361.653626 -293.32317)
			(xy 361.683191 -293.362514) (xy 361.706062 -293.406091) (xy 361.721646 -293.452772) (xy 361.729541 -293.501349)
			(xy 361.730036 -293.525956) (xy 362.058978 -293.525956) (xy 362.062938 -293.476902) (xy 362.074715 -293.429118)
			(xy 362.094006 -293.383842) (xy 362.120309 -293.342246) (xy 362.152944 -293.305409) (xy 362.191065 -293.274284)
			(xy 362.233686 -293.249677) (xy 362.279702 -293.232225) (xy 362.327921 -293.222381) (xy 362.377096 -293.2204)
			(xy 362.425951 -293.226332) (xy 362.473222 -293.240024) (xy 362.517684 -293.261122) (xy 362.558187 -293.289078)
			(xy 362.59368 -293.32317) (xy 362.623245 -293.362514) (xy 362.646116 -293.406091) (xy 362.6617 -293.452772)
			(xy 362.669595 -293.501349) (xy 362.67009 -293.525956) (xy 362.998778 -293.525956) (xy 363.002738 -293.476902)
			(xy 363.014515 -293.429118) (xy 363.033806 -293.383842) (xy 363.060109 -293.342246) (xy 363.092744 -293.305409)
			(xy 363.130865 -293.274284) (xy 363.173486 -293.249677) (xy 363.219502 -293.232225) (xy 363.267721 -293.222381)
			(xy 363.316896 -293.2204) (xy 363.365751 -293.226332) (xy 363.413022 -293.240024) (xy 363.457484 -293.261122)
			(xy 363.497987 -293.289078) (xy 363.53348 -293.32317) (xy 363.563045 -293.362514) (xy 363.585916 -293.406091)
			(xy 363.6015 -293.452772) (xy 363.609395 -293.501349) (xy 363.60989 -293.525956) (xy 363.939086 -293.525956)
			(xy 363.943046 -293.476902) (xy 363.954823 -293.429118) (xy 363.974114 -293.383842) (xy 364.000417 -293.342246)
			(xy 364.033052 -293.305409) (xy 364.071173 -293.274284) (xy 364.113794 -293.249677) (xy 364.15981 -293.232225)
			(xy 364.208029 -293.222381) (xy 364.257204 -293.2204) (xy 364.306059 -293.226332) (xy 364.35333 -293.240024)
			(xy 364.397792 -293.261122) (xy 364.438295 -293.289078) (xy 364.473788 -293.32317) (xy 364.503353 -293.362514)
			(xy 364.526224 -293.406091) (xy 364.541808 -293.452772) (xy 364.549703 -293.501349) (xy 364.550198 -293.525956)
			(xy 364.878886 -293.525956) (xy 364.882846 -293.476902) (xy 364.894623 -293.429118) (xy 364.913914 -293.383842)
			(xy 364.940217 -293.342246) (xy 364.972852 -293.305409) (xy 365.010973 -293.274284) (xy 365.053594 -293.249677)
			(xy 365.09961 -293.232225) (xy 365.147829 -293.222381) (xy 365.197004 -293.2204) (xy 365.245859 -293.226332)
			(xy 365.29313 -293.240024) (xy 365.337592 -293.261122) (xy 365.378095 -293.289078) (xy 365.413588 -293.32317)
			(xy 365.443153 -293.362514) (xy 365.466024 -293.406091) (xy 365.481608 -293.452772) (xy 365.489503 -293.501349)
			(xy 365.489998 -293.525956) (xy 365.81894 -293.525956) (xy 365.8229 -293.476902) (xy 365.834677 -293.429118)
			(xy 365.853968 -293.383842) (xy 365.880271 -293.342246) (xy 365.912906 -293.305409) (xy 365.951027 -293.274284)
			(xy 365.993648 -293.249677) (xy 366.039664 -293.232225) (xy 366.087883 -293.222381) (xy 366.137058 -293.2204)
			(xy 366.185913 -293.226332) (xy 366.233184 -293.240024) (xy 366.277646 -293.261122) (xy 366.318149 -293.289078)
			(xy 366.353642 -293.32317) (xy 366.383207 -293.362514) (xy 366.406078 -293.406091) (xy 366.421662 -293.452772)
			(xy 366.429557 -293.501349) (xy 366.430052 -293.525956) (xy 366.758994 -293.525956) (xy 366.762954 -293.476902)
			(xy 366.774731 -293.429118) (xy 366.794022 -293.383842) (xy 366.820325 -293.342246) (xy 366.85296 -293.305409)
			(xy 366.891081 -293.274284) (xy 366.933702 -293.249677) (xy 366.979718 -293.232225) (xy 367.027937 -293.222381)
			(xy 367.077112 -293.2204) (xy 367.125967 -293.226332) (xy 367.173238 -293.240024) (xy 367.2177 -293.261122)
			(xy 367.258203 -293.289078) (xy 367.293696 -293.32317) (xy 367.323261 -293.362514) (xy 367.346132 -293.406091)
			(xy 367.361716 -293.452772) (xy 367.369611 -293.501349) (xy 367.370106 -293.525956) (xy 367.699048 -293.525956)
			(xy 367.703008 -293.476902) (xy 367.714785 -293.429118) (xy 367.734076 -293.383842) (xy 367.760379 -293.342246)
			(xy 367.793014 -293.305409) (xy 367.831135 -293.274284) (xy 367.873756 -293.249677) (xy 367.919772 -293.232225)
			(xy 367.967991 -293.222381) (xy 368.017166 -293.2204) (xy 368.066021 -293.226332) (xy 368.113292 -293.240024)
			(xy 368.157754 -293.261122) (xy 368.198257 -293.289078) (xy 368.23375 -293.32317) (xy 368.263315 -293.362514)
			(xy 368.286186 -293.406091) (xy 368.30177 -293.452772) (xy 368.309665 -293.501349) (xy 368.31016 -293.525956)
			(xy 369.578902 -293.525956) (xy 369.582862 -293.476902) (xy 369.594639 -293.429118) (xy 369.61393 -293.383842)
			(xy 369.640233 -293.342246) (xy 369.672868 -293.305409) (xy 369.710989 -293.274284) (xy 369.75361 -293.249677)
			(xy 369.799626 -293.232225) (xy 369.847845 -293.222381) (xy 369.89702 -293.2204) (xy 369.945875 -293.226332)
			(xy 369.993146 -293.240024) (xy 370.037608 -293.261122) (xy 370.078111 -293.289078) (xy 370.113604 -293.32317)
			(xy 370.143169 -293.362514) (xy 370.16604 -293.406091) (xy 370.181624 -293.452772) (xy 370.189519 -293.501349)
			(xy 370.190014 -293.525956) (xy 370.518956 -293.525956) (xy 370.522916 -293.476902) (xy 370.534693 -293.429118)
			(xy 370.553984 -293.383842) (xy 370.580287 -293.342246) (xy 370.612922 -293.305409) (xy 370.651043 -293.274284)
			(xy 370.693664 -293.249677) (xy 370.73968 -293.232225) (xy 370.787899 -293.222381) (xy 370.837074 -293.2204)
			(xy 370.885929 -293.226332) (xy 370.9332 -293.240024) (xy 370.977662 -293.261122) (xy 371.018165 -293.289078)
			(xy 371.053658 -293.32317) (xy 371.083223 -293.362514) (xy 371.106094 -293.406091) (xy 371.121678 -293.452772)
			(xy 371.129573 -293.501349) (xy 371.130068 -293.525956) (xy 371.45901 -293.525956) (xy 371.46297 -293.476902)
			(xy 371.474747 -293.429118) (xy 371.494038 -293.383842) (xy 371.520341 -293.342246) (xy 371.552976 -293.305409)
			(xy 371.591097 -293.274284) (xy 371.633718 -293.249677) (xy 371.679734 -293.232225) (xy 371.727953 -293.222381)
			(xy 371.777128 -293.2204) (xy 371.825983 -293.226332) (xy 371.873254 -293.240024) (xy 371.917716 -293.261122)
			(xy 371.958219 -293.289078) (xy 371.993712 -293.32317) (xy 372.023277 -293.362514) (xy 372.046148 -293.406091)
			(xy 372.061732 -293.452772) (xy 372.069627 -293.501349) (xy 372.070122 -293.525956) (xy 372.399064 -293.525956)
			(xy 372.403024 -293.476902) (xy 372.414801 -293.429118) (xy 372.434092 -293.383842) (xy 372.460395 -293.342246)
			(xy 372.49303 -293.305409) (xy 372.531151 -293.274284) (xy 372.573772 -293.249677) (xy 372.619788 -293.232225)
			(xy 372.668007 -293.222381) (xy 372.717182 -293.2204) (xy 372.766037 -293.226332) (xy 372.813308 -293.240024)
			(xy 372.85777 -293.261122) (xy 372.898273 -293.289078) (xy 372.933766 -293.32317) (xy 372.963331 -293.362514)
			(xy 372.986202 -293.406091) (xy 373.001786 -293.452772) (xy 373.009681 -293.501349) (xy 373.010176 -293.525956)
			(xy 373.339118 -293.525956) (xy 373.343078 -293.476902) (xy 373.354855 -293.429118) (xy 373.374146 -293.383842)
			(xy 373.400449 -293.342246) (xy 373.433084 -293.305409) (xy 373.471205 -293.274284) (xy 373.513826 -293.249677)
			(xy 373.559842 -293.232225) (xy 373.608061 -293.222381) (xy 373.657236 -293.2204) (xy 373.706091 -293.226332)
			(xy 373.753362 -293.240024) (xy 373.797824 -293.261122) (xy 373.838327 -293.289078) (xy 373.87382 -293.32317)
			(xy 373.903385 -293.362514) (xy 373.926256 -293.406091) (xy 373.94184 -293.452772) (xy 373.949735 -293.501349)
			(xy 373.95023 -293.525956) (xy 373.949735 -293.550563) (xy 373.94184 -293.59914) (xy 373.926256 -293.645821)
			(xy 373.903385 -293.689398) (xy 373.87382 -293.728742) (xy 373.838327 -293.762834) (xy 373.797824 -293.79079)
			(xy 373.753362 -293.811888) (xy 373.706091 -293.82558) (xy 373.657236 -293.831512) (xy 373.608061 -293.829531)
			(xy 373.559842 -293.819687) (xy 373.513826 -293.802235) (xy 373.471205 -293.777628) (xy 373.433084 -293.746503)
			(xy 373.400449 -293.709666) (xy 373.374146 -293.66807) (xy 373.354855 -293.622794) (xy 373.343078 -293.57501)
			(xy 373.339118 -293.525956) (xy 373.010176 -293.525956) (xy 373.009681 -293.550563) (xy 373.001786 -293.59914)
			(xy 372.986202 -293.645821) (xy 372.963331 -293.689398) (xy 372.933766 -293.728742) (xy 372.898273 -293.762834)
			(xy 372.85777 -293.79079) (xy 372.813308 -293.811888) (xy 372.766037 -293.82558) (xy 372.717182 -293.831512)
			(xy 372.668007 -293.829531) (xy 372.619788 -293.819687) (xy 372.573772 -293.802235) (xy 372.531151 -293.777628)
			(xy 372.49303 -293.746503) (xy 372.460395 -293.709666) (xy 372.434092 -293.66807) (xy 372.414801 -293.622794)
			(xy 372.403024 -293.57501) (xy 372.399064 -293.525956) (xy 372.070122 -293.525956) (xy 372.069627 -293.550563)
			(xy 372.061732 -293.59914) (xy 372.046148 -293.645821) (xy 372.023277 -293.689398) (xy 371.993712 -293.728742)
			(xy 371.958219 -293.762834) (xy 371.917716 -293.79079) (xy 371.873254 -293.811888) (xy 371.825983 -293.82558)
			(xy 371.777128 -293.831512) (xy 371.727953 -293.829531) (xy 371.679734 -293.819687) (xy 371.633718 -293.802235)
			(xy 371.591097 -293.777628) (xy 371.552976 -293.746503) (xy 371.520341 -293.709666) (xy 371.494038 -293.66807)
			(xy 371.474747 -293.622794) (xy 371.46297 -293.57501) (xy 371.45901 -293.525956) (xy 371.130068 -293.525956)
			(xy 371.129573 -293.550563) (xy 371.121678 -293.59914) (xy 371.106094 -293.645821) (xy 371.083223 -293.689398)
			(xy 371.053658 -293.728742) (xy 371.018165 -293.762834) (xy 370.977662 -293.79079) (xy 370.9332 -293.811888)
			(xy 370.885929 -293.82558) (xy 370.837074 -293.831512) (xy 370.787899 -293.829531) (xy 370.73968 -293.819687)
			(xy 370.693664 -293.802235) (xy 370.651043 -293.777628) (xy 370.612922 -293.746503) (xy 370.580287 -293.709666)
			(xy 370.553984 -293.66807) (xy 370.534693 -293.622794) (xy 370.522916 -293.57501) (xy 370.518956 -293.525956)
			(xy 370.190014 -293.525956) (xy 370.189519 -293.550563) (xy 370.181624 -293.59914) (xy 370.16604 -293.645821)
			(xy 370.143169 -293.689398) (xy 370.113604 -293.728742) (xy 370.078111 -293.762834) (xy 370.037608 -293.79079)
			(xy 369.993146 -293.811888) (xy 369.945875 -293.82558) (xy 369.89702 -293.831512) (xy 369.847845 -293.829531)
			(xy 369.799626 -293.819687) (xy 369.75361 -293.802235) (xy 369.710989 -293.777628) (xy 369.672868 -293.746503)
			(xy 369.640233 -293.709666) (xy 369.61393 -293.66807) (xy 369.594639 -293.622794) (xy 369.582862 -293.57501)
			(xy 369.578902 -293.525956) (xy 368.31016 -293.525956) (xy 368.309665 -293.550563) (xy 368.30177 -293.59914)
			(xy 368.286186 -293.645821) (xy 368.263315 -293.689398) (xy 368.23375 -293.728742) (xy 368.198257 -293.762834)
			(xy 368.157754 -293.79079) (xy 368.113292 -293.811888) (xy 368.066021 -293.82558) (xy 368.017166 -293.831512)
			(xy 367.967991 -293.829531) (xy 367.919772 -293.819687) (xy 367.873756 -293.802235) (xy 367.831135 -293.777628)
			(xy 367.793014 -293.746503) (xy 367.760379 -293.709666) (xy 367.734076 -293.66807) (xy 367.714785 -293.622794)
			(xy 367.703008 -293.57501) (xy 367.699048 -293.525956) (xy 367.370106 -293.525956) (xy 367.369611 -293.550563)
			(xy 367.361716 -293.59914) (xy 367.346132 -293.645821) (xy 367.323261 -293.689398) (xy 367.293696 -293.728742)
			(xy 367.258203 -293.762834) (xy 367.2177 -293.79079) (xy 367.173238 -293.811888) (xy 367.125967 -293.82558)
			(xy 367.077112 -293.831512) (xy 367.027937 -293.829531) (xy 366.979718 -293.819687) (xy 366.933702 -293.802235)
			(xy 366.891081 -293.777628) (xy 366.85296 -293.746503) (xy 366.820325 -293.709666) (xy 366.794022 -293.66807)
			(xy 366.774731 -293.622794) (xy 366.762954 -293.57501) (xy 366.758994 -293.525956) (xy 366.430052 -293.525956)
			(xy 366.429557 -293.550563) (xy 366.421662 -293.59914) (xy 366.406078 -293.645821) (xy 366.383207 -293.689398)
			(xy 366.353642 -293.728742) (xy 366.318149 -293.762834) (xy 366.277646 -293.79079) (xy 366.233184 -293.811888)
			(xy 366.185913 -293.82558) (xy 366.137058 -293.831512) (xy 366.087883 -293.829531) (xy 366.039664 -293.819687)
			(xy 365.993648 -293.802235) (xy 365.951027 -293.777628) (xy 365.912906 -293.746503) (xy 365.880271 -293.709666)
			(xy 365.853968 -293.66807) (xy 365.834677 -293.622794) (xy 365.8229 -293.57501) (xy 365.81894 -293.525956)
			(xy 365.489998 -293.525956) (xy 365.489503 -293.550563) (xy 365.481608 -293.59914) (xy 365.466024 -293.645821)
			(xy 365.443153 -293.689398) (xy 365.413588 -293.728742) (xy 365.378095 -293.762834) (xy 365.337592 -293.79079)
			(xy 365.29313 -293.811888) (xy 365.245859 -293.82558) (xy 365.197004 -293.831512) (xy 365.147829 -293.829531)
			(xy 365.09961 -293.819687) (xy 365.053594 -293.802235) (xy 365.010973 -293.777628) (xy 364.972852 -293.746503)
			(xy 364.940217 -293.709666) (xy 364.913914 -293.66807) (xy 364.894623 -293.622794) (xy 364.882846 -293.57501)
			(xy 364.878886 -293.525956) (xy 364.550198 -293.525956) (xy 364.549703 -293.550563) (xy 364.541808 -293.59914)
			(xy 364.526224 -293.645821) (xy 364.503353 -293.689398) (xy 364.473788 -293.728742) (xy 364.438295 -293.762834)
			(xy 364.397792 -293.79079) (xy 364.35333 -293.811888) (xy 364.306059 -293.82558) (xy 364.257204 -293.831512)
			(xy 364.208029 -293.829531) (xy 364.15981 -293.819687) (xy 364.113794 -293.802235) (xy 364.071173 -293.777628)
			(xy 364.033052 -293.746503) (xy 364.000417 -293.709666) (xy 363.974114 -293.66807) (xy 363.954823 -293.622794)
			(xy 363.943046 -293.57501) (xy 363.939086 -293.525956) (xy 363.60989 -293.525956) (xy 363.609395 -293.550563)
			(xy 363.6015 -293.59914) (xy 363.585916 -293.645821) (xy 363.563045 -293.689398) (xy 363.53348 -293.728742)
			(xy 363.497987 -293.762834) (xy 363.457484 -293.79079) (xy 363.413022 -293.811888) (xy 363.365751 -293.82558)
			(xy 363.316896 -293.831512) (xy 363.267721 -293.829531) (xy 363.219502 -293.819687) (xy 363.173486 -293.802235)
			(xy 363.130865 -293.777628) (xy 363.092744 -293.746503) (xy 363.060109 -293.709666) (xy 363.033806 -293.66807)
			(xy 363.014515 -293.622794) (xy 363.002738 -293.57501) (xy 362.998778 -293.525956) (xy 362.67009 -293.525956)
			(xy 362.669595 -293.550563) (xy 362.6617 -293.59914) (xy 362.646116 -293.645821) (xy 362.623245 -293.689398)
			(xy 362.59368 -293.728742) (xy 362.558187 -293.762834) (xy 362.517684 -293.79079) (xy 362.473222 -293.811888)
			(xy 362.425951 -293.82558) (xy 362.377096 -293.831512) (xy 362.327921 -293.829531) (xy 362.279702 -293.819687)
			(xy 362.233686 -293.802235) (xy 362.191065 -293.777628) (xy 362.152944 -293.746503) (xy 362.120309 -293.709666)
			(xy 362.094006 -293.66807) (xy 362.074715 -293.622794) (xy 362.062938 -293.57501) (xy 362.058978 -293.525956)
			(xy 361.730036 -293.525956) (xy 361.729541 -293.550563) (xy 361.721646 -293.59914) (xy 361.706062 -293.645821)
			(xy 361.683191 -293.689398) (xy 361.653626 -293.728742) (xy 361.618133 -293.762834) (xy 361.57763 -293.79079)
			(xy 361.533168 -293.811888) (xy 361.485897 -293.82558) (xy 361.437042 -293.831512) (xy 361.387867 -293.829531)
			(xy 361.339648 -293.819687) (xy 361.293632 -293.802235) (xy 361.251011 -293.777628) (xy 361.21289 -293.746503)
			(xy 361.180255 -293.709666) (xy 361.153952 -293.66807) (xy 361.134661 -293.622794) (xy 361.122884 -293.57501)
			(xy 361.118924 -293.525956) (xy 358.916478 -293.525956) (xy 358.915983 -293.550563) (xy 358.908088 -293.59914)
			(xy 358.892504 -293.645821) (xy 358.869633 -293.689398) (xy 358.840068 -293.728742) (xy 358.804575 -293.762834)
			(xy 358.764072 -293.79079) (xy 358.71961 -293.811888) (xy 358.672339 -293.82558) (xy 358.623484 -293.831512)
			(xy 358.574309 -293.829531) (xy 358.52609 -293.819687) (xy 358.480074 -293.802235) (xy 358.437453 -293.777628)
			(xy 358.399332 -293.746503) (xy 358.366697 -293.709666) (xy 358.340394 -293.66807) (xy 358.321103 -293.622794)
			(xy 358.309326 -293.57501) (xy 358.305366 -293.525956) (xy 357.976424 -293.525956) (xy 357.975929 -293.550563)
			(xy 357.968034 -293.59914) (xy 357.95245 -293.645821) (xy 357.929579 -293.689398) (xy 357.900014 -293.728742)
			(xy 357.864521 -293.762834) (xy 357.824018 -293.79079) (xy 357.779556 -293.811888) (xy 357.732285 -293.82558)
			(xy 357.68343 -293.831512) (xy 357.634255 -293.829531) (xy 357.586036 -293.819687) (xy 357.54002 -293.802235)
			(xy 357.497399 -293.777628) (xy 357.459278 -293.746503) (xy 357.426643 -293.709666) (xy 357.40034 -293.66807)
			(xy 357.381049 -293.622794) (xy 357.369272 -293.57501) (xy 357.365312 -293.525956) (xy 356.441248 -293.525956)
			(xy 356.441248 -294.335962) (xy 356.895412 -294.335962) (xy 356.899372 -294.286908) (xy 356.911149 -294.239124)
			(xy 356.93044 -294.193848) (xy 356.956743 -294.152252) (xy 356.989378 -294.115415) (xy 357.027499 -294.08429)
			(xy 357.07012 -294.059683) (xy 357.116136 -294.042231) (xy 357.164355 -294.032387) (xy 357.21353 -294.030406)
			(xy 357.262385 -294.036338) (xy 357.309656 -294.05003) (xy 357.354118 -294.071128) (xy 357.394621 -294.099084)
			(xy 357.430114 -294.133176) (xy 357.459679 -294.17252) (xy 357.48255 -294.216097) (xy 357.498134 -294.262778)
			(xy 357.506029 -294.311355) (xy 357.506524 -294.335962) (xy 357.835212 -294.335962) (xy 357.839172 -294.286908)
			(xy 357.850949 -294.239124) (xy 357.87024 -294.193848) (xy 357.896543 -294.152252) (xy 357.929178 -294.115415)
			(xy 357.967299 -294.08429) (xy 358.00992 -294.059683) (xy 358.055936 -294.042231) (xy 358.104155 -294.032387)
			(xy 358.15333 -294.030406) (xy 358.202185 -294.036338) (xy 358.249456 -294.05003) (xy 358.293918 -294.071128)
			(xy 358.334421 -294.099084) (xy 358.369914 -294.133176) (xy 358.399479 -294.17252) (xy 358.42235 -294.216097)
			(xy 358.437934 -294.262778) (xy 358.445829 -294.311355) (xy 358.446324 -294.335962) (xy 361.589078 -294.335962)
			(xy 361.593038 -294.286908) (xy 361.604815 -294.239124) (xy 361.624106 -294.193848) (xy 361.650409 -294.152252)
			(xy 361.683044 -294.115415) (xy 361.721165 -294.08429) (xy 361.763786 -294.059683) (xy 361.809802 -294.042231)
			(xy 361.858021 -294.032387) (xy 361.907196 -294.030406) (xy 361.956051 -294.036338) (xy 362.003322 -294.05003)
			(xy 362.047784 -294.071128) (xy 362.088287 -294.099084) (xy 362.12378 -294.133176) (xy 362.153345 -294.17252)
			(xy 362.176216 -294.216097) (xy 362.1918 -294.262778) (xy 362.199695 -294.311355) (xy 362.20019 -294.335962)
			(xy 362.529132 -294.335962) (xy 362.533092 -294.286908) (xy 362.544869 -294.239124) (xy 362.56416 -294.193848)
			(xy 362.590463 -294.152252) (xy 362.623098 -294.115415) (xy 362.661219 -294.08429) (xy 362.70384 -294.059683)
			(xy 362.749856 -294.042231) (xy 362.798075 -294.032387) (xy 362.84725 -294.030406) (xy 362.896105 -294.036338)
			(xy 362.943376 -294.05003) (xy 362.987838 -294.071128) (xy 363.028341 -294.099084) (xy 363.063834 -294.133176)
			(xy 363.093399 -294.17252) (xy 363.11627 -294.216097) (xy 363.131854 -294.262778) (xy 363.139749 -294.311355)
			(xy 363.140244 -294.335962) (xy 363.468932 -294.335962) (xy 363.472892 -294.286908) (xy 363.484669 -294.239124)
			(xy 363.50396 -294.193848) (xy 363.530263 -294.152252) (xy 363.562898 -294.115415) (xy 363.601019 -294.08429)
			(xy 363.64364 -294.059683) (xy 363.689656 -294.042231) (xy 363.737875 -294.032387) (xy 363.78705 -294.030406)
			(xy 363.835905 -294.036338) (xy 363.883176 -294.05003) (xy 363.927638 -294.071128) (xy 363.968141 -294.099084)
			(xy 364.003634 -294.133176) (xy 364.033199 -294.17252) (xy 364.05607 -294.216097) (xy 364.071654 -294.262778)
			(xy 364.079549 -294.311355) (xy 364.080044 -294.335962) (xy 364.408986 -294.335962) (xy 364.412946 -294.286908)
			(xy 364.424723 -294.239124) (xy 364.444014 -294.193848) (xy 364.470317 -294.152252) (xy 364.502952 -294.115415)
			(xy 364.541073 -294.08429) (xy 364.583694 -294.059683) (xy 364.62971 -294.042231) (xy 364.677929 -294.032387)
			(xy 364.727104 -294.030406) (xy 364.775959 -294.036338) (xy 364.82323 -294.05003) (xy 364.867692 -294.071128)
			(xy 364.908195 -294.099084) (xy 364.943688 -294.133176) (xy 364.973253 -294.17252) (xy 364.996124 -294.216097)
			(xy 365.011708 -294.262778) (xy 365.019603 -294.311355) (xy 365.020098 -294.335962) (xy 365.34904 -294.335962)
			(xy 365.353 -294.286908) (xy 365.364777 -294.239124) (xy 365.384068 -294.193848) (xy 365.410371 -294.152252)
			(xy 365.443006 -294.115415) (xy 365.481127 -294.08429) (xy 365.523748 -294.059683) (xy 365.569764 -294.042231)
			(xy 365.617983 -294.032387) (xy 365.667158 -294.030406) (xy 365.716013 -294.036338) (xy 365.763284 -294.05003)
			(xy 365.807746 -294.071128) (xy 365.848249 -294.099084) (xy 365.883742 -294.133176) (xy 365.913307 -294.17252)
			(xy 365.936178 -294.216097) (xy 365.951762 -294.262778) (xy 365.959657 -294.311355) (xy 365.960152 -294.335962)
			(xy 366.289094 -294.335962) (xy 366.293054 -294.286908) (xy 366.304831 -294.239124) (xy 366.324122 -294.193848)
			(xy 366.350425 -294.152252) (xy 366.38306 -294.115415) (xy 366.421181 -294.08429) (xy 366.463802 -294.059683)
			(xy 366.509818 -294.042231) (xy 366.558037 -294.032387) (xy 366.607212 -294.030406) (xy 366.656067 -294.036338)
			(xy 366.703338 -294.05003) (xy 366.7478 -294.071128) (xy 366.788303 -294.099084) (xy 366.823796 -294.133176)
			(xy 366.853361 -294.17252) (xy 366.876232 -294.216097) (xy 366.891816 -294.262778) (xy 366.899711 -294.311355)
			(xy 366.900206 -294.335962) (xy 367.228894 -294.335962) (xy 367.232854 -294.286908) (xy 367.244631 -294.239124)
			(xy 367.263922 -294.193848) (xy 367.290225 -294.152252) (xy 367.32286 -294.115415) (xy 367.360981 -294.08429)
			(xy 367.403602 -294.059683) (xy 367.449618 -294.042231) (xy 367.497837 -294.032387) (xy 367.547012 -294.030406)
			(xy 367.595867 -294.036338) (xy 367.643138 -294.05003) (xy 367.6876 -294.071128) (xy 367.728103 -294.099084)
			(xy 367.763596 -294.133176) (xy 367.793161 -294.17252) (xy 367.816032 -294.216097) (xy 367.831616 -294.262778)
			(xy 367.839511 -294.311355) (xy 367.840006 -294.335962) (xy 369.109002 -294.335962) (xy 369.112962 -294.286908)
			(xy 369.124739 -294.239124) (xy 369.14403 -294.193848) (xy 369.170333 -294.152252) (xy 369.202968 -294.115415)
			(xy 369.241089 -294.08429) (xy 369.28371 -294.059683) (xy 369.329726 -294.042231) (xy 369.377945 -294.032387)
			(xy 369.42712 -294.030406) (xy 369.475975 -294.036338) (xy 369.523246 -294.05003) (xy 369.567708 -294.071128)
			(xy 369.608211 -294.099084) (xy 369.643704 -294.133176) (xy 369.673269 -294.17252) (xy 369.69614 -294.216097)
			(xy 369.711724 -294.262778) (xy 369.719619 -294.311355) (xy 369.720114 -294.335962) (xy 370.049056 -294.335962)
			(xy 370.053016 -294.286908) (xy 370.064793 -294.239124) (xy 370.084084 -294.193848) (xy 370.110387 -294.152252)
			(xy 370.143022 -294.115415) (xy 370.181143 -294.08429) (xy 370.223764 -294.059683) (xy 370.26978 -294.042231)
			(xy 370.317999 -294.032387) (xy 370.367174 -294.030406) (xy 370.416029 -294.036338) (xy 370.4633 -294.05003)
			(xy 370.507762 -294.071128) (xy 370.548265 -294.099084) (xy 370.583758 -294.133176) (xy 370.613323 -294.17252)
			(xy 370.636194 -294.216097) (xy 370.651778 -294.262778) (xy 370.659673 -294.311355) (xy 370.660168 -294.335962)
			(xy 370.98911 -294.335962) (xy 370.99307 -294.286908) (xy 371.004847 -294.239124) (xy 371.024138 -294.193848)
			(xy 371.050441 -294.152252) (xy 371.083076 -294.115415) (xy 371.121197 -294.08429) (xy 371.163818 -294.059683)
			(xy 371.209834 -294.042231) (xy 371.258053 -294.032387) (xy 371.307228 -294.030406) (xy 371.356083 -294.036338)
			(xy 371.403354 -294.05003) (xy 371.447816 -294.071128) (xy 371.488319 -294.099084) (xy 371.523812 -294.133176)
			(xy 371.553377 -294.17252) (xy 371.576248 -294.216097) (xy 371.591832 -294.262778) (xy 371.599727 -294.311355)
			(xy 371.600222 -294.335962) (xy 371.92891 -294.335962) (xy 371.93287 -294.286908) (xy 371.944647 -294.239124)
			(xy 371.963938 -294.193848) (xy 371.990241 -294.152252) (xy 372.022876 -294.115415) (xy 372.060997 -294.08429)
			(xy 372.103618 -294.059683) (xy 372.149634 -294.042231) (xy 372.197853 -294.032387) (xy 372.247028 -294.030406)
			(xy 372.295883 -294.036338) (xy 372.343154 -294.05003) (xy 372.387616 -294.071128) (xy 372.428119 -294.099084)
			(xy 372.463612 -294.133176) (xy 372.493177 -294.17252) (xy 372.516048 -294.216097) (xy 372.531632 -294.262778)
			(xy 372.539527 -294.311355) (xy 372.540022 -294.335962) (xy 372.868964 -294.335962) (xy 372.872924 -294.286908)
			(xy 372.884701 -294.239124) (xy 372.903992 -294.193848) (xy 372.930295 -294.152252) (xy 372.96293 -294.115415)
			(xy 373.001051 -294.08429) (xy 373.043672 -294.059683) (xy 373.089688 -294.042231) (xy 373.137907 -294.032387)
			(xy 373.187082 -294.030406) (xy 373.235937 -294.036338) (xy 373.283208 -294.05003) (xy 373.32767 -294.071128)
			(xy 373.368173 -294.099084) (xy 373.403666 -294.133176) (xy 373.433231 -294.17252) (xy 373.456102 -294.216097)
			(xy 373.471686 -294.262778) (xy 373.479581 -294.311355) (xy 373.480076 -294.335962) (xy 373.479581 -294.360569)
			(xy 373.471686 -294.409146) (xy 373.456102 -294.455827) (xy 373.433231 -294.499404) (xy 373.403666 -294.538748)
			(xy 373.368173 -294.57284) (xy 373.32767 -294.600796) (xy 373.283208 -294.621894) (xy 373.235937 -294.635586)
			(xy 373.187082 -294.641518) (xy 373.137907 -294.639537) (xy 373.089688 -294.629693) (xy 373.043672 -294.612241)
			(xy 373.001051 -294.587634) (xy 372.96293 -294.556509) (xy 372.930295 -294.519672) (xy 372.903992 -294.478076)
			(xy 372.884701 -294.4328) (xy 372.872924 -294.385016) (xy 372.868964 -294.335962) (xy 372.540022 -294.335962)
			(xy 372.539527 -294.360569) (xy 372.531632 -294.409146) (xy 372.516048 -294.455827) (xy 372.493177 -294.499404)
			(xy 372.463612 -294.538748) (xy 372.428119 -294.57284) (xy 372.387616 -294.600796) (xy 372.343154 -294.621894)
			(xy 372.295883 -294.635586) (xy 372.247028 -294.641518) (xy 372.197853 -294.639537) (xy 372.149634 -294.629693)
			(xy 372.103618 -294.612241) (xy 372.060997 -294.587634) (xy 372.022876 -294.556509) (xy 371.990241 -294.519672)
			(xy 371.963938 -294.478076) (xy 371.944647 -294.4328) (xy 371.93287 -294.385016) (xy 371.92891 -294.335962)
			(xy 371.600222 -294.335962) (xy 371.599727 -294.360569) (xy 371.591832 -294.409146) (xy 371.576248 -294.455827)
			(xy 371.553377 -294.499404) (xy 371.523812 -294.538748) (xy 371.488319 -294.57284) (xy 371.447816 -294.600796)
			(xy 371.403354 -294.621894) (xy 371.356083 -294.635586) (xy 371.307228 -294.641518) (xy 371.258053 -294.639537)
			(xy 371.209834 -294.629693) (xy 371.163818 -294.612241) (xy 371.121197 -294.587634) (xy 371.083076 -294.556509)
			(xy 371.050441 -294.519672) (xy 371.024138 -294.478076) (xy 371.004847 -294.4328) (xy 370.99307 -294.385016)
			(xy 370.98911 -294.335962) (xy 370.660168 -294.335962) (xy 370.659673 -294.360569) (xy 370.651778 -294.409146)
			(xy 370.636194 -294.455827) (xy 370.613323 -294.499404) (xy 370.583758 -294.538748) (xy 370.548265 -294.57284)
			(xy 370.507762 -294.600796) (xy 370.4633 -294.621894) (xy 370.416029 -294.635586) (xy 370.367174 -294.641518)
			(xy 370.317999 -294.639537) (xy 370.26978 -294.629693) (xy 370.223764 -294.612241) (xy 370.181143 -294.587634)
			(xy 370.143022 -294.556509) (xy 370.110387 -294.519672) (xy 370.084084 -294.478076) (xy 370.064793 -294.4328)
			(xy 370.053016 -294.385016) (xy 370.049056 -294.335962) (xy 369.720114 -294.335962) (xy 369.719619 -294.360569)
			(xy 369.711724 -294.409146) (xy 369.69614 -294.455827) (xy 369.673269 -294.499404) (xy 369.643704 -294.538748)
			(xy 369.608211 -294.57284) (xy 369.567708 -294.600796) (xy 369.523246 -294.621894) (xy 369.475975 -294.635586)
			(xy 369.42712 -294.641518) (xy 369.377945 -294.639537) (xy 369.329726 -294.629693) (xy 369.28371 -294.612241)
			(xy 369.241089 -294.587634) (xy 369.202968 -294.556509) (xy 369.170333 -294.519672) (xy 369.14403 -294.478076)
			(xy 369.124739 -294.4328) (xy 369.112962 -294.385016) (xy 369.109002 -294.335962) (xy 367.840006 -294.335962)
			(xy 367.839511 -294.360569) (xy 367.831616 -294.409146) (xy 367.816032 -294.455827) (xy 367.793161 -294.499404)
			(xy 367.763596 -294.538748) (xy 367.728103 -294.57284) (xy 367.6876 -294.600796) (xy 367.643138 -294.621894)
			(xy 367.595867 -294.635586) (xy 367.547012 -294.641518) (xy 367.497837 -294.639537) (xy 367.449618 -294.629693)
			(xy 367.403602 -294.612241) (xy 367.360981 -294.587634) (xy 367.32286 -294.556509) (xy 367.290225 -294.519672)
			(xy 367.263922 -294.478076) (xy 367.244631 -294.4328) (xy 367.232854 -294.385016) (xy 367.228894 -294.335962)
			(xy 366.900206 -294.335962) (xy 366.899711 -294.360569) (xy 366.891816 -294.409146) (xy 366.876232 -294.455827)
			(xy 366.853361 -294.499404) (xy 366.823796 -294.538748) (xy 366.788303 -294.57284) (xy 366.7478 -294.600796)
			(xy 366.703338 -294.621894) (xy 366.656067 -294.635586) (xy 366.607212 -294.641518) (xy 366.558037 -294.639537)
			(xy 366.509818 -294.629693) (xy 366.463802 -294.612241) (xy 366.421181 -294.587634) (xy 366.38306 -294.556509)
			(xy 366.350425 -294.519672) (xy 366.324122 -294.478076) (xy 366.304831 -294.4328) (xy 366.293054 -294.385016)
			(xy 366.289094 -294.335962) (xy 365.960152 -294.335962) (xy 365.959657 -294.360569) (xy 365.951762 -294.409146)
			(xy 365.936178 -294.455827) (xy 365.913307 -294.499404) (xy 365.883742 -294.538748) (xy 365.848249 -294.57284)
			(xy 365.807746 -294.600796) (xy 365.763284 -294.621894) (xy 365.716013 -294.635586) (xy 365.667158 -294.641518)
			(xy 365.617983 -294.639537) (xy 365.569764 -294.629693) (xy 365.523748 -294.612241) (xy 365.481127 -294.587634)
			(xy 365.443006 -294.556509) (xy 365.410371 -294.519672) (xy 365.384068 -294.478076) (xy 365.364777 -294.4328)
			(xy 365.353 -294.385016) (xy 365.34904 -294.335962) (xy 365.020098 -294.335962) (xy 365.019603 -294.360569)
			(xy 365.011708 -294.409146) (xy 364.996124 -294.455827) (xy 364.973253 -294.499404) (xy 364.943688 -294.538748)
			(xy 364.908195 -294.57284) (xy 364.867692 -294.600796) (xy 364.82323 -294.621894) (xy 364.775959 -294.635586)
			(xy 364.727104 -294.641518) (xy 364.677929 -294.639537) (xy 364.62971 -294.629693) (xy 364.583694 -294.612241)
			(xy 364.541073 -294.587634) (xy 364.502952 -294.556509) (xy 364.470317 -294.519672) (xy 364.444014 -294.478076)
			(xy 364.424723 -294.4328) (xy 364.412946 -294.385016) (xy 364.408986 -294.335962) (xy 364.080044 -294.335962)
			(xy 364.079549 -294.360569) (xy 364.071654 -294.409146) (xy 364.05607 -294.455827) (xy 364.033199 -294.499404)
			(xy 364.003634 -294.538748) (xy 363.968141 -294.57284) (xy 363.927638 -294.600796) (xy 363.883176 -294.621894)
			(xy 363.835905 -294.635586) (xy 363.78705 -294.641518) (xy 363.737875 -294.639537) (xy 363.689656 -294.629693)
			(xy 363.64364 -294.612241) (xy 363.601019 -294.587634) (xy 363.562898 -294.556509) (xy 363.530263 -294.519672)
			(xy 363.50396 -294.478076) (xy 363.484669 -294.4328) (xy 363.472892 -294.385016) (xy 363.468932 -294.335962)
			(xy 363.140244 -294.335962) (xy 363.139749 -294.360569) (xy 363.131854 -294.409146) (xy 363.11627 -294.455827)
			(xy 363.093399 -294.499404) (xy 363.063834 -294.538748) (xy 363.028341 -294.57284) (xy 362.987838 -294.600796)
			(xy 362.943376 -294.621894) (xy 362.896105 -294.635586) (xy 362.84725 -294.641518) (xy 362.798075 -294.639537)
			(xy 362.749856 -294.629693) (xy 362.70384 -294.612241) (xy 362.661219 -294.587634) (xy 362.623098 -294.556509)
			(xy 362.590463 -294.519672) (xy 362.56416 -294.478076) (xy 362.544869 -294.4328) (xy 362.533092 -294.385016)
			(xy 362.529132 -294.335962) (xy 362.20019 -294.335962) (xy 362.199695 -294.360569) (xy 362.1918 -294.409146)
			(xy 362.176216 -294.455827) (xy 362.153345 -294.499404) (xy 362.12378 -294.538748) (xy 362.088287 -294.57284)
			(xy 362.047784 -294.600796) (xy 362.003322 -294.621894) (xy 361.956051 -294.635586) (xy 361.907196 -294.641518)
			(xy 361.858021 -294.639537) (xy 361.809802 -294.629693) (xy 361.763786 -294.612241) (xy 361.721165 -294.587634)
			(xy 361.683044 -294.556509) (xy 361.650409 -294.519672) (xy 361.624106 -294.478076) (xy 361.604815 -294.4328)
			(xy 361.593038 -294.385016) (xy 361.589078 -294.335962) (xy 358.446324 -294.335962) (xy 358.445829 -294.360569)
			(xy 358.437934 -294.409146) (xy 358.42235 -294.455827) (xy 358.399479 -294.499404) (xy 358.369914 -294.538748)
			(xy 358.334421 -294.57284) (xy 358.293918 -294.600796) (xy 358.249456 -294.621894) (xy 358.202185 -294.635586)
			(xy 358.15333 -294.641518) (xy 358.104155 -294.639537) (xy 358.055936 -294.629693) (xy 358.00992 -294.612241)
			(xy 357.967299 -294.587634) (xy 357.929178 -294.556509) (xy 357.896543 -294.519672) (xy 357.87024 -294.478076)
			(xy 357.850949 -294.4328) (xy 357.839172 -294.385016) (xy 357.835212 -294.335962) (xy 357.506524 -294.335962)
			(xy 357.506029 -294.360569) (xy 357.498134 -294.409146) (xy 357.48255 -294.455827) (xy 357.459679 -294.499404)
			(xy 357.430114 -294.538748) (xy 357.394621 -294.57284) (xy 357.354118 -294.600796) (xy 357.309656 -294.621894)
			(xy 357.262385 -294.635586) (xy 357.21353 -294.641518) (xy 357.164355 -294.639537) (xy 357.116136 -294.629693)
			(xy 357.07012 -294.612241) (xy 357.027499 -294.587634) (xy 356.989378 -294.556509) (xy 356.956743 -294.519672)
			(xy 356.93044 -294.478076) (xy 356.911149 -294.4328) (xy 356.899372 -294.385016) (xy 356.895412 -294.335962)
			(xy 356.441248 -294.335962) (xy 356.441248 -294.695372) (xy 356.441686 -294.705435) (xy 356.449424 -294.724016)
			(xy 356.456234 -294.73144) (xy 356.563676 -294.838882) (xy 356.593394 -294.844978) (xy 356.607618 -294.839136)
			(xy 356.637253 -294.827991) (xy 356.699408 -294.815969) (xy 356.731062 -294.81526) (xy 356.757054 -294.81574)
			(xy 356.808399 -294.823867) (xy 356.857841 -294.839925) (xy 356.904162 -294.86352) (xy 356.946221 -294.894071)
			(xy 356.982983 -294.930826) (xy 357.013543 -294.972879) (xy 357.037148 -295.019194) (xy 357.053217 -295.068633)
			(xy 357.061354 -295.119976) (xy 357.06177 -295.145968) (xy 358.305366 -295.145968) (xy 358.309326 -295.096914)
			(xy 358.321103 -295.04913) (xy 358.340394 -295.003854) (xy 358.366697 -294.962258) (xy 358.399332 -294.925421)
			(xy 358.437453 -294.894296) (xy 358.480074 -294.869689) (xy 358.52609 -294.852237) (xy 358.574309 -294.842393)
			(xy 358.623484 -294.840412) (xy 358.672339 -294.846344) (xy 358.71961 -294.860036) (xy 358.764072 -294.881134)
			(xy 358.804575 -294.90909) (xy 358.840068 -294.943182) (xy 358.869633 -294.982526) (xy 358.892504 -295.026103)
			(xy 358.908088 -295.072784) (xy 358.915983 -295.121361) (xy 358.916478 -295.145968) (xy 361.118924 -295.145968)
			(xy 361.122884 -295.096914) (xy 361.134661 -295.04913) (xy 361.153952 -295.003854) (xy 361.180255 -294.962258)
			(xy 361.21289 -294.925421) (xy 361.251011 -294.894296) (xy 361.293632 -294.869689) (xy 361.339648 -294.852237)
			(xy 361.387867 -294.842393) (xy 361.437042 -294.840412) (xy 361.485897 -294.846344) (xy 361.533168 -294.860036)
			(xy 361.57763 -294.881134) (xy 361.618133 -294.90909) (xy 361.653626 -294.943182) (xy 361.683191 -294.982526)
			(xy 361.706062 -295.026103) (xy 361.721646 -295.072784) (xy 361.729541 -295.121361) (xy 361.730036 -295.145968)
			(xy 362.058978 -295.145968) (xy 362.062938 -295.096914) (xy 362.074715 -295.04913) (xy 362.094006 -295.003854)
			(xy 362.120309 -294.962258) (xy 362.152944 -294.925421) (xy 362.191065 -294.894296) (xy 362.233686 -294.869689)
			(xy 362.279702 -294.852237) (xy 362.327921 -294.842393) (xy 362.377096 -294.840412) (xy 362.425951 -294.846344)
			(xy 362.473222 -294.860036) (xy 362.517684 -294.881134) (xy 362.558187 -294.90909) (xy 362.59368 -294.943182)
			(xy 362.623245 -294.982526) (xy 362.646116 -295.026103) (xy 362.6617 -295.072784) (xy 362.669595 -295.121361)
			(xy 362.67009 -295.145968) (xy 373.339118 -295.145968) (xy 373.343078 -295.096914) (xy 373.354855 -295.04913)
			(xy 373.374146 -295.003854) (xy 373.400449 -294.962258) (xy 373.433084 -294.925421) (xy 373.471205 -294.894296)
			(xy 373.513826 -294.869689) (xy 373.559842 -294.852237) (xy 373.608061 -294.842393) (xy 373.657236 -294.840412)
			(xy 373.706091 -294.846344) (xy 373.753362 -294.860036) (xy 373.797824 -294.881134) (xy 373.838327 -294.90909)
			(xy 373.87382 -294.943182) (xy 373.903385 -294.982526) (xy 373.926256 -295.026103) (xy 373.94184 -295.072784)
			(xy 373.949735 -295.121361) (xy 373.95023 -295.145968) (xy 373.949735 -295.170575) (xy 373.94184 -295.219152)
			(xy 373.926256 -295.265833) (xy 373.903385 -295.30941) (xy 373.87382 -295.348754) (xy 373.838327 -295.382846)
			(xy 373.797824 -295.410802) (xy 373.753362 -295.4319) (xy 373.706091 -295.445592) (xy 373.657236 -295.451524)
			(xy 373.608061 -295.449543) (xy 373.559842 -295.439699) (xy 373.513826 -295.422247) (xy 373.471205 -295.39764)
			(xy 373.433084 -295.366515) (xy 373.400449 -295.329678) (xy 373.374146 -295.288082) (xy 373.354855 -295.242806)
			(xy 373.343078 -295.195022) (xy 373.339118 -295.145968) (xy 362.67009 -295.145968) (xy 362.669595 -295.170575)
			(xy 362.6617 -295.219152) (xy 362.646116 -295.265833) (xy 362.623245 -295.30941) (xy 362.59368 -295.348754)
			(xy 362.558187 -295.382846) (xy 362.517684 -295.410802) (xy 362.473222 -295.4319) (xy 362.425951 -295.445592)
			(xy 362.377096 -295.451524) (xy 362.327921 -295.449543) (xy 362.279702 -295.439699) (xy 362.233686 -295.422247)
			(xy 362.191065 -295.39764) (xy 362.152944 -295.366515) (xy 362.120309 -295.329678) (xy 362.094006 -295.288082)
			(xy 362.074715 -295.242806) (xy 362.062938 -295.195022) (xy 362.058978 -295.145968) (xy 361.730036 -295.145968)
			(xy 361.729541 -295.170575) (xy 361.721646 -295.219152) (xy 361.706062 -295.265833) (xy 361.683191 -295.30941)
			(xy 361.653626 -295.348754) (xy 361.618133 -295.382846) (xy 361.57763 -295.410802) (xy 361.533168 -295.4319)
			(xy 361.485897 -295.445592) (xy 361.437042 -295.451524) (xy 361.387867 -295.449543) (xy 361.339648 -295.439699)
			(xy 361.293632 -295.422247) (xy 361.251011 -295.39764) (xy 361.21289 -295.366515) (xy 361.180255 -295.329678)
			(xy 361.153952 -295.288082) (xy 361.134661 -295.242806) (xy 361.122884 -295.195022) (xy 361.118924 -295.145968)
			(xy 358.916478 -295.145968) (xy 358.915983 -295.170575) (xy 358.908088 -295.219152) (xy 358.892504 -295.265833)
			(xy 358.869633 -295.30941) (xy 358.840068 -295.348754) (xy 358.804575 -295.382846) (xy 358.764072 -295.410802)
			(xy 358.71961 -295.4319) (xy 358.672339 -295.445592) (xy 358.623484 -295.451524) (xy 358.574309 -295.449543)
			(xy 358.52609 -295.439699) (xy 358.480074 -295.422247) (xy 358.437453 -295.39764) (xy 358.399332 -295.366515)
			(xy 358.366697 -295.329678) (xy 358.340394 -295.288082) (xy 358.321103 -295.242806) (xy 358.309326 -295.195022)
			(xy 358.305366 -295.145968) (xy 357.06177 -295.145968) (xy 357.061061 -295.177622) (xy 357.049049 -295.239781)
			(xy 357.037894 -295.269412) (xy 357.032052 -295.283636) (xy 357.038148 -295.313354) (xy 357.96093 -296.236136)
			(xy 357.968327 -296.242985) (xy 357.986926 -296.250718) (xy 357.996998 -296.251122) (xy 366.237012 -296.251122)
			(xy 366.248953 -296.250487) (xy 366.270292 -296.239766) (xy 366.277906 -296.230548) (xy 366.27943 -296.228516)
			(xy 366.332262 -296.139616) (xy 366.33277 -296.1132) (xy 366.32642 -296.101262) (xy 366.314825 -296.07882)
			(xy 366.298409 -296.03105) (xy 366.290081 -295.98123) (xy 366.28959 -295.955974) (xy 366.290112 -295.930719)
			(xy 366.298425 -295.880897) (xy 366.314826 -295.833123) (xy 366.338867 -295.7887) (xy 366.369891 -295.74884)
			(xy 366.407053 -295.71463) (xy 366.449339 -295.687004) (xy 366.495595 -295.666714) (xy 366.54456 -295.654314)
			(xy 366.594898 -295.650143) (xy 366.645236 -295.654314) (xy 366.694201 -295.666714) (xy 366.740457 -295.687004)
			(xy 366.782743 -295.71463) (xy 366.819905 -295.74884) (xy 366.850929 -295.7887) (xy 366.87497 -295.833123)
			(xy 366.891371 -295.880897) (xy 366.899684 -295.930719) (xy 366.900206 -295.955974) (xy 366.899713 -295.98123)
			(xy 366.891393 -296.031052) (xy 366.874976 -296.078822) (xy 366.863376 -296.101262) (xy 366.857026 -296.1132)
			(xy 366.857534 -296.139616) (xy 366.909096 -296.22623) (xy 366.91189 -296.230294) (xy 366.91189 -296.230548)
			(xy 366.919504 -296.239768) (xy 366.940842 -296.250491) (xy 366.952784 -296.251122) (xy 370.937028 -296.251122)
			(xy 370.948967 -296.250484) (xy 370.970301 -296.239759) (xy 370.977922 -296.230548) (xy 370.979446 -296.228516)
			(xy 371.032278 -296.139616) (xy 371.032786 -296.1132) (xy 371.026436 -296.101262) (xy 371.014841 -296.07882)
			(xy 370.998424 -296.03105) (xy 370.990096 -295.98123) (xy 370.989606 -295.955974) (xy 370.990128 -295.930719)
			(xy 370.998441 -295.880897) (xy 371.014842 -295.833123) (xy 371.038883 -295.7887) (xy 371.069907 -295.74884)
			(xy 371.107069 -295.71463) (xy 371.149355 -295.687004) (xy 371.195611 -295.666714) (xy 371.244576 -295.654314)
			(xy 371.294914 -295.650143) (xy 371.345252 -295.654314) (xy 371.394217 -295.666714) (xy 371.440473 -295.687004)
			(xy 371.482759 -295.71463) (xy 371.519921 -295.74884) (xy 371.550945 -295.7887) (xy 371.574986 -295.833123)
			(xy 371.591387 -295.880897) (xy 371.5997 -295.930719) (xy 371.600222 -295.955974) (xy 371.599729 -295.98123)
			(xy 371.59141 -296.031053) (xy 371.574993 -296.078823) (xy 371.563392 -296.101262) (xy 371.557042 -296.1132)
			(xy 371.55755 -296.139616) (xy 371.609112 -296.22623) (xy 371.611906 -296.230294) (xy 371.611906 -296.230548)
			(xy 371.619521 -296.239766) (xy 371.640859 -296.250482) (xy 371.6528 -296.251122) (xy 373.815102 -296.251122)
			(xy 373.825172 -296.251546) (xy 373.843773 -296.259263) (xy 373.85117 -296.266108) (xy 373.895112 -296.31005)
			(xy 373.902509 -296.3169) (xy 373.921107 -296.324638) (xy 373.93118 -296.325036) (xy 374.63349 -296.325036)
			(xy 374.64356 -296.325458) (xy 374.662164 -296.333174) (xy 374.669558 -296.340022)
		)
		(stroke
			(width 0)
			(type solid)
		)
		(fill yes)
		(layer "In2.Cu")
		(net "PVDDCR_CPU1_P0")
	)
	(gr_poly
		(pts
			(xy 64.809878 -335.146904) (xy 64.818983 -335.145924) (xy 64.835653 -335.138375) (xy 64.84239 -335.132172)
			(xy 65.627758 -334.346804) (xy 65.632744 -334.341304) (xy 65.639588 -334.328138) (xy 65.64122 -334.320896)
			(xy 65.642236 -334.311244) (xy 65.642236 -325.39432) (xy 65.642674 -325.384257) (xy 65.650413 -325.365677)
			(xy 65.657222 -325.358252) (xy 67.484244 -323.53123) (xy 67.491644 -323.524387) (xy 67.510242 -323.516664)
			(xy 67.520312 -323.516244) (xy 96.1009 -323.516244) (xy 96.110969 -323.516668) (xy 96.129569 -323.524388)
			(xy 96.136968 -323.53123) (xy 100.928678 -328.32294) (xy 100.936078 -328.32978) (xy 100.954677 -328.337496)
			(xy 100.964746 -328.337926) (xy 106.508296 -328.337926) (xy 106.517948 -328.33691) (xy 106.525193 -328.335284)
			(xy 106.538367 -328.328448) (xy 106.543856 -328.323448) (xy 107.16641 -327.700894) (xy 107.171399 -327.695396)
			(xy 107.178247 -327.68223) (xy 107.179872 -327.674986) (xy 107.180888 -327.665334) (xy 107.180888 -323.982588)
			(xy 107.177078 -323.97319) (xy 107.16383 -323.939152) (xy 107.145192 -323.868528) (xy 107.135771 -323.796096)
			(xy 107.135168 -323.759576) (xy 107.135753 -323.723055) (xy 107.145172 -323.650621) (xy 107.163827 -323.58)
			(xy 107.177078 -323.545962) (xy 107.180888 -323.536564) (xy 107.180888 -321.55003) (xy 107.181323 -321.539965)
			(xy 107.189054 -321.521378) (xy 107.195874 -321.513962) (xy 107.648502 -321.061334) (xy 107.655899 -321.054484)
			(xy 107.674497 -321.046745) (xy 107.68457 -321.046348) (xy 130.59791 -321.046348) (xy 130.607562 -321.045332)
			(xy 130.614804 -321.043702) (xy 130.627968 -321.036855) (xy 130.63347 -321.03187) (xy 135.784082 -315.881258)
			(xy 135.789069 -315.875759) (xy 135.795912 -315.862592) (xy 135.797544 -315.85535) (xy 135.79856 -315.845698)
			(xy 135.79856 -298.427902) (xy 135.798388 -298.421894) (xy 135.795557 -298.410215) (xy 135.792972 -298.404788)
			(xy 135.791132 -298.401314) (xy 135.786537 -298.394937) (xy 135.783828 -298.392088) (xy 134.644892 -297.253152)
			(xy 134.642041 -297.250446) (xy 134.635663 -297.245852) (xy 134.632192 -297.244008) (xy 134.626766 -297.241421)
			(xy 134.615086 -297.238589) (xy 134.609078 -297.23842) (xy 130.881882 -297.23842) (xy 130.871813 -297.237994)
			(xy 130.853211 -297.230277) (xy 130.845814 -297.223434) (xy 129.88925 -296.26687) (xy 129.886674 -296.264361)
			(xy 129.880939 -296.260024) (xy 129.87782 -296.258234) (xy 129.872232 -296.255186) (xy 129.86512 -296.253408)
			(xy 129.841634 -296.247432) (xy 129.796787 -296.229069) (xy 129.755405 -296.20385) (xy 129.718527 -296.17241)
			(xy 129.687081 -296.135538) (xy 129.661855 -296.09416) (xy 129.643484 -296.049317) (xy 129.637536 -296.025824)
			(xy 129.635758 -296.018712) (xy 129.63271 -296.013124) (xy 129.630912 -296.01001) (xy 129.626578 -296.004274)
			(xy 129.624074 -296.001694) (xy 128.930146 -295.307766) (xy 128.922176 -295.300645) (xy 128.902227 -295.293046)
			(xy 128.891538 -295.293034) (xy 128.862074 -295.295574) (xy 128.812036 -295.299892) (xy 128.806494 -295.300505)
			(xy 128.795854 -295.303835) (xy 128.790954 -295.306496) (xy 128.781556 -295.312084) (xy 128.774952 -295.321482)
			(xy 128.760526 -295.341213) (xy 128.726447 -295.376247) (xy 128.687224 -295.405406) (xy 128.643857 -295.427947)
			(xy 128.597454 -295.443294) (xy 128.5492 -295.451056) (xy 128.524762 -295.45153) (xy 128.500772 -295.451057)
			(xy 128.453384 -295.443546) (xy 128.407753 -295.428715) (xy 128.365004 -295.40693) (xy 128.326189 -295.378727)
			(xy 128.292263 -295.344799) (xy 128.264061 -295.305982) (xy 128.242278 -295.263232) (xy 128.22745 -295.217601)
			(xy 128.219942 -295.170212) (xy 128.219454 -295.146222) (xy 128.219454 -295.145968) (xy 128.219929 -295.121548)
			(xy 128.227698 -295.07333) (xy 128.243047 -295.026966) (xy 128.265586 -294.983638) (xy 128.294738 -294.944453)
			(xy 128.32976 -294.910412) (xy 128.349502 -294.896032) (xy 128.349756 -294.895778) (xy 128.354167 -294.892513)
			(xy 128.361606 -294.884446) (xy 128.364488 -294.879776) (xy 128.370076 -294.870124) (xy 128.37541 -294.80891)
			(xy 128.37795 -294.779446) (xy 128.378074 -294.768735) (xy 128.370451 -294.748737) (xy 128.363218 -294.740838)
			(xy 128.244092 -294.621712) (xy 128.236352 -294.614687) (xy 128.216927 -294.607024) (xy 128.196058 -294.607734)
			(xy 128.186434 -294.611806) (xy 128.18618 -294.611806) (xy 128.16557 -294.621178) (xy 128.122275 -294.634416)
			(xy 128.077499 -294.641112) (xy 128.054862 -294.641524) (xy 128.030872 -294.641051) (xy 127.983484 -294.63354)
			(xy 127.937854 -294.618709) (xy 127.895106 -294.596924) (xy 127.856291 -294.56872) (xy 127.822365 -294.534792)
			(xy 127.794165 -294.495975) (xy 127.772382 -294.453225) (xy 127.757555 -294.407594) (xy 127.750048 -294.360206)
			(xy 127.749554 -294.336216) (xy 127.749966 -294.313579) (xy 127.756657 -294.268802) (xy 127.769895 -294.225506)
			(xy 127.779272 -294.204898) (xy 127.779272 -294.204644) (xy 127.783316 -294.195006) (xy 127.784055 -294.17414)
			(xy 127.776401 -294.154715) (xy 127.769366 -294.146986) (xy 127.101854 -293.479474) (xy 127.095006 -293.472077)
			(xy 127.087272 -293.453478) (xy 127.086868 -293.443406) (xy 127.086868 -293.08933) (xy 127.086527 -293.080637)
			(xy 127.080691 -293.06426) (xy 127.075438 -293.057326) (xy 127.070104 -293.050722) (xy 127.055372 -293.041578)
			(xy 127.046482 -293.0398) (xy 127.022066 -293.034173) (xy 126.975165 -293.016547) (xy 126.931459 -292.992049)
			(xy 126.891949 -292.961238) (xy 126.857538 -292.924821) (xy 126.829014 -292.883629) (xy 126.807029 -292.838606)
			(xy 126.792087 -292.790783) (xy 126.784529 -292.741253) (xy 126.784529 -292.691149) (xy 126.792087 -292.641619)
			(xy 126.807028 -292.593795) (xy 126.829013 -292.548772) (xy 126.857537 -292.507581) (xy 126.891948 -292.471163)
			(xy 126.931458 -292.440352) (xy 126.975164 -292.415854) (xy 127.022064 -292.398228) (xy 127.046482 -292.392608)
			(xy 127.046736 -292.392608) (xy 127.055067 -292.390478) (xy 127.069727 -292.381512) (xy 127.075438 -292.375082)
			(xy 127.081026 -292.368224) (xy 127.086868 -292.351968) (xy 127.086868 -291.44341) (xy 127.086868 -291.44087)
			(xy 127.085784 -291.430297) (xy 127.076229 -291.411338) (xy 127.059839 -291.397844) (xy 127.049784 -291.394388)
			(xy 127.047244 -291.39388) (xy 127.023735 -291.388069) (xy 126.978796 -291.370031) (xy 126.937269 -291.345124)
			(xy 126.900195 -291.313973) (xy 126.868504 -291.277359) (xy 126.842991 -291.236201) (xy 126.824296 -291.191531)
			(xy 126.812889 -291.14447) (xy 126.809054 -291.096198) (xy 126.812889 -291.047926) (xy 126.824297 -291.000865)
			(xy 126.842992 -290.956196) (xy 126.868506 -290.915038) (xy 126.900197 -290.878425) (xy 126.937272 -290.847274)
			(xy 126.978799 -290.822367) (xy 127.023738 -290.80433) (xy 127.047244 -290.798504) (xy 127.049784 -290.797996)
			(xy 127.059867 -290.794609) (xy 127.076256 -290.781092) (xy 127.08577 -290.762096) (xy 127.086868 -290.751514)
			(xy 127.086868 -289.823398) (xy 127.086868 -289.820858) (xy 127.0858 -289.810273) (xy 127.076261 -289.791285)
			(xy 127.059868 -289.777764) (xy 127.049784 -289.774376) (xy 127.047244 -289.773868) (xy 127.023736 -289.768057)
			(xy 126.978799 -289.750019) (xy 126.937273 -289.725113) (xy 126.900201 -289.693963) (xy 126.868511 -289.65735)
			(xy 126.843 -289.616193) (xy 126.824306 -289.571525) (xy 126.8129 -289.524466) (xy 126.809066 -289.476196)
			(xy 126.812901 -289.427926) (xy 126.824309 -289.380866) (xy 126.843004 -289.336199) (xy 126.868517 -289.295043)
			(xy 126.900207 -289.258431) (xy 126.937281 -289.227282) (xy 126.978807 -289.202377) (xy 127.023744 -289.18434)
			(xy 127.047244 -289.178492) (xy 127.049784 -289.177984) (xy 127.059866 -289.174597) (xy 127.076252 -289.161078)
			(xy 127.085761 -289.142083) (xy 127.086868 -289.131502) (xy 127.086868 -288.20364) (xy 127.086868 -288.2011)
			(xy 127.085789 -288.190523) (xy 127.07624 -288.171554) (xy 127.059849 -288.158051) (xy 127.049784 -288.154618)
			(xy 127.047244 -288.15411) (xy 127.023733 -288.148299) (xy 126.978789 -288.13026) (xy 126.937257 -288.105352)
			(xy 126.900179 -288.074198) (xy 126.868484 -288.037582) (xy 126.842968 -287.99642) (xy 126.82427 -287.951747)
			(xy 126.812861 -287.904681) (xy 126.809025 -287.856405) (xy 126.812859 -287.808128) (xy 126.824267 -287.761063)
			(xy 126.842963 -287.716388) (xy 126.868478 -287.675226) (xy 126.900172 -287.638608) (xy 126.937249 -287.607454)
			(xy 126.97878 -287.582544) (xy 127.023723 -287.564504) (xy 127.047244 -287.558734) (xy 127.049784 -287.558226)
			(xy 127.05987 -287.554841) (xy 127.076267 -287.541325) (xy 127.085791 -287.522329) (xy 127.086868 -287.511744)
			(xy 127.086868 -286.583628) (xy 127.086868 -286.581088) (xy 127.085787 -286.570512) (xy 127.076236 -286.551548)
			(xy 127.059845 -286.538048) (xy 127.049784 -286.534606) (xy 127.047244 -286.534098) (xy 127.023734 -286.528287)
			(xy 126.978792 -286.510249) (xy 126.937262 -286.485341) (xy 126.900185 -286.454188) (xy 126.868492 -286.417573)
			(xy 126.842977 -286.376413) (xy 126.824281 -286.331741) (xy 126.812872 -286.284677) (xy 126.809037 -286.236402)
			(xy 126.812871 -286.188127) (xy 126.824279 -286.141064) (xy 126.842975 -286.096391) (xy 126.868489 -286.055231)
			(xy 126.900182 -286.018615) (xy 126.937258 -285.987462) (xy 126.978788 -285.962553) (xy 127.023729 -285.944514)
			(xy 127.047244 -285.938722) (xy 127.049784 -285.938214) (xy 127.059869 -285.934829) (xy 127.076263 -285.921312)
			(xy 127.085783 -285.902316) (xy 127.086868 -285.891732) (xy 127.086868 -284.963616) (xy 127.086868 -284.961076)
			(xy 127.085785 -284.950502) (xy 127.076231 -284.931541) (xy 127.059841 -284.918046) (xy 127.049784 -284.914594)
			(xy 127.047244 -284.914086) (xy 127.023735 -284.908275) (xy 126.978795 -284.890237) (xy 126.937266 -284.86533)
			(xy 126.900191 -284.834178) (xy 126.8685 -284.797564) (xy 126.842986 -284.756405) (xy 126.824291 -284.711734)
			(xy 126.812883 -284.664672) (xy 126.809048 -284.6164) (xy 126.812883 -284.568127) (xy 126.824291 -284.521065)
			(xy 126.842987 -284.476394) (xy 126.8685 -284.435236) (xy 126.900192 -284.398621) (xy 126.937267 -284.36747)
			(xy 126.978795 -284.342563) (xy 127.023735 -284.324524) (xy 127.047244 -284.31871) (xy 127.049784 -284.318202)
			(xy 127.059867 -284.314816) (xy 127.076258 -284.301298) (xy 127.085774 -284.282303) (xy 127.086868 -284.27172)
			(xy 127.086868 -284.17012) (xy 127.087374 -284.160069) (xy 127.095094 -284.141508) (xy 127.101854 -284.134052)
			(xy 127.282448 -283.953458) (xy 127.28721 -283.948315) (xy 127.294044 -283.936084) (xy 127.29591 -283.929328)
			(xy 127.297434 -283.92247) (xy 127.296926 -283.909008) (xy 127.29464 -283.901896) (xy 127.287621 -283.879033)
			(xy 127.279966 -283.831826) (xy 127.2794 -283.807916) (xy 127.2794 -283.80309) (xy 127.280179 -283.77809)
			(xy 127.288875 -283.728838) (xy 127.305478 -283.681659) (xy 127.329543 -283.637815) (xy 127.360427 -283.598476)
			(xy 127.397307 -283.564693) (xy 127.439196 -283.537367) (xy 127.484977 -283.517229) (xy 127.533427 -283.504817)
			(xy 127.558292 -283.5021) (xy 127.566928 -283.501338) (xy 127.590804 -283.49067) (xy 127.594925 -283.488732)
			(xy 127.60246 -283.483617) (xy 127.60579 -283.48051) (xy 127.620776 -283.465524) (xy 127.625748 -283.46009)
			(xy 127.632576 -283.447047) (xy 127.634238 -283.43987) (xy 127.634238 -283.439362) (xy 127.635254 -283.429964)
			(xy 127.635254 -283.401008) (xy 127.635061 -283.39434) (xy 127.631591 -283.381464) (xy 127.628396 -283.375608)
			(xy 127.571246 -283.27731) (xy 127.560777 -283.25883) (xy 127.542346 -283.22056) (xy 127.534416 -283.200856)
			(xy 127.531622 -283.193998) (xy 127.524002 -283.183584) (xy 127.518414 -283.179266) (xy 127.513744 -283.175829)
			(xy 127.503228 -283.170951) (xy 127.497586 -283.169614) (xy 127.404876 -283.157422) (xy 127.398771 -283.157111)
			(xy 127.386701 -283.159026) (xy 127.381 -283.161232) (xy 127.375158 -283.163772) (xy 127.364998 -283.1719)
			(xy 127.360426 -283.177996) (xy 127.345895 -283.196826) (xy 127.311989 -283.230178) (xy 127.27333 -283.257882)
			(xy 127.230851 -283.27927) (xy 127.185573 -283.293827) (xy 127.138588 -283.301203) (xy 127.114808 -283.301694)
			(xy 127.089551 -283.301202) (xy 127.039726 -283.292889) (xy 126.991948 -283.276488) (xy 126.947522 -283.252447)
			(xy 126.907659 -283.221421) (xy 126.873447 -283.184257) (xy 126.845818 -283.141969) (xy 126.825526 -283.09571)
			(xy 126.813125 -283.046741) (xy 126.808954 -282.9964) (xy 126.813125 -282.946059) (xy 126.825526 -282.89709)
			(xy 126.845818 -282.850831) (xy 126.873447 -282.808543) (xy 126.907659 -282.771379) (xy 126.947522 -282.740353)
			(xy 126.991948 -282.716312) (xy 127.039726 -282.699911) (xy 127.089551 -282.691598) (xy 127.114808 -282.691078)
			(xy 127.138575 -282.691525) (xy 127.185537 -282.698882) (xy 127.23079 -282.713433) (xy 127.273238 -282.734826)
			(xy 127.311856 -282.762542) (xy 127.345708 -282.795912) (xy 127.360172 -282.814776) (xy 127.362458 -282.817824)
			(xy 127.366476 -282.822185) (xy 127.3761 -282.829107) (xy 127.381508 -282.83154) (xy 127.38735 -282.83408)
			(xy 127.400558 -282.835858) (xy 127.493776 -282.823666) (xy 127.500455 -282.822625) (xy 127.512952 -282.817486)
			(xy 127.518414 -282.813506) (xy 127.524002 -282.809188) (xy 127.531876 -282.79852) (xy 127.534416 -282.791916)
			(xy 127.545521 -282.76468) (xy 127.572663 -282.712496) (xy 127.605141 -282.663456) (xy 127.62357 -282.640532)
			(xy 127.629158 -282.633674) (xy 127.632206 -282.6258) (xy 127.634492 -282.617672) (xy 127.635254 -282.608528)
			(xy 127.635254 -282.562808) (xy 127.635083 -282.556799) (xy 127.632253 -282.54512) (xy 127.629666 -282.539694)
			(xy 127.627826 -282.53622) (xy 127.623231 -282.529842) (xy 127.620522 -282.526994) (xy 127.60579 -282.512262)
			(xy 127.602466 -282.509148) (xy 127.594929 -282.504035) (xy 127.590804 -282.502102) (xy 127.566928 -282.491434)
			(xy 127.558292 -282.490672) (xy 127.533233 -282.487979) (xy 127.484421 -282.475438) (xy 127.438331 -282.455054)
			(xy 127.396213 -282.42738) (xy 127.359209 -282.393167) (xy 127.328324 -282.353343) (xy 127.304395 -282.30899)
			(xy 127.288073 -282.261309) (xy 127.2798 -282.211597) (xy 127.2798 -282.1612) (xy 127.288074 -282.111487)
			(xy 127.304397 -282.063807) (xy 127.328326 -282.019454) (xy 127.359211 -281.97963) (xy 127.396215 -281.945418)
			(xy 127.438334 -281.917744) (xy 127.484425 -281.897361) (xy 127.533236 -281.88482) (xy 127.558292 -281.882088)
			(xy 127.566928 -281.881326) (xy 127.590804 -281.870658) (xy 127.594925 -281.868719) (xy 127.602459 -281.863604)
			(xy 127.60579 -281.860498) (xy 127.620776 -281.845512) (xy 127.625747 -281.840077) (xy 127.632572 -281.827034)
			(xy 127.634238 -281.819858) (xy 127.634238 -281.81935) (xy 127.635254 -281.809952) (xy 127.635254 -281.780996)
			(xy 127.63506 -281.774328) (xy 127.631587 -281.761454) (xy 127.628396 -281.755596) (xy 127.571246 -281.657298)
			(xy 127.560775 -281.638819) (xy 127.542338 -281.600551) (xy 127.534416 -281.580844) (xy 127.531622 -281.573986)
			(xy 127.524002 -281.563572) (xy 127.518414 -281.559254) (xy 127.513747 -281.555812) (xy 127.503232 -281.550926)
			(xy 127.497586 -281.549602) (xy 127.404876 -281.53741) (xy 127.398771 -281.537099) (xy 127.3867 -281.539014)
			(xy 127.381 -281.54122) (xy 127.375158 -281.54376) (xy 127.364998 -281.551888) (xy 127.360426 -281.557984)
			(xy 127.345896 -281.576814) (xy 127.31199 -281.610168) (xy 127.273332 -281.637872) (xy 127.230852 -281.659262)
			(xy 127.185574 -281.67382) (xy 127.138588 -281.681196) (xy 127.114808 -281.681682) (xy 127.089552 -281.68119)
			(xy 127.039729 -281.672877) (xy 126.991953 -281.656477) (xy 126.947529 -281.632437) (xy 126.907667 -281.601412)
			(xy 126.873456 -281.56425) (xy 126.845828 -281.521963) (xy 126.825537 -281.475706) (xy 126.813137 -281.426739)
			(xy 126.808966 -281.3764) (xy 126.813137 -281.326061) (xy 126.825537 -281.277094) (xy 126.845828 -281.230837)
			(xy 126.873456 -281.18855) (xy 126.907667 -281.151388) (xy 126.947529 -281.120363) (xy 126.991953 -281.096323)
			(xy 127.039729 -281.079923) (xy 127.089552 -281.07161) (xy 127.114808 -281.071066) (xy 127.138576 -281.071512)
			(xy 127.185538 -281.07887) (xy 127.230791 -281.09342) (xy 127.27324 -281.114812) (xy 127.311858 -281.142528)
			(xy 127.345711 -281.175897) (xy 127.360172 -281.194764) (xy 127.362458 -281.197812) (xy 127.366475 -281.202174)
			(xy 127.376099 -281.209098) (xy 127.381508 -281.211528) (xy 127.38735 -281.214068) (xy 127.400558 -281.215846)
			(xy 127.493776 -281.203654) (xy 127.500455 -281.202613) (xy 127.512951 -281.197473) (xy 127.518414 -281.193494)
			(xy 127.524002 -281.189176) (xy 127.531876 -281.178508) (xy 127.534416 -281.171904) (xy 127.545517 -281.144666)
			(xy 127.572652 -281.092477) (xy 127.605125 -281.043431) (xy 127.62357 -281.02052) (xy 127.629158 -281.013662)
			(xy 127.632206 -281.005788) (xy 127.634492 -280.99766) (xy 127.635254 -280.988516) (xy 127.635254 -280.942796)
			(xy 127.635081 -280.936788) (xy 127.632249 -280.92511) (xy 127.629666 -280.919682) (xy 127.627825 -280.916209)
			(xy 127.62323 -280.909832) (xy 127.620522 -280.906982) (xy 127.60579 -280.89225) (xy 127.602466 -280.889136)
			(xy 127.594928 -280.884024) (xy 127.590804 -280.88209) (xy 127.566928 -280.871422) (xy 127.558292 -280.87066)
			(xy 127.533234 -280.867967) (xy 127.484424 -280.855427) (xy 127.438336 -280.835043) (xy 127.396219 -280.80737)
			(xy 127.359217 -280.773158) (xy 127.328333 -280.733336) (xy 127.304406 -280.688984) (xy 127.288085 -280.641306)
			(xy 127.279812 -280.591595) (xy 127.279812 -280.5412) (xy 127.288086 -280.491489) (xy 127.304408 -280.443811)
			(xy 127.328336 -280.399459) (xy 127.359221 -280.359638) (xy 127.396224 -280.325427) (xy 127.438341 -280.297754)
			(xy 127.48443 -280.277372) (xy 127.533239 -280.264832) (xy 127.558292 -280.262076) (xy 127.566928 -280.261314)
			(xy 127.590804 -280.250646) (xy 127.594925 -280.248707) (xy 127.602458 -280.243591) (xy 127.60579 -280.240486)
			(xy 127.620776 -280.2255) (xy 127.625756 -280.220069) (xy 127.632603 -280.20703) (xy 127.634238 -280.199846)
			(xy 127.634238 -280.199338) (xy 127.635254 -280.18994) (xy 127.635254 -280.160984) (xy 127.635058 -280.154317)
			(xy 127.631582 -280.141444) (xy 127.628396 -280.135584) (xy 127.571246 -280.037286) (xy 127.560775 -280.018807)
			(xy 127.542339 -279.980538) (xy 127.534416 -279.960832) (xy 127.531622 -279.953974) (xy 127.524002 -279.94356)
			(xy 127.518414 -279.939242) (xy 127.513746 -279.935801) (xy 127.503231 -279.930916) (xy 127.497586 -279.92959)
			(xy 127.404876 -279.917398) (xy 127.398771 -279.917087) (xy 127.3867 -279.919001) (xy 127.381 -279.921208)
			(xy 127.375158 -279.923748) (xy 127.364998 -279.931876) (xy 127.360426 -279.937972) (xy 127.345896 -279.956803)
			(xy 127.311991 -279.990157) (xy 127.273333 -280.017863) (xy 127.230853 -280.039253) (xy 127.185574 -280.053812)
			(xy 127.138589 -280.061189) (xy 127.114808 -280.06167) (xy 127.089553 -280.061178) (xy 127.039732 -280.052866)
			(xy 126.991958 -280.036466) (xy 126.947535 -280.012427) (xy 126.907675 -279.981403) (xy 126.873466 -279.944242)
			(xy 126.845839 -279.901957) (xy 126.825549 -279.855702) (xy 126.813149 -279.806737) (xy 126.808978 -279.7564)
			(xy 126.813149 -279.706063) (xy 126.825549 -279.657098) (xy 126.845839 -279.610843) (xy 126.873466 -279.568558)
			(xy 126.907675 -279.531397) (xy 126.947535 -279.500373) (xy 126.991958 -279.476334) (xy 127.039732 -279.459934)
			(xy 127.089553 -279.451622) (xy 127.114808 -279.451054) (xy 127.138575 -279.451501) (xy 127.185534 -279.45886)
			(xy 127.230784 -279.473413) (xy 127.273229 -279.494809) (xy 127.311842 -279.52253) (xy 127.345687 -279.555905)
			(xy 127.360172 -279.574752) (xy 127.362458 -279.5778) (xy 127.366475 -279.582163) (xy 127.376097 -279.589088)
			(xy 127.381508 -279.591516) (xy 127.38735 -279.594056) (xy 127.400558 -279.595834) (xy 127.493776 -279.583642)
			(xy 127.500455 -279.582601) (xy 127.51295 -279.57746) (xy 127.518414 -279.573482) (xy 127.524002 -279.569164)
			(xy 127.531876 -279.558496) (xy 127.534416 -279.551892) (xy 127.545517 -279.524654) (xy 127.572654 -279.472466)
			(xy 127.605127 -279.423421) (xy 127.62357 -279.400508) (xy 127.629158 -279.39365) (xy 127.632206 -279.385776)
			(xy 127.634492 -279.377648) (xy 127.635254 -279.368504) (xy 127.635254 -279.322784) (xy 127.635092 -279.316773)
			(xy 127.632277 -279.305086) (xy 127.629666 -279.29967) (xy 127.627825 -279.296197) (xy 127.623228 -279.289821)
			(xy 127.620522 -279.28697) (xy 127.60579 -279.272238) (xy 127.602465 -279.269125) (xy 127.594927 -279.264014)
			(xy 127.590804 -279.262078) (xy 127.566928 -279.25141) (xy 127.558292 -279.250648) (xy 127.533235 -279.247955)
			(xy 127.484427 -279.235415) (xy 127.438341 -279.215032) (xy 127.396226 -279.18736) (xy 127.359225 -279.153149)
			(xy 127.328343 -279.113329) (xy 127.304417 -279.068978) (xy 127.288096 -279.021302) (xy 127.279824 -278.971593)
			(xy 127.279824 -278.9212) (xy 127.288098 -278.871491) (xy 127.30442 -278.823815) (xy 127.328347 -278.779465)
			(xy 127.35923 -278.739645) (xy 127.396232 -278.705435) (xy 127.438347 -278.677764) (xy 127.484434 -278.657383)
			(xy 127.533242 -278.644843) (xy 127.558292 -278.642064) (xy 127.566928 -278.641302) (xy 127.590804 -278.630634)
			(xy 127.594924 -278.628695) (xy 127.602457 -278.623577) (xy 127.60579 -278.620474) (xy 127.620776 -278.605488)
			(xy 127.625754 -278.600057) (xy 127.632599 -278.587017) (xy 127.634238 -278.579834) (xy 127.634238 -278.579326)
			(xy 127.635254 -278.569928) (xy 127.635254 -278.540972) (xy 127.635057 -278.534305) (xy 127.631578 -278.521434)
			(xy 127.628396 -278.515572) (xy 127.571246 -278.417274) (xy 127.560775 -278.398795) (xy 127.54234 -278.360526)
			(xy 127.534416 -278.34082) (xy 127.531622 -278.333962) (xy 127.524002 -278.323548) (xy 127.518414 -278.31923)
			(xy 127.513746 -278.315789) (xy 127.503231 -278.310906) (xy 127.497586 -278.309578) (xy 127.404876 -278.297386)
			(xy 127.398771 -278.297075) (xy 127.3867 -278.298988) (xy 127.381 -278.301196) (xy 127.375158 -278.303736)
			(xy 127.364998 -278.311864) (xy 127.360426 -278.31796) (xy 127.345896 -278.336792) (xy 127.311992 -278.370147)
			(xy 127.273334 -278.397854) (xy 127.230854 -278.419245) (xy 127.185575 -278.433805) (xy 127.138589 -278.441181)
			(xy 127.114808 -278.441658) (xy 127.089546 -278.441166) (xy 127.03971 -278.432851) (xy 126.991923 -278.416447)
			(xy 126.947487 -278.3924) (xy 126.907616 -278.361368) (xy 126.873396 -278.324196) (xy 126.845761 -278.281899)
			(xy 126.825466 -278.23563) (xy 126.813062 -278.186652) (xy 126.80889 -278.1363) (xy 126.813062 -278.085948)
			(xy 126.825466 -278.03697) (xy 126.845761 -277.990701) (xy 126.873396 -277.948404) (xy 126.907616 -277.911232)
			(xy 126.947487 -277.8802) (xy 126.991923 -277.856153) (xy 127.03971 -277.839749) (xy 127.089546 -277.831434)
			(xy 127.114808 -277.831042) (xy 127.138575 -277.831489) (xy 127.185535 -277.838848) (xy 127.230785 -277.853401)
			(xy 127.273231 -277.874796) (xy 127.311844 -277.902516) (xy 127.34569 -277.93589) (xy 127.360172 -277.95474)
			(xy 127.362458 -277.957788) (xy 127.366474 -277.962151) (xy 127.376096 -277.969078) (xy 127.381508 -277.971504)
			(xy 127.38735 -277.974044) (xy 127.400558 -277.975822) (xy 127.493776 -277.96363) (xy 127.500454 -277.962588)
			(xy 127.512949 -277.957447) (xy 127.518414 -277.95347) (xy 127.524002 -277.949152) (xy 127.531876 -277.938484)
			(xy 127.534416 -277.93188) (xy 127.545518 -277.904643) (xy 127.572655 -277.852455) (xy 127.60513 -277.803411)
			(xy 127.62357 -277.780496) (xy 127.629158 -277.773638) (xy 127.632206 -277.765764) (xy 127.634492 -277.757636)
			(xy 127.635254 -277.748492) (xy 127.635254 -277.702772) (xy 127.63509 -277.696761) (xy 127.632274 -277.685075)
			(xy 127.629666 -277.679658) (xy 127.627824 -277.676186) (xy 127.623226 -277.669811) (xy 127.620522 -277.666958)
			(xy 127.60579 -277.652226) (xy 127.602465 -277.649113) (xy 127.594926 -277.644004) (xy 127.590804 -277.642066)
			(xy 127.566928 -277.631398) (xy 127.558292 -277.630636) (xy 127.533227 -277.627943) (xy 127.484406 -277.6154)
			(xy 127.438306 -277.595013) (xy 127.396178 -277.567334) (xy 127.359166 -277.533114) (xy 127.328273 -277.493283)
			(xy 127.304339 -277.44892) (xy 127.288013 -277.40123) (xy 127.279737 -277.351507) (xy 127.279736 -277.3011)
			(xy 127.288011 -277.251377) (xy 127.304336 -277.203687) (xy 127.328269 -277.159324) (xy 127.35916 -277.119491)
			(xy 127.396172 -277.085271) (xy 127.438299 -277.057591) (xy 127.484399 -277.037202) (xy 127.53322 -277.024658)
			(xy 127.558292 -277.022052) (xy 127.566928 -277.02129) (xy 127.590804 -277.010622) (xy 127.594924 -277.008682)
			(xy 127.602455 -277.003564) (xy 127.60579 -277.000462) (xy 127.620776 -276.985476) (xy 127.625753 -276.980044)
			(xy 127.632595 -276.967004) (xy 127.634238 -276.959822) (xy 127.634238 -276.959314) (xy 127.635254 -276.949916)
			(xy 127.635254 -276.92096) (xy 127.635055 -276.914294) (xy 127.631574 -276.901424) (xy 127.628396 -276.89556)
			(xy 127.571246 -276.797262) (xy 127.560776 -276.778782) (xy 127.542341 -276.740514) (xy 127.534416 -276.720808)
			(xy 127.531622 -276.71395) (xy 127.524002 -276.703536) (xy 127.518414 -276.699218) (xy 127.513746 -276.695778)
			(xy 127.50323 -276.690895) (xy 127.497586 -276.689566) (xy 127.404876 -276.677374) (xy 127.398771 -276.677063)
			(xy 127.386701 -276.67898) (xy 127.381 -276.681184) (xy 127.375158 -276.683724) (xy 127.364998 -276.691852)
			(xy 127.360426 -276.697948) (xy 127.345897 -276.71678) (xy 127.311993 -276.750137) (xy 127.273335 -276.777845)
			(xy 127.230855 -276.799237) (xy 127.185576 -276.813797) (xy 127.138589 -276.821174) (xy 127.114808 -276.821646)
			(xy 127.089547 -276.821154) (xy 127.039713 -276.812839) (xy 126.991928 -276.796436) (xy 126.947494 -276.77239)
			(xy 126.907624 -276.741359) (xy 126.873406 -276.704189) (xy 126.845772 -276.661894) (xy 126.825477 -276.615627)
			(xy 126.813074 -276.56665) (xy 126.808902 -276.5163) (xy 126.813074 -276.46595) (xy 126.825477 -276.416973)
			(xy 126.845772 -276.370706) (xy 126.873406 -276.328411) (xy 126.907624 -276.291241) (xy 126.947494 -276.26021)
			(xy 126.991928 -276.236164) (xy 127.039713 -276.219761) (xy 127.089547 -276.211446) (xy 127.114808 -276.21103)
			(xy 127.138575 -276.211477) (xy 127.185535 -276.218835) (xy 127.230786 -276.233388) (xy 127.273232 -276.254783)
			(xy 127.311846 -276.282502) (xy 127.345694 -276.315875) (xy 127.360172 -276.334728) (xy 127.362458 -276.337776)
			(xy 127.366474 -276.34214) (xy 127.376095 -276.349068) (xy 127.381508 -276.351492) (xy 127.38735 -276.354032)
			(xy 127.400558 -276.35581) (xy 127.493776 -276.343618) (xy 127.500454 -276.342576) (xy 127.512948 -276.337433)
			(xy 127.518414 -276.333458) (xy 127.524002 -276.32914) (xy 127.531876 -276.318472) (xy 127.534416 -276.311868)
			(xy 127.545519 -276.284631) (xy 127.572657 -276.232444) (xy 127.605132 -276.1834) (xy 127.62357 -276.160484)
			(xy 127.629158 -276.153626) (xy 127.632206 -276.145752) (xy 127.634492 -276.137624) (xy 127.635254 -276.12848)
			(xy 127.635254 -276.08276) (xy 127.635089 -276.07675) (xy 127.63227 -276.065065) (xy 127.629666 -276.059646)
			(xy 127.627823 -276.056174) (xy 127.623224 -276.049801) (xy 127.620522 -276.046946) (xy 127.60579 -276.032214)
			(xy 127.602464 -276.029102) (xy 127.594925 -276.023993) (xy 127.590804 -276.022054) (xy 127.566928 -276.011386)
			(xy 127.558292 -276.010624) (xy 127.533228 -276.007931) (xy 127.484409 -275.995389) (xy 127.43831 -275.975002)
			(xy 127.396184 -275.947324) (xy 127.359174 -275.913105) (xy 127.328283 -275.873275) (xy 127.30435 -275.828915)
			(xy 127.288024 -275.781227) (xy 127.279749 -275.731505) (xy 127.279748 -275.6811) (xy 127.288023 -275.631379)
			(xy 127.304348 -275.583691) (xy 127.32828 -275.539329) (xy 127.35917 -275.499499) (xy 127.39618 -275.46528)
			(xy 127.438305 -275.437601) (xy 127.484403 -275.417213) (xy 127.533223 -275.40467) (xy 127.558292 -275.40204)
			(xy 127.566928 -275.401278) (xy 127.590804 -275.39061) (xy 127.594927 -275.388673) (xy 127.602464 -275.383562)
			(xy 127.60579 -275.38045) (xy 127.620776 -275.365464) (xy 127.625752 -275.360031) (xy 127.632591 -275.346991)
			(xy 127.634238 -275.33981) (xy 127.634238 -275.339302) (xy 127.635254 -275.329904) (xy 127.635254 -275.300948)
			(xy 127.635054 -275.294282) (xy 127.63157 -275.281414) (xy 127.628396 -275.275548) (xy 127.571246 -275.17725)
			(xy 127.560776 -275.15877) (xy 127.542343 -275.120501) (xy 127.534416 -275.100796) (xy 127.531622 -275.093938)
			(xy 127.524002 -275.083524) (xy 127.518414 -275.079206) (xy 127.513745 -275.075767) (xy 127.50323 -275.070885)
			(xy 127.497586 -275.069554) (xy 127.404876 -275.057362) (xy 127.398771 -275.057051) (xy 127.386701 -275.058967)
			(xy 127.381 -275.061172) (xy 127.375158 -275.063712) (xy 127.364998 -275.07184) (xy 127.360426 -275.077936)
			(xy 127.345894 -275.096764) (xy 127.311986 -275.130111) (xy 127.273327 -275.157812) (xy 127.230847 -275.179197)
			(xy 127.185571 -275.193752) (xy 127.138587 -275.201127) (xy 127.114808 -275.201634) (xy 127.089548 -275.201142)
			(xy 127.039716 -275.192828) (xy 126.991932 -275.176425) (xy 126.9475 -275.15238) (xy 126.907632 -275.121351)
			(xy 126.873415 -275.084182) (xy 126.845782 -275.041888) (xy 126.825488 -274.995623) (xy 126.813086 -274.946648)
			(xy 126.808914 -274.8963) (xy 126.813086 -274.845952) (xy 126.825488 -274.796977) (xy 126.845782 -274.750712)
			(xy 126.873415 -274.708418) (xy 126.907632 -274.671249) (xy 126.9475 -274.64022) (xy 126.991932 -274.616175)
			(xy 127.039716 -274.599772) (xy 127.089548 -274.591458) (xy 127.114808 -274.591018) (xy 127.138575 -274.591465)
			(xy 127.185536 -274.598823) (xy 127.230787 -274.613375) (xy 127.273233 -274.63477) (xy 127.311848 -274.662489)
			(xy 127.345697 -274.695861) (xy 127.360172 -274.714716) (xy 127.362458 -274.717764) (xy 127.366478 -274.722122)
			(xy 127.376104 -274.72904) (xy 127.381508 -274.73148) (xy 127.38735 -274.73402) (xy 127.400558 -274.735798)
			(xy 127.493776 -274.723606) (xy 127.500454 -274.722564) (xy 127.512947 -274.71742) (xy 127.518414 -274.713446)
			(xy 127.524002 -274.709128) (xy 127.531876 -274.69846) (xy 127.534416 -274.691856) (xy 127.545519 -274.664619)
			(xy 127.572658 -274.612433) (xy 127.605134 -274.56339) (xy 127.62357 -274.540472) (xy 127.629158 -274.533614)
			(xy 127.632206 -274.52574) (xy 127.634492 -274.517612) (xy 127.635254 -274.508468) (xy 127.635254 -274.462748)
			(xy 127.635087 -274.456738) (xy 127.632266 -274.445055) (xy 127.629666 -274.439634) (xy 127.627828 -274.436159)
			(xy 127.623237 -274.429777) (xy 127.620522 -274.426934) (xy 127.60579 -274.412202) (xy 127.602467 -274.409086)
			(xy 127.594931 -274.403969) (xy 127.590804 -274.402042) (xy 127.566928 -274.391374) (xy 127.558292 -274.390612)
			(xy 127.533229 -274.387919) (xy 127.484412 -274.375377) (xy 127.438315 -274.354991) (xy 127.396191 -274.327314)
			(xy 127.359182 -274.293097) (xy 127.328292 -274.253268) (xy 127.30436 -274.208909) (xy 127.288035 -274.161223)
			(xy 127.279761 -274.111503) (xy 127.27976 -274.0611) (xy 127.288035 -274.011381) (xy 127.304359 -273.963694)
			(xy 127.32829 -273.919335) (xy 127.359179 -273.879506) (xy 127.396188 -273.845288) (xy 127.438312 -273.817611)
			(xy 127.484408 -273.797224) (xy 127.533226 -273.784682) (xy 127.558292 -273.782028) (xy 127.566928 -273.781266)
			(xy 127.590804 -273.770598) (xy 127.594926 -273.768661) (xy 127.602463 -273.763549) (xy 127.60579 -273.760438)
			(xy 127.620776 -273.745452) (xy 127.625751 -273.740019) (xy 127.632586 -273.726978) (xy 127.634238 -273.719798)
			(xy 127.634238 -273.71929) (xy 127.635254 -273.709892) (xy 127.635254 -273.680936) (xy 127.635065 -273.674267)
			(xy 127.631601 -273.661387) (xy 127.628396 -273.655536) (xy 127.571246 -273.557238) (xy 127.560777 -273.538758)
			(xy 127.542344 -273.500489) (xy 127.534416 -273.480784) (xy 127.531622 -273.473926) (xy 127.524002 -273.463512)
			(xy 127.518414 -273.459194) (xy 127.513745 -273.455755) (xy 127.503229 -273.450875) (xy 127.497586 -273.449542)
			(xy 127.404876 -273.43735) (xy 127.398771 -273.437039) (xy 127.386701 -273.438955) (xy 127.381 -273.44116)
			(xy 127.375158 -273.4437) (xy 127.364998 -273.451828) (xy 127.360426 -273.457924) (xy 127.345894 -273.476752)
			(xy 127.311987 -273.510101) (xy 127.273328 -273.537803) (xy 127.230848 -273.559189) (xy 127.185571 -273.573745)
			(xy 127.138587 -273.58112) (xy 127.114808 -273.581622) (xy 127.089549 -273.58113) (xy 127.039719 -273.572816)
			(xy 126.991937 -273.556414) (xy 126.947507 -273.53237) (xy 126.90764 -273.501342) (xy 126.873425 -273.464174)
			(xy 126.845793 -273.421882) (xy 126.8255 -273.375619) (xy 126.813098 -273.326646) (xy 126.808926 -273.2763)
			(xy 126.813098 -273.225954) (xy 126.8255 -273.176981) (xy 126.845793 -273.130718) (xy 126.873425 -273.088426)
			(xy 126.90764 -273.051258) (xy 126.947507 -273.02023) (xy 126.991937 -272.996186) (xy 127.039719 -272.979784)
			(xy 127.089549 -272.97147) (xy 127.114808 -272.971006) (xy 127.138575 -272.971453) (xy 127.185536 -272.978811)
			(xy 127.230788 -272.993363) (xy 127.273235 -273.014757) (xy 127.311851 -273.042475) (xy 127.3457 -273.075846)
			(xy 127.360172 -273.094704) (xy 127.362458 -273.097752) (xy 127.366477 -273.102111) (xy 127.376103 -273.10903)
			(xy 127.381508 -273.111468) (xy 127.38735 -273.114008) (xy 127.400558 -273.115786) (xy 127.493776 -273.103594)
			(xy 127.500454 -273.102552) (xy 127.512947 -273.097407) (xy 127.518414 -273.093434) (xy 127.524002 -273.089116)
			(xy 127.531876 -273.078448) (xy 127.534416 -273.071844) (xy 127.54552 -273.044607) (xy 127.572659 -272.992422)
			(xy 127.605136 -272.94338) (xy 127.62357 -272.92046) (xy 127.629158 -272.913602) (xy 127.632206 -272.905728)
			(xy 127.634492 -272.8976) (xy 127.635254 -272.888456) (xy 127.635254 -272.842736) (xy 127.635086 -272.836727)
			(xy 127.632262 -272.825044) (xy 127.629666 -272.819622) (xy 127.627828 -272.816147) (xy 127.623236 -272.809767)
			(xy 127.620522 -272.806922) (xy 127.60579 -272.79219) (xy 127.602467 -272.789074) (xy 127.594931 -272.783959)
			(xy 127.590804 -272.78203) (xy 127.566928 -272.771362) (xy 127.558292 -272.7706) (xy 127.53323 -272.767907)
			(xy 127.484415 -272.755365) (xy 127.43832 -272.73498) (xy 127.396197 -272.707304) (xy 127.35919 -272.673088)
			(xy 127.328302 -272.633261) (xy 127.304371 -272.588903) (xy 127.288047 -272.541219) (xy 127.279772 -272.491501)
			(xy 127.279772 -272.4411) (xy 127.288046 -272.391383) (xy 127.30437 -272.343698) (xy 127.328301 -272.299341)
			(xy 127.359189 -272.259513) (xy 127.396196 -272.225297) (xy 127.438319 -272.197621) (xy 127.484413 -272.177235)
			(xy 127.533229 -272.164693) (xy 127.558292 -272.162016) (xy 127.566928 -272.161254) (xy 127.590804 -272.150586)
			(xy 127.594926 -272.148649) (xy 127.602462 -272.143535) (xy 127.60579 -272.140426) (xy 127.620776 -272.12544)
			(xy 127.625749 -272.120006) (xy 127.632582 -272.106964) (xy 127.634238 -272.099786) (xy 127.634238 -272.099278)
			(xy 127.635254 -272.08988) (xy 127.635254 -272.060924) (xy 127.635063 -272.054255) (xy 127.631596 -272.041377)
			(xy 127.628396 -272.035524) (xy 127.571246 -271.937226) (xy 127.560777 -271.918746) (xy 127.542345 -271.880476)
			(xy 127.534416 -271.860772) (xy 127.531622 -271.853914) (xy 127.524002 -271.8435) (xy 127.518414 -271.839182)
			(xy 127.513745 -271.835744) (xy 127.503228 -271.830865) (xy 127.497586 -271.82953) (xy 127.404876 -271.817338)
			(xy 127.398771 -271.817027) (xy 127.386701 -271.818943) (xy 127.381 -271.821148) (xy 127.375158 -271.823688)
			(xy 127.364998 -271.831816) (xy 127.360426 -271.837912) (xy 127.345895 -271.856741) (xy 127.311988 -271.890091)
			(xy 127.273329 -271.917794) (xy 127.230849 -271.939181) (xy 127.185572 -271.953737) (xy 127.138588 -271.961113)
			(xy 127.114808 -271.96161) (xy 127.08955 -271.961118) (xy 127.039722 -271.952804) (xy 126.991942 -271.936403)
			(xy 126.947514 -271.91236) (xy 126.907648 -271.881333) (xy 126.873434 -271.844167) (xy 126.845804 -271.801876)
			(xy 126.825511 -271.755615) (xy 126.81311 -271.706644) (xy 126.808938 -271.6563) (xy 126.81311 -271.605956)
			(xy 126.825511 -271.556985) (xy 126.845804 -271.510724) (xy 126.873434 -271.468433) (xy 126.907648 -271.431267)
			(xy 126.947514 -271.40024) (xy 126.991942 -271.376197) (xy 127.039722 -271.359796) (xy 127.08955 -271.351482)
			(xy 127.114808 -271.350994) (xy 127.138575 -271.351441) (xy 127.185536 -271.358799) (xy 127.230788 -271.37335)
			(xy 127.273236 -271.394743) (xy 127.311853 -271.422461) (xy 127.345703 -271.455832) (xy 127.360172 -271.474692)
			(xy 127.362458 -271.47774) (xy 127.366477 -271.4821) (xy 127.376101 -271.48902) (xy 127.381508 -271.491456)
			(xy 127.38735 -271.493996) (xy 127.400558 -271.495774) (xy 127.493776 -271.483582) (xy 127.500454 -271.482539)
			(xy 127.512945 -271.477393) (xy 127.518414 -271.473422) (xy 127.524002 -271.469104) (xy 127.531876 -271.458436)
			(xy 127.534416 -271.451832) (xy 127.54552 -271.424596) (xy 127.572661 -271.372411) (xy 127.605138 -271.323369)
			(xy 127.62357 -271.300448) (xy 127.629158 -271.29359) (xy 127.632206 -271.285716) (xy 127.634492 -271.277588)
			(xy 127.635254 -271.268444) (xy 127.635254 -271.222724) (xy 127.635085 -271.216715) (xy 127.632258 -271.205034)
			(xy 127.629666 -271.19961) (xy 127.627827 -271.196136) (xy 127.623234 -271.189756) (xy 127.620522 -271.18691)
			(xy 127.60579 -271.172178) (xy 127.602467 -271.169063) (xy 127.59493 -271.163948) (xy 127.590804 -271.162018)
			(xy 127.566928 -271.15135) (xy 127.558292 -271.150588) (xy 127.533231 -271.147895) (xy 127.484417 -271.135354)
			(xy 127.438325 -271.114969) (xy 127.396204 -271.087294) (xy 127.359198 -271.053079) (xy 127.328311 -271.013253)
			(xy 127.304381 -270.968897) (xy 127.288058 -270.921215) (xy 127.279784 -270.871499) (xy 127.279784 -270.8211)
			(xy 127.288058 -270.771385) (xy 127.304382 -270.723702) (xy 127.328312 -270.679346) (xy 127.359199 -270.639521)
			(xy 127.396205 -270.605306) (xy 127.438325 -270.577631) (xy 127.484418 -270.557246) (xy 127.533232 -270.544705)
			(xy 127.558292 -270.542004) (xy 127.566928 -270.541242) (xy 127.590804 -270.530574) (xy 127.594925 -270.528636)
			(xy 127.60246 -270.523522) (xy 127.60579 -270.520414) (xy 127.620776 -270.505428) (xy 127.625748 -270.499994)
			(xy 127.632578 -270.486951) (xy 127.634238 -270.479774) (xy 127.634238 -270.479266) (xy 127.635254 -270.469868)
			(xy 127.635254 -270.440912) (xy 127.635062 -270.434244) (xy 127.631592 -270.421367) (xy 127.628396 -270.415512)
			(xy 127.571246 -270.317214) (xy 127.560777 -270.298734) (xy 127.542346 -270.260464) (xy 127.534416 -270.24076)
			(xy 127.531622 -270.233902) (xy 127.524002 -270.223488) (xy 127.518414 -270.21917) (xy 127.513744 -270.215733)
			(xy 127.503228 -270.210855) (xy 127.497586 -270.209518) (xy 127.404876 -270.197326) (xy 127.398771 -270.197015)
			(xy 127.386701 -270.19893) (xy 127.381 -270.201136) (xy 127.375158 -270.203676) (xy 127.364998 -270.211804)
			(xy 127.360426 -270.2179) (xy 127.345895 -270.236729) (xy 127.311989 -270.270081) (xy 127.27333 -270.297785)
			(xy 127.23085 -270.319172) (xy 127.185573 -270.33373) (xy 127.138588 -270.341105) (xy 127.114808 -270.341598)
			(xy 127.089551 -270.341106) (xy 127.039725 -270.332793) (xy 126.991947 -270.316392) (xy 126.94752 -270.29235)
			(xy 126.907657 -270.261324) (xy 126.873443 -270.22416) (xy 126.845814 -270.181871) (xy 126.825522 -270.135611)
			(xy 126.813122 -270.086642) (xy 126.80895 -270.0363) (xy 126.813122 -269.985958) (xy 126.825522 -269.936989)
			(xy 126.845814 -269.890729) (xy 126.873443 -269.84844) (xy 126.907657 -269.811276) (xy 126.94752 -269.78025)
			(xy 126.991947 -269.756208) (xy 127.039725 -269.739807) (xy 127.089551 -269.731494) (xy 127.114808 -269.730982)
			(xy 127.138575 -269.731429) (xy 127.185537 -269.738786) (xy 127.230789 -269.753337) (xy 127.273238 -269.77473)
			(xy 127.311855 -269.802447) (xy 127.345707 -269.835817) (xy 127.360172 -269.85468) (xy 127.362458 -269.857728)
			(xy 127.366476 -269.862089) (xy 127.3761 -269.869011) (xy 127.381508 -269.871444) (xy 127.38735 -269.873984)
			(xy 127.400558 -269.875762) (xy 127.493776 -269.86357) (xy 127.500453 -269.862527) (xy 127.512945 -269.85738)
			(xy 127.518414 -269.85341) (xy 127.524002 -269.849092) (xy 127.531876 -269.838424) (xy 127.534416 -269.83182)
			(xy 127.545521 -269.804584) (xy 127.572662 -269.7524) (xy 127.60514 -269.703359) (xy 127.62357 -269.680436)
			(xy 127.629158 -269.673578) (xy 127.632206 -269.665704) (xy 127.634492 -269.657576) (xy 127.635254 -269.648432)
			(xy 127.635254 -269.602712) (xy 127.635083 -269.596703) (xy 127.632254 -269.585024) (xy 127.629666 -269.579598)
			(xy 127.627826 -269.576124) (xy 127.623232 -269.569746) (xy 127.620522 -269.566898) (xy 127.60579 -269.552166)
			(xy 127.603758 -269.550388) (xy 127.58547 -269.550388) (xy 127.584708 -269.550388) (xy 127.583184 -269.550388)
			(xy 127.563626 -269.549626) (xy 127.538078 -269.547469) (xy 127.488085 -269.536106) (xy 127.440509 -269.517002)
			(xy 127.39654 -269.490636) (xy 127.357278 -269.457667) (xy 127.340106 -269.438628) (xy 127.337058 -269.43558)
			(xy 127.323596 -269.425674) (xy 127.31369 -269.419832) (xy 127.032766 -269.295626) (xy 127.022791 -269.29061)
			(xy 127.008109 -269.273824) (xy 127.001924 -269.252398) (xy 127.005399 -269.23037) (xy 127.017881 -269.211889)
			(xy 127.027178 -269.20571) (xy 127.323342 -269.027402) (xy 127.3302 -269.022322) (xy 127.336296 -269.016988)
			(xy 127.341376 -269.012162) (xy 127.359159 -268.992773) (xy 127.399878 -268.959463) (xy 127.422402 -268.945868)
			(xy 127.430558 -268.940757) (xy 127.442567 -268.925735) (xy 127.44577 -268.916658) (xy 127.447548 -268.90726)
			(xy 127.453644 -268.850872) (xy 127.453708 -268.841106) (xy 127.447313 -268.822672) (xy 127.441198 -268.815058)
			(xy 127.319532 -268.693392) (xy 127.318516 -268.69263) (xy 127.3175 -268.691614) (xy 127.295338 -268.707281)
			(xy 127.247098 -268.732143) (xy 127.195534 -268.749068) (xy 127.141943 -268.757631) (xy 127.114808 -268.758162)
			(xy 127.087941 -268.757663) (xy 127.034868 -268.749258) (xy 126.983763 -268.732653) (xy 126.935885 -268.708258)
			(xy 126.892413 -268.676673) (xy 126.854418 -268.638676) (xy 126.822835 -268.595203) (xy 126.798441 -268.547324)
			(xy 126.781839 -268.496219) (xy 126.773436 -268.443145) (xy 126.772924 -268.416278) (xy 126.772924 -268.41577)
			(xy 126.773587 -268.386059) (xy 126.783896 -268.327538) (xy 126.804146 -268.271672) (xy 126.81839 -268.24559)
			(xy 126.823466 -268.235637) (xy 126.825382 -268.213404) (xy 126.817719 -268.192445) (xy 126.810262 -268.184122)
			(xy 126.503176 -267.877036) (xy 126.496826 -267.87348) (xy 126.472172 -267.859105) (xy 126.428243 -267.822686)
			(xy 126.391838 -267.778745) (xy 126.377446 -267.7541) (xy 126.37389 -267.74775) (xy 125.990096 -267.363956)
			(xy 125.987246 -267.361249) (xy 125.980868 -267.356655) (xy 125.977396 -267.354812) (xy 125.97197 -267.352224)
			(xy 125.960291 -267.349391) (xy 125.954282 -267.349224) (xy 125.139196 -267.349224) (xy 125.126641 -267.349867)
			(xy 125.10451 -267.361725) (xy 125.097032 -267.37183) (xy 125.055122 -267.434568) (xy 125.053852 -267.4366)
			(xy 125.051799 -267.440177) (xy 125.048739 -267.447835) (xy 125.047756 -267.45184) (xy 125.047756 -267.452348)
			(xy 125.046486 -267.462762) (xy 125.046486 -267.488162) (xy 125.049788 -267.497052) (xy 125.059157 -267.523122)
			(xy 125.069381 -267.577563) (xy 125.070108 -267.605256) (xy 125.070108 -267.606272) (xy 125.069664 -267.630267)
			(xy 125.062161 -267.677665) (xy 125.047335 -267.723307) (xy 125.025551 -267.766067) (xy 124.997346 -267.804892)
			(xy 124.963414 -267.838827) (xy 124.924591 -267.867036) (xy 124.881833 -267.888824) (xy 124.836193 -267.903654)
			(xy 124.788795 -267.911162) (xy 124.7648 -267.91158) (xy 124.740946 -267.91112) (xy 124.693819 -267.903702)
			(xy 124.648419 -267.889044) (xy 124.60585 -267.867505) (xy 124.567149 -267.839609) (xy 124.533257 -267.806033)
			(xy 124.504998 -267.767595) (xy 124.483061 -267.725231) (xy 124.467978 -267.67997) (xy 124.460117 -267.632915)
			(xy 124.459492 -267.609066) (xy 124.459492 -267.606018) (xy 124.460229 -267.575808) (xy 124.472134 -267.51657)
			(xy 124.483114 -267.488416) (xy 124.4854 -267.483336) (xy 124.485654 -267.482574) (xy 124.487432 -267.469874)
			(xy 124.486924 -267.464032) (xy 124.486134 -267.458391) (xy 124.482407 -267.44763) (xy 124.479558 -267.442696)
			(xy 124.455428 -267.406374) (xy 124.432568 -267.372084) (xy 124.425456 -267.363194) (xy 124.419095 -267.357577)
			(xy 124.403646 -267.35058) (xy 124.39523 -267.349478) (xy 124.390404 -267.349224) (xy 124.146818 -267.349224)
			(xy 124.136981 -267.348687) (xy 124.118821 -267.341099) (xy 124.111512 -267.334492) (xy 123.748546 -266.971526)
			(xy 123.74114 -266.964832) (xy 123.722704 -266.957229) (xy 123.712732 -266.956794) (xy 123.709684 -266.956794)
			(xy 123.635008 -266.961874) (xy 123.625903 -266.962856) (xy 123.609235 -266.970406) (xy 123.602496 -266.976606)
			(xy 123.597416 -266.981686) (xy 123.595638 -266.983972) (xy 123.581183 -267.001846) (xy 123.547811 -267.033461)
			(xy 123.510077 -267.059715) (xy 123.468834 -267.080016) (xy 123.425013 -267.093905) (xy 123.379606 -267.101067)
			(xy 123.356624 -267.101574) (xy 123.354846 -267.101574) (xy 123.330398 -267.101088) (xy 123.282127 -267.093287)
			(xy 123.235715 -267.077895) (xy 123.19235 -267.055303) (xy 123.153139 -267.02609) (xy 123.119084 -266.991002)
			(xy 123.091056 -266.950935) (xy 123.06977 -266.906914) (xy 123.055771 -266.860064) (xy 123.052078 -266.83589)
			(xy 123.049792 -266.819126) (xy 123.049538 -266.81303) (xy 123.049538 -266.796774) (xy 123.049949 -266.773154)
			(xy 123.057157 -266.726469) (xy 123.071459 -266.681448) (xy 123.092515 -266.639162) (xy 123.119824 -266.600618)
			(xy 123.152736 -266.566732) (xy 123.190468 -266.538311) (xy 123.211082 -266.526772) (xy 123.217686 -266.523216)
			(xy 123.224798 -266.516104) (xy 123.230982 -266.508614) (xy 123.237715 -266.490412) (xy 123.23722 -266.471011)
			(xy 123.229567 -266.453176) (xy 123.22302 -266.446) (xy 123.196096 -266.419076) (xy 123.193246 -266.416369)
			(xy 123.186869 -266.411773) (xy 123.183396 -266.409932) (xy 123.17797 -266.407343) (xy 123.166291 -266.404509)
			(xy 123.160282 -266.404344) (xy 122.318526 -266.404344) (xy 122.312517 -266.404513) (xy 122.300836 -266.407339)
			(xy 122.295412 -266.409932) (xy 122.291937 -266.411771) (xy 122.285558 -266.416364) (xy 122.282712 -266.419076)
			(xy 121.70664 -266.995148) (xy 121.70537 -266.996672) (xy 121.68632 -267.016738) (xy 121.685812 -267.017246)
			(xy 121.675652 -267.02639) (xy 121.673112 -267.028676) (xy 121.433336 -267.268452) (xy 121.426098 -267.275168)
			(xy 121.407894 -267.282773) (xy 121.39803 -267.283184) (xy 121.343928 -267.283184) (xy 121.336197 -267.28345)
			(xy 121.321454 -267.288106) (xy 121.314972 -267.292328) (xy 121.311051 -267.295165) (xy 121.304271 -267.30207)
			(xy 121.30151 -267.306044) (xy 121.299224 -267.309854) (xy 121.266204 -267.371322) (xy 121.263385 -267.376952)
			(xy 121.260313 -267.389158) (xy 121.260108 -267.395452) (xy 121.260108 -267.417804) (xy 121.261886 -267.431012)
			(xy 121.26722 -267.449808) (xy 121.270268 -267.455396) (xy 121.282792 -267.47855) (xy 121.300565 -267.528095)
			(xy 121.309579 -267.579954) (xy 121.310146 -267.606272) (xy 122.578888 -267.606272) (xy 122.582848 -267.557218)
			(xy 122.594625 -267.509434) (xy 122.613916 -267.464158) (xy 122.640219 -267.422562) (xy 122.672854 -267.385725)
			(xy 122.710975 -267.3546) (xy 122.753596 -267.329993) (xy 122.799612 -267.312541) (xy 122.847831 -267.302697)
			(xy 122.897006 -267.300716) (xy 122.945861 -267.306648) (xy 122.993132 -267.32034) (xy 123.037594 -267.341438)
			(xy 123.078097 -267.369394) (xy 123.11359 -267.403486) (xy 123.143155 -267.44283) (xy 123.166026 -267.486407)
			(xy 123.18161 -267.533088) (xy 123.189505 -267.581665) (xy 123.19 -267.606272) (xy 123.189505 -267.630879)
			(xy 123.18161 -267.679456) (xy 123.166026 -267.726137) (xy 123.143155 -267.769714) (xy 123.11359 -267.809058)
			(xy 123.078097 -267.84315) (xy 123.037594 -267.871106) (xy 122.993132 -267.892204) (xy 122.945861 -267.905896)
			(xy 122.897006 -267.911828) (xy 122.847831 -267.909847) (xy 122.799612 -267.900003) (xy 122.753596 -267.882551)
			(xy 122.710975 -267.857944) (xy 122.672854 -267.826819) (xy 122.640219 -267.789982) (xy 122.613916 -267.748386)
			(xy 122.594625 -267.70311) (xy 122.582848 -267.655326) (xy 122.578888 -267.606272) (xy 121.310146 -267.606272)
			(xy 121.310146 -267.611098) (xy 121.309321 -267.634841) (xy 121.301225 -267.681652) (xy 121.285976 -267.726644)
			(xy 121.263942 -267.76873) (xy 121.235655 -267.806896) (xy 121.201797 -267.840219) (xy 121.163186 -267.867895)
			(xy 121.120754 -267.889257) (xy 121.075525 -267.903787) (xy 121.028591 -267.911136) (xy 121.004838 -267.91158)
			(xy 120.982054 -267.911161) (xy 120.936991 -267.904395) (xy 120.893434 -267.891009) (xy 120.852349 -267.871299)
			(xy 120.81465 -267.845702) (xy 120.781172 -267.814788) (xy 120.766586 -267.79728) (xy 120.755664 -267.783818)
			(xy 120.751854 -267.777976) (xy 120.743472 -267.764006) (xy 120.743218 -267.763752) (xy 120.742964 -267.763244)
			(xy 120.73494 -267.749469) (xy 120.721454 -267.72058) (xy 120.71604 -267.705586) (xy 120.71154 -267.691978)
			(xy 120.704802 -267.664119) (xy 120.702578 -267.64996) (xy 120.701308 -267.64107) (xy 120.700358 -267.632402)
			(xy 120.699338 -267.614992) (xy 120.699276 -267.606272) (xy 120.699692 -267.584116) (xy 120.706128 -267.540273)
			(xy 120.718818 -267.497816) (xy 120.737498 -267.457633) (xy 120.749314 -267.438886) (xy 120.751092 -267.436346)
			(xy 120.754055 -267.430943) (xy 120.757528 -267.419125) (xy 120.75795 -267.412978) (xy 120.758458 -267.399516)
			(xy 120.710452 -267.310108) (xy 120.705821 -267.302186) (xy 120.69207 -267.290058) (xy 120.674916 -267.283584)
			(xy 120.665748 -267.283184) (xy 120.250458 -267.283184) (xy 120.240619 -267.282653) (xy 120.222452 -267.275071)
			(xy 120.215152 -267.268452) (xy 119.955564 -267.008864) (xy 119.944388 -267.000482) (xy 119.93753 -266.99718)
			(xy 119.934019 -266.995971) (xy 119.926752 -266.994445) (xy 119.923052 -266.994132) (xy 119.885714 -266.994386)
			(xy 119.858028 -266.99464) (xy 119.853125 -266.994821) (xy 119.843531 -266.996874) (xy 119.838978 -266.998704)
			(xy 119.813832 -267.009118) (xy 119.806974 -267.015722) (xy 119.789784 -267.031738) (xy 119.751404 -267.058835)
			(xy 119.709328 -267.079738) (xy 119.664549 -267.093954) (xy 119.618121 -267.10115) (xy 119.59463 -267.101574)
			(xy 119.570762 -267.101116) (xy 119.523607 -267.093693) (xy 119.478182 -267.079023) (xy 119.435592 -267.057463)
			(xy 119.396876 -267.029539) (xy 119.362977 -266.995931) (xy 119.33472 -266.957458) (xy 119.312793 -266.915056)
			(xy 119.297732 -266.869759) (xy 119.289902 -266.82267) (xy 119.289322 -266.798806) (xy 119.289322 -266.796012)
			(xy 119.289792 -266.771668) (xy 119.297524 -266.723598) (xy 119.312811 -266.677372) (xy 119.323612 -266.65555)
			(xy 119.328946 -266.64539) (xy 119.329962 -266.643358) (xy 119.329454 -266.630404) (xy 119.329071 -266.624831)
			(xy 119.326117 -266.614061) (xy 119.323612 -266.609068) (xy 119.276114 -266.530074) (xy 119.273066 -266.526264)
			(xy 119.272558 -266.525756) (xy 119.265229 -266.518215) (xy 119.246212 -266.509288) (xy 119.235728 -266.508484)
			(xy 118.439946 -266.508484) (xy 118.433936 -266.508652) (xy 118.422254 -266.511475) (xy 118.416832 -266.514072)
			(xy 118.413355 -266.515908) (xy 118.40697 -266.520495) (xy 118.404132 -266.523216) (xy 117.98046 -266.946888)
			(xy 117.977158 -266.952476) (xy 117.96379 -266.973963) (xy 117.931092 -267.012582) (xy 117.892474 -267.045282)
			(xy 117.870986 -267.058648) (xy 117.865398 -267.06195) (xy 117.618256 -267.309092) (xy 117.613542 -267.31355)
			(xy 117.60235 -267.320106) (xy 117.596158 -267.322046) (xy 117.586252 -267.32484) (xy 117.57914 -267.330174)
			(xy 117.575688 -267.332875) (xy 117.569682 -267.33926) (xy 117.567202 -267.342874) (xy 117.52453 -267.41247)
			(xy 117.522523 -267.416115) (xy 117.519592 -267.423902) (xy 117.518688 -267.427964) (xy 117.517672 -267.43787)
			(xy 117.517672 -267.457682) (xy 117.517833 -267.463201) (xy 117.520257 -267.473972) (xy 117.522498 -267.479018)
			(xy 117.522498 -267.479272) (xy 117.531215 -267.499299) (xy 117.543527 -267.541205) (xy 117.549762 -267.584434)
			(xy 117.550184 -267.606272) (xy 118.818926 -267.606272) (xy 118.822886 -267.557218) (xy 118.834663 -267.509434)
			(xy 118.853954 -267.464158) (xy 118.880257 -267.422562) (xy 118.912892 -267.385725) (xy 118.951013 -267.3546)
			(xy 118.993634 -267.329993) (xy 119.03965 -267.312541) (xy 119.087869 -267.302697) (xy 119.137044 -267.300716)
			(xy 119.185899 -267.306648) (xy 119.23317 -267.32034) (xy 119.277632 -267.341438) (xy 119.318135 -267.369394)
			(xy 119.353628 -267.403486) (xy 119.383193 -267.44283) (xy 119.406064 -267.486407) (xy 119.421648 -267.533088)
			(xy 119.429543 -267.581665) (xy 119.430038 -267.606272) (xy 119.429543 -267.630879) (xy 119.421648 -267.679456)
			(xy 119.406064 -267.726137) (xy 119.383193 -267.769714) (xy 119.353628 -267.809058) (xy 119.318135 -267.84315)
			(xy 119.277632 -267.871106) (xy 119.23317 -267.892204) (xy 119.185899 -267.905896) (xy 119.137044 -267.911828)
			(xy 119.087869 -267.909847) (xy 119.03965 -267.900003) (xy 118.993634 -267.882551) (xy 118.951013 -267.857944)
			(xy 118.912892 -267.826819) (xy 118.880257 -267.789982) (xy 118.853954 -267.748386) (xy 118.834663 -267.70311)
			(xy 118.822886 -267.655326) (xy 118.818926 -267.606272) (xy 117.550184 -267.606272) (xy 117.550184 -267.60932)
			(xy 117.549676 -267.617956) (xy 117.54815 -267.643923) (xy 117.537371 -267.694806) (xy 117.518126 -267.743128)
			(xy 117.490973 -267.78749) (xy 117.456696 -267.826611) (xy 117.416287 -267.859359) (xy 117.370914 -267.884787)
			(xy 117.321888 -267.90216) (xy 117.270628 -267.910976) (xy 117.244622 -267.91158) (xy 117.220629 -267.911135)
			(xy 117.173232 -267.903631) (xy 117.127593 -267.888804) (xy 117.084836 -267.86702) (xy 117.046014 -267.838814)
			(xy 117.012082 -267.804882) (xy 116.983877 -267.766059) (xy 116.962093 -267.723301) (xy 116.947267 -267.677662)
			(xy 116.939764 -267.630265) (xy 116.939314 -267.606272) (xy 116.939314 -267.605764) (xy 116.93977 -267.582181)
			(xy 116.947053 -267.53558) (xy 116.96141 -267.490652) (xy 116.971572 -267.469366) (xy 116.971572 -267.469112)
			(xy 116.971826 -267.468858) (xy 116.97436 -267.463161) (xy 116.976933 -267.450963) (xy 116.976906 -267.444728)
			(xy 116.976398 -267.43152) (xy 116.923312 -267.34516) (xy 116.919978 -267.340743) (xy 116.911777 -267.333316)
			(xy 116.907056 -267.330428) (xy 116.904008 -267.328904) (xy 116.899266 -267.326725) (xy 116.88915 -267.324166)
			(xy 116.883942 -267.323824) (xy 116.473478 -267.323824) (xy 116.463636 -267.323297) (xy 116.44546 -267.315725)
			(xy 116.438172 -267.309092) (xy 116.165884 -267.036804) (xy 116.159426 -267.030889) (xy 116.143577 -267.023474)
			(xy 116.134896 -267.022326) (xy 116.09832 -267.020548) (xy 116.073174 -267.019278) (xy 116.06819 -267.019203)
			(xy 116.058342 -267.020741) (xy 116.053616 -267.022326) (xy 116.030756 -267.030454) (xy 116.024406 -267.035534)
			(xy 116.004013 -267.051027) (xy 115.959133 -267.075691) (xy 115.910768 -267.092526) (xy 115.860273 -267.10106)
			(xy 115.834668 -267.101574) (xy 115.830604 -267.101574) (xy 115.806819 -267.100808) (xy 115.75991 -267.09281)
			(xy 115.714811 -267.077631) (xy 115.672612 -267.055639) (xy 115.634337 -267.027365) (xy 115.600911 -266.993496)
			(xy 115.573146 -266.954851) (xy 115.551712 -266.912365) (xy 115.53713 -266.867069) (xy 115.529752 -266.820059)
			(xy 115.52936 -266.796266) (xy 115.529935 -266.76934) (xy 115.539396 -266.716324) (xy 115.548156 -266.690856)
			(xy 115.550188 -266.685268) (xy 115.55222 -266.680188) (xy 115.55476 -266.674092) (xy 115.557046 -266.663678)
			(xy 115.558678 -266.653674) (xy 115.554867 -266.63378) (xy 115.54968 -266.62507) (xy 115.517676 -266.57681)
			(xy 115.517676 -266.576302) (xy 115.503706 -266.554966) (xy 115.500404 -266.550902) (xy 115.493041 -266.543443)
			(xy 115.474027 -266.534674) (xy 115.463574 -266.533884) (xy 114.673126 -266.533884) (xy 114.667117 -266.534054)
			(xy 114.655437 -266.536882) (xy 114.650012 -266.539472) (xy 114.646536 -266.541309) (xy 114.640152 -266.545898)
			(xy 114.637312 -266.548616) (xy 113.904776 -267.281152) (xy 113.897535 -267.287859) (xy 113.879331 -267.295442)
			(xy 113.86947 -267.295884) (xy 113.832386 -267.295884) (xy 113.819743 -267.29656) (xy 113.797484 -267.308555)
			(xy 113.789968 -267.318744) (xy 113.738914 -267.408914) (xy 113.73866 -267.409422) (xy 113.739168 -267.426948)
			(xy 113.739422 -267.429488) (xy 113.752431 -267.449011) (xy 113.773033 -267.491157) (xy 113.787033 -267.535932)
			(xy 113.794109 -267.582308) (xy 113.79454 -267.605764) (xy 113.79454 -267.606272) (xy 115.058964 -267.606272)
			(xy 115.062924 -267.557218) (xy 115.074701 -267.509434) (xy 115.093992 -267.464158) (xy 115.120295 -267.422562)
			(xy 115.15293 -267.385725) (xy 115.191051 -267.3546) (xy 115.233672 -267.329993) (xy 115.279688 -267.312541)
			(xy 115.327907 -267.302697) (xy 115.377082 -267.300716) (xy 115.425937 -267.306648) (xy 115.473208 -267.32034)
			(xy 115.51767 -267.341438) (xy 115.558173 -267.369394) (xy 115.593666 -267.403486) (xy 115.623231 -267.44283)
			(xy 115.646102 -267.486407) (xy 115.661686 -267.533088) (xy 115.669581 -267.581665) (xy 115.670076 -267.606272)
			(xy 115.669581 -267.630879) (xy 115.661686 -267.679456) (xy 115.646102 -267.726137) (xy 115.623231 -267.769714)
			(xy 115.593666 -267.809058) (xy 115.558173 -267.84315) (xy 115.51767 -267.871106) (xy 115.473208 -267.892204)
			(xy 115.425937 -267.905896) (xy 115.377082 -267.911828) (xy 115.327907 -267.909847) (xy 115.279688 -267.900003)
			(xy 115.233672 -267.882551) (xy 115.191051 -267.857944) (xy 115.15293 -267.826819) (xy 115.120295 -267.789982)
			(xy 115.093992 -267.748386) (xy 115.074701 -267.70311) (xy 115.062924 -267.655326) (xy 115.058964 -267.606272)
			(xy 113.79454 -267.606272) (xy 113.794062 -267.630622) (xy 113.786444 -267.678724) (xy 113.771394 -267.725041)
			(xy 113.749285 -267.768434) (xy 113.720659 -267.807834) (xy 113.686222 -267.842271) (xy 113.646822 -267.870897)
			(xy 113.603429 -267.893006) (xy 113.557112 -267.908056) (xy 113.50901 -267.915674) (xy 113.46031 -267.915674)
			(xy 113.412208 -267.908056) (xy 113.365891 -267.893006) (xy 113.322498 -267.870897) (xy 113.283098 -267.842271)
			(xy 113.248661 -267.807834) (xy 113.220035 -267.768434) (xy 113.197926 -267.725041) (xy 113.182876 -267.678724)
			(xy 113.175258 -267.630622) (xy 113.17478 -267.606272) (xy 113.17516 -267.584306) (xy 113.181368 -267.540816)
			(xy 113.193668 -267.498642) (xy 113.211814 -267.458633) (xy 113.223294 -267.439902) (xy 113.223548 -267.43406)
			(xy 113.223548 -267.409676) (xy 113.22334 -267.403589) (xy 113.220387 -267.391777) (xy 113.217706 -267.386308)
			(xy 113.200688 -267.35659) (xy 113.183162 -267.325602) (xy 113.176304 -267.316966) (xy 112.48771 -266.628372)
			(xy 112.48486 -266.625664) (xy 112.478484 -266.621067) (xy 112.47501 -266.619228) (xy 112.469582 -266.616649)
			(xy 112.457903 -266.613834) (xy 112.451896 -266.61364) (xy 111.569246 -266.61364) (xy 111.563236 -266.613807)
			(xy 111.551553 -266.616628) (xy 111.546132 -266.619228) (xy 111.542656 -266.621066) (xy 111.536275 -266.625656)
			(xy 111.533432 -266.628372) (xy 110.880906 -267.280898) (xy 110.873508 -267.287746) (xy 110.85491 -267.295483)
			(xy 110.844838 -267.295884) (xy 110.078774 -267.295884) (xy 110.066133 -267.296563) (xy 110.043878 -267.308561)
			(xy 110.036356 -267.318744) (xy 109.985302 -267.408914) (xy 109.985048 -267.409422) (xy 109.985556 -267.426948)
			(xy 109.98581 -267.429488) (xy 109.998819 -267.449011) (xy 110.019422 -267.491157) (xy 110.033423 -267.535932)
			(xy 110.040499 -267.582308) (xy 110.040928 -267.605764) (xy 110.040928 -267.606272) (xy 110.04045 -267.630622)
			(xy 110.032832 -267.678724) (xy 110.017782 -267.725041) (xy 109.995673 -267.768434) (xy 109.967047 -267.807834)
			(xy 109.93261 -267.842271) (xy 109.89321 -267.870897) (xy 109.849817 -267.893006) (xy 109.8035 -267.908056)
			(xy 109.755398 -267.915674) (xy 109.706698 -267.915674) (xy 109.658596 -267.908056) (xy 109.612279 -267.893006)
			(xy 109.568886 -267.870897) (xy 109.529486 -267.842271) (xy 109.495049 -267.807834) (xy 109.466423 -267.768434)
			(xy 109.444314 -267.725041) (xy 109.429264 -267.678724) (xy 109.421646 -267.630622) (xy 109.421168 -267.606272)
			(xy 109.421618 -267.581871) (xy 109.429253 -267.533669) (xy 109.444345 -267.487258) (xy 109.466522 -267.443785)
			(xy 109.495236 -267.404324) (xy 109.529778 -267.369848) (xy 109.569295 -267.34121) (xy 109.61281 -267.319117)
			(xy 109.65925 -267.304114) (xy 109.683296 -267.299948) (xy 109.684566 -267.298932) (xy 109.706918 -267.279374)
			(xy 109.711088 -267.275022) (xy 109.717385 -267.264747) (xy 109.719364 -267.259054) (xy 109.719872 -267.258038)
			(xy 109.742224 -267.187172) (xy 109.744256 -267.17752) (xy 109.744866 -267.16879) (xy 109.74085 -267.151769)
			(xy 109.736382 -267.144246) (xy 109.729524 -267.135864) (xy 109.60989 -267.01623) (xy 109.603537 -267.011149)
			(xy 109.588511 -267.004944) (xy 109.580426 -267.004038) (xy 109.534452 -267.00353) (xy 109.50702 -267.003276)
			(xy 109.50321 -267.003276) (xy 109.499296 -267.003642) (xy 109.491641 -267.005427) (xy 109.48797 -267.006832)
			(xy 109.479588 -267.010134) (xy 109.471968 -267.017246) (xy 109.47146 -267.017754) (xy 109.454344 -267.033391)
			(xy 109.416271 -267.059841) (xy 109.374639 -267.080237) (xy 109.330404 -267.09411) (xy 109.284581 -267.101143)
			(xy 109.261402 -267.101574) (xy 109.261148 -267.101574) (xy 109.236611 -267.101081) (xy 109.18817 -267.093228)
			(xy 109.141608 -267.077731) (xy 109.098121 -267.054989) (xy 109.05883 -267.025588) (xy 109.024745 -266.990284)
			(xy 108.996742 -266.949984) (xy 108.975542 -266.905726) (xy 108.96169 -266.858648) (xy 108.958126 -266.834366)
			(xy 108.958126 -266.833858) (xy 108.956348 -266.821158) (xy 108.95584 -266.8143) (xy 108.95584 -266.796266)
			(xy 108.956266 -266.773453) (xy 108.963055 -266.728334) (xy 108.976478 -266.684727) (xy 108.996236 -266.643601)
			(xy 109.02189 -266.605869) (xy 109.052869 -266.572372) (xy 109.070394 -266.55776) (xy 109.07268 -266.555982)
			(xy 109.07522 -266.553442) (xy 109.081936 -266.546008) (xy 109.089572 -266.527508) (xy 109.089572 -266.507494)
			(xy 109.081937 -266.488994) (xy 109.07522 -266.48156) (xy 109.063536 -266.469876) (xy 109.060687 -266.467167)
			(xy 109.054313 -266.462566) (xy 109.050836 -266.460732) (xy 109.045409 -266.45815) (xy 109.033729 -266.455329)
			(xy 109.027722 -266.455144) (xy 108.282486 -266.455144) (xy 108.276475 -266.455306) (xy 108.264787 -266.45812)
			(xy 108.259372 -266.460732) (xy 108.255899 -266.462573) (xy 108.249523 -266.46717) (xy 108.246672 -266.469876)
			(xy 107.460796 -267.255752) (xy 107.453557 -267.262462) (xy 107.435352 -267.270053) (xy 107.42549 -267.270484)
			(xy 106.301794 -267.270484) (xy 106.295698 -267.270992) (xy 106.29519 -267.270992) (xy 106.284411 -267.272934)
			(xy 106.265839 -267.284503) (xy 106.259376 -267.293344) (xy 106.258868 -267.293852) (xy 106.257598 -267.295884)
			(xy 106.21772 -267.373354) (xy 106.213618 -267.38224) (xy 106.211781 -267.401708) (xy 106.214164 -267.4112)
			(xy 106.214164 -267.411708) (xy 106.214418 -267.41247) (xy 106.217466 -267.421868) (xy 106.218482 -267.424916)
			(xy 106.22153 -267.431774) (xy 106.224578 -267.436092) (xy 106.22661 -267.438886) (xy 106.231436 -267.44676)
			(xy 106.245555 -267.470953) (xy 106.265691 -267.523216) (xy 106.275989 -267.578269) (xy 106.276648 -267.606272)
			(xy 107.545136 -267.606272) (xy 107.549096 -267.557218) (xy 107.560873 -267.509434) (xy 107.580164 -267.464158)
			(xy 107.606467 -267.422562) (xy 107.639102 -267.385725) (xy 107.677223 -267.3546) (xy 107.719844 -267.329993)
			(xy 107.76586 -267.312541) (xy 107.814079 -267.302697) (xy 107.863254 -267.300716) (xy 107.912109 -267.306648)
			(xy 107.95938 -267.32034) (xy 108.003842 -267.341438) (xy 108.044345 -267.369394) (xy 108.079838 -267.403486)
			(xy 108.109403 -267.44283) (xy 108.132274 -267.486407) (xy 108.147858 -267.533088) (xy 108.155753 -267.581665)
			(xy 108.156248 -267.606272) (xy 108.155753 -267.630879) (xy 108.147858 -267.679456) (xy 108.132274 -267.726137)
			(xy 108.109403 -267.769714) (xy 108.079838 -267.809058) (xy 108.044345 -267.84315) (xy 108.003842 -267.871106)
			(xy 107.95938 -267.892204) (xy 107.912109 -267.905896) (xy 107.863254 -267.911828) (xy 107.814079 -267.909847)
			(xy 107.76586 -267.900003) (xy 107.719844 -267.882551) (xy 107.677223 -267.857944) (xy 107.639102 -267.826819)
			(xy 107.606467 -267.789982) (xy 107.580164 -267.748386) (xy 107.560873 -267.70311) (xy 107.549096 -267.655326)
			(xy 107.545136 -267.606272) (xy 106.276648 -267.606272) (xy 106.276648 -267.626338) (xy 106.27487 -267.638022)
			(xy 106.271811 -267.662609) (xy 106.258764 -267.710404) (xy 106.238174 -267.755467) (xy 106.21058 -267.796615)
			(xy 106.176708 -267.832771) (xy 106.137443 -267.862985) (xy 106.093817 -267.886467) (xy 106.046973 -267.902599)
			(xy 105.99814 -267.910959) (xy 105.973372 -267.91158) (xy 105.970832 -267.91158) (xy 105.944934 -267.911011)
			(xy 105.893888 -267.902228) (xy 105.845055 -267.88496) (xy 105.799835 -267.859701) (xy 105.759524 -267.827176)
			(xy 105.725279 -267.788316) (xy 105.698079 -267.744236) (xy 105.678705 -267.6962) (xy 105.667713 -267.645583)
			(xy 105.666032 -267.619734) (xy 105.666032 -267.618718) (xy 105.665778 -267.61567) (xy 105.665778 -267.606272)
			(xy 105.66623 -267.58222) (xy 105.673776 -267.53471) (xy 105.688675 -267.488971) (xy 105.710561 -267.446133)
			(xy 105.738891 -267.407255) (xy 105.772966 -267.373299) (xy 105.811942 -267.345104) (xy 105.854856 -267.323368)
			(xy 105.900647 -267.308628) (xy 105.92435 -267.30452) (xy 105.932224 -267.30325) (xy 105.949496 -267.294614)
			(xy 105.9561 -267.290804) (xy 105.960505 -267.287533) (xy 105.967928 -267.279457) (xy 105.970832 -267.274802)
			(xy 105.97515 -267.265404) (xy 106.002328 -267.18514) (xy 106.005045 -267.176053) (xy 106.004243 -267.157118)
			(xy 105.996567 -267.13979) (xy 105.990136 -267.132816) (xy 105.863644 -267.006324) (xy 105.85577 -266.999974)
			(xy 105.854246 -266.999212) (xy 105.848161 -266.995877) (xy 105.834767 -266.992273) (xy 105.82783 -266.9921)
			(xy 105.795318 -266.992354) (xy 105.755186 -266.992862) (xy 105.750544 -266.993152) (xy 105.74147 -266.995197)
			(xy 105.737152 -266.996926) (xy 105.728516 -267.000482) (xy 105.720896 -267.008356) (xy 105.703507 -267.025684)
			(xy 105.664224 -267.055117) (xy 105.620741 -267.077892) (xy 105.574177 -267.093425) (xy 105.525729 -267.101316)
			(xy 105.501186 -267.101828) (xy 105.500678 -267.101828) (xy 105.471722 -267.100304) (xy 105.467404 -267.099796)
			(xy 105.466896 -267.099796) (xy 105.442413 -267.096581) (xy 105.394864 -267.083267) (xy 105.35008 -267.062471)
			(xy 105.309227 -267.034738) (xy 105.273372 -267.000789) (xy 105.24345 -266.96151) (xy 105.220242 -266.917927)
			(xy 105.204353 -266.871176) (xy 105.196198 -266.822476) (xy 105.195624 -266.79779) (xy 105.195624 -266.790678)
			(xy 105.197402 -266.762738) (xy 105.202482 -266.731496) (xy 105.204401 -266.722936) (xy 105.209101 -266.706034)
			(xy 105.21188 -266.697714) (xy 105.215627 -266.686892) (xy 105.224527 -266.665788) (xy 105.22966 -266.65555)
			(xy 105.229914 -266.655296) (xy 105.230168 -266.654788) (xy 105.235214 -266.643317) (xy 105.23467 -266.618289)
			(xy 105.229152 -266.607036) (xy 105.184194 -266.532868) (xy 105.181654 -266.529058) (xy 105.174288 -266.52093)
			(xy 105.16711 -266.51522) (xy 105.149926 -266.508842) (xy 105.14076 -266.508484) (xy 104.464866 -266.508484)
			(xy 104.458856 -266.508649) (xy 104.447171 -266.511469) (xy 104.441752 -266.514072) (xy 104.438278 -266.515912)
			(xy 104.4319 -266.520507) (xy 104.429052 -266.523216) (xy 103.617776 -267.334492) (xy 103.610538 -267.341205)
			(xy 103.592333 -267.348798) (xy 103.58247 -267.349224) (xy 102.58552 -267.349224) (xy 102.572962 -267.349862)
			(xy 102.550822 -267.361714) (xy 102.543356 -267.37183) (xy 102.501446 -267.434568) (xy 102.500176 -267.4366)
			(xy 102.498126 -267.440178) (xy 102.49507 -267.447837) (xy 102.49408 -267.45184) (xy 102.49408 -267.452348)
			(xy 102.49281 -267.462762) (xy 102.49281 -267.488162) (xy 102.496112 -267.497052) (xy 102.505482 -267.523122)
			(xy 102.51571 -267.577563) (xy 102.516432 -267.605256) (xy 102.516432 -267.606272) (xy 103.785174 -267.606272)
			(xy 103.789134 -267.557218) (xy 103.800911 -267.509434) (xy 103.820202 -267.464158) (xy 103.846505 -267.422562)
			(xy 103.87914 -267.385725) (xy 103.917261 -267.3546) (xy 103.959882 -267.329993) (xy 104.005898 -267.312541)
			(xy 104.054117 -267.302697) (xy 104.103292 -267.300716) (xy 104.152147 -267.306648) (xy 104.199418 -267.32034)
			(xy 104.24388 -267.341438) (xy 104.284383 -267.369394) (xy 104.319876 -267.403486) (xy 104.349441 -267.44283)
			(xy 104.372312 -267.486407) (xy 104.387896 -267.533088) (xy 104.395791 -267.581665) (xy 104.396286 -267.606272)
			(xy 104.395791 -267.630879) (xy 104.387896 -267.679456) (xy 104.372312 -267.726137) (xy 104.349441 -267.769714)
			(xy 104.319876 -267.809058) (xy 104.284383 -267.84315) (xy 104.24388 -267.871106) (xy 104.199418 -267.892204)
			(xy 104.152147 -267.905896) (xy 104.103292 -267.911828) (xy 104.054117 -267.909847) (xy 104.005898 -267.900003)
			(xy 103.959882 -267.882551) (xy 103.917261 -267.857944) (xy 103.87914 -267.826819) (xy 103.846505 -267.789982)
			(xy 103.820202 -267.748386) (xy 103.800911 -267.70311) (xy 103.789134 -267.655326) (xy 103.785174 -267.606272)
			(xy 102.516432 -267.606272) (xy 102.515988 -267.630267) (xy 102.508485 -267.677668) (xy 102.493659 -267.723311)
			(xy 102.471876 -267.766072) (xy 102.443671 -267.8049) (xy 102.409739 -267.838837) (xy 102.370917 -267.867048)
			(xy 102.328159 -267.888839) (xy 102.282518 -267.903673) (xy 102.235119 -267.911184) (xy 102.211124 -267.91158)
			(xy 102.187269 -267.911122) (xy 102.140139 -267.903706) (xy 102.094736 -267.889051) (xy 102.052164 -267.867513)
			(xy 102.013459 -267.839617) (xy 101.979564 -267.806041) (xy 101.951303 -267.767603) (xy 101.929363 -267.725237)
			(xy 101.914279 -267.679974) (xy 101.906417 -267.632916) (xy 101.905816 -267.609066) (xy 101.905816 -267.606018)
			(xy 101.906553 -267.575808) (xy 101.918459 -267.51657) (xy 101.929438 -267.488416) (xy 101.931724 -267.483336)
			(xy 101.931978 -267.482574) (xy 101.933756 -267.469874) (xy 101.933248 -267.464032) (xy 101.932511 -267.458465)
			(xy 101.928924 -267.447825) (xy 101.926136 -267.44295) (xy 101.905816 -267.412216) (xy 101.878638 -267.371576)
			(xy 101.874993 -267.366523) (xy 101.865751 -267.358172) (xy 101.86035 -267.355066) (xy 101.846634 -267.3477)
			(xy 101.843509 -267.34592) (xy 101.837769 -267.341586) (xy 101.835204 -267.339064) (xy 101.057456 -266.561316)
			(xy 101.054603 -266.558613) (xy 101.048221 -266.554026) (xy 101.044756 -266.552172) (xy 101.039329 -266.54959)
			(xy 101.027649 -266.546768) (xy 101.021642 -266.546584) (xy 100.362766 -266.546584) (xy 100.356756 -266.546749)
			(xy 100.345071 -266.549569) (xy 100.339652 -266.552172) (xy 100.336178 -266.554012) (xy 100.3298 -266.558607)
			(xy 100.326952 -266.561316) (xy 100.177854 -266.710414) (xy 100.17379 -266.714986) (xy 100.168422 -266.722549)
			(xy 100.162959 -266.740257) (xy 100.163122 -266.74953) (xy 100.163376 -266.752578) (xy 100.16363 -266.754102)
			(xy 100.16492 -266.764213) (xy 100.166321 -266.78455) (xy 100.166424 -266.794742) (xy 100.166424 -266.796774)
			(xy 100.16592 -266.820716) (xy 100.158371 -266.868003) (xy 100.143533 -266.913531) (xy 100.121769 -266.956185)
			(xy 100.093613 -266.994918) (xy 100.059756 -267.028781) (xy 100.021027 -267.056943) (xy 99.978377 -267.078714)
			(xy 99.932851 -267.093559) (xy 99.885566 -267.101116) (xy 99.861624 -267.101574) (xy 99.860608 -267.101574)
			(xy 99.850161 -267.101506) (xy 99.829314 -267.100111) (xy 99.818952 -267.09878) (xy 99.817428 -267.098526)
			(xy 99.81438 -267.098272) (xy 99.8051 -267.098064) (xy 99.787375 -267.103526) (xy 99.779836 -267.10894)
			(xy 99.775264 -267.113004) (xy 99.622864 -267.265404) (xy 99.616394 -267.272495) (xy 99.608821 -267.290119)
			(xy 99.608132 -267.299694) (xy 99.606862 -267.345414) (xy 99.606862 -267.345922) (xy 99.6061 -267.367766)
			(xy 99.6061 -267.37183) (xy 99.60636 -267.375662) (xy 99.607888 -267.383188) (xy 99.609148 -267.386816)
			(xy 99.61245 -267.395706) (xy 99.618038 -267.402056) (xy 99.633165 -267.419552) (xy 99.658512 -267.458236)
			(xy 99.677742 -267.500297) (xy 99.690418 -267.544775) (xy 99.69373 -267.567664) (xy 99.694903 -267.577273)
			(xy 99.69617 -267.596592) (xy 99.69627 -267.606272) (xy 100.025212 -267.606272) (xy 100.029172 -267.557218)
			(xy 100.040949 -267.509434) (xy 100.06024 -267.464158) (xy 100.086543 -267.422562) (xy 100.119178 -267.385725)
			(xy 100.157299 -267.3546) (xy 100.19992 -267.329993) (xy 100.245936 -267.312541) (xy 100.294155 -267.302697)
			(xy 100.34333 -267.300716) (xy 100.392185 -267.306648) (xy 100.439456 -267.32034) (xy 100.483918 -267.341438)
			(xy 100.524421 -267.369394) (xy 100.559914 -267.403486) (xy 100.589479 -267.44283) (xy 100.61235 -267.486407)
			(xy 100.627934 -267.533088) (xy 100.635829 -267.581665) (xy 100.636324 -267.606272) (xy 100.635829 -267.630879)
			(xy 100.627934 -267.679456) (xy 100.61235 -267.726137) (xy 100.589479 -267.769714) (xy 100.559914 -267.809058)
			(xy 100.524421 -267.84315) (xy 100.483918 -267.871106) (xy 100.439456 -267.892204) (xy 100.392185 -267.905896)
			(xy 100.34333 -267.911828) (xy 100.294155 -267.909847) (xy 100.245936 -267.900003) (xy 100.19992 -267.882551)
			(xy 100.157299 -267.857944) (xy 100.119178 -267.826819) (xy 100.086543 -267.789982) (xy 100.06024 -267.748386)
			(xy 100.040949 -267.70311) (xy 100.029172 -267.655326) (xy 100.025212 -267.606272) (xy 99.69627 -267.606272)
			(xy 99.695826 -267.630265) (xy 99.688322 -267.677662) (xy 99.673496 -267.723301) (xy 99.651711 -267.766058)
			(xy 99.623506 -267.804881) (xy 99.589573 -267.838812) (xy 99.55075 -267.867017) (xy 99.507992 -267.8888)
			(xy 99.462352 -267.903625) (xy 99.414956 -267.911127) (xy 99.390962 -267.91158) (xy 99.365492 -267.911066)
			(xy 99.315258 -267.902605) (xy 99.267126 -267.885922) (xy 99.222431 -267.861482) (xy 99.182413 -267.829962)
			(xy 99.148181 -267.792236) (xy 99.120687 -267.749352) (xy 99.100692 -267.702499) (xy 99.088751 -267.652977)
			(xy 99.086416 -267.627608) (xy 99.086162 -267.625576) (xy 99.084835 -267.616588) (xy 99.076761 -267.600327)
			(xy 99.070414 -267.593826) (xy 99.063302 -267.587222) (xy 99.054666 -267.58392) (xy 99.050203 -267.58229)
			(xy 99.040873 -267.580494) (xy 99.036124 -267.580364) (xy 98.806 -267.580364) (xy 98.796452 -267.580807)
			(xy 98.778695 -267.587841) (xy 98.771456 -267.59408) (xy 98.764598 -267.60043) (xy 98.75647 -267.617448)
			(xy 98.755708 -267.627608) (xy 98.753566 -267.651647) (xy 98.742661 -267.698658) (xy 98.724496 -267.743369)
			(xy 98.699522 -267.784664) (xy 98.668363 -267.821516) (xy 98.631794 -267.853008) (xy 98.590726 -267.878353)
			(xy 98.546182 -267.896922) (xy 98.499271 -267.908252) (xy 98.451162 -267.91206) (xy 98.403053 -267.908252)
			(xy 98.356142 -267.896922) (xy 98.311598 -267.878353) (xy 98.27053 -267.853008) (xy 98.233961 -267.821516)
			(xy 98.202802 -267.784664) (xy 98.177828 -267.743369) (xy 98.159663 -267.698658) (xy 98.148758 -267.651647)
			(xy 98.146616 -267.627608) (xy 98.146362 -267.625576) (xy 98.145035 -267.616588) (xy 98.136961 -267.600327)
			(xy 98.130614 -267.593826) (xy 98.123502 -267.587222) (xy 98.114866 -267.58392) (xy 98.110403 -267.58229)
			(xy 98.101073 -267.580494) (xy 98.096324 -267.580364) (xy 97.865946 -267.580364) (xy 97.856402 -267.580816)
			(xy 97.838658 -267.587864) (xy 97.831402 -267.59408) (xy 97.824544 -267.60043) (xy 97.816416 -267.617448)
			(xy 97.815654 -267.627608) (xy 97.813367 -267.652984) (xy 97.801424 -267.702511) (xy 97.781425 -267.74937)
			(xy 97.753926 -267.792258) (xy 97.719688 -267.829986) (xy 97.679663 -267.861508) (xy 97.634961 -267.885948)
			(xy 97.586822 -267.902629) (xy 97.536582 -267.911087) (xy 97.511108 -267.91158) (xy 97.487203 -267.911118)
			(xy 97.439976 -267.903671) (xy 97.394485 -267.888957) (xy 97.351843 -267.867336) (xy 97.313089 -267.839335)
			(xy 97.279171 -267.805639) (xy 97.250917 -267.767071) (xy 97.229016 -267.724571) (xy 97.22104 -267.70203)
			(xy 97.218754 -267.695426) (xy 97.21215 -267.684758) (xy 97.207324 -267.68044) (xy 97.202471 -267.676245)
			(xy 97.191155 -267.670213) (xy 97.184972 -267.668502) (xy 97.102676 -267.648436) (xy 97.097088 -267.64742)
			(xy 97.095056 -267.647166) (xy 97.083903 -267.646791) (xy 97.062964 -267.654432) (xy 97.05467 -267.661898)
			(xy 96.710754 -268.005814) (xy 111.710473 -268.005814) (xy 111.714503 -267.953316) (xy 111.7265 -267.902048)
			(xy 111.746183 -267.853213) (xy 111.773089 -267.807954) (xy 111.806589 -267.767333) (xy 111.845897 -267.732302)
			(xy 111.890092 -267.703682) (xy 111.938137 -267.682143) (xy 111.988908 -267.668191) (xy 112.041213 -267.662153)
			(xy 112.093827 -267.66417) (xy 112.145517 -267.674194) (xy 112.19507 -267.691992) (xy 112.241326 -267.717145)
			(xy 112.2832 -267.749064) (xy 112.319712 -267.787002) (xy 112.350004 -267.830068) (xy 112.373367 -267.877253)
			(xy 112.389253 -267.927452) (xy 112.39729 -267.979488) (xy 112.397794 -268.005814) (xy 112.39729 -268.03214)
			(xy 112.389253 -268.084176) (xy 112.373367 -268.134375) (xy 112.350004 -268.18156) (xy 112.319712 -268.224626)
			(xy 112.2832 -268.262564) (xy 112.241326 -268.294483) (xy 112.19507 -268.319636) (xy 112.145517 -268.337434)
			(xy 112.093827 -268.347458) (xy 112.041213 -268.349475) (xy 111.988908 -268.343437) (xy 111.938137 -268.329485)
			(xy 111.890092 -268.307946) (xy 111.845897 -268.279326) (xy 111.806589 -268.244295) (xy 111.773089 -268.203674)
			(xy 111.746183 -268.158415) (xy 111.7265 -268.10958) (xy 111.714503 -268.058312) (xy 111.710473 -268.005814)
			(xy 96.710754 -268.005814) (xy 96.412558 -268.30401) (xy 96.405954 -268.312138) (xy 96.404023 -268.315169)
			(xy 96.400956 -268.32167) (xy 96.399858 -268.325092) (xy 96.398334 -268.33068) (xy 96.397826 -268.343888)
			(xy 96.39935 -268.350492) (xy 96.402483 -268.365672) (xy 96.406047 -268.396465) (xy 96.406462 -268.41196)
			(xy 96.406462 -268.416278) (xy 96.73515 -268.416278) (xy 96.73911 -268.367224) (xy 96.750887 -268.31944)
			(xy 96.770178 -268.274164) (xy 96.796481 -268.232568) (xy 96.829116 -268.195731) (xy 96.867237 -268.164606)
			(xy 96.909858 -268.139999) (xy 96.955874 -268.122547) (xy 97.004093 -268.112703) (xy 97.053268 -268.110722)
			(xy 97.102123 -268.116654) (xy 97.149394 -268.130346) (xy 97.193856 -268.151444) (xy 97.234359 -268.1794)
			(xy 97.269852 -268.213492) (xy 97.299417 -268.252836) (xy 97.322288 -268.296413) (xy 97.337872 -268.343094)
			(xy 97.345767 -268.391671) (xy 97.346262 -268.416278) (xy 97.675204 -268.416278) (xy 97.679164 -268.367224)
			(xy 97.690941 -268.31944) (xy 97.710232 -268.274164) (xy 97.736535 -268.232568) (xy 97.76917 -268.195731)
			(xy 97.807291 -268.164606) (xy 97.849912 -268.139999) (xy 97.895928 -268.122547) (xy 97.944147 -268.112703)
			(xy 97.993322 -268.110722) (xy 98.042177 -268.116654) (xy 98.089448 -268.130346) (xy 98.13391 -268.151444)
			(xy 98.174413 -268.1794) (xy 98.209906 -268.213492) (xy 98.239471 -268.252836) (xy 98.262342 -268.296413)
			(xy 98.277926 -268.343094) (xy 98.285821 -268.391671) (xy 98.286316 -268.416278) (xy 99.555312 -268.416278)
			(xy 99.559272 -268.367224) (xy 99.571049 -268.31944) (xy 99.59034 -268.274164) (xy 99.616643 -268.232568)
			(xy 99.649278 -268.195731) (xy 99.687399 -268.164606) (xy 99.73002 -268.139999) (xy 99.776036 -268.122547)
			(xy 99.824255 -268.112703) (xy 99.87343 -268.110722) (xy 99.922285 -268.116654) (xy 99.969556 -268.130346)
			(xy 100.014018 -268.151444) (xy 100.054521 -268.1794) (xy 100.090014 -268.213492) (xy 100.119579 -268.252836)
			(xy 100.14245 -268.296413) (xy 100.158034 -268.343094) (xy 100.165929 -268.391671) (xy 100.166424 -268.416278)
			(xy 101.435166 -268.416278) (xy 101.439126 -268.367224) (xy 101.450903 -268.31944) (xy 101.470194 -268.274164)
			(xy 101.496497 -268.232568) (xy 101.529132 -268.195731) (xy 101.567253 -268.164606) (xy 101.609874 -268.139999)
			(xy 101.65589 -268.122547) (xy 101.704109 -268.112703) (xy 101.753284 -268.110722) (xy 101.802139 -268.116654)
			(xy 101.84941 -268.130346) (xy 101.893872 -268.151444) (xy 101.934375 -268.1794) (xy 101.969868 -268.213492)
			(xy 101.999433 -268.252836) (xy 102.022304 -268.296413) (xy 102.037888 -268.343094) (xy 102.045783 -268.391671)
			(xy 102.046278 -268.416278) (xy 103.315274 -268.416278) (xy 103.319234 -268.367224) (xy 103.331011 -268.31944)
			(xy 103.350302 -268.274164) (xy 103.376605 -268.232568) (xy 103.40924 -268.195731) (xy 103.447361 -268.164606)
			(xy 103.489982 -268.139999) (xy 103.535998 -268.122547) (xy 103.584217 -268.112703) (xy 103.633392 -268.110722)
			(xy 103.682247 -268.116654) (xy 103.729518 -268.130346) (xy 103.77398 -268.151444) (xy 103.814483 -268.1794)
			(xy 103.849976 -268.213492) (xy 103.879541 -268.252836) (xy 103.902412 -268.296413) (xy 103.917996 -268.343094)
			(xy 103.925891 -268.391671) (xy 103.926386 -268.416278) (xy 105.195128 -268.416278) (xy 105.199088 -268.367224)
			(xy 105.210865 -268.31944) (xy 105.230156 -268.274164) (xy 105.256459 -268.232568) (xy 105.289094 -268.195731)
			(xy 105.327215 -268.164606) (xy 105.369836 -268.139999) (xy 105.415852 -268.122547) (xy 105.464071 -268.112703)
			(xy 105.513246 -268.110722) (xy 105.562101 -268.116654) (xy 105.609372 -268.130346) (xy 105.653834 -268.151444)
			(xy 105.694337 -268.1794) (xy 105.72983 -268.213492) (xy 105.759395 -268.252836) (xy 105.782266 -268.296413)
			(xy 105.79785 -268.343094) (xy 105.805745 -268.391671) (xy 105.80624 -268.416278) (xy 107.075236 -268.416278)
			(xy 107.079196 -268.367224) (xy 107.090973 -268.31944) (xy 107.110264 -268.274164) (xy 107.136567 -268.232568)
			(xy 107.169202 -268.195731) (xy 107.207323 -268.164606) (xy 107.249944 -268.139999) (xy 107.29596 -268.122547)
			(xy 107.344179 -268.112703) (xy 107.393354 -268.110722) (xy 107.442209 -268.116654) (xy 107.48948 -268.130346)
			(xy 107.533942 -268.151444) (xy 107.574445 -268.1794) (xy 107.609938 -268.213492) (xy 107.639503 -268.252836)
			(xy 107.662374 -268.296413) (xy 107.677958 -268.343094) (xy 107.685853 -268.391671) (xy 107.686348 -268.416278)
			(xy 108.955344 -268.416278) (xy 108.959304 -268.367224) (xy 108.971081 -268.31944) (xy 108.990372 -268.274164)
			(xy 109.016675 -268.232568) (xy 109.04931 -268.195731) (xy 109.087431 -268.164606) (xy 109.130052 -268.139999)
			(xy 109.176068 -268.122547) (xy 109.224287 -268.112703) (xy 109.273462 -268.110722) (xy 109.322317 -268.116654)
			(xy 109.369588 -268.130346) (xy 109.41405 -268.151444) (xy 109.454553 -268.1794) (xy 109.490046 -268.213492)
			(xy 109.519611 -268.252836) (xy 109.542482 -268.296413) (xy 109.558066 -268.343094) (xy 109.565961 -268.391671)
			(xy 109.566456 -268.416278) (xy 113.64901 -268.416278) (xy 113.65297 -268.367224) (xy 113.664747 -268.31944)
			(xy 113.684038 -268.274164) (xy 113.710341 -268.232568) (xy 113.742976 -268.195731) (xy 113.781097 -268.164606)
			(xy 113.823718 -268.139999) (xy 113.869734 -268.122547) (xy 113.917953 -268.112703) (xy 113.967128 -268.110722)
			(xy 114.015983 -268.116654) (xy 114.063254 -268.130346) (xy 114.107716 -268.151444) (xy 114.148219 -268.1794)
			(xy 114.183712 -268.213492) (xy 114.213277 -268.252836) (xy 114.236148 -268.296413) (xy 114.251732 -268.343094)
			(xy 114.259627 -268.391671) (xy 114.260122 -268.416278) (xy 115.528864 -268.416278) (xy 115.532824 -268.367224)
			(xy 115.544601 -268.31944) (xy 115.563892 -268.274164) (xy 115.590195 -268.232568) (xy 115.62283 -268.195731)
			(xy 115.660951 -268.164606) (xy 115.703572 -268.139999) (xy 115.749588 -268.122547) (xy 115.797807 -268.112703)
			(xy 115.846982 -268.110722) (xy 115.895837 -268.116654) (xy 115.943108 -268.130346) (xy 115.98757 -268.151444)
			(xy 116.028073 -268.1794) (xy 116.063566 -268.213492) (xy 116.093131 -268.252836) (xy 116.116002 -268.296413)
			(xy 116.131586 -268.343094) (xy 116.139481 -268.391671) (xy 116.139976 -268.416278) (xy 117.408972 -268.416278)
			(xy 117.412932 -268.367224) (xy 117.424709 -268.31944) (xy 117.444 -268.274164) (xy 117.470303 -268.232568)
			(xy 117.502938 -268.195731) (xy 117.541059 -268.164606) (xy 117.58368 -268.139999) (xy 117.629696 -268.122547)
			(xy 117.677915 -268.112703) (xy 117.72709 -268.110722) (xy 117.775945 -268.116654) (xy 117.823216 -268.130346)
			(xy 117.867678 -268.151444) (xy 117.908181 -268.1794) (xy 117.943674 -268.213492) (xy 117.973239 -268.252836)
			(xy 117.99611 -268.296413) (xy 118.011694 -268.343094) (xy 118.019589 -268.391671) (xy 118.020084 -268.416278)
			(xy 119.288826 -268.416278) (xy 119.292786 -268.367224) (xy 119.304563 -268.31944) (xy 119.323854 -268.274164)
			(xy 119.350157 -268.232568) (xy 119.382792 -268.195731) (xy 119.420913 -268.164606) (xy 119.463534 -268.139999)
			(xy 119.50955 -268.122547) (xy 119.557769 -268.112703) (xy 119.606944 -268.110722) (xy 119.655799 -268.116654)
			(xy 119.70307 -268.130346) (xy 119.747532 -268.151444) (xy 119.788035 -268.1794) (xy 119.823528 -268.213492)
			(xy 119.853093 -268.252836) (xy 119.875964 -268.296413) (xy 119.891548 -268.343094) (xy 119.899443 -268.391671)
			(xy 119.899938 -268.416278) (xy 121.168934 -268.416278) (xy 121.172894 -268.367224) (xy 121.184671 -268.31944)
			(xy 121.203962 -268.274164) (xy 121.230265 -268.232568) (xy 121.2629 -268.195731) (xy 121.301021 -268.164606)
			(xy 121.343642 -268.139999) (xy 121.389658 -268.122547) (xy 121.437877 -268.112703) (xy 121.487052 -268.110722)
			(xy 121.535907 -268.116654) (xy 121.583178 -268.130346) (xy 121.62764 -268.151444) (xy 121.668143 -268.1794)
			(xy 121.703636 -268.213492) (xy 121.733201 -268.252836) (xy 121.756072 -268.296413) (xy 121.771656 -268.343094)
			(xy 121.779551 -268.391671) (xy 121.780046 -268.416278) (xy 123.049042 -268.416278) (xy 123.053002 -268.367224)
			(xy 123.064779 -268.31944) (xy 123.08407 -268.274164) (xy 123.110373 -268.232568) (xy 123.143008 -268.195731)
			(xy 123.181129 -268.164606) (xy 123.22375 -268.139999) (xy 123.269766 -268.122547) (xy 123.317985 -268.112703)
			(xy 123.36716 -268.110722) (xy 123.416015 -268.116654) (xy 123.463286 -268.130346) (xy 123.507748 -268.151444)
			(xy 123.548251 -268.1794) (xy 123.583744 -268.213492) (xy 123.613309 -268.252836) (xy 123.63618 -268.296413)
			(xy 123.651764 -268.343094) (xy 123.659659 -268.391671) (xy 123.660154 -268.416278) (xy 124.928896 -268.416278)
			(xy 124.932856 -268.367224) (xy 124.944633 -268.31944) (xy 124.963924 -268.274164) (xy 124.990227 -268.232568)
			(xy 125.022862 -268.195731) (xy 125.060983 -268.164606) (xy 125.103604 -268.139999) (xy 125.14962 -268.122547)
			(xy 125.197839 -268.112703) (xy 125.247014 -268.110722) (xy 125.295869 -268.116654) (xy 125.34314 -268.130346)
			(xy 125.387602 -268.151444) (xy 125.428105 -268.1794) (xy 125.463598 -268.213492) (xy 125.493163 -268.252836)
			(xy 125.516034 -268.296413) (xy 125.531618 -268.343094) (xy 125.539513 -268.391671) (xy 125.540008 -268.416278)
			(xy 125.539513 -268.440885) (xy 125.531618 -268.489462) (xy 125.516034 -268.536143) (xy 125.493163 -268.57972)
			(xy 125.463598 -268.619064) (xy 125.428105 -268.653156) (xy 125.387602 -268.681112) (xy 125.34314 -268.70221)
			(xy 125.295869 -268.715902) (xy 125.247014 -268.721834) (xy 125.197839 -268.719853) (xy 125.14962 -268.710009)
			(xy 125.103604 -268.692557) (xy 125.060983 -268.66795) (xy 125.022862 -268.636825) (xy 124.990227 -268.599988)
			(xy 124.963924 -268.558392) (xy 124.944633 -268.513116) (xy 124.932856 -268.465332) (xy 124.928896 -268.416278)
			(xy 123.660154 -268.416278) (xy 123.659659 -268.440885) (xy 123.651764 -268.489462) (xy 123.63618 -268.536143)
			(xy 123.613309 -268.57972) (xy 123.583744 -268.619064) (xy 123.548251 -268.653156) (xy 123.507748 -268.681112)
			(xy 123.463286 -268.70221) (xy 123.416015 -268.715902) (xy 123.36716 -268.721834) (xy 123.317985 -268.719853)
			(xy 123.269766 -268.710009) (xy 123.22375 -268.692557) (xy 123.181129 -268.66795) (xy 123.143008 -268.636825)
			(xy 123.110373 -268.599988) (xy 123.08407 -268.558392) (xy 123.064779 -268.513116) (xy 123.053002 -268.465332)
			(xy 123.049042 -268.416278) (xy 121.780046 -268.416278) (xy 121.779551 -268.440885) (xy 121.771656 -268.489462)
			(xy 121.756072 -268.536143) (xy 121.733201 -268.57972) (xy 121.703636 -268.619064) (xy 121.668143 -268.653156)
			(xy 121.62764 -268.681112) (xy 121.583178 -268.70221) (xy 121.535907 -268.715902) (xy 121.487052 -268.721834)
			(xy 121.437877 -268.719853) (xy 121.389658 -268.710009) (xy 121.343642 -268.692557) (xy 121.301021 -268.66795)
			(xy 121.2629 -268.636825) (xy 121.230265 -268.599988) (xy 121.203962 -268.558392) (xy 121.184671 -268.513116)
			(xy 121.172894 -268.465332) (xy 121.168934 -268.416278) (xy 119.899938 -268.416278) (xy 119.899443 -268.440885)
			(xy 119.891548 -268.489462) (xy 119.875964 -268.536143) (xy 119.853093 -268.57972) (xy 119.823528 -268.619064)
			(xy 119.788035 -268.653156) (xy 119.747532 -268.681112) (xy 119.70307 -268.70221) (xy 119.655799 -268.715902)
			(xy 119.606944 -268.721834) (xy 119.557769 -268.719853) (xy 119.50955 -268.710009) (xy 119.463534 -268.692557)
			(xy 119.420913 -268.66795) (xy 119.382792 -268.636825) (xy 119.350157 -268.599988) (xy 119.323854 -268.558392)
			(xy 119.304563 -268.513116) (xy 119.292786 -268.465332) (xy 119.288826 -268.416278) (xy 118.020084 -268.416278)
			(xy 118.019589 -268.440885) (xy 118.011694 -268.489462) (xy 117.99611 -268.536143) (xy 117.973239 -268.57972)
			(xy 117.943674 -268.619064) (xy 117.908181 -268.653156) (xy 117.867678 -268.681112) (xy 117.823216 -268.70221)
			(xy 117.775945 -268.715902) (xy 117.72709 -268.721834) (xy 117.677915 -268.719853) (xy 117.629696 -268.710009)
			(xy 117.58368 -268.692557) (xy 117.541059 -268.66795) (xy 117.502938 -268.636825) (xy 117.470303 -268.599988)
			(xy 117.444 -268.558392) (xy 117.424709 -268.513116) (xy 117.412932 -268.465332) (xy 117.408972 -268.416278)
			(xy 116.139976 -268.416278) (xy 116.139481 -268.440885) (xy 116.131586 -268.489462) (xy 116.116002 -268.536143)
			(xy 116.093131 -268.57972) (xy 116.063566 -268.619064) (xy 116.028073 -268.653156) (xy 115.98757 -268.681112)
			(xy 115.943108 -268.70221) (xy 115.895837 -268.715902) (xy 115.846982 -268.721834) (xy 115.797807 -268.719853)
			(xy 115.749588 -268.710009) (xy 115.703572 -268.692557) (xy 115.660951 -268.66795) (xy 115.62283 -268.636825)
			(xy 115.590195 -268.599988) (xy 115.563892 -268.558392) (xy 115.544601 -268.513116) (xy 115.532824 -268.465332)
			(xy 115.528864 -268.416278) (xy 114.260122 -268.416278) (xy 114.259627 -268.440885) (xy 114.251732 -268.489462)
			(xy 114.236148 -268.536143) (xy 114.213277 -268.57972) (xy 114.183712 -268.619064) (xy 114.148219 -268.653156)
			(xy 114.107716 -268.681112) (xy 114.063254 -268.70221) (xy 114.015983 -268.715902) (xy 113.967128 -268.721834)
			(xy 113.917953 -268.719853) (xy 113.869734 -268.710009) (xy 113.823718 -268.692557) (xy 113.781097 -268.66795)
			(xy 113.742976 -268.636825) (xy 113.710341 -268.599988) (xy 113.684038 -268.558392) (xy 113.664747 -268.513116)
			(xy 113.65297 -268.465332) (xy 113.64901 -268.416278) (xy 109.566456 -268.416278) (xy 109.565961 -268.440885)
			(xy 109.558066 -268.489462) (xy 109.542482 -268.536143) (xy 109.519611 -268.57972) (xy 109.490046 -268.619064)
			(xy 109.454553 -268.653156) (xy 109.41405 -268.681112) (xy 109.369588 -268.70221) (xy 109.322317 -268.715902)
			(xy 109.273462 -268.721834) (xy 109.224287 -268.719853) (xy 109.176068 -268.710009) (xy 109.130052 -268.692557)
			(xy 109.087431 -268.66795) (xy 109.04931 -268.636825) (xy 109.016675 -268.599988) (xy 108.990372 -268.558392)
			(xy 108.971081 -268.513116) (xy 108.959304 -268.465332) (xy 108.955344 -268.416278) (xy 107.686348 -268.416278)
			(xy 107.685853 -268.440885) (xy 107.677958 -268.489462) (xy 107.662374 -268.536143) (xy 107.639503 -268.57972)
			(xy 107.609938 -268.619064) (xy 107.574445 -268.653156) (xy 107.533942 -268.681112) (xy 107.48948 -268.70221)
			(xy 107.442209 -268.715902) (xy 107.393354 -268.721834) (xy 107.344179 -268.719853) (xy 107.29596 -268.710009)
			(xy 107.249944 -268.692557) (xy 107.207323 -268.66795) (xy 107.169202 -268.636825) (xy 107.136567 -268.599988)
			(xy 107.110264 -268.558392) (xy 107.090973 -268.513116) (xy 107.079196 -268.465332) (xy 107.075236 -268.416278)
			(xy 105.80624 -268.416278) (xy 105.805745 -268.440885) (xy 105.79785 -268.489462) (xy 105.782266 -268.536143)
			(xy 105.759395 -268.57972) (xy 105.72983 -268.619064) (xy 105.694337 -268.653156) (xy 105.653834 -268.681112)
			(xy 105.609372 -268.70221) (xy 105.562101 -268.715902) (xy 105.513246 -268.721834) (xy 105.464071 -268.719853)
			(xy 105.415852 -268.710009) (xy 105.369836 -268.692557) (xy 105.327215 -268.66795) (xy 105.289094 -268.636825)
			(xy 105.256459 -268.599988) (xy 105.230156 -268.558392) (xy 105.210865 -268.513116) (xy 105.199088 -268.465332)
			(xy 105.195128 -268.416278) (xy 103.926386 -268.416278) (xy 103.925891 -268.440885) (xy 103.917996 -268.489462)
			(xy 103.902412 -268.536143) (xy 103.879541 -268.57972) (xy 103.849976 -268.619064) (xy 103.814483 -268.653156)
			(xy 103.77398 -268.681112) (xy 103.729518 -268.70221) (xy 103.682247 -268.715902) (xy 103.633392 -268.721834)
			(xy 103.584217 -268.719853) (xy 103.535998 -268.710009) (xy 103.489982 -268.692557) (xy 103.447361 -268.66795)
			(xy 103.40924 -268.636825) (xy 103.376605 -268.599988) (xy 103.350302 -268.558392) (xy 103.331011 -268.513116)
			(xy 103.319234 -268.465332) (xy 103.315274 -268.416278) (xy 102.046278 -268.416278) (xy 102.045783 -268.440885)
			(xy 102.037888 -268.489462) (xy 102.022304 -268.536143) (xy 101.999433 -268.57972) (xy 101.969868 -268.619064)
			(xy 101.934375 -268.653156) (xy 101.893872 -268.681112) (xy 101.84941 -268.70221) (xy 101.802139 -268.715902)
			(xy 101.753284 -268.721834) (xy 101.704109 -268.719853) (xy 101.65589 -268.710009) (xy 101.609874 -268.692557)
			(xy 101.567253 -268.66795) (xy 101.529132 -268.636825) (xy 101.496497 -268.599988) (xy 101.470194 -268.558392)
			(xy 101.450903 -268.513116) (xy 101.439126 -268.465332) (xy 101.435166 -268.416278) (xy 100.166424 -268.416278)
			(xy 100.165929 -268.440885) (xy 100.158034 -268.489462) (xy 100.14245 -268.536143) (xy 100.119579 -268.57972)
			(xy 100.090014 -268.619064) (xy 100.054521 -268.653156) (xy 100.014018 -268.681112) (xy 99.969556 -268.70221)
			(xy 99.922285 -268.715902) (xy 99.87343 -268.721834) (xy 99.824255 -268.719853) (xy 99.776036 -268.710009)
			(xy 99.73002 -268.692557) (xy 99.687399 -268.66795) (xy 99.649278 -268.636825) (xy 99.616643 -268.599988)
			(xy 99.59034 -268.558392) (xy 99.571049 -268.513116) (xy 99.559272 -268.465332) (xy 99.555312 -268.416278)
			(xy 98.286316 -268.416278) (xy 98.285821 -268.440885) (xy 98.277926 -268.489462) (xy 98.262342 -268.536143)
			(xy 98.239471 -268.57972) (xy 98.209906 -268.619064) (xy 98.174413 -268.653156) (xy 98.13391 -268.681112)
			(xy 98.089448 -268.70221) (xy 98.042177 -268.715902) (xy 97.993322 -268.721834) (xy 97.944147 -268.719853)
			(xy 97.895928 -268.710009) (xy 97.849912 -268.692557) (xy 97.807291 -268.66795) (xy 97.76917 -268.636825)
			(xy 97.736535 -268.599988) (xy 97.710232 -268.558392) (xy 97.690941 -268.513116) (xy 97.679164 -268.465332)
			(xy 97.675204 -268.416278) (xy 97.346262 -268.416278) (xy 97.345767 -268.440885) (xy 97.337872 -268.489462)
			(xy 97.322288 -268.536143) (xy 97.299417 -268.57972) (xy 97.269852 -268.619064) (xy 97.234359 -268.653156)
			(xy 97.193856 -268.681112) (xy 97.149394 -268.70221) (xy 97.102123 -268.715902) (xy 97.053268 -268.721834)
			(xy 97.004093 -268.719853) (xy 96.955874 -268.710009) (xy 96.909858 -268.692557) (xy 96.867237 -268.66795)
			(xy 96.829116 -268.636825) (xy 96.796481 -268.599988) (xy 96.770178 -268.558392) (xy 96.750887 -268.513116)
			(xy 96.73911 -268.465332) (xy 96.73515 -268.416278) (xy 96.406462 -268.416278) (xy 96.406462 -268.419072)
			(xy 96.405737 -268.444362) (xy 96.396946 -268.494185) (xy 96.380065 -268.541877) (xy 96.355555 -268.586135)
			(xy 96.324085 -268.625748) (xy 96.286518 -268.659634) (xy 96.24388 -268.686864) (xy 96.220788 -268.697202)
			(xy 96.214184 -268.699996) (xy 96.191324 -268.718284) (xy 96.191324 -268.718538) (xy 96.190816 -268.718792)
			(xy 96.187057 -268.72496) (xy 96.182804 -268.738756) (xy 96.182434 -268.74597) (xy 96.182434 -268.941804)
			(xy 96.182989 -268.951415) (xy 96.190367 -268.969179) (xy 96.203804 -268.982944) (xy 96.212406 -268.98727)
			(xy 96.29902 -269.023084) (xy 96.305621 -269.025392) (xy 96.319539 -269.026677) (xy 96.326452 -269.025624)
			(xy 96.331532 -269.024608) (xy 96.337785 -269.022681) (xy 96.3491 -269.016119) (xy 96.353884 -269.011654)
			(xy 96.354138 -269.0114) (xy 96.37145 -268.994572) (xy 96.410399 -268.966048) (xy 96.453352 -268.944011)
			(xy 96.499239 -268.92901) (xy 96.546916 -268.921419) (xy 96.571054 -268.920976) (xy 96.59505 -268.921419)
			(xy 96.642452 -268.92892) (xy 96.688097 -268.943744) (xy 96.73086 -268.965527) (xy 96.76969 -268.993731)
			(xy 96.803629 -269.027663) (xy 96.831841 -269.066487) (xy 96.853632 -269.109246) (xy 96.868466 -269.154888)
			(xy 96.875976 -269.202288) (xy 96.876362 -269.226284) (xy 99.085158 -269.226284) (xy 99.089118 -269.17723)
			(xy 99.100895 -269.129446) (xy 99.120186 -269.08417) (xy 99.146489 -269.042574) (xy 99.179124 -269.005737)
			(xy 99.217245 -268.974612) (xy 99.259866 -268.950005) (xy 99.305882 -268.932553) (xy 99.354101 -268.922709)
			(xy 99.403276 -268.920728) (xy 99.452131 -268.92666) (xy 99.499402 -268.940352) (xy 99.543864 -268.96145)
			(xy 99.584367 -268.989406) (xy 99.61986 -269.023498) (xy 99.649425 -269.062842) (xy 99.672296 -269.106419)
			(xy 99.68788 -269.1531) (xy 99.695775 -269.201677) (xy 99.69627 -269.226284) (xy 101.90532 -269.226284)
			(xy 101.90928 -269.17723) (xy 101.921057 -269.129446) (xy 101.940348 -269.08417) (xy 101.966651 -269.042574)
			(xy 101.999286 -269.005737) (xy 102.037407 -268.974612) (xy 102.080028 -268.950005) (xy 102.126044 -268.932553)
			(xy 102.174263 -268.922709) (xy 102.223438 -268.920728) (xy 102.272293 -268.92666) (xy 102.319564 -268.940352)
			(xy 102.364026 -268.96145) (xy 102.404529 -268.989406) (xy 102.440022 -269.023498) (xy 102.469587 -269.062842)
			(xy 102.492458 -269.106419) (xy 102.508042 -269.1531) (xy 102.515937 -269.201677) (xy 102.516432 -269.226284)
			(xy 104.725228 -269.226284) (xy 104.729188 -269.17723) (xy 104.740965 -269.129446) (xy 104.760256 -269.08417)
			(xy 104.786559 -269.042574) (xy 104.819194 -269.005737) (xy 104.857315 -268.974612) (xy 104.899936 -268.950005)
			(xy 104.945952 -268.932553) (xy 104.994171 -268.922709) (xy 105.043346 -268.920728) (xy 105.092201 -268.92666)
			(xy 105.139472 -268.940352) (xy 105.183934 -268.96145) (xy 105.224437 -268.989406) (xy 105.25993 -269.023498)
			(xy 105.289495 -269.062842) (xy 105.312366 -269.106419) (xy 105.32795 -269.1531) (xy 105.335845 -269.201677)
			(xy 105.33634 -269.226284) (xy 107.545136 -269.226284) (xy 107.549096 -269.17723) (xy 107.560873 -269.129446)
			(xy 107.580164 -269.08417) (xy 107.606467 -269.042574) (xy 107.639102 -269.005737) (xy 107.677223 -268.974612)
			(xy 107.719844 -268.950005) (xy 107.76586 -268.932553) (xy 107.814079 -268.922709) (xy 107.863254 -268.920728)
			(xy 107.912109 -268.92666) (xy 107.95938 -268.940352) (xy 108.003842 -268.96145) (xy 108.044345 -268.989406)
			(xy 108.079838 -269.023498) (xy 108.109403 -269.062842) (xy 108.132274 -269.106419) (xy 108.147858 -269.1531)
			(xy 108.155753 -269.201677) (xy 108.156248 -269.226284) (xy 108.48519 -269.226284) (xy 108.48915 -269.17723)
			(xy 108.500927 -269.129446) (xy 108.520218 -269.08417) (xy 108.546521 -269.042574) (xy 108.579156 -269.005737)
			(xy 108.617277 -268.974612) (xy 108.659898 -268.950005) (xy 108.705914 -268.932553) (xy 108.754133 -268.922709)
			(xy 108.803308 -268.920728) (xy 108.852163 -268.92666) (xy 108.899434 -268.940352) (xy 108.943896 -268.96145)
			(xy 108.984399 -268.989406) (xy 109.019892 -269.023498) (xy 109.049457 -269.062842) (xy 109.072328 -269.106419)
			(xy 109.087912 -269.1531) (xy 109.095807 -269.201677) (xy 109.096302 -269.226284) (xy 109.425244 -269.226284)
			(xy 109.429204 -269.17723) (xy 109.440981 -269.129446) (xy 109.460272 -269.08417) (xy 109.486575 -269.042574)
			(xy 109.51921 -269.005737) (xy 109.557331 -268.974612) (xy 109.599952 -268.950005) (xy 109.645968 -268.932553)
			(xy 109.694187 -268.922709) (xy 109.743362 -268.920728) (xy 109.792217 -268.92666) (xy 109.839488 -268.940352)
			(xy 109.88395 -268.96145) (xy 109.924453 -268.989406) (xy 109.959946 -269.023498) (xy 109.989511 -269.062842)
			(xy 110.012382 -269.106419) (xy 110.027966 -269.1531) (xy 110.035861 -269.201677) (xy 110.036356 -269.226284)
			(xy 110.365298 -269.226284) (xy 110.369258 -269.17723) (xy 110.381035 -269.129446) (xy 110.400326 -269.08417)
			(xy 110.426629 -269.042574) (xy 110.459264 -269.005737) (xy 110.497385 -268.974612) (xy 110.540006 -268.950005)
			(xy 110.586022 -268.932553) (xy 110.634241 -268.922709) (xy 110.683416 -268.920728) (xy 110.732271 -268.92666)
			(xy 110.779542 -268.940352) (xy 110.824004 -268.96145) (xy 110.864507 -268.989406) (xy 110.9 -269.023498)
			(xy 110.929565 -269.062842) (xy 110.952436 -269.106419) (xy 110.96802 -269.1531) (xy 110.975915 -269.201677)
			(xy 110.97641 -269.226284) (xy 113.178856 -269.226284) (xy 113.182816 -269.17723) (xy 113.194593 -269.129446)
			(xy 113.213884 -269.08417) (xy 113.240187 -269.042574) (xy 113.272822 -269.005737) (xy 113.310943 -268.974612)
			(xy 113.353564 -268.950005) (xy 113.39958 -268.932553) (xy 113.447799 -268.922709) (xy 113.496974 -268.920728)
			(xy 113.545829 -268.92666) (xy 113.5931 -268.940352) (xy 113.637562 -268.96145) (xy 113.678065 -268.989406)
			(xy 113.713558 -269.023498) (xy 113.743123 -269.062842) (xy 113.765994 -269.106419) (xy 113.781578 -269.1531)
			(xy 113.789473 -269.201677) (xy 113.789968 -269.226284) (xy 114.11891 -269.226284) (xy 114.12287 -269.17723)
			(xy 114.134647 -269.129446) (xy 114.153938 -269.08417) (xy 114.180241 -269.042574) (xy 114.212876 -269.005737)
			(xy 114.250997 -268.974612) (xy 114.293618 -268.950005) (xy 114.339634 -268.932553) (xy 114.387853 -268.922709)
			(xy 114.437028 -268.920728) (xy 114.485883 -268.92666) (xy 114.533154 -268.940352) (xy 114.577616 -268.96145)
			(xy 114.618119 -268.989406) (xy 114.653612 -269.023498) (xy 114.683177 -269.062842) (xy 114.706048 -269.106419)
			(xy 114.721632 -269.1531) (xy 114.729527 -269.201677) (xy 114.730022 -269.226284) (xy 115.058964 -269.226284)
			(xy 115.062924 -269.17723) (xy 115.074701 -269.129446) (xy 115.093992 -269.08417) (xy 115.120295 -269.042574)
			(xy 115.15293 -269.005737) (xy 115.191051 -268.974612) (xy 115.233672 -268.950005) (xy 115.279688 -268.932553)
			(xy 115.327907 -268.922709) (xy 115.377082 -268.920728) (xy 115.425937 -268.92666) (xy 115.473208 -268.940352)
			(xy 115.51767 -268.96145) (xy 115.558173 -268.989406) (xy 115.593666 -269.023498) (xy 115.623231 -269.062842)
			(xy 115.646102 -269.106419) (xy 115.661686 -269.1531) (xy 115.669581 -269.201677) (xy 115.670076 -269.226284)
			(xy 115.999018 -269.226284) (xy 116.002978 -269.17723) (xy 116.014755 -269.129446) (xy 116.034046 -269.08417)
			(xy 116.060349 -269.042574) (xy 116.092984 -269.005737) (xy 116.131105 -268.974612) (xy 116.173726 -268.950005)
			(xy 116.219742 -268.932553) (xy 116.267961 -268.922709) (xy 116.317136 -268.920728) (xy 116.365991 -268.92666)
			(xy 116.413262 -268.940352) (xy 116.457724 -268.96145) (xy 116.498227 -268.989406) (xy 116.53372 -269.023498)
			(xy 116.563285 -269.062842) (xy 116.586156 -269.106419) (xy 116.60174 -269.1531) (xy 116.609635 -269.201677)
			(xy 116.61013 -269.226284) (xy 118.818926 -269.226284) (xy 118.822886 -269.17723) (xy 118.834663 -269.129446)
			(xy 118.853954 -269.08417) (xy 118.880257 -269.042574) (xy 118.912892 -269.005737) (xy 118.951013 -268.974612)
			(xy 118.993634 -268.950005) (xy 119.03965 -268.932553) (xy 119.087869 -268.922709) (xy 119.137044 -268.920728)
			(xy 119.185899 -268.92666) (xy 119.23317 -268.940352) (xy 119.277632 -268.96145) (xy 119.318135 -268.989406)
			(xy 119.353628 -269.023498) (xy 119.383193 -269.062842) (xy 119.406064 -269.106419) (xy 119.421648 -269.1531)
			(xy 119.429543 -269.201677) (xy 119.430038 -269.226284) (xy 121.638834 -269.226284) (xy 121.642794 -269.17723)
			(xy 121.654571 -269.129446) (xy 121.673862 -269.08417) (xy 121.700165 -269.042574) (xy 121.7328 -269.005737)
			(xy 121.770921 -268.974612) (xy 121.813542 -268.950005) (xy 121.859558 -268.932553) (xy 121.907777 -268.922709)
			(xy 121.956952 -268.920728) (xy 122.005807 -268.92666) (xy 122.053078 -268.940352) (xy 122.09754 -268.96145)
			(xy 122.138043 -268.989406) (xy 122.173536 -269.023498) (xy 122.203101 -269.062842) (xy 122.225972 -269.106419)
			(xy 122.241556 -269.1531) (xy 122.249451 -269.201677) (xy 122.249946 -269.226284) (xy 124.458996 -269.226284)
			(xy 124.462956 -269.17723) (xy 124.474733 -269.129446) (xy 124.494024 -269.08417) (xy 124.520327 -269.042574)
			(xy 124.552962 -269.005737) (xy 124.591083 -268.974612) (xy 124.633704 -268.950005) (xy 124.67972 -268.932553)
			(xy 124.727939 -268.922709) (xy 124.777114 -268.920728) (xy 124.825969 -268.92666) (xy 124.87324 -268.940352)
			(xy 124.917702 -268.96145) (xy 124.958205 -268.989406) (xy 124.993698 -269.023498) (xy 125.023263 -269.062842)
			(xy 125.046134 -269.106419) (xy 125.061718 -269.1531) (xy 125.069613 -269.201677) (xy 125.070108 -269.226284)
			(xy 125.069613 -269.250891) (xy 125.061718 -269.299468) (xy 125.046134 -269.346149) (xy 125.023263 -269.389726)
			(xy 124.993698 -269.42907) (xy 124.958205 -269.463162) (xy 124.917702 -269.491118) (xy 124.87324 -269.512216)
			(xy 124.825969 -269.525908) (xy 124.777114 -269.53184) (xy 124.727939 -269.529859) (xy 124.67972 -269.520015)
			(xy 124.633704 -269.502563) (xy 124.591083 -269.477956) (xy 124.552962 -269.446831) (xy 124.520327 -269.409994)
			(xy 124.494024 -269.368398) (xy 124.474733 -269.323122) (xy 124.462956 -269.275338) (xy 124.458996 -269.226284)
			(xy 122.249946 -269.226284) (xy 122.249451 -269.250891) (xy 122.241556 -269.299468) (xy 122.225972 -269.346149)
			(xy 122.203101 -269.389726) (xy 122.173536 -269.42907) (xy 122.138043 -269.463162) (xy 122.09754 -269.491118)
			(xy 122.053078 -269.512216) (xy 122.005807 -269.525908) (xy 121.956952 -269.53184) (xy 121.907777 -269.529859)
			(xy 121.859558 -269.520015) (xy 121.813542 -269.502563) (xy 121.770921 -269.477956) (xy 121.7328 -269.446831)
			(xy 121.700165 -269.409994) (xy 121.673862 -269.368398) (xy 121.654571 -269.323122) (xy 121.642794 -269.275338)
			(xy 121.638834 -269.226284) (xy 119.430038 -269.226284) (xy 119.429543 -269.250891) (xy 119.421648 -269.299468)
			(xy 119.406064 -269.346149) (xy 119.383193 -269.389726) (xy 119.353628 -269.42907) (xy 119.318135 -269.463162)
			(xy 119.277632 -269.491118) (xy 119.23317 -269.512216) (xy 119.185899 -269.525908) (xy 119.137044 -269.53184)
			(xy 119.087869 -269.529859) (xy 119.03965 -269.520015) (xy 118.993634 -269.502563) (xy 118.951013 -269.477956)
			(xy 118.912892 -269.446831) (xy 118.880257 -269.409994) (xy 118.853954 -269.368398) (xy 118.834663 -269.323122)
			(xy 118.822886 -269.275338) (xy 118.818926 -269.226284) (xy 116.61013 -269.226284) (xy 116.609635 -269.250891)
			(xy 116.60174 -269.299468) (xy 116.586156 -269.346149) (xy 116.563285 -269.389726) (xy 116.53372 -269.42907)
			(xy 116.498227 -269.463162) (xy 116.457724 -269.491118) (xy 116.413262 -269.512216) (xy 116.365991 -269.525908)
			(xy 116.317136 -269.53184) (xy 116.267961 -269.529859) (xy 116.219742 -269.520015) (xy 116.173726 -269.502563)
			(xy 116.131105 -269.477956) (xy 116.092984 -269.446831) (xy 116.060349 -269.409994) (xy 116.034046 -269.368398)
			(xy 116.014755 -269.323122) (xy 116.002978 -269.275338) (xy 115.999018 -269.226284) (xy 115.670076 -269.226284)
			(xy 115.669581 -269.250891) (xy 115.661686 -269.299468) (xy 115.646102 -269.346149) (xy 115.623231 -269.389726)
			(xy 115.593666 -269.42907) (xy 115.558173 -269.463162) (xy 115.51767 -269.491118) (xy 115.473208 -269.512216)
			(xy 115.425937 -269.525908) (xy 115.377082 -269.53184) (xy 115.327907 -269.529859) (xy 115.279688 -269.520015)
			(xy 115.233672 -269.502563) (xy 115.191051 -269.477956) (xy 115.15293 -269.446831) (xy 115.120295 -269.409994)
			(xy 115.093992 -269.368398) (xy 115.074701 -269.323122) (xy 115.062924 -269.275338) (xy 115.058964 -269.226284)
			(xy 114.730022 -269.226284) (xy 114.729527 -269.250891) (xy 114.721632 -269.299468) (xy 114.706048 -269.346149)
			(xy 114.683177 -269.389726) (xy 114.653612 -269.42907) (xy 114.618119 -269.463162) (xy 114.577616 -269.491118)
			(xy 114.533154 -269.512216) (xy 114.485883 -269.525908) (xy 114.437028 -269.53184) (xy 114.387853 -269.529859)
			(xy 114.339634 -269.520015) (xy 114.293618 -269.502563) (xy 114.250997 -269.477956) (xy 114.212876 -269.446831)
			(xy 114.180241 -269.409994) (xy 114.153938 -269.368398) (xy 114.134647 -269.323122) (xy 114.12287 -269.275338)
			(xy 114.11891 -269.226284) (xy 113.789968 -269.226284) (xy 113.789473 -269.250891) (xy 113.781578 -269.299468)
			(xy 113.765994 -269.346149) (xy 113.743123 -269.389726) (xy 113.713558 -269.42907) (xy 113.678065 -269.463162)
			(xy 113.637562 -269.491118) (xy 113.5931 -269.512216) (xy 113.545829 -269.525908) (xy 113.496974 -269.53184)
			(xy 113.447799 -269.529859) (xy 113.39958 -269.520015) (xy 113.353564 -269.502563) (xy 113.310943 -269.477956)
			(xy 113.272822 -269.446831) (xy 113.240187 -269.409994) (xy 113.213884 -269.368398) (xy 113.194593 -269.323122)
			(xy 113.182816 -269.275338) (xy 113.178856 -269.226284) (xy 110.97641 -269.226284) (xy 110.975915 -269.250891)
			(xy 110.96802 -269.299468) (xy 110.952436 -269.346149) (xy 110.929565 -269.389726) (xy 110.9 -269.42907)
			(xy 110.864507 -269.463162) (xy 110.824004 -269.491118) (xy 110.779542 -269.512216) (xy 110.732271 -269.525908)
			(xy 110.683416 -269.53184) (xy 110.634241 -269.529859) (xy 110.586022 -269.520015) (xy 110.540006 -269.502563)
			(xy 110.497385 -269.477956) (xy 110.459264 -269.446831) (xy 110.426629 -269.409994) (xy 110.400326 -269.368398)
			(xy 110.381035 -269.323122) (xy 110.369258 -269.275338) (xy 110.365298 -269.226284) (xy 110.036356 -269.226284)
			(xy 110.035861 -269.250891) (xy 110.027966 -269.299468) (xy 110.012382 -269.346149) (xy 109.989511 -269.389726)
			(xy 109.959946 -269.42907) (xy 109.924453 -269.463162) (xy 109.88395 -269.491118) (xy 109.839488 -269.512216)
			(xy 109.792217 -269.525908) (xy 109.743362 -269.53184) (xy 109.694187 -269.529859) (xy 109.645968 -269.520015)
			(xy 109.599952 -269.502563) (xy 109.557331 -269.477956) (xy 109.51921 -269.446831) (xy 109.486575 -269.409994)
			(xy 109.460272 -269.368398) (xy 109.440981 -269.323122) (xy 109.429204 -269.275338) (xy 109.425244 -269.226284)
			(xy 109.096302 -269.226284) (xy 109.095807 -269.250891) (xy 109.087912 -269.299468) (xy 109.072328 -269.346149)
			(xy 109.049457 -269.389726) (xy 109.019892 -269.42907) (xy 108.984399 -269.463162) (xy 108.943896 -269.491118)
			(xy 108.899434 -269.512216) (xy 108.852163 -269.525908) (xy 108.803308 -269.53184) (xy 108.754133 -269.529859)
			(xy 108.705914 -269.520015) (xy 108.659898 -269.502563) (xy 108.617277 -269.477956) (xy 108.579156 -269.446831)
			(xy 108.546521 -269.409994) (xy 108.520218 -269.368398) (xy 108.500927 -269.323122) (xy 108.48915 -269.275338)
			(xy 108.48519 -269.226284) (xy 108.156248 -269.226284) (xy 108.155753 -269.250891) (xy 108.147858 -269.299468)
			(xy 108.132274 -269.346149) (xy 108.109403 -269.389726) (xy 108.079838 -269.42907) (xy 108.044345 -269.463162)
			(xy 108.003842 -269.491118) (xy 107.95938 -269.512216) (xy 107.912109 -269.525908) (xy 107.863254 -269.53184)
			(xy 107.814079 -269.529859) (xy 107.76586 -269.520015) (xy 107.719844 -269.502563) (xy 107.677223 -269.477956)
			(xy 107.639102 -269.446831) (xy 107.606467 -269.409994) (xy 107.580164 -269.368398) (xy 107.560873 -269.323122)
			(xy 107.549096 -269.275338) (xy 107.545136 -269.226284) (xy 105.33634 -269.226284) (xy 105.335845 -269.250891)
			(xy 105.32795 -269.299468) (xy 105.312366 -269.346149) (xy 105.289495 -269.389726) (xy 105.25993 -269.42907)
			(xy 105.224437 -269.463162) (xy 105.183934 -269.491118) (xy 105.139472 -269.512216) (xy 105.092201 -269.525908)
			(xy 105.043346 -269.53184) (xy 104.994171 -269.529859) (xy 104.945952 -269.520015) (xy 104.899936 -269.502563)
			(xy 104.857315 -269.477956) (xy 104.819194 -269.446831) (xy 104.786559 -269.409994) (xy 104.760256 -269.368398)
			(xy 104.740965 -269.323122) (xy 104.729188 -269.275338) (xy 104.725228 -269.226284) (xy 102.516432 -269.226284)
			(xy 102.515937 -269.250891) (xy 102.508042 -269.299468) (xy 102.492458 -269.346149) (xy 102.469587 -269.389726)
			(xy 102.440022 -269.42907) (xy 102.404529 -269.463162) (xy 102.364026 -269.491118) (xy 102.319564 -269.512216)
			(xy 102.272293 -269.525908) (xy 102.223438 -269.53184) (xy 102.174263 -269.529859) (xy 102.126044 -269.520015)
			(xy 102.080028 -269.502563) (xy 102.037407 -269.477956) (xy 101.999286 -269.446831) (xy 101.966651 -269.409994)
			(xy 101.940348 -269.368398) (xy 101.921057 -269.323122) (xy 101.90928 -269.275338) (xy 101.90532 -269.226284)
			(xy 99.69627 -269.226284) (xy 99.695775 -269.250891) (xy 99.68788 -269.299468) (xy 99.672296 -269.346149)
			(xy 99.649425 -269.389726) (xy 99.61986 -269.42907) (xy 99.584367 -269.463162) (xy 99.543864 -269.491118)
			(xy 99.499402 -269.512216) (xy 99.452131 -269.525908) (xy 99.403276 -269.53184) (xy 99.354101 -269.529859)
			(xy 99.305882 -269.520015) (xy 99.259866 -269.502563) (xy 99.217245 -269.477956) (xy 99.179124 -269.446831)
			(xy 99.146489 -269.409994) (xy 99.120186 -269.368398) (xy 99.100895 -269.323122) (xy 99.089118 -269.275338)
			(xy 99.085158 -269.226284) (xy 96.876362 -269.226284) (xy 96.875894 -269.250888) (xy 96.868001 -269.29946)
			(xy 96.852417 -269.346135) (xy 96.829545 -269.389705) (xy 96.799978 -269.429041) (xy 96.764483 -269.463123)
			(xy 96.723979 -269.491067) (xy 96.679517 -269.512151) (xy 96.632247 -269.525827) (xy 96.607884 -269.529306)
			(xy 96.60509 -269.52956) (xy 96.599042 -269.530833) (xy 96.587749 -269.535847) (xy 96.582738 -269.539466)
			(xy 96.577658 -269.543276) (xy 96.573848 -269.548356) (xy 96.567244 -269.559786) (xy 96.533208 -269.642336)
			(xy 96.531262 -269.648225) (xy 96.529968 -269.660558) (xy 96.530668 -269.66672) (xy 96.532446 -269.679674)
			(xy 96.541082 -269.69085) (xy 96.565555 -269.72333) (xy 96.605849 -269.793967) (xy 96.621346 -269.831566)
			(xy 96.62414 -269.838424) (xy 96.63176 -269.848838) (xy 96.637348 -269.853156) (xy 96.642018 -269.856592)
			(xy 96.652536 -269.861464) (xy 96.658176 -269.862808) (xy 96.75114 -269.875) (xy 96.754912 -269.875177)
			(xy 96.762436 -269.874532) (xy 96.766126 -269.87373) (xy 96.77527 -269.870936) (xy 96.787208 -269.865602)
			(xy 96.788478 -269.863824) (xy 96.795336 -269.85468) (xy 96.79559 -269.854172) (xy 96.810125 -269.835397)
			(xy 96.844023 -269.802153) (xy 96.882653 -269.774549) (xy 96.925086 -269.75325) (xy 96.970303 -269.738768)
			(xy 97.017214 -269.731451) (xy 97.040954 -269.730982) (xy 97.06495 -269.731425) (xy 97.112351 -269.738926)
			(xy 97.157996 -269.75375) (xy 97.200759 -269.775533) (xy 97.239588 -269.803737) (xy 97.273526 -269.837669)
			(xy 97.301738 -269.876493) (xy 97.323528 -269.919252) (xy 97.338361 -269.964894) (xy 97.345871 -270.012294)
			(xy 97.346262 -270.03629) (xy 97.675204 -270.03629) (xy 97.679164 -269.987236) (xy 97.690941 -269.939452)
			(xy 97.710232 -269.894176) (xy 97.736535 -269.85258) (xy 97.76917 -269.815743) (xy 97.807291 -269.784618)
			(xy 97.849912 -269.760011) (xy 97.895928 -269.742559) (xy 97.944147 -269.732715) (xy 97.993322 -269.730734)
			(xy 98.042177 -269.736666) (xy 98.089448 -269.750358) (xy 98.13391 -269.771456) (xy 98.174413 -269.799412)
			(xy 98.209906 -269.833504) (xy 98.239471 -269.872848) (xy 98.262342 -269.916425) (xy 98.277926 -269.963106)
			(xy 98.285821 -270.011683) (xy 98.286316 -270.03629) (xy 98.615258 -270.03629) (xy 98.619218 -269.987236)
			(xy 98.630995 -269.939452) (xy 98.650286 -269.894176) (xy 98.676589 -269.85258) (xy 98.709224 -269.815743)
			(xy 98.747345 -269.784618) (xy 98.789966 -269.760011) (xy 98.835982 -269.742559) (xy 98.884201 -269.732715)
			(xy 98.933376 -269.730734) (xy 98.982231 -269.736666) (xy 99.029502 -269.750358) (xy 99.073964 -269.771456)
			(xy 99.114467 -269.799412) (xy 99.14996 -269.833504) (xy 99.179525 -269.872848) (xy 99.202396 -269.916425)
			(xy 99.21798 -269.963106) (xy 99.225875 -270.011683) (xy 99.22637 -270.03629) (xy 99.555312 -270.03629)
			(xy 99.559272 -269.987236) (xy 99.571049 -269.939452) (xy 99.59034 -269.894176) (xy 99.616643 -269.85258)
			(xy 99.649278 -269.815743) (xy 99.687399 -269.784618) (xy 99.73002 -269.760011) (xy 99.776036 -269.742559)
			(xy 99.824255 -269.732715) (xy 99.87343 -269.730734) (xy 99.922285 -269.736666) (xy 99.969556 -269.750358)
			(xy 100.014018 -269.771456) (xy 100.054521 -269.799412) (xy 100.090014 -269.833504) (xy 100.119579 -269.872848)
			(xy 100.14245 -269.916425) (xy 100.158034 -269.963106) (xy 100.165929 -270.011683) (xy 100.166424 -270.03629)
			(xy 100.495366 -270.03629) (xy 100.499326 -269.987236) (xy 100.511103 -269.939452) (xy 100.530394 -269.894176)
			(xy 100.556697 -269.85258) (xy 100.589332 -269.815743) (xy 100.627453 -269.784618) (xy 100.670074 -269.760011)
			(xy 100.71609 -269.742559) (xy 100.764309 -269.732715) (xy 100.813484 -269.730734) (xy 100.862339 -269.736666)
			(xy 100.90961 -269.750358) (xy 100.954072 -269.771456) (xy 100.994575 -269.799412) (xy 101.030068 -269.833504)
			(xy 101.059633 -269.872848) (xy 101.082504 -269.916425) (xy 101.098088 -269.963106) (xy 101.105983 -270.011683)
			(xy 101.106478 -270.03629) (xy 101.435166 -270.03629) (xy 101.439126 -269.987236) (xy 101.450903 -269.939452)
			(xy 101.470194 -269.894176) (xy 101.496497 -269.85258) (xy 101.529132 -269.815743) (xy 101.567253 -269.784618)
			(xy 101.609874 -269.760011) (xy 101.65589 -269.742559) (xy 101.704109 -269.732715) (xy 101.753284 -269.730734)
			(xy 101.802139 -269.736666) (xy 101.84941 -269.750358) (xy 101.893872 -269.771456) (xy 101.934375 -269.799412)
			(xy 101.969868 -269.833504) (xy 101.999433 -269.872848) (xy 102.022304 -269.916425) (xy 102.037888 -269.963106)
			(xy 102.045783 -270.011683) (xy 102.046278 -270.03629) (xy 102.37522 -270.03629) (xy 102.37918 -269.987236)
			(xy 102.390957 -269.939452) (xy 102.410248 -269.894176) (xy 102.436551 -269.85258) (xy 102.469186 -269.815743)
			(xy 102.507307 -269.784618) (xy 102.549928 -269.760011) (xy 102.595944 -269.742559) (xy 102.644163 -269.732715)
			(xy 102.693338 -269.730734) (xy 102.742193 -269.736666) (xy 102.789464 -269.750358) (xy 102.833926 -269.771456)
			(xy 102.874429 -269.799412) (xy 102.909922 -269.833504) (xy 102.939487 -269.872848) (xy 102.962358 -269.916425)
			(xy 102.977942 -269.963106) (xy 102.985837 -270.011683) (xy 102.986332 -270.03629) (xy 103.315274 -270.03629)
			(xy 103.319234 -269.987236) (xy 103.331011 -269.939452) (xy 103.350302 -269.894176) (xy 103.376605 -269.85258)
			(xy 103.40924 -269.815743) (xy 103.447361 -269.784618) (xy 103.489982 -269.760011) (xy 103.535998 -269.742559)
			(xy 103.584217 -269.732715) (xy 103.633392 -269.730734) (xy 103.682247 -269.736666) (xy 103.729518 -269.750358)
			(xy 103.77398 -269.771456) (xy 103.814483 -269.799412) (xy 103.849976 -269.833504) (xy 103.879541 -269.872848)
			(xy 103.902412 -269.916425) (xy 103.917996 -269.963106) (xy 103.925891 -270.011683) (xy 103.926386 -270.03629)
			(xy 104.255328 -270.03629) (xy 104.259288 -269.987236) (xy 104.271065 -269.939452) (xy 104.290356 -269.894176)
			(xy 104.316659 -269.85258) (xy 104.349294 -269.815743) (xy 104.387415 -269.784618) (xy 104.430036 -269.760011)
			(xy 104.476052 -269.742559) (xy 104.524271 -269.732715) (xy 104.573446 -269.730734) (xy 104.622301 -269.736666)
			(xy 104.669572 -269.750358) (xy 104.714034 -269.771456) (xy 104.754537 -269.799412) (xy 104.79003 -269.833504)
			(xy 104.819595 -269.872848) (xy 104.842466 -269.916425) (xy 104.85805 -269.963106) (xy 104.865945 -270.011683)
			(xy 104.86644 -270.03629) (xy 105.195128 -270.03629) (xy 105.199088 -269.987236) (xy 105.210865 -269.939452)
			(xy 105.230156 -269.894176) (xy 105.256459 -269.85258) (xy 105.289094 -269.815743) (xy 105.327215 -269.784618)
			(xy 105.369836 -269.760011) (xy 105.415852 -269.742559) (xy 105.464071 -269.732715) (xy 105.513246 -269.730734)
			(xy 105.562101 -269.736666) (xy 105.609372 -269.750358) (xy 105.653834 -269.771456) (xy 105.694337 -269.799412)
			(xy 105.72983 -269.833504) (xy 105.759395 -269.872848) (xy 105.782266 -269.916425) (xy 105.79785 -269.963106)
			(xy 105.805745 -270.011683) (xy 105.80624 -270.03629) (xy 106.135182 -270.03629) (xy 106.139142 -269.987236)
			(xy 106.150919 -269.939452) (xy 106.17021 -269.894176) (xy 106.196513 -269.85258) (xy 106.229148 -269.815743)
			(xy 106.267269 -269.784618) (xy 106.30989 -269.760011) (xy 106.355906 -269.742559) (xy 106.404125 -269.732715)
			(xy 106.4533 -269.730734) (xy 106.502155 -269.736666) (xy 106.549426 -269.750358) (xy 106.593888 -269.771456)
			(xy 106.634391 -269.799412) (xy 106.669884 -269.833504) (xy 106.699449 -269.872848) (xy 106.72232 -269.916425)
			(xy 106.737904 -269.963106) (xy 106.745799 -270.011683) (xy 106.746294 -270.03629) (xy 107.075236 -270.03629)
			(xy 107.079196 -269.987236) (xy 107.090973 -269.939452) (xy 107.110264 -269.894176) (xy 107.136567 -269.85258)
			(xy 107.169202 -269.815743) (xy 107.207323 -269.784618) (xy 107.249944 -269.760011) (xy 107.29596 -269.742559)
			(xy 107.344179 -269.732715) (xy 107.393354 -269.730734) (xy 107.442209 -269.736666) (xy 107.48948 -269.750358)
			(xy 107.533942 -269.771456) (xy 107.574445 -269.799412) (xy 107.609938 -269.833504) (xy 107.639503 -269.872848)
			(xy 107.662374 -269.916425) (xy 107.677958 -269.963106) (xy 107.685853 -270.011683) (xy 107.686348 -270.03629)
			(xy 108.01529 -270.03629) (xy 108.01925 -269.987236) (xy 108.031027 -269.939452) (xy 108.050318 -269.894176)
			(xy 108.076621 -269.85258) (xy 108.109256 -269.815743) (xy 108.147377 -269.784618) (xy 108.189998 -269.760011)
			(xy 108.236014 -269.742559) (xy 108.284233 -269.732715) (xy 108.333408 -269.730734) (xy 108.382263 -269.736666)
			(xy 108.429534 -269.750358) (xy 108.473996 -269.771456) (xy 108.514499 -269.799412) (xy 108.549992 -269.833504)
			(xy 108.579557 -269.872848) (xy 108.602428 -269.916425) (xy 108.618012 -269.963106) (xy 108.625907 -270.011683)
			(xy 108.626402 -270.03629) (xy 108.955344 -270.03629) (xy 108.959304 -269.987236) (xy 108.971081 -269.939452)
			(xy 108.990372 -269.894176) (xy 109.016675 -269.85258) (xy 109.04931 -269.815743) (xy 109.087431 -269.784618)
			(xy 109.130052 -269.760011) (xy 109.176068 -269.742559) (xy 109.224287 -269.732715) (xy 109.273462 -269.730734)
			(xy 109.322317 -269.736666) (xy 109.369588 -269.750358) (xy 109.41405 -269.771456) (xy 109.454553 -269.799412)
			(xy 109.490046 -269.833504) (xy 109.519611 -269.872848) (xy 109.542482 -269.916425) (xy 109.558066 -269.963106)
			(xy 109.565961 -270.011683) (xy 109.566456 -270.03629) (xy 109.895144 -270.03629) (xy 109.899104 -269.987236)
			(xy 109.910881 -269.939452) (xy 109.930172 -269.894176) (xy 109.956475 -269.85258) (xy 109.98911 -269.815743)
			(xy 110.027231 -269.784618) (xy 110.069852 -269.760011) (xy 110.115868 -269.742559) (xy 110.164087 -269.732715)
			(xy 110.213262 -269.730734) (xy 110.262117 -269.736666) (xy 110.309388 -269.750358) (xy 110.35385 -269.771456)
			(xy 110.394353 -269.799412) (xy 110.429846 -269.833504) (xy 110.459411 -269.872848) (xy 110.482282 -269.916425)
			(xy 110.497866 -269.963106) (xy 110.505761 -270.011683) (xy 110.506256 -270.03629) (xy 113.64901 -270.03629)
			(xy 113.65297 -269.987236) (xy 113.664747 -269.939452) (xy 113.684038 -269.894176) (xy 113.710341 -269.85258)
			(xy 113.742976 -269.815743) (xy 113.781097 -269.784618) (xy 113.823718 -269.760011) (xy 113.869734 -269.742559)
			(xy 113.917953 -269.732715) (xy 113.967128 -269.730734) (xy 114.015983 -269.736666) (xy 114.063254 -269.750358)
			(xy 114.107716 -269.771456) (xy 114.148219 -269.799412) (xy 114.183712 -269.833504) (xy 114.213277 -269.872848)
			(xy 114.236148 -269.916425) (xy 114.251732 -269.963106) (xy 114.259627 -270.011683) (xy 114.260122 -270.03629)
			(xy 114.58881 -270.03629) (xy 114.59277 -269.987236) (xy 114.604547 -269.939452) (xy 114.623838 -269.894176)
			(xy 114.650141 -269.85258) (xy 114.682776 -269.815743) (xy 114.720897 -269.784618) (xy 114.763518 -269.760011)
			(xy 114.809534 -269.742559) (xy 114.857753 -269.732715) (xy 114.906928 -269.730734) (xy 114.955783 -269.736666)
			(xy 115.003054 -269.750358) (xy 115.047516 -269.771456) (xy 115.088019 -269.799412) (xy 115.123512 -269.833504)
			(xy 115.153077 -269.872848) (xy 115.175948 -269.916425) (xy 115.191532 -269.963106) (xy 115.199427 -270.011683)
			(xy 115.199922 -270.03629) (xy 115.528864 -270.03629) (xy 115.532824 -269.987236) (xy 115.544601 -269.939452)
			(xy 115.563892 -269.894176) (xy 115.590195 -269.85258) (xy 115.62283 -269.815743) (xy 115.660951 -269.784618)
			(xy 115.703572 -269.760011) (xy 115.749588 -269.742559) (xy 115.797807 -269.732715) (xy 115.846982 -269.730734)
			(xy 115.895837 -269.736666) (xy 115.943108 -269.750358) (xy 115.98757 -269.771456) (xy 116.028073 -269.799412)
			(xy 116.063566 -269.833504) (xy 116.093131 -269.872848) (xy 116.116002 -269.916425) (xy 116.131586 -269.963106)
			(xy 116.139481 -270.011683) (xy 116.139976 -270.03629) (xy 116.468918 -270.03629) (xy 116.472878 -269.987236)
			(xy 116.484655 -269.939452) (xy 116.503946 -269.894176) (xy 116.530249 -269.85258) (xy 116.562884 -269.815743)
			(xy 116.601005 -269.784618) (xy 116.643626 -269.760011) (xy 116.689642 -269.742559) (xy 116.737861 -269.732715)
			(xy 116.787036 -269.730734) (xy 116.835891 -269.736666) (xy 116.883162 -269.750358) (xy 116.927624 -269.771456)
			(xy 116.968127 -269.799412) (xy 117.00362 -269.833504) (xy 117.033185 -269.872848) (xy 117.056056 -269.916425)
			(xy 117.07164 -269.963106) (xy 117.079535 -270.011683) (xy 117.08003 -270.03629) (xy 117.408972 -270.03629)
			(xy 117.412932 -269.987236) (xy 117.424709 -269.939452) (xy 117.444 -269.894176) (xy 117.470303 -269.85258)
			(xy 117.502938 -269.815743) (xy 117.541059 -269.784618) (xy 117.58368 -269.760011) (xy 117.629696 -269.742559)
			(xy 117.677915 -269.732715) (xy 117.72709 -269.730734) (xy 117.775945 -269.736666) (xy 117.823216 -269.750358)
			(xy 117.867678 -269.771456) (xy 117.908181 -269.799412) (xy 117.943674 -269.833504) (xy 117.973239 -269.872848)
			(xy 117.99611 -269.916425) (xy 118.011694 -269.963106) (xy 118.019589 -270.011683) (xy 118.020084 -270.03629)
			(xy 118.349026 -270.03629) (xy 118.352986 -269.987236) (xy 118.364763 -269.939452) (xy 118.384054 -269.894176)
			(xy 118.410357 -269.85258) (xy 118.442992 -269.815743) (xy 118.481113 -269.784618) (xy 118.523734 -269.760011)
			(xy 118.56975 -269.742559) (xy 118.617969 -269.732715) (xy 118.667144 -269.730734) (xy 118.715999 -269.736666)
			(xy 118.76327 -269.750358) (xy 118.807732 -269.771456) (xy 118.848235 -269.799412) (xy 118.883728 -269.833504)
			(xy 118.913293 -269.872848) (xy 118.936164 -269.916425) (xy 118.951748 -269.963106) (xy 118.959643 -270.011683)
			(xy 118.960138 -270.03629) (xy 119.288826 -270.03629) (xy 119.292786 -269.987236) (xy 119.304563 -269.939452)
			(xy 119.323854 -269.894176) (xy 119.350157 -269.85258) (xy 119.382792 -269.815743) (xy 119.420913 -269.784618)
			(xy 119.463534 -269.760011) (xy 119.50955 -269.742559) (xy 119.557769 -269.732715) (xy 119.606944 -269.730734)
			(xy 119.655799 -269.736666) (xy 119.70307 -269.750358) (xy 119.747532 -269.771456) (xy 119.788035 -269.799412)
			(xy 119.823528 -269.833504) (xy 119.853093 -269.872848) (xy 119.875964 -269.916425) (xy 119.891548 -269.963106)
			(xy 119.899443 -270.011683) (xy 119.899938 -270.03629) (xy 120.22888 -270.03629) (xy 120.23284 -269.987236)
			(xy 120.244617 -269.939452) (xy 120.263908 -269.894176) (xy 120.290211 -269.85258) (xy 120.322846 -269.815743)
			(xy 120.360967 -269.784618) (xy 120.403588 -269.760011) (xy 120.449604 -269.742559) (xy 120.497823 -269.732715)
			(xy 120.546998 -269.730734) (xy 120.595853 -269.736666) (xy 120.643124 -269.750358) (xy 120.687586 -269.771456)
			(xy 120.728089 -269.799412) (xy 120.763582 -269.833504) (xy 120.793147 -269.872848) (xy 120.816018 -269.916425)
			(xy 120.831602 -269.963106) (xy 120.839497 -270.011683) (xy 120.839992 -270.03629) (xy 121.168934 -270.03629)
			(xy 121.172894 -269.987236) (xy 121.184671 -269.939452) (xy 121.203962 -269.894176) (xy 121.230265 -269.85258)
			(xy 121.2629 -269.815743) (xy 121.301021 -269.784618) (xy 121.343642 -269.760011) (xy 121.389658 -269.742559)
			(xy 121.437877 -269.732715) (xy 121.487052 -269.730734) (xy 121.535907 -269.736666) (xy 121.583178 -269.750358)
			(xy 121.62764 -269.771456) (xy 121.668143 -269.799412) (xy 121.703636 -269.833504) (xy 121.733201 -269.872848)
			(xy 121.756072 -269.916425) (xy 121.771656 -269.963106) (xy 121.779551 -270.011683) (xy 121.780046 -270.03629)
			(xy 122.108988 -270.03629) (xy 122.112948 -269.987236) (xy 122.124725 -269.939452) (xy 122.144016 -269.894176)
			(xy 122.170319 -269.85258) (xy 122.202954 -269.815743) (xy 122.241075 -269.784618) (xy 122.283696 -269.760011)
			(xy 122.329712 -269.742559) (xy 122.377931 -269.732715) (xy 122.427106 -269.730734) (xy 122.475961 -269.736666)
			(xy 122.523232 -269.750358) (xy 122.567694 -269.771456) (xy 122.608197 -269.799412) (xy 122.64369 -269.833504)
			(xy 122.673255 -269.872848) (xy 122.696126 -269.916425) (xy 122.71171 -269.963106) (xy 122.719605 -270.011683)
			(xy 122.7201 -270.03629) (xy 123.049042 -270.03629) (xy 123.053002 -269.987236) (xy 123.064779 -269.939452)
			(xy 123.08407 -269.894176) (xy 123.110373 -269.85258) (xy 123.143008 -269.815743) (xy 123.181129 -269.784618)
			(xy 123.22375 -269.760011) (xy 123.269766 -269.742559) (xy 123.317985 -269.732715) (xy 123.36716 -269.730734)
			(xy 123.416015 -269.736666) (xy 123.463286 -269.750358) (xy 123.507748 -269.771456) (xy 123.548251 -269.799412)
			(xy 123.583744 -269.833504) (xy 123.613309 -269.872848) (xy 123.63618 -269.916425) (xy 123.651764 -269.963106)
			(xy 123.659659 -270.011683) (xy 123.660154 -270.03629) (xy 123.988842 -270.03629) (xy 123.992802 -269.987236)
			(xy 124.004579 -269.939452) (xy 124.02387 -269.894176) (xy 124.050173 -269.85258) (xy 124.082808 -269.815743)
			(xy 124.120929 -269.784618) (xy 124.16355 -269.760011) (xy 124.209566 -269.742559) (xy 124.257785 -269.732715)
			(xy 124.30696 -269.730734) (xy 124.355815 -269.736666) (xy 124.403086 -269.750358) (xy 124.447548 -269.771456)
			(xy 124.488051 -269.799412) (xy 124.523544 -269.833504) (xy 124.553109 -269.872848) (xy 124.57598 -269.916425)
			(xy 124.591564 -269.963106) (xy 124.599459 -270.011683) (xy 124.599954 -270.03629) (xy 124.928896 -270.03629)
			(xy 124.932856 -269.987236) (xy 124.944633 -269.939452) (xy 124.963924 -269.894176) (xy 124.990227 -269.85258)
			(xy 125.022862 -269.815743) (xy 125.060983 -269.784618) (xy 125.103604 -269.760011) (xy 125.14962 -269.742559)
			(xy 125.197839 -269.732715) (xy 125.247014 -269.730734) (xy 125.295869 -269.736666) (xy 125.34314 -269.750358)
			(xy 125.387602 -269.771456) (xy 125.428105 -269.799412) (xy 125.463598 -269.833504) (xy 125.493163 -269.872848)
			(xy 125.516034 -269.916425) (xy 125.531618 -269.963106) (xy 125.539513 -270.011683) (xy 125.540008 -270.03629)
			(xy 125.86895 -270.03629) (xy 125.87291 -269.987236) (xy 125.884687 -269.939452) (xy 125.903978 -269.894176)
			(xy 125.930281 -269.85258) (xy 125.962916 -269.815743) (xy 126.001037 -269.784618) (xy 126.043658 -269.760011)
			(xy 126.089674 -269.742559) (xy 126.137893 -269.732715) (xy 126.187068 -269.730734) (xy 126.235923 -269.736666)
			(xy 126.283194 -269.750358) (xy 126.327656 -269.771456) (xy 126.368159 -269.799412) (xy 126.403652 -269.833504)
			(xy 126.433217 -269.872848) (xy 126.456088 -269.916425) (xy 126.471672 -269.963106) (xy 126.479567 -270.011683)
			(xy 126.480062 -270.03629) (xy 126.479567 -270.060897) (xy 126.471672 -270.109474) (xy 126.456088 -270.156155)
			(xy 126.433217 -270.199732) (xy 126.403652 -270.239076) (xy 126.368159 -270.273168) (xy 126.327656 -270.301124)
			(xy 126.283194 -270.322222) (xy 126.235923 -270.335914) (xy 126.187068 -270.341846) (xy 126.137893 -270.339865)
			(xy 126.089674 -270.330021) (xy 126.043658 -270.312569) (xy 126.001037 -270.287962) (xy 125.962916 -270.256837)
			(xy 125.930281 -270.22) (xy 125.903978 -270.178404) (xy 125.884687 -270.133128) (xy 125.87291 -270.085344)
			(xy 125.86895 -270.03629) (xy 125.540008 -270.03629) (xy 125.539513 -270.060897) (xy 125.531618 -270.109474)
			(xy 125.516034 -270.156155) (xy 125.493163 -270.199732) (xy 125.463598 -270.239076) (xy 125.428105 -270.273168)
			(xy 125.387602 -270.301124) (xy 125.34314 -270.322222) (xy 125.295869 -270.335914) (xy 125.247014 -270.341846)
			(xy 125.197839 -270.339865) (xy 125.14962 -270.330021) (xy 125.103604 -270.312569) (xy 125.060983 -270.287962)
			(xy 125.022862 -270.256837) (xy 124.990227 -270.22) (xy 124.963924 -270.178404) (xy 124.944633 -270.133128)
			(xy 124.932856 -270.085344) (xy 124.928896 -270.03629) (xy 124.599954 -270.03629) (xy 124.599459 -270.060897)
			(xy 124.591564 -270.109474) (xy 124.57598 -270.156155) (xy 124.553109 -270.199732) (xy 124.523544 -270.239076)
			(xy 124.488051 -270.273168) (xy 124.447548 -270.301124) (xy 124.403086 -270.322222) (xy 124.355815 -270.335914)
			(xy 124.30696 -270.341846) (xy 124.257785 -270.339865) (xy 124.209566 -270.330021) (xy 124.16355 -270.312569)
			(xy 124.120929 -270.287962) (xy 124.082808 -270.256837) (xy 124.050173 -270.22) (xy 124.02387 -270.178404)
			(xy 124.004579 -270.133128) (xy 123.992802 -270.085344) (xy 123.988842 -270.03629) (xy 123.660154 -270.03629)
			(xy 123.659659 -270.060897) (xy 123.651764 -270.109474) (xy 123.63618 -270.156155) (xy 123.613309 -270.199732)
			(xy 123.583744 -270.239076) (xy 123.548251 -270.273168) (xy 123.507748 -270.301124) (xy 123.463286 -270.322222)
			(xy 123.416015 -270.335914) (xy 123.36716 -270.341846) (xy 123.317985 -270.339865) (xy 123.269766 -270.330021)
			(xy 123.22375 -270.312569) (xy 123.181129 -270.287962) (xy 123.143008 -270.256837) (xy 123.110373 -270.22)
			(xy 123.08407 -270.178404) (xy 123.064779 -270.133128) (xy 123.053002 -270.085344) (xy 123.049042 -270.03629)
			(xy 122.7201 -270.03629) (xy 122.719605 -270.060897) (xy 122.71171 -270.109474) (xy 122.696126 -270.156155)
			(xy 122.673255 -270.199732) (xy 122.64369 -270.239076) (xy 122.608197 -270.273168) (xy 122.567694 -270.301124)
			(xy 122.523232 -270.322222) (xy 122.475961 -270.335914) (xy 122.427106 -270.341846) (xy 122.377931 -270.339865)
			(xy 122.329712 -270.330021) (xy 122.283696 -270.312569) (xy 122.241075 -270.287962) (xy 122.202954 -270.256837)
			(xy 122.170319 -270.22) (xy 122.144016 -270.178404) (xy 122.124725 -270.133128) (xy 122.112948 -270.085344)
			(xy 122.108988 -270.03629) (xy 121.780046 -270.03629) (xy 121.779551 -270.060897) (xy 121.771656 -270.109474)
			(xy 121.756072 -270.156155) (xy 121.733201 -270.199732) (xy 121.703636 -270.239076) (xy 121.668143 -270.273168)
			(xy 121.62764 -270.301124) (xy 121.583178 -270.322222) (xy 121.535907 -270.335914) (xy 121.487052 -270.341846)
			(xy 121.437877 -270.339865) (xy 121.389658 -270.330021) (xy 121.343642 -270.312569) (xy 121.301021 -270.287962)
			(xy 121.2629 -270.256837) (xy 121.230265 -270.22) (xy 121.203962 -270.178404) (xy 121.184671 -270.133128)
			(xy 121.172894 -270.085344) (xy 121.168934 -270.03629) (xy 120.839992 -270.03629) (xy 120.839497 -270.060897)
			(xy 120.831602 -270.109474) (xy 120.816018 -270.156155) (xy 120.793147 -270.199732) (xy 120.763582 -270.239076)
			(xy 120.728089 -270.273168) (xy 120.687586 -270.301124) (xy 120.643124 -270.322222) (xy 120.595853 -270.335914)
			(xy 120.546998 -270.341846) (xy 120.497823 -270.339865) (xy 120.449604 -270.330021) (xy 120.403588 -270.312569)
			(xy 120.360967 -270.287962) (xy 120.322846 -270.256837) (xy 120.290211 -270.22) (xy 120.263908 -270.178404)
			(xy 120.244617 -270.133128) (xy 120.23284 -270.085344) (xy 120.22888 -270.03629) (xy 119.899938 -270.03629)
			(xy 119.899443 -270.060897) (xy 119.891548 -270.109474) (xy 119.875964 -270.156155) (xy 119.853093 -270.199732)
			(xy 119.823528 -270.239076) (xy 119.788035 -270.273168) (xy 119.747532 -270.301124) (xy 119.70307 -270.322222)
			(xy 119.655799 -270.335914) (xy 119.606944 -270.341846) (xy 119.557769 -270.339865) (xy 119.50955 -270.330021)
			(xy 119.463534 -270.312569) (xy 119.420913 -270.287962) (xy 119.382792 -270.256837) (xy 119.350157 -270.22)
			(xy 119.323854 -270.178404) (xy 119.304563 -270.133128) (xy 119.292786 -270.085344) (xy 119.288826 -270.03629)
			(xy 118.960138 -270.03629) (xy 118.959643 -270.060897) (xy 118.951748 -270.109474) (xy 118.936164 -270.156155)
			(xy 118.913293 -270.199732) (xy 118.883728 -270.239076) (xy 118.848235 -270.273168) (xy 118.807732 -270.301124)
			(xy 118.76327 -270.322222) (xy 118.715999 -270.335914) (xy 118.667144 -270.341846) (xy 118.617969 -270.339865)
			(xy 118.56975 -270.330021) (xy 118.523734 -270.312569) (xy 118.481113 -270.287962) (xy 118.442992 -270.256837)
			(xy 118.410357 -270.22) (xy 118.384054 -270.178404) (xy 118.364763 -270.133128) (xy 118.352986 -270.085344)
			(xy 118.349026 -270.03629) (xy 118.020084 -270.03629) (xy 118.019589 -270.060897) (xy 118.011694 -270.109474)
			(xy 117.99611 -270.156155) (xy 117.973239 -270.199732) (xy 117.943674 -270.239076) (xy 117.908181 -270.273168)
			(xy 117.867678 -270.301124) (xy 117.823216 -270.322222) (xy 117.775945 -270.335914) (xy 117.72709 -270.341846)
			(xy 117.677915 -270.339865) (xy 117.629696 -270.330021) (xy 117.58368 -270.312569) (xy 117.541059 -270.287962)
			(xy 117.502938 -270.256837) (xy 117.470303 -270.22) (xy 117.444 -270.178404) (xy 117.424709 -270.133128)
			(xy 117.412932 -270.085344) (xy 117.408972 -270.03629) (xy 117.08003 -270.03629) (xy 117.079535 -270.060897)
			(xy 117.07164 -270.109474) (xy 117.056056 -270.156155) (xy 117.033185 -270.199732) (xy 117.00362 -270.239076)
			(xy 116.968127 -270.273168) (xy 116.927624 -270.301124) (xy 116.883162 -270.322222) (xy 116.835891 -270.335914)
			(xy 116.787036 -270.341846) (xy 116.737861 -270.339865) (xy 116.689642 -270.330021) (xy 116.643626 -270.312569)
			(xy 116.601005 -270.287962) (xy 116.562884 -270.256837) (xy 116.530249 -270.22) (xy 116.503946 -270.178404)
			(xy 116.484655 -270.133128) (xy 116.472878 -270.085344) (xy 116.468918 -270.03629) (xy 116.139976 -270.03629)
			(xy 116.139481 -270.060897) (xy 116.131586 -270.109474) (xy 116.116002 -270.156155) (xy 116.093131 -270.199732)
			(xy 116.063566 -270.239076) (xy 116.028073 -270.273168) (xy 115.98757 -270.301124) (xy 115.943108 -270.322222)
			(xy 115.895837 -270.335914) (xy 115.846982 -270.341846) (xy 115.797807 -270.339865) (xy 115.749588 -270.330021)
			(xy 115.703572 -270.312569) (xy 115.660951 -270.287962) (xy 115.62283 -270.256837) (xy 115.590195 -270.22)
			(xy 115.563892 -270.178404) (xy 115.544601 -270.133128) (xy 115.532824 -270.085344) (xy 115.528864 -270.03629)
			(xy 115.199922 -270.03629) (xy 115.199427 -270.060897) (xy 115.191532 -270.109474) (xy 115.175948 -270.156155)
			(xy 115.153077 -270.199732) (xy 115.123512 -270.239076) (xy 115.088019 -270.273168) (xy 115.047516 -270.301124)
			(xy 115.003054 -270.322222) (xy 114.955783 -270.335914) (xy 114.906928 -270.341846) (xy 114.857753 -270.339865)
			(xy 114.809534 -270.330021) (xy 114.763518 -270.312569) (xy 114.720897 -270.287962) (xy 114.682776 -270.256837)
			(xy 114.650141 -270.22) (xy 114.623838 -270.178404) (xy 114.604547 -270.133128) (xy 114.59277 -270.085344)
			(xy 114.58881 -270.03629) (xy 114.260122 -270.03629) (xy 114.259627 -270.060897) (xy 114.251732 -270.109474)
			(xy 114.236148 -270.156155) (xy 114.213277 -270.199732) (xy 114.183712 -270.239076) (xy 114.148219 -270.273168)
			(xy 114.107716 -270.301124) (xy 114.063254 -270.322222) (xy 114.015983 -270.335914) (xy 113.967128 -270.341846)
			(xy 113.917953 -270.339865) (xy 113.869734 -270.330021) (xy 113.823718 -270.312569) (xy 113.781097 -270.287962)
			(xy 113.742976 -270.256837) (xy 113.710341 -270.22) (xy 113.684038 -270.178404) (xy 113.664747 -270.133128)
			(xy 113.65297 -270.085344) (xy 113.64901 -270.03629) (xy 110.506256 -270.03629) (xy 110.505761 -270.060897)
			(xy 110.497866 -270.109474) (xy 110.482282 -270.156155) (xy 110.459411 -270.199732) (xy 110.429846 -270.239076)
			(xy 110.394353 -270.273168) (xy 110.35385 -270.301124) (xy 110.309388 -270.322222) (xy 110.262117 -270.335914)
			(xy 110.213262 -270.341846) (xy 110.164087 -270.339865) (xy 110.115868 -270.330021) (xy 110.069852 -270.312569)
			(xy 110.027231 -270.287962) (xy 109.98911 -270.256837) (xy 109.956475 -270.22) (xy 109.930172 -270.178404)
			(xy 109.910881 -270.133128) (xy 109.899104 -270.085344) (xy 109.895144 -270.03629) (xy 109.566456 -270.03629)
			(xy 109.565961 -270.060897) (xy 109.558066 -270.109474) (xy 109.542482 -270.156155) (xy 109.519611 -270.199732)
			(xy 109.490046 -270.239076) (xy 109.454553 -270.273168) (xy 109.41405 -270.301124) (xy 109.369588 -270.322222)
			(xy 109.322317 -270.335914) (xy 109.273462 -270.341846) (xy 109.224287 -270.339865) (xy 109.176068 -270.330021)
			(xy 109.130052 -270.312569) (xy 109.087431 -270.287962) (xy 109.04931 -270.256837) (xy 109.016675 -270.22)
			(xy 108.990372 -270.178404) (xy 108.971081 -270.133128) (xy 108.959304 -270.085344) (xy 108.955344 -270.03629)
			(xy 108.626402 -270.03629) (xy 108.625907 -270.060897) (xy 108.618012 -270.109474) (xy 108.602428 -270.156155)
			(xy 108.579557 -270.199732) (xy 108.549992 -270.239076) (xy 108.514499 -270.273168) (xy 108.473996 -270.301124)
			(xy 108.429534 -270.322222) (xy 108.382263 -270.335914) (xy 108.333408 -270.341846) (xy 108.284233 -270.339865)
			(xy 108.236014 -270.330021) (xy 108.189998 -270.312569) (xy 108.147377 -270.287962) (xy 108.109256 -270.256837)
			(xy 108.076621 -270.22) (xy 108.050318 -270.178404) (xy 108.031027 -270.133128) (xy 108.01925 -270.085344)
			(xy 108.01529 -270.03629) (xy 107.686348 -270.03629) (xy 107.685853 -270.060897) (xy 107.677958 -270.109474)
			(xy 107.662374 -270.156155) (xy 107.639503 -270.199732) (xy 107.609938 -270.239076) (xy 107.574445 -270.273168)
			(xy 107.533942 -270.301124) (xy 107.48948 -270.322222) (xy 107.442209 -270.335914) (xy 107.393354 -270.341846)
			(xy 107.344179 -270.339865) (xy 107.29596 -270.330021) (xy 107.249944 -270.312569) (xy 107.207323 -270.287962)
			(xy 107.169202 -270.256837) (xy 107.136567 -270.22) (xy 107.110264 -270.178404) (xy 107.090973 -270.133128)
			(xy 107.079196 -270.085344) (xy 107.075236 -270.03629) (xy 106.746294 -270.03629) (xy 106.745799 -270.060897)
			(xy 106.737904 -270.109474) (xy 106.72232 -270.156155) (xy 106.699449 -270.199732) (xy 106.669884 -270.239076)
			(xy 106.634391 -270.273168) (xy 106.593888 -270.301124) (xy 106.549426 -270.322222) (xy 106.502155 -270.335914)
			(xy 106.4533 -270.341846) (xy 106.404125 -270.339865) (xy 106.355906 -270.330021) (xy 106.30989 -270.312569)
			(xy 106.267269 -270.287962) (xy 106.229148 -270.256837) (xy 106.196513 -270.22) (xy 106.17021 -270.178404)
			(xy 106.150919 -270.133128) (xy 106.139142 -270.085344) (xy 106.135182 -270.03629) (xy 105.80624 -270.03629)
			(xy 105.805745 -270.060897) (xy 105.79785 -270.109474) (xy 105.782266 -270.156155) (xy 105.759395 -270.199732)
			(xy 105.72983 -270.239076) (xy 105.694337 -270.273168) (xy 105.653834 -270.301124) (xy 105.609372 -270.322222)
			(xy 105.562101 -270.335914) (xy 105.513246 -270.341846) (xy 105.464071 -270.339865) (xy 105.415852 -270.330021)
			(xy 105.369836 -270.312569) (xy 105.327215 -270.287962) (xy 105.289094 -270.256837) (xy 105.256459 -270.22)
			(xy 105.230156 -270.178404) (xy 105.210865 -270.133128) (xy 105.199088 -270.085344) (xy 105.195128 -270.03629)
			(xy 104.86644 -270.03629) (xy 104.865945 -270.060897) (xy 104.85805 -270.109474) (xy 104.842466 -270.156155)
			(xy 104.819595 -270.199732) (xy 104.79003 -270.239076) (xy 104.754537 -270.273168) (xy 104.714034 -270.301124)
			(xy 104.669572 -270.322222) (xy 104.622301 -270.335914) (xy 104.573446 -270.341846) (xy 104.524271 -270.339865)
			(xy 104.476052 -270.330021) (xy 104.430036 -270.312569) (xy 104.387415 -270.287962) (xy 104.349294 -270.256837)
			(xy 104.316659 -270.22) (xy 104.290356 -270.178404) (xy 104.271065 -270.133128) (xy 104.259288 -270.085344)
			(xy 104.255328 -270.03629) (xy 103.926386 -270.03629) (xy 103.925891 -270.060897) (xy 103.917996 -270.109474)
			(xy 103.902412 -270.156155) (xy 103.879541 -270.199732) (xy 103.849976 -270.239076) (xy 103.814483 -270.273168)
			(xy 103.77398 -270.301124) (xy 103.729518 -270.322222) (xy 103.682247 -270.335914) (xy 103.633392 -270.341846)
			(xy 103.584217 -270.339865) (xy 103.535998 -270.330021) (xy 103.489982 -270.312569) (xy 103.447361 -270.287962)
			(xy 103.40924 -270.256837) (xy 103.376605 -270.22) (xy 103.350302 -270.178404) (xy 103.331011 -270.133128)
			(xy 103.319234 -270.085344) (xy 103.315274 -270.03629) (xy 102.986332 -270.03629) (xy 102.985837 -270.060897)
			(xy 102.977942 -270.109474) (xy 102.962358 -270.156155) (xy 102.939487 -270.199732) (xy 102.909922 -270.239076)
			(xy 102.874429 -270.273168) (xy 102.833926 -270.301124) (xy 102.789464 -270.322222) (xy 102.742193 -270.335914)
			(xy 102.693338 -270.341846) (xy 102.644163 -270.339865) (xy 102.595944 -270.330021) (xy 102.549928 -270.312569)
			(xy 102.507307 -270.287962) (xy 102.469186 -270.256837) (xy 102.436551 -270.22) (xy 102.410248 -270.178404)
			(xy 102.390957 -270.133128) (xy 102.37918 -270.085344) (xy 102.37522 -270.03629) (xy 102.046278 -270.03629)
			(xy 102.045783 -270.060897) (xy 102.037888 -270.109474) (xy 102.022304 -270.156155) (xy 101.999433 -270.199732)
			(xy 101.969868 -270.239076) (xy 101.934375 -270.273168) (xy 101.893872 -270.301124) (xy 101.84941 -270.322222)
			(xy 101.802139 -270.335914) (xy 101.753284 -270.341846) (xy 101.704109 -270.339865) (xy 101.65589 -270.330021)
			(xy 101.609874 -270.312569) (xy 101.567253 -270.287962) (xy 101.529132 -270.256837) (xy 101.496497 -270.22)
			(xy 101.470194 -270.178404) (xy 101.450903 -270.133128) (xy 101.439126 -270.085344) (xy 101.435166 -270.03629)
			(xy 101.106478 -270.03629) (xy 101.105983 -270.060897) (xy 101.098088 -270.109474) (xy 101.082504 -270.156155)
			(xy 101.059633 -270.199732) (xy 101.030068 -270.239076) (xy 100.994575 -270.273168) (xy 100.954072 -270.301124)
			(xy 100.90961 -270.322222) (xy 100.862339 -270.335914) (xy 100.813484 -270.341846) (xy 100.764309 -270.339865)
			(xy 100.71609 -270.330021) (xy 100.670074 -270.312569) (xy 100.627453 -270.287962) (xy 100.589332 -270.256837)
			(xy 100.556697 -270.22) (xy 100.530394 -270.178404) (xy 100.511103 -270.133128) (xy 100.499326 -270.085344)
			(xy 100.495366 -270.03629) (xy 100.166424 -270.03629) (xy 100.165929 -270.060897) (xy 100.158034 -270.109474)
			(xy 100.14245 -270.156155) (xy 100.119579 -270.199732) (xy 100.090014 -270.239076) (xy 100.054521 -270.273168)
			(xy 100.014018 -270.301124) (xy 99.969556 -270.322222) (xy 99.922285 -270.335914) (xy 99.87343 -270.341846)
			(xy 99.824255 -270.339865) (xy 99.776036 -270.330021) (xy 99.73002 -270.312569) (xy 99.687399 -270.287962)
			(xy 99.649278 -270.256837) (xy 99.616643 -270.22) (xy 99.59034 -270.178404) (xy 99.571049 -270.133128)
			(xy 99.559272 -270.085344) (xy 99.555312 -270.03629) (xy 99.22637 -270.03629) (xy 99.225875 -270.060897)
			(xy 99.21798 -270.109474) (xy 99.202396 -270.156155) (xy 99.179525 -270.199732) (xy 99.14996 -270.239076)
			(xy 99.114467 -270.273168) (xy 99.073964 -270.301124) (xy 99.029502 -270.322222) (xy 98.982231 -270.335914)
			(xy 98.933376 -270.341846) (xy 98.884201 -270.339865) (xy 98.835982 -270.330021) (xy 98.789966 -270.312569)
			(xy 98.747345 -270.287962) (xy 98.709224 -270.256837) (xy 98.676589 -270.22) (xy 98.650286 -270.178404)
			(xy 98.630995 -270.133128) (xy 98.619218 -270.085344) (xy 98.615258 -270.03629) (xy 98.286316 -270.03629)
			(xy 98.285821 -270.060897) (xy 98.277926 -270.109474) (xy 98.262342 -270.156155) (xy 98.239471 -270.199732)
			(xy 98.209906 -270.239076) (xy 98.174413 -270.273168) (xy 98.13391 -270.301124) (xy 98.089448 -270.322222)
			(xy 98.042177 -270.335914) (xy 97.993322 -270.341846) (xy 97.944147 -270.339865) (xy 97.895928 -270.330021)
			(xy 97.849912 -270.312569) (xy 97.807291 -270.287962) (xy 97.76917 -270.256837) (xy 97.736535 -270.22)
			(xy 97.710232 -270.178404) (xy 97.690941 -270.133128) (xy 97.679164 -270.085344) (xy 97.675204 -270.03629)
			(xy 97.346262 -270.03629) (xy 97.34579 -270.060526) (xy 97.338121 -270.108387) (xy 97.32299 -270.154436)
			(xy 97.300776 -270.197518) (xy 97.272037 -270.236551) (xy 97.237494 -270.270555) (xy 97.198014 -270.298678)
			(xy 97.154589 -270.320212) (xy 97.108308 -270.334619) (xy 97.084388 -270.33855) (xy 97.071942 -270.340328)
			(xy 97.040954 -270.341852) (xy 97.017458 -270.341419) (xy 96.971021 -270.334225) (xy 96.92623 -270.320012)
			(xy 96.88414 -270.299116) (xy 96.845742 -270.272028) (xy 96.811939 -270.239386) (xy 96.797368 -270.220948)
			(xy 96.795336 -270.218154) (xy 96.795082 -270.2179) (xy 96.79094 -270.212533) (xy 96.78038 -270.20404)
			(xy 96.774254 -270.201136) (xy 96.768412 -270.19885) (xy 96.755204 -270.197072) (xy 96.661986 -270.209264)
			(xy 96.65531 -270.21031) (xy 96.64282 -270.215459) (xy 96.637348 -270.219424) (xy 96.63176 -270.223742)
			(xy 96.62414 -270.234156) (xy 96.621346 -270.241268) (xy 96.613468 -270.260839) (xy 96.595161 -270.298853)
			(xy 96.58477 -270.317214) (xy 96.539812 -270.394684) (xy 96.53422 -270.405753) (xy 96.533442 -270.430511)
			(xy 96.538288 -270.441928) (xy 96.552766 -270.471392) (xy 96.576388 -270.51889) (xy 96.57715 -270.52016)
			(xy 96.579848 -270.524402) (xy 96.586636 -270.531815) (xy 96.590612 -270.534892) (xy 96.600518 -270.542004)
			(xy 96.613218 -270.543782) (xy 96.637226 -270.547628) (xy 96.683694 -270.561926) (xy 96.727314 -270.583399)
			(xy 96.766984 -270.611505) (xy 96.801706 -270.645537) (xy 96.830604 -270.684635) (xy 96.852948 -270.727815)
			(xy 96.868176 -270.773987) (xy 96.875904 -270.821987) (xy 96.876362 -270.846296) (xy 97.205304 -270.846296)
			(xy 97.209264 -270.797242) (xy 97.221041 -270.749458) (xy 97.240332 -270.704182) (xy 97.266635 -270.662586)
			(xy 97.29927 -270.625749) (xy 97.337391 -270.594624) (xy 97.380012 -270.570017) (xy 97.426028 -270.552565)
			(xy 97.474247 -270.542721) (xy 97.523422 -270.54074) (xy 97.572277 -270.546672) (xy 97.619548 -270.560364)
			(xy 97.66401 -270.581462) (xy 97.704513 -270.609418) (xy 97.740006 -270.64351) (xy 97.769571 -270.682854)
			(xy 97.792442 -270.726431) (xy 97.808026 -270.773112) (xy 97.815921 -270.821689) (xy 97.816416 -270.846296)
			(xy 98.145358 -270.846296) (xy 98.149318 -270.797242) (xy 98.161095 -270.749458) (xy 98.180386 -270.704182)
			(xy 98.206689 -270.662586) (xy 98.239324 -270.625749) (xy 98.277445 -270.594624) (xy 98.320066 -270.570017)
			(xy 98.366082 -270.552565) (xy 98.414301 -270.542721) (xy 98.463476 -270.54074) (xy 98.512331 -270.546672)
			(xy 98.559602 -270.560364) (xy 98.604064 -270.581462) (xy 98.644567 -270.609418) (xy 98.68006 -270.64351)
			(xy 98.709625 -270.682854) (xy 98.732496 -270.726431) (xy 98.74808 -270.773112) (xy 98.755975 -270.821689)
			(xy 98.75647 -270.846296) (xy 99.085158 -270.846296) (xy 99.089118 -270.797242) (xy 99.100895 -270.749458)
			(xy 99.120186 -270.704182) (xy 99.146489 -270.662586) (xy 99.179124 -270.625749) (xy 99.217245 -270.594624)
			(xy 99.259866 -270.570017) (xy 99.305882 -270.552565) (xy 99.354101 -270.542721) (xy 99.403276 -270.54074)
			(xy 99.452131 -270.546672) (xy 99.499402 -270.560364) (xy 99.543864 -270.581462) (xy 99.584367 -270.609418)
			(xy 99.61986 -270.64351) (xy 99.649425 -270.682854) (xy 99.672296 -270.726431) (xy 99.68788 -270.773112)
			(xy 99.695775 -270.821689) (xy 99.69627 -270.846296) (xy 100.025212 -270.846296) (xy 100.029172 -270.797242)
			(xy 100.040949 -270.749458) (xy 100.06024 -270.704182) (xy 100.086543 -270.662586) (xy 100.119178 -270.625749)
			(xy 100.157299 -270.594624) (xy 100.19992 -270.570017) (xy 100.245936 -270.552565) (xy 100.294155 -270.542721)
			(xy 100.34333 -270.54074) (xy 100.392185 -270.546672) (xy 100.439456 -270.560364) (xy 100.483918 -270.581462)
			(xy 100.524421 -270.609418) (xy 100.559914 -270.64351) (xy 100.589479 -270.682854) (xy 100.61235 -270.726431)
			(xy 100.627934 -270.773112) (xy 100.635829 -270.821689) (xy 100.636324 -270.846296) (xy 100.965266 -270.846296)
			(xy 100.969226 -270.797242) (xy 100.981003 -270.749458) (xy 101.000294 -270.704182) (xy 101.026597 -270.662586)
			(xy 101.059232 -270.625749) (xy 101.097353 -270.594624) (xy 101.139974 -270.570017) (xy 101.18599 -270.552565)
			(xy 101.234209 -270.542721) (xy 101.283384 -270.54074) (xy 101.332239 -270.546672) (xy 101.37951 -270.560364)
			(xy 101.423972 -270.581462) (xy 101.464475 -270.609418) (xy 101.499968 -270.64351) (xy 101.529533 -270.682854)
			(xy 101.552404 -270.726431) (xy 101.567988 -270.773112) (xy 101.575883 -270.821689) (xy 101.576378 -270.846296)
			(xy 101.90532 -270.846296) (xy 101.90928 -270.797242) (xy 101.921057 -270.749458) (xy 101.940348 -270.704182)
			(xy 101.966651 -270.662586) (xy 101.999286 -270.625749) (xy 102.037407 -270.594624) (xy 102.080028 -270.570017)
			(xy 102.126044 -270.552565) (xy 102.174263 -270.542721) (xy 102.223438 -270.54074) (xy 102.272293 -270.546672)
			(xy 102.319564 -270.560364) (xy 102.364026 -270.581462) (xy 102.404529 -270.609418) (xy 102.440022 -270.64351)
			(xy 102.469587 -270.682854) (xy 102.492458 -270.726431) (xy 102.508042 -270.773112) (xy 102.515937 -270.821689)
			(xy 102.516432 -270.846296) (xy 102.845374 -270.846296) (xy 102.849334 -270.797242) (xy 102.861111 -270.749458)
			(xy 102.880402 -270.704182) (xy 102.906705 -270.662586) (xy 102.93934 -270.625749) (xy 102.977461 -270.594624)
			(xy 103.020082 -270.570017) (xy 103.066098 -270.552565) (xy 103.114317 -270.542721) (xy 103.163492 -270.54074)
			(xy 103.212347 -270.546672) (xy 103.259618 -270.560364) (xy 103.30408 -270.581462) (xy 103.344583 -270.609418)
			(xy 103.380076 -270.64351) (xy 103.409641 -270.682854) (xy 103.432512 -270.726431) (xy 103.448096 -270.773112)
			(xy 103.455991 -270.821689) (xy 103.456486 -270.846296) (xy 103.785174 -270.846296) (xy 103.789134 -270.797242)
			(xy 103.800911 -270.749458) (xy 103.820202 -270.704182) (xy 103.846505 -270.662586) (xy 103.87914 -270.625749)
			(xy 103.917261 -270.594624) (xy 103.959882 -270.570017) (xy 104.005898 -270.552565) (xy 104.054117 -270.542721)
			(xy 104.103292 -270.54074) (xy 104.152147 -270.546672) (xy 104.199418 -270.560364) (xy 104.24388 -270.581462)
			(xy 104.284383 -270.609418) (xy 104.319876 -270.64351) (xy 104.349441 -270.682854) (xy 104.372312 -270.726431)
			(xy 104.387896 -270.773112) (xy 104.395791 -270.821689) (xy 104.396286 -270.846296) (xy 104.725228 -270.846296)
			(xy 104.729188 -270.797242) (xy 104.740965 -270.749458) (xy 104.760256 -270.704182) (xy 104.786559 -270.662586)
			(xy 104.819194 -270.625749) (xy 104.857315 -270.594624) (xy 104.899936 -270.570017) (xy 104.945952 -270.552565)
			(xy 104.994171 -270.542721) (xy 105.043346 -270.54074) (xy 105.092201 -270.546672) (xy 105.139472 -270.560364)
			(xy 105.183934 -270.581462) (xy 105.224437 -270.609418) (xy 105.25993 -270.64351) (xy 105.289495 -270.682854)
			(xy 105.312366 -270.726431) (xy 105.32795 -270.773112) (xy 105.335845 -270.821689) (xy 105.33634 -270.846296)
			(xy 105.665282 -270.846296) (xy 105.669242 -270.797242) (xy 105.681019 -270.749458) (xy 105.70031 -270.704182)
			(xy 105.726613 -270.662586) (xy 105.759248 -270.625749) (xy 105.797369 -270.594624) (xy 105.83999 -270.570017)
			(xy 105.886006 -270.552565) (xy 105.934225 -270.542721) (xy 105.9834 -270.54074) (xy 106.032255 -270.546672)
			(xy 106.079526 -270.560364) (xy 106.123988 -270.581462) (xy 106.164491 -270.609418) (xy 106.199984 -270.64351)
			(xy 106.229549 -270.682854) (xy 106.25242 -270.726431) (xy 106.268004 -270.773112) (xy 106.275899 -270.821689)
			(xy 106.276394 -270.846296) (xy 106.605336 -270.846296) (xy 106.609296 -270.797242) (xy 106.621073 -270.749458)
			(xy 106.640364 -270.704182) (xy 106.666667 -270.662586) (xy 106.699302 -270.625749) (xy 106.737423 -270.594624)
			(xy 106.780044 -270.570017) (xy 106.82606 -270.552565) (xy 106.874279 -270.542721) (xy 106.923454 -270.54074)
			(xy 106.972309 -270.546672) (xy 107.01958 -270.560364) (xy 107.064042 -270.581462) (xy 107.104545 -270.609418)
			(xy 107.140038 -270.64351) (xy 107.169603 -270.682854) (xy 107.192474 -270.726431) (xy 107.208058 -270.773112)
			(xy 107.215953 -270.821689) (xy 107.216448 -270.846296) (xy 107.545136 -270.846296) (xy 107.549096 -270.797242)
			(xy 107.560873 -270.749458) (xy 107.580164 -270.704182) (xy 107.606467 -270.662586) (xy 107.639102 -270.625749)
			(xy 107.677223 -270.594624) (xy 107.719844 -270.570017) (xy 107.76586 -270.552565) (xy 107.814079 -270.542721)
			(xy 107.863254 -270.54074) (xy 107.912109 -270.546672) (xy 107.95938 -270.560364) (xy 108.003842 -270.581462)
			(xy 108.044345 -270.609418) (xy 108.079838 -270.64351) (xy 108.109403 -270.682854) (xy 108.132274 -270.726431)
			(xy 108.147858 -270.773112) (xy 108.155753 -270.821689) (xy 108.156248 -270.846296) (xy 108.48519 -270.846296)
			(xy 108.48915 -270.797242) (xy 108.500927 -270.749458) (xy 108.520218 -270.704182) (xy 108.546521 -270.662586)
			(xy 108.579156 -270.625749) (xy 108.617277 -270.594624) (xy 108.659898 -270.570017) (xy 108.705914 -270.552565)
			(xy 108.754133 -270.542721) (xy 108.803308 -270.54074) (xy 108.852163 -270.546672) (xy 108.899434 -270.560364)
			(xy 108.943896 -270.581462) (xy 108.984399 -270.609418) (xy 109.019892 -270.64351) (xy 109.049457 -270.682854)
			(xy 109.072328 -270.726431) (xy 109.087912 -270.773112) (xy 109.095807 -270.821689) (xy 109.096302 -270.846296)
			(xy 109.425244 -270.846296) (xy 109.429204 -270.797242) (xy 109.440981 -270.749458) (xy 109.460272 -270.704182)
			(xy 109.486575 -270.662586) (xy 109.51921 -270.625749) (xy 109.557331 -270.594624) (xy 109.599952 -270.570017)
			(xy 109.645968 -270.552565) (xy 109.694187 -270.542721) (xy 109.743362 -270.54074) (xy 109.792217 -270.546672)
			(xy 109.839488 -270.560364) (xy 109.88395 -270.581462) (xy 109.924453 -270.609418) (xy 109.959946 -270.64351)
			(xy 109.989511 -270.682854) (xy 110.012382 -270.726431) (xy 110.027966 -270.773112) (xy 110.035861 -270.821689)
			(xy 110.036356 -270.846296) (xy 110.365298 -270.846296) (xy 110.369258 -270.797242) (xy 110.381035 -270.749458)
			(xy 110.400326 -270.704182) (xy 110.426629 -270.662586) (xy 110.459264 -270.625749) (xy 110.497385 -270.594624)
			(xy 110.540006 -270.570017) (xy 110.586022 -270.552565) (xy 110.634241 -270.542721) (xy 110.683416 -270.54074)
			(xy 110.732271 -270.546672) (xy 110.779542 -270.560364) (xy 110.824004 -270.581462) (xy 110.864507 -270.609418)
			(xy 110.9 -270.64351) (xy 110.929565 -270.682854) (xy 110.952436 -270.726431) (xy 110.96802 -270.773112)
			(xy 110.975915 -270.821689) (xy 110.97641 -270.846296) (xy 113.178856 -270.846296) (xy 113.182816 -270.797242)
			(xy 113.194593 -270.749458) (xy 113.213884 -270.704182) (xy 113.240187 -270.662586) (xy 113.272822 -270.625749)
			(xy 113.310943 -270.594624) (xy 113.353564 -270.570017) (xy 113.39958 -270.552565) (xy 113.447799 -270.542721)
			(xy 113.496974 -270.54074) (xy 113.545829 -270.546672) (xy 113.5931 -270.560364) (xy 113.637562 -270.581462)
			(xy 113.678065 -270.609418) (xy 113.713558 -270.64351) (xy 113.743123 -270.682854) (xy 113.765994 -270.726431)
			(xy 113.781578 -270.773112) (xy 113.789473 -270.821689) (xy 113.789968 -270.846296) (xy 114.11891 -270.846296)
			(xy 114.12287 -270.797242) (xy 114.134647 -270.749458) (xy 114.153938 -270.704182) (xy 114.180241 -270.662586)
			(xy 114.212876 -270.625749) (xy 114.250997 -270.594624) (xy 114.293618 -270.570017) (xy 114.339634 -270.552565)
			(xy 114.387853 -270.542721) (xy 114.437028 -270.54074) (xy 114.485883 -270.546672) (xy 114.533154 -270.560364)
			(xy 114.577616 -270.581462) (xy 114.618119 -270.609418) (xy 114.653612 -270.64351) (xy 114.683177 -270.682854)
			(xy 114.706048 -270.726431) (xy 114.721632 -270.773112) (xy 114.729527 -270.821689) (xy 114.730022 -270.846296)
			(xy 115.058964 -270.846296) (xy 115.062924 -270.797242) (xy 115.074701 -270.749458) (xy 115.093992 -270.704182)
			(xy 115.120295 -270.662586) (xy 115.15293 -270.625749) (xy 115.191051 -270.594624) (xy 115.233672 -270.570017)
			(xy 115.279688 -270.552565) (xy 115.327907 -270.542721) (xy 115.377082 -270.54074) (xy 115.425937 -270.546672)
			(xy 115.473208 -270.560364) (xy 115.51767 -270.581462) (xy 115.558173 -270.609418) (xy 115.593666 -270.64351)
			(xy 115.623231 -270.682854) (xy 115.646102 -270.726431) (xy 115.661686 -270.773112) (xy 115.669581 -270.821689)
			(xy 115.670076 -270.846296) (xy 115.999018 -270.846296) (xy 116.002978 -270.797242) (xy 116.014755 -270.749458)
			(xy 116.034046 -270.704182) (xy 116.060349 -270.662586) (xy 116.092984 -270.625749) (xy 116.131105 -270.594624)
			(xy 116.173726 -270.570017) (xy 116.219742 -270.552565) (xy 116.267961 -270.542721) (xy 116.317136 -270.54074)
			(xy 116.365991 -270.546672) (xy 116.413262 -270.560364) (xy 116.457724 -270.581462) (xy 116.498227 -270.609418)
			(xy 116.53372 -270.64351) (xy 116.563285 -270.682854) (xy 116.586156 -270.726431) (xy 116.60174 -270.773112)
			(xy 116.609635 -270.821689) (xy 116.61013 -270.846296) (xy 116.938818 -270.846296) (xy 116.942778 -270.797242)
			(xy 116.954555 -270.749458) (xy 116.973846 -270.704182) (xy 117.000149 -270.662586) (xy 117.032784 -270.625749)
			(xy 117.070905 -270.594624) (xy 117.113526 -270.570017) (xy 117.159542 -270.552565) (xy 117.207761 -270.542721)
			(xy 117.256936 -270.54074) (xy 117.305791 -270.546672) (xy 117.353062 -270.560364) (xy 117.397524 -270.581462)
			(xy 117.438027 -270.609418) (xy 117.47352 -270.64351) (xy 117.503085 -270.682854) (xy 117.525956 -270.726431)
			(xy 117.54154 -270.773112) (xy 117.549435 -270.821689) (xy 117.54993 -270.846296) (xy 117.878872 -270.846296)
			(xy 117.882832 -270.797242) (xy 117.894609 -270.749458) (xy 117.9139 -270.704182) (xy 117.940203 -270.662586)
			(xy 117.972838 -270.625749) (xy 118.010959 -270.594624) (xy 118.05358 -270.570017) (xy 118.099596 -270.552565)
			(xy 118.147815 -270.542721) (xy 118.19699 -270.54074) (xy 118.245845 -270.546672) (xy 118.293116 -270.560364)
			(xy 118.337578 -270.581462) (xy 118.378081 -270.609418) (xy 118.413574 -270.64351) (xy 118.443139 -270.682854)
			(xy 118.46601 -270.726431) (xy 118.481594 -270.773112) (xy 118.489489 -270.821689) (xy 118.489984 -270.846296)
			(xy 118.818926 -270.846296) (xy 118.822886 -270.797242) (xy 118.834663 -270.749458) (xy 118.853954 -270.704182)
			(xy 118.880257 -270.662586) (xy 118.912892 -270.625749) (xy 118.951013 -270.594624) (xy 118.993634 -270.570017)
			(xy 119.03965 -270.552565) (xy 119.087869 -270.542721) (xy 119.137044 -270.54074) (xy 119.185899 -270.546672)
			(xy 119.23317 -270.560364) (xy 119.277632 -270.581462) (xy 119.318135 -270.609418) (xy 119.353628 -270.64351)
			(xy 119.383193 -270.682854) (xy 119.406064 -270.726431) (xy 119.421648 -270.773112) (xy 119.429543 -270.821689)
			(xy 119.430038 -270.846296) (xy 119.75898 -270.846296) (xy 119.76294 -270.797242) (xy 119.774717 -270.749458)
			(xy 119.794008 -270.704182) (xy 119.820311 -270.662586) (xy 119.852946 -270.625749) (xy 119.891067 -270.594624)
			(xy 119.933688 -270.570017) (xy 119.979704 -270.552565) (xy 120.027923 -270.542721) (xy 120.077098 -270.54074)
			(xy 120.125953 -270.546672) (xy 120.173224 -270.560364) (xy 120.217686 -270.581462) (xy 120.258189 -270.609418)
			(xy 120.293682 -270.64351) (xy 120.323247 -270.682854) (xy 120.346118 -270.726431) (xy 120.361702 -270.773112)
			(xy 120.369597 -270.821689) (xy 120.370092 -270.846296) (xy 120.699034 -270.846296) (xy 120.702994 -270.797242)
			(xy 120.714771 -270.749458) (xy 120.734062 -270.704182) (xy 120.760365 -270.662586) (xy 120.793 -270.625749)
			(xy 120.831121 -270.594624) (xy 120.873742 -270.570017) (xy 120.919758 -270.552565) (xy 120.967977 -270.542721)
			(xy 121.017152 -270.54074) (xy 121.066007 -270.546672) (xy 121.113278 -270.560364) (xy 121.15774 -270.581462)
			(xy 121.198243 -270.609418) (xy 121.233736 -270.64351) (xy 121.263301 -270.682854) (xy 121.286172 -270.726431)
			(xy 121.301756 -270.773112) (xy 121.309651 -270.821689) (xy 121.310146 -270.846296) (xy 121.638834 -270.846296)
			(xy 121.642794 -270.797242) (xy 121.654571 -270.749458) (xy 121.673862 -270.704182) (xy 121.700165 -270.662586)
			(xy 121.7328 -270.625749) (xy 121.770921 -270.594624) (xy 121.813542 -270.570017) (xy 121.859558 -270.552565)
			(xy 121.907777 -270.542721) (xy 121.956952 -270.54074) (xy 122.005807 -270.546672) (xy 122.053078 -270.560364)
			(xy 122.09754 -270.581462) (xy 122.138043 -270.609418) (xy 122.173536 -270.64351) (xy 122.203101 -270.682854)
			(xy 122.225972 -270.726431) (xy 122.241556 -270.773112) (xy 122.249451 -270.821689) (xy 122.249946 -270.846296)
			(xy 122.578888 -270.846296) (xy 122.582848 -270.797242) (xy 122.594625 -270.749458) (xy 122.613916 -270.704182)
			(xy 122.640219 -270.662586) (xy 122.672854 -270.625749) (xy 122.710975 -270.594624) (xy 122.753596 -270.570017)
			(xy 122.799612 -270.552565) (xy 122.847831 -270.542721) (xy 122.897006 -270.54074) (xy 122.945861 -270.546672)
			(xy 122.993132 -270.560364) (xy 123.037594 -270.581462) (xy 123.078097 -270.609418) (xy 123.11359 -270.64351)
			(xy 123.143155 -270.682854) (xy 123.166026 -270.726431) (xy 123.18161 -270.773112) (xy 123.189505 -270.821689)
			(xy 123.19 -270.846296) (xy 123.518942 -270.846296) (xy 123.522902 -270.797242) (xy 123.534679 -270.749458)
			(xy 123.55397 -270.704182) (xy 123.580273 -270.662586) (xy 123.612908 -270.625749) (xy 123.651029 -270.594624)
			(xy 123.69365 -270.570017) (xy 123.739666 -270.552565) (xy 123.787885 -270.542721) (xy 123.83706 -270.54074)
			(xy 123.885915 -270.546672) (xy 123.933186 -270.560364) (xy 123.977648 -270.581462) (xy 124.018151 -270.609418)
			(xy 124.053644 -270.64351) (xy 124.083209 -270.682854) (xy 124.10608 -270.726431) (xy 124.121664 -270.773112)
			(xy 124.129559 -270.821689) (xy 124.130054 -270.846296) (xy 124.458996 -270.846296) (xy 124.462956 -270.797242)
			(xy 124.474733 -270.749458) (xy 124.494024 -270.704182) (xy 124.520327 -270.662586) (xy 124.552962 -270.625749)
			(xy 124.591083 -270.594624) (xy 124.633704 -270.570017) (xy 124.67972 -270.552565) (xy 124.727939 -270.542721)
			(xy 124.777114 -270.54074) (xy 124.825969 -270.546672) (xy 124.87324 -270.560364) (xy 124.917702 -270.581462)
			(xy 124.958205 -270.609418) (xy 124.993698 -270.64351) (xy 125.023263 -270.682854) (xy 125.046134 -270.726431)
			(xy 125.061718 -270.773112) (xy 125.069613 -270.821689) (xy 125.070108 -270.846296) (xy 125.39905 -270.846296)
			(xy 125.40301 -270.797242) (xy 125.414787 -270.749458) (xy 125.434078 -270.704182) (xy 125.460381 -270.662586)
			(xy 125.493016 -270.625749) (xy 125.531137 -270.594624) (xy 125.573758 -270.570017) (xy 125.619774 -270.552565)
			(xy 125.667993 -270.542721) (xy 125.717168 -270.54074) (xy 125.766023 -270.546672) (xy 125.813294 -270.560364)
			(xy 125.857756 -270.581462) (xy 125.898259 -270.609418) (xy 125.933752 -270.64351) (xy 125.963317 -270.682854)
			(xy 125.986188 -270.726431) (xy 126.001772 -270.773112) (xy 126.009667 -270.821689) (xy 126.010162 -270.846296)
			(xy 126.33885 -270.846296) (xy 126.34281 -270.797242) (xy 126.354587 -270.749458) (xy 126.373878 -270.704182)
			(xy 126.400181 -270.662586) (xy 126.432816 -270.625749) (xy 126.470937 -270.594624) (xy 126.513558 -270.570017)
			(xy 126.559574 -270.552565) (xy 126.607793 -270.542721) (xy 126.656968 -270.54074) (xy 126.705823 -270.546672)
			(xy 126.753094 -270.560364) (xy 126.797556 -270.581462) (xy 126.838059 -270.609418) (xy 126.873552 -270.64351)
			(xy 126.903117 -270.682854) (xy 126.925988 -270.726431) (xy 126.941572 -270.773112) (xy 126.949467 -270.821689)
			(xy 126.949962 -270.846296) (xy 126.949467 -270.870903) (xy 126.941572 -270.91948) (xy 126.925988 -270.966161)
			(xy 126.903117 -271.009738) (xy 126.873552 -271.049082) (xy 126.838059 -271.083174) (xy 126.797556 -271.11113)
			(xy 126.753094 -271.132228) (xy 126.705823 -271.14592) (xy 126.656968 -271.151852) (xy 126.607793 -271.149871)
			(xy 126.559574 -271.140027) (xy 126.513558 -271.122575) (xy 126.470937 -271.097968) (xy 126.432816 -271.066843)
			(xy 126.400181 -271.030006) (xy 126.373878 -270.98841) (xy 126.354587 -270.943134) (xy 126.34281 -270.89535)
			(xy 126.33885 -270.846296) (xy 126.010162 -270.846296) (xy 126.009667 -270.870903) (xy 126.001772 -270.91948)
			(xy 125.986188 -270.966161) (xy 125.963317 -271.009738) (xy 125.933752 -271.049082) (xy 125.898259 -271.083174)
			(xy 125.857756 -271.11113) (xy 125.813294 -271.132228) (xy 125.766023 -271.14592) (xy 125.717168 -271.151852)
			(xy 125.667993 -271.149871) (xy 125.619774 -271.140027) (xy 125.573758 -271.122575) (xy 125.531137 -271.097968)
			(xy 125.493016 -271.066843) (xy 125.460381 -271.030006) (xy 125.434078 -270.98841) (xy 125.414787 -270.943134)
			(xy 125.40301 -270.89535) (xy 125.39905 -270.846296) (xy 125.070108 -270.846296) (xy 125.069613 -270.870903)
			(xy 125.061718 -270.91948) (xy 125.046134 -270.966161) (xy 125.023263 -271.009738) (xy 124.993698 -271.049082)
			(xy 124.958205 -271.083174) (xy 124.917702 -271.11113) (xy 124.87324 -271.132228) (xy 124.825969 -271.14592)
			(xy 124.777114 -271.151852) (xy 124.727939 -271.149871) (xy 124.67972 -271.140027) (xy 124.633704 -271.122575)
			(xy 124.591083 -271.097968) (xy 124.552962 -271.066843) (xy 124.520327 -271.030006) (xy 124.494024 -270.98841)
			(xy 124.474733 -270.943134) (xy 124.462956 -270.89535) (xy 124.458996 -270.846296) (xy 124.130054 -270.846296)
			(xy 124.129559 -270.870903) (xy 124.121664 -270.91948) (xy 124.10608 -270.966161) (xy 124.083209 -271.009738)
			(xy 124.053644 -271.049082) (xy 124.018151 -271.083174) (xy 123.977648 -271.11113) (xy 123.933186 -271.132228)
			(xy 123.885915 -271.14592) (xy 123.83706 -271.151852) (xy 123.787885 -271.149871) (xy 123.739666 -271.140027)
			(xy 123.69365 -271.122575) (xy 123.651029 -271.097968) (xy 123.612908 -271.066843) (xy 123.580273 -271.030006)
			(xy 123.55397 -270.98841) (xy 123.534679 -270.943134) (xy 123.522902 -270.89535) (xy 123.518942 -270.846296)
			(xy 123.19 -270.846296) (xy 123.189505 -270.870903) (xy 123.18161 -270.91948) (xy 123.166026 -270.966161)
			(xy 123.143155 -271.009738) (xy 123.11359 -271.049082) (xy 123.078097 -271.083174) (xy 123.037594 -271.11113)
			(xy 122.993132 -271.132228) (xy 122.945861 -271.14592) (xy 122.897006 -271.151852) (xy 122.847831 -271.149871)
			(xy 122.799612 -271.140027) (xy 122.753596 -271.122575) (xy 122.710975 -271.097968) (xy 122.672854 -271.066843)
			(xy 122.640219 -271.030006) (xy 122.613916 -270.98841) (xy 122.594625 -270.943134) (xy 122.582848 -270.89535)
			(xy 122.578888 -270.846296) (xy 122.249946 -270.846296) (xy 122.249451 -270.870903) (xy 122.241556 -270.91948)
			(xy 122.225972 -270.966161) (xy 122.203101 -271.009738) (xy 122.173536 -271.049082) (xy 122.138043 -271.083174)
			(xy 122.09754 -271.11113) (xy 122.053078 -271.132228) (xy 122.005807 -271.14592) (xy 121.956952 -271.151852)
			(xy 121.907777 -271.149871) (xy 121.859558 -271.140027) (xy 121.813542 -271.122575) (xy 121.770921 -271.097968)
			(xy 121.7328 -271.066843) (xy 121.700165 -271.030006) (xy 121.673862 -270.98841) (xy 121.654571 -270.943134)
			(xy 121.642794 -270.89535) (xy 121.638834 -270.846296) (xy 121.310146 -270.846296) (xy 121.309651 -270.870903)
			(xy 121.301756 -270.91948) (xy 121.286172 -270.966161) (xy 121.263301 -271.009738) (xy 121.233736 -271.049082)
			(xy 121.198243 -271.083174) (xy 121.15774 -271.11113) (xy 121.113278 -271.132228) (xy 121.066007 -271.14592)
			(xy 121.017152 -271.151852) (xy 120.967977 -271.149871) (xy 120.919758 -271.140027) (xy 120.873742 -271.122575)
			(xy 120.831121 -271.097968) (xy 120.793 -271.066843) (xy 120.760365 -271.030006) (xy 120.734062 -270.98841)
			(xy 120.714771 -270.943134) (xy 120.702994 -270.89535) (xy 120.699034 -270.846296) (xy 120.370092 -270.846296)
			(xy 120.369597 -270.870903) (xy 120.361702 -270.91948) (xy 120.346118 -270.966161) (xy 120.323247 -271.009738)
			(xy 120.293682 -271.049082) (xy 120.258189 -271.083174) (xy 120.217686 -271.11113) (xy 120.173224 -271.132228)
			(xy 120.125953 -271.14592) (xy 120.077098 -271.151852) (xy 120.027923 -271.149871) (xy 119.979704 -271.140027)
			(xy 119.933688 -271.122575) (xy 119.891067 -271.097968) (xy 119.852946 -271.066843) (xy 119.820311 -271.030006)
			(xy 119.794008 -270.98841) (xy 119.774717 -270.943134) (xy 119.76294 -270.89535) (xy 119.75898 -270.846296)
			(xy 119.430038 -270.846296) (xy 119.429543 -270.870903) (xy 119.421648 -270.91948) (xy 119.406064 -270.966161)
			(xy 119.383193 -271.009738) (xy 119.353628 -271.049082) (xy 119.318135 -271.083174) (xy 119.277632 -271.11113)
			(xy 119.23317 -271.132228) (xy 119.185899 -271.14592) (xy 119.137044 -271.151852) (xy 119.087869 -271.149871)
			(xy 119.03965 -271.140027) (xy 118.993634 -271.122575) (xy 118.951013 -271.097968) (xy 118.912892 -271.066843)
			(xy 118.880257 -271.030006) (xy 118.853954 -270.98841) (xy 118.834663 -270.943134) (xy 118.822886 -270.89535)
			(xy 118.818926 -270.846296) (xy 118.489984 -270.846296) (xy 118.489489 -270.870903) (xy 118.481594 -270.91948)
			(xy 118.46601 -270.966161) (xy 118.443139 -271.009738) (xy 118.413574 -271.049082) (xy 118.378081 -271.083174)
			(xy 118.337578 -271.11113) (xy 118.293116 -271.132228) (xy 118.245845 -271.14592) (xy 118.19699 -271.151852)
			(xy 118.147815 -271.149871) (xy 118.099596 -271.140027) (xy 118.05358 -271.122575) (xy 118.010959 -271.097968)
			(xy 117.972838 -271.066843) (xy 117.940203 -271.030006) (xy 117.9139 -270.98841) (xy 117.894609 -270.943134)
			(xy 117.882832 -270.89535) (xy 117.878872 -270.846296) (xy 117.54993 -270.846296) (xy 117.549435 -270.870903)
			(xy 117.54154 -270.91948) (xy 117.525956 -270.966161) (xy 117.503085 -271.009738) (xy 117.47352 -271.049082)
			(xy 117.438027 -271.083174) (xy 117.397524 -271.11113) (xy 117.353062 -271.132228) (xy 117.305791 -271.14592)
			(xy 117.256936 -271.151852) (xy 117.207761 -271.149871) (xy 117.159542 -271.140027) (xy 117.113526 -271.122575)
			(xy 117.070905 -271.097968) (xy 117.032784 -271.066843) (xy 117.000149 -271.030006) (xy 116.973846 -270.98841)
			(xy 116.954555 -270.943134) (xy 116.942778 -270.89535) (xy 116.938818 -270.846296) (xy 116.61013 -270.846296)
			(xy 116.609635 -270.870903) (xy 116.60174 -270.91948) (xy 116.586156 -270.966161) (xy 116.563285 -271.009738)
			(xy 116.53372 -271.049082) (xy 116.498227 -271.083174) (xy 116.457724 -271.11113) (xy 116.413262 -271.132228)
			(xy 116.365991 -271.14592) (xy 116.317136 -271.151852) (xy 116.267961 -271.149871) (xy 116.219742 -271.140027)
			(xy 116.173726 -271.122575) (xy 116.131105 -271.097968) (xy 116.092984 -271.066843) (xy 116.060349 -271.030006)
			(xy 116.034046 -270.98841) (xy 116.014755 -270.943134) (xy 116.002978 -270.89535) (xy 115.999018 -270.846296)
			(xy 115.670076 -270.846296) (xy 115.669581 -270.870903) (xy 115.661686 -270.91948) (xy 115.646102 -270.966161)
			(xy 115.623231 -271.009738) (xy 115.593666 -271.049082) (xy 115.558173 -271.083174) (xy 115.51767 -271.11113)
			(xy 115.473208 -271.132228) (xy 115.425937 -271.14592) (xy 115.377082 -271.151852) (xy 115.327907 -271.149871)
			(xy 115.279688 -271.140027) (xy 115.233672 -271.122575) (xy 115.191051 -271.097968) (xy 115.15293 -271.066843)
			(xy 115.120295 -271.030006) (xy 115.093992 -270.98841) (xy 115.074701 -270.943134) (xy 115.062924 -270.89535)
			(xy 115.058964 -270.846296) (xy 114.730022 -270.846296) (xy 114.729527 -270.870903) (xy 114.721632 -270.91948)
			(xy 114.706048 -270.966161) (xy 114.683177 -271.009738) (xy 114.653612 -271.049082) (xy 114.618119 -271.083174)
			(xy 114.577616 -271.11113) (xy 114.533154 -271.132228) (xy 114.485883 -271.14592) (xy 114.437028 -271.151852)
			(xy 114.387853 -271.149871) (xy 114.339634 -271.140027) (xy 114.293618 -271.122575) (xy 114.250997 -271.097968)
			(xy 114.212876 -271.066843) (xy 114.180241 -271.030006) (xy 114.153938 -270.98841) (xy 114.134647 -270.943134)
			(xy 114.12287 -270.89535) (xy 114.11891 -270.846296) (xy 113.789968 -270.846296) (xy 113.789473 -270.870903)
			(xy 113.781578 -270.91948) (xy 113.765994 -270.966161) (xy 113.743123 -271.009738) (xy 113.713558 -271.049082)
			(xy 113.678065 -271.083174) (xy 113.637562 -271.11113) (xy 113.5931 -271.132228) (xy 113.545829 -271.14592)
			(xy 113.496974 -271.151852) (xy 113.447799 -271.149871) (xy 113.39958 -271.140027) (xy 113.353564 -271.122575)
			(xy 113.310943 -271.097968) (xy 113.272822 -271.066843) (xy 113.240187 -271.030006) (xy 113.213884 -270.98841)
			(xy 113.194593 -270.943134) (xy 113.182816 -270.89535) (xy 113.178856 -270.846296) (xy 110.97641 -270.846296)
			(xy 110.975915 -270.870903) (xy 110.96802 -270.91948) (xy 110.952436 -270.966161) (xy 110.929565 -271.009738)
			(xy 110.9 -271.049082) (xy 110.864507 -271.083174) (xy 110.824004 -271.11113) (xy 110.779542 -271.132228)
			(xy 110.732271 -271.14592) (xy 110.683416 -271.151852) (xy 110.634241 -271.149871) (xy 110.586022 -271.140027)
			(xy 110.540006 -271.122575) (xy 110.497385 -271.097968) (xy 110.459264 -271.066843) (xy 110.426629 -271.030006)
			(xy 110.400326 -270.98841) (xy 110.381035 -270.943134) (xy 110.369258 -270.89535) (xy 110.365298 -270.846296)
			(xy 110.036356 -270.846296) (xy 110.035861 -270.870903) (xy 110.027966 -270.91948) (xy 110.012382 -270.966161)
			(xy 109.989511 -271.009738) (xy 109.959946 -271.049082) (xy 109.924453 -271.083174) (xy 109.88395 -271.11113)
			(xy 109.839488 -271.132228) (xy 109.792217 -271.14592) (xy 109.743362 -271.151852) (xy 109.694187 -271.149871)
			(xy 109.645968 -271.140027) (xy 109.599952 -271.122575) (xy 109.557331 -271.097968) (xy 109.51921 -271.066843)
			(xy 109.486575 -271.030006) (xy 109.460272 -270.98841) (xy 109.440981 -270.943134) (xy 109.429204 -270.89535)
			(xy 109.425244 -270.846296) (xy 109.096302 -270.846296) (xy 109.095807 -270.870903) (xy 109.087912 -270.91948)
			(xy 109.072328 -270.966161) (xy 109.049457 -271.009738) (xy 109.019892 -271.049082) (xy 108.984399 -271.083174)
			(xy 108.943896 -271.11113) (xy 108.899434 -271.132228) (xy 108.852163 -271.14592) (xy 108.803308 -271.151852)
			(xy 108.754133 -271.149871) (xy 108.705914 -271.140027) (xy 108.659898 -271.122575) (xy 108.617277 -271.097968)
			(xy 108.579156 -271.066843) (xy 108.546521 -271.030006) (xy 108.520218 -270.98841) (xy 108.500927 -270.943134)
			(xy 108.48915 -270.89535) (xy 108.48519 -270.846296) (xy 108.156248 -270.846296) (xy 108.155753 -270.870903)
			(xy 108.147858 -270.91948) (xy 108.132274 -270.966161) (xy 108.109403 -271.009738) (xy 108.079838 -271.049082)
			(xy 108.044345 -271.083174) (xy 108.003842 -271.11113) (xy 107.95938 -271.132228) (xy 107.912109 -271.14592)
			(xy 107.863254 -271.151852) (xy 107.814079 -271.149871) (xy 107.76586 -271.140027) (xy 107.719844 -271.122575)
			(xy 107.677223 -271.097968) (xy 107.639102 -271.066843) (xy 107.606467 -271.030006) (xy 107.580164 -270.98841)
			(xy 107.560873 -270.943134) (xy 107.549096 -270.89535) (xy 107.545136 -270.846296) (xy 107.216448 -270.846296)
			(xy 107.215953 -270.870903) (xy 107.208058 -270.91948) (xy 107.192474 -270.966161) (xy 107.169603 -271.009738)
			(xy 107.140038 -271.049082) (xy 107.104545 -271.083174) (xy 107.064042 -271.11113) (xy 107.01958 -271.132228)
			(xy 106.972309 -271.14592) (xy 106.923454 -271.151852) (xy 106.874279 -271.149871) (xy 106.82606 -271.140027)
			(xy 106.780044 -271.122575) (xy 106.737423 -271.097968) (xy 106.699302 -271.066843) (xy 106.666667 -271.030006)
			(xy 106.640364 -270.98841) (xy 106.621073 -270.943134) (xy 106.609296 -270.89535) (xy 106.605336 -270.846296)
			(xy 106.276394 -270.846296) (xy 106.275899 -270.870903) (xy 106.268004 -270.91948) (xy 106.25242 -270.966161)
			(xy 106.229549 -271.009738) (xy 106.199984 -271.049082) (xy 106.164491 -271.083174) (xy 106.123988 -271.11113)
			(xy 106.079526 -271.132228) (xy 106.032255 -271.14592) (xy 105.9834 -271.151852) (xy 105.934225 -271.149871)
			(xy 105.886006 -271.140027) (xy 105.83999 -271.122575) (xy 105.797369 -271.097968) (xy 105.759248 -271.066843)
			(xy 105.726613 -271.030006) (xy 105.70031 -270.98841) (xy 105.681019 -270.943134) (xy 105.669242 -270.89535)
			(xy 105.665282 -270.846296) (xy 105.33634 -270.846296) (xy 105.335845 -270.870903) (xy 105.32795 -270.91948)
			(xy 105.312366 -270.966161) (xy 105.289495 -271.009738) (xy 105.25993 -271.049082) (xy 105.224437 -271.083174)
			(xy 105.183934 -271.11113) (xy 105.139472 -271.132228) (xy 105.092201 -271.14592) (xy 105.043346 -271.151852)
			(xy 104.994171 -271.149871) (xy 104.945952 -271.140027) (xy 104.899936 -271.122575) (xy 104.857315 -271.097968)
			(xy 104.819194 -271.066843) (xy 104.786559 -271.030006) (xy 104.760256 -270.98841) (xy 104.740965 -270.943134)
			(xy 104.729188 -270.89535) (xy 104.725228 -270.846296) (xy 104.396286 -270.846296) (xy 104.395791 -270.870903)
			(xy 104.387896 -270.91948) (xy 104.372312 -270.966161) (xy 104.349441 -271.009738) (xy 104.319876 -271.049082)
			(xy 104.284383 -271.083174) (xy 104.24388 -271.11113) (xy 104.199418 -271.132228) (xy 104.152147 -271.14592)
			(xy 104.103292 -271.151852) (xy 104.054117 -271.149871) (xy 104.005898 -271.140027) (xy 103.959882 -271.122575)
			(xy 103.917261 -271.097968) (xy 103.87914 -271.066843) (xy 103.846505 -271.030006) (xy 103.820202 -270.98841)
			(xy 103.800911 -270.943134) (xy 103.789134 -270.89535) (xy 103.785174 -270.846296) (xy 103.456486 -270.846296)
			(xy 103.455991 -270.870903) (xy 103.448096 -270.91948) (xy 103.432512 -270.966161) (xy 103.409641 -271.009738)
			(xy 103.380076 -271.049082) (xy 103.344583 -271.083174) (xy 103.30408 -271.11113) (xy 103.259618 -271.132228)
			(xy 103.212347 -271.14592) (xy 103.163492 -271.151852) (xy 103.114317 -271.149871) (xy 103.066098 -271.140027)
			(xy 103.020082 -271.122575) (xy 102.977461 -271.097968) (xy 102.93934 -271.066843) (xy 102.906705 -271.030006)
			(xy 102.880402 -270.98841) (xy 102.861111 -270.943134) (xy 102.849334 -270.89535) (xy 102.845374 -270.846296)
			(xy 102.516432 -270.846296) (xy 102.515937 -270.870903) (xy 102.508042 -270.91948) (xy 102.492458 -270.966161)
			(xy 102.469587 -271.009738) (xy 102.440022 -271.049082) (xy 102.404529 -271.083174) (xy 102.364026 -271.11113)
			(xy 102.319564 -271.132228) (xy 102.272293 -271.14592) (xy 102.223438 -271.151852) (xy 102.174263 -271.149871)
			(xy 102.126044 -271.140027) (xy 102.080028 -271.122575) (xy 102.037407 -271.097968) (xy 101.999286 -271.066843)
			(xy 101.966651 -271.030006) (xy 101.940348 -270.98841) (xy 101.921057 -270.943134) (xy 101.90928 -270.89535)
			(xy 101.90532 -270.846296) (xy 101.576378 -270.846296) (xy 101.575883 -270.870903) (xy 101.567988 -270.91948)
			(xy 101.552404 -270.966161) (xy 101.529533 -271.009738) (xy 101.499968 -271.049082) (xy 101.464475 -271.083174)
			(xy 101.423972 -271.11113) (xy 101.37951 -271.132228) (xy 101.332239 -271.14592) (xy 101.283384 -271.151852)
			(xy 101.234209 -271.149871) (xy 101.18599 -271.140027) (xy 101.139974 -271.122575) (xy 101.097353 -271.097968)
			(xy 101.059232 -271.066843) (xy 101.026597 -271.030006) (xy 101.000294 -270.98841) (xy 100.981003 -270.943134)
			(xy 100.969226 -270.89535) (xy 100.965266 -270.846296) (xy 100.636324 -270.846296) (xy 100.635829 -270.870903)
			(xy 100.627934 -270.91948) (xy 100.61235 -270.966161) (xy 100.589479 -271.009738) (xy 100.559914 -271.049082)
			(xy 100.524421 -271.083174) (xy 100.483918 -271.11113) (xy 100.439456 -271.132228) (xy 100.392185 -271.14592)
			(xy 100.34333 -271.151852) (xy 100.294155 -271.149871) (xy 100.245936 -271.140027) (xy 100.19992 -271.122575)
			(xy 100.157299 -271.097968) (xy 100.119178 -271.066843) (xy 100.086543 -271.030006) (xy 100.06024 -270.98841)
			(xy 100.040949 -270.943134) (xy 100.029172 -270.89535) (xy 100.025212 -270.846296) (xy 99.69627 -270.846296)
			(xy 99.695775 -270.870903) (xy 99.68788 -270.91948) (xy 99.672296 -270.966161) (xy 99.649425 -271.009738)
			(xy 99.61986 -271.049082) (xy 99.584367 -271.083174) (xy 99.543864 -271.11113) (xy 99.499402 -271.132228)
			(xy 99.452131 -271.14592) (xy 99.403276 -271.151852) (xy 99.354101 -271.149871) (xy 99.305882 -271.140027)
			(xy 99.259866 -271.122575) (xy 99.217245 -271.097968) (xy 99.179124 -271.066843) (xy 99.146489 -271.030006)
			(xy 99.120186 -270.98841) (xy 99.100895 -270.943134) (xy 99.089118 -270.89535) (xy 99.085158 -270.846296)
			(xy 98.75647 -270.846296) (xy 98.755975 -270.870903) (xy 98.74808 -270.91948) (xy 98.732496 -270.966161)
			(xy 98.709625 -271.009738) (xy 98.68006 -271.049082) (xy 98.644567 -271.083174) (xy 98.604064 -271.11113)
			(xy 98.559602 -271.132228) (xy 98.512331 -271.14592) (xy 98.463476 -271.151852) (xy 98.414301 -271.149871)
			(xy 98.366082 -271.140027) (xy 98.320066 -271.122575) (xy 98.277445 -271.097968) (xy 98.239324 -271.066843)
			(xy 98.206689 -271.030006) (xy 98.180386 -270.98841) (xy 98.161095 -270.943134) (xy 98.149318 -270.89535)
			(xy 98.145358 -270.846296) (xy 97.816416 -270.846296) (xy 97.815921 -270.870903) (xy 97.808026 -270.91948)
			(xy 97.792442 -270.966161) (xy 97.769571 -271.009738) (xy 97.740006 -271.049082) (xy 97.704513 -271.083174)
			(xy 97.66401 -271.11113) (xy 97.619548 -271.132228) (xy 97.572277 -271.14592) (xy 97.523422 -271.151852)
			(xy 97.474247 -271.149871) (xy 97.426028 -271.140027) (xy 97.380012 -271.122575) (xy 97.337391 -271.097968)
			(xy 97.29927 -271.066843) (xy 97.266635 -271.030006) (xy 97.240332 -270.98841) (xy 97.221041 -270.943134)
			(xy 97.209264 -270.89535) (xy 97.205304 -270.846296) (xy 96.876362 -270.846296) (xy 96.875894 -270.8709)
			(xy 96.867999 -270.91947) (xy 96.852413 -270.966143) (xy 96.829541 -271.009712) (xy 96.799974 -271.049046)
			(xy 96.764479 -271.083126) (xy 96.723976 -271.11107) (xy 96.679514 -271.132152) (xy 96.632245 -271.145828)
			(xy 96.607884 -271.149318) (xy 96.60509 -271.149572) (xy 96.599042 -271.150845) (xy 96.58775 -271.15586)
			(xy 96.582738 -271.159478) (xy 96.577658 -271.163288) (xy 96.573848 -271.168368) (xy 96.567244 -271.179798)
			(xy 96.533208 -271.262348) (xy 96.531263 -271.268237) (xy 96.529972 -271.280569) (xy 96.530668 -271.286732)
			(xy 96.532446 -271.299686) (xy 96.541082 -271.310862) (xy 96.565554 -271.343342) (xy 96.605847 -271.41398)
			(xy 96.621346 -271.451578) (xy 96.62414 -271.458436) (xy 96.63176 -271.46885) (xy 96.637348 -271.473168)
			(xy 96.642019 -271.476603) (xy 96.652536 -271.481474) (xy 96.658176 -271.48282) (xy 96.75114 -271.495012)
			(xy 96.754912 -271.495189) (xy 96.762436 -271.494544) (xy 96.766126 -271.493742) (xy 96.77527 -271.490948)
			(xy 96.787208 -271.485614) (xy 96.788478 -271.483836) (xy 96.795336 -271.474692) (xy 96.79559 -271.474184)
			(xy 96.810125 -271.455409) (xy 96.844022 -271.422163) (xy 96.882652 -271.394558) (xy 96.925085 -271.373258)
			(xy 96.970302 -271.358775) (xy 97.017214 -271.351458) (xy 97.040954 -271.350994) (xy 97.064949 -271.351437)
			(xy 97.11235 -271.358938) (xy 97.157994 -271.373762) (xy 97.200756 -271.395545) (xy 97.239584 -271.42375)
			(xy 97.273521 -271.457682) (xy 97.301732 -271.496506) (xy 97.323521 -271.539265) (xy 97.338352 -271.584907)
			(xy 97.34586 -271.632307) (xy 97.346262 -271.656302) (xy 97.675204 -271.656302) (xy 97.679164 -271.607248)
			(xy 97.690941 -271.559464) (xy 97.710232 -271.514188) (xy 97.736535 -271.472592) (xy 97.76917 -271.435755)
			(xy 97.807291 -271.40463) (xy 97.849912 -271.380023) (xy 97.895928 -271.362571) (xy 97.944147 -271.352727)
			(xy 97.993322 -271.350746) (xy 98.042177 -271.356678) (xy 98.089448 -271.37037) (xy 98.13391 -271.391468)
			(xy 98.174413 -271.419424) (xy 98.209906 -271.453516) (xy 98.239471 -271.49286) (xy 98.262342 -271.536437)
			(xy 98.277926 -271.583118) (xy 98.285821 -271.631695) (xy 98.286316 -271.656302) (xy 98.615258 -271.656302)
			(xy 98.619218 -271.607248) (xy 98.630995 -271.559464) (xy 98.650286 -271.514188) (xy 98.676589 -271.472592)
			(xy 98.709224 -271.435755) (xy 98.747345 -271.40463) (xy 98.789966 -271.380023) (xy 98.835982 -271.362571)
			(xy 98.884201 -271.352727) (xy 98.933376 -271.350746) (xy 98.982231 -271.356678) (xy 99.029502 -271.37037)
			(xy 99.073964 -271.391468) (xy 99.114467 -271.419424) (xy 99.14996 -271.453516) (xy 99.179525 -271.49286)
			(xy 99.202396 -271.536437) (xy 99.21798 -271.583118) (xy 99.225875 -271.631695) (xy 99.22637 -271.656302)
			(xy 99.555312 -271.656302) (xy 99.559272 -271.607248) (xy 99.571049 -271.559464) (xy 99.59034 -271.514188)
			(xy 99.616643 -271.472592) (xy 99.649278 -271.435755) (xy 99.687399 -271.40463) (xy 99.73002 -271.380023)
			(xy 99.776036 -271.362571) (xy 99.824255 -271.352727) (xy 99.87343 -271.350746) (xy 99.922285 -271.356678)
			(xy 99.969556 -271.37037) (xy 100.014018 -271.391468) (xy 100.054521 -271.419424) (xy 100.090014 -271.453516)
			(xy 100.119579 -271.49286) (xy 100.14245 -271.536437) (xy 100.158034 -271.583118) (xy 100.165929 -271.631695)
			(xy 100.166424 -271.656302) (xy 100.495366 -271.656302) (xy 100.499326 -271.607248) (xy 100.511103 -271.559464)
			(xy 100.530394 -271.514188) (xy 100.556697 -271.472592) (xy 100.589332 -271.435755) (xy 100.627453 -271.40463)
			(xy 100.670074 -271.380023) (xy 100.71609 -271.362571) (xy 100.764309 -271.352727) (xy 100.813484 -271.350746)
			(xy 100.862339 -271.356678) (xy 100.90961 -271.37037) (xy 100.954072 -271.391468) (xy 100.994575 -271.419424)
			(xy 101.030068 -271.453516) (xy 101.059633 -271.49286) (xy 101.082504 -271.536437) (xy 101.098088 -271.583118)
			(xy 101.105983 -271.631695) (xy 101.106478 -271.656302) (xy 101.435166 -271.656302) (xy 101.439126 -271.607248)
			(xy 101.450903 -271.559464) (xy 101.470194 -271.514188) (xy 101.496497 -271.472592) (xy 101.529132 -271.435755)
			(xy 101.567253 -271.40463) (xy 101.609874 -271.380023) (xy 101.65589 -271.362571) (xy 101.704109 -271.352727)
			(xy 101.753284 -271.350746) (xy 101.802139 -271.356678) (xy 101.84941 -271.37037) (xy 101.893872 -271.391468)
			(xy 101.934375 -271.419424) (xy 101.969868 -271.453516) (xy 101.999433 -271.49286) (xy 102.022304 -271.536437)
			(xy 102.037888 -271.583118) (xy 102.045783 -271.631695) (xy 102.046278 -271.656302) (xy 102.37522 -271.656302)
			(xy 102.37918 -271.607248) (xy 102.390957 -271.559464) (xy 102.410248 -271.514188) (xy 102.436551 -271.472592)
			(xy 102.469186 -271.435755) (xy 102.507307 -271.40463) (xy 102.549928 -271.380023) (xy 102.595944 -271.362571)
			(xy 102.644163 -271.352727) (xy 102.693338 -271.350746) (xy 102.742193 -271.356678) (xy 102.789464 -271.37037)
			(xy 102.833926 -271.391468) (xy 102.874429 -271.419424) (xy 102.909922 -271.453516) (xy 102.939487 -271.49286)
			(xy 102.962358 -271.536437) (xy 102.977942 -271.583118) (xy 102.985837 -271.631695) (xy 102.986332 -271.656302)
			(xy 103.315274 -271.656302) (xy 103.319234 -271.607248) (xy 103.331011 -271.559464) (xy 103.350302 -271.514188)
			(xy 103.376605 -271.472592) (xy 103.40924 -271.435755) (xy 103.447361 -271.40463) (xy 103.489982 -271.380023)
			(xy 103.535998 -271.362571) (xy 103.584217 -271.352727) (xy 103.633392 -271.350746) (xy 103.682247 -271.356678)
			(xy 103.729518 -271.37037) (xy 103.77398 -271.391468) (xy 103.814483 -271.419424) (xy 103.849976 -271.453516)
			(xy 103.879541 -271.49286) (xy 103.902412 -271.536437) (xy 103.917996 -271.583118) (xy 103.925891 -271.631695)
			(xy 103.926386 -271.656302) (xy 104.255328 -271.656302) (xy 104.259288 -271.607248) (xy 104.271065 -271.559464)
			(xy 104.290356 -271.514188) (xy 104.316659 -271.472592) (xy 104.349294 -271.435755) (xy 104.387415 -271.40463)
			(xy 104.430036 -271.380023) (xy 104.476052 -271.362571) (xy 104.524271 -271.352727) (xy 104.573446 -271.350746)
			(xy 104.622301 -271.356678) (xy 104.669572 -271.37037) (xy 104.714034 -271.391468) (xy 104.754537 -271.419424)
			(xy 104.79003 -271.453516) (xy 104.819595 -271.49286) (xy 104.842466 -271.536437) (xy 104.85805 -271.583118)
			(xy 104.865945 -271.631695) (xy 104.86644 -271.656302) (xy 105.195128 -271.656302) (xy 105.199088 -271.607248)
			(xy 105.210865 -271.559464) (xy 105.230156 -271.514188) (xy 105.256459 -271.472592) (xy 105.289094 -271.435755)
			(xy 105.327215 -271.40463) (xy 105.369836 -271.380023) (xy 105.415852 -271.362571) (xy 105.464071 -271.352727)
			(xy 105.513246 -271.350746) (xy 105.562101 -271.356678) (xy 105.609372 -271.37037) (xy 105.653834 -271.391468)
			(xy 105.694337 -271.419424) (xy 105.72983 -271.453516) (xy 105.759395 -271.49286) (xy 105.782266 -271.536437)
			(xy 105.79785 -271.583118) (xy 105.805745 -271.631695) (xy 105.80624 -271.656302) (xy 106.135182 -271.656302)
			(xy 106.139142 -271.607248) (xy 106.150919 -271.559464) (xy 106.17021 -271.514188) (xy 106.196513 -271.472592)
			(xy 106.229148 -271.435755) (xy 106.267269 -271.40463) (xy 106.30989 -271.380023) (xy 106.355906 -271.362571)
			(xy 106.404125 -271.352727) (xy 106.4533 -271.350746) (xy 106.502155 -271.356678) (xy 106.549426 -271.37037)
			(xy 106.593888 -271.391468) (xy 106.634391 -271.419424) (xy 106.669884 -271.453516) (xy 106.699449 -271.49286)
			(xy 106.72232 -271.536437) (xy 106.737904 -271.583118) (xy 106.745799 -271.631695) (xy 106.746294 -271.656302)
			(xy 107.075236 -271.656302) (xy 107.079196 -271.607248) (xy 107.090973 -271.559464) (xy 107.110264 -271.514188)
			(xy 107.136567 -271.472592) (xy 107.169202 -271.435755) (xy 107.207323 -271.40463) (xy 107.249944 -271.380023)
			(xy 107.29596 -271.362571) (xy 107.344179 -271.352727) (xy 107.393354 -271.350746) (xy 107.442209 -271.356678)
			(xy 107.48948 -271.37037) (xy 107.533942 -271.391468) (xy 107.574445 -271.419424) (xy 107.609938 -271.453516)
			(xy 107.639503 -271.49286) (xy 107.662374 -271.536437) (xy 107.677958 -271.583118) (xy 107.685853 -271.631695)
			(xy 107.686348 -271.656302) (xy 108.01529 -271.656302) (xy 108.01925 -271.607248) (xy 108.031027 -271.559464)
			(xy 108.050318 -271.514188) (xy 108.076621 -271.472592) (xy 108.109256 -271.435755) (xy 108.147377 -271.40463)
			(xy 108.189998 -271.380023) (xy 108.236014 -271.362571) (xy 108.284233 -271.352727) (xy 108.333408 -271.350746)
			(xy 108.382263 -271.356678) (xy 108.429534 -271.37037) (xy 108.473996 -271.391468) (xy 108.514499 -271.419424)
			(xy 108.549992 -271.453516) (xy 108.579557 -271.49286) (xy 108.602428 -271.536437) (xy 108.618012 -271.583118)
			(xy 108.625907 -271.631695) (xy 108.626402 -271.656302) (xy 115.528864 -271.656302) (xy 115.532824 -271.607248)
			(xy 115.544601 -271.559464) (xy 115.563892 -271.514188) (xy 115.590195 -271.472592) (xy 115.62283 -271.435755)
			(xy 115.660951 -271.40463) (xy 115.703572 -271.380023) (xy 115.749588 -271.362571) (xy 115.797807 -271.352727)
			(xy 115.846982 -271.350746) (xy 115.895837 -271.356678) (xy 115.943108 -271.37037) (xy 115.98757 -271.391468)
			(xy 116.028073 -271.419424) (xy 116.063566 -271.453516) (xy 116.093131 -271.49286) (xy 116.116002 -271.536437)
			(xy 116.131586 -271.583118) (xy 116.139481 -271.631695) (xy 116.139976 -271.656302) (xy 116.468918 -271.656302)
			(xy 116.472878 -271.607248) (xy 116.484655 -271.559464) (xy 116.503946 -271.514188) (xy 116.530249 -271.472592)
			(xy 116.562884 -271.435755) (xy 116.601005 -271.40463) (xy 116.643626 -271.380023) (xy 116.689642 -271.362571)
			(xy 116.737861 -271.352727) (xy 116.787036 -271.350746) (xy 116.835891 -271.356678) (xy 116.883162 -271.37037)
			(xy 116.927624 -271.391468) (xy 116.968127 -271.419424) (xy 117.00362 -271.453516) (xy 117.033185 -271.49286)
			(xy 117.056056 -271.536437) (xy 117.07164 -271.583118) (xy 117.079535 -271.631695) (xy 117.08003 -271.656302)
			(xy 117.408972 -271.656302) (xy 117.412932 -271.607248) (xy 117.424709 -271.559464) (xy 117.444 -271.514188)
			(xy 117.470303 -271.472592) (xy 117.502938 -271.435755) (xy 117.541059 -271.40463) (xy 117.58368 -271.380023)
			(xy 117.629696 -271.362571) (xy 117.677915 -271.352727) (xy 117.72709 -271.350746) (xy 117.775945 -271.356678)
			(xy 117.823216 -271.37037) (xy 117.867678 -271.391468) (xy 117.908181 -271.419424) (xy 117.943674 -271.453516)
			(xy 117.973239 -271.49286) (xy 117.99611 -271.536437) (xy 118.011694 -271.583118) (xy 118.019589 -271.631695)
			(xy 118.020084 -271.656302) (xy 118.349026 -271.656302) (xy 118.352986 -271.607248) (xy 118.364763 -271.559464)
			(xy 118.384054 -271.514188) (xy 118.410357 -271.472592) (xy 118.442992 -271.435755) (xy 118.481113 -271.40463)
			(xy 118.523734 -271.380023) (xy 118.56975 -271.362571) (xy 118.617969 -271.352727) (xy 118.667144 -271.350746)
			(xy 118.715999 -271.356678) (xy 118.76327 -271.37037) (xy 118.807732 -271.391468) (xy 118.848235 -271.419424)
			(xy 118.883728 -271.453516) (xy 118.913293 -271.49286) (xy 118.936164 -271.536437) (xy 118.951748 -271.583118)
			(xy 118.959643 -271.631695) (xy 118.960138 -271.656302) (xy 119.288826 -271.656302) (xy 119.292786 -271.607248)
			(xy 119.304563 -271.559464) (xy 119.323854 -271.514188) (xy 119.350157 -271.472592) (xy 119.382792 -271.435755)
			(xy 119.420913 -271.40463) (xy 119.463534 -271.380023) (xy 119.50955 -271.362571) (xy 119.557769 -271.352727)
			(xy 119.606944 -271.350746) (xy 119.655799 -271.356678) (xy 119.70307 -271.37037) (xy 119.747532 -271.391468)
			(xy 119.788035 -271.419424) (xy 119.823528 -271.453516) (xy 119.853093 -271.49286) (xy 119.875964 -271.536437)
			(xy 119.891548 -271.583118) (xy 119.899443 -271.631695) (xy 119.899938 -271.656302) (xy 120.22888 -271.656302)
			(xy 120.23284 -271.607248) (xy 120.244617 -271.559464) (xy 120.263908 -271.514188) (xy 120.290211 -271.472592)
			(xy 120.322846 -271.435755) (xy 120.360967 -271.40463) (xy 120.403588 -271.380023) (xy 120.449604 -271.362571)
			(xy 120.497823 -271.352727) (xy 120.546998 -271.350746) (xy 120.595853 -271.356678) (xy 120.643124 -271.37037)
			(xy 120.687586 -271.391468) (xy 120.728089 -271.419424) (xy 120.763582 -271.453516) (xy 120.793147 -271.49286)
			(xy 120.816018 -271.536437) (xy 120.831602 -271.583118) (xy 120.839497 -271.631695) (xy 120.839992 -271.656302)
			(xy 121.168934 -271.656302) (xy 121.172894 -271.607248) (xy 121.184671 -271.559464) (xy 121.203962 -271.514188)
			(xy 121.230265 -271.472592) (xy 121.2629 -271.435755) (xy 121.301021 -271.40463) (xy 121.343642 -271.380023)
			(xy 121.389658 -271.362571) (xy 121.437877 -271.352727) (xy 121.487052 -271.350746) (xy 121.535907 -271.356678)
			(xy 121.583178 -271.37037) (xy 121.62764 -271.391468) (xy 121.668143 -271.419424) (xy 121.703636 -271.453516)
			(xy 121.733201 -271.49286) (xy 121.756072 -271.536437) (xy 121.771656 -271.583118) (xy 121.779551 -271.631695)
			(xy 121.780046 -271.656302) (xy 122.108988 -271.656302) (xy 122.112948 -271.607248) (xy 122.124725 -271.559464)
			(xy 122.144016 -271.514188) (xy 122.170319 -271.472592) (xy 122.202954 -271.435755) (xy 122.241075 -271.40463)
			(xy 122.283696 -271.380023) (xy 122.329712 -271.362571) (xy 122.377931 -271.352727) (xy 122.427106 -271.350746)
			(xy 122.475961 -271.356678) (xy 122.523232 -271.37037) (xy 122.567694 -271.391468) (xy 122.608197 -271.419424)
			(xy 122.64369 -271.453516) (xy 122.673255 -271.49286) (xy 122.696126 -271.536437) (xy 122.71171 -271.583118)
			(xy 122.719605 -271.631695) (xy 122.7201 -271.656302) (xy 123.049042 -271.656302) (xy 123.053002 -271.607248)
			(xy 123.064779 -271.559464) (xy 123.08407 -271.514188) (xy 123.110373 -271.472592) (xy 123.143008 -271.435755)
			(xy 123.181129 -271.40463) (xy 123.22375 -271.380023) (xy 123.269766 -271.362571) (xy 123.317985 -271.352727)
			(xy 123.36716 -271.350746) (xy 123.416015 -271.356678) (xy 123.463286 -271.37037) (xy 123.507748 -271.391468)
			(xy 123.548251 -271.419424) (xy 123.583744 -271.453516) (xy 123.613309 -271.49286) (xy 123.63618 -271.536437)
			(xy 123.651764 -271.583118) (xy 123.659659 -271.631695) (xy 123.660154 -271.656302) (xy 123.988842 -271.656302)
			(xy 123.992802 -271.607248) (xy 124.004579 -271.559464) (xy 124.02387 -271.514188) (xy 124.050173 -271.472592)
			(xy 124.082808 -271.435755) (xy 124.120929 -271.40463) (xy 124.16355 -271.380023) (xy 124.209566 -271.362571)
			(xy 124.257785 -271.352727) (xy 124.30696 -271.350746) (xy 124.355815 -271.356678) (xy 124.403086 -271.37037)
			(xy 124.447548 -271.391468) (xy 124.488051 -271.419424) (xy 124.523544 -271.453516) (xy 124.553109 -271.49286)
			(xy 124.57598 -271.536437) (xy 124.591564 -271.583118) (xy 124.599459 -271.631695) (xy 124.599954 -271.656302)
			(xy 124.928896 -271.656302) (xy 124.932856 -271.607248) (xy 124.944633 -271.559464) (xy 124.963924 -271.514188)
			(xy 124.990227 -271.472592) (xy 125.022862 -271.435755) (xy 125.060983 -271.40463) (xy 125.103604 -271.380023)
			(xy 125.14962 -271.362571) (xy 125.197839 -271.352727) (xy 125.247014 -271.350746) (xy 125.295869 -271.356678)
			(xy 125.34314 -271.37037) (xy 125.387602 -271.391468) (xy 125.428105 -271.419424) (xy 125.463598 -271.453516)
			(xy 125.493163 -271.49286) (xy 125.516034 -271.536437) (xy 125.531618 -271.583118) (xy 125.539513 -271.631695)
			(xy 125.540008 -271.656302) (xy 125.86895 -271.656302) (xy 125.87291 -271.607248) (xy 125.884687 -271.559464)
			(xy 125.903978 -271.514188) (xy 125.930281 -271.472592) (xy 125.962916 -271.435755) (xy 126.001037 -271.40463)
			(xy 126.043658 -271.380023) (xy 126.089674 -271.362571) (xy 126.137893 -271.352727) (xy 126.187068 -271.350746)
			(xy 126.235923 -271.356678) (xy 126.283194 -271.37037) (xy 126.327656 -271.391468) (xy 126.368159 -271.419424)
			(xy 126.403652 -271.453516) (xy 126.433217 -271.49286) (xy 126.456088 -271.536437) (xy 126.471672 -271.583118)
			(xy 126.479567 -271.631695) (xy 126.480062 -271.656302) (xy 126.479567 -271.680909) (xy 126.471672 -271.729486)
			(xy 126.456088 -271.776167) (xy 126.433217 -271.819744) (xy 126.403652 -271.859088) (xy 126.368159 -271.89318)
			(xy 126.327656 -271.921136) (xy 126.283194 -271.942234) (xy 126.235923 -271.955926) (xy 126.187068 -271.961858)
			(xy 126.137893 -271.959877) (xy 126.089674 -271.950033) (xy 126.043658 -271.932581) (xy 126.001037 -271.907974)
			(xy 125.962916 -271.876849) (xy 125.930281 -271.840012) (xy 125.903978 -271.798416) (xy 125.884687 -271.75314)
			(xy 125.87291 -271.705356) (xy 125.86895 -271.656302) (xy 125.540008 -271.656302) (xy 125.539513 -271.680909)
			(xy 125.531618 -271.729486) (xy 125.516034 -271.776167) (xy 125.493163 -271.819744) (xy 125.463598 -271.859088)
			(xy 125.428105 -271.89318) (xy 125.387602 -271.921136) (xy 125.34314 -271.942234) (xy 125.295869 -271.955926)
			(xy 125.247014 -271.961858) (xy 125.197839 -271.959877) (xy 125.14962 -271.950033) (xy 125.103604 -271.932581)
			(xy 125.060983 -271.907974) (xy 125.022862 -271.876849) (xy 124.990227 -271.840012) (xy 124.963924 -271.798416)
			(xy 124.944633 -271.75314) (xy 124.932856 -271.705356) (xy 124.928896 -271.656302) (xy 124.599954 -271.656302)
			(xy 124.599459 -271.680909) (xy 124.591564 -271.729486) (xy 124.57598 -271.776167) (xy 124.553109 -271.819744)
			(xy 124.523544 -271.859088) (xy 124.488051 -271.89318) (xy 124.447548 -271.921136) (xy 124.403086 -271.942234)
			(xy 124.355815 -271.955926) (xy 124.30696 -271.961858) (xy 124.257785 -271.959877) (xy 124.209566 -271.950033)
			(xy 124.16355 -271.932581) (xy 124.120929 -271.907974) (xy 124.082808 -271.876849) (xy 124.050173 -271.840012)
			(xy 124.02387 -271.798416) (xy 124.004579 -271.75314) (xy 123.992802 -271.705356) (xy 123.988842 -271.656302)
			(xy 123.660154 -271.656302) (xy 123.659659 -271.680909) (xy 123.651764 -271.729486) (xy 123.63618 -271.776167)
			(xy 123.613309 -271.819744) (xy 123.583744 -271.859088) (xy 123.548251 -271.89318) (xy 123.507748 -271.921136)
			(xy 123.463286 -271.942234) (xy 123.416015 -271.955926) (xy 123.36716 -271.961858) (xy 123.317985 -271.959877)
			(xy 123.269766 -271.950033) (xy 123.22375 -271.932581) (xy 123.181129 -271.907974) (xy 123.143008 -271.876849)
			(xy 123.110373 -271.840012) (xy 123.08407 -271.798416) (xy 123.064779 -271.75314) (xy 123.053002 -271.705356)
			(xy 123.049042 -271.656302) (xy 122.7201 -271.656302) (xy 122.719605 -271.680909) (xy 122.71171 -271.729486)
			(xy 122.696126 -271.776167) (xy 122.673255 -271.819744) (xy 122.64369 -271.859088) (xy 122.608197 -271.89318)
			(xy 122.567694 -271.921136) (xy 122.523232 -271.942234) (xy 122.475961 -271.955926) (xy 122.427106 -271.961858)
			(xy 122.377931 -271.959877) (xy 122.329712 -271.950033) (xy 122.283696 -271.932581) (xy 122.241075 -271.907974)
			(xy 122.202954 -271.876849) (xy 122.170319 -271.840012) (xy 122.144016 -271.798416) (xy 122.124725 -271.75314)
			(xy 122.112948 -271.705356) (xy 122.108988 -271.656302) (xy 121.780046 -271.656302) (xy 121.779551 -271.680909)
			(xy 121.771656 -271.729486) (xy 121.756072 -271.776167) (xy 121.733201 -271.819744) (xy 121.703636 -271.859088)
			(xy 121.668143 -271.89318) (xy 121.62764 -271.921136) (xy 121.583178 -271.942234) (xy 121.535907 -271.955926)
			(xy 121.487052 -271.961858) (xy 121.437877 -271.959877) (xy 121.389658 -271.950033) (xy 121.343642 -271.932581)
			(xy 121.301021 -271.907974) (xy 121.2629 -271.876849) (xy 121.230265 -271.840012) (xy 121.203962 -271.798416)
			(xy 121.184671 -271.75314) (xy 121.172894 -271.705356) (xy 121.168934 -271.656302) (xy 120.839992 -271.656302)
			(xy 120.839497 -271.680909) (xy 120.831602 -271.729486) (xy 120.816018 -271.776167) (xy 120.793147 -271.819744)
			(xy 120.763582 -271.859088) (xy 120.728089 -271.89318) (xy 120.687586 -271.921136) (xy 120.643124 -271.942234)
			(xy 120.595853 -271.955926) (xy 120.546998 -271.961858) (xy 120.497823 -271.959877) (xy 120.449604 -271.950033)
			(xy 120.403588 -271.932581) (xy 120.360967 -271.907974) (xy 120.322846 -271.876849) (xy 120.290211 -271.840012)
			(xy 120.263908 -271.798416) (xy 120.244617 -271.75314) (xy 120.23284 -271.705356) (xy 120.22888 -271.656302)
			(xy 119.899938 -271.656302) (xy 119.899443 -271.680909) (xy 119.891548 -271.729486) (xy 119.875964 -271.776167)
			(xy 119.853093 -271.819744) (xy 119.823528 -271.859088) (xy 119.788035 -271.89318) (xy 119.747532 -271.921136)
			(xy 119.70307 -271.942234) (xy 119.655799 -271.955926) (xy 119.606944 -271.961858) (xy 119.557769 -271.959877)
			(xy 119.50955 -271.950033) (xy 119.463534 -271.932581) (xy 119.420913 -271.907974) (xy 119.382792 -271.876849)
			(xy 119.350157 -271.840012) (xy 119.323854 -271.798416) (xy 119.304563 -271.75314) (xy 119.292786 -271.705356)
			(xy 119.288826 -271.656302) (xy 118.960138 -271.656302) (xy 118.959643 -271.680909) (xy 118.951748 -271.729486)
			(xy 118.936164 -271.776167) (xy 118.913293 -271.819744) (xy 118.883728 -271.859088) (xy 118.848235 -271.89318)
			(xy 118.807732 -271.921136) (xy 118.76327 -271.942234) (xy 118.715999 -271.955926) (xy 118.667144 -271.961858)
			(xy 118.617969 -271.959877) (xy 118.56975 -271.950033) (xy 118.523734 -271.932581) (xy 118.481113 -271.907974)
			(xy 118.442992 -271.876849) (xy 118.410357 -271.840012) (xy 118.384054 -271.798416) (xy 118.364763 -271.75314)
			(xy 118.352986 -271.705356) (xy 118.349026 -271.656302) (xy 118.020084 -271.656302) (xy 118.019589 -271.680909)
			(xy 118.011694 -271.729486) (xy 117.99611 -271.776167) (xy 117.973239 -271.819744) (xy 117.943674 -271.859088)
			(xy 117.908181 -271.89318) (xy 117.867678 -271.921136) (xy 117.823216 -271.942234) (xy 117.775945 -271.955926)
			(xy 117.72709 -271.961858) (xy 117.677915 -271.959877) (xy 117.629696 -271.950033) (xy 117.58368 -271.932581)
			(xy 117.541059 -271.907974) (xy 117.502938 -271.876849) (xy 117.470303 -271.840012) (xy 117.444 -271.798416)
			(xy 117.424709 -271.75314) (xy 117.412932 -271.705356) (xy 117.408972 -271.656302) (xy 117.08003 -271.656302)
			(xy 117.079535 -271.680909) (xy 117.07164 -271.729486) (xy 117.056056 -271.776167) (xy 117.033185 -271.819744)
			(xy 117.00362 -271.859088) (xy 116.968127 -271.89318) (xy 116.927624 -271.921136) (xy 116.883162 -271.942234)
			(xy 116.835891 -271.955926) (xy 116.787036 -271.961858) (xy 116.737861 -271.959877) (xy 116.689642 -271.950033)
			(xy 116.643626 -271.932581) (xy 116.601005 -271.907974) (xy 116.562884 -271.876849) (xy 116.530249 -271.840012)
			(xy 116.503946 -271.798416) (xy 116.484655 -271.75314) (xy 116.472878 -271.705356) (xy 116.468918 -271.656302)
			(xy 116.139976 -271.656302) (xy 116.139481 -271.680909) (xy 116.131586 -271.729486) (xy 116.116002 -271.776167)
			(xy 116.093131 -271.819744) (xy 116.063566 -271.859088) (xy 116.028073 -271.89318) (xy 115.98757 -271.921136)
			(xy 115.943108 -271.942234) (xy 115.895837 -271.955926) (xy 115.846982 -271.961858) (xy 115.797807 -271.959877)
			(xy 115.749588 -271.950033) (xy 115.703572 -271.932581) (xy 115.660951 -271.907974) (xy 115.62283 -271.876849)
			(xy 115.590195 -271.840012) (xy 115.563892 -271.798416) (xy 115.544601 -271.75314) (xy 115.532824 -271.705356)
			(xy 115.528864 -271.656302) (xy 108.626402 -271.656302) (xy 108.625907 -271.680909) (xy 108.618012 -271.729486)
			(xy 108.602428 -271.776167) (xy 108.579557 -271.819744) (xy 108.549992 -271.859088) (xy 108.514499 -271.89318)
			(xy 108.473996 -271.921136) (xy 108.429534 -271.942234) (xy 108.382263 -271.955926) (xy 108.333408 -271.961858)
			(xy 108.284233 -271.959877) (xy 108.236014 -271.950033) (xy 108.189998 -271.932581) (xy 108.147377 -271.907974)
			(xy 108.109256 -271.876849) (xy 108.076621 -271.840012) (xy 108.050318 -271.798416) (xy 108.031027 -271.75314)
			(xy 108.01925 -271.705356) (xy 108.01529 -271.656302) (xy 107.686348 -271.656302) (xy 107.685853 -271.680909)
			(xy 107.677958 -271.729486) (xy 107.662374 -271.776167) (xy 107.639503 -271.819744) (xy 107.609938 -271.859088)
			(xy 107.574445 -271.89318) (xy 107.533942 -271.921136) (xy 107.48948 -271.942234) (xy 107.442209 -271.955926)
			(xy 107.393354 -271.961858) (xy 107.344179 -271.959877) (xy 107.29596 -271.950033) (xy 107.249944 -271.932581)
			(xy 107.207323 -271.907974) (xy 107.169202 -271.876849) (xy 107.136567 -271.840012) (xy 107.110264 -271.798416)
			(xy 107.090973 -271.75314) (xy 107.079196 -271.705356) (xy 107.075236 -271.656302) (xy 106.746294 -271.656302)
			(xy 106.745799 -271.680909) (xy 106.737904 -271.729486) (xy 106.72232 -271.776167) (xy 106.699449 -271.819744)
			(xy 106.669884 -271.859088) (xy 106.634391 -271.89318) (xy 106.593888 -271.921136) (xy 106.549426 -271.942234)
			(xy 106.502155 -271.955926) (xy 106.4533 -271.961858) (xy 106.404125 -271.959877) (xy 106.355906 -271.950033)
			(xy 106.30989 -271.932581) (xy 106.267269 -271.907974) (xy 106.229148 -271.876849) (xy 106.196513 -271.840012)
			(xy 106.17021 -271.798416) (xy 106.150919 -271.75314) (xy 106.139142 -271.705356) (xy 106.135182 -271.656302)
			(xy 105.80624 -271.656302) (xy 105.805745 -271.680909) (xy 105.79785 -271.729486) (xy 105.782266 -271.776167)
			(xy 105.759395 -271.819744) (xy 105.72983 -271.859088) (xy 105.694337 -271.89318) (xy 105.653834 -271.921136)
			(xy 105.609372 -271.942234) (xy 105.562101 -271.955926) (xy 105.513246 -271.961858) (xy 105.464071 -271.959877)
			(xy 105.415852 -271.950033) (xy 105.369836 -271.932581) (xy 105.327215 -271.907974) (xy 105.289094 -271.876849)
			(xy 105.256459 -271.840012) (xy 105.230156 -271.798416) (xy 105.210865 -271.75314) (xy 105.199088 -271.705356)
			(xy 105.195128 -271.656302) (xy 104.86644 -271.656302) (xy 104.865945 -271.680909) (xy 104.85805 -271.729486)
			(xy 104.842466 -271.776167) (xy 104.819595 -271.819744) (xy 104.79003 -271.859088) (xy 104.754537 -271.89318)
			(xy 104.714034 -271.921136) (xy 104.669572 -271.942234) (xy 104.622301 -271.955926) (xy 104.573446 -271.961858)
			(xy 104.524271 -271.959877) (xy 104.476052 -271.950033) (xy 104.430036 -271.932581) (xy 104.387415 -271.907974)
			(xy 104.349294 -271.876849) (xy 104.316659 -271.840012) (xy 104.290356 -271.798416) (xy 104.271065 -271.75314)
			(xy 104.259288 -271.705356) (xy 104.255328 -271.656302) (xy 103.926386 -271.656302) (xy 103.925891 -271.680909)
			(xy 103.917996 -271.729486) (xy 103.902412 -271.776167) (xy 103.879541 -271.819744) (xy 103.849976 -271.859088)
			(xy 103.814483 -271.89318) (xy 103.77398 -271.921136) (xy 103.729518 -271.942234) (xy 103.682247 -271.955926)
			(xy 103.633392 -271.961858) (xy 103.584217 -271.959877) (xy 103.535998 -271.950033) (xy 103.489982 -271.932581)
			(xy 103.447361 -271.907974) (xy 103.40924 -271.876849) (xy 103.376605 -271.840012) (xy 103.350302 -271.798416)
			(xy 103.331011 -271.75314) (xy 103.319234 -271.705356) (xy 103.315274 -271.656302) (xy 102.986332 -271.656302)
			(xy 102.985837 -271.680909) (xy 102.977942 -271.729486) (xy 102.962358 -271.776167) (xy 102.939487 -271.819744)
			(xy 102.909922 -271.859088) (xy 102.874429 -271.89318) (xy 102.833926 -271.921136) (xy 102.789464 -271.942234)
			(xy 102.742193 -271.955926) (xy 102.693338 -271.961858) (xy 102.644163 -271.959877) (xy 102.595944 -271.950033)
			(xy 102.549928 -271.932581) (xy 102.507307 -271.907974) (xy 102.469186 -271.876849) (xy 102.436551 -271.840012)
			(xy 102.410248 -271.798416) (xy 102.390957 -271.75314) (xy 102.37918 -271.705356) (xy 102.37522 -271.656302)
			(xy 102.046278 -271.656302) (xy 102.045783 -271.680909) (xy 102.037888 -271.729486) (xy 102.022304 -271.776167)
			(xy 101.999433 -271.819744) (xy 101.969868 -271.859088) (xy 101.934375 -271.89318) (xy 101.893872 -271.921136)
			(xy 101.84941 -271.942234) (xy 101.802139 -271.955926) (xy 101.753284 -271.961858) (xy 101.704109 -271.959877)
			(xy 101.65589 -271.950033) (xy 101.609874 -271.932581) (xy 101.567253 -271.907974) (xy 101.529132 -271.876849)
			(xy 101.496497 -271.840012) (xy 101.470194 -271.798416) (xy 101.450903 -271.75314) (xy 101.439126 -271.705356)
			(xy 101.435166 -271.656302) (xy 101.106478 -271.656302) (xy 101.105983 -271.680909) (xy 101.098088 -271.729486)
			(xy 101.082504 -271.776167) (xy 101.059633 -271.819744) (xy 101.030068 -271.859088) (xy 100.994575 -271.89318)
			(xy 100.954072 -271.921136) (xy 100.90961 -271.942234) (xy 100.862339 -271.955926) (xy 100.813484 -271.961858)
			(xy 100.764309 -271.959877) (xy 100.71609 -271.950033) (xy 100.670074 -271.932581) (xy 100.627453 -271.907974)
			(xy 100.589332 -271.876849) (xy 100.556697 -271.840012) (xy 100.530394 -271.798416) (xy 100.511103 -271.75314)
			(xy 100.499326 -271.705356) (xy 100.495366 -271.656302) (xy 100.166424 -271.656302) (xy 100.165929 -271.680909)
			(xy 100.158034 -271.729486) (xy 100.14245 -271.776167) (xy 100.119579 -271.819744) (xy 100.090014 -271.859088)
			(xy 100.054521 -271.89318) (xy 100.014018 -271.921136) (xy 99.969556 -271.942234) (xy 99.922285 -271.955926)
			(xy 99.87343 -271.961858) (xy 99.824255 -271.959877) (xy 99.776036 -271.950033) (xy 99.73002 -271.932581)
			(xy 99.687399 -271.907974) (xy 99.649278 -271.876849) (xy 99.616643 -271.840012) (xy 99.59034 -271.798416)
			(xy 99.571049 -271.75314) (xy 99.559272 -271.705356) (xy 99.555312 -271.656302) (xy 99.22637 -271.656302)
			(xy 99.225875 -271.680909) (xy 99.21798 -271.729486) (xy 99.202396 -271.776167) (xy 99.179525 -271.819744)
			(xy 99.14996 -271.859088) (xy 99.114467 -271.89318) (xy 99.073964 -271.921136) (xy 99.029502 -271.942234)
			(xy 98.982231 -271.955926) (xy 98.933376 -271.961858) (xy 98.884201 -271.959877) (xy 98.835982 -271.950033)
			(xy 98.789966 -271.932581) (xy 98.747345 -271.907974) (xy 98.709224 -271.876849) (xy 98.676589 -271.840012)
			(xy 98.650286 -271.798416) (xy 98.630995 -271.75314) (xy 98.619218 -271.705356) (xy 98.615258 -271.656302)
			(xy 98.286316 -271.656302) (xy 98.285821 -271.680909) (xy 98.277926 -271.729486) (xy 98.262342 -271.776167)
			(xy 98.239471 -271.819744) (xy 98.209906 -271.859088) (xy 98.174413 -271.89318) (xy 98.13391 -271.921136)
			(xy 98.089448 -271.942234) (xy 98.042177 -271.955926) (xy 97.993322 -271.961858) (xy 97.944147 -271.959877)
			(xy 97.895928 -271.950033) (xy 97.849912 -271.932581) (xy 97.807291 -271.907974) (xy 97.76917 -271.876849)
			(xy 97.736535 -271.840012) (xy 97.710232 -271.798416) (xy 97.690941 -271.75314) (xy 97.679164 -271.705356)
			(xy 97.675204 -271.656302) (xy 97.346262 -271.656302) (xy 97.345797 -271.680542) (xy 97.338139 -271.728413)
			(xy 97.323016 -271.774474) (xy 97.300807 -271.817568) (xy 97.27207 -271.856613) (xy 97.237526 -271.890628)
			(xy 97.198043 -271.91876) (xy 97.154612 -271.940303) (xy 97.108324 -271.954715) (xy 97.084388 -271.958562)
			(xy 97.071942 -271.96034) (xy 97.040954 -271.961864) (xy 97.017458 -271.961431) (xy 96.97102 -271.954237)
			(xy 96.926229 -271.940025) (xy 96.884139 -271.919129) (xy 96.84574 -271.892042) (xy 96.811935 -271.8594)
			(xy 96.797368 -271.84096) (xy 96.795336 -271.838166) (xy 96.795082 -271.837912) (xy 96.790941 -271.832544)
			(xy 96.780382 -271.824049) (xy 96.774254 -271.821148) (xy 96.768412 -271.818862) (xy 96.755204 -271.817084)
			(xy 96.661986 -271.829276) (xy 96.65531 -271.830322) (xy 96.642821 -271.835472) (xy 96.637348 -271.839436)
			(xy 96.63176 -271.843754) (xy 96.62414 -271.854168) (xy 96.621346 -271.86128) (xy 96.613468 -271.880851)
			(xy 96.59516 -271.918865) (xy 96.58477 -271.937226) (xy 96.539812 -272.014696) (xy 96.534199 -272.025765)
			(xy 96.533381 -272.050542) (xy 96.538288 -272.06194) (xy 96.552766 -272.091404) (xy 96.576388 -272.138902)
			(xy 96.57715 -272.140172) (xy 96.579843 -272.144418) (xy 96.586623 -272.151843) (xy 96.590612 -272.154904)
			(xy 96.600518 -272.162016) (xy 96.613218 -272.163794) (xy 96.637225 -272.16764) (xy 96.683693 -272.181938)
			(xy 96.727311 -272.203411) (xy 96.766981 -272.231518) (xy 96.801702 -272.26555) (xy 96.830598 -272.304648)
			(xy 96.852941 -272.347828) (xy 96.868167 -272.394) (xy 96.875893 -272.441999) (xy 96.876362 -272.466308)
			(xy 99.085158 -272.466308) (xy 99.089118 -272.417254) (xy 99.100895 -272.36947) (xy 99.120186 -272.324194)
			(xy 99.146489 -272.282598) (xy 99.179124 -272.245761) (xy 99.217245 -272.214636) (xy 99.259866 -272.190029)
			(xy 99.305882 -272.172577) (xy 99.354101 -272.162733) (xy 99.403276 -272.160752) (xy 99.452131 -272.166684)
			(xy 99.499402 -272.180376) (xy 99.543864 -272.201474) (xy 99.584367 -272.22943) (xy 99.61986 -272.263522)
			(xy 99.649425 -272.302866) (xy 99.672296 -272.346443) (xy 99.68788 -272.393124) (xy 99.695775 -272.441701)
			(xy 99.69627 -272.466308) (xy 101.90532 -272.466308) (xy 101.90928 -272.417254) (xy 101.921057 -272.36947)
			(xy 101.940348 -272.324194) (xy 101.966651 -272.282598) (xy 101.999286 -272.245761) (xy 102.037407 -272.214636)
			(xy 102.080028 -272.190029) (xy 102.126044 -272.172577) (xy 102.174263 -272.162733) (xy 102.223438 -272.160752)
			(xy 102.272293 -272.166684) (xy 102.319564 -272.180376) (xy 102.364026 -272.201474) (xy 102.404529 -272.22943)
			(xy 102.440022 -272.263522) (xy 102.469587 -272.302866) (xy 102.492458 -272.346443) (xy 102.508042 -272.393124)
			(xy 102.515937 -272.441701) (xy 102.516432 -272.466308) (xy 104.725228 -272.466308) (xy 104.729188 -272.417254)
			(xy 104.740965 -272.36947) (xy 104.760256 -272.324194) (xy 104.786559 -272.282598) (xy 104.819194 -272.245761)
			(xy 104.857315 -272.214636) (xy 104.899936 -272.190029) (xy 104.945952 -272.172577) (xy 104.994171 -272.162733)
			(xy 105.043346 -272.160752) (xy 105.092201 -272.166684) (xy 105.139472 -272.180376) (xy 105.183934 -272.201474)
			(xy 105.224437 -272.22943) (xy 105.25993 -272.263522) (xy 105.289495 -272.302866) (xy 105.312366 -272.346443)
			(xy 105.32795 -272.393124) (xy 105.335845 -272.441701) (xy 105.33634 -272.466308) (xy 107.545136 -272.466308)
			(xy 107.549096 -272.417254) (xy 107.560873 -272.36947) (xy 107.580164 -272.324194) (xy 107.606467 -272.282598)
			(xy 107.639102 -272.245761) (xy 107.677223 -272.214636) (xy 107.719844 -272.190029) (xy 107.76586 -272.172577)
			(xy 107.814079 -272.162733) (xy 107.863254 -272.160752) (xy 107.912109 -272.166684) (xy 107.95938 -272.180376)
			(xy 108.003842 -272.201474) (xy 108.044345 -272.22943) (xy 108.079838 -272.263522) (xy 108.109403 -272.302866)
			(xy 108.132274 -272.346443) (xy 108.147858 -272.393124) (xy 108.155753 -272.441701) (xy 108.156248 -272.466308)
			(xy 108.48519 -272.466308) (xy 108.48915 -272.417254) (xy 108.500927 -272.36947) (xy 108.520218 -272.324194)
			(xy 108.546521 -272.282598) (xy 108.579156 -272.245761) (xy 108.617277 -272.214636) (xy 108.659898 -272.190029)
			(xy 108.705914 -272.172577) (xy 108.754133 -272.162733) (xy 108.803308 -272.160752) (xy 108.852163 -272.166684)
			(xy 108.899434 -272.180376) (xy 108.943896 -272.201474) (xy 108.984399 -272.22943) (xy 109.019892 -272.263522)
			(xy 109.049457 -272.302866) (xy 109.072328 -272.346443) (xy 109.087912 -272.393124) (xy 109.095807 -272.441701)
			(xy 109.096302 -272.466308) (xy 109.425244 -272.466308) (xy 109.429204 -272.417254) (xy 109.440981 -272.36947)
			(xy 109.460272 -272.324194) (xy 109.486575 -272.282598) (xy 109.51921 -272.245761) (xy 109.557331 -272.214636)
			(xy 109.599952 -272.190029) (xy 109.645968 -272.172577) (xy 109.694187 -272.162733) (xy 109.743362 -272.160752)
			(xy 109.792217 -272.166684) (xy 109.839488 -272.180376) (xy 109.88395 -272.201474) (xy 109.924453 -272.22943)
			(xy 109.959946 -272.263522) (xy 109.989511 -272.302866) (xy 110.012382 -272.346443) (xy 110.027966 -272.393124)
			(xy 110.035861 -272.441701) (xy 110.036356 -272.466308) (xy 110.365298 -272.466308) (xy 110.369258 -272.417254)
			(xy 110.381035 -272.36947) (xy 110.400326 -272.324194) (xy 110.426629 -272.282598) (xy 110.459264 -272.245761)
			(xy 110.497385 -272.214636) (xy 110.540006 -272.190029) (xy 110.586022 -272.172577) (xy 110.634241 -272.162733)
			(xy 110.683416 -272.160752) (xy 110.732271 -272.166684) (xy 110.779542 -272.180376) (xy 110.824004 -272.201474)
			(xy 110.864507 -272.22943) (xy 110.9 -272.263522) (xy 110.929565 -272.302866) (xy 110.952436 -272.346443)
			(xy 110.96802 -272.393124) (xy 110.975915 -272.441701) (xy 110.97641 -272.466308) (xy 113.178856 -272.466308)
			(xy 113.182816 -272.417254) (xy 113.194593 -272.36947) (xy 113.213884 -272.324194) (xy 113.240187 -272.282598)
			(xy 113.272822 -272.245761) (xy 113.310943 -272.214636) (xy 113.353564 -272.190029) (xy 113.39958 -272.172577)
			(xy 113.447799 -272.162733) (xy 113.496974 -272.160752) (xy 113.545829 -272.166684) (xy 113.5931 -272.180376)
			(xy 113.637562 -272.201474) (xy 113.678065 -272.22943) (xy 113.713558 -272.263522) (xy 113.743123 -272.302866)
			(xy 113.765994 -272.346443) (xy 113.781578 -272.393124) (xy 113.789473 -272.441701) (xy 113.789968 -272.466308)
			(xy 114.11891 -272.466308) (xy 114.12287 -272.417254) (xy 114.134647 -272.36947) (xy 114.153938 -272.324194)
			(xy 114.180241 -272.282598) (xy 114.212876 -272.245761) (xy 114.250997 -272.214636) (xy 114.293618 -272.190029)
			(xy 114.339634 -272.172577) (xy 114.387853 -272.162733) (xy 114.437028 -272.160752) (xy 114.485883 -272.166684)
			(xy 114.533154 -272.180376) (xy 114.577616 -272.201474) (xy 114.618119 -272.22943) (xy 114.653612 -272.263522)
			(xy 114.683177 -272.302866) (xy 114.706048 -272.346443) (xy 114.721632 -272.393124) (xy 114.729527 -272.441701)
			(xy 114.730022 -272.466308) (xy 115.058964 -272.466308) (xy 115.062924 -272.417254) (xy 115.074701 -272.36947)
			(xy 115.093992 -272.324194) (xy 115.120295 -272.282598) (xy 115.15293 -272.245761) (xy 115.191051 -272.214636)
			(xy 115.233672 -272.190029) (xy 115.279688 -272.172577) (xy 115.327907 -272.162733) (xy 115.377082 -272.160752)
			(xy 115.425937 -272.166684) (xy 115.473208 -272.180376) (xy 115.51767 -272.201474) (xy 115.558173 -272.22943)
			(xy 115.593666 -272.263522) (xy 115.623231 -272.302866) (xy 115.646102 -272.346443) (xy 115.661686 -272.393124)
			(xy 115.669581 -272.441701) (xy 115.670076 -272.466308) (xy 115.999018 -272.466308) (xy 116.002978 -272.417254)
			(xy 116.014755 -272.36947) (xy 116.034046 -272.324194) (xy 116.060349 -272.282598) (xy 116.092984 -272.245761)
			(xy 116.131105 -272.214636) (xy 116.173726 -272.190029) (xy 116.219742 -272.172577) (xy 116.267961 -272.162733)
			(xy 116.317136 -272.160752) (xy 116.365991 -272.166684) (xy 116.413262 -272.180376) (xy 116.457724 -272.201474)
			(xy 116.498227 -272.22943) (xy 116.53372 -272.263522) (xy 116.563285 -272.302866) (xy 116.586156 -272.346443)
			(xy 116.60174 -272.393124) (xy 116.609635 -272.441701) (xy 116.61013 -272.466308) (xy 118.818926 -272.466308)
			(xy 118.822886 -272.417254) (xy 118.834663 -272.36947) (xy 118.853954 -272.324194) (xy 118.880257 -272.282598)
			(xy 118.912892 -272.245761) (xy 118.951013 -272.214636) (xy 118.993634 -272.190029) (xy 119.03965 -272.172577)
			(xy 119.087869 -272.162733) (xy 119.137044 -272.160752) (xy 119.185899 -272.166684) (xy 119.23317 -272.180376)
			(xy 119.277632 -272.201474) (xy 119.318135 -272.22943) (xy 119.353628 -272.263522) (xy 119.383193 -272.302866)
			(xy 119.406064 -272.346443) (xy 119.421648 -272.393124) (xy 119.429543 -272.441701) (xy 119.430038 -272.466308)
			(xy 121.638834 -272.466308) (xy 121.642794 -272.417254) (xy 121.654571 -272.36947) (xy 121.673862 -272.324194)
			(xy 121.700165 -272.282598) (xy 121.7328 -272.245761) (xy 121.770921 -272.214636) (xy 121.813542 -272.190029)
			(xy 121.859558 -272.172577) (xy 121.907777 -272.162733) (xy 121.956952 -272.160752) (xy 122.005807 -272.166684)
			(xy 122.053078 -272.180376) (xy 122.09754 -272.201474) (xy 122.138043 -272.22943) (xy 122.173536 -272.263522)
			(xy 122.203101 -272.302866) (xy 122.225972 -272.346443) (xy 122.241556 -272.393124) (xy 122.249451 -272.441701)
			(xy 122.249946 -272.466308) (xy 124.458996 -272.466308) (xy 124.462956 -272.417254) (xy 124.474733 -272.36947)
			(xy 124.494024 -272.324194) (xy 124.520327 -272.282598) (xy 124.552962 -272.245761) (xy 124.591083 -272.214636)
			(xy 124.633704 -272.190029) (xy 124.67972 -272.172577) (xy 124.727939 -272.162733) (xy 124.777114 -272.160752)
			(xy 124.825969 -272.166684) (xy 124.87324 -272.180376) (xy 124.917702 -272.201474) (xy 124.958205 -272.22943)
			(xy 124.993698 -272.263522) (xy 125.023263 -272.302866) (xy 125.046134 -272.346443) (xy 125.061718 -272.393124)
			(xy 125.069613 -272.441701) (xy 125.070108 -272.466308) (xy 125.069613 -272.490915) (xy 125.061718 -272.539492)
			(xy 125.046134 -272.586173) (xy 125.023263 -272.62975) (xy 124.993698 -272.669094) (xy 124.958205 -272.703186)
			(xy 124.917702 -272.731142) (xy 124.87324 -272.75224) (xy 124.825969 -272.765932) (xy 124.777114 -272.771864)
			(xy 124.727939 -272.769883) (xy 124.67972 -272.760039) (xy 124.633704 -272.742587) (xy 124.591083 -272.71798)
			(xy 124.552962 -272.686855) (xy 124.520327 -272.650018) (xy 124.494024 -272.608422) (xy 124.474733 -272.563146)
			(xy 124.462956 -272.515362) (xy 124.458996 -272.466308) (xy 122.249946 -272.466308) (xy 122.249451 -272.490915)
			(xy 122.241556 -272.539492) (xy 122.225972 -272.586173) (xy 122.203101 -272.62975) (xy 122.173536 -272.669094)
			(xy 122.138043 -272.703186) (xy 122.09754 -272.731142) (xy 122.053078 -272.75224) (xy 122.005807 -272.765932)
			(xy 121.956952 -272.771864) (xy 121.907777 -272.769883) (xy 121.859558 -272.760039) (xy 121.813542 -272.742587)
			(xy 121.770921 -272.71798) (xy 121.7328 -272.686855) (xy 121.700165 -272.650018) (xy 121.673862 -272.608422)
			(xy 121.654571 -272.563146) (xy 121.642794 -272.515362) (xy 121.638834 -272.466308) (xy 119.430038 -272.466308)
			(xy 119.429543 -272.490915) (xy 119.421648 -272.539492) (xy 119.406064 -272.586173) (xy 119.383193 -272.62975)
			(xy 119.353628 -272.669094) (xy 119.318135 -272.703186) (xy 119.277632 -272.731142) (xy 119.23317 -272.75224)
			(xy 119.185899 -272.765932) (xy 119.137044 -272.771864) (xy 119.087869 -272.769883) (xy 119.03965 -272.760039)
			(xy 118.993634 -272.742587) (xy 118.951013 -272.71798) (xy 118.912892 -272.686855) (xy 118.880257 -272.650018)
			(xy 118.853954 -272.608422) (xy 118.834663 -272.563146) (xy 118.822886 -272.515362) (xy 118.818926 -272.466308)
			(xy 116.61013 -272.466308) (xy 116.609635 -272.490915) (xy 116.60174 -272.539492) (xy 116.586156 -272.586173)
			(xy 116.563285 -272.62975) (xy 116.53372 -272.669094) (xy 116.498227 -272.703186) (xy 116.457724 -272.731142)
			(xy 116.413262 -272.75224) (xy 116.365991 -272.765932) (xy 116.317136 -272.771864) (xy 116.267961 -272.769883)
			(xy 116.219742 -272.760039) (xy 116.173726 -272.742587) (xy 116.131105 -272.71798) (xy 116.092984 -272.686855)
			(xy 116.060349 -272.650018) (xy 116.034046 -272.608422) (xy 116.014755 -272.563146) (xy 116.002978 -272.515362)
			(xy 115.999018 -272.466308) (xy 115.670076 -272.466308) (xy 115.669581 -272.490915) (xy 115.661686 -272.539492)
			(xy 115.646102 -272.586173) (xy 115.623231 -272.62975) (xy 115.593666 -272.669094) (xy 115.558173 -272.703186)
			(xy 115.51767 -272.731142) (xy 115.473208 -272.75224) (xy 115.425937 -272.765932) (xy 115.377082 -272.771864)
			(xy 115.327907 -272.769883) (xy 115.279688 -272.760039) (xy 115.233672 -272.742587) (xy 115.191051 -272.71798)
			(xy 115.15293 -272.686855) (xy 115.120295 -272.650018) (xy 115.093992 -272.608422) (xy 115.074701 -272.563146)
			(xy 115.062924 -272.515362) (xy 115.058964 -272.466308) (xy 114.730022 -272.466308) (xy 114.729527 -272.490915)
			(xy 114.721632 -272.539492) (xy 114.706048 -272.586173) (xy 114.683177 -272.62975) (xy 114.653612 -272.669094)
			(xy 114.618119 -272.703186) (xy 114.577616 -272.731142) (xy 114.533154 -272.75224) (xy 114.485883 -272.765932)
			(xy 114.437028 -272.771864) (xy 114.387853 -272.769883) (xy 114.339634 -272.760039) (xy 114.293618 -272.742587)
			(xy 114.250997 -272.71798) (xy 114.212876 -272.686855) (xy 114.180241 -272.650018) (xy 114.153938 -272.608422)
			(xy 114.134647 -272.563146) (xy 114.12287 -272.515362) (xy 114.11891 -272.466308) (xy 113.789968 -272.466308)
			(xy 113.789473 -272.490915) (xy 113.781578 -272.539492) (xy 113.765994 -272.586173) (xy 113.743123 -272.62975)
			(xy 113.713558 -272.669094) (xy 113.678065 -272.703186) (xy 113.637562 -272.731142) (xy 113.5931 -272.75224)
			(xy 113.545829 -272.765932) (xy 113.496974 -272.771864) (xy 113.447799 -272.769883) (xy 113.39958 -272.760039)
			(xy 113.353564 -272.742587) (xy 113.310943 -272.71798) (xy 113.272822 -272.686855) (xy 113.240187 -272.650018)
			(xy 113.213884 -272.608422) (xy 113.194593 -272.563146) (xy 113.182816 -272.515362) (xy 113.178856 -272.466308)
			(xy 110.97641 -272.466308) (xy 110.975915 -272.490915) (xy 110.96802 -272.539492) (xy 110.952436 -272.586173)
			(xy 110.929565 -272.62975) (xy 110.9 -272.669094) (xy 110.864507 -272.703186) (xy 110.824004 -272.731142)
			(xy 110.779542 -272.75224) (xy 110.732271 -272.765932) (xy 110.683416 -272.771864) (xy 110.634241 -272.769883)
			(xy 110.586022 -272.760039) (xy 110.540006 -272.742587) (xy 110.497385 -272.71798) (xy 110.459264 -272.686855)
			(xy 110.426629 -272.650018) (xy 110.400326 -272.608422) (xy 110.381035 -272.563146) (xy 110.369258 -272.515362)
			(xy 110.365298 -272.466308) (xy 110.036356 -272.466308) (xy 110.035861 -272.490915) (xy 110.027966 -272.539492)
			(xy 110.012382 -272.586173) (xy 109.989511 -272.62975) (xy 109.959946 -272.669094) (xy 109.924453 -272.703186)
			(xy 109.88395 -272.731142) (xy 109.839488 -272.75224) (xy 109.792217 -272.765932) (xy 109.743362 -272.771864)
			(xy 109.694187 -272.769883) (xy 109.645968 -272.760039) (xy 109.599952 -272.742587) (xy 109.557331 -272.71798)
			(xy 109.51921 -272.686855) (xy 109.486575 -272.650018) (xy 109.460272 -272.608422) (xy 109.440981 -272.563146)
			(xy 109.429204 -272.515362) (xy 109.425244 -272.466308) (xy 109.096302 -272.466308) (xy 109.095807 -272.490915)
			(xy 109.087912 -272.539492) (xy 109.072328 -272.586173) (xy 109.049457 -272.62975) (xy 109.019892 -272.669094)
			(xy 108.984399 -272.703186) (xy 108.943896 -272.731142) (xy 108.899434 -272.75224) (xy 108.852163 -272.765932)
			(xy 108.803308 -272.771864) (xy 108.754133 -272.769883) (xy 108.705914 -272.760039) (xy 108.659898 -272.742587)
			(xy 108.617277 -272.71798) (xy 108.579156 -272.686855) (xy 108.546521 -272.650018) (xy 108.520218 -272.608422)
			(xy 108.500927 -272.563146) (xy 108.48915 -272.515362) (xy 108.48519 -272.466308) (xy 108.156248 -272.466308)
			(xy 108.155753 -272.490915) (xy 108.147858 -272.539492) (xy 108.132274 -272.586173) (xy 108.109403 -272.62975)
			(xy 108.079838 -272.669094) (xy 108.044345 -272.703186) (xy 108.003842 -272.731142) (xy 107.95938 -272.75224)
			(xy 107.912109 -272.765932) (xy 107.863254 -272.771864) (xy 107.814079 -272.769883) (xy 107.76586 -272.760039)
			(xy 107.719844 -272.742587) (xy 107.677223 -272.71798) (xy 107.639102 -272.686855) (xy 107.606467 -272.650018)
			(xy 107.580164 -272.608422) (xy 107.560873 -272.563146) (xy 107.549096 -272.515362) (xy 107.545136 -272.466308)
			(xy 105.33634 -272.466308) (xy 105.335845 -272.490915) (xy 105.32795 -272.539492) (xy 105.312366 -272.586173)
			(xy 105.289495 -272.62975) (xy 105.25993 -272.669094) (xy 105.224437 -272.703186) (xy 105.183934 -272.731142)
			(xy 105.139472 -272.75224) (xy 105.092201 -272.765932) (xy 105.043346 -272.771864) (xy 104.994171 -272.769883)
			(xy 104.945952 -272.760039) (xy 104.899936 -272.742587) (xy 104.857315 -272.71798) (xy 104.819194 -272.686855)
			(xy 104.786559 -272.650018) (xy 104.760256 -272.608422) (xy 104.740965 -272.563146) (xy 104.729188 -272.515362)
			(xy 104.725228 -272.466308) (xy 102.516432 -272.466308) (xy 102.515937 -272.490915) (xy 102.508042 -272.539492)
			(xy 102.492458 -272.586173) (xy 102.469587 -272.62975) (xy 102.440022 -272.669094) (xy 102.404529 -272.703186)
			(xy 102.364026 -272.731142) (xy 102.319564 -272.75224) (xy 102.272293 -272.765932) (xy 102.223438 -272.771864)
			(xy 102.174263 -272.769883) (xy 102.126044 -272.760039) (xy 102.080028 -272.742587) (xy 102.037407 -272.71798)
			(xy 101.999286 -272.686855) (xy 101.966651 -272.650018) (xy 101.940348 -272.608422) (xy 101.921057 -272.563146)
			(xy 101.90928 -272.515362) (xy 101.90532 -272.466308) (xy 99.69627 -272.466308) (xy 99.695775 -272.490915)
			(xy 99.68788 -272.539492) (xy 99.672296 -272.586173) (xy 99.649425 -272.62975) (xy 99.61986 -272.669094)
			(xy 99.584367 -272.703186) (xy 99.543864 -272.731142) (xy 99.499402 -272.75224) (xy 99.452131 -272.765932)
			(xy 99.403276 -272.771864) (xy 99.354101 -272.769883) (xy 99.305882 -272.760039) (xy 99.259866 -272.742587)
			(xy 99.217245 -272.71798) (xy 99.179124 -272.686855) (xy 99.146489 -272.650018) (xy 99.120186 -272.608422)
			(xy 99.100895 -272.563146) (xy 99.089118 -272.515362) (xy 99.085158 -272.466308) (xy 96.876362 -272.466308)
			(xy 96.875893 -272.490911) (xy 96.867996 -272.539479) (xy 96.85241 -272.586152) (xy 96.829536 -272.629718)
			(xy 96.799969 -272.669051) (xy 96.764475 -272.70313) (xy 96.723972 -272.731072) (xy 96.679511 -272.752153)
			(xy 96.632243 -272.765828) (xy 96.607884 -272.76933) (xy 96.60509 -272.769584) (xy 96.599041 -272.770855)
			(xy 96.587743 -272.775863) (xy 96.582738 -272.77949) (xy 96.577658 -272.7833) (xy 96.573848 -272.78838)
			(xy 96.567244 -272.79981) (xy 96.533208 -272.88236) (xy 96.531265 -272.888249) (xy 96.529976 -272.900581)
			(xy 96.530668 -272.906744) (xy 96.532446 -272.919698) (xy 96.541082 -272.930874) (xy 96.565554 -272.963354)
			(xy 96.605845 -273.033993) (xy 96.621346 -273.07159) (xy 96.62414 -273.078448) (xy 96.63176 -273.088862)
			(xy 96.637348 -273.09318) (xy 96.642019 -273.096615) (xy 96.652537 -273.101485) (xy 96.658176 -273.102832)
			(xy 96.75114 -273.115024) (xy 96.754912 -273.115202) (xy 96.762436 -273.114557) (xy 96.766126 -273.113754)
			(xy 96.77527 -273.11096) (xy 96.787208 -273.105626) (xy 96.788478 -273.103848) (xy 96.795336 -273.094704)
			(xy 96.79559 -273.094196) (xy 96.810125 -273.07542) (xy 96.844021 -273.042173) (xy 96.882651 -273.014567)
			(xy 96.925084 -272.993266) (xy 96.970301 -272.978783) (xy 97.017214 -272.971465) (xy 97.040954 -272.971006)
			(xy 97.064949 -272.971449) (xy 97.112349 -272.97895) (xy 97.157992 -272.993775) (xy 97.200754 -273.015558)
			(xy 97.239581 -273.043763) (xy 97.273516 -273.077695) (xy 97.301726 -273.116519) (xy 97.323513 -273.159278)
			(xy 97.338343 -273.204919) (xy 97.345849 -273.252319) (xy 97.346262 -273.276314) (xy 97.675204 -273.276314)
			(xy 97.679164 -273.22726) (xy 97.690941 -273.179476) (xy 97.710232 -273.1342) (xy 97.736535 -273.092604)
			(xy 97.76917 -273.055767) (xy 97.807291 -273.024642) (xy 97.849912 -273.000035) (xy 97.895928 -272.982583)
			(xy 97.944147 -272.972739) (xy 97.993322 -272.970758) (xy 98.042177 -272.97669) (xy 98.089448 -272.990382)
			(xy 98.13391 -273.01148) (xy 98.174413 -273.039436) (xy 98.209906 -273.073528) (xy 98.239471 -273.112872)
			(xy 98.262342 -273.156449) (xy 98.277926 -273.20313) (xy 98.285821 -273.251707) (xy 98.286316 -273.276314)
			(xy 98.615258 -273.276314) (xy 98.619218 -273.22726) (xy 98.630995 -273.179476) (xy 98.650286 -273.1342)
			(xy 98.676589 -273.092604) (xy 98.709224 -273.055767) (xy 98.747345 -273.024642) (xy 98.789966 -273.000035)
			(xy 98.835982 -272.982583) (xy 98.884201 -272.972739) (xy 98.933376 -272.970758) (xy 98.982231 -272.97669)
			(xy 99.029502 -272.990382) (xy 99.073964 -273.01148) (xy 99.114467 -273.039436) (xy 99.14996 -273.073528)
			(xy 99.179525 -273.112872) (xy 99.202396 -273.156449) (xy 99.21798 -273.20313) (xy 99.225875 -273.251707)
			(xy 99.22637 -273.276314) (xy 99.555312 -273.276314) (xy 99.559272 -273.22726) (xy 99.571049 -273.179476)
			(xy 99.59034 -273.1342) (xy 99.616643 -273.092604) (xy 99.649278 -273.055767) (xy 99.687399 -273.024642)
			(xy 99.73002 -273.000035) (xy 99.776036 -272.982583) (xy 99.824255 -272.972739) (xy 99.87343 -272.970758)
			(xy 99.922285 -272.97669) (xy 99.969556 -272.990382) (xy 100.014018 -273.01148) (xy 100.054521 -273.039436)
			(xy 100.090014 -273.073528) (xy 100.119579 -273.112872) (xy 100.14245 -273.156449) (xy 100.158034 -273.20313)
			(xy 100.165929 -273.251707) (xy 100.166424 -273.276314) (xy 100.495366 -273.276314) (xy 100.499326 -273.22726)
			(xy 100.511103 -273.179476) (xy 100.530394 -273.1342) (xy 100.556697 -273.092604) (xy 100.589332 -273.055767)
			(xy 100.627453 -273.024642) (xy 100.670074 -273.000035) (xy 100.71609 -272.982583) (xy 100.764309 -272.972739)
			(xy 100.813484 -272.970758) (xy 100.862339 -272.97669) (xy 100.90961 -272.990382) (xy 100.954072 -273.01148)
			(xy 100.994575 -273.039436) (xy 101.030068 -273.073528) (xy 101.059633 -273.112872) (xy 101.082504 -273.156449)
			(xy 101.098088 -273.20313) (xy 101.105983 -273.251707) (xy 101.106478 -273.276314) (xy 101.435166 -273.276314)
			(xy 101.439126 -273.22726) (xy 101.450903 -273.179476) (xy 101.470194 -273.1342) (xy 101.496497 -273.092604)
			(xy 101.529132 -273.055767) (xy 101.567253 -273.024642) (xy 101.609874 -273.000035) (xy 101.65589 -272.982583)
			(xy 101.704109 -272.972739) (xy 101.753284 -272.970758) (xy 101.802139 -272.97669) (xy 101.84941 -272.990382)
			(xy 101.893872 -273.01148) (xy 101.934375 -273.039436) (xy 101.969868 -273.073528) (xy 101.999433 -273.112872)
			(xy 102.022304 -273.156449) (xy 102.037888 -273.20313) (xy 102.045783 -273.251707) (xy 102.046278 -273.276314)
			(xy 102.37522 -273.276314) (xy 102.37918 -273.22726) (xy 102.390957 -273.179476) (xy 102.410248 -273.1342)
			(xy 102.436551 -273.092604) (xy 102.469186 -273.055767) (xy 102.507307 -273.024642) (xy 102.549928 -273.000035)
			(xy 102.595944 -272.982583) (xy 102.644163 -272.972739) (xy 102.693338 -272.970758) (xy 102.742193 -272.97669)
			(xy 102.789464 -272.990382) (xy 102.833926 -273.01148) (xy 102.874429 -273.039436) (xy 102.909922 -273.073528)
			(xy 102.939487 -273.112872) (xy 102.962358 -273.156449) (xy 102.977942 -273.20313) (xy 102.985837 -273.251707)
			(xy 102.986332 -273.276314) (xy 103.315274 -273.276314) (xy 103.319234 -273.22726) (xy 103.331011 -273.179476)
			(xy 103.350302 -273.1342) (xy 103.376605 -273.092604) (xy 103.40924 -273.055767) (xy 103.447361 -273.024642)
			(xy 103.489982 -273.000035) (xy 103.535998 -272.982583) (xy 103.584217 -272.972739) (xy 103.633392 -272.970758)
			(xy 103.682247 -272.97669) (xy 103.729518 -272.990382) (xy 103.77398 -273.01148) (xy 103.814483 -273.039436)
			(xy 103.849976 -273.073528) (xy 103.879541 -273.112872) (xy 103.902412 -273.156449) (xy 103.917996 -273.20313)
			(xy 103.925891 -273.251707) (xy 103.926386 -273.276314) (xy 104.255328 -273.276314) (xy 104.259288 -273.22726)
			(xy 104.271065 -273.179476) (xy 104.290356 -273.1342) (xy 104.316659 -273.092604) (xy 104.349294 -273.055767)
			(xy 104.387415 -273.024642) (xy 104.430036 -273.000035) (xy 104.476052 -272.982583) (xy 104.524271 -272.972739)
			(xy 104.573446 -272.970758) (xy 104.622301 -272.97669) (xy 104.669572 -272.990382) (xy 104.714034 -273.01148)
			(xy 104.754537 -273.039436) (xy 104.79003 -273.073528) (xy 104.819595 -273.112872) (xy 104.842466 -273.156449)
			(xy 104.85805 -273.20313) (xy 104.865945 -273.251707) (xy 104.86644 -273.276314) (xy 105.195128 -273.276314)
			(xy 105.199088 -273.22726) (xy 105.210865 -273.179476) (xy 105.230156 -273.1342) (xy 105.256459 -273.092604)
			(xy 105.289094 -273.055767) (xy 105.327215 -273.024642) (xy 105.369836 -273.000035) (xy 105.415852 -272.982583)
			(xy 105.464071 -272.972739) (xy 105.513246 -272.970758) (xy 105.562101 -272.97669) (xy 105.609372 -272.990382)
			(xy 105.653834 -273.01148) (xy 105.694337 -273.039436) (xy 105.72983 -273.073528) (xy 105.759395 -273.112872)
			(xy 105.782266 -273.156449) (xy 105.79785 -273.20313) (xy 105.805745 -273.251707) (xy 105.80624 -273.276314)
			(xy 106.135182 -273.276314) (xy 106.139142 -273.22726) (xy 106.150919 -273.179476) (xy 106.17021 -273.1342)
			(xy 106.196513 -273.092604) (xy 106.229148 -273.055767) (xy 106.267269 -273.024642) (xy 106.30989 -273.000035)
			(xy 106.355906 -272.982583) (xy 106.404125 -272.972739) (xy 106.4533 -272.970758) (xy 106.502155 -272.97669)
			(xy 106.549426 -272.990382) (xy 106.593888 -273.01148) (xy 106.634391 -273.039436) (xy 106.669884 -273.073528)
			(xy 106.699449 -273.112872) (xy 106.72232 -273.156449) (xy 106.737904 -273.20313) (xy 106.745799 -273.251707)
			(xy 106.746294 -273.276314) (xy 107.075236 -273.276314) (xy 107.079196 -273.22726) (xy 107.090973 -273.179476)
			(xy 107.110264 -273.1342) (xy 107.136567 -273.092604) (xy 107.169202 -273.055767) (xy 107.207323 -273.024642)
			(xy 107.249944 -273.000035) (xy 107.29596 -272.982583) (xy 107.344179 -272.972739) (xy 107.393354 -272.970758)
			(xy 107.442209 -272.97669) (xy 107.48948 -272.990382) (xy 107.533942 -273.01148) (xy 107.574445 -273.039436)
			(xy 107.609938 -273.073528) (xy 107.639503 -273.112872) (xy 107.662374 -273.156449) (xy 107.677958 -273.20313)
			(xy 107.685853 -273.251707) (xy 107.686348 -273.276314) (xy 108.01529 -273.276314) (xy 108.01925 -273.22726)
			(xy 108.031027 -273.179476) (xy 108.050318 -273.1342) (xy 108.076621 -273.092604) (xy 108.109256 -273.055767)
			(xy 108.147377 -273.024642) (xy 108.189998 -273.000035) (xy 108.236014 -272.982583) (xy 108.284233 -272.972739)
			(xy 108.333408 -272.970758) (xy 108.382263 -272.97669) (xy 108.429534 -272.990382) (xy 108.473996 -273.01148)
			(xy 108.514499 -273.039436) (xy 108.549992 -273.073528) (xy 108.579557 -273.112872) (xy 108.602428 -273.156449)
			(xy 108.618012 -273.20313) (xy 108.625907 -273.251707) (xy 108.626402 -273.276314) (xy 108.955344 -273.276314)
			(xy 108.959304 -273.22726) (xy 108.971081 -273.179476) (xy 108.990372 -273.1342) (xy 109.016675 -273.092604)
			(xy 109.04931 -273.055767) (xy 109.087431 -273.024642) (xy 109.130052 -273.000035) (xy 109.176068 -272.982583)
			(xy 109.224287 -272.972739) (xy 109.273462 -272.970758) (xy 109.322317 -272.97669) (xy 109.369588 -272.990382)
			(xy 109.41405 -273.01148) (xy 109.454553 -273.039436) (xy 109.490046 -273.073528) (xy 109.519611 -273.112872)
			(xy 109.542482 -273.156449) (xy 109.558066 -273.20313) (xy 109.565961 -273.251707) (xy 109.566456 -273.276314)
			(xy 109.895144 -273.276314) (xy 109.899104 -273.22726) (xy 109.910881 -273.179476) (xy 109.930172 -273.1342)
			(xy 109.956475 -273.092604) (xy 109.98911 -273.055767) (xy 110.027231 -273.024642) (xy 110.069852 -273.000035)
			(xy 110.115868 -272.982583) (xy 110.164087 -272.972739) (xy 110.213262 -272.970758) (xy 110.262117 -272.97669)
			(xy 110.309388 -272.990382) (xy 110.35385 -273.01148) (xy 110.394353 -273.039436) (xy 110.429846 -273.073528)
			(xy 110.459411 -273.112872) (xy 110.482282 -273.156449) (xy 110.497866 -273.20313) (xy 110.505761 -273.251707)
			(xy 110.506256 -273.276314) (xy 113.64901 -273.276314) (xy 113.65297 -273.22726) (xy 113.664747 -273.179476)
			(xy 113.684038 -273.1342) (xy 113.710341 -273.092604) (xy 113.742976 -273.055767) (xy 113.781097 -273.024642)
			(xy 113.823718 -273.000035) (xy 113.869734 -272.982583) (xy 113.917953 -272.972739) (xy 113.967128 -272.970758)
			(xy 114.015983 -272.97669) (xy 114.063254 -272.990382) (xy 114.107716 -273.01148) (xy 114.148219 -273.039436)
			(xy 114.183712 -273.073528) (xy 114.213277 -273.112872) (xy 114.236148 -273.156449) (xy 114.251732 -273.20313)
			(xy 114.259627 -273.251707) (xy 114.260122 -273.276314) (xy 114.58881 -273.276314) (xy 114.59277 -273.22726)
			(xy 114.604547 -273.179476) (xy 114.623838 -273.1342) (xy 114.650141 -273.092604) (xy 114.682776 -273.055767)
			(xy 114.720897 -273.024642) (xy 114.763518 -273.000035) (xy 114.809534 -272.982583) (xy 114.857753 -272.972739)
			(xy 114.906928 -272.970758) (xy 114.955783 -272.97669) (xy 115.003054 -272.990382) (xy 115.047516 -273.01148)
			(xy 115.088019 -273.039436) (xy 115.123512 -273.073528) (xy 115.153077 -273.112872) (xy 115.175948 -273.156449)
			(xy 115.191532 -273.20313) (xy 115.199427 -273.251707) (xy 115.199922 -273.276314) (xy 115.528864 -273.276314)
			(xy 115.532824 -273.22726) (xy 115.544601 -273.179476) (xy 115.563892 -273.1342) (xy 115.590195 -273.092604)
			(xy 115.62283 -273.055767) (xy 115.660951 -273.024642) (xy 115.703572 -273.000035) (xy 115.749588 -272.982583)
			(xy 115.797807 -272.972739) (xy 115.846982 -272.970758) (xy 115.895837 -272.97669) (xy 115.943108 -272.990382)
			(xy 115.98757 -273.01148) (xy 116.028073 -273.039436) (xy 116.063566 -273.073528) (xy 116.093131 -273.112872)
			(xy 116.116002 -273.156449) (xy 116.131586 -273.20313) (xy 116.139481 -273.251707) (xy 116.139976 -273.276314)
			(xy 116.468918 -273.276314) (xy 116.472878 -273.22726) (xy 116.484655 -273.179476) (xy 116.503946 -273.1342)
			(xy 116.530249 -273.092604) (xy 116.562884 -273.055767) (xy 116.601005 -273.024642) (xy 116.643626 -273.000035)
			(xy 116.689642 -272.982583) (xy 116.737861 -272.972739) (xy 116.787036 -272.970758) (xy 116.835891 -272.97669)
			(xy 116.883162 -272.990382) (xy 116.927624 -273.01148) (xy 116.968127 -273.039436) (xy 117.00362 -273.073528)
			(xy 117.033185 -273.112872) (xy 117.056056 -273.156449) (xy 117.07164 -273.20313) (xy 117.079535 -273.251707)
			(xy 117.08003 -273.276314) (xy 117.408972 -273.276314) (xy 117.412932 -273.22726) (xy 117.424709 -273.179476)
			(xy 117.444 -273.1342) (xy 117.470303 -273.092604) (xy 117.502938 -273.055767) (xy 117.541059 -273.024642)
			(xy 117.58368 -273.000035) (xy 117.629696 -272.982583) (xy 117.677915 -272.972739) (xy 117.72709 -272.970758)
			(xy 117.775945 -272.97669) (xy 117.823216 -272.990382) (xy 117.867678 -273.01148) (xy 117.908181 -273.039436)
			(xy 117.943674 -273.073528) (xy 117.973239 -273.112872) (xy 117.99611 -273.156449) (xy 118.011694 -273.20313)
			(xy 118.019589 -273.251707) (xy 118.020084 -273.276314) (xy 118.349026 -273.276314) (xy 118.352986 -273.22726)
			(xy 118.364763 -273.179476) (xy 118.384054 -273.1342) (xy 118.410357 -273.092604) (xy 118.442992 -273.055767)
			(xy 118.481113 -273.024642) (xy 118.523734 -273.000035) (xy 118.56975 -272.982583) (xy 118.617969 -272.972739)
			(xy 118.667144 -272.970758) (xy 118.715999 -272.97669) (xy 118.76327 -272.990382) (xy 118.807732 -273.01148)
			(xy 118.848235 -273.039436) (xy 118.883728 -273.073528) (xy 118.913293 -273.112872) (xy 118.936164 -273.156449)
			(xy 118.951748 -273.20313) (xy 118.959643 -273.251707) (xy 118.960138 -273.276314) (xy 119.288826 -273.276314)
			(xy 119.292786 -273.22726) (xy 119.304563 -273.179476) (xy 119.323854 -273.1342) (xy 119.350157 -273.092604)
			(xy 119.382792 -273.055767) (xy 119.420913 -273.024642) (xy 119.463534 -273.000035) (xy 119.50955 -272.982583)
			(xy 119.557769 -272.972739) (xy 119.606944 -272.970758) (xy 119.655799 -272.97669) (xy 119.70307 -272.990382)
			(xy 119.747532 -273.01148) (xy 119.788035 -273.039436) (xy 119.823528 -273.073528) (xy 119.853093 -273.112872)
			(xy 119.875964 -273.156449) (xy 119.891548 -273.20313) (xy 119.899443 -273.251707) (xy 119.899938 -273.276314)
			(xy 120.22888 -273.276314) (xy 120.23284 -273.22726) (xy 120.244617 -273.179476) (xy 120.263908 -273.1342)
			(xy 120.290211 -273.092604) (xy 120.322846 -273.055767) (xy 120.360967 -273.024642) (xy 120.403588 -273.000035)
			(xy 120.449604 -272.982583) (xy 120.497823 -272.972739) (xy 120.546998 -272.970758) (xy 120.595853 -272.97669)
			(xy 120.643124 -272.990382) (xy 120.687586 -273.01148) (xy 120.728089 -273.039436) (xy 120.763582 -273.073528)
			(xy 120.793147 -273.112872) (xy 120.816018 -273.156449) (xy 120.831602 -273.20313) (xy 120.839497 -273.251707)
			(xy 120.839992 -273.276314) (xy 121.168934 -273.276314) (xy 121.172894 -273.22726) (xy 121.184671 -273.179476)
			(xy 121.203962 -273.1342) (xy 121.230265 -273.092604) (xy 121.2629 -273.055767) (xy 121.301021 -273.024642)
			(xy 121.343642 -273.000035) (xy 121.389658 -272.982583) (xy 121.437877 -272.972739) (xy 121.487052 -272.970758)
			(xy 121.535907 -272.97669) (xy 121.583178 -272.990382) (xy 121.62764 -273.01148) (xy 121.668143 -273.039436)
			(xy 121.703636 -273.073528) (xy 121.733201 -273.112872) (xy 121.756072 -273.156449) (xy 121.771656 -273.20313)
			(xy 121.779551 -273.251707) (xy 121.780046 -273.276314) (xy 122.108988 -273.276314) (xy 122.112948 -273.22726)
			(xy 122.124725 -273.179476) (xy 122.144016 -273.1342) (xy 122.170319 -273.092604) (xy 122.202954 -273.055767)
			(xy 122.241075 -273.024642) (xy 122.283696 -273.000035) (xy 122.329712 -272.982583) (xy 122.377931 -272.972739)
			(xy 122.427106 -272.970758) (xy 122.475961 -272.97669) (xy 122.523232 -272.990382) (xy 122.567694 -273.01148)
			(xy 122.608197 -273.039436) (xy 122.64369 -273.073528) (xy 122.673255 -273.112872) (xy 122.696126 -273.156449)
			(xy 122.71171 -273.20313) (xy 122.719605 -273.251707) (xy 122.7201 -273.276314) (xy 123.049042 -273.276314)
			(xy 123.053002 -273.22726) (xy 123.064779 -273.179476) (xy 123.08407 -273.1342) (xy 123.110373 -273.092604)
			(xy 123.143008 -273.055767) (xy 123.181129 -273.024642) (xy 123.22375 -273.000035) (xy 123.269766 -272.982583)
			(xy 123.317985 -272.972739) (xy 123.36716 -272.970758) (xy 123.416015 -272.97669) (xy 123.463286 -272.990382)
			(xy 123.507748 -273.01148) (xy 123.548251 -273.039436) (xy 123.583744 -273.073528) (xy 123.613309 -273.112872)
			(xy 123.63618 -273.156449) (xy 123.651764 -273.20313) (xy 123.659659 -273.251707) (xy 123.660154 -273.276314)
			(xy 123.988842 -273.276314) (xy 123.992802 -273.22726) (xy 124.004579 -273.179476) (xy 124.02387 -273.1342)
			(xy 124.050173 -273.092604) (xy 124.082808 -273.055767) (xy 124.120929 -273.024642) (xy 124.16355 -273.000035)
			(xy 124.209566 -272.982583) (xy 124.257785 -272.972739) (xy 124.30696 -272.970758) (xy 124.355815 -272.97669)
			(xy 124.403086 -272.990382) (xy 124.447548 -273.01148) (xy 124.488051 -273.039436) (xy 124.523544 -273.073528)
			(xy 124.553109 -273.112872) (xy 124.57598 -273.156449) (xy 124.591564 -273.20313) (xy 124.599459 -273.251707)
			(xy 124.599954 -273.276314) (xy 124.928896 -273.276314) (xy 124.932856 -273.22726) (xy 124.944633 -273.179476)
			(xy 124.963924 -273.1342) (xy 124.990227 -273.092604) (xy 125.022862 -273.055767) (xy 125.060983 -273.024642)
			(xy 125.103604 -273.000035) (xy 125.14962 -272.982583) (xy 125.197839 -272.972739) (xy 125.247014 -272.970758)
			(xy 125.295869 -272.97669) (xy 125.34314 -272.990382) (xy 125.387602 -273.01148) (xy 125.428105 -273.039436)
			(xy 125.463598 -273.073528) (xy 125.493163 -273.112872) (xy 125.516034 -273.156449) (xy 125.531618 -273.20313)
			(xy 125.539513 -273.251707) (xy 125.540008 -273.276314) (xy 125.86895 -273.276314) (xy 125.87291 -273.22726)
			(xy 125.884687 -273.179476) (xy 125.903978 -273.1342) (xy 125.930281 -273.092604) (xy 125.962916 -273.055767)
			(xy 126.001037 -273.024642) (xy 126.043658 -273.000035) (xy 126.089674 -272.982583) (xy 126.137893 -272.972739)
			(xy 126.187068 -272.970758) (xy 126.235923 -272.97669) (xy 126.283194 -272.990382) (xy 126.327656 -273.01148)
			(xy 126.368159 -273.039436) (xy 126.403652 -273.073528) (xy 126.433217 -273.112872) (xy 126.456088 -273.156449)
			(xy 126.471672 -273.20313) (xy 126.479567 -273.251707) (xy 126.480062 -273.276314) (xy 126.479567 -273.300921)
			(xy 126.471672 -273.349498) (xy 126.456088 -273.396179) (xy 126.433217 -273.439756) (xy 126.403652 -273.4791)
			(xy 126.368159 -273.513192) (xy 126.327656 -273.541148) (xy 126.283194 -273.562246) (xy 126.235923 -273.575938)
			(xy 126.187068 -273.58187) (xy 126.137893 -273.579889) (xy 126.089674 -273.570045) (xy 126.043658 -273.552593)
			(xy 126.001037 -273.527986) (xy 125.962916 -273.496861) (xy 125.930281 -273.460024) (xy 125.903978 -273.418428)
			(xy 125.884687 -273.373152) (xy 125.87291 -273.325368) (xy 125.86895 -273.276314) (xy 125.540008 -273.276314)
			(xy 125.539513 -273.300921) (xy 125.531618 -273.349498) (xy 125.516034 -273.396179) (xy 125.493163 -273.439756)
			(xy 125.463598 -273.4791) (xy 125.428105 -273.513192) (xy 125.387602 -273.541148) (xy 125.34314 -273.562246)
			(xy 125.295869 -273.575938) (xy 125.247014 -273.58187) (xy 125.197839 -273.579889) (xy 125.14962 -273.570045)
			(xy 125.103604 -273.552593) (xy 125.060983 -273.527986) (xy 125.022862 -273.496861) (xy 124.990227 -273.460024)
			(xy 124.963924 -273.418428) (xy 124.944633 -273.373152) (xy 124.932856 -273.325368) (xy 124.928896 -273.276314)
			(xy 124.599954 -273.276314) (xy 124.599459 -273.300921) (xy 124.591564 -273.349498) (xy 124.57598 -273.396179)
			(xy 124.553109 -273.439756) (xy 124.523544 -273.4791) (xy 124.488051 -273.513192) (xy 124.447548 -273.541148)
			(xy 124.403086 -273.562246) (xy 124.355815 -273.575938) (xy 124.30696 -273.58187) (xy 124.257785 -273.579889)
			(xy 124.209566 -273.570045) (xy 124.16355 -273.552593) (xy 124.120929 -273.527986) (xy 124.082808 -273.496861)
			(xy 124.050173 -273.460024) (xy 124.02387 -273.418428) (xy 124.004579 -273.373152) (xy 123.992802 -273.325368)
			(xy 123.988842 -273.276314) (xy 123.660154 -273.276314) (xy 123.659659 -273.300921) (xy 123.651764 -273.349498)
			(xy 123.63618 -273.396179) (xy 123.613309 -273.439756) (xy 123.583744 -273.4791) (xy 123.548251 -273.513192)
			(xy 123.507748 -273.541148) (xy 123.463286 -273.562246) (xy 123.416015 -273.575938) (xy 123.36716 -273.58187)
			(xy 123.317985 -273.579889) (xy 123.269766 -273.570045) (xy 123.22375 -273.552593) (xy 123.181129 -273.527986)
			(xy 123.143008 -273.496861) (xy 123.110373 -273.460024) (xy 123.08407 -273.418428) (xy 123.064779 -273.373152)
			(xy 123.053002 -273.325368) (xy 123.049042 -273.276314) (xy 122.7201 -273.276314) (xy 122.719605 -273.300921)
			(xy 122.71171 -273.349498) (xy 122.696126 -273.396179) (xy 122.673255 -273.439756) (xy 122.64369 -273.4791)
			(xy 122.608197 -273.513192) (xy 122.567694 -273.541148) (xy 122.523232 -273.562246) (xy 122.475961 -273.575938)
			(xy 122.427106 -273.58187) (xy 122.377931 -273.579889) (xy 122.329712 -273.570045) (xy 122.283696 -273.552593)
			(xy 122.241075 -273.527986) (xy 122.202954 -273.496861) (xy 122.170319 -273.460024) (xy 122.144016 -273.418428)
			(xy 122.124725 -273.373152) (xy 122.112948 -273.325368) (xy 122.108988 -273.276314) (xy 121.780046 -273.276314)
			(xy 121.779551 -273.300921) (xy 121.771656 -273.349498) (xy 121.756072 -273.396179) (xy 121.733201 -273.439756)
			(xy 121.703636 -273.4791) (xy 121.668143 -273.513192) (xy 121.62764 -273.541148) (xy 121.583178 -273.562246)
			(xy 121.535907 -273.575938) (xy 121.487052 -273.58187) (xy 121.437877 -273.579889) (xy 121.389658 -273.570045)
			(xy 121.343642 -273.552593) (xy 121.301021 -273.527986) (xy 121.2629 -273.496861) (xy 121.230265 -273.460024)
			(xy 121.203962 -273.418428) (xy 121.184671 -273.373152) (xy 121.172894 -273.325368) (xy 121.168934 -273.276314)
			(xy 120.839992 -273.276314) (xy 120.839497 -273.300921) (xy 120.831602 -273.349498) (xy 120.816018 -273.396179)
			(xy 120.793147 -273.439756) (xy 120.763582 -273.4791) (xy 120.728089 -273.513192) (xy 120.687586 -273.541148)
			(xy 120.643124 -273.562246) (xy 120.595853 -273.575938) (xy 120.546998 -273.58187) (xy 120.497823 -273.579889)
			(xy 120.449604 -273.570045) (xy 120.403588 -273.552593) (xy 120.360967 -273.527986) (xy 120.322846 -273.496861)
			(xy 120.290211 -273.460024) (xy 120.263908 -273.418428) (xy 120.244617 -273.373152) (xy 120.23284 -273.325368)
			(xy 120.22888 -273.276314) (xy 119.899938 -273.276314) (xy 119.899443 -273.300921) (xy 119.891548 -273.349498)
			(xy 119.875964 -273.396179) (xy 119.853093 -273.439756) (xy 119.823528 -273.4791) (xy 119.788035 -273.513192)
			(xy 119.747532 -273.541148) (xy 119.70307 -273.562246) (xy 119.655799 -273.575938) (xy 119.606944 -273.58187)
			(xy 119.557769 -273.579889) (xy 119.50955 -273.570045) (xy 119.463534 -273.552593) (xy 119.420913 -273.527986)
			(xy 119.382792 -273.496861) (xy 119.350157 -273.460024) (xy 119.323854 -273.418428) (xy 119.304563 -273.373152)
			(xy 119.292786 -273.325368) (xy 119.288826 -273.276314) (xy 118.960138 -273.276314) (xy 118.959643 -273.300921)
			(xy 118.951748 -273.349498) (xy 118.936164 -273.396179) (xy 118.913293 -273.439756) (xy 118.883728 -273.4791)
			(xy 118.848235 -273.513192) (xy 118.807732 -273.541148) (xy 118.76327 -273.562246) (xy 118.715999 -273.575938)
			(xy 118.667144 -273.58187) (xy 118.617969 -273.579889) (xy 118.56975 -273.570045) (xy 118.523734 -273.552593)
			(xy 118.481113 -273.527986) (xy 118.442992 -273.496861) (xy 118.410357 -273.460024) (xy 118.384054 -273.418428)
			(xy 118.364763 -273.373152) (xy 118.352986 -273.325368) (xy 118.349026 -273.276314) (xy 118.020084 -273.276314)
			(xy 118.019589 -273.300921) (xy 118.011694 -273.349498) (xy 117.99611 -273.396179) (xy 117.973239 -273.439756)
			(xy 117.943674 -273.4791) (xy 117.908181 -273.513192) (xy 117.867678 -273.541148) (xy 117.823216 -273.562246)
			(xy 117.775945 -273.575938) (xy 117.72709 -273.58187) (xy 117.677915 -273.579889) (xy 117.629696 -273.570045)
			(xy 117.58368 -273.552593) (xy 117.541059 -273.527986) (xy 117.502938 -273.496861) (xy 117.470303 -273.460024)
			(xy 117.444 -273.418428) (xy 117.424709 -273.373152) (xy 117.412932 -273.325368) (xy 117.408972 -273.276314)
			(xy 117.08003 -273.276314) (xy 117.079535 -273.300921) (xy 117.07164 -273.349498) (xy 117.056056 -273.396179)
			(xy 117.033185 -273.439756) (xy 117.00362 -273.4791) (xy 116.968127 -273.513192) (xy 116.927624 -273.541148)
			(xy 116.883162 -273.562246) (xy 116.835891 -273.575938) (xy 116.787036 -273.58187) (xy 116.737861 -273.579889)
			(xy 116.689642 -273.570045) (xy 116.643626 -273.552593) (xy 116.601005 -273.527986) (xy 116.562884 -273.496861)
			(xy 116.530249 -273.460024) (xy 116.503946 -273.418428) (xy 116.484655 -273.373152) (xy 116.472878 -273.325368)
			(xy 116.468918 -273.276314) (xy 116.139976 -273.276314) (xy 116.139481 -273.300921) (xy 116.131586 -273.349498)
			(xy 116.116002 -273.396179) (xy 116.093131 -273.439756) (xy 116.063566 -273.4791) (xy 116.028073 -273.513192)
			(xy 115.98757 -273.541148) (xy 115.943108 -273.562246) (xy 115.895837 -273.575938) (xy 115.846982 -273.58187)
			(xy 115.797807 -273.579889) (xy 115.749588 -273.570045) (xy 115.703572 -273.552593) (xy 115.660951 -273.527986)
			(xy 115.62283 -273.496861) (xy 115.590195 -273.460024) (xy 115.563892 -273.418428) (xy 115.544601 -273.373152)
			(xy 115.532824 -273.325368) (xy 115.528864 -273.276314) (xy 115.199922 -273.276314) (xy 115.199427 -273.300921)
			(xy 115.191532 -273.349498) (xy 115.175948 -273.396179) (xy 115.153077 -273.439756) (xy 115.123512 -273.4791)
			(xy 115.088019 -273.513192) (xy 115.047516 -273.541148) (xy 115.003054 -273.562246) (xy 114.955783 -273.575938)
			(xy 114.906928 -273.58187) (xy 114.857753 -273.579889) (xy 114.809534 -273.570045) (xy 114.763518 -273.552593)
			(xy 114.720897 -273.527986) (xy 114.682776 -273.496861) (xy 114.650141 -273.460024) (xy 114.623838 -273.418428)
			(xy 114.604547 -273.373152) (xy 114.59277 -273.325368) (xy 114.58881 -273.276314) (xy 114.260122 -273.276314)
			(xy 114.259627 -273.300921) (xy 114.251732 -273.349498) (xy 114.236148 -273.396179) (xy 114.213277 -273.439756)
			(xy 114.183712 -273.4791) (xy 114.148219 -273.513192) (xy 114.107716 -273.541148) (xy 114.063254 -273.562246)
			(xy 114.015983 -273.575938) (xy 113.967128 -273.58187) (xy 113.917953 -273.579889) (xy 113.869734 -273.570045)
			(xy 113.823718 -273.552593) (xy 113.781097 -273.527986) (xy 113.742976 -273.496861) (xy 113.710341 -273.460024)
			(xy 113.684038 -273.418428) (xy 113.664747 -273.373152) (xy 113.65297 -273.325368) (xy 113.64901 -273.276314)
			(xy 110.506256 -273.276314) (xy 110.505761 -273.300921) (xy 110.497866 -273.349498) (xy 110.482282 -273.396179)
			(xy 110.459411 -273.439756) (xy 110.429846 -273.4791) (xy 110.394353 -273.513192) (xy 110.35385 -273.541148)
			(xy 110.309388 -273.562246) (xy 110.262117 -273.575938) (xy 110.213262 -273.58187) (xy 110.164087 -273.579889)
			(xy 110.115868 -273.570045) (xy 110.069852 -273.552593) (xy 110.027231 -273.527986) (xy 109.98911 -273.496861)
			(xy 109.956475 -273.460024) (xy 109.930172 -273.418428) (xy 109.910881 -273.373152) (xy 109.899104 -273.325368)
			(xy 109.895144 -273.276314) (xy 109.566456 -273.276314) (xy 109.565961 -273.300921) (xy 109.558066 -273.349498)
			(xy 109.542482 -273.396179) (xy 109.519611 -273.439756) (xy 109.490046 -273.4791) (xy 109.454553 -273.513192)
			(xy 109.41405 -273.541148) (xy 109.369588 -273.562246) (xy 109.322317 -273.575938) (xy 109.273462 -273.58187)
			(xy 109.224287 -273.579889) (xy 109.176068 -273.570045) (xy 109.130052 -273.552593) (xy 109.087431 -273.527986)
			(xy 109.04931 -273.496861) (xy 109.016675 -273.460024) (xy 108.990372 -273.418428) (xy 108.971081 -273.373152)
			(xy 108.959304 -273.325368) (xy 108.955344 -273.276314) (xy 108.626402 -273.276314) (xy 108.625907 -273.300921)
			(xy 108.618012 -273.349498) (xy 108.602428 -273.396179) (xy 108.579557 -273.439756) (xy 108.549992 -273.4791)
			(xy 108.514499 -273.513192) (xy 108.473996 -273.541148) (xy 108.429534 -273.562246) (xy 108.382263 -273.575938)
			(xy 108.333408 -273.58187) (xy 108.284233 -273.579889) (xy 108.236014 -273.570045) (xy 108.189998 -273.552593)
			(xy 108.147377 -273.527986) (xy 108.109256 -273.496861) (xy 108.076621 -273.460024) (xy 108.050318 -273.418428)
			(xy 108.031027 -273.373152) (xy 108.01925 -273.325368) (xy 108.01529 -273.276314) (xy 107.686348 -273.276314)
			(xy 107.685853 -273.300921) (xy 107.677958 -273.349498) (xy 107.662374 -273.396179) (xy 107.639503 -273.439756)
			(xy 107.609938 -273.4791) (xy 107.574445 -273.513192) (xy 107.533942 -273.541148) (xy 107.48948 -273.562246)
			(xy 107.442209 -273.575938) (xy 107.393354 -273.58187) (xy 107.344179 -273.579889) (xy 107.29596 -273.570045)
			(xy 107.249944 -273.552593) (xy 107.207323 -273.527986) (xy 107.169202 -273.496861) (xy 107.136567 -273.460024)
			(xy 107.110264 -273.418428) (xy 107.090973 -273.373152) (xy 107.079196 -273.325368) (xy 107.075236 -273.276314)
			(xy 106.746294 -273.276314) (xy 106.745799 -273.300921) (xy 106.737904 -273.349498) (xy 106.72232 -273.396179)
			(xy 106.699449 -273.439756) (xy 106.669884 -273.4791) (xy 106.634391 -273.513192) (xy 106.593888 -273.541148)
			(xy 106.549426 -273.562246) (xy 106.502155 -273.575938) (xy 106.4533 -273.58187) (xy 106.404125 -273.579889)
			(xy 106.355906 -273.570045) (xy 106.30989 -273.552593) (xy 106.267269 -273.527986) (xy 106.229148 -273.496861)
			(xy 106.196513 -273.460024) (xy 106.17021 -273.418428) (xy 106.150919 -273.373152) (xy 106.139142 -273.325368)
			(xy 106.135182 -273.276314) (xy 105.80624 -273.276314) (xy 105.805745 -273.300921) (xy 105.79785 -273.349498)
			(xy 105.782266 -273.396179) (xy 105.759395 -273.439756) (xy 105.72983 -273.4791) (xy 105.694337 -273.513192)
			(xy 105.653834 -273.541148) (xy 105.609372 -273.562246) (xy 105.562101 -273.575938) (xy 105.513246 -273.58187)
			(xy 105.464071 -273.579889) (xy 105.415852 -273.570045) (xy 105.369836 -273.552593) (xy 105.327215 -273.527986)
			(xy 105.289094 -273.496861) (xy 105.256459 -273.460024) (xy 105.230156 -273.418428) (xy 105.210865 -273.373152)
			(xy 105.199088 -273.325368) (xy 105.195128 -273.276314) (xy 104.86644 -273.276314) (xy 104.865945 -273.300921)
			(xy 104.85805 -273.349498) (xy 104.842466 -273.396179) (xy 104.819595 -273.439756) (xy 104.79003 -273.4791)
			(xy 104.754537 -273.513192) (xy 104.714034 -273.541148) (xy 104.669572 -273.562246) (xy 104.622301 -273.575938)
			(xy 104.573446 -273.58187) (xy 104.524271 -273.579889) (xy 104.476052 -273.570045) (xy 104.430036 -273.552593)
			(xy 104.387415 -273.527986) (xy 104.349294 -273.496861) (xy 104.316659 -273.460024) (xy 104.290356 -273.418428)
			(xy 104.271065 -273.373152) (xy 104.259288 -273.325368) (xy 104.255328 -273.276314) (xy 103.926386 -273.276314)
			(xy 103.925891 -273.300921) (xy 103.917996 -273.349498) (xy 103.902412 -273.396179) (xy 103.879541 -273.439756)
			(xy 103.849976 -273.4791) (xy 103.814483 -273.513192) (xy 103.77398 -273.541148) (xy 103.729518 -273.562246)
			(xy 103.682247 -273.575938) (xy 103.633392 -273.58187) (xy 103.584217 -273.579889) (xy 103.535998 -273.570045)
			(xy 103.489982 -273.552593) (xy 103.447361 -273.527986) (xy 103.40924 -273.496861) (xy 103.376605 -273.460024)
			(xy 103.350302 -273.418428) (xy 103.331011 -273.373152) (xy 103.319234 -273.325368) (xy 103.315274 -273.276314)
			(xy 102.986332 -273.276314) (xy 102.985837 -273.300921) (xy 102.977942 -273.349498) (xy 102.962358 -273.396179)
			(xy 102.939487 -273.439756) (xy 102.909922 -273.4791) (xy 102.874429 -273.513192) (xy 102.833926 -273.541148)
			(xy 102.789464 -273.562246) (xy 102.742193 -273.575938) (xy 102.693338 -273.58187) (xy 102.644163 -273.579889)
			(xy 102.595944 -273.570045) (xy 102.549928 -273.552593) (xy 102.507307 -273.527986) (xy 102.469186 -273.496861)
			(xy 102.436551 -273.460024) (xy 102.410248 -273.418428) (xy 102.390957 -273.373152) (xy 102.37918 -273.325368)
			(xy 102.37522 -273.276314) (xy 102.046278 -273.276314) (xy 102.045783 -273.300921) (xy 102.037888 -273.349498)
			(xy 102.022304 -273.396179) (xy 101.999433 -273.439756) (xy 101.969868 -273.4791) (xy 101.934375 -273.513192)
			(xy 101.893872 -273.541148) (xy 101.84941 -273.562246) (xy 101.802139 -273.575938) (xy 101.753284 -273.58187)
			(xy 101.704109 -273.579889) (xy 101.65589 -273.570045) (xy 101.609874 -273.552593) (xy 101.567253 -273.527986)
			(xy 101.529132 -273.496861) (xy 101.496497 -273.460024) (xy 101.470194 -273.418428) (xy 101.450903 -273.373152)
			(xy 101.439126 -273.325368) (xy 101.435166 -273.276314) (xy 101.106478 -273.276314) (xy 101.105983 -273.300921)
			(xy 101.098088 -273.349498) (xy 101.082504 -273.396179) (xy 101.059633 -273.439756) (xy 101.030068 -273.4791)
			(xy 100.994575 -273.513192) (xy 100.954072 -273.541148) (xy 100.90961 -273.562246) (xy 100.862339 -273.575938)
			(xy 100.813484 -273.58187) (xy 100.764309 -273.579889) (xy 100.71609 -273.570045) (xy 100.670074 -273.552593)
			(xy 100.627453 -273.527986) (xy 100.589332 -273.496861) (xy 100.556697 -273.460024) (xy 100.530394 -273.418428)
			(xy 100.511103 -273.373152) (xy 100.499326 -273.325368) (xy 100.495366 -273.276314) (xy 100.166424 -273.276314)
			(xy 100.165929 -273.300921) (xy 100.158034 -273.349498) (xy 100.14245 -273.396179) (xy 100.119579 -273.439756)
			(xy 100.090014 -273.4791) (xy 100.054521 -273.513192) (xy 100.014018 -273.541148) (xy 99.969556 -273.562246)
			(xy 99.922285 -273.575938) (xy 99.87343 -273.58187) (xy 99.824255 -273.579889) (xy 99.776036 -273.570045)
			(xy 99.73002 -273.552593) (xy 99.687399 -273.527986) (xy 99.649278 -273.496861) (xy 99.616643 -273.460024)
			(xy 99.59034 -273.418428) (xy 99.571049 -273.373152) (xy 99.559272 -273.325368) (xy 99.555312 -273.276314)
			(xy 99.22637 -273.276314) (xy 99.225875 -273.300921) (xy 99.21798 -273.349498) (xy 99.202396 -273.396179)
			(xy 99.179525 -273.439756) (xy 99.14996 -273.4791) (xy 99.114467 -273.513192) (xy 99.073964 -273.541148)
			(xy 99.029502 -273.562246) (xy 98.982231 -273.575938) (xy 98.933376 -273.58187) (xy 98.884201 -273.579889)
			(xy 98.835982 -273.570045) (xy 98.789966 -273.552593) (xy 98.747345 -273.527986) (xy 98.709224 -273.496861)
			(xy 98.676589 -273.460024) (xy 98.650286 -273.418428) (xy 98.630995 -273.373152) (xy 98.619218 -273.325368)
			(xy 98.615258 -273.276314) (xy 98.286316 -273.276314) (xy 98.285821 -273.300921) (xy 98.277926 -273.349498)
			(xy 98.262342 -273.396179) (xy 98.239471 -273.439756) (xy 98.209906 -273.4791) (xy 98.174413 -273.513192)
			(xy 98.13391 -273.541148) (xy 98.089448 -273.562246) (xy 98.042177 -273.575938) (xy 97.993322 -273.58187)
			(xy 97.944147 -273.579889) (xy 97.895928 -273.570045) (xy 97.849912 -273.552593) (xy 97.807291 -273.527986)
			(xy 97.76917 -273.496861) (xy 97.736535 -273.460024) (xy 97.710232 -273.418428) (xy 97.690941 -273.373152)
			(xy 97.679164 -273.325368) (xy 97.675204 -273.276314) (xy 97.346262 -273.276314) (xy 97.345796 -273.300553)
			(xy 97.338137 -273.348423) (xy 97.323012 -273.394483) (xy 97.300803 -273.437575) (xy 97.272065 -273.476618)
			(xy 97.237522 -273.510632) (xy 97.198039 -273.538763) (xy 97.154609 -273.560304) (xy 97.108322 -273.574715)
			(xy 97.084388 -273.578574) (xy 97.071942 -273.580352) (xy 97.040954 -273.581876) (xy 97.017458 -273.581443)
			(xy 96.97102 -273.574249) (xy 96.926229 -273.560037) (xy 96.884138 -273.539142) (xy 96.845738 -273.512056)
			(xy 96.811932 -273.479415) (xy 96.797368 -273.460972) (xy 96.795336 -273.458178) (xy 96.795082 -273.457924)
			(xy 96.790942 -273.452555) (xy 96.780383 -273.444058) (xy 96.774254 -273.44116) (xy 96.768412 -273.438874)
			(xy 96.755204 -273.437096) (xy 96.661986 -273.449288) (xy 96.65531 -273.450335) (xy 96.642822 -273.455485)
			(xy 96.637348 -273.459448) (xy 96.63176 -273.463766) (xy 96.62414 -273.47418) (xy 96.621346 -273.481292)
			(xy 96.613467 -273.500863) (xy 96.595159 -273.538876) (xy 96.58477 -273.557238) (xy 96.539812 -273.634708)
			(xy 96.534202 -273.645777) (xy 96.53339 -273.670551) (xy 96.538288 -273.681952) (xy 96.552766 -273.711416)
			(xy 96.576388 -273.758914) (xy 96.57715 -273.760184) (xy 96.579844 -273.76443) (xy 96.586625 -273.771853)
			(xy 96.590612 -273.774916) (xy 96.600518 -273.782028) (xy 96.613218 -273.783806) (xy 96.637225 -273.787652)
			(xy 96.683692 -273.801951) (xy 96.727309 -273.823424) (xy 96.766978 -273.851531) (xy 96.801697 -273.885563)
			(xy 96.830592 -273.924661) (xy 96.852933 -273.967841) (xy 96.868158 -274.014012) (xy 96.875882 -274.062012)
			(xy 96.876362 -274.08632) (xy 97.205304 -274.08632) (xy 97.209264 -274.037266) (xy 97.221041 -273.989482)
			(xy 97.240332 -273.944206) (xy 97.266635 -273.90261) (xy 97.29927 -273.865773) (xy 97.337391 -273.834648)
			(xy 97.380012 -273.810041) (xy 97.426028 -273.792589) (xy 97.474247 -273.782745) (xy 97.523422 -273.780764)
			(xy 97.572277 -273.786696) (xy 97.619548 -273.800388) (xy 97.66401 -273.821486) (xy 97.704513 -273.849442)
			(xy 97.740006 -273.883534) (xy 97.769571 -273.922878) (xy 97.792442 -273.966455) (xy 97.808026 -274.013136)
			(xy 97.815921 -274.061713) (xy 97.816416 -274.08632) (xy 98.145358 -274.08632) (xy 98.149318 -274.037266)
			(xy 98.161095 -273.989482) (xy 98.180386 -273.944206) (xy 98.206689 -273.90261) (xy 98.239324 -273.865773)
			(xy 98.277445 -273.834648) (xy 98.320066 -273.810041) (xy 98.366082 -273.792589) (xy 98.414301 -273.782745)
			(xy 98.463476 -273.780764) (xy 98.512331 -273.786696) (xy 98.559602 -273.800388) (xy 98.604064 -273.821486)
			(xy 98.644567 -273.849442) (xy 98.68006 -273.883534) (xy 98.709625 -273.922878) (xy 98.732496 -273.966455)
			(xy 98.74808 -274.013136) (xy 98.755975 -274.061713) (xy 98.75647 -274.08632) (xy 99.085158 -274.08632)
			(xy 99.089118 -274.037266) (xy 99.100895 -273.989482) (xy 99.120186 -273.944206) (xy 99.146489 -273.90261)
			(xy 99.179124 -273.865773) (xy 99.217245 -273.834648) (xy 99.259866 -273.810041) (xy 99.305882 -273.792589)
			(xy 99.354101 -273.782745) (xy 99.403276 -273.780764) (xy 99.452131 -273.786696) (xy 99.499402 -273.800388)
			(xy 99.543864 -273.821486) (xy 99.584367 -273.849442) (xy 99.61986 -273.883534) (xy 99.649425 -273.922878)
			(xy 99.672296 -273.966455) (xy 99.68788 -274.013136) (xy 99.695775 -274.061713) (xy 99.69627 -274.08632)
			(xy 100.025212 -274.08632) (xy 100.029172 -274.037266) (xy 100.040949 -273.989482) (xy 100.06024 -273.944206)
			(xy 100.086543 -273.90261) (xy 100.119178 -273.865773) (xy 100.157299 -273.834648) (xy 100.19992 -273.810041)
			(xy 100.245936 -273.792589) (xy 100.294155 -273.782745) (xy 100.34333 -273.780764) (xy 100.392185 -273.786696)
			(xy 100.439456 -273.800388) (xy 100.483918 -273.821486) (xy 100.524421 -273.849442) (xy 100.559914 -273.883534)
			(xy 100.589479 -273.922878) (xy 100.61235 -273.966455) (xy 100.627934 -274.013136) (xy 100.635829 -274.061713)
			(xy 100.636324 -274.08632) (xy 100.965266 -274.08632) (xy 100.969226 -274.037266) (xy 100.981003 -273.989482)
			(xy 101.000294 -273.944206) (xy 101.026597 -273.90261) (xy 101.059232 -273.865773) (xy 101.097353 -273.834648)
			(xy 101.139974 -273.810041) (xy 101.18599 -273.792589) (xy 101.234209 -273.782745) (xy 101.283384 -273.780764)
			(xy 101.332239 -273.786696) (xy 101.37951 -273.800388) (xy 101.423972 -273.821486) (xy 101.464475 -273.849442)
			(xy 101.499968 -273.883534) (xy 101.529533 -273.922878) (xy 101.552404 -273.966455) (xy 101.567988 -274.013136)
			(xy 101.575883 -274.061713) (xy 101.576378 -274.08632) (xy 101.90532 -274.08632) (xy 101.90928 -274.037266)
			(xy 101.921057 -273.989482) (xy 101.940348 -273.944206) (xy 101.966651 -273.90261) (xy 101.999286 -273.865773)
			(xy 102.037407 -273.834648) (xy 102.080028 -273.810041) (xy 102.126044 -273.792589) (xy 102.174263 -273.782745)
			(xy 102.223438 -273.780764) (xy 102.272293 -273.786696) (xy 102.319564 -273.800388) (xy 102.364026 -273.821486)
			(xy 102.404529 -273.849442) (xy 102.440022 -273.883534) (xy 102.469587 -273.922878) (xy 102.492458 -273.966455)
			(xy 102.508042 -274.013136) (xy 102.515937 -274.061713) (xy 102.516432 -274.08632) (xy 102.845374 -274.08632)
			(xy 102.849334 -274.037266) (xy 102.861111 -273.989482) (xy 102.880402 -273.944206) (xy 102.906705 -273.90261)
			(xy 102.93934 -273.865773) (xy 102.977461 -273.834648) (xy 103.020082 -273.810041) (xy 103.066098 -273.792589)
			(xy 103.114317 -273.782745) (xy 103.163492 -273.780764) (xy 103.212347 -273.786696) (xy 103.259618 -273.800388)
			(xy 103.30408 -273.821486) (xy 103.344583 -273.849442) (xy 103.380076 -273.883534) (xy 103.409641 -273.922878)
			(xy 103.432512 -273.966455) (xy 103.448096 -274.013136) (xy 103.455991 -274.061713) (xy 103.456486 -274.08632)
			(xy 103.785174 -274.08632) (xy 103.789134 -274.037266) (xy 103.800911 -273.989482) (xy 103.820202 -273.944206)
			(xy 103.846505 -273.90261) (xy 103.87914 -273.865773) (xy 103.917261 -273.834648) (xy 103.959882 -273.810041)
			(xy 104.005898 -273.792589) (xy 104.054117 -273.782745) (xy 104.103292 -273.780764) (xy 104.152147 -273.786696)
			(xy 104.199418 -273.800388) (xy 104.24388 -273.821486) (xy 104.284383 -273.849442) (xy 104.319876 -273.883534)
			(xy 104.349441 -273.922878) (xy 104.372312 -273.966455) (xy 104.387896 -274.013136) (xy 104.395791 -274.061713)
			(xy 104.396286 -274.08632) (xy 104.725228 -274.08632) (xy 104.729188 -274.037266) (xy 104.740965 -273.989482)
			(xy 104.760256 -273.944206) (xy 104.786559 -273.90261) (xy 104.819194 -273.865773) (xy 104.857315 -273.834648)
			(xy 104.899936 -273.810041) (xy 104.945952 -273.792589) (xy 104.994171 -273.782745) (xy 105.043346 -273.780764)
			(xy 105.092201 -273.786696) (xy 105.139472 -273.800388) (xy 105.183934 -273.821486) (xy 105.224437 -273.849442)
			(xy 105.25993 -273.883534) (xy 105.289495 -273.922878) (xy 105.312366 -273.966455) (xy 105.32795 -274.013136)
			(xy 105.335845 -274.061713) (xy 105.33634 -274.08632) (xy 105.665282 -274.08632) (xy 105.669242 -274.037266)
			(xy 105.681019 -273.989482) (xy 105.70031 -273.944206) (xy 105.726613 -273.90261) (xy 105.759248 -273.865773)
			(xy 105.797369 -273.834648) (xy 105.83999 -273.810041) (xy 105.886006 -273.792589) (xy 105.934225 -273.782745)
			(xy 105.9834 -273.780764) (xy 106.032255 -273.786696) (xy 106.079526 -273.800388) (xy 106.123988 -273.821486)
			(xy 106.164491 -273.849442) (xy 106.199984 -273.883534) (xy 106.229549 -273.922878) (xy 106.25242 -273.966455)
			(xy 106.268004 -274.013136) (xy 106.275899 -274.061713) (xy 106.276394 -274.08632) (xy 106.605336 -274.08632)
			(xy 106.609296 -274.037266) (xy 106.621073 -273.989482) (xy 106.640364 -273.944206) (xy 106.666667 -273.90261)
			(xy 106.699302 -273.865773) (xy 106.737423 -273.834648) (xy 106.780044 -273.810041) (xy 106.82606 -273.792589)
			(xy 106.874279 -273.782745) (xy 106.923454 -273.780764) (xy 106.972309 -273.786696) (xy 107.01958 -273.800388)
			(xy 107.064042 -273.821486) (xy 107.104545 -273.849442) (xy 107.140038 -273.883534) (xy 107.169603 -273.922878)
			(xy 107.192474 -273.966455) (xy 107.208058 -274.013136) (xy 107.215953 -274.061713) (xy 107.216448 -274.08632)
			(xy 107.545136 -274.08632) (xy 107.549096 -274.037266) (xy 107.560873 -273.989482) (xy 107.580164 -273.944206)
			(xy 107.606467 -273.90261) (xy 107.639102 -273.865773) (xy 107.677223 -273.834648) (xy 107.719844 -273.810041)
			(xy 107.76586 -273.792589) (xy 107.814079 -273.782745) (xy 107.863254 -273.780764) (xy 107.912109 -273.786696)
			(xy 107.95938 -273.800388) (xy 108.003842 -273.821486) (xy 108.044345 -273.849442) (xy 108.079838 -273.883534)
			(xy 108.109403 -273.922878) (xy 108.132274 -273.966455) (xy 108.147858 -274.013136) (xy 108.155753 -274.061713)
			(xy 108.156248 -274.08632) (xy 108.48519 -274.08632) (xy 108.48915 -274.037266) (xy 108.500927 -273.989482)
			(xy 108.520218 -273.944206) (xy 108.546521 -273.90261) (xy 108.579156 -273.865773) (xy 108.617277 -273.834648)
			(xy 108.659898 -273.810041) (xy 108.705914 -273.792589) (xy 108.754133 -273.782745) (xy 108.803308 -273.780764)
			(xy 108.852163 -273.786696) (xy 108.899434 -273.800388) (xy 108.943896 -273.821486) (xy 108.984399 -273.849442)
			(xy 109.019892 -273.883534) (xy 109.049457 -273.922878) (xy 109.072328 -273.966455) (xy 109.087912 -274.013136)
			(xy 109.095807 -274.061713) (xy 109.096302 -274.08632) (xy 109.425244 -274.08632) (xy 109.429204 -274.037266)
			(xy 109.440981 -273.989482) (xy 109.460272 -273.944206) (xy 109.486575 -273.90261) (xy 109.51921 -273.865773)
			(xy 109.557331 -273.834648) (xy 109.599952 -273.810041) (xy 109.645968 -273.792589) (xy 109.694187 -273.782745)
			(xy 109.743362 -273.780764) (xy 109.792217 -273.786696) (xy 109.839488 -273.800388) (xy 109.88395 -273.821486)
			(xy 109.924453 -273.849442) (xy 109.959946 -273.883534) (xy 109.989511 -273.922878) (xy 110.012382 -273.966455)
			(xy 110.027966 -274.013136) (xy 110.035861 -274.061713) (xy 110.036356 -274.08632) (xy 110.365298 -274.08632)
			(xy 110.369258 -274.037266) (xy 110.381035 -273.989482) (xy 110.400326 -273.944206) (xy 110.426629 -273.90261)
			(xy 110.459264 -273.865773) (xy 110.497385 -273.834648) (xy 110.540006 -273.810041) (xy 110.586022 -273.792589)
			(xy 110.634241 -273.782745) (xy 110.683416 -273.780764) (xy 110.732271 -273.786696) (xy 110.779542 -273.800388)
			(xy 110.824004 -273.821486) (xy 110.864507 -273.849442) (xy 110.9 -273.883534) (xy 110.929565 -273.922878)
			(xy 110.952436 -273.966455) (xy 110.96802 -274.013136) (xy 110.975915 -274.061713) (xy 110.97641 -274.08632)
			(xy 113.178856 -274.08632) (xy 113.182816 -274.037266) (xy 113.194593 -273.989482) (xy 113.213884 -273.944206)
			(xy 113.240187 -273.90261) (xy 113.272822 -273.865773) (xy 113.310943 -273.834648) (xy 113.353564 -273.810041)
			(xy 113.39958 -273.792589) (xy 113.447799 -273.782745) (xy 113.496974 -273.780764) (xy 113.545829 -273.786696)
			(xy 113.5931 -273.800388) (xy 113.637562 -273.821486) (xy 113.678065 -273.849442) (xy 113.713558 -273.883534)
			(xy 113.743123 -273.922878) (xy 113.765994 -273.966455) (xy 113.781578 -274.013136) (xy 113.789473 -274.061713)
			(xy 113.789968 -274.08632) (xy 114.11891 -274.08632) (xy 114.12287 -274.037266) (xy 114.134647 -273.989482)
			(xy 114.153938 -273.944206) (xy 114.180241 -273.90261) (xy 114.212876 -273.865773) (xy 114.250997 -273.834648)
			(xy 114.293618 -273.810041) (xy 114.339634 -273.792589) (xy 114.387853 -273.782745) (xy 114.437028 -273.780764)
			(xy 114.485883 -273.786696) (xy 114.533154 -273.800388) (xy 114.577616 -273.821486) (xy 114.618119 -273.849442)
			(xy 114.653612 -273.883534) (xy 114.683177 -273.922878) (xy 114.706048 -273.966455) (xy 114.721632 -274.013136)
			(xy 114.729527 -274.061713) (xy 114.730022 -274.08632) (xy 115.058964 -274.08632) (xy 115.062924 -274.037266)
			(xy 115.074701 -273.989482) (xy 115.093992 -273.944206) (xy 115.120295 -273.90261) (xy 115.15293 -273.865773)
			(xy 115.191051 -273.834648) (xy 115.233672 -273.810041) (xy 115.279688 -273.792589) (xy 115.327907 -273.782745)
			(xy 115.377082 -273.780764) (xy 115.425937 -273.786696) (xy 115.473208 -273.800388) (xy 115.51767 -273.821486)
			(xy 115.558173 -273.849442) (xy 115.593666 -273.883534) (xy 115.623231 -273.922878) (xy 115.646102 -273.966455)
			(xy 115.661686 -274.013136) (xy 115.669581 -274.061713) (xy 115.670076 -274.08632) (xy 115.999018 -274.08632)
			(xy 116.002978 -274.037266) (xy 116.014755 -273.989482) (xy 116.034046 -273.944206) (xy 116.060349 -273.90261)
			(xy 116.092984 -273.865773) (xy 116.131105 -273.834648) (xy 116.173726 -273.810041) (xy 116.219742 -273.792589)
			(xy 116.267961 -273.782745) (xy 116.317136 -273.780764) (xy 116.365991 -273.786696) (xy 116.413262 -273.800388)
			(xy 116.457724 -273.821486) (xy 116.498227 -273.849442) (xy 116.53372 -273.883534) (xy 116.563285 -273.922878)
			(xy 116.586156 -273.966455) (xy 116.60174 -274.013136) (xy 116.609635 -274.061713) (xy 116.61013 -274.08632)
			(xy 116.938818 -274.08632) (xy 116.942778 -274.037266) (xy 116.954555 -273.989482) (xy 116.973846 -273.944206)
			(xy 117.000149 -273.90261) (xy 117.032784 -273.865773) (xy 117.070905 -273.834648) (xy 117.113526 -273.810041)
			(xy 117.159542 -273.792589) (xy 117.207761 -273.782745) (xy 117.256936 -273.780764) (xy 117.305791 -273.786696)
			(xy 117.353062 -273.800388) (xy 117.397524 -273.821486) (xy 117.438027 -273.849442) (xy 117.47352 -273.883534)
			(xy 117.503085 -273.922878) (xy 117.525956 -273.966455) (xy 117.54154 -274.013136) (xy 117.549435 -274.061713)
			(xy 117.54993 -274.08632) (xy 117.878872 -274.08632) (xy 117.882832 -274.037266) (xy 117.894609 -273.989482)
			(xy 117.9139 -273.944206) (xy 117.940203 -273.90261) (xy 117.972838 -273.865773) (xy 118.010959 -273.834648)
			(xy 118.05358 -273.810041) (xy 118.099596 -273.792589) (xy 118.147815 -273.782745) (xy 118.19699 -273.780764)
			(xy 118.245845 -273.786696) (xy 118.293116 -273.800388) (xy 118.337578 -273.821486) (xy 118.378081 -273.849442)
			(xy 118.413574 -273.883534) (xy 118.443139 -273.922878) (xy 118.46601 -273.966455) (xy 118.481594 -274.013136)
			(xy 118.489489 -274.061713) (xy 118.489984 -274.08632) (xy 118.818926 -274.08632) (xy 118.822886 -274.037266)
			(xy 118.834663 -273.989482) (xy 118.853954 -273.944206) (xy 118.880257 -273.90261) (xy 118.912892 -273.865773)
			(xy 118.951013 -273.834648) (xy 118.993634 -273.810041) (xy 119.03965 -273.792589) (xy 119.087869 -273.782745)
			(xy 119.137044 -273.780764) (xy 119.185899 -273.786696) (xy 119.23317 -273.800388) (xy 119.277632 -273.821486)
			(xy 119.318135 -273.849442) (xy 119.353628 -273.883534) (xy 119.383193 -273.922878) (xy 119.406064 -273.966455)
			(xy 119.421648 -274.013136) (xy 119.429543 -274.061713) (xy 119.430038 -274.08632) (xy 119.75898 -274.08632)
			(xy 119.76294 -274.037266) (xy 119.774717 -273.989482) (xy 119.794008 -273.944206) (xy 119.820311 -273.90261)
			(xy 119.852946 -273.865773) (xy 119.891067 -273.834648) (xy 119.933688 -273.810041) (xy 119.979704 -273.792589)
			(xy 120.027923 -273.782745) (xy 120.077098 -273.780764) (xy 120.125953 -273.786696) (xy 120.173224 -273.800388)
			(xy 120.217686 -273.821486) (xy 120.258189 -273.849442) (xy 120.293682 -273.883534) (xy 120.323247 -273.922878)
			(xy 120.346118 -273.966455) (xy 120.361702 -274.013136) (xy 120.369597 -274.061713) (xy 120.370092 -274.08632)
			(xy 120.699034 -274.08632) (xy 120.702994 -274.037266) (xy 120.714771 -273.989482) (xy 120.734062 -273.944206)
			(xy 120.760365 -273.90261) (xy 120.793 -273.865773) (xy 120.831121 -273.834648) (xy 120.873742 -273.810041)
			(xy 120.919758 -273.792589) (xy 120.967977 -273.782745) (xy 121.017152 -273.780764) (xy 121.066007 -273.786696)
			(xy 121.113278 -273.800388) (xy 121.15774 -273.821486) (xy 121.198243 -273.849442) (xy 121.233736 -273.883534)
			(xy 121.263301 -273.922878) (xy 121.286172 -273.966455) (xy 121.301756 -274.013136) (xy 121.309651 -274.061713)
			(xy 121.310146 -274.08632) (xy 121.638834 -274.08632) (xy 121.642794 -274.037266) (xy 121.654571 -273.989482)
			(xy 121.673862 -273.944206) (xy 121.700165 -273.90261) (xy 121.7328 -273.865773) (xy 121.770921 -273.834648)
			(xy 121.813542 -273.810041) (xy 121.859558 -273.792589) (xy 121.907777 -273.782745) (xy 121.956952 -273.780764)
			(xy 122.005807 -273.786696) (xy 122.053078 -273.800388) (xy 122.09754 -273.821486) (xy 122.138043 -273.849442)
			(xy 122.173536 -273.883534) (xy 122.203101 -273.922878) (xy 122.225972 -273.966455) (xy 122.241556 -274.013136)
			(xy 122.249451 -274.061713) (xy 122.249946 -274.08632) (xy 122.578888 -274.08632) (xy 122.582848 -274.037266)
			(xy 122.594625 -273.989482) (xy 122.613916 -273.944206) (xy 122.640219 -273.90261) (xy 122.672854 -273.865773)
			(xy 122.710975 -273.834648) (xy 122.753596 -273.810041) (xy 122.799612 -273.792589) (xy 122.847831 -273.782745)
			(xy 122.897006 -273.780764) (xy 122.945861 -273.786696) (xy 122.993132 -273.800388) (xy 123.037594 -273.821486)
			(xy 123.078097 -273.849442) (xy 123.11359 -273.883534) (xy 123.143155 -273.922878) (xy 123.166026 -273.966455)
			(xy 123.18161 -274.013136) (xy 123.189505 -274.061713) (xy 123.19 -274.08632) (xy 123.518942 -274.08632)
			(xy 123.522902 -274.037266) (xy 123.534679 -273.989482) (xy 123.55397 -273.944206) (xy 123.580273 -273.90261)
			(xy 123.612908 -273.865773) (xy 123.651029 -273.834648) (xy 123.69365 -273.810041) (xy 123.739666 -273.792589)
			(xy 123.787885 -273.782745) (xy 123.83706 -273.780764) (xy 123.885915 -273.786696) (xy 123.933186 -273.800388)
			(xy 123.977648 -273.821486) (xy 124.018151 -273.849442) (xy 124.053644 -273.883534) (xy 124.083209 -273.922878)
			(xy 124.10608 -273.966455) (xy 124.121664 -274.013136) (xy 124.129559 -274.061713) (xy 124.130054 -274.08632)
			(xy 124.458996 -274.08632) (xy 124.462956 -274.037266) (xy 124.474733 -273.989482) (xy 124.494024 -273.944206)
			(xy 124.520327 -273.90261) (xy 124.552962 -273.865773) (xy 124.591083 -273.834648) (xy 124.633704 -273.810041)
			(xy 124.67972 -273.792589) (xy 124.727939 -273.782745) (xy 124.777114 -273.780764) (xy 124.825969 -273.786696)
			(xy 124.87324 -273.800388) (xy 124.917702 -273.821486) (xy 124.958205 -273.849442) (xy 124.993698 -273.883534)
			(xy 125.023263 -273.922878) (xy 125.046134 -273.966455) (xy 125.061718 -274.013136) (xy 125.069613 -274.061713)
			(xy 125.070108 -274.08632) (xy 125.39905 -274.08632) (xy 125.40301 -274.037266) (xy 125.414787 -273.989482)
			(xy 125.434078 -273.944206) (xy 125.460381 -273.90261) (xy 125.493016 -273.865773) (xy 125.531137 -273.834648)
			(xy 125.573758 -273.810041) (xy 125.619774 -273.792589) (xy 125.667993 -273.782745) (xy 125.717168 -273.780764)
			(xy 125.766023 -273.786696) (xy 125.813294 -273.800388) (xy 125.857756 -273.821486) (xy 125.898259 -273.849442)
			(xy 125.933752 -273.883534) (xy 125.963317 -273.922878) (xy 125.986188 -273.966455) (xy 126.001772 -274.013136)
			(xy 126.009667 -274.061713) (xy 126.010162 -274.08632) (xy 126.33885 -274.08632) (xy 126.34281 -274.037266)
			(xy 126.354587 -273.989482) (xy 126.373878 -273.944206) (xy 126.400181 -273.90261) (xy 126.432816 -273.865773)
			(xy 126.470937 -273.834648) (xy 126.513558 -273.810041) (xy 126.559574 -273.792589) (xy 126.607793 -273.782745)
			(xy 126.656968 -273.780764) (xy 126.705823 -273.786696) (xy 126.753094 -273.800388) (xy 126.797556 -273.821486)
			(xy 126.838059 -273.849442) (xy 126.873552 -273.883534) (xy 126.903117 -273.922878) (xy 126.925988 -273.966455)
			(xy 126.941572 -274.013136) (xy 126.949467 -274.061713) (xy 126.949962 -274.08632) (xy 126.949467 -274.110927)
			(xy 126.941572 -274.159504) (xy 126.925988 -274.206185) (xy 126.903117 -274.249762) (xy 126.873552 -274.289106)
			(xy 126.838059 -274.323198) (xy 126.797556 -274.351154) (xy 126.753094 -274.372252) (xy 126.705823 -274.385944)
			(xy 126.656968 -274.391876) (xy 126.607793 -274.389895) (xy 126.559574 -274.380051) (xy 126.513558 -274.362599)
			(xy 126.470937 -274.337992) (xy 126.432816 -274.306867) (xy 126.400181 -274.27003) (xy 126.373878 -274.228434)
			(xy 126.354587 -274.183158) (xy 126.34281 -274.135374) (xy 126.33885 -274.08632) (xy 126.010162 -274.08632)
			(xy 126.009667 -274.110927) (xy 126.001772 -274.159504) (xy 125.986188 -274.206185) (xy 125.963317 -274.249762)
			(xy 125.933752 -274.289106) (xy 125.898259 -274.323198) (xy 125.857756 -274.351154) (xy 125.813294 -274.372252)
			(xy 125.766023 -274.385944) (xy 125.717168 -274.391876) (xy 125.667993 -274.389895) (xy 125.619774 -274.380051)
			(xy 125.573758 -274.362599) (xy 125.531137 -274.337992) (xy 125.493016 -274.306867) (xy 125.460381 -274.27003)
			(xy 125.434078 -274.228434) (xy 125.414787 -274.183158) (xy 125.40301 -274.135374) (xy 125.39905 -274.08632)
			(xy 125.070108 -274.08632) (xy 125.069613 -274.110927) (xy 125.061718 -274.159504) (xy 125.046134 -274.206185)
			(xy 125.023263 -274.249762) (xy 124.993698 -274.289106) (xy 124.958205 -274.323198) (xy 124.917702 -274.351154)
			(xy 124.87324 -274.372252) (xy 124.825969 -274.385944) (xy 124.777114 -274.391876) (xy 124.727939 -274.389895)
			(xy 124.67972 -274.380051) (xy 124.633704 -274.362599) (xy 124.591083 -274.337992) (xy 124.552962 -274.306867)
			(xy 124.520327 -274.27003) (xy 124.494024 -274.228434) (xy 124.474733 -274.183158) (xy 124.462956 -274.135374)
			(xy 124.458996 -274.08632) (xy 124.130054 -274.08632) (xy 124.129559 -274.110927) (xy 124.121664 -274.159504)
			(xy 124.10608 -274.206185) (xy 124.083209 -274.249762) (xy 124.053644 -274.289106) (xy 124.018151 -274.323198)
			(xy 123.977648 -274.351154) (xy 123.933186 -274.372252) (xy 123.885915 -274.385944) (xy 123.83706 -274.391876)
			(xy 123.787885 -274.389895) (xy 123.739666 -274.380051) (xy 123.69365 -274.362599) (xy 123.651029 -274.337992)
			(xy 123.612908 -274.306867) (xy 123.580273 -274.27003) (xy 123.55397 -274.228434) (xy 123.534679 -274.183158)
			(xy 123.522902 -274.135374) (xy 123.518942 -274.08632) (xy 123.19 -274.08632) (xy 123.189505 -274.110927)
			(xy 123.18161 -274.159504) (xy 123.166026 -274.206185) (xy 123.143155 -274.249762) (xy 123.11359 -274.289106)
			(xy 123.078097 -274.323198) (xy 123.037594 -274.351154) (xy 122.993132 -274.372252) (xy 122.945861 -274.385944)
			(xy 122.897006 -274.391876) (xy 122.847831 -274.389895) (xy 122.799612 -274.380051) (xy 122.753596 -274.362599)
			(xy 122.710975 -274.337992) (xy 122.672854 -274.306867) (xy 122.640219 -274.27003) (xy 122.613916 -274.228434)
			(xy 122.594625 -274.183158) (xy 122.582848 -274.135374) (xy 122.578888 -274.08632) (xy 122.249946 -274.08632)
			(xy 122.249451 -274.110927) (xy 122.241556 -274.159504) (xy 122.225972 -274.206185) (xy 122.203101 -274.249762)
			(xy 122.173536 -274.289106) (xy 122.138043 -274.323198) (xy 122.09754 -274.351154) (xy 122.053078 -274.372252)
			(xy 122.005807 -274.385944) (xy 121.956952 -274.391876) (xy 121.907777 -274.389895) (xy 121.859558 -274.380051)
			(xy 121.813542 -274.362599) (xy 121.770921 -274.337992) (xy 121.7328 -274.306867) (xy 121.700165 -274.27003)
			(xy 121.673862 -274.228434) (xy 121.654571 -274.183158) (xy 121.642794 -274.135374) (xy 121.638834 -274.08632)
			(xy 121.310146 -274.08632) (xy 121.309651 -274.110927) (xy 121.301756 -274.159504) (xy 121.286172 -274.206185)
			(xy 121.263301 -274.249762) (xy 121.233736 -274.289106) (xy 121.198243 -274.323198) (xy 121.15774 -274.351154)
			(xy 121.113278 -274.372252) (xy 121.066007 -274.385944) (xy 121.017152 -274.391876) (xy 120.967977 -274.389895)
			(xy 120.919758 -274.380051) (xy 120.873742 -274.362599) (xy 120.831121 -274.337992) (xy 120.793 -274.306867)
			(xy 120.760365 -274.27003) (xy 120.734062 -274.228434) (xy 120.714771 -274.183158) (xy 120.702994 -274.135374)
			(xy 120.699034 -274.08632) (xy 120.370092 -274.08632) (xy 120.369597 -274.110927) (xy 120.361702 -274.159504)
			(xy 120.346118 -274.206185) (xy 120.323247 -274.249762) (xy 120.293682 -274.289106) (xy 120.258189 -274.323198)
			(xy 120.217686 -274.351154) (xy 120.173224 -274.372252) (xy 120.125953 -274.385944) (xy 120.077098 -274.391876)
			(xy 120.027923 -274.389895) (xy 119.979704 -274.380051) (xy 119.933688 -274.362599) (xy 119.891067 -274.337992)
			(xy 119.852946 -274.306867) (xy 119.820311 -274.27003) (xy 119.794008 -274.228434) (xy 119.774717 -274.183158)
			(xy 119.76294 -274.135374) (xy 119.75898 -274.08632) (xy 119.430038 -274.08632) (xy 119.429543 -274.110927)
			(xy 119.421648 -274.159504) (xy 119.406064 -274.206185) (xy 119.383193 -274.249762) (xy 119.353628 -274.289106)
			(xy 119.318135 -274.323198) (xy 119.277632 -274.351154) (xy 119.23317 -274.372252) (xy 119.185899 -274.385944)
			(xy 119.137044 -274.391876) (xy 119.087869 -274.389895) (xy 119.03965 -274.380051) (xy 118.993634 -274.362599)
			(xy 118.951013 -274.337992) (xy 118.912892 -274.306867) (xy 118.880257 -274.27003) (xy 118.853954 -274.228434)
			(xy 118.834663 -274.183158) (xy 118.822886 -274.135374) (xy 118.818926 -274.08632) (xy 118.489984 -274.08632)
			(xy 118.489489 -274.110927) (xy 118.481594 -274.159504) (xy 118.46601 -274.206185) (xy 118.443139 -274.249762)
			(xy 118.413574 -274.289106) (xy 118.378081 -274.323198) (xy 118.337578 -274.351154) (xy 118.293116 -274.372252)
			(xy 118.245845 -274.385944) (xy 118.19699 -274.391876) (xy 118.147815 -274.389895) (xy 118.099596 -274.380051)
			(xy 118.05358 -274.362599) (xy 118.010959 -274.337992) (xy 117.972838 -274.306867) (xy 117.940203 -274.27003)
			(xy 117.9139 -274.228434) (xy 117.894609 -274.183158) (xy 117.882832 -274.135374) (xy 117.878872 -274.08632)
			(xy 117.54993 -274.08632) (xy 117.549435 -274.110927) (xy 117.54154 -274.159504) (xy 117.525956 -274.206185)
			(xy 117.503085 -274.249762) (xy 117.47352 -274.289106) (xy 117.438027 -274.323198) (xy 117.397524 -274.351154)
			(xy 117.353062 -274.372252) (xy 117.305791 -274.385944) (xy 117.256936 -274.391876) (xy 117.207761 -274.389895)
			(xy 117.159542 -274.380051) (xy 117.113526 -274.362599) (xy 117.070905 -274.337992) (xy 117.032784 -274.306867)
			(xy 117.000149 -274.27003) (xy 116.973846 -274.228434) (xy 116.954555 -274.183158) (xy 116.942778 -274.135374)
			(xy 116.938818 -274.08632) (xy 116.61013 -274.08632) (xy 116.609635 -274.110927) (xy 116.60174 -274.159504)
			(xy 116.586156 -274.206185) (xy 116.563285 -274.249762) (xy 116.53372 -274.289106) (xy 116.498227 -274.323198)
			(xy 116.457724 -274.351154) (xy 116.413262 -274.372252) (xy 116.365991 -274.385944) (xy 116.317136 -274.391876)
			(xy 116.267961 -274.389895) (xy 116.219742 -274.380051) (xy 116.173726 -274.362599) (xy 116.131105 -274.337992)
			(xy 116.092984 -274.306867) (xy 116.060349 -274.27003) (xy 116.034046 -274.228434) (xy 116.014755 -274.183158)
			(xy 116.002978 -274.135374) (xy 115.999018 -274.08632) (xy 115.670076 -274.08632) (xy 115.669581 -274.110927)
			(xy 115.661686 -274.159504) (xy 115.646102 -274.206185) (xy 115.623231 -274.249762) (xy 115.593666 -274.289106)
			(xy 115.558173 -274.323198) (xy 115.51767 -274.351154) (xy 115.473208 -274.372252) (xy 115.425937 -274.385944)
			(xy 115.377082 -274.391876) (xy 115.327907 -274.389895) (xy 115.279688 -274.380051) (xy 115.233672 -274.362599)
			(xy 115.191051 -274.337992) (xy 115.15293 -274.306867) (xy 115.120295 -274.27003) (xy 115.093992 -274.228434)
			(xy 115.074701 -274.183158) (xy 115.062924 -274.135374) (xy 115.058964 -274.08632) (xy 114.730022 -274.08632)
			(xy 114.729527 -274.110927) (xy 114.721632 -274.159504) (xy 114.706048 -274.206185) (xy 114.683177 -274.249762)
			(xy 114.653612 -274.289106) (xy 114.618119 -274.323198) (xy 114.577616 -274.351154) (xy 114.533154 -274.372252)
			(xy 114.485883 -274.385944) (xy 114.437028 -274.391876) (xy 114.387853 -274.389895) (xy 114.339634 -274.380051)
			(xy 114.293618 -274.362599) (xy 114.250997 -274.337992) (xy 114.212876 -274.306867) (xy 114.180241 -274.27003)
			(xy 114.153938 -274.228434) (xy 114.134647 -274.183158) (xy 114.12287 -274.135374) (xy 114.11891 -274.08632)
			(xy 113.789968 -274.08632) (xy 113.789473 -274.110927) (xy 113.781578 -274.159504) (xy 113.765994 -274.206185)
			(xy 113.743123 -274.249762) (xy 113.713558 -274.289106) (xy 113.678065 -274.323198) (xy 113.637562 -274.351154)
			(xy 113.5931 -274.372252) (xy 113.545829 -274.385944) (xy 113.496974 -274.391876) (xy 113.447799 -274.389895)
			(xy 113.39958 -274.380051) (xy 113.353564 -274.362599) (xy 113.310943 -274.337992) (xy 113.272822 -274.306867)
			(xy 113.240187 -274.27003) (xy 113.213884 -274.228434) (xy 113.194593 -274.183158) (xy 113.182816 -274.135374)
			(xy 113.178856 -274.08632) (xy 110.97641 -274.08632) (xy 110.975915 -274.110927) (xy 110.96802 -274.159504)
			(xy 110.952436 -274.206185) (xy 110.929565 -274.249762) (xy 110.9 -274.289106) (xy 110.864507 -274.323198)
			(xy 110.824004 -274.351154) (xy 110.779542 -274.372252) (xy 110.732271 -274.385944) (xy 110.683416 -274.391876)
			(xy 110.634241 -274.389895) (xy 110.586022 -274.380051) (xy 110.540006 -274.362599) (xy 110.497385 -274.337992)
			(xy 110.459264 -274.306867) (xy 110.426629 -274.27003) (xy 110.400326 -274.228434) (xy 110.381035 -274.183158)
			(xy 110.369258 -274.135374) (xy 110.365298 -274.08632) (xy 110.036356 -274.08632) (xy 110.035861 -274.110927)
			(xy 110.027966 -274.159504) (xy 110.012382 -274.206185) (xy 109.989511 -274.249762) (xy 109.959946 -274.289106)
			(xy 109.924453 -274.323198) (xy 109.88395 -274.351154) (xy 109.839488 -274.372252) (xy 109.792217 -274.385944)
			(xy 109.743362 -274.391876) (xy 109.694187 -274.389895) (xy 109.645968 -274.380051) (xy 109.599952 -274.362599)
			(xy 109.557331 -274.337992) (xy 109.51921 -274.306867) (xy 109.486575 -274.27003) (xy 109.460272 -274.228434)
			(xy 109.440981 -274.183158) (xy 109.429204 -274.135374) (xy 109.425244 -274.08632) (xy 109.096302 -274.08632)
			(xy 109.095807 -274.110927) (xy 109.087912 -274.159504) (xy 109.072328 -274.206185) (xy 109.049457 -274.249762)
			(xy 109.019892 -274.289106) (xy 108.984399 -274.323198) (xy 108.943896 -274.351154) (xy 108.899434 -274.372252)
			(xy 108.852163 -274.385944) (xy 108.803308 -274.391876) (xy 108.754133 -274.389895) (xy 108.705914 -274.380051)
			(xy 108.659898 -274.362599) (xy 108.617277 -274.337992) (xy 108.579156 -274.306867) (xy 108.546521 -274.27003)
			(xy 108.520218 -274.228434) (xy 108.500927 -274.183158) (xy 108.48915 -274.135374) (xy 108.48519 -274.08632)
			(xy 108.156248 -274.08632) (xy 108.155753 -274.110927) (xy 108.147858 -274.159504) (xy 108.132274 -274.206185)
			(xy 108.109403 -274.249762) (xy 108.079838 -274.289106) (xy 108.044345 -274.323198) (xy 108.003842 -274.351154)
			(xy 107.95938 -274.372252) (xy 107.912109 -274.385944) (xy 107.863254 -274.391876) (xy 107.814079 -274.389895)
			(xy 107.76586 -274.380051) (xy 107.719844 -274.362599) (xy 107.677223 -274.337992) (xy 107.639102 -274.306867)
			(xy 107.606467 -274.27003) (xy 107.580164 -274.228434) (xy 107.560873 -274.183158) (xy 107.549096 -274.135374)
			(xy 107.545136 -274.08632) (xy 107.216448 -274.08632) (xy 107.215953 -274.110927) (xy 107.208058 -274.159504)
			(xy 107.192474 -274.206185) (xy 107.169603 -274.249762) (xy 107.140038 -274.289106) (xy 107.104545 -274.323198)
			(xy 107.064042 -274.351154) (xy 107.01958 -274.372252) (xy 106.972309 -274.385944) (xy 106.923454 -274.391876)
			(xy 106.874279 -274.389895) (xy 106.82606 -274.380051) (xy 106.780044 -274.362599) (xy 106.737423 -274.337992)
			(xy 106.699302 -274.306867) (xy 106.666667 -274.27003) (xy 106.640364 -274.228434) (xy 106.621073 -274.183158)
			(xy 106.609296 -274.135374) (xy 106.605336 -274.08632) (xy 106.276394 -274.08632) (xy 106.275899 -274.110927)
			(xy 106.268004 -274.159504) (xy 106.25242 -274.206185) (xy 106.229549 -274.249762) (xy 106.199984 -274.289106)
			(xy 106.164491 -274.323198) (xy 106.123988 -274.351154) (xy 106.079526 -274.372252) (xy 106.032255 -274.385944)
			(xy 105.9834 -274.391876) (xy 105.934225 -274.389895) (xy 105.886006 -274.380051) (xy 105.83999 -274.362599)
			(xy 105.797369 -274.337992) (xy 105.759248 -274.306867) (xy 105.726613 -274.27003) (xy 105.70031 -274.228434)
			(xy 105.681019 -274.183158) (xy 105.669242 -274.135374) (xy 105.665282 -274.08632) (xy 105.33634 -274.08632)
			(xy 105.335845 -274.110927) (xy 105.32795 -274.159504) (xy 105.312366 -274.206185) (xy 105.289495 -274.249762)
			(xy 105.25993 -274.289106) (xy 105.224437 -274.323198) (xy 105.183934 -274.351154) (xy 105.139472 -274.372252)
			(xy 105.092201 -274.385944) (xy 105.043346 -274.391876) (xy 104.994171 -274.389895) (xy 104.945952 -274.380051)
			(xy 104.899936 -274.362599) (xy 104.857315 -274.337992) (xy 104.819194 -274.306867) (xy 104.786559 -274.27003)
			(xy 104.760256 -274.228434) (xy 104.740965 -274.183158) (xy 104.729188 -274.135374) (xy 104.725228 -274.08632)
			(xy 104.396286 -274.08632) (xy 104.395791 -274.110927) (xy 104.387896 -274.159504) (xy 104.372312 -274.206185)
			(xy 104.349441 -274.249762) (xy 104.319876 -274.289106) (xy 104.284383 -274.323198) (xy 104.24388 -274.351154)
			(xy 104.199418 -274.372252) (xy 104.152147 -274.385944) (xy 104.103292 -274.391876) (xy 104.054117 -274.389895)
			(xy 104.005898 -274.380051) (xy 103.959882 -274.362599) (xy 103.917261 -274.337992) (xy 103.87914 -274.306867)
			(xy 103.846505 -274.27003) (xy 103.820202 -274.228434) (xy 103.800911 -274.183158) (xy 103.789134 -274.135374)
			(xy 103.785174 -274.08632) (xy 103.456486 -274.08632) (xy 103.455991 -274.110927) (xy 103.448096 -274.159504)
			(xy 103.432512 -274.206185) (xy 103.409641 -274.249762) (xy 103.380076 -274.289106) (xy 103.344583 -274.323198)
			(xy 103.30408 -274.351154) (xy 103.259618 -274.372252) (xy 103.212347 -274.385944) (xy 103.163492 -274.391876)
			(xy 103.114317 -274.389895) (xy 103.066098 -274.380051) (xy 103.020082 -274.362599) (xy 102.977461 -274.337992)
			(xy 102.93934 -274.306867) (xy 102.906705 -274.27003) (xy 102.880402 -274.228434) (xy 102.861111 -274.183158)
			(xy 102.849334 -274.135374) (xy 102.845374 -274.08632) (xy 102.516432 -274.08632) (xy 102.515937 -274.110927)
			(xy 102.508042 -274.159504) (xy 102.492458 -274.206185) (xy 102.469587 -274.249762) (xy 102.440022 -274.289106)
			(xy 102.404529 -274.323198) (xy 102.364026 -274.351154) (xy 102.319564 -274.372252) (xy 102.272293 -274.385944)
			(xy 102.223438 -274.391876) (xy 102.174263 -274.389895) (xy 102.126044 -274.380051) (xy 102.080028 -274.362599)
			(xy 102.037407 -274.337992) (xy 101.999286 -274.306867) (xy 101.966651 -274.27003) (xy 101.940348 -274.228434)
			(xy 101.921057 -274.183158) (xy 101.90928 -274.135374) (xy 101.90532 -274.08632) (xy 101.576378 -274.08632)
			(xy 101.575883 -274.110927) (xy 101.567988 -274.159504) (xy 101.552404 -274.206185) (xy 101.529533 -274.249762)
			(xy 101.499968 -274.289106) (xy 101.464475 -274.323198) (xy 101.423972 -274.351154) (xy 101.37951 -274.372252)
			(xy 101.332239 -274.385944) (xy 101.283384 -274.391876) (xy 101.234209 -274.389895) (xy 101.18599 -274.380051)
			(xy 101.139974 -274.362599) (xy 101.097353 -274.337992) (xy 101.059232 -274.306867) (xy 101.026597 -274.27003)
			(xy 101.000294 -274.228434) (xy 100.981003 -274.183158) (xy 100.969226 -274.135374) (xy 100.965266 -274.08632)
			(xy 100.636324 -274.08632) (xy 100.635829 -274.110927) (xy 100.627934 -274.159504) (xy 100.61235 -274.206185)
			(xy 100.589479 -274.249762) (xy 100.559914 -274.289106) (xy 100.524421 -274.323198) (xy 100.483918 -274.351154)
			(xy 100.439456 -274.372252) (xy 100.392185 -274.385944) (xy 100.34333 -274.391876) (xy 100.294155 -274.389895)
			(xy 100.245936 -274.380051) (xy 100.19992 -274.362599) (xy 100.157299 -274.337992) (xy 100.119178 -274.306867)
			(xy 100.086543 -274.27003) (xy 100.06024 -274.228434) (xy 100.040949 -274.183158) (xy 100.029172 -274.135374)
			(xy 100.025212 -274.08632) (xy 99.69627 -274.08632) (xy 99.695775 -274.110927) (xy 99.68788 -274.159504)
			(xy 99.672296 -274.206185) (xy 99.649425 -274.249762) (xy 99.61986 -274.289106) (xy 99.584367 -274.323198)
			(xy 99.543864 -274.351154) (xy 99.499402 -274.372252) (xy 99.452131 -274.385944) (xy 99.403276 -274.391876)
			(xy 99.354101 -274.389895) (xy 99.305882 -274.380051) (xy 99.259866 -274.362599) (xy 99.217245 -274.337992)
			(xy 99.179124 -274.306867) (xy 99.146489 -274.27003) (xy 99.120186 -274.228434) (xy 99.100895 -274.183158)
			(xy 99.089118 -274.135374) (xy 99.085158 -274.08632) (xy 98.75647 -274.08632) (xy 98.755975 -274.110927)
			(xy 98.74808 -274.159504) (xy 98.732496 -274.206185) (xy 98.709625 -274.249762) (xy 98.68006 -274.289106)
			(xy 98.644567 -274.323198) (xy 98.604064 -274.351154) (xy 98.559602 -274.372252) (xy 98.512331 -274.385944)
			(xy 98.463476 -274.391876) (xy 98.414301 -274.389895) (xy 98.366082 -274.380051) (xy 98.320066 -274.362599)
			(xy 98.277445 -274.337992) (xy 98.239324 -274.306867) (xy 98.206689 -274.27003) (xy 98.180386 -274.228434)
			(xy 98.161095 -274.183158) (xy 98.149318 -274.135374) (xy 98.145358 -274.08632) (xy 97.816416 -274.08632)
			(xy 97.815921 -274.110927) (xy 97.808026 -274.159504) (xy 97.792442 -274.206185) (xy 97.769571 -274.249762)
			(xy 97.740006 -274.289106) (xy 97.704513 -274.323198) (xy 97.66401 -274.351154) (xy 97.619548 -274.372252)
			(xy 97.572277 -274.385944) (xy 97.523422 -274.391876) (xy 97.474247 -274.389895) (xy 97.426028 -274.380051)
			(xy 97.380012 -274.362599) (xy 97.337391 -274.337992) (xy 97.29927 -274.306867) (xy 97.266635 -274.27003)
			(xy 97.240332 -274.228434) (xy 97.221041 -274.183158) (xy 97.209264 -274.135374) (xy 97.205304 -274.08632)
			(xy 96.876362 -274.08632) (xy 96.875899 -274.110927) (xy 96.868014 -274.159506) (xy 96.852436 -274.20619)
			(xy 96.829567 -274.249769) (xy 96.800002 -274.289114) (xy 96.764506 -274.323204) (xy 96.724 -274.351156)
			(xy 96.679533 -274.372245) (xy 96.632257 -274.385925) (xy 96.607884 -274.389342) (xy 96.60509 -274.389596)
			(xy 96.599041 -274.390867) (xy 96.587744 -274.395876) (xy 96.582738 -274.399502) (xy 96.577658 -274.403312)
			(xy 96.573848 -274.408392) (xy 96.567244 -274.419822) (xy 96.533208 -274.502372) (xy 96.531266 -274.508262)
			(xy 96.52998 -274.520593) (xy 96.530668 -274.526756) (xy 96.532446 -274.53971) (xy 96.541082 -274.550886)
			(xy 96.565553 -274.583367) (xy 96.605843 -274.654006) (xy 96.621346 -274.691602) (xy 96.62414 -274.69846)
			(xy 96.63176 -274.708874) (xy 96.637348 -274.713192) (xy 96.642019 -274.716626) (xy 96.652537 -274.721495)
			(xy 96.658176 -274.722844) (xy 96.75114 -274.735036) (xy 96.754912 -274.735213) (xy 96.762436 -274.734569)
			(xy 96.766126 -274.733766) (xy 96.77527 -274.730972) (xy 96.787208 -274.725638) (xy 96.788478 -274.72386)
			(xy 96.795336 -274.714716) (xy 96.79559 -274.714208) (xy 96.810128 -274.695437) (xy 96.844028 -274.662199)
			(xy 96.882659 -274.634601) (xy 96.925092 -274.613307) (xy 96.970306 -274.598828) (xy 97.017216 -274.591512)
			(xy 97.040954 -274.591018) (xy 97.064949 -274.591461) (xy 97.112348 -274.598962) (xy 97.15799 -274.613787)
			(xy 97.200751 -274.63557) (xy 97.239577 -274.663775) (xy 97.273512 -274.697708) (xy 97.301719 -274.736532)
			(xy 97.323506 -274.779291) (xy 97.338333 -274.824932) (xy 97.345838 -274.872331) (xy 97.346262 -274.896326)
			(xy 97.675204 -274.896326) (xy 97.679164 -274.847272) (xy 97.690941 -274.799488) (xy 97.710232 -274.754212)
			(xy 97.736535 -274.712616) (xy 97.76917 -274.675779) (xy 97.807291 -274.644654) (xy 97.849912 -274.620047)
			(xy 97.895928 -274.602595) (xy 97.944147 -274.592751) (xy 97.993322 -274.59077) (xy 98.042177 -274.596702)
			(xy 98.089448 -274.610394) (xy 98.13391 -274.631492) (xy 98.174413 -274.659448) (xy 98.209906 -274.69354)
			(xy 98.239471 -274.732884) (xy 98.262342 -274.776461) (xy 98.277926 -274.823142) (xy 98.285821 -274.871719)
			(xy 98.286316 -274.896326) (xy 98.615258 -274.896326) (xy 98.619218 -274.847272) (xy 98.630995 -274.799488)
			(xy 98.650286 -274.754212) (xy 98.676589 -274.712616) (xy 98.709224 -274.675779) (xy 98.747345 -274.644654)
			(xy 98.789966 -274.620047) (xy 98.835982 -274.602595) (xy 98.884201 -274.592751) (xy 98.933376 -274.59077)
			(xy 98.982231 -274.596702) (xy 99.029502 -274.610394) (xy 99.073964 -274.631492) (xy 99.114467 -274.659448)
			(xy 99.14996 -274.69354) (xy 99.179525 -274.732884) (xy 99.202396 -274.776461) (xy 99.21798 -274.823142)
			(xy 99.225875 -274.871719) (xy 99.22637 -274.896326) (xy 99.555312 -274.896326) (xy 99.559272 -274.847272)
			(xy 99.571049 -274.799488) (xy 99.59034 -274.754212) (xy 99.616643 -274.712616) (xy 99.649278 -274.675779)
			(xy 99.687399 -274.644654) (xy 99.73002 -274.620047) (xy 99.776036 -274.602595) (xy 99.824255 -274.592751)
			(xy 99.87343 -274.59077) (xy 99.922285 -274.596702) (xy 99.969556 -274.610394) (xy 100.014018 -274.631492)
			(xy 100.054521 -274.659448) (xy 100.090014 -274.69354) (xy 100.119579 -274.732884) (xy 100.14245 -274.776461)
			(xy 100.158034 -274.823142) (xy 100.165929 -274.871719) (xy 100.166424 -274.896326) (xy 100.495366 -274.896326)
			(xy 100.499326 -274.847272) (xy 100.511103 -274.799488) (xy 100.530394 -274.754212) (xy 100.556697 -274.712616)
			(xy 100.589332 -274.675779) (xy 100.627453 -274.644654) (xy 100.670074 -274.620047) (xy 100.71609 -274.602595)
			(xy 100.764309 -274.592751) (xy 100.813484 -274.59077) (xy 100.862339 -274.596702) (xy 100.90961 -274.610394)
			(xy 100.954072 -274.631492) (xy 100.994575 -274.659448) (xy 101.030068 -274.69354) (xy 101.059633 -274.732884)
			(xy 101.082504 -274.776461) (xy 101.098088 -274.823142) (xy 101.105983 -274.871719) (xy 101.106478 -274.896326)
			(xy 101.435166 -274.896326) (xy 101.439126 -274.847272) (xy 101.450903 -274.799488) (xy 101.470194 -274.754212)
			(xy 101.496497 -274.712616) (xy 101.529132 -274.675779) (xy 101.567253 -274.644654) (xy 101.609874 -274.620047)
			(xy 101.65589 -274.602595) (xy 101.704109 -274.592751) (xy 101.753284 -274.59077) (xy 101.802139 -274.596702)
			(xy 101.84941 -274.610394) (xy 101.893872 -274.631492) (xy 101.934375 -274.659448) (xy 101.969868 -274.69354)
			(xy 101.999433 -274.732884) (xy 102.022304 -274.776461) (xy 102.037888 -274.823142) (xy 102.045783 -274.871719)
			(xy 102.046278 -274.896326) (xy 102.37522 -274.896326) (xy 102.37918 -274.847272) (xy 102.390957 -274.799488)
			(xy 102.410248 -274.754212) (xy 102.436551 -274.712616) (xy 102.469186 -274.675779) (xy 102.507307 -274.644654)
			(xy 102.549928 -274.620047) (xy 102.595944 -274.602595) (xy 102.644163 -274.592751) (xy 102.693338 -274.59077)
			(xy 102.742193 -274.596702) (xy 102.789464 -274.610394) (xy 102.833926 -274.631492) (xy 102.874429 -274.659448)
			(xy 102.909922 -274.69354) (xy 102.939487 -274.732884) (xy 102.962358 -274.776461) (xy 102.977942 -274.823142)
			(xy 102.985837 -274.871719) (xy 102.986332 -274.896326) (xy 103.315274 -274.896326) (xy 103.319234 -274.847272)
			(xy 103.331011 -274.799488) (xy 103.350302 -274.754212) (xy 103.376605 -274.712616) (xy 103.40924 -274.675779)
			(xy 103.447361 -274.644654) (xy 103.489982 -274.620047) (xy 103.535998 -274.602595) (xy 103.584217 -274.592751)
			(xy 103.633392 -274.59077) (xy 103.682247 -274.596702) (xy 103.729518 -274.610394) (xy 103.77398 -274.631492)
			(xy 103.814483 -274.659448) (xy 103.849976 -274.69354) (xy 103.879541 -274.732884) (xy 103.902412 -274.776461)
			(xy 103.917996 -274.823142) (xy 103.925891 -274.871719) (xy 103.926386 -274.896326) (xy 104.255328 -274.896326)
			(xy 104.259288 -274.847272) (xy 104.271065 -274.799488) (xy 104.290356 -274.754212) (xy 104.316659 -274.712616)
			(xy 104.349294 -274.675779) (xy 104.387415 -274.644654) (xy 104.430036 -274.620047) (xy 104.476052 -274.602595)
			(xy 104.524271 -274.592751) (xy 104.573446 -274.59077) (xy 104.622301 -274.596702) (xy 104.669572 -274.610394)
			(xy 104.714034 -274.631492) (xy 104.754537 -274.659448) (xy 104.79003 -274.69354) (xy 104.819595 -274.732884)
			(xy 104.842466 -274.776461) (xy 104.85805 -274.823142) (xy 104.865945 -274.871719) (xy 104.86644 -274.896326)
			(xy 105.195128 -274.896326) (xy 105.199088 -274.847272) (xy 105.210865 -274.799488) (xy 105.230156 -274.754212)
			(xy 105.256459 -274.712616) (xy 105.289094 -274.675779) (xy 105.327215 -274.644654) (xy 105.369836 -274.620047)
			(xy 105.415852 -274.602595) (xy 105.464071 -274.592751) (xy 105.513246 -274.59077) (xy 105.562101 -274.596702)
			(xy 105.609372 -274.610394) (xy 105.653834 -274.631492) (xy 105.694337 -274.659448) (xy 105.72983 -274.69354)
			(xy 105.759395 -274.732884) (xy 105.782266 -274.776461) (xy 105.79785 -274.823142) (xy 105.805745 -274.871719)
			(xy 105.80624 -274.896326) (xy 106.135182 -274.896326) (xy 106.139142 -274.847272) (xy 106.150919 -274.799488)
			(xy 106.17021 -274.754212) (xy 106.196513 -274.712616) (xy 106.229148 -274.675779) (xy 106.267269 -274.644654)
			(xy 106.30989 -274.620047) (xy 106.355906 -274.602595) (xy 106.404125 -274.592751) (xy 106.4533 -274.59077)
			(xy 106.502155 -274.596702) (xy 106.549426 -274.610394) (xy 106.593888 -274.631492) (xy 106.634391 -274.659448)
			(xy 106.669884 -274.69354) (xy 106.699449 -274.732884) (xy 106.72232 -274.776461) (xy 106.737904 -274.823142)
			(xy 106.745799 -274.871719) (xy 106.746294 -274.896326) (xy 107.075236 -274.896326) (xy 107.079196 -274.847272)
			(xy 107.090973 -274.799488) (xy 107.110264 -274.754212) (xy 107.136567 -274.712616) (xy 107.169202 -274.675779)
			(xy 107.207323 -274.644654) (xy 107.249944 -274.620047) (xy 107.29596 -274.602595) (xy 107.344179 -274.592751)
			(xy 107.393354 -274.59077) (xy 107.442209 -274.596702) (xy 107.48948 -274.610394) (xy 107.533942 -274.631492)
			(xy 107.574445 -274.659448) (xy 107.609938 -274.69354) (xy 107.639503 -274.732884) (xy 107.662374 -274.776461)
			(xy 107.677958 -274.823142) (xy 107.685853 -274.871719) (xy 107.686348 -274.896326) (xy 108.01529 -274.896326)
			(xy 108.01925 -274.847272) (xy 108.031027 -274.799488) (xy 108.050318 -274.754212) (xy 108.076621 -274.712616)
			(xy 108.109256 -274.675779) (xy 108.147377 -274.644654) (xy 108.189998 -274.620047) (xy 108.236014 -274.602595)
			(xy 108.284233 -274.592751) (xy 108.333408 -274.59077) (xy 108.382263 -274.596702) (xy 108.429534 -274.610394)
			(xy 108.473996 -274.631492) (xy 108.514499 -274.659448) (xy 108.549992 -274.69354) (xy 108.579557 -274.732884)
			(xy 108.602428 -274.776461) (xy 108.618012 -274.823142) (xy 108.625907 -274.871719) (xy 108.626402 -274.896326)
			(xy 115.528864 -274.896326) (xy 115.532824 -274.847272) (xy 115.544601 -274.799488) (xy 115.563892 -274.754212)
			(xy 115.590195 -274.712616) (xy 115.62283 -274.675779) (xy 115.660951 -274.644654) (xy 115.703572 -274.620047)
			(xy 115.749588 -274.602595) (xy 115.797807 -274.592751) (xy 115.846982 -274.59077) (xy 115.895837 -274.596702)
			(xy 115.943108 -274.610394) (xy 115.98757 -274.631492) (xy 116.028073 -274.659448) (xy 116.063566 -274.69354)
			(xy 116.093131 -274.732884) (xy 116.116002 -274.776461) (xy 116.131586 -274.823142) (xy 116.139481 -274.871719)
			(xy 116.139976 -274.896326) (xy 116.468918 -274.896326) (xy 116.472878 -274.847272) (xy 116.484655 -274.799488)
			(xy 116.503946 -274.754212) (xy 116.530249 -274.712616) (xy 116.562884 -274.675779) (xy 116.601005 -274.644654)
			(xy 116.643626 -274.620047) (xy 116.689642 -274.602595) (xy 116.737861 -274.592751) (xy 116.787036 -274.59077)
			(xy 116.835891 -274.596702) (xy 116.883162 -274.610394) (xy 116.927624 -274.631492) (xy 116.968127 -274.659448)
			(xy 117.00362 -274.69354) (xy 117.033185 -274.732884) (xy 117.056056 -274.776461) (xy 117.07164 -274.823142)
			(xy 117.079535 -274.871719) (xy 117.08003 -274.896326) (xy 117.408972 -274.896326) (xy 117.412932 -274.847272)
			(xy 117.424709 -274.799488) (xy 117.444 -274.754212) (xy 117.470303 -274.712616) (xy 117.502938 -274.675779)
			(xy 117.541059 -274.644654) (xy 117.58368 -274.620047) (xy 117.629696 -274.602595) (xy 117.677915 -274.592751)
			(xy 117.72709 -274.59077) (xy 117.775945 -274.596702) (xy 117.823216 -274.610394) (xy 117.867678 -274.631492)
			(xy 117.908181 -274.659448) (xy 117.943674 -274.69354) (xy 117.973239 -274.732884) (xy 117.99611 -274.776461)
			(xy 118.011694 -274.823142) (xy 118.019589 -274.871719) (xy 118.020084 -274.896326) (xy 118.349026 -274.896326)
			(xy 118.352986 -274.847272) (xy 118.364763 -274.799488) (xy 118.384054 -274.754212) (xy 118.410357 -274.712616)
			(xy 118.442992 -274.675779) (xy 118.481113 -274.644654) (xy 118.523734 -274.620047) (xy 118.56975 -274.602595)
			(xy 118.617969 -274.592751) (xy 118.667144 -274.59077) (xy 118.715999 -274.596702) (xy 118.76327 -274.610394)
			(xy 118.807732 -274.631492) (xy 118.848235 -274.659448) (xy 118.883728 -274.69354) (xy 118.913293 -274.732884)
			(xy 118.936164 -274.776461) (xy 118.951748 -274.823142) (xy 118.959643 -274.871719) (xy 118.960138 -274.896326)
			(xy 119.288826 -274.896326) (xy 119.292786 -274.847272) (xy 119.304563 -274.799488) (xy 119.323854 -274.754212)
			(xy 119.350157 -274.712616) (xy 119.382792 -274.675779) (xy 119.420913 -274.644654) (xy 119.463534 -274.620047)
			(xy 119.50955 -274.602595) (xy 119.557769 -274.592751) (xy 119.606944 -274.59077) (xy 119.655799 -274.596702)
			(xy 119.70307 -274.610394) (xy 119.747532 -274.631492) (xy 119.788035 -274.659448) (xy 119.823528 -274.69354)
			(xy 119.853093 -274.732884) (xy 119.875964 -274.776461) (xy 119.891548 -274.823142) (xy 119.899443 -274.871719)
			(xy 119.899938 -274.896326) (xy 120.22888 -274.896326) (xy 120.23284 -274.847272) (xy 120.244617 -274.799488)
			(xy 120.263908 -274.754212) (xy 120.290211 -274.712616) (xy 120.322846 -274.675779) (xy 120.360967 -274.644654)
			(xy 120.403588 -274.620047) (xy 120.449604 -274.602595) (xy 120.497823 -274.592751) (xy 120.546998 -274.59077)
			(xy 120.595853 -274.596702) (xy 120.643124 -274.610394) (xy 120.687586 -274.631492) (xy 120.728089 -274.659448)
			(xy 120.763582 -274.69354) (xy 120.793147 -274.732884) (xy 120.816018 -274.776461) (xy 120.831602 -274.823142)
			(xy 120.839497 -274.871719) (xy 120.839992 -274.896326) (xy 121.168934 -274.896326) (xy 121.172894 -274.847272)
			(xy 121.184671 -274.799488) (xy 121.203962 -274.754212) (xy 121.230265 -274.712616) (xy 121.2629 -274.675779)
			(xy 121.301021 -274.644654) (xy 121.343642 -274.620047) (xy 121.389658 -274.602595) (xy 121.437877 -274.592751)
			(xy 121.487052 -274.59077) (xy 121.535907 -274.596702) (xy 121.583178 -274.610394) (xy 121.62764 -274.631492)
			(xy 121.668143 -274.659448) (xy 121.703636 -274.69354) (xy 121.733201 -274.732884) (xy 121.756072 -274.776461)
			(xy 121.771656 -274.823142) (xy 121.779551 -274.871719) (xy 121.780046 -274.896326) (xy 122.108988 -274.896326)
			(xy 122.112948 -274.847272) (xy 122.124725 -274.799488) (xy 122.144016 -274.754212) (xy 122.170319 -274.712616)
			(xy 122.202954 -274.675779) (xy 122.241075 -274.644654) (xy 122.283696 -274.620047) (xy 122.329712 -274.602595)
			(xy 122.377931 -274.592751) (xy 122.427106 -274.59077) (xy 122.475961 -274.596702) (xy 122.523232 -274.610394)
			(xy 122.567694 -274.631492) (xy 122.608197 -274.659448) (xy 122.64369 -274.69354) (xy 122.673255 -274.732884)
			(xy 122.696126 -274.776461) (xy 122.71171 -274.823142) (xy 122.719605 -274.871719) (xy 122.7201 -274.896326)
			(xy 123.049042 -274.896326) (xy 123.053002 -274.847272) (xy 123.064779 -274.799488) (xy 123.08407 -274.754212)
			(xy 123.110373 -274.712616) (xy 123.143008 -274.675779) (xy 123.181129 -274.644654) (xy 123.22375 -274.620047)
			(xy 123.269766 -274.602595) (xy 123.317985 -274.592751) (xy 123.36716 -274.59077) (xy 123.416015 -274.596702)
			(xy 123.463286 -274.610394) (xy 123.507748 -274.631492) (xy 123.548251 -274.659448) (xy 123.583744 -274.69354)
			(xy 123.613309 -274.732884) (xy 123.63618 -274.776461) (xy 123.651764 -274.823142) (xy 123.659659 -274.871719)
			(xy 123.660154 -274.896326) (xy 123.988842 -274.896326) (xy 123.992802 -274.847272) (xy 124.004579 -274.799488)
			(xy 124.02387 -274.754212) (xy 124.050173 -274.712616) (xy 124.082808 -274.675779) (xy 124.120929 -274.644654)
			(xy 124.16355 -274.620047) (xy 124.209566 -274.602595) (xy 124.257785 -274.592751) (xy 124.30696 -274.59077)
			(xy 124.355815 -274.596702) (xy 124.403086 -274.610394) (xy 124.447548 -274.631492) (xy 124.488051 -274.659448)
			(xy 124.523544 -274.69354) (xy 124.553109 -274.732884) (xy 124.57598 -274.776461) (xy 124.591564 -274.823142)
			(xy 124.599459 -274.871719) (xy 124.599954 -274.896326) (xy 124.928896 -274.896326) (xy 124.932856 -274.847272)
			(xy 124.944633 -274.799488) (xy 124.963924 -274.754212) (xy 124.990227 -274.712616) (xy 125.022862 -274.675779)
			(xy 125.060983 -274.644654) (xy 125.103604 -274.620047) (xy 125.14962 -274.602595) (xy 125.197839 -274.592751)
			(xy 125.247014 -274.59077) (xy 125.295869 -274.596702) (xy 125.34314 -274.610394) (xy 125.387602 -274.631492)
			(xy 125.428105 -274.659448) (xy 125.463598 -274.69354) (xy 125.493163 -274.732884) (xy 125.516034 -274.776461)
			(xy 125.531618 -274.823142) (xy 125.539513 -274.871719) (xy 125.540008 -274.896326) (xy 125.86895 -274.896326)
			(xy 125.87291 -274.847272) (xy 125.884687 -274.799488) (xy 125.903978 -274.754212) (xy 125.930281 -274.712616)
			(xy 125.962916 -274.675779) (xy 126.001037 -274.644654) (xy 126.043658 -274.620047) (xy 126.089674 -274.602595)
			(xy 126.137893 -274.592751) (xy 126.187068 -274.59077) (xy 126.235923 -274.596702) (xy 126.283194 -274.610394)
			(xy 126.327656 -274.631492) (xy 126.368159 -274.659448) (xy 126.403652 -274.69354) (xy 126.433217 -274.732884)
			(xy 126.456088 -274.776461) (xy 126.471672 -274.823142) (xy 126.479567 -274.871719) (xy 126.480062 -274.896326)
			(xy 126.479567 -274.920933) (xy 126.471672 -274.96951) (xy 126.456088 -275.016191) (xy 126.433217 -275.059768)
			(xy 126.403652 -275.099112) (xy 126.368159 -275.133204) (xy 126.327656 -275.16116) (xy 126.283194 -275.182258)
			(xy 126.235923 -275.19595) (xy 126.187068 -275.201882) (xy 126.137893 -275.199901) (xy 126.089674 -275.190057)
			(xy 126.043658 -275.172605) (xy 126.001037 -275.147998) (xy 125.962916 -275.116873) (xy 125.930281 -275.080036)
			(xy 125.903978 -275.03844) (xy 125.884687 -274.993164) (xy 125.87291 -274.94538) (xy 125.86895 -274.896326)
			(xy 125.540008 -274.896326) (xy 125.539513 -274.920933) (xy 125.531618 -274.96951) (xy 125.516034 -275.016191)
			(xy 125.493163 -275.059768) (xy 125.463598 -275.099112) (xy 125.428105 -275.133204) (xy 125.387602 -275.16116)
			(xy 125.34314 -275.182258) (xy 125.295869 -275.19595) (xy 125.247014 -275.201882) (xy 125.197839 -275.199901)
			(xy 125.14962 -275.190057) (xy 125.103604 -275.172605) (xy 125.060983 -275.147998) (xy 125.022862 -275.116873)
			(xy 124.990227 -275.080036) (xy 124.963924 -275.03844) (xy 124.944633 -274.993164) (xy 124.932856 -274.94538)
			(xy 124.928896 -274.896326) (xy 124.599954 -274.896326) (xy 124.599459 -274.920933) (xy 124.591564 -274.96951)
			(xy 124.57598 -275.016191) (xy 124.553109 -275.059768) (xy 124.523544 -275.099112) (xy 124.488051 -275.133204)
			(xy 124.447548 -275.16116) (xy 124.403086 -275.182258) (xy 124.355815 -275.19595) (xy 124.30696 -275.201882)
			(xy 124.257785 -275.199901) (xy 124.209566 -275.190057) (xy 124.16355 -275.172605) (xy 124.120929 -275.147998)
			(xy 124.082808 -275.116873) (xy 124.050173 -275.080036) (xy 124.02387 -275.03844) (xy 124.004579 -274.993164)
			(xy 123.992802 -274.94538) (xy 123.988842 -274.896326) (xy 123.660154 -274.896326) (xy 123.659659 -274.920933)
			(xy 123.651764 -274.96951) (xy 123.63618 -275.016191) (xy 123.613309 -275.059768) (xy 123.583744 -275.099112)
			(xy 123.548251 -275.133204) (xy 123.507748 -275.16116) (xy 123.463286 -275.182258) (xy 123.416015 -275.19595)
			(xy 123.36716 -275.201882) (xy 123.317985 -275.199901) (xy 123.269766 -275.190057) (xy 123.22375 -275.172605)
			(xy 123.181129 -275.147998) (xy 123.143008 -275.116873) (xy 123.110373 -275.080036) (xy 123.08407 -275.03844)
			(xy 123.064779 -274.993164) (xy 123.053002 -274.94538) (xy 123.049042 -274.896326) (xy 122.7201 -274.896326)
			(xy 122.719605 -274.920933) (xy 122.71171 -274.96951) (xy 122.696126 -275.016191) (xy 122.673255 -275.059768)
			(xy 122.64369 -275.099112) (xy 122.608197 -275.133204) (xy 122.567694 -275.16116) (xy 122.523232 -275.182258)
			(xy 122.475961 -275.19595) (xy 122.427106 -275.201882) (xy 122.377931 -275.199901) (xy 122.329712 -275.190057)
			(xy 122.283696 -275.172605) (xy 122.241075 -275.147998) (xy 122.202954 -275.116873) (xy 122.170319 -275.080036)
			(xy 122.144016 -275.03844) (xy 122.124725 -274.993164) (xy 122.112948 -274.94538) (xy 122.108988 -274.896326)
			(xy 121.780046 -274.896326) (xy 121.779551 -274.920933) (xy 121.771656 -274.96951) (xy 121.756072 -275.016191)
			(xy 121.733201 -275.059768) (xy 121.703636 -275.099112) (xy 121.668143 -275.133204) (xy 121.62764 -275.16116)
			(xy 121.583178 -275.182258) (xy 121.535907 -275.19595) (xy 121.487052 -275.201882) (xy 121.437877 -275.199901)
			(xy 121.389658 -275.190057) (xy 121.343642 -275.172605) (xy 121.301021 -275.147998) (xy 121.2629 -275.116873)
			(xy 121.230265 -275.080036) (xy 121.203962 -275.03844) (xy 121.184671 -274.993164) (xy 121.172894 -274.94538)
			(xy 121.168934 -274.896326) (xy 120.839992 -274.896326) (xy 120.839497 -274.920933) (xy 120.831602 -274.96951)
			(xy 120.816018 -275.016191) (xy 120.793147 -275.059768) (xy 120.763582 -275.099112) (xy 120.728089 -275.133204)
			(xy 120.687586 -275.16116) (xy 120.643124 -275.182258) (xy 120.595853 -275.19595) (xy 120.546998 -275.201882)
			(xy 120.497823 -275.199901) (xy 120.449604 -275.190057) (xy 120.403588 -275.172605) (xy 120.360967 -275.147998)
			(xy 120.322846 -275.116873) (xy 120.290211 -275.080036) (xy 120.263908 -275.03844) (xy 120.244617 -274.993164)
			(xy 120.23284 -274.94538) (xy 120.22888 -274.896326) (xy 119.899938 -274.896326) (xy 119.899443 -274.920933)
			(xy 119.891548 -274.96951) (xy 119.875964 -275.016191) (xy 119.853093 -275.059768) (xy 119.823528 -275.099112)
			(xy 119.788035 -275.133204) (xy 119.747532 -275.16116) (xy 119.70307 -275.182258) (xy 119.655799 -275.19595)
			(xy 119.606944 -275.201882) (xy 119.557769 -275.199901) (xy 119.50955 -275.190057) (xy 119.463534 -275.172605)
			(xy 119.420913 -275.147998) (xy 119.382792 -275.116873) (xy 119.350157 -275.080036) (xy 119.323854 -275.03844)
			(xy 119.304563 -274.993164) (xy 119.292786 -274.94538) (xy 119.288826 -274.896326) (xy 118.960138 -274.896326)
			(xy 118.959643 -274.920933) (xy 118.951748 -274.96951) (xy 118.936164 -275.016191) (xy 118.913293 -275.059768)
			(xy 118.883728 -275.099112) (xy 118.848235 -275.133204) (xy 118.807732 -275.16116) (xy 118.76327 -275.182258)
			(xy 118.715999 -275.19595) (xy 118.667144 -275.201882) (xy 118.617969 -275.199901) (xy 118.56975 -275.190057)
			(xy 118.523734 -275.172605) (xy 118.481113 -275.147998) (xy 118.442992 -275.116873) (xy 118.410357 -275.080036)
			(xy 118.384054 -275.03844) (xy 118.364763 -274.993164) (xy 118.352986 -274.94538) (xy 118.349026 -274.896326)
			(xy 118.020084 -274.896326) (xy 118.019589 -274.920933) (xy 118.011694 -274.96951) (xy 117.99611 -275.016191)
			(xy 117.973239 -275.059768) (xy 117.943674 -275.099112) (xy 117.908181 -275.133204) (xy 117.867678 -275.16116)
			(xy 117.823216 -275.182258) (xy 117.775945 -275.19595) (xy 117.72709 -275.201882) (xy 117.677915 -275.199901)
			(xy 117.629696 -275.190057) (xy 117.58368 -275.172605) (xy 117.541059 -275.147998) (xy 117.502938 -275.116873)
			(xy 117.470303 -275.080036) (xy 117.444 -275.03844) (xy 117.424709 -274.993164) (xy 117.412932 -274.94538)
			(xy 117.408972 -274.896326) (xy 117.08003 -274.896326) (xy 117.079535 -274.920933) (xy 117.07164 -274.96951)
			(xy 117.056056 -275.016191) (xy 117.033185 -275.059768) (xy 117.00362 -275.099112) (xy 116.968127 -275.133204)
			(xy 116.927624 -275.16116) (xy 116.883162 -275.182258) (xy 116.835891 -275.19595) (xy 116.787036 -275.201882)
			(xy 116.737861 -275.199901) (xy 116.689642 -275.190057) (xy 116.643626 -275.172605) (xy 116.601005 -275.147998)
			(xy 116.562884 -275.116873) (xy 116.530249 -275.080036) (xy 116.503946 -275.03844) (xy 116.484655 -274.993164)
			(xy 116.472878 -274.94538) (xy 116.468918 -274.896326) (xy 116.139976 -274.896326) (xy 116.139481 -274.920933)
			(xy 116.131586 -274.96951) (xy 116.116002 -275.016191) (xy 116.093131 -275.059768) (xy 116.063566 -275.099112)
			(xy 116.028073 -275.133204) (xy 115.98757 -275.16116) (xy 115.943108 -275.182258) (xy 115.895837 -275.19595)
			(xy 115.846982 -275.201882) (xy 115.797807 -275.199901) (xy 115.749588 -275.190057) (xy 115.703572 -275.172605)
			(xy 115.660951 -275.147998) (xy 115.62283 -275.116873) (xy 115.590195 -275.080036) (xy 115.563892 -275.03844)
			(xy 115.544601 -274.993164) (xy 115.532824 -274.94538) (xy 115.528864 -274.896326) (xy 108.626402 -274.896326)
			(xy 108.625907 -274.920933) (xy 108.618012 -274.96951) (xy 108.602428 -275.016191) (xy 108.579557 -275.059768)
			(xy 108.549992 -275.099112) (xy 108.514499 -275.133204) (xy 108.473996 -275.16116) (xy 108.429534 -275.182258)
			(xy 108.382263 -275.19595) (xy 108.333408 -275.201882) (xy 108.284233 -275.199901) (xy 108.236014 -275.190057)
			(xy 108.189998 -275.172605) (xy 108.147377 -275.147998) (xy 108.109256 -275.116873) (xy 108.076621 -275.080036)
			(xy 108.050318 -275.03844) (xy 108.031027 -274.993164) (xy 108.01925 -274.94538) (xy 108.01529 -274.896326)
			(xy 107.686348 -274.896326) (xy 107.685853 -274.920933) (xy 107.677958 -274.96951) (xy 107.662374 -275.016191)
			(xy 107.639503 -275.059768) (xy 107.609938 -275.099112) (xy 107.574445 -275.133204) (xy 107.533942 -275.16116)
			(xy 107.48948 -275.182258) (xy 107.442209 -275.19595) (xy 107.393354 -275.201882) (xy 107.344179 -275.199901)
			(xy 107.29596 -275.190057) (xy 107.249944 -275.172605) (xy 107.207323 -275.147998) (xy 107.169202 -275.116873)
			(xy 107.136567 -275.080036) (xy 107.110264 -275.03844) (xy 107.090973 -274.993164) (xy 107.079196 -274.94538)
			(xy 107.075236 -274.896326) (xy 106.746294 -274.896326) (xy 106.745799 -274.920933) (xy 106.737904 -274.96951)
			(xy 106.72232 -275.016191) (xy 106.699449 -275.059768) (xy 106.669884 -275.099112) (xy 106.634391 -275.133204)
			(xy 106.593888 -275.16116) (xy 106.549426 -275.182258) (xy 106.502155 -275.19595) (xy 106.4533 -275.201882)
			(xy 106.404125 -275.199901) (xy 106.355906 -275.190057) (xy 106.30989 -275.172605) (xy 106.267269 -275.147998)
			(xy 106.229148 -275.116873) (xy 106.196513 -275.080036) (xy 106.17021 -275.03844) (xy 106.150919 -274.993164)
			(xy 106.139142 -274.94538) (xy 106.135182 -274.896326) (xy 105.80624 -274.896326) (xy 105.805745 -274.920933)
			(xy 105.79785 -274.96951) (xy 105.782266 -275.016191) (xy 105.759395 -275.059768) (xy 105.72983 -275.099112)
			(xy 105.694337 -275.133204) (xy 105.653834 -275.16116) (xy 105.609372 -275.182258) (xy 105.562101 -275.19595)
			(xy 105.513246 -275.201882) (xy 105.464071 -275.199901) (xy 105.415852 -275.190057) (xy 105.369836 -275.172605)
			(xy 105.327215 -275.147998) (xy 105.289094 -275.116873) (xy 105.256459 -275.080036) (xy 105.230156 -275.03844)
			(xy 105.210865 -274.993164) (xy 105.199088 -274.94538) (xy 105.195128 -274.896326) (xy 104.86644 -274.896326)
			(xy 104.865945 -274.920933) (xy 104.85805 -274.96951) (xy 104.842466 -275.016191) (xy 104.819595 -275.059768)
			(xy 104.79003 -275.099112) (xy 104.754537 -275.133204) (xy 104.714034 -275.16116) (xy 104.669572 -275.182258)
			(xy 104.622301 -275.19595) (xy 104.573446 -275.201882) (xy 104.524271 -275.199901) (xy 104.476052 -275.190057)
			(xy 104.430036 -275.172605) (xy 104.387415 -275.147998) (xy 104.349294 -275.116873) (xy 104.316659 -275.080036)
			(xy 104.290356 -275.03844) (xy 104.271065 -274.993164) (xy 104.259288 -274.94538) (xy 104.255328 -274.896326)
			(xy 103.926386 -274.896326) (xy 103.925891 -274.920933) (xy 103.917996 -274.96951) (xy 103.902412 -275.016191)
			(xy 103.879541 -275.059768) (xy 103.849976 -275.099112) (xy 103.814483 -275.133204) (xy 103.77398 -275.16116)
			(xy 103.729518 -275.182258) (xy 103.682247 -275.19595) (xy 103.633392 -275.201882) (xy 103.584217 -275.199901)
			(xy 103.535998 -275.190057) (xy 103.489982 -275.172605) (xy 103.447361 -275.147998) (xy 103.40924 -275.116873)
			(xy 103.376605 -275.080036) (xy 103.350302 -275.03844) (xy 103.331011 -274.993164) (xy 103.319234 -274.94538)
			(xy 103.315274 -274.896326) (xy 102.986332 -274.896326) (xy 102.985837 -274.920933) (xy 102.977942 -274.96951)
			(xy 102.962358 -275.016191) (xy 102.939487 -275.059768) (xy 102.909922 -275.099112) (xy 102.874429 -275.133204)
			(xy 102.833926 -275.16116) (xy 102.789464 -275.182258) (xy 102.742193 -275.19595) (xy 102.693338 -275.201882)
			(xy 102.644163 -275.199901) (xy 102.595944 -275.190057) (xy 102.549928 -275.172605) (xy 102.507307 -275.147998)
			(xy 102.469186 -275.116873) (xy 102.436551 -275.080036) (xy 102.410248 -275.03844) (xy 102.390957 -274.993164)
			(xy 102.37918 -274.94538) (xy 102.37522 -274.896326) (xy 102.046278 -274.896326) (xy 102.045783 -274.920933)
			(xy 102.037888 -274.96951) (xy 102.022304 -275.016191) (xy 101.999433 -275.059768) (xy 101.969868 -275.099112)
			(xy 101.934375 -275.133204) (xy 101.893872 -275.16116) (xy 101.84941 -275.182258) (xy 101.802139 -275.19595)
			(xy 101.753284 -275.201882) (xy 101.704109 -275.199901) (xy 101.65589 -275.190057) (xy 101.609874 -275.172605)
			(xy 101.567253 -275.147998) (xy 101.529132 -275.116873) (xy 101.496497 -275.080036) (xy 101.470194 -275.03844)
			(xy 101.450903 -274.993164) (xy 101.439126 -274.94538) (xy 101.435166 -274.896326) (xy 101.106478 -274.896326)
			(xy 101.105983 -274.920933) (xy 101.098088 -274.96951) (xy 101.082504 -275.016191) (xy 101.059633 -275.059768)
			(xy 101.030068 -275.099112) (xy 100.994575 -275.133204) (xy 100.954072 -275.16116) (xy 100.90961 -275.182258)
			(xy 100.862339 -275.19595) (xy 100.813484 -275.201882) (xy 100.764309 -275.199901) (xy 100.71609 -275.190057)
			(xy 100.670074 -275.172605) (xy 100.627453 -275.147998) (xy 100.589332 -275.116873) (xy 100.556697 -275.080036)
			(xy 100.530394 -275.03844) (xy 100.511103 -274.993164) (xy 100.499326 -274.94538) (xy 100.495366 -274.896326)
			(xy 100.166424 -274.896326) (xy 100.165929 -274.920933) (xy 100.158034 -274.96951) (xy 100.14245 -275.016191)
			(xy 100.119579 -275.059768) (xy 100.090014 -275.099112) (xy 100.054521 -275.133204) (xy 100.014018 -275.16116)
			(xy 99.969556 -275.182258) (xy 99.922285 -275.19595) (xy 99.87343 -275.201882) (xy 99.824255 -275.199901)
			(xy 99.776036 -275.190057) (xy 99.73002 -275.172605) (xy 99.687399 -275.147998) (xy 99.649278 -275.116873)
			(xy 99.616643 -275.080036) (xy 99.59034 -275.03844) (xy 99.571049 -274.993164) (xy 99.559272 -274.94538)
			(xy 99.555312 -274.896326) (xy 99.22637 -274.896326) (xy 99.225875 -274.920933) (xy 99.21798 -274.96951)
			(xy 99.202396 -275.016191) (xy 99.179525 -275.059768) (xy 99.14996 -275.099112) (xy 99.114467 -275.133204)
			(xy 99.073964 -275.16116) (xy 99.029502 -275.182258) (xy 98.982231 -275.19595) (xy 98.933376 -275.201882)
			(xy 98.884201 -275.199901) (xy 98.835982 -275.190057) (xy 98.789966 -275.172605) (xy 98.747345 -275.147998)
			(xy 98.709224 -275.116873) (xy 98.676589 -275.080036) (xy 98.650286 -275.03844) (xy 98.630995 -274.993164)
			(xy 98.619218 -274.94538) (xy 98.615258 -274.896326) (xy 98.286316 -274.896326) (xy 98.285821 -274.920933)
			(xy 98.277926 -274.96951) (xy 98.262342 -275.016191) (xy 98.239471 -275.059768) (xy 98.209906 -275.099112)
			(xy 98.174413 -275.133204) (xy 98.13391 -275.16116) (xy 98.089448 -275.182258) (xy 98.042177 -275.19595)
			(xy 97.993322 -275.201882) (xy 97.944147 -275.199901) (xy 97.895928 -275.190057) (xy 97.849912 -275.172605)
			(xy 97.807291 -275.147998) (xy 97.76917 -275.116873) (xy 97.736535 -275.080036) (xy 97.710232 -275.03844)
			(xy 97.690941 -274.993164) (xy 97.679164 -274.94538) (xy 97.675204 -274.896326) (xy 97.346262 -274.896326)
			(xy 97.345795 -274.920565) (xy 97.338134 -274.968433) (xy 97.323009 -275.014491) (xy 97.300798 -275.057582)
			(xy 97.272061 -275.096623) (xy 97.237517 -275.130636) (xy 97.198035 -275.158765) (xy 97.154606 -275.180305)
			(xy 97.10832 -275.194716) (xy 97.084388 -275.198586) (xy 97.071942 -275.200364) (xy 97.040954 -275.201888)
			(xy 97.017458 -275.201455) (xy 96.97102 -275.194261) (xy 96.926228 -275.18005) (xy 96.884136 -275.159156)
			(xy 96.845736 -275.13207) (xy 96.811929 -275.09943) (xy 96.797368 -275.080984) (xy 96.795336 -275.07819)
			(xy 96.795082 -275.077936) (xy 96.790942 -275.072566) (xy 96.780385 -275.064067) (xy 96.774254 -275.061172)
			(xy 96.768412 -275.058886) (xy 96.755204 -275.057108) (xy 96.661986 -275.0693) (xy 96.65531 -275.070347)
			(xy 96.642823 -275.075499) (xy 96.637348 -275.07946) (xy 96.63176 -275.083778) (xy 96.62414 -275.094192)
			(xy 96.621346 -275.101304) (xy 96.613467 -275.120875) (xy 96.595158 -275.158887) (xy 96.58477 -275.17725)
			(xy 96.539812 -275.25472) (xy 96.534205 -275.265789) (xy 96.533398 -275.290561) (xy 96.538288 -275.301964)
			(xy 96.552766 -275.331428) (xy 96.576388 -275.378926) (xy 96.57715 -275.380196) (xy 96.579845 -275.384441)
			(xy 96.586626 -275.391863) (xy 96.590612 -275.394928) (xy 96.600518 -275.40204) (xy 96.613218 -275.403818)
			(xy 96.637224 -275.407664) (xy 96.68369 -275.421963) (xy 96.727307 -275.443436) (xy 96.766975 -275.471544)
			(xy 96.801693 -275.505576) (xy 96.830586 -275.544674) (xy 96.852926 -275.587854) (xy 96.868149 -275.634025)
			(xy 96.875871 -275.682024) (xy 96.876362 -275.706332) (xy 99.085158 -275.706332) (xy 99.089118 -275.657278)
			(xy 99.100895 -275.609494) (xy 99.120186 -275.564218) (xy 99.146489 -275.522622) (xy 99.179124 -275.485785)
			(xy 99.217245 -275.45466) (xy 99.259866 -275.430053) (xy 99.305882 -275.412601) (xy 99.354101 -275.402757)
			(xy 99.403276 -275.400776) (xy 99.452131 -275.406708) (xy 99.499402 -275.4204) (xy 99.543864 -275.441498)
			(xy 99.584367 -275.469454) (xy 99.61986 -275.503546) (xy 99.649425 -275.54289) (xy 99.672296 -275.586467)
			(xy 99.68788 -275.633148) (xy 99.695775 -275.681725) (xy 99.69627 -275.706332) (xy 101.90532 -275.706332)
			(xy 101.90928 -275.657278) (xy 101.921057 -275.609494) (xy 101.940348 -275.564218) (xy 101.966651 -275.522622)
			(xy 101.999286 -275.485785) (xy 102.037407 -275.45466) (xy 102.080028 -275.430053) (xy 102.126044 -275.412601)
			(xy 102.174263 -275.402757) (xy 102.223438 -275.400776) (xy 102.272293 -275.406708) (xy 102.319564 -275.4204)
			(xy 102.364026 -275.441498) (xy 102.404529 -275.469454) (xy 102.440022 -275.503546) (xy 102.469587 -275.54289)
			(xy 102.492458 -275.586467) (xy 102.508042 -275.633148) (xy 102.515937 -275.681725) (xy 102.516432 -275.706332)
			(xy 104.725228 -275.706332) (xy 104.729188 -275.657278) (xy 104.740965 -275.609494) (xy 104.760256 -275.564218)
			(xy 104.786559 -275.522622) (xy 104.819194 -275.485785) (xy 104.857315 -275.45466) (xy 104.899936 -275.430053)
			(xy 104.945952 -275.412601) (xy 104.994171 -275.402757) (xy 105.043346 -275.400776) (xy 105.092201 -275.406708)
			(xy 105.139472 -275.4204) (xy 105.183934 -275.441498) (xy 105.224437 -275.469454) (xy 105.25993 -275.503546)
			(xy 105.289495 -275.54289) (xy 105.312366 -275.586467) (xy 105.32795 -275.633148) (xy 105.335845 -275.681725)
			(xy 105.33634 -275.706332) (xy 107.545136 -275.706332) (xy 107.549096 -275.657278) (xy 107.560873 -275.609494)
			(xy 107.580164 -275.564218) (xy 107.606467 -275.522622) (xy 107.639102 -275.485785) (xy 107.677223 -275.45466)
			(xy 107.719844 -275.430053) (xy 107.76586 -275.412601) (xy 107.814079 -275.402757) (xy 107.863254 -275.400776)
			(xy 107.912109 -275.406708) (xy 107.95938 -275.4204) (xy 108.003842 -275.441498) (xy 108.044345 -275.469454)
			(xy 108.079838 -275.503546) (xy 108.109403 -275.54289) (xy 108.132274 -275.586467) (xy 108.147858 -275.633148)
			(xy 108.155753 -275.681725) (xy 108.156248 -275.706332) (xy 108.48519 -275.706332) (xy 108.48915 -275.657278)
			(xy 108.500927 -275.609494) (xy 108.520218 -275.564218) (xy 108.546521 -275.522622) (xy 108.579156 -275.485785)
			(xy 108.617277 -275.45466) (xy 108.659898 -275.430053) (xy 108.705914 -275.412601) (xy 108.754133 -275.402757)
			(xy 108.803308 -275.400776) (xy 108.852163 -275.406708) (xy 108.899434 -275.4204) (xy 108.943896 -275.441498)
			(xy 108.984399 -275.469454) (xy 109.019892 -275.503546) (xy 109.049457 -275.54289) (xy 109.072328 -275.586467)
			(xy 109.087912 -275.633148) (xy 109.095807 -275.681725) (xy 109.096302 -275.706332) (xy 109.425244 -275.706332)
			(xy 109.429204 -275.657278) (xy 109.440981 -275.609494) (xy 109.460272 -275.564218) (xy 109.486575 -275.522622)
			(xy 109.51921 -275.485785) (xy 109.557331 -275.45466) (xy 109.599952 -275.430053) (xy 109.645968 -275.412601)
			(xy 109.694187 -275.402757) (xy 109.743362 -275.400776) (xy 109.792217 -275.406708) (xy 109.839488 -275.4204)
			(xy 109.88395 -275.441498) (xy 109.924453 -275.469454) (xy 109.959946 -275.503546) (xy 109.989511 -275.54289)
			(xy 110.012382 -275.586467) (xy 110.027966 -275.633148) (xy 110.035861 -275.681725) (xy 110.036356 -275.706332)
			(xy 110.365298 -275.706332) (xy 110.369258 -275.657278) (xy 110.381035 -275.609494) (xy 110.400326 -275.564218)
			(xy 110.426629 -275.522622) (xy 110.459264 -275.485785) (xy 110.497385 -275.45466) (xy 110.540006 -275.430053)
			(xy 110.586022 -275.412601) (xy 110.634241 -275.402757) (xy 110.683416 -275.400776) (xy 110.732271 -275.406708)
			(xy 110.779542 -275.4204) (xy 110.824004 -275.441498) (xy 110.864507 -275.469454) (xy 110.9 -275.503546)
			(xy 110.929565 -275.54289) (xy 110.952436 -275.586467) (xy 110.96802 -275.633148) (xy 110.975915 -275.681725)
			(xy 110.97641 -275.706332) (xy 113.178856 -275.706332) (xy 113.182816 -275.657278) (xy 113.194593 -275.609494)
			(xy 113.213884 -275.564218) (xy 113.240187 -275.522622) (xy 113.272822 -275.485785) (xy 113.310943 -275.45466)
			(xy 113.353564 -275.430053) (xy 113.39958 -275.412601) (xy 113.447799 -275.402757) (xy 113.496974 -275.400776)
			(xy 113.545829 -275.406708) (xy 113.5931 -275.4204) (xy 113.637562 -275.441498) (xy 113.678065 -275.469454)
			(xy 113.713558 -275.503546) (xy 113.743123 -275.54289) (xy 113.765994 -275.586467) (xy 113.781578 -275.633148)
			(xy 113.789473 -275.681725) (xy 113.789968 -275.706332) (xy 114.11891 -275.706332) (xy 114.12287 -275.657278)
			(xy 114.134647 -275.609494) (xy 114.153938 -275.564218) (xy 114.180241 -275.522622) (xy 114.212876 -275.485785)
			(xy 114.250997 -275.45466) (xy 114.293618 -275.430053) (xy 114.339634 -275.412601) (xy 114.387853 -275.402757)
			(xy 114.437028 -275.400776) (xy 114.485883 -275.406708) (xy 114.533154 -275.4204) (xy 114.577616 -275.441498)
			(xy 114.618119 -275.469454) (xy 114.653612 -275.503546) (xy 114.683177 -275.54289) (xy 114.706048 -275.586467)
			(xy 114.721632 -275.633148) (xy 114.729527 -275.681725) (xy 114.730022 -275.706332) (xy 115.058964 -275.706332)
			(xy 115.062924 -275.657278) (xy 115.074701 -275.609494) (xy 115.093992 -275.564218) (xy 115.120295 -275.522622)
			(xy 115.15293 -275.485785) (xy 115.191051 -275.45466) (xy 115.233672 -275.430053) (xy 115.279688 -275.412601)
			(xy 115.327907 -275.402757) (xy 115.377082 -275.400776) (xy 115.425937 -275.406708) (xy 115.473208 -275.4204)
			(xy 115.51767 -275.441498) (xy 115.558173 -275.469454) (xy 115.593666 -275.503546) (xy 115.623231 -275.54289)
			(xy 115.646102 -275.586467) (xy 115.661686 -275.633148) (xy 115.669581 -275.681725) (xy 115.670076 -275.706332)
			(xy 115.999018 -275.706332) (xy 116.002978 -275.657278) (xy 116.014755 -275.609494) (xy 116.034046 -275.564218)
			(xy 116.060349 -275.522622) (xy 116.092984 -275.485785) (xy 116.131105 -275.45466) (xy 116.173726 -275.430053)
			(xy 116.219742 -275.412601) (xy 116.267961 -275.402757) (xy 116.317136 -275.400776) (xy 116.365991 -275.406708)
			(xy 116.413262 -275.4204) (xy 116.457724 -275.441498) (xy 116.498227 -275.469454) (xy 116.53372 -275.503546)
			(xy 116.563285 -275.54289) (xy 116.586156 -275.586467) (xy 116.60174 -275.633148) (xy 116.609635 -275.681725)
			(xy 116.61013 -275.706332) (xy 118.818926 -275.706332) (xy 118.822886 -275.657278) (xy 118.834663 -275.609494)
			(xy 118.853954 -275.564218) (xy 118.880257 -275.522622) (xy 118.912892 -275.485785) (xy 118.951013 -275.45466)
			(xy 118.993634 -275.430053) (xy 119.03965 -275.412601) (xy 119.087869 -275.402757) (xy 119.137044 -275.400776)
			(xy 119.185899 -275.406708) (xy 119.23317 -275.4204) (xy 119.277632 -275.441498) (xy 119.318135 -275.469454)
			(xy 119.353628 -275.503546) (xy 119.383193 -275.54289) (xy 119.406064 -275.586467) (xy 119.421648 -275.633148)
			(xy 119.429543 -275.681725) (xy 119.430038 -275.706332) (xy 121.638834 -275.706332) (xy 121.642794 -275.657278)
			(xy 121.654571 -275.609494) (xy 121.673862 -275.564218) (xy 121.700165 -275.522622) (xy 121.7328 -275.485785)
			(xy 121.770921 -275.45466) (xy 121.813542 -275.430053) (xy 121.859558 -275.412601) (xy 121.907777 -275.402757)
			(xy 121.956952 -275.400776) (xy 122.005807 -275.406708) (xy 122.053078 -275.4204) (xy 122.09754 -275.441498)
			(xy 122.138043 -275.469454) (xy 122.173536 -275.503546) (xy 122.203101 -275.54289) (xy 122.225972 -275.586467)
			(xy 122.241556 -275.633148) (xy 122.249451 -275.681725) (xy 122.249946 -275.706332) (xy 124.458996 -275.706332)
			(xy 124.462956 -275.657278) (xy 124.474733 -275.609494) (xy 124.494024 -275.564218) (xy 124.520327 -275.522622)
			(xy 124.552962 -275.485785) (xy 124.591083 -275.45466) (xy 124.633704 -275.430053) (xy 124.67972 -275.412601)
			(xy 124.727939 -275.402757) (xy 124.777114 -275.400776) (xy 124.825969 -275.406708) (xy 124.87324 -275.4204)
			(xy 124.917702 -275.441498) (xy 124.958205 -275.469454) (xy 124.993698 -275.503546) (xy 125.023263 -275.54289)
			(xy 125.046134 -275.586467) (xy 125.061718 -275.633148) (xy 125.069613 -275.681725) (xy 125.070108 -275.706332)
			(xy 125.069613 -275.730939) (xy 125.061718 -275.779516) (xy 125.046134 -275.826197) (xy 125.023263 -275.869774)
			(xy 124.993698 -275.909118) (xy 124.958205 -275.94321) (xy 124.917702 -275.971166) (xy 124.87324 -275.992264)
			(xy 124.825969 -276.005956) (xy 124.777114 -276.011888) (xy 124.727939 -276.009907) (xy 124.67972 -276.000063)
			(xy 124.633704 -275.982611) (xy 124.591083 -275.958004) (xy 124.552962 -275.926879) (xy 124.520327 -275.890042)
			(xy 124.494024 -275.848446) (xy 124.474733 -275.80317) (xy 124.462956 -275.755386) (xy 124.458996 -275.706332)
			(xy 122.249946 -275.706332) (xy 122.249451 -275.730939) (xy 122.241556 -275.779516) (xy 122.225972 -275.826197)
			(xy 122.203101 -275.869774) (xy 122.173536 -275.909118) (xy 122.138043 -275.94321) (xy 122.09754 -275.971166)
			(xy 122.053078 -275.992264) (xy 122.005807 -276.005956) (xy 121.956952 -276.011888) (xy 121.907777 -276.009907)
			(xy 121.859558 -276.000063) (xy 121.813542 -275.982611) (xy 121.770921 -275.958004) (xy 121.7328 -275.926879)
			(xy 121.700165 -275.890042) (xy 121.673862 -275.848446) (xy 121.654571 -275.80317) (xy 121.642794 -275.755386)
			(xy 121.638834 -275.706332) (xy 119.430038 -275.706332) (xy 119.429543 -275.730939) (xy 119.421648 -275.779516)
			(xy 119.406064 -275.826197) (xy 119.383193 -275.869774) (xy 119.353628 -275.909118) (xy 119.318135 -275.94321)
			(xy 119.277632 -275.971166) (xy 119.23317 -275.992264) (xy 119.185899 -276.005956) (xy 119.137044 -276.011888)
			(xy 119.087869 -276.009907) (xy 119.03965 -276.000063) (xy 118.993634 -275.982611) (xy 118.951013 -275.958004)
			(xy 118.912892 -275.926879) (xy 118.880257 -275.890042) (xy 118.853954 -275.848446) (xy 118.834663 -275.80317)
			(xy 118.822886 -275.755386) (xy 118.818926 -275.706332) (xy 116.61013 -275.706332) (xy 116.609635 -275.730939)
			(xy 116.60174 -275.779516) (xy 116.586156 -275.826197) (xy 116.563285 -275.869774) (xy 116.53372 -275.909118)
			(xy 116.498227 -275.94321) (xy 116.457724 -275.971166) (xy 116.413262 -275.992264) (xy 116.365991 -276.005956)
			(xy 116.317136 -276.011888) (xy 116.267961 -276.009907) (xy 116.219742 -276.000063) (xy 116.173726 -275.982611)
			(xy 116.131105 -275.958004) (xy 116.092984 -275.926879) (xy 116.060349 -275.890042) (xy 116.034046 -275.848446)
			(xy 116.014755 -275.80317) (xy 116.002978 -275.755386) (xy 115.999018 -275.706332) (xy 115.670076 -275.706332)
			(xy 115.669581 -275.730939) (xy 115.661686 -275.779516) (xy 115.646102 -275.826197) (xy 115.623231 -275.869774)
			(xy 115.593666 -275.909118) (xy 115.558173 -275.94321) (xy 115.51767 -275.971166) (xy 115.473208 -275.992264)
			(xy 115.425937 -276.005956) (xy 115.377082 -276.011888) (xy 115.327907 -276.009907) (xy 115.279688 -276.000063)
			(xy 115.233672 -275.982611) (xy 115.191051 -275.958004) (xy 115.15293 -275.926879) (xy 115.120295 -275.890042)
			(xy 115.093992 -275.848446) (xy 115.074701 -275.80317) (xy 115.062924 -275.755386) (xy 115.058964 -275.706332)
			(xy 114.730022 -275.706332) (xy 114.729527 -275.730939) (xy 114.721632 -275.779516) (xy 114.706048 -275.826197)
			(xy 114.683177 -275.869774) (xy 114.653612 -275.909118) (xy 114.618119 -275.94321) (xy 114.577616 -275.971166)
			(xy 114.533154 -275.992264) (xy 114.485883 -276.005956) (xy 114.437028 -276.011888) (xy 114.387853 -276.009907)
			(xy 114.339634 -276.000063) (xy 114.293618 -275.982611) (xy 114.250997 -275.958004) (xy 114.212876 -275.926879)
			(xy 114.180241 -275.890042) (xy 114.153938 -275.848446) (xy 114.134647 -275.80317) (xy 114.12287 -275.755386)
			(xy 114.11891 -275.706332) (xy 113.789968 -275.706332) (xy 113.789473 -275.730939) (xy 113.781578 -275.779516)
			(xy 113.765994 -275.826197) (xy 113.743123 -275.869774) (xy 113.713558 -275.909118) (xy 113.678065 -275.94321)
			(xy 113.637562 -275.971166) (xy 113.5931 -275.992264) (xy 113.545829 -276.005956) (xy 113.496974 -276.011888)
			(xy 113.447799 -276.009907) (xy 113.39958 -276.000063) (xy 113.353564 -275.982611) (xy 113.310943 -275.958004)
			(xy 113.272822 -275.926879) (xy 113.240187 -275.890042) (xy 113.213884 -275.848446) (xy 113.194593 -275.80317)
			(xy 113.182816 -275.755386) (xy 113.178856 -275.706332) (xy 110.97641 -275.706332) (xy 110.975915 -275.730939)
			(xy 110.96802 -275.779516) (xy 110.952436 -275.826197) (xy 110.929565 -275.869774) (xy 110.9 -275.909118)
			(xy 110.864507 -275.94321) (xy 110.824004 -275.971166) (xy 110.779542 -275.992264) (xy 110.732271 -276.005956)
			(xy 110.683416 -276.011888) (xy 110.634241 -276.009907) (xy 110.586022 -276.000063) (xy 110.540006 -275.982611)
			(xy 110.497385 -275.958004) (xy 110.459264 -275.926879) (xy 110.426629 -275.890042) (xy 110.400326 -275.848446)
			(xy 110.381035 -275.80317) (xy 110.369258 -275.755386) (xy 110.365298 -275.706332) (xy 110.036356 -275.706332)
			(xy 110.035861 -275.730939) (xy 110.027966 -275.779516) (xy 110.012382 -275.826197) (xy 109.989511 -275.869774)
			(xy 109.959946 -275.909118) (xy 109.924453 -275.94321) (xy 109.88395 -275.971166) (xy 109.839488 -275.992264)
			(xy 109.792217 -276.005956) (xy 109.743362 -276.011888) (xy 109.694187 -276.009907) (xy 109.645968 -276.000063)
			(xy 109.599952 -275.982611) (xy 109.557331 -275.958004) (xy 109.51921 -275.926879) (xy 109.486575 -275.890042)
			(xy 109.460272 -275.848446) (xy 109.440981 -275.80317) (xy 109.429204 -275.755386) (xy 109.425244 -275.706332)
			(xy 109.096302 -275.706332) (xy 109.095807 -275.730939) (xy 109.087912 -275.779516) (xy 109.072328 -275.826197)
			(xy 109.049457 -275.869774) (xy 109.019892 -275.909118) (xy 108.984399 -275.94321) (xy 108.943896 -275.971166)
			(xy 108.899434 -275.992264) (xy 108.852163 -276.005956) (xy 108.803308 -276.011888) (xy 108.754133 -276.009907)
			(xy 108.705914 -276.000063) (xy 108.659898 -275.982611) (xy 108.617277 -275.958004) (xy 108.579156 -275.926879)
			(xy 108.546521 -275.890042) (xy 108.520218 -275.848446) (xy 108.500927 -275.80317) (xy 108.48915 -275.755386)
			(xy 108.48519 -275.706332) (xy 108.156248 -275.706332) (xy 108.155753 -275.730939) (xy 108.147858 -275.779516)
			(xy 108.132274 -275.826197) (xy 108.109403 -275.869774) (xy 108.079838 -275.909118) (xy 108.044345 -275.94321)
			(xy 108.003842 -275.971166) (xy 107.95938 -275.992264) (xy 107.912109 -276.005956) (xy 107.863254 -276.011888)
			(xy 107.814079 -276.009907) (xy 107.76586 -276.000063) (xy 107.719844 -275.982611) (xy 107.677223 -275.958004)
			(xy 107.639102 -275.926879) (xy 107.606467 -275.890042) (xy 107.580164 -275.848446) (xy 107.560873 -275.80317)
			(xy 107.549096 -275.755386) (xy 107.545136 -275.706332) (xy 105.33634 -275.706332) (xy 105.335845 -275.730939)
			(xy 105.32795 -275.779516) (xy 105.312366 -275.826197) (xy 105.289495 -275.869774) (xy 105.25993 -275.909118)
			(xy 105.224437 -275.94321) (xy 105.183934 -275.971166) (xy 105.139472 -275.992264) (xy 105.092201 -276.005956)
			(xy 105.043346 -276.011888) (xy 104.994171 -276.009907) (xy 104.945952 -276.000063) (xy 104.899936 -275.982611)
			(xy 104.857315 -275.958004) (xy 104.819194 -275.926879) (xy 104.786559 -275.890042) (xy 104.760256 -275.848446)
			(xy 104.740965 -275.80317) (xy 104.729188 -275.755386) (xy 104.725228 -275.706332) (xy 102.516432 -275.706332)
			(xy 102.515937 -275.730939) (xy 102.508042 -275.779516) (xy 102.492458 -275.826197) (xy 102.469587 -275.869774)
			(xy 102.440022 -275.909118) (xy 102.404529 -275.94321) (xy 102.364026 -275.971166) (xy 102.319564 -275.992264)
			(xy 102.272293 -276.005956) (xy 102.223438 -276.011888) (xy 102.174263 -276.009907) (xy 102.126044 -276.000063)
			(xy 102.080028 -275.982611) (xy 102.037407 -275.958004) (xy 101.999286 -275.926879) (xy 101.966651 -275.890042)
			(xy 101.940348 -275.848446) (xy 101.921057 -275.80317) (xy 101.90928 -275.755386) (xy 101.90532 -275.706332)
			(xy 99.69627 -275.706332) (xy 99.695775 -275.730939) (xy 99.68788 -275.779516) (xy 99.672296 -275.826197)
			(xy 99.649425 -275.869774) (xy 99.61986 -275.909118) (xy 99.584367 -275.94321) (xy 99.543864 -275.971166)
			(xy 99.499402 -275.992264) (xy 99.452131 -276.005956) (xy 99.403276 -276.011888) (xy 99.354101 -276.009907)
			(xy 99.305882 -276.000063) (xy 99.259866 -275.982611) (xy 99.217245 -275.958004) (xy 99.179124 -275.926879)
			(xy 99.146489 -275.890042) (xy 99.120186 -275.848446) (xy 99.100895 -275.80317) (xy 99.089118 -275.755386)
			(xy 99.085158 -275.706332) (xy 96.876362 -275.706332) (xy 96.875898 -275.730939) (xy 96.868012 -275.779516)
			(xy 96.852432 -275.826199) (xy 96.829563 -275.869776) (xy 96.799998 -275.909119) (xy 96.764502 -275.943207)
			(xy 96.723996 -275.971158) (xy 96.67953 -275.992246) (xy 96.632255 -276.005926) (xy 96.607884 -276.009354)
			(xy 96.60509 -276.009608) (xy 96.599041 -276.01088) (xy 96.587745 -276.015889) (xy 96.582738 -276.019514)
			(xy 96.577658 -276.023324) (xy 96.573848 -276.028404) (xy 96.567244 -276.039834) (xy 96.533208 -276.122384)
			(xy 96.531267 -276.128274) (xy 96.529985 -276.140605) (xy 96.530668 -276.146768) (xy 96.532446 -276.159722)
			(xy 96.541082 -276.170898) (xy 96.565552 -276.203379) (xy 96.605841 -276.274018) (xy 96.621346 -276.311614)
			(xy 96.62414 -276.318472) (xy 96.63176 -276.328886) (xy 96.637348 -276.333204) (xy 96.642019 -276.336637)
			(xy 96.652538 -276.341505) (xy 96.658176 -276.342856) (xy 96.75114 -276.355048) (xy 96.754912 -276.355225)
			(xy 96.762436 -276.354581) (xy 96.766126 -276.353778) (xy 96.77527 -276.350984) (xy 96.787208 -276.34565)
			(xy 96.788478 -276.343872) (xy 96.795336 -276.334728) (xy 96.79559 -276.33422) (xy 96.810127 -276.315448)
			(xy 96.844027 -276.282209) (xy 96.882658 -276.25461) (xy 96.925091 -276.233315) (xy 96.970306 -276.218835)
			(xy 97.017215 -276.211519) (xy 97.040954 -276.21103) (xy 97.064948 -276.211473) (xy 97.112347 -276.218974)
			(xy 97.157989 -276.233799) (xy 97.200748 -276.255583) (xy 97.239573 -276.283788) (xy 97.273507 -276.317721)
			(xy 97.301713 -276.356545) (xy 97.323498 -276.399304) (xy 97.338324 -276.444945) (xy 97.345827 -276.492344)
			(xy 97.346262 -276.516338) (xy 97.675204 -276.516338) (xy 97.679164 -276.467284) (xy 97.690941 -276.4195)
			(xy 97.710232 -276.374224) (xy 97.736535 -276.332628) (xy 97.76917 -276.295791) (xy 97.807291 -276.264666)
			(xy 97.849912 -276.240059) (xy 97.895928 -276.222607) (xy 97.944147 -276.212763) (xy 97.993322 -276.210782)
			(xy 98.042177 -276.216714) (xy 98.089448 -276.230406) (xy 98.13391 -276.251504) (xy 98.174413 -276.27946)
			(xy 98.209906 -276.313552) (xy 98.239471 -276.352896) (xy 98.262342 -276.396473) (xy 98.277926 -276.443154)
			(xy 98.285821 -276.491731) (xy 98.286316 -276.516338) (xy 98.615258 -276.516338) (xy 98.619218 -276.467284)
			(xy 98.630995 -276.4195) (xy 98.650286 -276.374224) (xy 98.676589 -276.332628) (xy 98.709224 -276.295791)
			(xy 98.747345 -276.264666) (xy 98.789966 -276.240059) (xy 98.835982 -276.222607) (xy 98.884201 -276.212763)
			(xy 98.933376 -276.210782) (xy 98.982231 -276.216714) (xy 99.029502 -276.230406) (xy 99.073964 -276.251504)
			(xy 99.114467 -276.27946) (xy 99.14996 -276.313552) (xy 99.179525 -276.352896) (xy 99.202396 -276.396473)
			(xy 99.21798 -276.443154) (xy 99.225875 -276.491731) (xy 99.22637 -276.516338) (xy 99.555312 -276.516338)
			(xy 99.559272 -276.467284) (xy 99.571049 -276.4195) (xy 99.59034 -276.374224) (xy 99.616643 -276.332628)
			(xy 99.649278 -276.295791) (xy 99.687399 -276.264666) (xy 99.73002 -276.240059) (xy 99.776036 -276.222607)
			(xy 99.824255 -276.212763) (xy 99.87343 -276.210782) (xy 99.922285 -276.216714) (xy 99.969556 -276.230406)
			(xy 100.014018 -276.251504) (xy 100.054521 -276.27946) (xy 100.090014 -276.313552) (xy 100.119579 -276.352896)
			(xy 100.14245 -276.396473) (xy 100.158034 -276.443154) (xy 100.165929 -276.491731) (xy 100.166424 -276.516338)
			(xy 100.495366 -276.516338) (xy 100.499326 -276.467284) (xy 100.511103 -276.4195) (xy 100.530394 -276.374224)
			(xy 100.556697 -276.332628) (xy 100.589332 -276.295791) (xy 100.627453 -276.264666) (xy 100.670074 -276.240059)
			(xy 100.71609 -276.222607) (xy 100.764309 -276.212763) (xy 100.813484 -276.210782) (xy 100.862339 -276.216714)
			(xy 100.90961 -276.230406) (xy 100.954072 -276.251504) (xy 100.994575 -276.27946) (xy 101.030068 -276.313552)
			(xy 101.059633 -276.352896) (xy 101.082504 -276.396473) (xy 101.098088 -276.443154) (xy 101.105983 -276.491731)
			(xy 101.106478 -276.516338) (xy 101.435166 -276.516338) (xy 101.439126 -276.467284) (xy 101.450903 -276.4195)
			(xy 101.470194 -276.374224) (xy 101.496497 -276.332628) (xy 101.529132 -276.295791) (xy 101.567253 -276.264666)
			(xy 101.609874 -276.240059) (xy 101.65589 -276.222607) (xy 101.704109 -276.212763) (xy 101.753284 -276.210782)
			(xy 101.802139 -276.216714) (xy 101.84941 -276.230406) (xy 101.893872 -276.251504) (xy 101.934375 -276.27946)
			(xy 101.969868 -276.313552) (xy 101.999433 -276.352896) (xy 102.022304 -276.396473) (xy 102.037888 -276.443154)
			(xy 102.045783 -276.491731) (xy 102.046278 -276.516338) (xy 102.37522 -276.516338) (xy 102.37918 -276.467284)
			(xy 102.390957 -276.4195) (xy 102.410248 -276.374224) (xy 102.436551 -276.332628) (xy 102.469186 -276.295791)
			(xy 102.507307 -276.264666) (xy 102.549928 -276.240059) (xy 102.595944 -276.222607) (xy 102.644163 -276.212763)
			(xy 102.693338 -276.210782) (xy 102.742193 -276.216714) (xy 102.789464 -276.230406) (xy 102.833926 -276.251504)
			(xy 102.874429 -276.27946) (xy 102.909922 -276.313552) (xy 102.939487 -276.352896) (xy 102.962358 -276.396473)
			(xy 102.977942 -276.443154) (xy 102.985837 -276.491731) (xy 102.986332 -276.516338) (xy 103.315274 -276.516338)
			(xy 103.319234 -276.467284) (xy 103.331011 -276.4195) (xy 103.350302 -276.374224) (xy 103.376605 -276.332628)
			(xy 103.40924 -276.295791) (xy 103.447361 -276.264666) (xy 103.489982 -276.240059) (xy 103.535998 -276.222607)
			(xy 103.584217 -276.212763) (xy 103.633392 -276.210782) (xy 103.682247 -276.216714) (xy 103.729518 -276.230406)
			(xy 103.77398 -276.251504) (xy 103.814483 -276.27946) (xy 103.849976 -276.313552) (xy 103.879541 -276.352896)
			(xy 103.902412 -276.396473) (xy 103.917996 -276.443154) (xy 103.925891 -276.491731) (xy 103.926386 -276.516338)
			(xy 104.255328 -276.516338) (xy 104.259288 -276.467284) (xy 104.271065 -276.4195) (xy 104.290356 -276.374224)
			(xy 104.316659 -276.332628) (xy 104.349294 -276.295791) (xy 104.387415 -276.264666) (xy 104.430036 -276.240059)
			(xy 104.476052 -276.222607) (xy 104.524271 -276.212763) (xy 104.573446 -276.210782) (xy 104.622301 -276.216714)
			(xy 104.669572 -276.230406) (xy 104.714034 -276.251504) (xy 104.754537 -276.27946) (xy 104.79003 -276.313552)
			(xy 104.819595 -276.352896) (xy 104.842466 -276.396473) (xy 104.85805 -276.443154) (xy 104.865945 -276.491731)
			(xy 104.86644 -276.516338) (xy 105.195128 -276.516338) (xy 105.199088 -276.467284) (xy 105.210865 -276.4195)
			(xy 105.230156 -276.374224) (xy 105.256459 -276.332628) (xy 105.289094 -276.295791) (xy 105.327215 -276.264666)
			(xy 105.369836 -276.240059) (xy 105.415852 -276.222607) (xy 105.464071 -276.212763) (xy 105.513246 -276.210782)
			(xy 105.562101 -276.216714) (xy 105.609372 -276.230406) (xy 105.653834 -276.251504) (xy 105.694337 -276.27946)
			(xy 105.72983 -276.313552) (xy 105.759395 -276.352896) (xy 105.782266 -276.396473) (xy 105.79785 -276.443154)
			(xy 105.805745 -276.491731) (xy 105.80624 -276.516338) (xy 106.135182 -276.516338) (xy 106.139142 -276.467284)
			(xy 106.150919 -276.4195) (xy 106.17021 -276.374224) (xy 106.196513 -276.332628) (xy 106.229148 -276.295791)
			(xy 106.267269 -276.264666) (xy 106.30989 -276.240059) (xy 106.355906 -276.222607) (xy 106.404125 -276.212763)
			(xy 106.4533 -276.210782) (xy 106.502155 -276.216714) (xy 106.549426 -276.230406) (xy 106.593888 -276.251504)
			(xy 106.634391 -276.27946) (xy 106.669884 -276.313552) (xy 106.699449 -276.352896) (xy 106.72232 -276.396473)
			(xy 106.737904 -276.443154) (xy 106.745799 -276.491731) (xy 106.746294 -276.516338) (xy 107.075236 -276.516338)
			(xy 107.079196 -276.467284) (xy 107.090973 -276.4195) (xy 107.110264 -276.374224) (xy 107.136567 -276.332628)
			(xy 107.169202 -276.295791) (xy 107.207323 -276.264666) (xy 107.249944 -276.240059) (xy 107.29596 -276.222607)
			(xy 107.344179 -276.212763) (xy 107.393354 -276.210782) (xy 107.442209 -276.216714) (xy 107.48948 -276.230406)
			(xy 107.533942 -276.251504) (xy 107.574445 -276.27946) (xy 107.609938 -276.313552) (xy 107.639503 -276.352896)
			(xy 107.662374 -276.396473) (xy 107.677958 -276.443154) (xy 107.685853 -276.491731) (xy 107.686348 -276.516338)
			(xy 108.01529 -276.516338) (xy 108.01925 -276.467284) (xy 108.031027 -276.4195) (xy 108.050318 -276.374224)
			(xy 108.076621 -276.332628) (xy 108.109256 -276.295791) (xy 108.147377 -276.264666) (xy 108.189998 -276.240059)
			(xy 108.236014 -276.222607) (xy 108.284233 -276.212763) (xy 108.333408 -276.210782) (xy 108.382263 -276.216714)
			(xy 108.429534 -276.230406) (xy 108.473996 -276.251504) (xy 108.514499 -276.27946) (xy 108.549992 -276.313552)
			(xy 108.579557 -276.352896) (xy 108.602428 -276.396473) (xy 108.618012 -276.443154) (xy 108.625907 -276.491731)
			(xy 108.626402 -276.516338) (xy 108.955344 -276.516338) (xy 108.959304 -276.467284) (xy 108.971081 -276.4195)
			(xy 108.990372 -276.374224) (xy 109.016675 -276.332628) (xy 109.04931 -276.295791) (xy 109.087431 -276.264666)
			(xy 109.130052 -276.240059) (xy 109.176068 -276.222607) (xy 109.224287 -276.212763) (xy 109.273462 -276.210782)
			(xy 109.322317 -276.216714) (xy 109.369588 -276.230406) (xy 109.41405 -276.251504) (xy 109.454553 -276.27946)
			(xy 109.490046 -276.313552) (xy 109.519611 -276.352896) (xy 109.542482 -276.396473) (xy 109.558066 -276.443154)
			(xy 109.565961 -276.491731) (xy 109.566456 -276.516338) (xy 109.895144 -276.516338) (xy 109.899104 -276.467284)
			(xy 109.910881 -276.4195) (xy 109.930172 -276.374224) (xy 109.956475 -276.332628) (xy 109.98911 -276.295791)
			(xy 110.027231 -276.264666) (xy 110.069852 -276.240059) (xy 110.115868 -276.222607) (xy 110.164087 -276.212763)
			(xy 110.213262 -276.210782) (xy 110.262117 -276.216714) (xy 110.309388 -276.230406) (xy 110.35385 -276.251504)
			(xy 110.394353 -276.27946) (xy 110.429846 -276.313552) (xy 110.459411 -276.352896) (xy 110.482282 -276.396473)
			(xy 110.497866 -276.443154) (xy 110.505761 -276.491731) (xy 110.506256 -276.516338) (xy 113.64901 -276.516338)
			(xy 113.65297 -276.467284) (xy 113.664747 -276.4195) (xy 113.684038 -276.374224) (xy 113.710341 -276.332628)
			(xy 113.742976 -276.295791) (xy 113.781097 -276.264666) (xy 113.823718 -276.240059) (xy 113.869734 -276.222607)
			(xy 113.917953 -276.212763) (xy 113.967128 -276.210782) (xy 114.015983 -276.216714) (xy 114.063254 -276.230406)
			(xy 114.107716 -276.251504) (xy 114.148219 -276.27946) (xy 114.183712 -276.313552) (xy 114.213277 -276.352896)
			(xy 114.236148 -276.396473) (xy 114.251732 -276.443154) (xy 114.259627 -276.491731) (xy 114.260122 -276.516338)
			(xy 114.58881 -276.516338) (xy 114.59277 -276.467284) (xy 114.604547 -276.4195) (xy 114.623838 -276.374224)
			(xy 114.650141 -276.332628) (xy 114.682776 -276.295791) (xy 114.720897 -276.264666) (xy 114.763518 -276.240059)
			(xy 114.809534 -276.222607) (xy 114.857753 -276.212763) (xy 114.906928 -276.210782) (xy 114.955783 -276.216714)
			(xy 115.003054 -276.230406) (xy 115.047516 -276.251504) (xy 115.088019 -276.27946) (xy 115.123512 -276.313552)
			(xy 115.153077 -276.352896) (xy 115.175948 -276.396473) (xy 115.191532 -276.443154) (xy 115.199427 -276.491731)
			(xy 115.199922 -276.516338) (xy 115.528864 -276.516338) (xy 115.532824 -276.467284) (xy 115.544601 -276.4195)
			(xy 115.563892 -276.374224) (xy 115.590195 -276.332628) (xy 115.62283 -276.295791) (xy 115.660951 -276.264666)
			(xy 115.703572 -276.240059) (xy 115.749588 -276.222607) (xy 115.797807 -276.212763) (xy 115.846982 -276.210782)
			(xy 115.895837 -276.216714) (xy 115.943108 -276.230406) (xy 115.98757 -276.251504) (xy 116.028073 -276.27946)
			(xy 116.063566 -276.313552) (xy 116.093131 -276.352896) (xy 116.116002 -276.396473) (xy 116.131586 -276.443154)
			(xy 116.139481 -276.491731) (xy 116.139976 -276.516338) (xy 116.468918 -276.516338) (xy 116.472878 -276.467284)
			(xy 116.484655 -276.4195) (xy 116.503946 -276.374224) (xy 116.530249 -276.332628) (xy 116.562884 -276.295791)
			(xy 116.601005 -276.264666) (xy 116.643626 -276.240059) (xy 116.689642 -276.222607) (xy 116.737861 -276.212763)
			(xy 116.787036 -276.210782) (xy 116.835891 -276.216714) (xy 116.883162 -276.230406) (xy 116.927624 -276.251504)
			(xy 116.968127 -276.27946) (xy 117.00362 -276.313552) (xy 117.033185 -276.352896) (xy 117.056056 -276.396473)
			(xy 117.07164 -276.443154) (xy 117.079535 -276.491731) (xy 117.08003 -276.516338) (xy 117.408972 -276.516338)
			(xy 117.412932 -276.467284) (xy 117.424709 -276.4195) (xy 117.444 -276.374224) (xy 117.470303 -276.332628)
			(xy 117.502938 -276.295791) (xy 117.541059 -276.264666) (xy 117.58368 -276.240059) (xy 117.629696 -276.222607)
			(xy 117.677915 -276.212763) (xy 117.72709 -276.210782) (xy 117.775945 -276.216714) (xy 117.823216 -276.230406)
			(xy 117.867678 -276.251504) (xy 117.908181 -276.27946) (xy 117.943674 -276.313552) (xy 117.973239 -276.352896)
			(xy 117.99611 -276.396473) (xy 118.011694 -276.443154) (xy 118.019589 -276.491731) (xy 118.020084 -276.516338)
			(xy 118.349026 -276.516338) (xy 118.352986 -276.467284) (xy 118.364763 -276.4195) (xy 118.384054 -276.374224)
			(xy 118.410357 -276.332628) (xy 118.442992 -276.295791) (xy 118.481113 -276.264666) (xy 118.523734 -276.240059)
			(xy 118.56975 -276.222607) (xy 118.617969 -276.212763) (xy 118.667144 -276.210782) (xy 118.715999 -276.216714)
			(xy 118.76327 -276.230406) (xy 118.807732 -276.251504) (xy 118.848235 -276.27946) (xy 118.883728 -276.313552)
			(xy 118.913293 -276.352896) (xy 118.936164 -276.396473) (xy 118.951748 -276.443154) (xy 118.959643 -276.491731)
			(xy 118.960138 -276.516338) (xy 119.288826 -276.516338) (xy 119.292786 -276.467284) (xy 119.304563 -276.4195)
			(xy 119.323854 -276.374224) (xy 119.350157 -276.332628) (xy 119.382792 -276.295791) (xy 119.420913 -276.264666)
			(xy 119.463534 -276.240059) (xy 119.50955 -276.222607) (xy 119.557769 -276.212763) (xy 119.606944 -276.210782)
			(xy 119.655799 -276.216714) (xy 119.70307 -276.230406) (xy 119.747532 -276.251504) (xy 119.788035 -276.27946)
			(xy 119.823528 -276.313552) (xy 119.853093 -276.352896) (xy 119.875964 -276.396473) (xy 119.891548 -276.443154)
			(xy 119.899443 -276.491731) (xy 119.899938 -276.516338) (xy 120.22888 -276.516338) (xy 120.23284 -276.467284)
			(xy 120.244617 -276.4195) (xy 120.263908 -276.374224) (xy 120.290211 -276.332628) (xy 120.322846 -276.295791)
			(xy 120.360967 -276.264666) (xy 120.403588 -276.240059) (xy 120.449604 -276.222607) (xy 120.497823 -276.212763)
			(xy 120.546998 -276.210782) (xy 120.595853 -276.216714) (xy 120.643124 -276.230406) (xy 120.687586 -276.251504)
			(xy 120.728089 -276.27946) (xy 120.763582 -276.313552) (xy 120.793147 -276.352896) (xy 120.816018 -276.396473)
			(xy 120.831602 -276.443154) (xy 120.839497 -276.491731) (xy 120.839992 -276.516338) (xy 121.168934 -276.516338)
			(xy 121.172894 -276.467284) (xy 121.184671 -276.4195) (xy 121.203962 -276.374224) (xy 121.230265 -276.332628)
			(xy 121.2629 -276.295791) (xy 121.301021 -276.264666) (xy 121.343642 -276.240059) (xy 121.389658 -276.222607)
			(xy 121.437877 -276.212763) (xy 121.487052 -276.210782) (xy 121.535907 -276.216714) (xy 121.583178 -276.230406)
			(xy 121.62764 -276.251504) (xy 121.668143 -276.27946) (xy 121.703636 -276.313552) (xy 121.733201 -276.352896)
			(xy 121.756072 -276.396473) (xy 121.771656 -276.443154) (xy 121.779551 -276.491731) (xy 121.780046 -276.516338)
			(xy 122.108988 -276.516338) (xy 122.112948 -276.467284) (xy 122.124725 -276.4195) (xy 122.144016 -276.374224)
			(xy 122.170319 -276.332628) (xy 122.202954 -276.295791) (xy 122.241075 -276.264666) (xy 122.283696 -276.240059)
			(xy 122.329712 -276.222607) (xy 122.377931 -276.212763) (xy 122.427106 -276.210782) (xy 122.475961 -276.216714)
			(xy 122.523232 -276.230406) (xy 122.567694 -276.251504) (xy 122.608197 -276.27946) (xy 122.64369 -276.313552)
			(xy 122.673255 -276.352896) (xy 122.696126 -276.396473) (xy 122.71171 -276.443154) (xy 122.719605 -276.491731)
			(xy 122.7201 -276.516338) (xy 123.049042 -276.516338) (xy 123.053002 -276.467284) (xy 123.064779 -276.4195)
			(xy 123.08407 -276.374224) (xy 123.110373 -276.332628) (xy 123.143008 -276.295791) (xy 123.181129 -276.264666)
			(xy 123.22375 -276.240059) (xy 123.269766 -276.222607) (xy 123.317985 -276.212763) (xy 123.36716 -276.210782)
			(xy 123.416015 -276.216714) (xy 123.463286 -276.230406) (xy 123.507748 -276.251504) (xy 123.548251 -276.27946)
			(xy 123.583744 -276.313552) (xy 123.613309 -276.352896) (xy 123.63618 -276.396473) (xy 123.651764 -276.443154)
			(xy 123.659659 -276.491731) (xy 123.660154 -276.516338) (xy 123.988842 -276.516338) (xy 123.992802 -276.467284)
			(xy 124.004579 -276.4195) (xy 124.02387 -276.374224) (xy 124.050173 -276.332628) (xy 124.082808 -276.295791)
			(xy 124.120929 -276.264666) (xy 124.16355 -276.240059) (xy 124.209566 -276.222607) (xy 124.257785 -276.212763)
			(xy 124.30696 -276.210782) (xy 124.355815 -276.216714) (xy 124.403086 -276.230406) (xy 124.447548 -276.251504)
			(xy 124.488051 -276.27946) (xy 124.523544 -276.313552) (xy 124.553109 -276.352896) (xy 124.57598 -276.396473)
			(xy 124.591564 -276.443154) (xy 124.599459 -276.491731) (xy 124.599954 -276.516338) (xy 124.928896 -276.516338)
			(xy 124.932856 -276.467284) (xy 124.944633 -276.4195) (xy 124.963924 -276.374224) (xy 124.990227 -276.332628)
			(xy 125.022862 -276.295791) (xy 125.060983 -276.264666) (xy 125.103604 -276.240059) (xy 125.14962 -276.222607)
			(xy 125.197839 -276.212763) (xy 125.247014 -276.210782) (xy 125.295869 -276.216714) (xy 125.34314 -276.230406)
			(xy 125.387602 -276.251504) (xy 125.428105 -276.27946) (xy 125.463598 -276.313552) (xy 125.493163 -276.352896)
			(xy 125.516034 -276.396473) (xy 125.531618 -276.443154) (xy 125.539513 -276.491731) (xy 125.540008 -276.516338)
			(xy 125.86895 -276.516338) (xy 125.87291 -276.467284) (xy 125.884687 -276.4195) (xy 125.903978 -276.374224)
			(xy 125.930281 -276.332628) (xy 125.962916 -276.295791) (xy 126.001037 -276.264666) (xy 126.043658 -276.240059)
			(xy 126.089674 -276.222607) (xy 126.137893 -276.212763) (xy 126.187068 -276.210782) (xy 126.235923 -276.216714)
			(xy 126.283194 -276.230406) (xy 126.327656 -276.251504) (xy 126.368159 -276.27946) (xy 126.403652 -276.313552)
			(xy 126.433217 -276.352896) (xy 126.456088 -276.396473) (xy 126.471672 -276.443154) (xy 126.479567 -276.491731)
			(xy 126.480062 -276.516338) (xy 126.479567 -276.540945) (xy 126.471672 -276.589522) (xy 126.456088 -276.636203)
			(xy 126.433217 -276.67978) (xy 126.403652 -276.719124) (xy 126.368159 -276.753216) (xy 126.327656 -276.781172)
			(xy 126.283194 -276.80227) (xy 126.235923 -276.815962) (xy 126.187068 -276.821894) (xy 126.137893 -276.819913)
			(xy 126.089674 -276.810069) (xy 126.043658 -276.792617) (xy 126.001037 -276.76801) (xy 125.962916 -276.736885)
			(xy 125.930281 -276.700048) (xy 125.903978 -276.658452) (xy 125.884687 -276.613176) (xy 125.87291 -276.565392)
			(xy 125.86895 -276.516338) (xy 125.540008 -276.516338) (xy 125.539513 -276.540945) (xy 125.531618 -276.589522)
			(xy 125.516034 -276.636203) (xy 125.493163 -276.67978) (xy 125.463598 -276.719124) (xy 125.428105 -276.753216)
			(xy 125.387602 -276.781172) (xy 125.34314 -276.80227) (xy 125.295869 -276.815962) (xy 125.247014 -276.821894)
			(xy 125.197839 -276.819913) (xy 125.14962 -276.810069) (xy 125.103604 -276.792617) (xy 125.060983 -276.76801)
			(xy 125.022862 -276.736885) (xy 124.990227 -276.700048) (xy 124.963924 -276.658452) (xy 124.944633 -276.613176)
			(xy 124.932856 -276.565392) (xy 124.928896 -276.516338) (xy 124.599954 -276.516338) (xy 124.599459 -276.540945)
			(xy 124.591564 -276.589522) (xy 124.57598 -276.636203) (xy 124.553109 -276.67978) (xy 124.523544 -276.719124)
			(xy 124.488051 -276.753216) (xy 124.447548 -276.781172) (xy 124.403086 -276.80227) (xy 124.355815 -276.815962)
			(xy 124.30696 -276.821894) (xy 124.257785 -276.819913) (xy 124.209566 -276.810069) (xy 124.16355 -276.792617)
			(xy 124.120929 -276.76801) (xy 124.082808 -276.736885) (xy 124.050173 -276.700048) (xy 124.02387 -276.658452)
			(xy 124.004579 -276.613176) (xy 123.992802 -276.565392) (xy 123.988842 -276.516338) (xy 123.660154 -276.516338)
			(xy 123.659659 -276.540945) (xy 123.651764 -276.589522) (xy 123.63618 -276.636203) (xy 123.613309 -276.67978)
			(xy 123.583744 -276.719124) (xy 123.548251 -276.753216) (xy 123.507748 -276.781172) (xy 123.463286 -276.80227)
			(xy 123.416015 -276.815962) (xy 123.36716 -276.821894) (xy 123.317985 -276.819913) (xy 123.269766 -276.810069)
			(xy 123.22375 -276.792617) (xy 123.181129 -276.76801) (xy 123.143008 -276.736885) (xy 123.110373 -276.700048)
			(xy 123.08407 -276.658452) (xy 123.064779 -276.613176) (xy 123.053002 -276.565392) (xy 123.049042 -276.516338)
			(xy 122.7201 -276.516338) (xy 122.719605 -276.540945) (xy 122.71171 -276.589522) (xy 122.696126 -276.636203)
			(xy 122.673255 -276.67978) (xy 122.64369 -276.719124) (xy 122.608197 -276.753216) (xy 122.567694 -276.781172)
			(xy 122.523232 -276.80227) (xy 122.475961 -276.815962) (xy 122.427106 -276.821894) (xy 122.377931 -276.819913)
			(xy 122.329712 -276.810069) (xy 122.283696 -276.792617) (xy 122.241075 -276.76801) (xy 122.202954 -276.736885)
			(xy 122.170319 -276.700048) (xy 122.144016 -276.658452) (xy 122.124725 -276.613176) (xy 122.112948 -276.565392)
			(xy 122.108988 -276.516338) (xy 121.780046 -276.516338) (xy 121.779551 -276.540945) (xy 121.771656 -276.589522)
			(xy 121.756072 -276.636203) (xy 121.733201 -276.67978) (xy 121.703636 -276.719124) (xy 121.668143 -276.753216)
			(xy 121.62764 -276.781172) (xy 121.583178 -276.80227) (xy 121.535907 -276.815962) (xy 121.487052 -276.821894)
			(xy 121.437877 -276.819913) (xy 121.389658 -276.810069) (xy 121.343642 -276.792617) (xy 121.301021 -276.76801)
			(xy 121.2629 -276.736885) (xy 121.230265 -276.700048) (xy 121.203962 -276.658452) (xy 121.184671 -276.613176)
			(xy 121.172894 -276.565392) (xy 121.168934 -276.516338) (xy 120.839992 -276.516338) (xy 120.839497 -276.540945)
			(xy 120.831602 -276.589522) (xy 120.816018 -276.636203) (xy 120.793147 -276.67978) (xy 120.763582 -276.719124)
			(xy 120.728089 -276.753216) (xy 120.687586 -276.781172) (xy 120.643124 -276.80227) (xy 120.595853 -276.815962)
			(xy 120.546998 -276.821894) (xy 120.497823 -276.819913) (xy 120.449604 -276.810069) (xy 120.403588 -276.792617)
			(xy 120.360967 -276.76801) (xy 120.322846 -276.736885) (xy 120.290211 -276.700048) (xy 120.263908 -276.658452)
			(xy 120.244617 -276.613176) (xy 120.23284 -276.565392) (xy 120.22888 -276.516338) (xy 119.899938 -276.516338)
			(xy 119.899443 -276.540945) (xy 119.891548 -276.589522) (xy 119.875964 -276.636203) (xy 119.853093 -276.67978)
			(xy 119.823528 -276.719124) (xy 119.788035 -276.753216) (xy 119.747532 -276.781172) (xy 119.70307 -276.80227)
			(xy 119.655799 -276.815962) (xy 119.606944 -276.821894) (xy 119.557769 -276.819913) (xy 119.50955 -276.810069)
			(xy 119.463534 -276.792617) (xy 119.420913 -276.76801) (xy 119.382792 -276.736885) (xy 119.350157 -276.700048)
			(xy 119.323854 -276.658452) (xy 119.304563 -276.613176) (xy 119.292786 -276.565392) (xy 119.288826 -276.516338)
			(xy 118.960138 -276.516338) (xy 118.959643 -276.540945) (xy 118.951748 -276.589522) (xy 118.936164 -276.636203)
			(xy 118.913293 -276.67978) (xy 118.883728 -276.719124) (xy 118.848235 -276.753216) (xy 118.807732 -276.781172)
			(xy 118.76327 -276.80227) (xy 118.715999 -276.815962) (xy 118.667144 -276.821894) (xy 118.617969 -276.819913)
			(xy 118.56975 -276.810069) (xy 118.523734 -276.792617) (xy 118.481113 -276.76801) (xy 118.442992 -276.736885)
			(xy 118.410357 -276.700048) (xy 118.384054 -276.658452) (xy 118.364763 -276.613176) (xy 118.352986 -276.565392)
			(xy 118.349026 -276.516338) (xy 118.020084 -276.516338) (xy 118.019589 -276.540945) (xy 118.011694 -276.589522)
			(xy 117.99611 -276.636203) (xy 117.973239 -276.67978) (xy 117.943674 -276.719124) (xy 117.908181 -276.753216)
			(xy 117.867678 -276.781172) (xy 117.823216 -276.80227) (xy 117.775945 -276.815962) (xy 117.72709 -276.821894)
			(xy 117.677915 -276.819913) (xy 117.629696 -276.810069) (xy 117.58368 -276.792617) (xy 117.541059 -276.76801)
			(xy 117.502938 -276.736885) (xy 117.470303 -276.700048) (xy 117.444 -276.658452) (xy 117.424709 -276.613176)
			(xy 117.412932 -276.565392) (xy 117.408972 -276.516338) (xy 117.08003 -276.516338) (xy 117.079535 -276.540945)
			(xy 117.07164 -276.589522) (xy 117.056056 -276.636203) (xy 117.033185 -276.67978) (xy 117.00362 -276.719124)
			(xy 116.968127 -276.753216) (xy 116.927624 -276.781172) (xy 116.883162 -276.80227) (xy 116.835891 -276.815962)
			(xy 116.787036 -276.821894) (xy 116.737861 -276.819913) (xy 116.689642 -276.810069) (xy 116.643626 -276.792617)
			(xy 116.601005 -276.76801) (xy 116.562884 -276.736885) (xy 116.530249 -276.700048) (xy 116.503946 -276.658452)
			(xy 116.484655 -276.613176) (xy 116.472878 -276.565392) (xy 116.468918 -276.516338) (xy 116.139976 -276.516338)
			(xy 116.139481 -276.540945) (xy 116.131586 -276.589522) (xy 116.116002 -276.636203) (xy 116.093131 -276.67978)
			(xy 116.063566 -276.719124) (xy 116.028073 -276.753216) (xy 115.98757 -276.781172) (xy 115.943108 -276.80227)
			(xy 115.895837 -276.815962) (xy 115.846982 -276.821894) (xy 115.797807 -276.819913) (xy 115.749588 -276.810069)
			(xy 115.703572 -276.792617) (xy 115.660951 -276.76801) (xy 115.62283 -276.736885) (xy 115.590195 -276.700048)
			(xy 115.563892 -276.658452) (xy 115.544601 -276.613176) (xy 115.532824 -276.565392) (xy 115.528864 -276.516338)
			(xy 115.199922 -276.516338) (xy 115.199427 -276.540945) (xy 115.191532 -276.589522) (xy 115.175948 -276.636203)
			(xy 115.153077 -276.67978) (xy 115.123512 -276.719124) (xy 115.088019 -276.753216) (xy 115.047516 -276.781172)
			(xy 115.003054 -276.80227) (xy 114.955783 -276.815962) (xy 114.906928 -276.821894) (xy 114.857753 -276.819913)
			(xy 114.809534 -276.810069) (xy 114.763518 -276.792617) (xy 114.720897 -276.76801) (xy 114.682776 -276.736885)
			(xy 114.650141 -276.700048) (xy 114.623838 -276.658452) (xy 114.604547 -276.613176) (xy 114.59277 -276.565392)
			(xy 114.58881 -276.516338) (xy 114.260122 -276.516338) (xy 114.259627 -276.540945) (xy 114.251732 -276.589522)
			(xy 114.236148 -276.636203) (xy 114.213277 -276.67978) (xy 114.183712 -276.719124) (xy 114.148219 -276.753216)
			(xy 114.107716 -276.781172) (xy 114.063254 -276.80227) (xy 114.015983 -276.815962) (xy 113.967128 -276.821894)
			(xy 113.917953 -276.819913) (xy 113.869734 -276.810069) (xy 113.823718 -276.792617) (xy 113.781097 -276.76801)
			(xy 113.742976 -276.736885) (xy 113.710341 -276.700048) (xy 113.684038 -276.658452) (xy 113.664747 -276.613176)
			(xy 113.65297 -276.565392) (xy 113.64901 -276.516338) (xy 110.506256 -276.516338) (xy 110.505761 -276.540945)
			(xy 110.497866 -276.589522) (xy 110.482282 -276.636203) (xy 110.459411 -276.67978) (xy 110.429846 -276.719124)
			(xy 110.394353 -276.753216) (xy 110.35385 -276.781172) (xy 110.309388 -276.80227) (xy 110.262117 -276.815962)
			(xy 110.213262 -276.821894) (xy 110.164087 -276.819913) (xy 110.115868 -276.810069) (xy 110.069852 -276.792617)
			(xy 110.027231 -276.76801) (xy 109.98911 -276.736885) (xy 109.956475 -276.700048) (xy 109.930172 -276.658452)
			(xy 109.910881 -276.613176) (xy 109.899104 -276.565392) (xy 109.895144 -276.516338) (xy 109.566456 -276.516338)
			(xy 109.565961 -276.540945) (xy 109.558066 -276.589522) (xy 109.542482 -276.636203) (xy 109.519611 -276.67978)
			(xy 109.490046 -276.719124) (xy 109.454553 -276.753216) (xy 109.41405 -276.781172) (xy 109.369588 -276.80227)
			(xy 109.322317 -276.815962) (xy 109.273462 -276.821894) (xy 109.224287 -276.819913) (xy 109.176068 -276.810069)
			(xy 109.130052 -276.792617) (xy 109.087431 -276.76801) (xy 109.04931 -276.736885) (xy 109.016675 -276.700048)
			(xy 108.990372 -276.658452) (xy 108.971081 -276.613176) (xy 108.959304 -276.565392) (xy 108.955344 -276.516338)
			(xy 108.626402 -276.516338) (xy 108.625907 -276.540945) (xy 108.618012 -276.589522) (xy 108.602428 -276.636203)
			(xy 108.579557 -276.67978) (xy 108.549992 -276.719124) (xy 108.514499 -276.753216) (xy 108.473996 -276.781172)
			(xy 108.429534 -276.80227) (xy 108.382263 -276.815962) (xy 108.333408 -276.821894) (xy 108.284233 -276.819913)
			(xy 108.236014 -276.810069) (xy 108.189998 -276.792617) (xy 108.147377 -276.76801) (xy 108.109256 -276.736885)
			(xy 108.076621 -276.700048) (xy 108.050318 -276.658452) (xy 108.031027 -276.613176) (xy 108.01925 -276.565392)
			(xy 108.01529 -276.516338) (xy 107.686348 -276.516338) (xy 107.685853 -276.540945) (xy 107.677958 -276.589522)
			(xy 107.662374 -276.636203) (xy 107.639503 -276.67978) (xy 107.609938 -276.719124) (xy 107.574445 -276.753216)
			(xy 107.533942 -276.781172) (xy 107.48948 -276.80227) (xy 107.442209 -276.815962) (xy 107.393354 -276.821894)
			(xy 107.344179 -276.819913) (xy 107.29596 -276.810069) (xy 107.249944 -276.792617) (xy 107.207323 -276.76801)
			(xy 107.169202 -276.736885) (xy 107.136567 -276.700048) (xy 107.110264 -276.658452) (xy 107.090973 -276.613176)
			(xy 107.079196 -276.565392) (xy 107.075236 -276.516338) (xy 106.746294 -276.516338) (xy 106.745799 -276.540945)
			(xy 106.737904 -276.589522) (xy 106.72232 -276.636203) (xy 106.699449 -276.67978) (xy 106.669884 -276.719124)
			(xy 106.634391 -276.753216) (xy 106.593888 -276.781172) (xy 106.549426 -276.80227) (xy 106.502155 -276.815962)
			(xy 106.4533 -276.821894) (xy 106.404125 -276.819913) (xy 106.355906 -276.810069) (xy 106.30989 -276.792617)
			(xy 106.267269 -276.76801) (xy 106.229148 -276.736885) (xy 106.196513 -276.700048) (xy 106.17021 -276.658452)
			(xy 106.150919 -276.613176) (xy 106.139142 -276.565392) (xy 106.135182 -276.516338) (xy 105.80624 -276.516338)
			(xy 105.805745 -276.540945) (xy 105.79785 -276.589522) (xy 105.782266 -276.636203) (xy 105.759395 -276.67978)
			(xy 105.72983 -276.719124) (xy 105.694337 -276.753216) (xy 105.653834 -276.781172) (xy 105.609372 -276.80227)
			(xy 105.562101 -276.815962) (xy 105.513246 -276.821894) (xy 105.464071 -276.819913) (xy 105.415852 -276.810069)
			(xy 105.369836 -276.792617) (xy 105.327215 -276.76801) (xy 105.289094 -276.736885) (xy 105.256459 -276.700048)
			(xy 105.230156 -276.658452) (xy 105.210865 -276.613176) (xy 105.199088 -276.565392) (xy 105.195128 -276.516338)
			(xy 104.86644 -276.516338) (xy 104.865945 -276.540945) (xy 104.85805 -276.589522) (xy 104.842466 -276.636203)
			(xy 104.819595 -276.67978) (xy 104.79003 -276.719124) (xy 104.754537 -276.753216) (xy 104.714034 -276.781172)
			(xy 104.669572 -276.80227) (xy 104.622301 -276.815962) (xy 104.573446 -276.821894) (xy 104.524271 -276.819913)
			(xy 104.476052 -276.810069) (xy 104.430036 -276.792617) (xy 104.387415 -276.76801) (xy 104.349294 -276.736885)
			(xy 104.316659 -276.700048) (xy 104.290356 -276.658452) (xy 104.271065 -276.613176) (xy 104.259288 -276.565392)
			(xy 104.255328 -276.516338) (xy 103.926386 -276.516338) (xy 103.925891 -276.540945) (xy 103.917996 -276.589522)
			(xy 103.902412 -276.636203) (xy 103.879541 -276.67978) (xy 103.849976 -276.719124) (xy 103.814483 -276.753216)
			(xy 103.77398 -276.781172) (xy 103.729518 -276.80227) (xy 103.682247 -276.815962) (xy 103.633392 -276.821894)
			(xy 103.584217 -276.819913) (xy 103.535998 -276.810069) (xy 103.489982 -276.792617) (xy 103.447361 -276.76801)
			(xy 103.40924 -276.736885) (xy 103.376605 -276.700048) (xy 103.350302 -276.658452) (xy 103.331011 -276.613176)
			(xy 103.319234 -276.565392) (xy 103.315274 -276.516338) (xy 102.986332 -276.516338) (xy 102.985837 -276.540945)
			(xy 102.977942 -276.589522) (xy 102.962358 -276.636203) (xy 102.939487 -276.67978) (xy 102.909922 -276.719124)
			(xy 102.874429 -276.753216) (xy 102.833926 -276.781172) (xy 102.789464 -276.80227) (xy 102.742193 -276.815962)
			(xy 102.693338 -276.821894) (xy 102.644163 -276.819913) (xy 102.595944 -276.810069) (xy 102.549928 -276.792617)
			(xy 102.507307 -276.76801) (xy 102.469186 -276.736885) (xy 102.436551 -276.700048) (xy 102.410248 -276.658452)
			(xy 102.390957 -276.613176) (xy 102.37918 -276.565392) (xy 102.37522 -276.516338) (xy 102.046278 -276.516338)
			(xy 102.045783 -276.540945) (xy 102.037888 -276.589522) (xy 102.022304 -276.636203) (xy 101.999433 -276.67978)
			(xy 101.969868 -276.719124) (xy 101.934375 -276.753216) (xy 101.893872 -276.781172) (xy 101.84941 -276.80227)
			(xy 101.802139 -276.815962) (xy 101.753284 -276.821894) (xy 101.704109 -276.819913) (xy 101.65589 -276.810069)
			(xy 101.609874 -276.792617) (xy 101.567253 -276.76801) (xy 101.529132 -276.736885) (xy 101.496497 -276.700048)
			(xy 101.470194 -276.658452) (xy 101.450903 -276.613176) (xy 101.439126 -276.565392) (xy 101.435166 -276.516338)
			(xy 101.106478 -276.516338) (xy 101.105983 -276.540945) (xy 101.098088 -276.589522) (xy 101.082504 -276.636203)
			(xy 101.059633 -276.67978) (xy 101.030068 -276.719124) (xy 100.994575 -276.753216) (xy 100.954072 -276.781172)
			(xy 100.90961 -276.80227) (xy 100.862339 -276.815962) (xy 100.813484 -276.821894) (xy 100.764309 -276.819913)
			(xy 100.71609 -276.810069) (xy 100.670074 -276.792617) (xy 100.627453 -276.76801) (xy 100.589332 -276.736885)
			(xy 100.556697 -276.700048) (xy 100.530394 -276.658452) (xy 100.511103 -276.613176) (xy 100.499326 -276.565392)
			(xy 100.495366 -276.516338) (xy 100.166424 -276.516338) (xy 100.165929 -276.540945) (xy 100.158034 -276.589522)
			(xy 100.14245 -276.636203) (xy 100.119579 -276.67978) (xy 100.090014 -276.719124) (xy 100.054521 -276.753216)
			(xy 100.014018 -276.781172) (xy 99.969556 -276.80227) (xy 99.922285 -276.815962) (xy 99.87343 -276.821894)
			(xy 99.824255 -276.819913) (xy 99.776036 -276.810069) (xy 99.73002 -276.792617) (xy 99.687399 -276.76801)
			(xy 99.649278 -276.736885) (xy 99.616643 -276.700048) (xy 99.59034 -276.658452) (xy 99.571049 -276.613176)
			(xy 99.559272 -276.565392) (xy 99.555312 -276.516338) (xy 99.22637 -276.516338) (xy 99.225875 -276.540945)
			(xy 99.21798 -276.589522) (xy 99.202396 -276.636203) (xy 99.179525 -276.67978) (xy 99.14996 -276.719124)
			(xy 99.114467 -276.753216) (xy 99.073964 -276.781172) (xy 99.029502 -276.80227) (xy 98.982231 -276.815962)
			(xy 98.933376 -276.821894) (xy 98.884201 -276.819913) (xy 98.835982 -276.810069) (xy 98.789966 -276.792617)
			(xy 98.747345 -276.76801) (xy 98.709224 -276.736885) (xy 98.676589 -276.700048) (xy 98.650286 -276.658452)
			(xy 98.630995 -276.613176) (xy 98.619218 -276.565392) (xy 98.615258 -276.516338) (xy 98.286316 -276.516338)
			(xy 98.285821 -276.540945) (xy 98.277926 -276.589522) (xy 98.262342 -276.636203) (xy 98.239471 -276.67978)
			(xy 98.209906 -276.719124) (xy 98.174413 -276.753216) (xy 98.13391 -276.781172) (xy 98.089448 -276.80227)
			(xy 98.042177 -276.815962) (xy 97.993322 -276.821894) (xy 97.944147 -276.819913) (xy 97.895928 -276.810069)
			(xy 97.849912 -276.792617) (xy 97.807291 -276.76801) (xy 97.76917 -276.736885) (xy 97.736535 -276.700048)
			(xy 97.710232 -276.658452) (xy 97.690941 -276.613176) (xy 97.679164 -276.565392) (xy 97.675204 -276.516338)
			(xy 97.346262 -276.516338) (xy 97.345794 -276.540576) (xy 97.338132 -276.588443) (xy 97.323005 -276.6345)
			(xy 97.300794 -276.677588) (xy 97.272056 -276.716628) (xy 97.237513 -276.750639) (xy 97.198031 -276.778768)
			(xy 97.154603 -276.800307) (xy 97.108317 -276.814716) (xy 97.084388 -276.818598) (xy 97.071942 -276.820376)
			(xy 97.040954 -276.8219) (xy 97.017459 -276.821467) (xy 96.971023 -276.814272) (xy 96.926234 -276.800057)
			(xy 96.884146 -276.779159) (xy 96.845751 -276.752068) (xy 96.811952 -276.719423) (xy 96.797368 -276.700996)
			(xy 96.795336 -276.698202) (xy 96.795082 -276.697948) (xy 96.790943 -276.692577) (xy 96.780387 -276.684076)
			(xy 96.774254 -276.681184) (xy 96.768412 -276.678898) (xy 96.755204 -276.67712) (xy 96.661986 -276.689312)
			(xy 96.65531 -276.690359) (xy 96.642824 -276.695512) (xy 96.637348 -276.699472) (xy 96.63176 -276.70379)
			(xy 96.62414 -276.714204) (xy 96.621346 -276.721316) (xy 96.61347 -276.740888) (xy 96.595166 -276.778904)
			(xy 96.58477 -276.797262) (xy 96.539812 -276.874732) (xy 96.534208 -276.885801) (xy 96.533406 -276.91057)
			(xy 96.538288 -276.921976) (xy 96.552766 -276.95144) (xy 96.576388 -276.998938) (xy 96.57715 -277.000208)
			(xy 96.579845 -277.004452) (xy 96.586628 -277.011873) (xy 96.590612 -277.01494) (xy 96.600518 -277.022052)
			(xy 96.613218 -277.02383) (xy 96.637224 -277.027676) (xy 96.683689 -277.041975) (xy 96.727305 -277.063449)
			(xy 96.766971 -277.091556) (xy 96.801688 -277.125589) (xy 96.83058 -277.164687) (xy 96.852918 -277.207867)
			(xy 96.868139 -277.254038) (xy 96.87586 -277.302037) (xy 96.876362 -277.326344) (xy 97.205304 -277.326344)
			(xy 97.209264 -277.27729) (xy 97.221041 -277.229506) (xy 97.240332 -277.18423) (xy 97.266635 -277.142634)
			(xy 97.29927 -277.105797) (xy 97.337391 -277.074672) (xy 97.380012 -277.050065) (xy 97.426028 -277.032613)
			(xy 97.474247 -277.022769) (xy 97.523422 -277.020788) (xy 97.572277 -277.02672) (xy 97.619548 -277.040412)
			(xy 97.66401 -277.06151) (xy 97.704513 -277.089466) (xy 97.740006 -277.123558) (xy 97.769571 -277.162902)
			(xy 97.792442 -277.206479) (xy 97.808026 -277.25316) (xy 97.815921 -277.301737) (xy 97.816416 -277.326344)
			(xy 98.145358 -277.326344) (xy 98.149318 -277.27729) (xy 98.161095 -277.229506) (xy 98.180386 -277.18423)
			(xy 98.206689 -277.142634) (xy 98.239324 -277.105797) (xy 98.277445 -277.074672) (xy 98.320066 -277.050065)
			(xy 98.366082 -277.032613) (xy 98.414301 -277.022769) (xy 98.463476 -277.020788) (xy 98.512331 -277.02672)
			(xy 98.559602 -277.040412) (xy 98.604064 -277.06151) (xy 98.644567 -277.089466) (xy 98.68006 -277.123558)
			(xy 98.709625 -277.162902) (xy 98.732496 -277.206479) (xy 98.74808 -277.25316) (xy 98.755975 -277.301737)
			(xy 98.75647 -277.326344) (xy 99.085158 -277.326344) (xy 99.089118 -277.27729) (xy 99.100895 -277.229506)
			(xy 99.120186 -277.18423) (xy 99.146489 -277.142634) (xy 99.179124 -277.105797) (xy 99.217245 -277.074672)
			(xy 99.259866 -277.050065) (xy 99.305882 -277.032613) (xy 99.354101 -277.022769) (xy 99.403276 -277.020788)
			(xy 99.452131 -277.02672) (xy 99.499402 -277.040412) (xy 99.543864 -277.06151) (xy 99.584367 -277.089466)
			(xy 99.61986 -277.123558) (xy 99.649425 -277.162902) (xy 99.672296 -277.206479) (xy 99.68788 -277.25316)
			(xy 99.695775 -277.301737) (xy 99.69627 -277.326344) (xy 100.025212 -277.326344) (xy 100.029172 -277.27729)
			(xy 100.040949 -277.229506) (xy 100.06024 -277.18423) (xy 100.086543 -277.142634) (xy 100.119178 -277.105797)
			(xy 100.157299 -277.074672) (xy 100.19992 -277.050065) (xy 100.245936 -277.032613) (xy 100.294155 -277.022769)
			(xy 100.34333 -277.020788) (xy 100.392185 -277.02672) (xy 100.439456 -277.040412) (xy 100.483918 -277.06151)
			(xy 100.524421 -277.089466) (xy 100.559914 -277.123558) (xy 100.589479 -277.162902) (xy 100.61235 -277.206479)
			(xy 100.627934 -277.25316) (xy 100.635829 -277.301737) (xy 100.636324 -277.326344) (xy 100.965266 -277.326344)
			(xy 100.969226 -277.27729) (xy 100.981003 -277.229506) (xy 101.000294 -277.18423) (xy 101.026597 -277.142634)
			(xy 101.059232 -277.105797) (xy 101.097353 -277.074672) (xy 101.139974 -277.050065) (xy 101.18599 -277.032613)
			(xy 101.234209 -277.022769) (xy 101.283384 -277.020788) (xy 101.332239 -277.02672) (xy 101.37951 -277.040412)
			(xy 101.423972 -277.06151) (xy 101.464475 -277.089466) (xy 101.499968 -277.123558) (xy 101.529533 -277.162902)
			(xy 101.552404 -277.206479) (xy 101.567988 -277.25316) (xy 101.575883 -277.301737) (xy 101.576378 -277.326344)
			(xy 101.90532 -277.326344) (xy 101.90928 -277.27729) (xy 101.921057 -277.229506) (xy 101.940348 -277.18423)
			(xy 101.966651 -277.142634) (xy 101.999286 -277.105797) (xy 102.037407 -277.074672) (xy 102.080028 -277.050065)
			(xy 102.126044 -277.032613) (xy 102.174263 -277.022769) (xy 102.223438 -277.020788) (xy 102.272293 -277.02672)
			(xy 102.319564 -277.040412) (xy 102.364026 -277.06151) (xy 102.404529 -277.089466) (xy 102.440022 -277.123558)
			(xy 102.469587 -277.162902) (xy 102.492458 -277.206479) (xy 102.508042 -277.25316) (xy 102.515937 -277.301737)
			(xy 102.516432 -277.326344) (xy 102.845374 -277.326344) (xy 102.849334 -277.27729) (xy 102.861111 -277.229506)
			(xy 102.880402 -277.18423) (xy 102.906705 -277.142634) (xy 102.93934 -277.105797) (xy 102.977461 -277.074672)
			(xy 103.020082 -277.050065) (xy 103.066098 -277.032613) (xy 103.114317 -277.022769) (xy 103.163492 -277.020788)
			(xy 103.212347 -277.02672) (xy 103.259618 -277.040412) (xy 103.30408 -277.06151) (xy 103.344583 -277.089466)
			(xy 103.380076 -277.123558) (xy 103.409641 -277.162902) (xy 103.432512 -277.206479) (xy 103.448096 -277.25316)
			(xy 103.455991 -277.301737) (xy 103.456486 -277.326344) (xy 103.785174 -277.326344) (xy 103.789134 -277.27729)
			(xy 103.800911 -277.229506) (xy 103.820202 -277.18423) (xy 103.846505 -277.142634) (xy 103.87914 -277.105797)
			(xy 103.917261 -277.074672) (xy 103.959882 -277.050065) (xy 104.005898 -277.032613) (xy 104.054117 -277.022769)
			(xy 104.103292 -277.020788) (xy 104.152147 -277.02672) (xy 104.199418 -277.040412) (xy 104.24388 -277.06151)
			(xy 104.284383 -277.089466) (xy 104.319876 -277.123558) (xy 104.349441 -277.162902) (xy 104.372312 -277.206479)
			(xy 104.387896 -277.25316) (xy 104.395791 -277.301737) (xy 104.396286 -277.326344) (xy 104.725228 -277.326344)
			(xy 104.729188 -277.27729) (xy 104.740965 -277.229506) (xy 104.760256 -277.18423) (xy 104.786559 -277.142634)
			(xy 104.819194 -277.105797) (xy 104.857315 -277.074672) (xy 104.899936 -277.050065) (xy 104.945952 -277.032613)
			(xy 104.994171 -277.022769) (xy 105.043346 -277.020788) (xy 105.092201 -277.02672) (xy 105.139472 -277.040412)
			(xy 105.183934 -277.06151) (xy 105.224437 -277.089466) (xy 105.25993 -277.123558) (xy 105.289495 -277.162902)
			(xy 105.312366 -277.206479) (xy 105.32795 -277.25316) (xy 105.335845 -277.301737) (xy 105.33634 -277.326344)
			(xy 105.665282 -277.326344) (xy 105.669242 -277.27729) (xy 105.681019 -277.229506) (xy 105.70031 -277.18423)
			(xy 105.726613 -277.142634) (xy 105.759248 -277.105797) (xy 105.797369 -277.074672) (xy 105.83999 -277.050065)
			(xy 105.886006 -277.032613) (xy 105.934225 -277.022769) (xy 105.9834 -277.020788) (xy 106.032255 -277.02672)
			(xy 106.079526 -277.040412) (xy 106.123988 -277.06151) (xy 106.164491 -277.089466) (xy 106.199984 -277.123558)
			(xy 106.229549 -277.162902) (xy 106.25242 -277.206479) (xy 106.268004 -277.25316) (xy 106.275899 -277.301737)
			(xy 106.276394 -277.326344) (xy 106.605336 -277.326344) (xy 106.609296 -277.27729) (xy 106.621073 -277.229506)
			(xy 106.640364 -277.18423) (xy 106.666667 -277.142634) (xy 106.699302 -277.105797) (xy 106.737423 -277.074672)
			(xy 106.780044 -277.050065) (xy 106.82606 -277.032613) (xy 106.874279 -277.022769) (xy 106.923454 -277.020788)
			(xy 106.972309 -277.02672) (xy 107.01958 -277.040412) (xy 107.064042 -277.06151) (xy 107.104545 -277.089466)
			(xy 107.140038 -277.123558) (xy 107.169603 -277.162902) (xy 107.192474 -277.206479) (xy 107.208058 -277.25316)
			(xy 107.215953 -277.301737) (xy 107.216448 -277.326344) (xy 107.545136 -277.326344) (xy 107.549096 -277.27729)
			(xy 107.560873 -277.229506) (xy 107.580164 -277.18423) (xy 107.606467 -277.142634) (xy 107.639102 -277.105797)
			(xy 107.677223 -277.074672) (xy 107.719844 -277.050065) (xy 107.76586 -277.032613) (xy 107.814079 -277.022769)
			(xy 107.863254 -277.020788) (xy 107.912109 -277.02672) (xy 107.95938 -277.040412) (xy 108.003842 -277.06151)
			(xy 108.044345 -277.089466) (xy 108.079838 -277.123558) (xy 108.109403 -277.162902) (xy 108.132274 -277.206479)
			(xy 108.147858 -277.25316) (xy 108.155753 -277.301737) (xy 108.156248 -277.326344) (xy 108.48519 -277.326344)
			(xy 108.48915 -277.27729) (xy 108.500927 -277.229506) (xy 108.520218 -277.18423) (xy 108.546521 -277.142634)
			(xy 108.579156 -277.105797) (xy 108.617277 -277.074672) (xy 108.659898 -277.050065) (xy 108.705914 -277.032613)
			(xy 108.754133 -277.022769) (xy 108.803308 -277.020788) (xy 108.852163 -277.02672) (xy 108.899434 -277.040412)
			(xy 108.943896 -277.06151) (xy 108.984399 -277.089466) (xy 109.019892 -277.123558) (xy 109.049457 -277.162902)
			(xy 109.072328 -277.206479) (xy 109.087912 -277.25316) (xy 109.095807 -277.301737) (xy 109.096302 -277.326344)
			(xy 109.425244 -277.326344) (xy 109.429204 -277.27729) (xy 109.440981 -277.229506) (xy 109.460272 -277.18423)
			(xy 109.486575 -277.142634) (xy 109.51921 -277.105797) (xy 109.557331 -277.074672) (xy 109.599952 -277.050065)
			(xy 109.645968 -277.032613) (xy 109.694187 -277.022769) (xy 109.743362 -277.020788) (xy 109.792217 -277.02672)
			(xy 109.839488 -277.040412) (xy 109.88395 -277.06151) (xy 109.924453 -277.089466) (xy 109.959946 -277.123558)
			(xy 109.989511 -277.162902) (xy 110.012382 -277.206479) (xy 110.027966 -277.25316) (xy 110.035861 -277.301737)
			(xy 110.036356 -277.326344) (xy 110.365298 -277.326344) (xy 110.369258 -277.27729) (xy 110.381035 -277.229506)
			(xy 110.400326 -277.18423) (xy 110.426629 -277.142634) (xy 110.459264 -277.105797) (xy 110.497385 -277.074672)
			(xy 110.540006 -277.050065) (xy 110.586022 -277.032613) (xy 110.634241 -277.022769) (xy 110.683416 -277.020788)
			(xy 110.732271 -277.02672) (xy 110.779542 -277.040412) (xy 110.824004 -277.06151) (xy 110.864507 -277.089466)
			(xy 110.9 -277.123558) (xy 110.929565 -277.162902) (xy 110.952436 -277.206479) (xy 110.96802 -277.25316)
			(xy 110.975915 -277.301737) (xy 110.97641 -277.326344) (xy 113.178856 -277.326344) (xy 113.182816 -277.27729)
			(xy 113.194593 -277.229506) (xy 113.213884 -277.18423) (xy 113.240187 -277.142634) (xy 113.272822 -277.105797)
			(xy 113.310943 -277.074672) (xy 113.353564 -277.050065) (xy 113.39958 -277.032613) (xy 113.447799 -277.022769)
			(xy 113.496974 -277.020788) (xy 113.545829 -277.02672) (xy 113.5931 -277.040412) (xy 113.637562 -277.06151)
			(xy 113.678065 -277.089466) (xy 113.713558 -277.123558) (xy 113.743123 -277.162902) (xy 113.765994 -277.206479)
			(xy 113.781578 -277.25316) (xy 113.789473 -277.301737) (xy 113.789968 -277.326344) (xy 114.11891 -277.326344)
			(xy 114.12287 -277.27729) (xy 114.134647 -277.229506) (xy 114.153938 -277.18423) (xy 114.180241 -277.142634)
			(xy 114.212876 -277.105797) (xy 114.250997 -277.074672) (xy 114.293618 -277.050065) (xy 114.339634 -277.032613)
			(xy 114.387853 -277.022769) (xy 114.437028 -277.020788) (xy 114.485883 -277.02672) (xy 114.533154 -277.040412)
			(xy 114.577616 -277.06151) (xy 114.618119 -277.089466) (xy 114.653612 -277.123558) (xy 114.683177 -277.162902)
			(xy 114.706048 -277.206479) (xy 114.721632 -277.25316) (xy 114.729527 -277.301737) (xy 114.730022 -277.326344)
			(xy 115.058964 -277.326344) (xy 115.062924 -277.27729) (xy 115.074701 -277.229506) (xy 115.093992 -277.18423)
			(xy 115.120295 -277.142634) (xy 115.15293 -277.105797) (xy 115.191051 -277.074672) (xy 115.233672 -277.050065)
			(xy 115.279688 -277.032613) (xy 115.327907 -277.022769) (xy 115.377082 -277.020788) (xy 115.425937 -277.02672)
			(xy 115.473208 -277.040412) (xy 115.51767 -277.06151) (xy 115.558173 -277.089466) (xy 115.593666 -277.123558)
			(xy 115.623231 -277.162902) (xy 115.646102 -277.206479) (xy 115.661686 -277.25316) (xy 115.669581 -277.301737)
			(xy 115.670076 -277.326344) (xy 115.999018 -277.326344) (xy 116.002978 -277.27729) (xy 116.014755 -277.229506)
			(xy 116.034046 -277.18423) (xy 116.060349 -277.142634) (xy 116.092984 -277.105797) (xy 116.131105 -277.074672)
			(xy 116.173726 -277.050065) (xy 116.219742 -277.032613) (xy 116.267961 -277.022769) (xy 116.317136 -277.020788)
			(xy 116.365991 -277.02672) (xy 116.413262 -277.040412) (xy 116.457724 -277.06151) (xy 116.498227 -277.089466)
			(xy 116.53372 -277.123558) (xy 116.563285 -277.162902) (xy 116.586156 -277.206479) (xy 116.60174 -277.25316)
			(xy 116.609635 -277.301737) (xy 116.61013 -277.326344) (xy 116.938818 -277.326344) (xy 116.942778 -277.27729)
			(xy 116.954555 -277.229506) (xy 116.973846 -277.18423) (xy 117.000149 -277.142634) (xy 117.032784 -277.105797)
			(xy 117.070905 -277.074672) (xy 117.113526 -277.050065) (xy 117.159542 -277.032613) (xy 117.207761 -277.022769)
			(xy 117.256936 -277.020788) (xy 117.305791 -277.02672) (xy 117.353062 -277.040412) (xy 117.397524 -277.06151)
			(xy 117.438027 -277.089466) (xy 117.47352 -277.123558) (xy 117.503085 -277.162902) (xy 117.525956 -277.206479)
			(xy 117.54154 -277.25316) (xy 117.549435 -277.301737) (xy 117.54993 -277.326344) (xy 117.878872 -277.326344)
			(xy 117.882832 -277.27729) (xy 117.894609 -277.229506) (xy 117.9139 -277.18423) (xy 117.940203 -277.142634)
			(xy 117.972838 -277.105797) (xy 118.010959 -277.074672) (xy 118.05358 -277.050065) (xy 118.099596 -277.032613)
			(xy 118.147815 -277.022769) (xy 118.19699 -277.020788) (xy 118.245845 -277.02672) (xy 118.293116 -277.040412)
			(xy 118.337578 -277.06151) (xy 118.378081 -277.089466) (xy 118.413574 -277.123558) (xy 118.443139 -277.162902)
			(xy 118.46601 -277.206479) (xy 118.481594 -277.25316) (xy 118.489489 -277.301737) (xy 118.489984 -277.326344)
			(xy 118.818926 -277.326344) (xy 118.822886 -277.27729) (xy 118.834663 -277.229506) (xy 118.853954 -277.18423)
			(xy 118.880257 -277.142634) (xy 118.912892 -277.105797) (xy 118.951013 -277.074672) (xy 118.993634 -277.050065)
			(xy 119.03965 -277.032613) (xy 119.087869 -277.022769) (xy 119.137044 -277.020788) (xy 119.185899 -277.02672)
			(xy 119.23317 -277.040412) (xy 119.277632 -277.06151) (xy 119.318135 -277.089466) (xy 119.353628 -277.123558)
			(xy 119.383193 -277.162902) (xy 119.406064 -277.206479) (xy 119.421648 -277.25316) (xy 119.429543 -277.301737)
			(xy 119.430038 -277.326344) (xy 119.75898 -277.326344) (xy 119.76294 -277.27729) (xy 119.774717 -277.229506)
			(xy 119.794008 -277.18423) (xy 119.820311 -277.142634) (xy 119.852946 -277.105797) (xy 119.891067 -277.074672)
			(xy 119.933688 -277.050065) (xy 119.979704 -277.032613) (xy 120.027923 -277.022769) (xy 120.077098 -277.020788)
			(xy 120.125953 -277.02672) (xy 120.173224 -277.040412) (xy 120.217686 -277.06151) (xy 120.258189 -277.089466)
			(xy 120.293682 -277.123558) (xy 120.323247 -277.162902) (xy 120.346118 -277.206479) (xy 120.361702 -277.25316)
			(xy 120.369597 -277.301737) (xy 120.370092 -277.326344) (xy 120.699034 -277.326344) (xy 120.702994 -277.27729)
			(xy 120.714771 -277.229506) (xy 120.734062 -277.18423) (xy 120.760365 -277.142634) (xy 120.793 -277.105797)
			(xy 120.831121 -277.074672) (xy 120.873742 -277.050065) (xy 120.919758 -277.032613) (xy 120.967977 -277.022769)
			(xy 121.017152 -277.020788) (xy 121.066007 -277.02672) (xy 121.113278 -277.040412) (xy 121.15774 -277.06151)
			(xy 121.198243 -277.089466) (xy 121.233736 -277.123558) (xy 121.263301 -277.162902) (xy 121.286172 -277.206479)
			(xy 121.301756 -277.25316) (xy 121.309651 -277.301737) (xy 121.310146 -277.326344) (xy 121.638834 -277.326344)
			(xy 121.642794 -277.27729) (xy 121.654571 -277.229506) (xy 121.673862 -277.18423) (xy 121.700165 -277.142634)
			(xy 121.7328 -277.105797) (xy 121.770921 -277.074672) (xy 121.813542 -277.050065) (xy 121.859558 -277.032613)
			(xy 121.907777 -277.022769) (xy 121.956952 -277.020788) (xy 122.005807 -277.02672) (xy 122.053078 -277.040412)
			(xy 122.09754 -277.06151) (xy 122.138043 -277.089466) (xy 122.173536 -277.123558) (xy 122.203101 -277.162902)
			(xy 122.225972 -277.206479) (xy 122.241556 -277.25316) (xy 122.249451 -277.301737) (xy 122.249946 -277.326344)
			(xy 122.578888 -277.326344) (xy 122.582848 -277.27729) (xy 122.594625 -277.229506) (xy 122.613916 -277.18423)
			(xy 122.640219 -277.142634) (xy 122.672854 -277.105797) (xy 122.710975 -277.074672) (xy 122.753596 -277.050065)
			(xy 122.799612 -277.032613) (xy 122.847831 -277.022769) (xy 122.897006 -277.020788) (xy 122.945861 -277.02672)
			(xy 122.993132 -277.040412) (xy 123.037594 -277.06151) (xy 123.078097 -277.089466) (xy 123.11359 -277.123558)
			(xy 123.143155 -277.162902) (xy 123.166026 -277.206479) (xy 123.18161 -277.25316) (xy 123.189505 -277.301737)
			(xy 123.19 -277.326344) (xy 123.518942 -277.326344) (xy 123.522902 -277.27729) (xy 123.534679 -277.229506)
			(xy 123.55397 -277.18423) (xy 123.580273 -277.142634) (xy 123.612908 -277.105797) (xy 123.651029 -277.074672)
			(xy 123.69365 -277.050065) (xy 123.739666 -277.032613) (xy 123.787885 -277.022769) (xy 123.83706 -277.020788)
			(xy 123.885915 -277.02672) (xy 123.933186 -277.040412) (xy 123.977648 -277.06151) (xy 124.018151 -277.089466)
			(xy 124.053644 -277.123558) (xy 124.083209 -277.162902) (xy 124.10608 -277.206479) (xy 124.121664 -277.25316)
			(xy 124.129559 -277.301737) (xy 124.130054 -277.326344) (xy 124.458996 -277.326344) (xy 124.462956 -277.27729)
			(xy 124.474733 -277.229506) (xy 124.494024 -277.18423) (xy 124.520327 -277.142634) (xy 124.552962 -277.105797)
			(xy 124.591083 -277.074672) (xy 124.633704 -277.050065) (xy 124.67972 -277.032613) (xy 124.727939 -277.022769)
			(xy 124.777114 -277.020788) (xy 124.825969 -277.02672) (xy 124.87324 -277.040412) (xy 124.917702 -277.06151)
			(xy 124.958205 -277.089466) (xy 124.993698 -277.123558) (xy 125.023263 -277.162902) (xy 125.046134 -277.206479)
			(xy 125.061718 -277.25316) (xy 125.069613 -277.301737) (xy 125.070108 -277.326344) (xy 125.39905 -277.326344)
			(xy 125.40301 -277.27729) (xy 125.414787 -277.229506) (xy 125.434078 -277.18423) (xy 125.460381 -277.142634)
			(xy 125.493016 -277.105797) (xy 125.531137 -277.074672) (xy 125.573758 -277.050065) (xy 125.619774 -277.032613)
			(xy 125.667993 -277.022769) (xy 125.717168 -277.020788) (xy 125.766023 -277.02672) (xy 125.813294 -277.040412)
			(xy 125.857756 -277.06151) (xy 125.898259 -277.089466) (xy 125.933752 -277.123558) (xy 125.963317 -277.162902)
			(xy 125.986188 -277.206479) (xy 126.001772 -277.25316) (xy 126.009667 -277.301737) (xy 126.010162 -277.326344)
			(xy 126.33885 -277.326344) (xy 126.34281 -277.27729) (xy 126.354587 -277.229506) (xy 126.373878 -277.18423)
			(xy 126.400181 -277.142634) (xy 126.432816 -277.105797) (xy 126.470937 -277.074672) (xy 126.513558 -277.050065)
			(xy 126.559574 -277.032613) (xy 126.607793 -277.022769) (xy 126.656968 -277.020788) (xy 126.705823 -277.02672)
			(xy 126.753094 -277.040412) (xy 126.797556 -277.06151) (xy 126.838059 -277.089466) (xy 126.873552 -277.123558)
			(xy 126.903117 -277.162902) (xy 126.925988 -277.206479) (xy 126.941572 -277.25316) (xy 126.949467 -277.301737)
			(xy 126.949962 -277.326344) (xy 126.949467 -277.350951) (xy 126.941572 -277.399528) (xy 126.925988 -277.446209)
			(xy 126.903117 -277.489786) (xy 126.873552 -277.52913) (xy 126.838059 -277.563222) (xy 126.797556 -277.591178)
			(xy 126.753094 -277.612276) (xy 126.705823 -277.625968) (xy 126.656968 -277.6319) (xy 126.607793 -277.629919)
			(xy 126.559574 -277.620075) (xy 126.513558 -277.602623) (xy 126.470937 -277.578016) (xy 126.432816 -277.546891)
			(xy 126.400181 -277.510054) (xy 126.373878 -277.468458) (xy 126.354587 -277.423182) (xy 126.34281 -277.375398)
			(xy 126.33885 -277.326344) (xy 126.010162 -277.326344) (xy 126.009667 -277.350951) (xy 126.001772 -277.399528)
			(xy 125.986188 -277.446209) (xy 125.963317 -277.489786) (xy 125.933752 -277.52913) (xy 125.898259 -277.563222)
			(xy 125.857756 -277.591178) (xy 125.813294 -277.612276) (xy 125.766023 -277.625968) (xy 125.717168 -277.6319)
			(xy 125.667993 -277.629919) (xy 125.619774 -277.620075) (xy 125.573758 -277.602623) (xy 125.531137 -277.578016)
			(xy 125.493016 -277.546891) (xy 125.460381 -277.510054) (xy 125.434078 -277.468458) (xy 125.414787 -277.423182)
			(xy 125.40301 -277.375398) (xy 125.39905 -277.326344) (xy 125.070108 -277.326344) (xy 125.069613 -277.350951)
			(xy 125.061718 -277.399528) (xy 125.046134 -277.446209) (xy 125.023263 -277.489786) (xy 124.993698 -277.52913)
			(xy 124.958205 -277.563222) (xy 124.917702 -277.591178) (xy 124.87324 -277.612276) (xy 124.825969 -277.625968)
			(xy 124.777114 -277.6319) (xy 124.727939 -277.629919) (xy 124.67972 -277.620075) (xy 124.633704 -277.602623)
			(xy 124.591083 -277.578016) (xy 124.552962 -277.546891) (xy 124.520327 -277.510054) (xy 124.494024 -277.468458)
			(xy 124.474733 -277.423182) (xy 124.462956 -277.375398) (xy 124.458996 -277.326344) (xy 124.130054 -277.326344)
			(xy 124.129559 -277.350951) (xy 124.121664 -277.399528) (xy 124.10608 -277.446209) (xy 124.083209 -277.489786)
			(xy 124.053644 -277.52913) (xy 124.018151 -277.563222) (xy 123.977648 -277.591178) (xy 123.933186 -277.612276)
			(xy 123.885915 -277.625968) (xy 123.83706 -277.6319) (xy 123.787885 -277.629919) (xy 123.739666 -277.620075)
			(xy 123.69365 -277.602623) (xy 123.651029 -277.578016) (xy 123.612908 -277.546891) (xy 123.580273 -277.510054)
			(xy 123.55397 -277.468458) (xy 123.534679 -277.423182) (xy 123.522902 -277.375398) (xy 123.518942 -277.326344)
			(xy 123.19 -277.326344) (xy 123.189505 -277.350951) (xy 123.18161 -277.399528) (xy 123.166026 -277.446209)
			(xy 123.143155 -277.489786) (xy 123.11359 -277.52913) (xy 123.078097 -277.563222) (xy 123.037594 -277.591178)
			(xy 122.993132 -277.612276) (xy 122.945861 -277.625968) (xy 122.897006 -277.6319) (xy 122.847831 -277.629919)
			(xy 122.799612 -277.620075) (xy 122.753596 -277.602623) (xy 122.710975 -277.578016) (xy 122.672854 -277.546891)
			(xy 122.640219 -277.510054) (xy 122.613916 -277.468458) (xy 122.594625 -277.423182) (xy 122.582848 -277.375398)
			(xy 122.578888 -277.326344) (xy 122.249946 -277.326344) (xy 122.249451 -277.350951) (xy 122.241556 -277.399528)
			(xy 122.225972 -277.446209) (xy 122.203101 -277.489786) (xy 122.173536 -277.52913) (xy 122.138043 -277.563222)
			(xy 122.09754 -277.591178) (xy 122.053078 -277.612276) (xy 122.005807 -277.625968) (xy 121.956952 -277.6319)
			(xy 121.907777 -277.629919) (xy 121.859558 -277.620075) (xy 121.813542 -277.602623) (xy 121.770921 -277.578016)
			(xy 121.7328 -277.546891) (xy 121.700165 -277.510054) (xy 121.673862 -277.468458) (xy 121.654571 -277.423182)
			(xy 121.642794 -277.375398) (xy 121.638834 -277.326344) (xy 121.310146 -277.326344) (xy 121.309651 -277.350951)
			(xy 121.301756 -277.399528) (xy 121.286172 -277.446209) (xy 121.263301 -277.489786) (xy 121.233736 -277.52913)
			(xy 121.198243 -277.563222) (xy 121.15774 -277.591178) (xy 121.113278 -277.612276) (xy 121.066007 -277.625968)
			(xy 121.017152 -277.6319) (xy 120.967977 -277.629919) (xy 120.919758 -277.620075) (xy 120.873742 -277.602623)
			(xy 120.831121 -277.578016) (xy 120.793 -277.546891) (xy 120.760365 -277.510054) (xy 120.734062 -277.468458)
			(xy 120.714771 -277.423182) (xy 120.702994 -277.375398) (xy 120.699034 -277.326344) (xy 120.370092 -277.326344)
			(xy 120.369597 -277.350951) (xy 120.361702 -277.399528) (xy 120.346118 -277.446209) (xy 120.323247 -277.489786)
			(xy 120.293682 -277.52913) (xy 120.258189 -277.563222) (xy 120.217686 -277.591178) (xy 120.173224 -277.612276)
			(xy 120.125953 -277.625968) (xy 120.077098 -277.6319) (xy 120.027923 -277.629919) (xy 119.979704 -277.620075)
			(xy 119.933688 -277.602623) (xy 119.891067 -277.578016) (xy 119.852946 -277.546891) (xy 119.820311 -277.510054)
			(xy 119.794008 -277.468458) (xy 119.774717 -277.423182) (xy 119.76294 -277.375398) (xy 119.75898 -277.326344)
			(xy 119.430038 -277.326344) (xy 119.429543 -277.350951) (xy 119.421648 -277.399528) (xy 119.406064 -277.446209)
			(xy 119.383193 -277.489786) (xy 119.353628 -277.52913) (xy 119.318135 -277.563222) (xy 119.277632 -277.591178)
			(xy 119.23317 -277.612276) (xy 119.185899 -277.625968) (xy 119.137044 -277.6319) (xy 119.087869 -277.629919)
			(xy 119.03965 -277.620075) (xy 118.993634 -277.602623) (xy 118.951013 -277.578016) (xy 118.912892 -277.546891)
			(xy 118.880257 -277.510054) (xy 118.853954 -277.468458) (xy 118.834663 -277.423182) (xy 118.822886 -277.375398)
			(xy 118.818926 -277.326344) (xy 118.489984 -277.326344) (xy 118.489489 -277.350951) (xy 118.481594 -277.399528)
			(xy 118.46601 -277.446209) (xy 118.443139 -277.489786) (xy 118.413574 -277.52913) (xy 118.378081 -277.563222)
			(xy 118.337578 -277.591178) (xy 118.293116 -277.612276) (xy 118.245845 -277.625968) (xy 118.19699 -277.6319)
			(xy 118.147815 -277.629919) (xy 118.099596 -277.620075) (xy 118.05358 -277.602623) (xy 118.010959 -277.578016)
			(xy 117.972838 -277.546891) (xy 117.940203 -277.510054) (xy 117.9139 -277.468458) (xy 117.894609 -277.423182)
			(xy 117.882832 -277.375398) (xy 117.878872 -277.326344) (xy 117.54993 -277.326344) (xy 117.549435 -277.350951)
			(xy 117.54154 -277.399528) (xy 117.525956 -277.446209) (xy 117.503085 -277.489786) (xy 117.47352 -277.52913)
			(xy 117.438027 -277.563222) (xy 117.397524 -277.591178) (xy 117.353062 -277.612276) (xy 117.305791 -277.625968)
			(xy 117.256936 -277.6319) (xy 117.207761 -277.629919) (xy 117.159542 -277.620075) (xy 117.113526 -277.602623)
			(xy 117.070905 -277.578016) (xy 117.032784 -277.546891) (xy 117.000149 -277.510054) (xy 116.973846 -277.468458)
			(xy 116.954555 -277.423182) (xy 116.942778 -277.375398) (xy 116.938818 -277.326344) (xy 116.61013 -277.326344)
			(xy 116.609635 -277.350951) (xy 116.60174 -277.399528) (xy 116.586156 -277.446209) (xy 116.563285 -277.489786)
			(xy 116.53372 -277.52913) (xy 116.498227 -277.563222) (xy 116.457724 -277.591178) (xy 116.413262 -277.612276)
			(xy 116.365991 -277.625968) (xy 116.317136 -277.6319) (xy 116.267961 -277.629919) (xy 116.219742 -277.620075)
			(xy 116.173726 -277.602623) (xy 116.131105 -277.578016) (xy 116.092984 -277.546891) (xy 116.060349 -277.510054)
			(xy 116.034046 -277.468458) (xy 116.014755 -277.423182) (xy 116.002978 -277.375398) (xy 115.999018 -277.326344)
			(xy 115.670076 -277.326344) (xy 115.669581 -277.350951) (xy 115.661686 -277.399528) (xy 115.646102 -277.446209)
			(xy 115.623231 -277.489786) (xy 115.593666 -277.52913) (xy 115.558173 -277.563222) (xy 115.51767 -277.591178)
			(xy 115.473208 -277.612276) (xy 115.425937 -277.625968) (xy 115.377082 -277.6319) (xy 115.327907 -277.629919)
			(xy 115.279688 -277.620075) (xy 115.233672 -277.602623) (xy 115.191051 -277.578016) (xy 115.15293 -277.546891)
			(xy 115.120295 -277.510054) (xy 115.093992 -277.468458) (xy 115.074701 -277.423182) (xy 115.062924 -277.375398)
			(xy 115.058964 -277.326344) (xy 114.730022 -277.326344) (xy 114.729527 -277.350951) (xy 114.721632 -277.399528)
			(xy 114.706048 -277.446209) (xy 114.683177 -277.489786) (xy 114.653612 -277.52913) (xy 114.618119 -277.563222)
			(xy 114.577616 -277.591178) (xy 114.533154 -277.612276) (xy 114.485883 -277.625968) (xy 114.437028 -277.6319)
			(xy 114.387853 -277.629919) (xy 114.339634 -277.620075) (xy 114.293618 -277.602623) (xy 114.250997 -277.578016)
			(xy 114.212876 -277.546891) (xy 114.180241 -277.510054) (xy 114.153938 -277.468458) (xy 114.134647 -277.423182)
			(xy 114.12287 -277.375398) (xy 114.11891 -277.326344) (xy 113.789968 -277.326344) (xy 113.789473 -277.350951)
			(xy 113.781578 -277.399528) (xy 113.765994 -277.446209) (xy 113.743123 -277.489786) (xy 113.713558 -277.52913)
			(xy 113.678065 -277.563222) (xy 113.637562 -277.591178) (xy 113.5931 -277.612276) (xy 113.545829 -277.625968)
			(xy 113.496974 -277.6319) (xy 113.447799 -277.629919) (xy 113.39958 -277.620075) (xy 113.353564 -277.602623)
			(xy 113.310943 -277.578016) (xy 113.272822 -277.546891) (xy 113.240187 -277.510054) (xy 113.213884 -277.468458)
			(xy 113.194593 -277.423182) (xy 113.182816 -277.375398) (xy 113.178856 -277.326344) (xy 110.97641 -277.326344)
			(xy 110.975915 -277.350951) (xy 110.96802 -277.399528) (xy 110.952436 -277.446209) (xy 110.929565 -277.489786)
			(xy 110.9 -277.52913) (xy 110.864507 -277.563222) (xy 110.824004 -277.591178) (xy 110.779542 -277.612276)
			(xy 110.732271 -277.625968) (xy 110.683416 -277.6319) (xy 110.634241 -277.629919) (xy 110.586022 -277.620075)
			(xy 110.540006 -277.602623) (xy 110.497385 -277.578016) (xy 110.459264 -277.546891) (xy 110.426629 -277.510054)
			(xy 110.400326 -277.468458) (xy 110.381035 -277.423182) (xy 110.369258 -277.375398) (xy 110.365298 -277.326344)
			(xy 110.036356 -277.326344) (xy 110.035861 -277.350951) (xy 110.027966 -277.399528) (xy 110.012382 -277.446209)
			(xy 109.989511 -277.489786) (xy 109.959946 -277.52913) (xy 109.924453 -277.563222) (xy 109.88395 -277.591178)
			(xy 109.839488 -277.612276) (xy 109.792217 -277.625968) (xy 109.743362 -277.6319) (xy 109.694187 -277.629919)
			(xy 109.645968 -277.620075) (xy 109.599952 -277.602623) (xy 109.557331 -277.578016) (xy 109.51921 -277.546891)
			(xy 109.486575 -277.510054) (xy 109.460272 -277.468458) (xy 109.440981 -277.423182) (xy 109.429204 -277.375398)
			(xy 109.425244 -277.326344) (xy 109.096302 -277.326344) (xy 109.095807 -277.350951) (xy 109.087912 -277.399528)
			(xy 109.072328 -277.446209) (xy 109.049457 -277.489786) (xy 109.019892 -277.52913) (xy 108.984399 -277.563222)
			(xy 108.943896 -277.591178) (xy 108.899434 -277.612276) (xy 108.852163 -277.625968) (xy 108.803308 -277.6319)
			(xy 108.754133 -277.629919) (xy 108.705914 -277.620075) (xy 108.659898 -277.602623) (xy 108.617277 -277.578016)
			(xy 108.579156 -277.546891) (xy 108.546521 -277.510054) (xy 108.520218 -277.468458) (xy 108.500927 -277.423182)
			(xy 108.48915 -277.375398) (xy 108.48519 -277.326344) (xy 108.156248 -277.326344) (xy 108.155753 -277.350951)
			(xy 108.147858 -277.399528) (xy 108.132274 -277.446209) (xy 108.109403 -277.489786) (xy 108.079838 -277.52913)
			(xy 108.044345 -277.563222) (xy 108.003842 -277.591178) (xy 107.95938 -277.612276) (xy 107.912109 -277.625968)
			(xy 107.863254 -277.6319) (xy 107.814079 -277.629919) (xy 107.76586 -277.620075) (xy 107.719844 -277.602623)
			(xy 107.677223 -277.578016) (xy 107.639102 -277.546891) (xy 107.606467 -277.510054) (xy 107.580164 -277.468458)
			(xy 107.560873 -277.423182) (xy 107.549096 -277.375398) (xy 107.545136 -277.326344) (xy 107.216448 -277.326344)
			(xy 107.215953 -277.350951) (xy 107.208058 -277.399528) (xy 107.192474 -277.446209) (xy 107.169603 -277.489786)
			(xy 107.140038 -277.52913) (xy 107.104545 -277.563222) (xy 107.064042 -277.591178) (xy 107.01958 -277.612276)
			(xy 106.972309 -277.625968) (xy 106.923454 -277.6319) (xy 106.874279 -277.629919) (xy 106.82606 -277.620075)
			(xy 106.780044 -277.602623) (xy 106.737423 -277.578016) (xy 106.699302 -277.546891) (xy 106.666667 -277.510054)
			(xy 106.640364 -277.468458) (xy 106.621073 -277.423182) (xy 106.609296 -277.375398) (xy 106.605336 -277.326344)
			(xy 106.276394 -277.326344) (xy 106.275899 -277.350951) (xy 106.268004 -277.399528) (xy 106.25242 -277.446209)
			(xy 106.229549 -277.489786) (xy 106.199984 -277.52913) (xy 106.164491 -277.563222) (xy 106.123988 -277.591178)
			(xy 106.079526 -277.612276) (xy 106.032255 -277.625968) (xy 105.9834 -277.6319) (xy 105.934225 -277.629919)
			(xy 105.886006 -277.620075) (xy 105.83999 -277.602623) (xy 105.797369 -277.578016) (xy 105.759248 -277.546891)
			(xy 105.726613 -277.510054) (xy 105.70031 -277.468458) (xy 105.681019 -277.423182) (xy 105.669242 -277.375398)
			(xy 105.665282 -277.326344) (xy 105.33634 -277.326344) (xy 105.335845 -277.350951) (xy 105.32795 -277.399528)
			(xy 105.312366 -277.446209) (xy 105.289495 -277.489786) (xy 105.25993 -277.52913) (xy 105.224437 -277.563222)
			(xy 105.183934 -277.591178) (xy 105.139472 -277.612276) (xy 105.092201 -277.625968) (xy 105.043346 -277.6319)
			(xy 104.994171 -277.629919) (xy 104.945952 -277.620075) (xy 104.899936 -277.602623) (xy 104.857315 -277.578016)
			(xy 104.819194 -277.546891) (xy 104.786559 -277.510054) (xy 104.760256 -277.468458) (xy 104.740965 -277.423182)
			(xy 104.729188 -277.375398) (xy 104.725228 -277.326344) (xy 104.396286 -277.326344) (xy 104.395791 -277.350951)
			(xy 104.387896 -277.399528) (xy 104.372312 -277.446209) (xy 104.349441 -277.489786) (xy 104.319876 -277.52913)
			(xy 104.284383 -277.563222) (xy 104.24388 -277.591178) (xy 104.199418 -277.612276) (xy 104.152147 -277.625968)
			(xy 104.103292 -277.6319) (xy 104.054117 -277.629919) (xy 104.005898 -277.620075) (xy 103.959882 -277.602623)
			(xy 103.917261 -277.578016) (xy 103.87914 -277.546891) (xy 103.846505 -277.510054) (xy 103.820202 -277.468458)
			(xy 103.800911 -277.423182) (xy 103.789134 -277.375398) (xy 103.785174 -277.326344) (xy 103.456486 -277.326344)
			(xy 103.455991 -277.350951) (xy 103.448096 -277.399528) (xy 103.432512 -277.446209) (xy 103.409641 -277.489786)
			(xy 103.380076 -277.52913) (xy 103.344583 -277.563222) (xy 103.30408 -277.591178) (xy 103.259618 -277.612276)
			(xy 103.212347 -277.625968) (xy 103.163492 -277.6319) (xy 103.114317 -277.629919) (xy 103.066098 -277.620075)
			(xy 103.020082 -277.602623) (xy 102.977461 -277.578016) (xy 102.93934 -277.546891) (xy 102.906705 -277.510054)
			(xy 102.880402 -277.468458) (xy 102.861111 -277.423182) (xy 102.849334 -277.375398) (xy 102.845374 -277.326344)
			(xy 102.516432 -277.326344) (xy 102.515937 -277.350951) (xy 102.508042 -277.399528) (xy 102.492458 -277.446209)
			(xy 102.469587 -277.489786) (xy 102.440022 -277.52913) (xy 102.404529 -277.563222) (xy 102.364026 -277.591178)
			(xy 102.319564 -277.612276) (xy 102.272293 -277.625968) (xy 102.223438 -277.6319) (xy 102.174263 -277.629919)
			(xy 102.126044 -277.620075) (xy 102.080028 -277.602623) (xy 102.037407 -277.578016) (xy 101.999286 -277.546891)
			(xy 101.966651 -277.510054) (xy 101.940348 -277.468458) (xy 101.921057 -277.423182) (xy 101.90928 -277.375398)
			(xy 101.90532 -277.326344) (xy 101.576378 -277.326344) (xy 101.575883 -277.350951) (xy 101.567988 -277.399528)
			(xy 101.552404 -277.446209) (xy 101.529533 -277.489786) (xy 101.499968 -277.52913) (xy 101.464475 -277.563222)
			(xy 101.423972 -277.591178) (xy 101.37951 -277.612276) (xy 101.332239 -277.625968) (xy 101.283384 -277.6319)
			(xy 101.234209 -277.629919) (xy 101.18599 -277.620075) (xy 101.139974 -277.602623) (xy 101.097353 -277.578016)
			(xy 101.059232 -277.546891) (xy 101.026597 -277.510054) (xy 101.000294 -277.468458) (xy 100.981003 -277.423182)
			(xy 100.969226 -277.375398) (xy 100.965266 -277.326344) (xy 100.636324 -277.326344) (xy 100.635829 -277.350951)
			(xy 100.627934 -277.399528) (xy 100.61235 -277.446209) (xy 100.589479 -277.489786) (xy 100.559914 -277.52913)
			(xy 100.524421 -277.563222) (xy 100.483918 -277.591178) (xy 100.439456 -277.612276) (xy 100.392185 -277.625968)
			(xy 100.34333 -277.6319) (xy 100.294155 -277.629919) (xy 100.245936 -277.620075) (xy 100.19992 -277.602623)
			(xy 100.157299 -277.578016) (xy 100.119178 -277.546891) (xy 100.086543 -277.510054) (xy 100.06024 -277.468458)
			(xy 100.040949 -277.423182) (xy 100.029172 -277.375398) (xy 100.025212 -277.326344) (xy 99.69627 -277.326344)
			(xy 99.695775 -277.350951) (xy 99.68788 -277.399528) (xy 99.672296 -277.446209) (xy 99.649425 -277.489786)
			(xy 99.61986 -277.52913) (xy 99.584367 -277.563222) (xy 99.543864 -277.591178) (xy 99.499402 -277.612276)
			(xy 99.452131 -277.625968) (xy 99.403276 -277.6319) (xy 99.354101 -277.629919) (xy 99.305882 -277.620075)
			(xy 99.259866 -277.602623) (xy 99.217245 -277.578016) (xy 99.179124 -277.546891) (xy 99.146489 -277.510054)
			(xy 99.120186 -277.468458) (xy 99.100895 -277.423182) (xy 99.089118 -277.375398) (xy 99.085158 -277.326344)
			(xy 98.75647 -277.326344) (xy 98.755975 -277.350951) (xy 98.74808 -277.399528) (xy 98.732496 -277.446209)
			(xy 98.709625 -277.489786) (xy 98.68006 -277.52913) (xy 98.644567 -277.563222) (xy 98.604064 -277.591178)
			(xy 98.559602 -277.612276) (xy 98.512331 -277.625968) (xy 98.463476 -277.6319) (xy 98.414301 -277.629919)
			(xy 98.366082 -277.620075) (xy 98.320066 -277.602623) (xy 98.277445 -277.578016) (xy 98.239324 -277.546891)
			(xy 98.206689 -277.510054) (xy 98.180386 -277.468458) (xy 98.161095 -277.423182) (xy 98.149318 -277.375398)
			(xy 98.145358 -277.326344) (xy 97.816416 -277.326344) (xy 97.815921 -277.350951) (xy 97.808026 -277.399528)
			(xy 97.792442 -277.446209) (xy 97.769571 -277.489786) (xy 97.740006 -277.52913) (xy 97.704513 -277.563222)
			(xy 97.66401 -277.591178) (xy 97.619548 -277.612276) (xy 97.572277 -277.625968) (xy 97.523422 -277.6319)
			(xy 97.474247 -277.629919) (xy 97.426028 -277.620075) (xy 97.380012 -277.602623) (xy 97.337391 -277.578016)
			(xy 97.29927 -277.546891) (xy 97.266635 -277.510054) (xy 97.240332 -277.468458) (xy 97.221041 -277.423182)
			(xy 97.209264 -277.375398) (xy 97.205304 -277.326344) (xy 96.876362 -277.326344) (xy 96.875898 -277.35095)
			(xy 96.868009 -277.399526) (xy 96.852429 -277.446207) (xy 96.829559 -277.489783) (xy 96.799993 -277.529124)
			(xy 96.764498 -277.563211) (xy 96.723992 -277.59116) (xy 96.679527 -277.612247) (xy 96.632253 -277.625926)
			(xy 96.607884 -277.629366) (xy 96.60509 -277.62962) (xy 96.599041 -277.630892) (xy 96.587746 -277.635903)
			(xy 96.582738 -277.639526) (xy 96.577658 -277.643336) (xy 96.573848 -277.648416) (xy 96.567244 -277.659846)
			(xy 96.533208 -277.742396) (xy 96.531269 -277.748286) (xy 96.529989 -277.760616) (xy 96.530668 -277.76678)
			(xy 96.532446 -277.779734) (xy 96.541082 -277.79091) (xy 96.565552 -277.823391) (xy 96.605839 -277.894031)
			(xy 96.621346 -277.931626) (xy 96.62414 -277.938484) (xy 96.63176 -277.948898) (xy 96.637348 -277.953216)
			(xy 96.64202 -277.956649) (xy 96.652538 -277.961515) (xy 96.658176 -277.962868) (xy 96.75114 -277.97506)
			(xy 96.754912 -277.975237) (xy 96.762436 -277.974593) (xy 96.766126 -277.97379) (xy 96.77527 -277.970996)
			(xy 96.787208 -277.965662) (xy 96.788478 -277.963884) (xy 96.795336 -277.95474) (xy 96.79559 -277.954232)
			(xy 96.810127 -277.93546) (xy 96.844026 -277.902219) (xy 96.882657 -277.874619) (xy 96.92509 -277.853323)
			(xy 96.970305 -277.838843) (xy 97.017215 -277.831527) (xy 97.040954 -277.831042) (xy 97.064949 -277.831509)
			(xy 97.112349 -277.839009) (xy 97.157993 -277.853832) (xy 97.200755 -277.875612) (xy 97.239584 -277.903814)
			(xy 97.273524 -277.937743) (xy 97.301738 -277.976563) (xy 97.323531 -278.019319) (xy 97.338368 -278.064957)
			(xy 97.345883 -278.112355) (xy 97.346262 -278.13635) (xy 97.675204 -278.13635) (xy 97.679164 -278.087296)
			(xy 97.690941 -278.039512) (xy 97.710232 -277.994236) (xy 97.736535 -277.95264) (xy 97.76917 -277.915803)
			(xy 97.807291 -277.884678) (xy 97.849912 -277.860071) (xy 97.895928 -277.842619) (xy 97.944147 -277.832775)
			(xy 97.993322 -277.830794) (xy 98.042177 -277.836726) (xy 98.089448 -277.850418) (xy 98.13391 -277.871516)
			(xy 98.174413 -277.899472) (xy 98.209906 -277.933564) (xy 98.239471 -277.972908) (xy 98.262342 -278.016485)
			(xy 98.277926 -278.063166) (xy 98.285821 -278.111743) (xy 98.286316 -278.13635) (xy 98.615258 -278.13635)
			(xy 98.619218 -278.087296) (xy 98.630995 -278.039512) (xy 98.650286 -277.994236) (xy 98.676589 -277.95264)
			(xy 98.709224 -277.915803) (xy 98.747345 -277.884678) (xy 98.789966 -277.860071) (xy 98.835982 -277.842619)
			(xy 98.884201 -277.832775) (xy 98.933376 -277.830794) (xy 98.982231 -277.836726) (xy 99.029502 -277.850418)
			(xy 99.073964 -277.871516) (xy 99.114467 -277.899472) (xy 99.14996 -277.933564) (xy 99.179525 -277.972908)
			(xy 99.202396 -278.016485) (xy 99.21798 -278.063166) (xy 99.225875 -278.111743) (xy 99.22637 -278.13635)
			(xy 99.555312 -278.13635) (xy 99.559272 -278.087296) (xy 99.571049 -278.039512) (xy 99.59034 -277.994236)
			(xy 99.616643 -277.95264) (xy 99.649278 -277.915803) (xy 99.687399 -277.884678) (xy 99.73002 -277.860071)
			(xy 99.776036 -277.842619) (xy 99.824255 -277.832775) (xy 99.87343 -277.830794) (xy 99.922285 -277.836726)
			(xy 99.969556 -277.850418) (xy 100.014018 -277.871516) (xy 100.054521 -277.899472) (xy 100.090014 -277.933564)
			(xy 100.119579 -277.972908) (xy 100.14245 -278.016485) (xy 100.158034 -278.063166) (xy 100.165929 -278.111743)
			(xy 100.166424 -278.13635) (xy 100.495366 -278.13635) (xy 100.499326 -278.087296) (xy 100.511103 -278.039512)
			(xy 100.530394 -277.994236) (xy 100.556697 -277.95264) (xy 100.589332 -277.915803) (xy 100.627453 -277.884678)
			(xy 100.670074 -277.860071) (xy 100.71609 -277.842619) (xy 100.764309 -277.832775) (xy 100.813484 -277.830794)
			(xy 100.862339 -277.836726) (xy 100.90961 -277.850418) (xy 100.954072 -277.871516) (xy 100.994575 -277.899472)
			(xy 101.030068 -277.933564) (xy 101.059633 -277.972908) (xy 101.082504 -278.016485) (xy 101.098088 -278.063166)
			(xy 101.105983 -278.111743) (xy 101.106478 -278.13635) (xy 101.435166 -278.13635) (xy 101.439126 -278.087296)
			(xy 101.450903 -278.039512) (xy 101.470194 -277.994236) (xy 101.496497 -277.95264) (xy 101.529132 -277.915803)
			(xy 101.567253 -277.884678) (xy 101.609874 -277.860071) (xy 101.65589 -277.842619) (xy 101.704109 -277.832775)
			(xy 101.753284 -277.830794) (xy 101.802139 -277.836726) (xy 101.84941 -277.850418) (xy 101.893872 -277.871516)
			(xy 101.934375 -277.899472) (xy 101.969868 -277.933564) (xy 101.999433 -277.972908) (xy 102.022304 -278.016485)
			(xy 102.037888 -278.063166) (xy 102.045783 -278.111743) (xy 102.046278 -278.13635) (xy 102.37522 -278.13635)
			(xy 102.37918 -278.087296) (xy 102.390957 -278.039512) (xy 102.410248 -277.994236) (xy 102.436551 -277.95264)
			(xy 102.469186 -277.915803) (xy 102.507307 -277.884678) (xy 102.549928 -277.860071) (xy 102.595944 -277.842619)
			(xy 102.644163 -277.832775) (xy 102.693338 -277.830794) (xy 102.742193 -277.836726) (xy 102.789464 -277.850418)
			(xy 102.833926 -277.871516) (xy 102.874429 -277.899472) (xy 102.909922 -277.933564) (xy 102.939487 -277.972908)
			(xy 102.962358 -278.016485) (xy 102.977942 -278.063166) (xy 102.985837 -278.111743) (xy 102.986332 -278.13635)
			(xy 103.315274 -278.13635) (xy 103.319234 -278.087296) (xy 103.331011 -278.039512) (xy 103.350302 -277.994236)
			(xy 103.376605 -277.95264) (xy 103.40924 -277.915803) (xy 103.447361 -277.884678) (xy 103.489982 -277.860071)
			(xy 103.535998 -277.842619) (xy 103.584217 -277.832775) (xy 103.633392 -277.830794) (xy 103.682247 -277.836726)
			(xy 103.729518 -277.850418) (xy 103.77398 -277.871516) (xy 103.814483 -277.899472) (xy 103.849976 -277.933564)
			(xy 103.879541 -277.972908) (xy 103.902412 -278.016485) (xy 103.917996 -278.063166) (xy 103.925891 -278.111743)
			(xy 103.926386 -278.13635) (xy 104.255328 -278.13635) (xy 104.259288 -278.087296) (xy 104.271065 -278.039512)
			(xy 104.290356 -277.994236) (xy 104.316659 -277.95264) (xy 104.349294 -277.915803) (xy 104.387415 -277.884678)
			(xy 104.430036 -277.860071) (xy 104.476052 -277.842619) (xy 104.524271 -277.832775) (xy 104.573446 -277.830794)
			(xy 104.622301 -277.836726) (xy 104.669572 -277.850418) (xy 104.714034 -277.871516) (xy 104.754537 -277.899472)
			(xy 104.79003 -277.933564) (xy 104.819595 -277.972908) (xy 104.842466 -278.016485) (xy 104.85805 -278.063166)
			(xy 104.865945 -278.111743) (xy 104.86644 -278.13635) (xy 105.195128 -278.13635) (xy 105.199088 -278.087296)
			(xy 105.210865 -278.039512) (xy 105.230156 -277.994236) (xy 105.256459 -277.95264) (xy 105.289094 -277.915803)
			(xy 105.327215 -277.884678) (xy 105.369836 -277.860071) (xy 105.415852 -277.842619) (xy 105.464071 -277.832775)
			(xy 105.513246 -277.830794) (xy 105.562101 -277.836726) (xy 105.609372 -277.850418) (xy 105.653834 -277.871516)
			(xy 105.694337 -277.899472) (xy 105.72983 -277.933564) (xy 105.759395 -277.972908) (xy 105.782266 -278.016485)
			(xy 105.79785 -278.063166) (xy 105.805745 -278.111743) (xy 105.80624 -278.13635) (xy 106.135182 -278.13635)
			(xy 106.139142 -278.087296) (xy 106.150919 -278.039512) (xy 106.17021 -277.994236) (xy 106.196513 -277.95264)
			(xy 106.229148 -277.915803) (xy 106.267269 -277.884678) (xy 106.30989 -277.860071) (xy 106.355906 -277.842619)
			(xy 106.404125 -277.832775) (xy 106.4533 -277.830794) (xy 106.502155 -277.836726) (xy 106.549426 -277.850418)
			(xy 106.593888 -277.871516) (xy 106.634391 -277.899472) (xy 106.669884 -277.933564) (xy 106.699449 -277.972908)
			(xy 106.72232 -278.016485) (xy 106.737904 -278.063166) (xy 106.745799 -278.111743) (xy 106.746294 -278.13635)
			(xy 107.075236 -278.13635) (xy 107.079196 -278.087296) (xy 107.090973 -278.039512) (xy 107.110264 -277.994236)
			(xy 107.136567 -277.95264) (xy 107.169202 -277.915803) (xy 107.207323 -277.884678) (xy 107.249944 -277.860071)
			(xy 107.29596 -277.842619) (xy 107.344179 -277.832775) (xy 107.393354 -277.830794) (xy 107.442209 -277.836726)
			(xy 107.48948 -277.850418) (xy 107.533942 -277.871516) (xy 107.574445 -277.899472) (xy 107.609938 -277.933564)
			(xy 107.639503 -277.972908) (xy 107.662374 -278.016485) (xy 107.677958 -278.063166) (xy 107.685853 -278.111743)
			(xy 107.686348 -278.13635) (xy 108.01529 -278.13635) (xy 108.01925 -278.087296) (xy 108.031027 -278.039512)
			(xy 108.050318 -277.994236) (xy 108.076621 -277.95264) (xy 108.109256 -277.915803) (xy 108.147377 -277.884678)
			(xy 108.189998 -277.860071) (xy 108.236014 -277.842619) (xy 108.284233 -277.832775) (xy 108.333408 -277.830794)
			(xy 108.382263 -277.836726) (xy 108.429534 -277.850418) (xy 108.473996 -277.871516) (xy 108.514499 -277.899472)
			(xy 108.549992 -277.933564) (xy 108.579557 -277.972908) (xy 108.602428 -278.016485) (xy 108.618012 -278.063166)
			(xy 108.625907 -278.111743) (xy 108.626402 -278.13635) (xy 115.528864 -278.13635) (xy 115.532824 -278.087296)
			(xy 115.544601 -278.039512) (xy 115.563892 -277.994236) (xy 115.590195 -277.95264) (xy 115.62283 -277.915803)
			(xy 115.660951 -277.884678) (xy 115.703572 -277.860071) (xy 115.749588 -277.842619) (xy 115.797807 -277.832775)
			(xy 115.846982 -277.830794) (xy 115.895837 -277.836726) (xy 115.943108 -277.850418) (xy 115.98757 -277.871516)
			(xy 116.028073 -277.899472) (xy 116.063566 -277.933564) (xy 116.093131 -277.972908) (xy 116.116002 -278.016485)
			(xy 116.131586 -278.063166) (xy 116.139481 -278.111743) (xy 116.139976 -278.13635) (xy 116.468918 -278.13635)
			(xy 116.472878 -278.087296) (xy 116.484655 -278.039512) (xy 116.503946 -277.994236) (xy 116.530249 -277.95264)
			(xy 116.562884 -277.915803) (xy 116.601005 -277.884678) (xy 116.643626 -277.860071) (xy 116.689642 -277.842619)
			(xy 116.737861 -277.832775) (xy 116.787036 -277.830794) (xy 116.835891 -277.836726) (xy 116.883162 -277.850418)
			(xy 116.927624 -277.871516) (xy 116.968127 -277.899472) (xy 117.00362 -277.933564) (xy 117.033185 -277.972908)
			(xy 117.056056 -278.016485) (xy 117.07164 -278.063166) (xy 117.079535 -278.111743) (xy 117.08003 -278.13635)
			(xy 117.408972 -278.13635) (xy 117.412932 -278.087296) (xy 117.424709 -278.039512) (xy 117.444 -277.994236)
			(xy 117.470303 -277.95264) (xy 117.502938 -277.915803) (xy 117.541059 -277.884678) (xy 117.58368 -277.860071)
			(xy 117.629696 -277.842619) (xy 117.677915 -277.832775) (xy 117.72709 -277.830794) (xy 117.775945 -277.836726)
			(xy 117.823216 -277.850418) (xy 117.867678 -277.871516) (xy 117.908181 -277.899472) (xy 117.943674 -277.933564)
			(xy 117.973239 -277.972908) (xy 117.99611 -278.016485) (xy 118.011694 -278.063166) (xy 118.019589 -278.111743)
			(xy 118.020084 -278.13635) (xy 118.349026 -278.13635) (xy 118.352986 -278.087296) (xy 118.364763 -278.039512)
			(xy 118.384054 -277.994236) (xy 118.410357 -277.95264) (xy 118.442992 -277.915803) (xy 118.481113 -277.884678)
			(xy 118.523734 -277.860071) (xy 118.56975 -277.842619) (xy 118.617969 -277.832775) (xy 118.667144 -277.830794)
			(xy 118.715999 -277.836726) (xy 118.76327 -277.850418) (xy 118.807732 -277.871516) (xy 118.848235 -277.899472)
			(xy 118.883728 -277.933564) (xy 118.913293 -277.972908) (xy 118.936164 -278.016485) (xy 118.951748 -278.063166)
			(xy 118.959643 -278.111743) (xy 118.960138 -278.13635) (xy 119.288826 -278.13635) (xy 119.292786 -278.087296)
			(xy 119.304563 -278.039512) (xy 119.323854 -277.994236) (xy 119.350157 -277.95264) (xy 119.382792 -277.915803)
			(xy 119.420913 -277.884678) (xy 119.463534 -277.860071) (xy 119.50955 -277.842619) (xy 119.557769 -277.832775)
			(xy 119.606944 -277.830794) (xy 119.655799 -277.836726) (xy 119.70307 -277.850418) (xy 119.747532 -277.871516)
			(xy 119.788035 -277.899472) (xy 119.823528 -277.933564) (xy 119.853093 -277.972908) (xy 119.875964 -278.016485)
			(xy 119.891548 -278.063166) (xy 119.899443 -278.111743) (xy 119.899938 -278.13635) (xy 120.22888 -278.13635)
			(xy 120.23284 -278.087296) (xy 120.244617 -278.039512) (xy 120.263908 -277.994236) (xy 120.290211 -277.95264)
			(xy 120.322846 -277.915803) (xy 120.360967 -277.884678) (xy 120.403588 -277.860071) (xy 120.449604 -277.842619)
			(xy 120.497823 -277.832775) (xy 120.546998 -277.830794) (xy 120.595853 -277.836726) (xy 120.643124 -277.850418)
			(xy 120.687586 -277.871516) (xy 120.728089 -277.899472) (xy 120.763582 -277.933564) (xy 120.793147 -277.972908)
			(xy 120.816018 -278.016485) (xy 120.831602 -278.063166) (xy 120.839497 -278.111743) (xy 120.839992 -278.13635)
			(xy 121.168934 -278.13635) (xy 121.172894 -278.087296) (xy 121.184671 -278.039512) (xy 121.203962 -277.994236)
			(xy 121.230265 -277.95264) (xy 121.2629 -277.915803) (xy 121.301021 -277.884678) (xy 121.343642 -277.860071)
			(xy 121.389658 -277.842619) (xy 121.437877 -277.832775) (xy 121.487052 -277.830794) (xy 121.535907 -277.836726)
			(xy 121.583178 -277.850418) (xy 121.62764 -277.871516) (xy 121.668143 -277.899472) (xy 121.703636 -277.933564)
			(xy 121.733201 -277.972908) (xy 121.756072 -278.016485) (xy 121.771656 -278.063166) (xy 121.779551 -278.111743)
			(xy 121.780046 -278.13635) (xy 122.108988 -278.13635) (xy 122.112948 -278.087296) (xy 122.124725 -278.039512)
			(xy 122.144016 -277.994236) (xy 122.170319 -277.95264) (xy 122.202954 -277.915803) (xy 122.241075 -277.884678)
			(xy 122.283696 -277.860071) (xy 122.329712 -277.842619) (xy 122.377931 -277.832775) (xy 122.427106 -277.830794)
			(xy 122.475961 -277.836726) (xy 122.523232 -277.850418) (xy 122.567694 -277.871516) (xy 122.608197 -277.899472)
			(xy 122.64369 -277.933564) (xy 122.673255 -277.972908) (xy 122.696126 -278.016485) (xy 122.71171 -278.063166)
			(xy 122.719605 -278.111743) (xy 122.7201 -278.13635) (xy 123.049042 -278.13635) (xy 123.053002 -278.087296)
			(xy 123.064779 -278.039512) (xy 123.08407 -277.994236) (xy 123.110373 -277.95264) (xy 123.143008 -277.915803)
			(xy 123.181129 -277.884678) (xy 123.22375 -277.860071) (xy 123.269766 -277.842619) (xy 123.317985 -277.832775)
			(xy 123.36716 -277.830794) (xy 123.416015 -277.836726) (xy 123.463286 -277.850418) (xy 123.507748 -277.871516)
			(xy 123.548251 -277.899472) (xy 123.583744 -277.933564) (xy 123.613309 -277.972908) (xy 123.63618 -278.016485)
			(xy 123.651764 -278.063166) (xy 123.659659 -278.111743) (xy 123.660154 -278.13635) (xy 123.988842 -278.13635)
			(xy 123.992802 -278.087296) (xy 124.004579 -278.039512) (xy 124.02387 -277.994236) (xy 124.050173 -277.95264)
			(xy 124.082808 -277.915803) (xy 124.120929 -277.884678) (xy 124.16355 -277.860071) (xy 124.209566 -277.842619)
			(xy 124.257785 -277.832775) (xy 124.30696 -277.830794) (xy 124.355815 -277.836726) (xy 124.403086 -277.850418)
			(xy 124.447548 -277.871516) (xy 124.488051 -277.899472) (xy 124.523544 -277.933564) (xy 124.553109 -277.972908)
			(xy 124.57598 -278.016485) (xy 124.591564 -278.063166) (xy 124.599459 -278.111743) (xy 124.599954 -278.13635)
			(xy 124.928896 -278.13635) (xy 124.932856 -278.087296) (xy 124.944633 -278.039512) (xy 124.963924 -277.994236)
			(xy 124.990227 -277.95264) (xy 125.022862 -277.915803) (xy 125.060983 -277.884678) (xy 125.103604 -277.860071)
			(xy 125.14962 -277.842619) (xy 125.197839 -277.832775) (xy 125.247014 -277.830794) (xy 125.295869 -277.836726)
			(xy 125.34314 -277.850418) (xy 125.387602 -277.871516) (xy 125.428105 -277.899472) (xy 125.463598 -277.933564)
			(xy 125.493163 -277.972908) (xy 125.516034 -278.016485) (xy 125.531618 -278.063166) (xy 125.539513 -278.111743)
			(xy 125.540008 -278.13635) (xy 125.86895 -278.13635) (xy 125.87291 -278.087296) (xy 125.884687 -278.039512)
			(xy 125.903978 -277.994236) (xy 125.930281 -277.95264) (xy 125.962916 -277.915803) (xy 126.001037 -277.884678)
			(xy 126.043658 -277.860071) (xy 126.089674 -277.842619) (xy 126.137893 -277.832775) (xy 126.187068 -277.830794)
			(xy 126.235923 -277.836726) (xy 126.283194 -277.850418) (xy 126.327656 -277.871516) (xy 126.368159 -277.899472)
			(xy 126.403652 -277.933564) (xy 126.433217 -277.972908) (xy 126.456088 -278.016485) (xy 126.471672 -278.063166)
			(xy 126.479567 -278.111743) (xy 126.480062 -278.13635) (xy 126.479567 -278.160957) (xy 126.471672 -278.209534)
			(xy 126.456088 -278.256215) (xy 126.433217 -278.299792) (xy 126.403652 -278.339136) (xy 126.368159 -278.373228)
			(xy 126.327656 -278.401184) (xy 126.283194 -278.422282) (xy 126.235923 -278.435974) (xy 126.187068 -278.441906)
			(xy 126.137893 -278.439925) (xy 126.089674 -278.430081) (xy 126.043658 -278.412629) (xy 126.001037 -278.388022)
			(xy 125.962916 -278.356897) (xy 125.930281 -278.32006) (xy 125.903978 -278.278464) (xy 125.884687 -278.233188)
			(xy 125.87291 -278.185404) (xy 125.86895 -278.13635) (xy 125.540008 -278.13635) (xy 125.539513 -278.160957)
			(xy 125.531618 -278.209534) (xy 125.516034 -278.256215) (xy 125.493163 -278.299792) (xy 125.463598 -278.339136)
			(xy 125.428105 -278.373228) (xy 125.387602 -278.401184) (xy 125.34314 -278.422282) (xy 125.295869 -278.435974)
			(xy 125.247014 -278.441906) (xy 125.197839 -278.439925) (xy 125.14962 -278.430081) (xy 125.103604 -278.412629)
			(xy 125.060983 -278.388022) (xy 125.022862 -278.356897) (xy 124.990227 -278.32006) (xy 124.963924 -278.278464)
			(xy 124.944633 -278.233188) (xy 124.932856 -278.185404) (xy 124.928896 -278.13635) (xy 124.599954 -278.13635)
			(xy 124.599459 -278.160957) (xy 124.591564 -278.209534) (xy 124.57598 -278.256215) (xy 124.553109 -278.299792)
			(xy 124.523544 -278.339136) (xy 124.488051 -278.373228) (xy 124.447548 -278.401184) (xy 124.403086 -278.422282)
			(xy 124.355815 -278.435974) (xy 124.30696 -278.441906) (xy 124.257785 -278.439925) (xy 124.209566 -278.430081)
			(xy 124.16355 -278.412629) (xy 124.120929 -278.388022) (xy 124.082808 -278.356897) (xy 124.050173 -278.32006)
			(xy 124.02387 -278.278464) (xy 124.004579 -278.233188) (xy 123.992802 -278.185404) (xy 123.988842 -278.13635)
			(xy 123.660154 -278.13635) (xy 123.659659 -278.160957) (xy 123.651764 -278.209534) (xy 123.63618 -278.256215)
			(xy 123.613309 -278.299792) (xy 123.583744 -278.339136) (xy 123.548251 -278.373228) (xy 123.507748 -278.401184)
			(xy 123.463286 -278.422282) (xy 123.416015 -278.435974) (xy 123.36716 -278.441906) (xy 123.317985 -278.439925)
			(xy 123.269766 -278.430081) (xy 123.22375 -278.412629) (xy 123.181129 -278.388022) (xy 123.143008 -278.356897)
			(xy 123.110373 -278.32006) (xy 123.08407 -278.278464) (xy 123.064779 -278.233188) (xy 123.053002 -278.185404)
			(xy 123.049042 -278.13635) (xy 122.7201 -278.13635) (xy 122.719605 -278.160957) (xy 122.71171 -278.209534)
			(xy 122.696126 -278.256215) (xy 122.673255 -278.299792) (xy 122.64369 -278.339136) (xy 122.608197 -278.373228)
			(xy 122.567694 -278.401184) (xy 122.523232 -278.422282) (xy 122.475961 -278.435974) (xy 122.427106 -278.441906)
			(xy 122.377931 -278.439925) (xy 122.329712 -278.430081) (xy 122.283696 -278.412629) (xy 122.241075 -278.388022)
			(xy 122.202954 -278.356897) (xy 122.170319 -278.32006) (xy 122.144016 -278.278464) (xy 122.124725 -278.233188)
			(xy 122.112948 -278.185404) (xy 122.108988 -278.13635) (xy 121.780046 -278.13635) (xy 121.779551 -278.160957)
			(xy 121.771656 -278.209534) (xy 121.756072 -278.256215) (xy 121.733201 -278.299792) (xy 121.703636 -278.339136)
			(xy 121.668143 -278.373228) (xy 121.62764 -278.401184) (xy 121.583178 -278.422282) (xy 121.535907 -278.435974)
			(xy 121.487052 -278.441906) (xy 121.437877 -278.439925) (xy 121.389658 -278.430081) (xy 121.343642 -278.412629)
			(xy 121.301021 -278.388022) (xy 121.2629 -278.356897) (xy 121.230265 -278.32006) (xy 121.203962 -278.278464)
			(xy 121.184671 -278.233188) (xy 121.172894 -278.185404) (xy 121.168934 -278.13635) (xy 120.839992 -278.13635)
			(xy 120.839497 -278.160957) (xy 120.831602 -278.209534) (xy 120.816018 -278.256215) (xy 120.793147 -278.299792)
			(xy 120.763582 -278.339136) (xy 120.728089 -278.373228) (xy 120.687586 -278.401184) (xy 120.643124 -278.422282)
			(xy 120.595853 -278.435974) (xy 120.546998 -278.441906) (xy 120.497823 -278.439925) (xy 120.449604 -278.430081)
			(xy 120.403588 -278.412629) (xy 120.360967 -278.388022) (xy 120.322846 -278.356897) (xy 120.290211 -278.32006)
			(xy 120.263908 -278.278464) (xy 120.244617 -278.233188) (xy 120.23284 -278.185404) (xy 120.22888 -278.13635)
			(xy 119.899938 -278.13635) (xy 119.899443 -278.160957) (xy 119.891548 -278.209534) (xy 119.875964 -278.256215)
			(xy 119.853093 -278.299792) (xy 119.823528 -278.339136) (xy 119.788035 -278.373228) (xy 119.747532 -278.401184)
			(xy 119.70307 -278.422282) (xy 119.655799 -278.435974) (xy 119.606944 -278.441906) (xy 119.557769 -278.439925)
			(xy 119.50955 -278.430081) (xy 119.463534 -278.412629) (xy 119.420913 -278.388022) (xy 119.382792 -278.356897)
			(xy 119.350157 -278.32006) (xy 119.323854 -278.278464) (xy 119.304563 -278.233188) (xy 119.292786 -278.185404)
			(xy 119.288826 -278.13635) (xy 118.960138 -278.13635) (xy 118.959643 -278.160957) (xy 118.951748 -278.209534)
			(xy 118.936164 -278.256215) (xy 118.913293 -278.299792) (xy 118.883728 -278.339136) (xy 118.848235 -278.373228)
			(xy 118.807732 -278.401184) (xy 118.76327 -278.422282) (xy 118.715999 -278.435974) (xy 118.667144 -278.441906)
			(xy 118.617969 -278.439925) (xy 118.56975 -278.430081) (xy 118.523734 -278.412629) (xy 118.481113 -278.388022)
			(xy 118.442992 -278.356897) (xy 118.410357 -278.32006) (xy 118.384054 -278.278464) (xy 118.364763 -278.233188)
			(xy 118.352986 -278.185404) (xy 118.349026 -278.13635) (xy 118.020084 -278.13635) (xy 118.019589 -278.160957)
			(xy 118.011694 -278.209534) (xy 117.99611 -278.256215) (xy 117.973239 -278.299792) (xy 117.943674 -278.339136)
			(xy 117.908181 -278.373228) (xy 117.867678 -278.401184) (xy 117.823216 -278.422282) (xy 117.775945 -278.435974)
			(xy 117.72709 -278.441906) (xy 117.677915 -278.439925) (xy 117.629696 -278.430081) (xy 117.58368 -278.412629)
			(xy 117.541059 -278.388022) (xy 117.502938 -278.356897) (xy 117.470303 -278.32006) (xy 117.444 -278.278464)
			(xy 117.424709 -278.233188) (xy 117.412932 -278.185404) (xy 117.408972 -278.13635) (xy 117.08003 -278.13635)
			(xy 117.079535 -278.160957) (xy 117.07164 -278.209534) (xy 117.056056 -278.256215) (xy 117.033185 -278.299792)
			(xy 117.00362 -278.339136) (xy 116.968127 -278.373228) (xy 116.927624 -278.401184) (xy 116.883162 -278.422282)
			(xy 116.835891 -278.435974) (xy 116.787036 -278.441906) (xy 116.737861 -278.439925) (xy 116.689642 -278.430081)
			(xy 116.643626 -278.412629) (xy 116.601005 -278.388022) (xy 116.562884 -278.356897) (xy 116.530249 -278.32006)
			(xy 116.503946 -278.278464) (xy 116.484655 -278.233188) (xy 116.472878 -278.185404) (xy 116.468918 -278.13635)
			(xy 116.139976 -278.13635) (xy 116.139481 -278.160957) (xy 116.131586 -278.209534) (xy 116.116002 -278.256215)
			(xy 116.093131 -278.299792) (xy 116.063566 -278.339136) (xy 116.028073 -278.373228) (xy 115.98757 -278.401184)
			(xy 115.943108 -278.422282) (xy 115.895837 -278.435974) (xy 115.846982 -278.441906) (xy 115.797807 -278.439925)
			(xy 115.749588 -278.430081) (xy 115.703572 -278.412629) (xy 115.660951 -278.388022) (xy 115.62283 -278.356897)
			(xy 115.590195 -278.32006) (xy 115.563892 -278.278464) (xy 115.544601 -278.233188) (xy 115.532824 -278.185404)
			(xy 115.528864 -278.13635) (xy 108.626402 -278.13635) (xy 108.625907 -278.160957) (xy 108.618012 -278.209534)
			(xy 108.602428 -278.256215) (xy 108.579557 -278.299792) (xy 108.549992 -278.339136) (xy 108.514499 -278.373228)
			(xy 108.473996 -278.401184) (xy 108.429534 -278.422282) (xy 108.382263 -278.435974) (xy 108.333408 -278.441906)
			(xy 108.284233 -278.439925) (xy 108.236014 -278.430081) (xy 108.189998 -278.412629) (xy 108.147377 -278.388022)
			(xy 108.109256 -278.356897) (xy 108.076621 -278.32006) (xy 108.050318 -278.278464) (xy 108.031027 -278.233188)
			(xy 108.01925 -278.185404) (xy 108.01529 -278.13635) (xy 107.686348 -278.13635) (xy 107.685853 -278.160957)
			(xy 107.677958 -278.209534) (xy 107.662374 -278.256215) (xy 107.639503 -278.299792) (xy 107.609938 -278.339136)
			(xy 107.574445 -278.373228) (xy 107.533942 -278.401184) (xy 107.48948 -278.422282) (xy 107.442209 -278.435974)
			(xy 107.393354 -278.441906) (xy 107.344179 -278.439925) (xy 107.29596 -278.430081) (xy 107.249944 -278.412629)
			(xy 107.207323 -278.388022) (xy 107.169202 -278.356897) (xy 107.136567 -278.32006) (xy 107.110264 -278.278464)
			(xy 107.090973 -278.233188) (xy 107.079196 -278.185404) (xy 107.075236 -278.13635) (xy 106.746294 -278.13635)
			(xy 106.745799 -278.160957) (xy 106.737904 -278.209534) (xy 106.72232 -278.256215) (xy 106.699449 -278.299792)
			(xy 106.669884 -278.339136) (xy 106.634391 -278.373228) (xy 106.593888 -278.401184) (xy 106.549426 -278.422282)
			(xy 106.502155 -278.435974) (xy 106.4533 -278.441906) (xy 106.404125 -278.439925) (xy 106.355906 -278.430081)
			(xy 106.30989 -278.412629) (xy 106.267269 -278.388022) (xy 106.229148 -278.356897) (xy 106.196513 -278.32006)
			(xy 106.17021 -278.278464) (xy 106.150919 -278.233188) (xy 106.139142 -278.185404) (xy 106.135182 -278.13635)
			(xy 105.80624 -278.13635) (xy 105.805745 -278.160957) (xy 105.79785 -278.209534) (xy 105.782266 -278.256215)
			(xy 105.759395 -278.299792) (xy 105.72983 -278.339136) (xy 105.694337 -278.373228) (xy 105.653834 -278.401184)
			(xy 105.609372 -278.422282) (xy 105.562101 -278.435974) (xy 105.513246 -278.441906) (xy 105.464071 -278.439925)
			(xy 105.415852 -278.430081) (xy 105.369836 -278.412629) (xy 105.327215 -278.388022) (xy 105.289094 -278.356897)
			(xy 105.256459 -278.32006) (xy 105.230156 -278.278464) (xy 105.210865 -278.233188) (xy 105.199088 -278.185404)
			(xy 105.195128 -278.13635) (xy 104.86644 -278.13635) (xy 104.865945 -278.160957) (xy 104.85805 -278.209534)
			(xy 104.842466 -278.256215) (xy 104.819595 -278.299792) (xy 104.79003 -278.339136) (xy 104.754537 -278.373228)
			(xy 104.714034 -278.401184) (xy 104.669572 -278.422282) (xy 104.622301 -278.435974) (xy 104.573446 -278.441906)
			(xy 104.524271 -278.439925) (xy 104.476052 -278.430081) (xy 104.430036 -278.412629) (xy 104.387415 -278.388022)
			(xy 104.349294 -278.356897) (xy 104.316659 -278.32006) (xy 104.290356 -278.278464) (xy 104.271065 -278.233188)
			(xy 104.259288 -278.185404) (xy 104.255328 -278.13635) (xy 103.926386 -278.13635) (xy 103.925891 -278.160957)
			(xy 103.917996 -278.209534) (xy 103.902412 -278.256215) (xy 103.879541 -278.299792) (xy 103.849976 -278.339136)
			(xy 103.814483 -278.373228) (xy 103.77398 -278.401184) (xy 103.729518 -278.422282) (xy 103.682247 -278.435974)
			(xy 103.633392 -278.441906) (xy 103.584217 -278.439925) (xy 103.535998 -278.430081) (xy 103.489982 -278.412629)
			(xy 103.447361 -278.388022) (xy 103.40924 -278.356897) (xy 103.376605 -278.32006) (xy 103.350302 -278.278464)
			(xy 103.331011 -278.233188) (xy 103.319234 -278.185404) (xy 103.315274 -278.13635) (xy 102.986332 -278.13635)
			(xy 102.985837 -278.160957) (xy 102.977942 -278.209534) (xy 102.962358 -278.256215) (xy 102.939487 -278.299792)
			(xy 102.909922 -278.339136) (xy 102.874429 -278.373228) (xy 102.833926 -278.401184) (xy 102.789464 -278.422282)
			(xy 102.742193 -278.435974) (xy 102.693338 -278.441906) (xy 102.644163 -278.439925) (xy 102.595944 -278.430081)
			(xy 102.549928 -278.412629) (xy 102.507307 -278.388022) (xy 102.469186 -278.356897) (xy 102.436551 -278.32006)
			(xy 102.410248 -278.278464) (xy 102.390957 -278.233188) (xy 102.37918 -278.185404) (xy 102.37522 -278.13635)
			(xy 102.046278 -278.13635) (xy 102.045783 -278.160957) (xy 102.037888 -278.209534) (xy 102.022304 -278.256215)
			(xy 101.999433 -278.299792) (xy 101.969868 -278.339136) (xy 101.934375 -278.373228) (xy 101.893872 -278.401184)
			(xy 101.84941 -278.422282) (xy 101.802139 -278.435974) (xy 101.753284 -278.441906) (xy 101.704109 -278.439925)
			(xy 101.65589 -278.430081) (xy 101.609874 -278.412629) (xy 101.567253 -278.388022) (xy 101.529132 -278.356897)
			(xy 101.496497 -278.32006) (xy 101.470194 -278.278464) (xy 101.450903 -278.233188) (xy 101.439126 -278.185404)
			(xy 101.435166 -278.13635) (xy 101.106478 -278.13635) (xy 101.105983 -278.160957) (xy 101.098088 -278.209534)
			(xy 101.082504 -278.256215) (xy 101.059633 -278.299792) (xy 101.030068 -278.339136) (xy 100.994575 -278.373228)
			(xy 100.954072 -278.401184) (xy 100.90961 -278.422282) (xy 100.862339 -278.435974) (xy 100.813484 -278.441906)
			(xy 100.764309 -278.439925) (xy 100.71609 -278.430081) (xy 100.670074 -278.412629) (xy 100.627453 -278.388022)
			(xy 100.589332 -278.356897) (xy 100.556697 -278.32006) (xy 100.530394 -278.278464) (xy 100.511103 -278.233188)
			(xy 100.499326 -278.185404) (xy 100.495366 -278.13635) (xy 100.166424 -278.13635) (xy 100.165929 -278.160957)
			(xy 100.158034 -278.209534) (xy 100.14245 -278.256215) (xy 100.119579 -278.299792) (xy 100.090014 -278.339136)
			(xy 100.054521 -278.373228) (xy 100.014018 -278.401184) (xy 99.969556 -278.422282) (xy 99.922285 -278.435974)
			(xy 99.87343 -278.441906) (xy 99.824255 -278.439925) (xy 99.776036 -278.430081) (xy 99.73002 -278.412629)
			(xy 99.687399 -278.388022) (xy 99.649278 -278.356897) (xy 99.616643 -278.32006) (xy 99.59034 -278.278464)
			(xy 99.571049 -278.233188) (xy 99.559272 -278.185404) (xy 99.555312 -278.13635) (xy 99.22637 -278.13635)
			(xy 99.225875 -278.160957) (xy 99.21798 -278.209534) (xy 99.202396 -278.256215) (xy 99.179525 -278.299792)
			(xy 99.14996 -278.339136) (xy 99.114467 -278.373228) (xy 99.073964 -278.401184) (xy 99.029502 -278.422282)
			(xy 98.982231 -278.435974) (xy 98.933376 -278.441906) (xy 98.884201 -278.439925) (xy 98.835982 -278.430081)
			(xy 98.789966 -278.412629) (xy 98.747345 -278.388022) (xy 98.709224 -278.356897) (xy 98.676589 -278.32006)
			(xy 98.650286 -278.278464) (xy 98.630995 -278.233188) (xy 98.619218 -278.185404) (xy 98.615258 -278.13635)
			(xy 98.286316 -278.13635) (xy 98.285821 -278.160957) (xy 98.277926 -278.209534) (xy 98.262342 -278.256215)
			(xy 98.239471 -278.299792) (xy 98.209906 -278.339136) (xy 98.174413 -278.373228) (xy 98.13391 -278.401184)
			(xy 98.089448 -278.422282) (xy 98.042177 -278.435974) (xy 97.993322 -278.441906) (xy 97.944147 -278.439925)
			(xy 97.895928 -278.430081) (xy 97.849912 -278.412629) (xy 97.807291 -278.388022) (xy 97.76917 -278.356897)
			(xy 97.736535 -278.32006) (xy 97.710232 -278.278464) (xy 97.690941 -278.233188) (xy 97.679164 -278.185404)
			(xy 97.675204 -278.13635) (xy 97.346262 -278.13635) (xy 97.345793 -278.160588) (xy 97.338129 -278.208453)
			(xy 97.323002 -278.254508) (xy 97.30079 -278.297595) (xy 97.272052 -278.336634) (xy 97.237509 -278.370643)
			(xy 97.198027 -278.39877) (xy 97.1546 -278.420308) (xy 97.108315 -278.434717) (xy 97.084388 -278.43861)
			(xy 97.071942 -278.440388) (xy 97.040954 -278.441912) (xy 97.017459 -278.441479) (xy 96.971022 -278.434284)
			(xy 96.926233 -278.42007) (xy 96.884145 -278.399172) (xy 96.845749 -278.372082) (xy 96.811949 -278.339438)
			(xy 96.797368 -278.321008) (xy 96.795336 -278.318214) (xy 96.795082 -278.31796) (xy 96.790944 -278.312588)
			(xy 96.780388 -278.304085) (xy 96.774254 -278.301196) (xy 96.768412 -278.29891) (xy 96.755204 -278.297132)
			(xy 96.661986 -278.309324) (xy 96.655311 -278.310372) (xy 96.642825 -278.315526) (xy 96.637348 -278.319484)
			(xy 96.63176 -278.323802) (xy 96.62414 -278.334216) (xy 96.621346 -278.341328) (xy 96.613469 -278.3609)
			(xy 96.595165 -278.398915) (xy 96.58477 -278.417274) (xy 96.539812 -278.494744) (xy 96.53421 -278.505813)
			(xy 96.533414 -278.53058) (xy 96.538288 -278.541988) (xy 96.552766 -278.571452) (xy 96.576388 -278.61895)
			(xy 96.57715 -278.62022) (xy 96.579846 -278.624464) (xy 96.58663 -278.631882) (xy 96.590612 -278.634952)
			(xy 96.600518 -278.642064) (xy 96.613218 -278.643842) (xy 96.637224 -278.647689) (xy 96.683688 -278.661987)
			(xy 96.727303 -278.683461) (xy 96.766968 -278.711569) (xy 96.801684 -278.745602) (xy 96.830574 -278.784701)
			(xy 96.852911 -278.82788) (xy 96.86813 -278.874051) (xy 96.875849 -278.922049) (xy 96.876362 -278.946356)
			(xy 99.085158 -278.946356) (xy 99.089118 -278.897302) (xy 99.100895 -278.849518) (xy 99.120186 -278.804242)
			(xy 99.146489 -278.762646) (xy 99.179124 -278.725809) (xy 99.217245 -278.694684) (xy 99.259866 -278.670077)
			(xy 99.305882 -278.652625) (xy 99.354101 -278.642781) (xy 99.403276 -278.6408) (xy 99.452131 -278.646732)
			(xy 99.499402 -278.660424) (xy 99.543864 -278.681522) (xy 99.584367 -278.709478) (xy 99.61986 -278.74357)
			(xy 99.649425 -278.782914) (xy 99.672296 -278.826491) (xy 99.68788 -278.873172) (xy 99.695775 -278.921749)
			(xy 99.69627 -278.946356) (xy 101.90532 -278.946356) (xy 101.90928 -278.897302) (xy 101.921057 -278.849518)
			(xy 101.940348 -278.804242) (xy 101.966651 -278.762646) (xy 101.999286 -278.725809) (xy 102.037407 -278.694684)
			(xy 102.080028 -278.670077) (xy 102.126044 -278.652625) (xy 102.174263 -278.642781) (xy 102.223438 -278.6408)
			(xy 102.272293 -278.646732) (xy 102.319564 -278.660424) (xy 102.364026 -278.681522) (xy 102.404529 -278.709478)
			(xy 102.440022 -278.74357) (xy 102.469587 -278.782914) (xy 102.492458 -278.826491) (xy 102.508042 -278.873172)
			(xy 102.515937 -278.921749) (xy 102.516432 -278.946356) (xy 104.725228 -278.946356) (xy 104.729188 -278.897302)
			(xy 104.740965 -278.849518) (xy 104.760256 -278.804242) (xy 104.786559 -278.762646) (xy 104.819194 -278.725809)
			(xy 104.857315 -278.694684) (xy 104.899936 -278.670077) (xy 104.945952 -278.652625) (xy 104.994171 -278.642781)
			(xy 105.043346 -278.6408) (xy 105.092201 -278.646732) (xy 105.139472 -278.660424) (xy 105.183934 -278.681522)
			(xy 105.224437 -278.709478) (xy 105.25993 -278.74357) (xy 105.289495 -278.782914) (xy 105.312366 -278.826491)
			(xy 105.32795 -278.873172) (xy 105.335845 -278.921749) (xy 105.33634 -278.946356) (xy 107.545136 -278.946356)
			(xy 107.549096 -278.897302) (xy 107.560873 -278.849518) (xy 107.580164 -278.804242) (xy 107.606467 -278.762646)
			(xy 107.639102 -278.725809) (xy 107.677223 -278.694684) (xy 107.719844 -278.670077) (xy 107.76586 -278.652625)
			(xy 107.814079 -278.642781) (xy 107.863254 -278.6408) (xy 107.912109 -278.646732) (xy 107.95938 -278.660424)
			(xy 108.003842 -278.681522) (xy 108.044345 -278.709478) (xy 108.079838 -278.74357) (xy 108.109403 -278.782914)
			(xy 108.132274 -278.826491) (xy 108.147858 -278.873172) (xy 108.155753 -278.921749) (xy 108.156248 -278.946356)
			(xy 108.48519 -278.946356) (xy 108.48915 -278.897302) (xy 108.500927 -278.849518) (xy 108.520218 -278.804242)
			(xy 108.546521 -278.762646) (xy 108.579156 -278.725809) (xy 108.617277 -278.694684) (xy 108.659898 -278.670077)
			(xy 108.705914 -278.652625) (xy 108.754133 -278.642781) (xy 108.803308 -278.6408) (xy 108.852163 -278.646732)
			(xy 108.899434 -278.660424) (xy 108.943896 -278.681522) (xy 108.984399 -278.709478) (xy 109.019892 -278.74357)
			(xy 109.049457 -278.782914) (xy 109.072328 -278.826491) (xy 109.087912 -278.873172) (xy 109.095807 -278.921749)
			(xy 109.096302 -278.946356) (xy 109.425244 -278.946356) (xy 109.429204 -278.897302) (xy 109.440981 -278.849518)
			(xy 109.460272 -278.804242) (xy 109.486575 -278.762646) (xy 109.51921 -278.725809) (xy 109.557331 -278.694684)
			(xy 109.599952 -278.670077) (xy 109.645968 -278.652625) (xy 109.694187 -278.642781) (xy 109.743362 -278.6408)
			(xy 109.792217 -278.646732) (xy 109.839488 -278.660424) (xy 109.88395 -278.681522) (xy 109.924453 -278.709478)
			(xy 109.959946 -278.74357) (xy 109.989511 -278.782914) (xy 110.012382 -278.826491) (xy 110.027966 -278.873172)
			(xy 110.035861 -278.921749) (xy 110.036356 -278.946356) (xy 110.365298 -278.946356) (xy 110.369258 -278.897302)
			(xy 110.381035 -278.849518) (xy 110.400326 -278.804242) (xy 110.426629 -278.762646) (xy 110.459264 -278.725809)
			(xy 110.497385 -278.694684) (xy 110.540006 -278.670077) (xy 110.586022 -278.652625) (xy 110.634241 -278.642781)
			(xy 110.683416 -278.6408) (xy 110.732271 -278.646732) (xy 110.779542 -278.660424) (xy 110.824004 -278.681522)
			(xy 110.864507 -278.709478) (xy 110.9 -278.74357) (xy 110.929565 -278.782914) (xy 110.952436 -278.826491)
			(xy 110.96802 -278.873172) (xy 110.975915 -278.921749) (xy 110.97641 -278.946356) (xy 113.178856 -278.946356)
			(xy 113.182816 -278.897302) (xy 113.194593 -278.849518) (xy 113.213884 -278.804242) (xy 113.240187 -278.762646)
			(xy 113.272822 -278.725809) (xy 113.310943 -278.694684) (xy 113.353564 -278.670077) (xy 113.39958 -278.652625)
			(xy 113.447799 -278.642781) (xy 113.496974 -278.6408) (xy 113.545829 -278.646732) (xy 113.5931 -278.660424)
			(xy 113.637562 -278.681522) (xy 113.678065 -278.709478) (xy 113.713558 -278.74357) (xy 113.743123 -278.782914)
			(xy 113.765994 -278.826491) (xy 113.781578 -278.873172) (xy 113.789473 -278.921749) (xy 113.789968 -278.946356)
			(xy 114.11891 -278.946356) (xy 114.12287 -278.897302) (xy 114.134647 -278.849518) (xy 114.153938 -278.804242)
			(xy 114.180241 -278.762646) (xy 114.212876 -278.725809) (xy 114.250997 -278.694684) (xy 114.293618 -278.670077)
			(xy 114.339634 -278.652625) (xy 114.387853 -278.642781) (xy 114.437028 -278.6408) (xy 114.485883 -278.646732)
			(xy 114.533154 -278.660424) (xy 114.577616 -278.681522) (xy 114.618119 -278.709478) (xy 114.653612 -278.74357)
			(xy 114.683177 -278.782914) (xy 114.706048 -278.826491) (xy 114.721632 -278.873172) (xy 114.729527 -278.921749)
			(xy 114.730022 -278.946356) (xy 115.058964 -278.946356) (xy 115.062924 -278.897302) (xy 115.074701 -278.849518)
			(xy 115.093992 -278.804242) (xy 115.120295 -278.762646) (xy 115.15293 -278.725809) (xy 115.191051 -278.694684)
			(xy 115.233672 -278.670077) (xy 115.279688 -278.652625) (xy 115.327907 -278.642781) (xy 115.377082 -278.6408)
			(xy 115.425937 -278.646732) (xy 115.473208 -278.660424) (xy 115.51767 -278.681522) (xy 115.558173 -278.709478)
			(xy 115.593666 -278.74357) (xy 115.623231 -278.782914) (xy 115.646102 -278.826491) (xy 115.661686 -278.873172)
			(xy 115.669581 -278.921749) (xy 115.670076 -278.946356) (xy 115.999018 -278.946356) (xy 116.002978 -278.897302)
			(xy 116.014755 -278.849518) (xy 116.034046 -278.804242) (xy 116.060349 -278.762646) (xy 116.092984 -278.725809)
			(xy 116.131105 -278.694684) (xy 116.173726 -278.670077) (xy 116.219742 -278.652625) (xy 116.267961 -278.642781)
			(xy 116.317136 -278.6408) (xy 116.365991 -278.646732) (xy 116.413262 -278.660424) (xy 116.457724 -278.681522)
			(xy 116.498227 -278.709478) (xy 116.53372 -278.74357) (xy 116.563285 -278.782914) (xy 116.586156 -278.826491)
			(xy 116.60174 -278.873172) (xy 116.609635 -278.921749) (xy 116.61013 -278.946356) (xy 118.818926 -278.946356)
			(xy 118.822886 -278.897302) (xy 118.834663 -278.849518) (xy 118.853954 -278.804242) (xy 118.880257 -278.762646)
			(xy 118.912892 -278.725809) (xy 118.951013 -278.694684) (xy 118.993634 -278.670077) (xy 119.03965 -278.652625)
			(xy 119.087869 -278.642781) (xy 119.137044 -278.6408) (xy 119.185899 -278.646732) (xy 119.23317 -278.660424)
			(xy 119.277632 -278.681522) (xy 119.318135 -278.709478) (xy 119.353628 -278.74357) (xy 119.383193 -278.782914)
			(xy 119.406064 -278.826491) (xy 119.421648 -278.873172) (xy 119.429543 -278.921749) (xy 119.430038 -278.946356)
			(xy 121.638834 -278.946356) (xy 121.642794 -278.897302) (xy 121.654571 -278.849518) (xy 121.673862 -278.804242)
			(xy 121.700165 -278.762646) (xy 121.7328 -278.725809) (xy 121.770921 -278.694684) (xy 121.813542 -278.670077)
			(xy 121.859558 -278.652625) (xy 121.907777 -278.642781) (xy 121.956952 -278.6408) (xy 122.005807 -278.646732)
			(xy 122.053078 -278.660424) (xy 122.09754 -278.681522) (xy 122.138043 -278.709478) (xy 122.173536 -278.74357)
			(xy 122.203101 -278.782914) (xy 122.225972 -278.826491) (xy 122.241556 -278.873172) (xy 122.249451 -278.921749)
			(xy 122.249946 -278.946356) (xy 124.458996 -278.946356) (xy 124.462956 -278.897302) (xy 124.474733 -278.849518)
			(xy 124.494024 -278.804242) (xy 124.520327 -278.762646) (xy 124.552962 -278.725809) (xy 124.591083 -278.694684)
			(xy 124.633704 -278.670077) (xy 124.67972 -278.652625) (xy 124.727939 -278.642781) (xy 124.777114 -278.6408)
			(xy 124.825969 -278.646732) (xy 124.87324 -278.660424) (xy 124.917702 -278.681522) (xy 124.958205 -278.709478)
			(xy 124.993698 -278.74357) (xy 125.023263 -278.782914) (xy 125.046134 -278.826491) (xy 125.061718 -278.873172)
			(xy 125.069613 -278.921749) (xy 125.070108 -278.946356) (xy 125.069613 -278.970963) (xy 125.061718 -279.01954)
			(xy 125.046134 -279.066221) (xy 125.023263 -279.109798) (xy 124.993698 -279.149142) (xy 124.958205 -279.183234)
			(xy 124.917702 -279.21119) (xy 124.87324 -279.232288) (xy 124.825969 -279.24598) (xy 124.777114 -279.251912)
			(xy 124.727939 -279.249931) (xy 124.67972 -279.240087) (xy 124.633704 -279.222635) (xy 124.591083 -279.198028)
			(xy 124.552962 -279.166903) (xy 124.520327 -279.130066) (xy 124.494024 -279.08847) (xy 124.474733 -279.043194)
			(xy 124.462956 -278.99541) (xy 124.458996 -278.946356) (xy 122.249946 -278.946356) (xy 122.249451 -278.970963)
			(xy 122.241556 -279.01954) (xy 122.225972 -279.066221) (xy 122.203101 -279.109798) (xy 122.173536 -279.149142)
			(xy 122.138043 -279.183234) (xy 122.09754 -279.21119) (xy 122.053078 -279.232288) (xy 122.005807 -279.24598)
			(xy 121.956952 -279.251912) (xy 121.907777 -279.249931) (xy 121.859558 -279.240087) (xy 121.813542 -279.222635)
			(xy 121.770921 -279.198028) (xy 121.7328 -279.166903) (xy 121.700165 -279.130066) (xy 121.673862 -279.08847)
			(xy 121.654571 -279.043194) (xy 121.642794 -278.99541) (xy 121.638834 -278.946356) (xy 119.430038 -278.946356)
			(xy 119.429543 -278.970963) (xy 119.421648 -279.01954) (xy 119.406064 -279.066221) (xy 119.383193 -279.109798)
			(xy 119.353628 -279.149142) (xy 119.318135 -279.183234) (xy 119.277632 -279.21119) (xy 119.23317 -279.232288)
			(xy 119.185899 -279.24598) (xy 119.137044 -279.251912) (xy 119.087869 -279.249931) (xy 119.03965 -279.240087)
			(xy 118.993634 -279.222635) (xy 118.951013 -279.198028) (xy 118.912892 -279.166903) (xy 118.880257 -279.130066)
			(xy 118.853954 -279.08847) (xy 118.834663 -279.043194) (xy 118.822886 -278.99541) (xy 118.818926 -278.946356)
			(xy 116.61013 -278.946356) (xy 116.609635 -278.970963) (xy 116.60174 -279.01954) (xy 116.586156 -279.066221)
			(xy 116.563285 -279.109798) (xy 116.53372 -279.149142) (xy 116.498227 -279.183234) (xy 116.457724 -279.21119)
			(xy 116.413262 -279.232288) (xy 116.365991 -279.24598) (xy 116.317136 -279.251912) (xy 116.267961 -279.249931)
			(xy 116.219742 -279.240087) (xy 116.173726 -279.222635) (xy 116.131105 -279.198028) (xy 116.092984 -279.166903)
			(xy 116.060349 -279.130066) (xy 116.034046 -279.08847) (xy 116.014755 -279.043194) (xy 116.002978 -278.99541)
			(xy 115.999018 -278.946356) (xy 115.670076 -278.946356) (xy 115.669581 -278.970963) (xy 115.661686 -279.01954)
			(xy 115.646102 -279.066221) (xy 115.623231 -279.109798) (xy 115.593666 -279.149142) (xy 115.558173 -279.183234)
			(xy 115.51767 -279.21119) (xy 115.473208 -279.232288) (xy 115.425937 -279.24598) (xy 115.377082 -279.251912)
			(xy 115.327907 -279.249931) (xy 115.279688 -279.240087) (xy 115.233672 -279.222635) (xy 115.191051 -279.198028)
			(xy 115.15293 -279.166903) (xy 115.120295 -279.130066) (xy 115.093992 -279.08847) (xy 115.074701 -279.043194)
			(xy 115.062924 -278.99541) (xy 115.058964 -278.946356) (xy 114.730022 -278.946356) (xy 114.729527 -278.970963)
			(xy 114.721632 -279.01954) (xy 114.706048 -279.066221) (xy 114.683177 -279.109798) (xy 114.653612 -279.149142)
			(xy 114.618119 -279.183234) (xy 114.577616 -279.21119) (xy 114.533154 -279.232288) (xy 114.485883 -279.24598)
			(xy 114.437028 -279.251912) (xy 114.387853 -279.249931) (xy 114.339634 -279.240087) (xy 114.293618 -279.222635)
			(xy 114.250997 -279.198028) (xy 114.212876 -279.166903) (xy 114.180241 -279.130066) (xy 114.153938 -279.08847)
			(xy 114.134647 -279.043194) (xy 114.12287 -278.99541) (xy 114.11891 -278.946356) (xy 113.789968 -278.946356)
			(xy 113.789473 -278.970963) (xy 113.781578 -279.01954) (xy 113.765994 -279.066221) (xy 113.743123 -279.109798)
			(xy 113.713558 -279.149142) (xy 113.678065 -279.183234) (xy 113.637562 -279.21119) (xy 113.5931 -279.232288)
			(xy 113.545829 -279.24598) (xy 113.496974 -279.251912) (xy 113.447799 -279.249931) (xy 113.39958 -279.240087)
			(xy 113.353564 -279.222635) (xy 113.310943 -279.198028) (xy 113.272822 -279.166903) (xy 113.240187 -279.130066)
			(xy 113.213884 -279.08847) (xy 113.194593 -279.043194) (xy 113.182816 -278.99541) (xy 113.178856 -278.946356)
			(xy 110.97641 -278.946356) (xy 110.975915 -278.970963) (xy 110.96802 -279.01954) (xy 110.952436 -279.066221)
			(xy 110.929565 -279.109798) (xy 110.9 -279.149142) (xy 110.864507 -279.183234) (xy 110.824004 -279.21119)
			(xy 110.779542 -279.232288) (xy 110.732271 -279.24598) (xy 110.683416 -279.251912) (xy 110.634241 -279.249931)
			(xy 110.586022 -279.240087) (xy 110.540006 -279.222635) (xy 110.497385 -279.198028) (xy 110.459264 -279.166903)
			(xy 110.426629 -279.130066) (xy 110.400326 -279.08847) (xy 110.381035 -279.043194) (xy 110.369258 -278.99541)
			(xy 110.365298 -278.946356) (xy 110.036356 -278.946356) (xy 110.035861 -278.970963) (xy 110.027966 -279.01954)
			(xy 110.012382 -279.066221) (xy 109.989511 -279.109798) (xy 109.959946 -279.149142) (xy 109.924453 -279.183234)
			(xy 109.88395 -279.21119) (xy 109.839488 -279.232288) (xy 109.792217 -279.24598) (xy 109.743362 -279.251912)
			(xy 109.694187 -279.249931) (xy 109.645968 -279.240087) (xy 109.599952 -279.222635) (xy 109.557331 -279.198028)
			(xy 109.51921 -279.166903) (xy 109.486575 -279.130066) (xy 109.460272 -279.08847) (xy 109.440981 -279.043194)
			(xy 109.429204 -278.99541) (xy 109.425244 -278.946356) (xy 109.096302 -278.946356) (xy 109.095807 -278.970963)
			(xy 109.087912 -279.01954) (xy 109.072328 -279.066221) (xy 109.049457 -279.109798) (xy 109.019892 -279.149142)
			(xy 108.984399 -279.183234) (xy 108.943896 -279.21119) (xy 108.899434 -279.232288) (xy 108.852163 -279.24598)
			(xy 108.803308 -279.251912) (xy 108.754133 -279.249931) (xy 108.705914 -279.240087) (xy 108.659898 -279.222635)
			(xy 108.617277 -279.198028) (xy 108.579156 -279.166903) (xy 108.546521 -279.130066) (xy 108.520218 -279.08847)
			(xy 108.500927 -279.043194) (xy 108.48915 -278.99541) (xy 108.48519 -278.946356) (xy 108.156248 -278.946356)
			(xy 108.155753 -278.970963) (xy 108.147858 -279.01954) (xy 108.132274 -279.066221) (xy 108.109403 -279.109798)
			(xy 108.079838 -279.149142) (xy 108.044345 -279.183234) (xy 108.003842 -279.21119) (xy 107.95938 -279.232288)
			(xy 107.912109 -279.24598) (xy 107.863254 -279.251912) (xy 107.814079 -279.249931) (xy 107.76586 -279.240087)
			(xy 107.719844 -279.222635) (xy 107.677223 -279.198028) (xy 107.639102 -279.166903) (xy 107.606467 -279.130066)
			(xy 107.580164 -279.08847) (xy 107.560873 -279.043194) (xy 107.549096 -278.99541) (xy 107.545136 -278.946356)
			(xy 105.33634 -278.946356) (xy 105.335845 -278.970963) (xy 105.32795 -279.01954) (xy 105.312366 -279.066221)
			(xy 105.289495 -279.109798) (xy 105.25993 -279.149142) (xy 105.224437 -279.183234) (xy 105.183934 -279.21119)
			(xy 105.139472 -279.232288) (xy 105.092201 -279.24598) (xy 105.043346 -279.251912) (xy 104.994171 -279.249931)
			(xy 104.945952 -279.240087) (xy 104.899936 -279.222635) (xy 104.857315 -279.198028) (xy 104.819194 -279.166903)
			(xy 104.786559 -279.130066) (xy 104.760256 -279.08847) (xy 104.740965 -279.043194) (xy 104.729188 -278.99541)
			(xy 104.725228 -278.946356) (xy 102.516432 -278.946356) (xy 102.515937 -278.970963) (xy 102.508042 -279.01954)
			(xy 102.492458 -279.066221) (xy 102.469587 -279.109798) (xy 102.440022 -279.149142) (xy 102.404529 -279.183234)
			(xy 102.364026 -279.21119) (xy 102.319564 -279.232288) (xy 102.272293 -279.24598) (xy 102.223438 -279.251912)
			(xy 102.174263 -279.249931) (xy 102.126044 -279.240087) (xy 102.080028 -279.222635) (xy 102.037407 -279.198028)
			(xy 101.999286 -279.166903) (xy 101.966651 -279.130066) (xy 101.940348 -279.08847) (xy 101.921057 -279.043194)
			(xy 101.90928 -278.99541) (xy 101.90532 -278.946356) (xy 99.69627 -278.946356) (xy 99.695775 -278.970963)
			(xy 99.68788 -279.01954) (xy 99.672296 -279.066221) (xy 99.649425 -279.109798) (xy 99.61986 -279.149142)
			(xy 99.584367 -279.183234) (xy 99.543864 -279.21119) (xy 99.499402 -279.232288) (xy 99.452131 -279.24598)
			(xy 99.403276 -279.251912) (xy 99.354101 -279.249931) (xy 99.305882 -279.240087) (xy 99.259866 -279.222635)
			(xy 99.217245 -279.198028) (xy 99.179124 -279.166903) (xy 99.146489 -279.130066) (xy 99.120186 -279.08847)
			(xy 99.100895 -279.043194) (xy 99.089118 -278.99541) (xy 99.085158 -278.946356) (xy 96.876362 -278.946356)
			(xy 96.875897 -278.970962) (xy 96.868007 -279.019536) (xy 96.852425 -279.066216) (xy 96.829555 -279.109789)
			(xy 96.799989 -279.149129) (xy 96.764493 -279.183214) (xy 96.723988 -279.211162) (xy 96.679524 -279.232248)
			(xy 96.632251 -279.245926) (xy 96.607884 -279.249378) (xy 96.60509 -279.249632) (xy 96.599041 -279.250904)
			(xy 96.587747 -279.255916) (xy 96.582738 -279.259538) (xy 96.577658 -279.263348) (xy 96.573848 -279.268428)
			(xy 96.567244 -279.279858) (xy 96.533208 -279.362408) (xy 96.531271 -279.368298) (xy 96.529994 -279.380628)
			(xy 96.530668 -279.386792) (xy 96.532446 -279.399746) (xy 96.541082 -279.410922) (xy 96.565556 -279.443401)
			(xy 96.605854 -279.514037) (xy 96.621346 -279.551638) (xy 96.62414 -279.558496) (xy 96.63176 -279.56891)
			(xy 96.637348 -279.573228) (xy 96.64202 -279.57666) (xy 96.652539 -279.581526) (xy 96.658176 -279.58288)
			(xy 96.75114 -279.595072) (xy 96.754912 -279.595249) (xy 96.762436 -279.594605) (xy 96.766126 -279.593802)
			(xy 96.77527 -279.591008) (xy 96.787208 -279.585674) (xy 96.788478 -279.583896) (xy 96.795336 -279.574752)
			(xy 96.79559 -279.574244) (xy 96.810126 -279.555471) (xy 96.844025 -279.522229) (xy 96.882656 -279.494628)
			(xy 96.925089 -279.473331) (xy 96.970304 -279.45885) (xy 97.017215 -279.451534) (xy 97.040954 -279.451054)
			(xy 97.064951 -279.451497) (xy 97.112354 -279.458997) (xy 97.158 -279.473822) (xy 97.200765 -279.495604)
			(xy 97.239597 -279.523808) (xy 97.273537 -279.557739) (xy 97.301752 -279.596563) (xy 97.323546 -279.639322)
			(xy 97.338383 -279.684964) (xy 97.345897 -279.732366) (xy 97.346262 -279.756362) (xy 97.675204 -279.756362)
			(xy 97.679164 -279.707308) (xy 97.690941 -279.659524) (xy 97.710232 -279.614248) (xy 97.736535 -279.572652)
			(xy 97.76917 -279.535815) (xy 97.807291 -279.50469) (xy 97.849912 -279.480083) (xy 97.895928 -279.462631)
			(xy 97.944147 -279.452787) (xy 97.993322 -279.450806) (xy 98.042177 -279.456738) (xy 98.089448 -279.47043)
			(xy 98.13391 -279.491528) (xy 98.174413 -279.519484) (xy 98.209906 -279.553576) (xy 98.239471 -279.59292)
			(xy 98.262342 -279.636497) (xy 98.277926 -279.683178) (xy 98.285821 -279.731755) (xy 98.286316 -279.756362)
			(xy 98.615258 -279.756362) (xy 98.619218 -279.707308) (xy 98.630995 -279.659524) (xy 98.650286 -279.614248)
			(xy 98.676589 -279.572652) (xy 98.709224 -279.535815) (xy 98.747345 -279.50469) (xy 98.789966 -279.480083)
			(xy 98.835982 -279.462631) (xy 98.884201 -279.452787) (xy 98.933376 -279.450806) (xy 98.982231 -279.456738)
			(xy 99.029502 -279.47043) (xy 99.073964 -279.491528) (xy 99.114467 -279.519484) (xy 99.14996 -279.553576)
			(xy 99.179525 -279.59292) (xy 99.202396 -279.636497) (xy 99.21798 -279.683178) (xy 99.225875 -279.731755)
			(xy 99.22637 -279.756362) (xy 99.555312 -279.756362) (xy 99.559272 -279.707308) (xy 99.571049 -279.659524)
			(xy 99.59034 -279.614248) (xy 99.616643 -279.572652) (xy 99.649278 -279.535815) (xy 99.687399 -279.50469)
			(xy 99.73002 -279.480083) (xy 99.776036 -279.462631) (xy 99.824255 -279.452787) (xy 99.87343 -279.450806)
			(xy 99.922285 -279.456738) (xy 99.969556 -279.47043) (xy 100.014018 -279.491528) (xy 100.054521 -279.519484)
			(xy 100.090014 -279.553576) (xy 100.119579 -279.59292) (xy 100.14245 -279.636497) (xy 100.158034 -279.683178)
			(xy 100.165929 -279.731755) (xy 100.166424 -279.756362) (xy 100.495366 -279.756362) (xy 100.499326 -279.707308)
			(xy 100.511103 -279.659524) (xy 100.530394 -279.614248) (xy 100.556697 -279.572652) (xy 100.589332 -279.535815)
			(xy 100.627453 -279.50469) (xy 100.670074 -279.480083) (xy 100.71609 -279.462631) (xy 100.764309 -279.452787)
			(xy 100.813484 -279.450806) (xy 100.862339 -279.456738) (xy 100.90961 -279.47043) (xy 100.954072 -279.491528)
			(xy 100.994575 -279.519484) (xy 101.030068 -279.553576) (xy 101.059633 -279.59292) (xy 101.082504 -279.636497)
			(xy 101.098088 -279.683178) (xy 101.105983 -279.731755) (xy 101.106478 -279.756362) (xy 101.435166 -279.756362)
			(xy 101.439126 -279.707308) (xy 101.450903 -279.659524) (xy 101.470194 -279.614248) (xy 101.496497 -279.572652)
			(xy 101.529132 -279.535815) (xy 101.567253 -279.50469) (xy 101.609874 -279.480083) (xy 101.65589 -279.462631)
			(xy 101.704109 -279.452787) (xy 101.753284 -279.450806) (xy 101.802139 -279.456738) (xy 101.84941 -279.47043)
			(xy 101.893872 -279.491528) (xy 101.934375 -279.519484) (xy 101.969868 -279.553576) (xy 101.999433 -279.59292)
			(xy 102.022304 -279.636497) (xy 102.037888 -279.683178) (xy 102.045783 -279.731755) (xy 102.046278 -279.756362)
			(xy 102.37522 -279.756362) (xy 102.37918 -279.707308) (xy 102.390957 -279.659524) (xy 102.410248 -279.614248)
			(xy 102.436551 -279.572652) (xy 102.469186 -279.535815) (xy 102.507307 -279.50469) (xy 102.549928 -279.480083)
			(xy 102.595944 -279.462631) (xy 102.644163 -279.452787) (xy 102.693338 -279.450806) (xy 102.742193 -279.456738)
			(xy 102.789464 -279.47043) (xy 102.833926 -279.491528) (xy 102.874429 -279.519484) (xy 102.909922 -279.553576)
			(xy 102.939487 -279.59292) (xy 102.962358 -279.636497) (xy 102.977942 -279.683178) (xy 102.985837 -279.731755)
			(xy 102.986332 -279.756362) (xy 103.315274 -279.756362) (xy 103.319234 -279.707308) (xy 103.331011 -279.659524)
			(xy 103.350302 -279.614248) (xy 103.376605 -279.572652) (xy 103.40924 -279.535815) (xy 103.447361 -279.50469)
			(xy 103.489982 -279.480083) (xy 103.535998 -279.462631) (xy 103.584217 -279.452787) (xy 103.633392 -279.450806)
			(xy 103.682247 -279.456738) (xy 103.729518 -279.47043) (xy 103.77398 -279.491528) (xy 103.814483 -279.519484)
			(xy 103.849976 -279.553576) (xy 103.879541 -279.59292) (xy 103.902412 -279.636497) (xy 103.917996 -279.683178)
			(xy 103.925891 -279.731755) (xy 103.926386 -279.756362) (xy 104.255328 -279.756362) (xy 104.259288 -279.707308)
			(xy 104.271065 -279.659524) (xy 104.290356 -279.614248) (xy 104.316659 -279.572652) (xy 104.349294 -279.535815)
			(xy 104.387415 -279.50469) (xy 104.430036 -279.480083) (xy 104.476052 -279.462631) (xy 104.524271 -279.452787)
			(xy 104.573446 -279.450806) (xy 104.622301 -279.456738) (xy 104.669572 -279.47043) (xy 104.714034 -279.491528)
			(xy 104.754537 -279.519484) (xy 104.79003 -279.553576) (xy 104.819595 -279.59292) (xy 104.842466 -279.636497)
			(xy 104.85805 -279.683178) (xy 104.865945 -279.731755) (xy 104.86644 -279.756362) (xy 105.195128 -279.756362)
			(xy 105.199088 -279.707308) (xy 105.210865 -279.659524) (xy 105.230156 -279.614248) (xy 105.256459 -279.572652)
			(xy 105.289094 -279.535815) (xy 105.327215 -279.50469) (xy 105.369836 -279.480083) (xy 105.415852 -279.462631)
			(xy 105.464071 -279.452787) (xy 105.513246 -279.450806) (xy 105.562101 -279.456738) (xy 105.609372 -279.47043)
			(xy 105.653834 -279.491528) (xy 105.694337 -279.519484) (xy 105.72983 -279.553576) (xy 105.759395 -279.59292)
			(xy 105.782266 -279.636497) (xy 105.79785 -279.683178) (xy 105.805745 -279.731755) (xy 105.80624 -279.756362)
			(xy 106.135182 -279.756362) (xy 106.139142 -279.707308) (xy 106.150919 -279.659524) (xy 106.17021 -279.614248)
			(xy 106.196513 -279.572652) (xy 106.229148 -279.535815) (xy 106.267269 -279.50469) (xy 106.30989 -279.480083)
			(xy 106.355906 -279.462631) (xy 106.404125 -279.452787) (xy 106.4533 -279.450806) (xy 106.502155 -279.456738)
			(xy 106.549426 -279.47043) (xy 106.593888 -279.491528) (xy 106.634391 -279.519484) (xy 106.669884 -279.553576)
			(xy 106.699449 -279.59292) (xy 106.72232 -279.636497) (xy 106.737904 -279.683178) (xy 106.745799 -279.731755)
			(xy 106.746294 -279.756362) (xy 107.075236 -279.756362) (xy 107.079196 -279.707308) (xy 107.090973 -279.659524)
			(xy 107.110264 -279.614248) (xy 107.136567 -279.572652) (xy 107.169202 -279.535815) (xy 107.207323 -279.50469)
			(xy 107.249944 -279.480083) (xy 107.29596 -279.462631) (xy 107.344179 -279.452787) (xy 107.393354 -279.450806)
			(xy 107.442209 -279.456738) (xy 107.48948 -279.47043) (xy 107.533942 -279.491528) (xy 107.574445 -279.519484)
			(xy 107.609938 -279.553576) (xy 107.639503 -279.59292) (xy 107.662374 -279.636497) (xy 107.677958 -279.683178)
			(xy 107.685853 -279.731755) (xy 107.686348 -279.756362) (xy 108.01529 -279.756362) (xy 108.01925 -279.707308)
			(xy 108.031027 -279.659524) (xy 108.050318 -279.614248) (xy 108.076621 -279.572652) (xy 108.109256 -279.535815)
			(xy 108.147377 -279.50469) (xy 108.189998 -279.480083) (xy 108.236014 -279.462631) (xy 108.284233 -279.452787)
			(xy 108.333408 -279.450806) (xy 108.382263 -279.456738) (xy 108.429534 -279.47043) (xy 108.473996 -279.491528)
			(xy 108.514499 -279.519484) (xy 108.549992 -279.553576) (xy 108.579557 -279.59292) (xy 108.602428 -279.636497)
			(xy 108.618012 -279.683178) (xy 108.625907 -279.731755) (xy 108.626402 -279.756362) (xy 108.955344 -279.756362)
			(xy 108.959304 -279.707308) (xy 108.971081 -279.659524) (xy 108.990372 -279.614248) (xy 109.016675 -279.572652)
			(xy 109.04931 -279.535815) (xy 109.087431 -279.50469) (xy 109.130052 -279.480083) (xy 109.176068 -279.462631)
			(xy 109.224287 -279.452787) (xy 109.273462 -279.450806) (xy 109.322317 -279.456738) (xy 109.369588 -279.47043)
			(xy 109.41405 -279.491528) (xy 109.454553 -279.519484) (xy 109.490046 -279.553576) (xy 109.519611 -279.59292)
			(xy 109.542482 -279.636497) (xy 109.558066 -279.683178) (xy 109.565961 -279.731755) (xy 109.566456 -279.756362)
			(xy 109.895144 -279.756362) (xy 109.899104 -279.707308) (xy 109.910881 -279.659524) (xy 109.930172 -279.614248)
			(xy 109.956475 -279.572652) (xy 109.98911 -279.535815) (xy 110.027231 -279.50469) (xy 110.069852 -279.480083)
			(xy 110.115868 -279.462631) (xy 110.164087 -279.452787) (xy 110.213262 -279.450806) (xy 110.262117 -279.456738)
			(xy 110.309388 -279.47043) (xy 110.35385 -279.491528) (xy 110.394353 -279.519484) (xy 110.429846 -279.553576)
			(xy 110.459411 -279.59292) (xy 110.482282 -279.636497) (xy 110.497866 -279.683178) (xy 110.505761 -279.731755)
			(xy 110.506256 -279.756362) (xy 113.64901 -279.756362) (xy 113.65297 -279.707308) (xy 113.664747 -279.659524)
			(xy 113.684038 -279.614248) (xy 113.710341 -279.572652) (xy 113.742976 -279.535815) (xy 113.781097 -279.50469)
			(xy 113.823718 -279.480083) (xy 113.869734 -279.462631) (xy 113.917953 -279.452787) (xy 113.967128 -279.450806)
			(xy 114.015983 -279.456738) (xy 114.063254 -279.47043) (xy 114.107716 -279.491528) (xy 114.148219 -279.519484)
			(xy 114.183712 -279.553576) (xy 114.213277 -279.59292) (xy 114.236148 -279.636497) (xy 114.251732 -279.683178)
			(xy 114.259627 -279.731755) (xy 114.260122 -279.756362) (xy 114.58881 -279.756362) (xy 114.59277 -279.707308)
			(xy 114.604547 -279.659524) (xy 114.623838 -279.614248) (xy 114.650141 -279.572652) (xy 114.682776 -279.535815)
			(xy 114.720897 -279.50469) (xy 114.763518 -279.480083) (xy 114.809534 -279.462631) (xy 114.857753 -279.452787)
			(xy 114.906928 -279.450806) (xy 114.955783 -279.456738) (xy 115.003054 -279.47043) (xy 115.047516 -279.491528)
			(xy 115.088019 -279.519484) (xy 115.123512 -279.553576) (xy 115.153077 -279.59292) (xy 115.175948 -279.636497)
			(xy 115.191532 -279.683178) (xy 115.199427 -279.731755) (xy 115.199922 -279.756362) (xy 115.528864 -279.756362)
			(xy 115.532824 -279.707308) (xy 115.544601 -279.659524) (xy 115.563892 -279.614248) (xy 115.590195 -279.572652)
			(xy 115.62283 -279.535815) (xy 115.660951 -279.50469) (xy 115.703572 -279.480083) (xy 115.749588 -279.462631)
			(xy 115.797807 -279.452787) (xy 115.846982 -279.450806) (xy 115.895837 -279.456738) (xy 115.943108 -279.47043)
			(xy 115.98757 -279.491528) (xy 116.028073 -279.519484) (xy 116.063566 -279.553576) (xy 116.093131 -279.59292)
			(xy 116.116002 -279.636497) (xy 116.131586 -279.683178) (xy 116.139481 -279.731755) (xy 116.139976 -279.756362)
			(xy 116.468918 -279.756362) (xy 116.472878 -279.707308) (xy 116.484655 -279.659524) (xy 116.503946 -279.614248)
			(xy 116.530249 -279.572652) (xy 116.562884 -279.535815) (xy 116.601005 -279.50469) (xy 116.643626 -279.480083)
			(xy 116.689642 -279.462631) (xy 116.737861 -279.452787) (xy 116.787036 -279.450806) (xy 116.835891 -279.456738)
			(xy 116.883162 -279.47043) (xy 116.927624 -279.491528) (xy 116.968127 -279.519484) (xy 117.00362 -279.553576)
			(xy 117.033185 -279.59292) (xy 117.056056 -279.636497) (xy 117.07164 -279.683178) (xy 117.079535 -279.731755)
			(xy 117.08003 -279.756362) (xy 117.408972 -279.756362) (xy 117.412932 -279.707308) (xy 117.424709 -279.659524)
			(xy 117.444 -279.614248) (xy 117.470303 -279.572652) (xy 117.502938 -279.535815) (xy 117.541059 -279.50469)
			(xy 117.58368 -279.480083) (xy 117.629696 -279.462631) (xy 117.677915 -279.452787) (xy 117.72709 -279.450806)
			(xy 117.775945 -279.456738) (xy 117.823216 -279.47043) (xy 117.867678 -279.491528) (xy 117.908181 -279.519484)
			(xy 117.943674 -279.553576) (xy 117.973239 -279.59292) (xy 117.99611 -279.636497) (xy 118.011694 -279.683178)
			(xy 118.019589 -279.731755) (xy 118.020084 -279.756362) (xy 118.349026 -279.756362) (xy 118.352986 -279.707308)
			(xy 118.364763 -279.659524) (xy 118.384054 -279.614248) (xy 118.410357 -279.572652) (xy 118.442992 -279.535815)
			(xy 118.481113 -279.50469) (xy 118.523734 -279.480083) (xy 118.56975 -279.462631) (xy 118.617969 -279.452787)
			(xy 118.667144 -279.450806) (xy 118.715999 -279.456738) (xy 118.76327 -279.47043) (xy 118.807732 -279.491528)
			(xy 118.848235 -279.519484) (xy 118.883728 -279.553576) (xy 118.913293 -279.59292) (xy 118.936164 -279.636497)
			(xy 118.951748 -279.683178) (xy 118.959643 -279.731755) (xy 118.960138 -279.756362) (xy 119.288826 -279.756362)
			(xy 119.292786 -279.707308) (xy 119.304563 -279.659524) (xy 119.323854 -279.614248) (xy 119.350157 -279.572652)
			(xy 119.382792 -279.535815) (xy 119.420913 -279.50469) (xy 119.463534 -279.480083) (xy 119.50955 -279.462631)
			(xy 119.557769 -279.452787) (xy 119.606944 -279.450806) (xy 119.655799 -279.456738) (xy 119.70307 -279.47043)
			(xy 119.747532 -279.491528) (xy 119.788035 -279.519484) (xy 119.823528 -279.553576) (xy 119.853093 -279.59292)
			(xy 119.875964 -279.636497) (xy 119.891548 -279.683178) (xy 119.899443 -279.731755) (xy 119.899938 -279.756362)
			(xy 120.22888 -279.756362) (xy 120.23284 -279.707308) (xy 120.244617 -279.659524) (xy 120.263908 -279.614248)
			(xy 120.290211 -279.572652) (xy 120.322846 -279.535815) (xy 120.360967 -279.50469) (xy 120.403588 -279.480083)
			(xy 120.449604 -279.462631) (xy 120.497823 -279.452787) (xy 120.546998 -279.450806) (xy 120.595853 -279.456738)
			(xy 120.643124 -279.47043) (xy 120.687586 -279.491528) (xy 120.728089 -279.519484) (xy 120.763582 -279.553576)
			(xy 120.793147 -279.59292) (xy 120.816018 -279.636497) (xy 120.831602 -279.683178) (xy 120.839497 -279.731755)
			(xy 120.839992 -279.756362) (xy 121.168934 -279.756362) (xy 121.172894 -279.707308) (xy 121.184671 -279.659524)
			(xy 121.203962 -279.614248) (xy 121.230265 -279.572652) (xy 121.2629 -279.535815) (xy 121.301021 -279.50469)
			(xy 121.343642 -279.480083) (xy 121.389658 -279.462631) (xy 121.437877 -279.452787) (xy 121.487052 -279.450806)
			(xy 121.535907 -279.456738) (xy 121.583178 -279.47043) (xy 121.62764 -279.491528) (xy 121.668143 -279.519484)
			(xy 121.703636 -279.553576) (xy 121.733201 -279.59292) (xy 121.756072 -279.636497) (xy 121.771656 -279.683178)
			(xy 121.779551 -279.731755) (xy 121.780046 -279.756362) (xy 122.108988 -279.756362) (xy 122.112948 -279.707308)
			(xy 122.124725 -279.659524) (xy 122.144016 -279.614248) (xy 122.170319 -279.572652) (xy 122.202954 -279.535815)
			(xy 122.241075 -279.50469) (xy 122.283696 -279.480083) (xy 122.329712 -279.462631) (xy 122.377931 -279.452787)
			(xy 122.427106 -279.450806) (xy 122.475961 -279.456738) (xy 122.523232 -279.47043) (xy 122.567694 -279.491528)
			(xy 122.608197 -279.519484) (xy 122.64369 -279.553576) (xy 122.673255 -279.59292) (xy 122.696126 -279.636497)
			(xy 122.71171 -279.683178) (xy 122.719605 -279.731755) (xy 122.7201 -279.756362) (xy 123.049042 -279.756362)
			(xy 123.053002 -279.707308) (xy 123.064779 -279.659524) (xy 123.08407 -279.614248) (xy 123.110373 -279.572652)
			(xy 123.143008 -279.535815) (xy 123.181129 -279.50469) (xy 123.22375 -279.480083) (xy 123.269766 -279.462631)
			(xy 123.317985 -279.452787) (xy 123.36716 -279.450806) (xy 123.416015 -279.456738) (xy 123.463286 -279.47043)
			(xy 123.507748 -279.491528) (xy 123.548251 -279.519484) (xy 123.583744 -279.553576) (xy 123.613309 -279.59292)
			(xy 123.63618 -279.636497) (xy 123.651764 -279.683178) (xy 123.659659 -279.731755) (xy 123.660154 -279.756362)
			(xy 123.988842 -279.756362) (xy 123.992802 -279.707308) (xy 124.004579 -279.659524) (xy 124.02387 -279.614248)
			(xy 124.050173 -279.572652) (xy 124.082808 -279.535815) (xy 124.120929 -279.50469) (xy 124.16355 -279.480083)
			(xy 124.209566 -279.462631) (xy 124.257785 -279.452787) (xy 124.30696 -279.450806) (xy 124.355815 -279.456738)
			(xy 124.403086 -279.47043) (xy 124.447548 -279.491528) (xy 124.488051 -279.519484) (xy 124.523544 -279.553576)
			(xy 124.553109 -279.59292) (xy 124.57598 -279.636497) (xy 124.591564 -279.683178) (xy 124.599459 -279.731755)
			(xy 124.599954 -279.756362) (xy 124.928896 -279.756362) (xy 124.932856 -279.707308) (xy 124.944633 -279.659524)
			(xy 124.963924 -279.614248) (xy 124.990227 -279.572652) (xy 125.022862 -279.535815) (xy 125.060983 -279.50469)
			(xy 125.103604 -279.480083) (xy 125.14962 -279.462631) (xy 125.197839 -279.452787) (xy 125.247014 -279.450806)
			(xy 125.295869 -279.456738) (xy 125.34314 -279.47043) (xy 125.387602 -279.491528) (xy 125.428105 -279.519484)
			(xy 125.463598 -279.553576) (xy 125.493163 -279.59292) (xy 125.516034 -279.636497) (xy 125.531618 -279.683178)
			(xy 125.539513 -279.731755) (xy 125.540008 -279.756362) (xy 125.86895 -279.756362) (xy 125.87291 -279.707308)
			(xy 125.884687 -279.659524) (xy 125.903978 -279.614248) (xy 125.930281 -279.572652) (xy 125.962916 -279.535815)
			(xy 126.001037 -279.50469) (xy 126.043658 -279.480083) (xy 126.089674 -279.462631) (xy 126.137893 -279.452787)
			(xy 126.187068 -279.450806) (xy 126.235923 -279.456738) (xy 126.283194 -279.47043) (xy 126.327656 -279.491528)
			(xy 126.368159 -279.519484) (xy 126.403652 -279.553576) (xy 126.433217 -279.59292) (xy 126.456088 -279.636497)
			(xy 126.471672 -279.683178) (xy 126.479567 -279.731755) (xy 126.480062 -279.756362) (xy 126.479567 -279.780969)
			(xy 126.471672 -279.829546) (xy 126.456088 -279.876227) (xy 126.433217 -279.919804) (xy 126.403652 -279.959148)
			(xy 126.368159 -279.99324) (xy 126.327656 -280.021196) (xy 126.283194 -280.042294) (xy 126.235923 -280.055986)
			(xy 126.187068 -280.061918) (xy 126.137893 -280.059937) (xy 126.089674 -280.050093) (xy 126.043658 -280.032641)
			(xy 126.001037 -280.008034) (xy 125.962916 -279.976909) (xy 125.930281 -279.940072) (xy 125.903978 -279.898476)
			(xy 125.884687 -279.8532) (xy 125.87291 -279.805416) (xy 125.86895 -279.756362) (xy 125.540008 -279.756362)
			(xy 125.539513 -279.780969) (xy 125.531618 -279.829546) (xy 125.516034 -279.876227) (xy 125.493163 -279.919804)
			(xy 125.463598 -279.959148) (xy 125.428105 -279.99324) (xy 125.387602 -280.021196) (xy 125.34314 -280.042294)
			(xy 125.295869 -280.055986) (xy 125.247014 -280.061918) (xy 125.197839 -280.059937) (xy 125.14962 -280.050093)
			(xy 125.103604 -280.032641) (xy 125.060983 -280.008034) (xy 125.022862 -279.976909) (xy 124.990227 -279.940072)
			(xy 124.963924 -279.898476) (xy 124.944633 -279.8532) (xy 124.932856 -279.805416) (xy 124.928896 -279.756362)
			(xy 124.599954 -279.756362) (xy 124.599459 -279.780969) (xy 124.591564 -279.829546) (xy 124.57598 -279.876227)
			(xy 124.553109 -279.919804) (xy 124.523544 -279.959148) (xy 124.488051 -279.99324) (xy 124.447548 -280.021196)
			(xy 124.403086 -280.042294) (xy 124.355815 -280.055986) (xy 124.30696 -280.061918) (xy 124.257785 -280.059937)
			(xy 124.209566 -280.050093) (xy 124.16355 -280.032641) (xy 124.120929 -280.008034) (xy 124.082808 -279.976909)
			(xy 124.050173 -279.940072) (xy 124.02387 -279.898476) (xy 124.004579 -279.8532) (xy 123.992802 -279.805416)
			(xy 123.988842 -279.756362) (xy 123.660154 -279.756362) (xy 123.659659 -279.780969) (xy 123.651764 -279.829546)
			(xy 123.63618 -279.876227) (xy 123.613309 -279.919804) (xy 123.583744 -279.959148) (xy 123.548251 -279.99324)
			(xy 123.507748 -280.021196) (xy 123.463286 -280.042294) (xy 123.416015 -280.055986) (xy 123.36716 -280.061918)
			(xy 123.317985 -280.059937) (xy 123.269766 -280.050093) (xy 123.22375 -280.032641) (xy 123.181129 -280.008034)
			(xy 123.143008 -279.976909) (xy 123.110373 -279.940072) (xy 123.08407 -279.898476) (xy 123.064779 -279.8532)
			(xy 123.053002 -279.805416) (xy 123.049042 -279.756362) (xy 122.7201 -279.756362) (xy 122.719605 -279.780969)
			(xy 122.71171 -279.829546) (xy 122.696126 -279.876227) (xy 122.673255 -279.919804) (xy 122.64369 -279.959148)
			(xy 122.608197 -279.99324) (xy 122.567694 -280.021196) (xy 122.523232 -280.042294) (xy 122.475961 -280.055986)
			(xy 122.427106 -280.061918) (xy 122.377931 -280.059937) (xy 122.329712 -280.050093) (xy 122.283696 -280.032641)
			(xy 122.241075 -280.008034) (xy 122.202954 -279.976909) (xy 122.170319 -279.940072) (xy 122.144016 -279.898476)
			(xy 122.124725 -279.8532) (xy 122.112948 -279.805416) (xy 122.108988 -279.756362) (xy 121.780046 -279.756362)
			(xy 121.779551 -279.780969) (xy 121.771656 -279.829546) (xy 121.756072 -279.876227) (xy 121.733201 -279.919804)
			(xy 121.703636 -279.959148) (xy 121.668143 -279.99324) (xy 121.62764 -280.021196) (xy 121.583178 -280.042294)
			(xy 121.535907 -280.055986) (xy 121.487052 -280.061918) (xy 121.437877 -280.059937) (xy 121.389658 -280.050093)
			(xy 121.343642 -280.032641) (xy 121.301021 -280.008034) (xy 121.2629 -279.976909) (xy 121.230265 -279.940072)
			(xy 121.203962 -279.898476) (xy 121.184671 -279.8532) (xy 121.172894 -279.805416) (xy 121.168934 -279.756362)
			(xy 120.839992 -279.756362) (xy 120.839497 -279.780969) (xy 120.831602 -279.829546) (xy 120.816018 -279.876227)
			(xy 120.793147 -279.919804) (xy 120.763582 -279.959148) (xy 120.728089 -279.99324) (xy 120.687586 -280.021196)
			(xy 120.643124 -280.042294) (xy 120.595853 -280.055986) (xy 120.546998 -280.061918) (xy 120.497823 -280.059937)
			(xy 120.449604 -280.050093) (xy 120.403588 -280.032641) (xy 120.360967 -280.008034) (xy 120.322846 -279.976909)
			(xy 120.290211 -279.940072) (xy 120.263908 -279.898476) (xy 120.244617 -279.8532) (xy 120.23284 -279.805416)
			(xy 120.22888 -279.756362) (xy 119.899938 -279.756362) (xy 119.899443 -279.780969) (xy 119.891548 -279.829546)
			(xy 119.875964 -279.876227) (xy 119.853093 -279.919804) (xy 119.823528 -279.959148) (xy 119.788035 -279.99324)
			(xy 119.747532 -280.021196) (xy 119.70307 -280.042294) (xy 119.655799 -280.055986) (xy 119.606944 -280.061918)
			(xy 119.557769 -280.059937) (xy 119.50955 -280.050093) (xy 119.463534 -280.032641) (xy 119.420913 -280.008034)
			(xy 119.382792 -279.976909) (xy 119.350157 -279.940072) (xy 119.323854 -279.898476) (xy 119.304563 -279.8532)
			(xy 119.292786 -279.805416) (xy 119.288826 -279.756362) (xy 118.960138 -279.756362) (xy 118.959643 -279.780969)
			(xy 118.951748 -279.829546) (xy 118.936164 -279.876227) (xy 118.913293 -279.919804) (xy 118.883728 -279.959148)
			(xy 118.848235 -279.99324) (xy 118.807732 -280.021196) (xy 118.76327 -280.042294) (xy 118.715999 -280.055986)
			(xy 118.667144 -280.061918) (xy 118.617969 -280.059937) (xy 118.56975 -280.050093) (xy 118.523734 -280.032641)
			(xy 118.481113 -280.008034) (xy 118.442992 -279.976909) (xy 118.410357 -279.940072) (xy 118.384054 -279.898476)
			(xy 118.364763 -279.8532) (xy 118.352986 -279.805416) (xy 118.349026 -279.756362) (xy 118.020084 -279.756362)
			(xy 118.019589 -279.780969) (xy 118.011694 -279.829546) (xy 117.99611 -279.876227) (xy 117.973239 -279.919804)
			(xy 117.943674 -279.959148) (xy 117.908181 -279.99324) (xy 117.867678 -280.021196) (xy 117.823216 -280.042294)
			(xy 117.775945 -280.055986) (xy 117.72709 -280.061918) (xy 117.677915 -280.059937) (xy 117.629696 -280.050093)
			(xy 117.58368 -280.032641) (xy 117.541059 -280.008034) (xy 117.502938 -279.976909) (xy 117.470303 -279.940072)
			(xy 117.444 -279.898476) (xy 117.424709 -279.8532) (xy 117.412932 -279.805416) (xy 117.408972 -279.756362)
			(xy 117.08003 -279.756362) (xy 117.079535 -279.780969) (xy 117.07164 -279.829546) (xy 117.056056 -279.876227)
			(xy 117.033185 -279.919804) (xy 117.00362 -279.959148) (xy 116.968127 -279.99324) (xy 116.927624 -280.021196)
			(xy 116.883162 -280.042294) (xy 116.835891 -280.055986) (xy 116.787036 -280.061918) (xy 116.737861 -280.059937)
			(xy 116.689642 -280.050093) (xy 116.643626 -280.032641) (xy 116.601005 -280.008034) (xy 116.562884 -279.976909)
			(xy 116.530249 -279.940072) (xy 116.503946 -279.898476) (xy 116.484655 -279.8532) (xy 116.472878 -279.805416)
			(xy 116.468918 -279.756362) (xy 116.139976 -279.756362) (xy 116.139481 -279.780969) (xy 116.131586 -279.829546)
			(xy 116.116002 -279.876227) (xy 116.093131 -279.919804) (xy 116.063566 -279.959148) (xy 116.028073 -279.99324)
			(xy 115.98757 -280.021196) (xy 115.943108 -280.042294) (xy 115.895837 -280.055986) (xy 115.846982 -280.061918)
			(xy 115.797807 -280.059937) (xy 115.749588 -280.050093) (xy 115.703572 -280.032641) (xy 115.660951 -280.008034)
			(xy 115.62283 -279.976909) (xy 115.590195 -279.940072) (xy 115.563892 -279.898476) (xy 115.544601 -279.8532)
			(xy 115.532824 -279.805416) (xy 115.528864 -279.756362) (xy 115.199922 -279.756362) (xy 115.199427 -279.780969)
			(xy 115.191532 -279.829546) (xy 115.175948 -279.876227) (xy 115.153077 -279.919804) (xy 115.123512 -279.959148)
			(xy 115.088019 -279.99324) (xy 115.047516 -280.021196) (xy 115.003054 -280.042294) (xy 114.955783 -280.055986)
			(xy 114.906928 -280.061918) (xy 114.857753 -280.059937) (xy 114.809534 -280.050093) (xy 114.763518 -280.032641)
			(xy 114.720897 -280.008034) (xy 114.682776 -279.976909) (xy 114.650141 -279.940072) (xy 114.623838 -279.898476)
			(xy 114.604547 -279.8532) (xy 114.59277 -279.805416) (xy 114.58881 -279.756362) (xy 114.260122 -279.756362)
			(xy 114.259627 -279.780969) (xy 114.251732 -279.829546) (xy 114.236148 -279.876227) (xy 114.213277 -279.919804)
			(xy 114.183712 -279.959148) (xy 114.148219 -279.99324) (xy 114.107716 -280.021196) (xy 114.063254 -280.042294)
			(xy 114.015983 -280.055986) (xy 113.967128 -280.061918) (xy 113.917953 -280.059937) (xy 113.869734 -280.050093)
			(xy 113.823718 -280.032641) (xy 113.781097 -280.008034) (xy 113.742976 -279.976909) (xy 113.710341 -279.940072)
			(xy 113.684038 -279.898476) (xy 113.664747 -279.8532) (xy 113.65297 -279.805416) (xy 113.64901 -279.756362)
			(xy 110.506256 -279.756362) (xy 110.505761 -279.780969) (xy 110.497866 -279.829546) (xy 110.482282 -279.876227)
			(xy 110.459411 -279.919804) (xy 110.429846 -279.959148) (xy 110.394353 -279.99324) (xy 110.35385 -280.021196)
			(xy 110.309388 -280.042294) (xy 110.262117 -280.055986) (xy 110.213262 -280.061918) (xy 110.164087 -280.059937)
			(xy 110.115868 -280.050093) (xy 110.069852 -280.032641) (xy 110.027231 -280.008034) (xy 109.98911 -279.976909)
			(xy 109.956475 -279.940072) (xy 109.930172 -279.898476) (xy 109.910881 -279.8532) (xy 109.899104 -279.805416)
			(xy 109.895144 -279.756362) (xy 109.566456 -279.756362) (xy 109.565961 -279.780969) (xy 109.558066 -279.829546)
			(xy 109.542482 -279.876227) (xy 109.519611 -279.919804) (xy 109.490046 -279.959148) (xy 109.454553 -279.99324)
			(xy 109.41405 -280.021196) (xy 109.369588 -280.042294) (xy 109.322317 -280.055986) (xy 109.273462 -280.061918)
			(xy 109.224287 -280.059937) (xy 109.176068 -280.050093) (xy 109.130052 -280.032641) (xy 109.087431 -280.008034)
			(xy 109.04931 -279.976909) (xy 109.016675 -279.940072) (xy 108.990372 -279.898476) (xy 108.971081 -279.8532)
			(xy 108.959304 -279.805416) (xy 108.955344 -279.756362) (xy 108.626402 -279.756362) (xy 108.625907 -279.780969)
			(xy 108.618012 -279.829546) (xy 108.602428 -279.876227) (xy 108.579557 -279.919804) (xy 108.549992 -279.959148)
			(xy 108.514499 -279.99324) (xy 108.473996 -280.021196) (xy 108.429534 -280.042294) (xy 108.382263 -280.055986)
			(xy 108.333408 -280.061918) (xy 108.284233 -280.059937) (xy 108.236014 -280.050093) (xy 108.189998 -280.032641)
			(xy 108.147377 -280.008034) (xy 108.109256 -279.976909) (xy 108.076621 -279.940072) (xy 108.050318 -279.898476)
			(xy 108.031027 -279.8532) (xy 108.01925 -279.805416) (xy 108.01529 -279.756362) (xy 107.686348 -279.756362)
			(xy 107.685853 -279.780969) (xy 107.677958 -279.829546) (xy 107.662374 -279.876227) (xy 107.639503 -279.919804)
			(xy 107.609938 -279.959148) (xy 107.574445 -279.99324) (xy 107.533942 -280.021196) (xy 107.48948 -280.042294)
			(xy 107.442209 -280.055986) (xy 107.393354 -280.061918) (xy 107.344179 -280.059937) (xy 107.29596 -280.050093)
			(xy 107.249944 -280.032641) (xy 107.207323 -280.008034) (xy 107.169202 -279.976909) (xy 107.136567 -279.940072)
			(xy 107.110264 -279.898476) (xy 107.090973 -279.8532) (xy 107.079196 -279.805416) (xy 107.075236 -279.756362)
			(xy 106.746294 -279.756362) (xy 106.745799 -279.780969) (xy 106.737904 -279.829546) (xy 106.72232 -279.876227)
			(xy 106.699449 -279.919804) (xy 106.669884 -279.959148) (xy 106.634391 -279.99324) (xy 106.593888 -280.021196)
			(xy 106.549426 -280.042294) (xy 106.502155 -280.055986) (xy 106.4533 -280.061918) (xy 106.404125 -280.059937)
			(xy 106.355906 -280.050093) (xy 106.30989 -280.032641) (xy 106.267269 -280.008034) (xy 106.229148 -279.976909)
			(xy 106.196513 -279.940072) (xy 106.17021 -279.898476) (xy 106.150919 -279.8532) (xy 106.139142 -279.805416)
			(xy 106.135182 -279.756362) (xy 105.80624 -279.756362) (xy 105.805745 -279.780969) (xy 105.79785 -279.829546)
			(xy 105.782266 -279.876227) (xy 105.759395 -279.919804) (xy 105.72983 -279.959148) (xy 105.694337 -279.99324)
			(xy 105.653834 -280.021196) (xy 105.609372 -280.042294) (xy 105.562101 -280.055986) (xy 105.513246 -280.061918)
			(xy 105.464071 -280.059937) (xy 105.415852 -280.050093) (xy 105.369836 -280.032641) (xy 105.327215 -280.008034)
			(xy 105.289094 -279.976909) (xy 105.256459 -279.940072) (xy 105.230156 -279.898476) (xy 105.210865 -279.8532)
			(xy 105.199088 -279.805416) (xy 105.195128 -279.756362) (xy 104.86644 -279.756362) (xy 104.865945 -279.780969)
			(xy 104.85805 -279.829546) (xy 104.842466 -279.876227) (xy 104.819595 -279.919804) (xy 104.79003 -279.959148)
			(xy 104.754537 -279.99324) (xy 104.714034 -280.021196) (xy 104.669572 -280.042294) (xy 104.622301 -280.055986)
			(xy 104.573446 -280.061918) (xy 104.524271 -280.059937) (xy 104.476052 -280.050093) (xy 104.430036 -280.032641)
			(xy 104.387415 -280.008034) (xy 104.349294 -279.976909) (xy 104.316659 -279.940072) (xy 104.290356 -279.898476)
			(xy 104.271065 -279.8532) (xy 104.259288 -279.805416) (xy 104.255328 -279.756362) (xy 103.926386 -279.756362)
			(xy 103.925891 -279.780969) (xy 103.917996 -279.829546) (xy 103.902412 -279.876227) (xy 103.879541 -279.919804)
			(xy 103.849976 -279.959148) (xy 103.814483 -279.99324) (xy 103.77398 -280.021196) (xy 103.729518 -280.042294)
			(xy 103.682247 -280.055986) (xy 103.633392 -280.061918) (xy 103.584217 -280.059937) (xy 103.535998 -280.050093)
			(xy 103.489982 -280.032641) (xy 103.447361 -280.008034) (xy 103.40924 -279.976909) (xy 103.376605 -279.940072)
			(xy 103.350302 -279.898476) (xy 103.331011 -279.8532) (xy 103.319234 -279.805416) (xy 103.315274 -279.756362)
			(xy 102.986332 -279.756362) (xy 102.985837 -279.780969) (xy 102.977942 -279.829546) (xy 102.962358 -279.876227)
			(xy 102.939487 -279.919804) (xy 102.909922 -279.959148) (xy 102.874429 -279.99324) (xy 102.833926 -280.021196)
			(xy 102.789464 -280.042294) (xy 102.742193 -280.055986) (xy 102.693338 -280.061918) (xy 102.644163 -280.059937)
			(xy 102.595944 -280.050093) (xy 102.549928 -280.032641) (xy 102.507307 -280.008034) (xy 102.469186 -279.976909)
			(xy 102.436551 -279.940072) (xy 102.410248 -279.898476) (xy 102.390957 -279.8532) (xy 102.37918 -279.805416)
			(xy 102.37522 -279.756362) (xy 102.046278 -279.756362) (xy 102.045783 -279.780969) (xy 102.037888 -279.829546)
			(xy 102.022304 -279.876227) (xy 101.999433 -279.919804) (xy 101.969868 -279.959148) (xy 101.934375 -279.99324)
			(xy 101.893872 -280.021196) (xy 101.84941 -280.042294) (xy 101.802139 -280.055986) (xy 101.753284 -280.061918)
			(xy 101.704109 -280.059937) (xy 101.65589 -280.050093) (xy 101.609874 -280.032641) (xy 101.567253 -280.008034)
			(xy 101.529132 -279.976909) (xy 101.496497 -279.940072) (xy 101.470194 -279.898476) (xy 101.450903 -279.8532)
			(xy 101.439126 -279.805416) (xy 101.435166 -279.756362) (xy 101.106478 -279.756362) (xy 101.105983 -279.780969)
			(xy 101.098088 -279.829546) (xy 101.082504 -279.876227) (xy 101.059633 -279.919804) (xy 101.030068 -279.959148)
			(xy 100.994575 -279.99324) (xy 100.954072 -280.021196) (xy 100.90961 -280.042294) (xy 100.862339 -280.055986)
			(xy 100.813484 -280.061918) (xy 100.764309 -280.059937) (xy 100.71609 -280.050093) (xy 100.670074 -280.032641)
			(xy 100.627453 -280.008034) (xy 100.589332 -279.976909) (xy 100.556697 -279.940072) (xy 100.530394 -279.898476)
			(xy 100.511103 -279.8532) (xy 100.499326 -279.805416) (xy 100.495366 -279.756362) (xy 100.166424 -279.756362)
			(xy 100.165929 -279.780969) (xy 100.158034 -279.829546) (xy 100.14245 -279.876227) (xy 100.119579 -279.919804)
			(xy 100.090014 -279.959148) (xy 100.054521 -279.99324) (xy 100.014018 -280.021196) (xy 99.969556 -280.042294)
			(xy 99.922285 -280.055986) (xy 99.87343 -280.061918) (xy 99.824255 -280.059937) (xy 99.776036 -280.050093)
			(xy 99.73002 -280.032641) (xy 99.687399 -280.008034) (xy 99.649278 -279.976909) (xy 99.616643 -279.940072)
			(xy 99.59034 -279.898476) (xy 99.571049 -279.8532) (xy 99.559272 -279.805416) (xy 99.555312 -279.756362)
			(xy 99.22637 -279.756362) (xy 99.225875 -279.780969) (xy 99.21798 -279.829546) (xy 99.202396 -279.876227)
			(xy 99.179525 -279.919804) (xy 99.14996 -279.959148) (xy 99.114467 -279.99324) (xy 99.073964 -280.021196)
			(xy 99.029502 -280.042294) (xy 98.982231 -280.055986) (xy 98.933376 -280.061918) (xy 98.884201 -280.059937)
			(xy 98.835982 -280.050093) (xy 98.789966 -280.032641) (xy 98.747345 -280.008034) (xy 98.709224 -279.976909)
			(xy 98.676589 -279.940072) (xy 98.650286 -279.898476) (xy 98.630995 -279.8532) (xy 98.619218 -279.805416)
			(xy 98.615258 -279.756362) (xy 98.286316 -279.756362) (xy 98.285821 -279.780969) (xy 98.277926 -279.829546)
			(xy 98.262342 -279.876227) (xy 98.239471 -279.919804) (xy 98.209906 -279.959148) (xy 98.174413 -279.99324)
			(xy 98.13391 -280.021196) (xy 98.089448 -280.042294) (xy 98.042177 -280.055986) (xy 97.993322 -280.061918)
			(xy 97.944147 -280.059937) (xy 97.895928 -280.050093) (xy 97.849912 -280.032641) (xy 97.807291 -280.008034)
			(xy 97.76917 -279.976909) (xy 97.736535 -279.940072) (xy 97.710232 -279.898476) (xy 97.690941 -279.8532)
			(xy 97.679164 -279.805416) (xy 97.675204 -279.756362) (xy 97.346262 -279.756362) (xy 97.345793 -279.780599)
			(xy 97.338127 -279.828463) (xy 97.322998 -279.874516) (xy 97.300786 -279.917602) (xy 97.272047 -279.956639)
			(xy 97.237504 -279.990647) (xy 97.198024 -280.018772) (xy 97.154596 -280.040309) (xy 97.108313 -280.054717)
			(xy 97.084388 -280.058622) (xy 97.071942 -280.0604) (xy 97.040954 -280.061924) (xy 97.017459 -280.061491)
			(xy 96.971022 -280.054296) (xy 96.926232 -280.040083) (xy 96.884144 -280.019185) (xy 96.845747 -279.992096)
			(xy 96.811946 -279.959452) (xy 96.797368 -279.94102) (xy 96.795336 -279.938226) (xy 96.795082 -279.937972)
			(xy 96.790945 -279.932599) (xy 96.78039 -279.924094) (xy 96.774254 -279.921208) (xy 96.768412 -279.918922)
			(xy 96.755204 -279.917144) (xy 96.661986 -279.929336) (xy 96.655309 -279.930382) (xy 96.642818 -279.935528)
			(xy 96.637348 -279.939496) (xy 96.63176 -279.943814) (xy 96.62414 -279.954228) (xy 96.621346 -279.96134)
			(xy 96.613469 -279.980912) (xy 96.595164 -280.018927) (xy 96.58477 -280.037286) (xy 96.539812 -280.114756)
			(xy 96.534213 -280.125825) (xy 96.533422 -280.150589) (xy 96.538288 -280.162) (xy 96.552766 -280.191464)
			(xy 96.576388 -280.238962) (xy 96.57715 -280.240232) (xy 96.579847 -280.244475) (xy 96.586632 -280.251892)
			(xy 96.590612 -280.254964) (xy 96.600518 -280.262076) (xy 96.613218 -280.263854) (xy 96.637223 -280.267701)
			(xy 96.683687 -280.282) (xy 96.727301 -280.303474) (xy 96.766965 -280.331582) (xy 96.801679 -280.365615)
			(xy 96.830568 -280.404714) (xy 96.852903 -280.447893) (xy 96.868121 -280.494064) (xy 96.875838 -280.542061)
			(xy 96.876362 -280.566368) (xy 97.205304 -280.566368) (xy 97.209264 -280.517314) (xy 97.221041 -280.46953)
			(xy 97.240332 -280.424254) (xy 97.266635 -280.382658) (xy 97.29927 -280.345821) (xy 97.337391 -280.314696)
			(xy 97.380012 -280.290089) (xy 97.426028 -280.272637) (xy 97.474247 -280.262793) (xy 97.523422 -280.260812)
			(xy 97.572277 -280.266744) (xy 97.619548 -280.280436) (xy 97.66401 -280.301534) (xy 97.704513 -280.32949)
			(xy 97.740006 -280.363582) (xy 97.769571 -280.402926) (xy 97.792442 -280.446503) (xy 97.808026 -280.493184)
			(xy 97.815921 -280.541761) (xy 97.816416 -280.566368) (xy 98.145358 -280.566368) (xy 98.149318 -280.517314)
			(xy 98.161095 -280.46953) (xy 98.180386 -280.424254) (xy 98.206689 -280.382658) (xy 98.239324 -280.345821)
			(xy 98.277445 -280.314696) (xy 98.320066 -280.290089) (xy 98.366082 -280.272637) (xy 98.414301 -280.262793)
			(xy 98.463476 -280.260812) (xy 98.512331 -280.266744) (xy 98.559602 -280.280436) (xy 98.604064 -280.301534)
			(xy 98.644567 -280.32949) (xy 98.68006 -280.363582) (xy 98.709625 -280.402926) (xy 98.732496 -280.446503)
			(xy 98.74808 -280.493184) (xy 98.755975 -280.541761) (xy 98.75647 -280.566368) (xy 99.085158 -280.566368)
			(xy 99.089118 -280.517314) (xy 99.100895 -280.46953) (xy 99.120186 -280.424254) (xy 99.146489 -280.382658)
			(xy 99.179124 -280.345821) (xy 99.217245 -280.314696) (xy 99.259866 -280.290089) (xy 99.305882 -280.272637)
			(xy 99.354101 -280.262793) (xy 99.403276 -280.260812) (xy 99.452131 -280.266744) (xy 99.499402 -280.280436)
			(xy 99.543864 -280.301534) (xy 99.584367 -280.32949) (xy 99.61986 -280.363582) (xy 99.649425 -280.402926)
			(xy 99.672296 -280.446503) (xy 99.68788 -280.493184) (xy 99.695775 -280.541761) (xy 99.69627 -280.566368)
			(xy 100.025212 -280.566368) (xy 100.029172 -280.517314) (xy 100.040949 -280.46953) (xy 100.06024 -280.424254)
			(xy 100.086543 -280.382658) (xy 100.119178 -280.345821) (xy 100.157299 -280.314696) (xy 100.19992 -280.290089)
			(xy 100.245936 -280.272637) (xy 100.294155 -280.262793) (xy 100.34333 -280.260812) (xy 100.392185 -280.266744)
			(xy 100.439456 -280.280436) (xy 100.483918 -280.301534) (xy 100.524421 -280.32949) (xy 100.559914 -280.363582)
			(xy 100.589479 -280.402926) (xy 100.61235 -280.446503) (xy 100.627934 -280.493184) (xy 100.635829 -280.541761)
			(xy 100.636324 -280.566368) (xy 100.965266 -280.566368) (xy 100.969226 -280.517314) (xy 100.981003 -280.46953)
			(xy 101.000294 -280.424254) (xy 101.026597 -280.382658) (xy 101.059232 -280.345821) (xy 101.097353 -280.314696)
			(xy 101.139974 -280.290089) (xy 101.18599 -280.272637) (xy 101.234209 -280.262793) (xy 101.283384 -280.260812)
			(xy 101.332239 -280.266744) (xy 101.37951 -280.280436) (xy 101.423972 -280.301534) (xy 101.464475 -280.32949)
			(xy 101.499968 -280.363582) (xy 101.529533 -280.402926) (xy 101.552404 -280.446503) (xy 101.567988 -280.493184)
			(xy 101.575883 -280.541761) (xy 101.576378 -280.566368) (xy 101.90532 -280.566368) (xy 101.90928 -280.517314)
			(xy 101.921057 -280.46953) (xy 101.940348 -280.424254) (xy 101.966651 -280.382658) (xy 101.999286 -280.345821)
			(xy 102.037407 -280.314696) (xy 102.080028 -280.290089) (xy 102.126044 -280.272637) (xy 102.174263 -280.262793)
			(xy 102.223438 -280.260812) (xy 102.272293 -280.266744) (xy 102.319564 -280.280436) (xy 102.364026 -280.301534)
			(xy 102.404529 -280.32949) (xy 102.440022 -280.363582) (xy 102.469587 -280.402926) (xy 102.492458 -280.446503)
			(xy 102.508042 -280.493184) (xy 102.515937 -280.541761) (xy 102.516432 -280.566368) (xy 102.845374 -280.566368)
			(xy 102.849334 -280.517314) (xy 102.861111 -280.46953) (xy 102.880402 -280.424254) (xy 102.906705 -280.382658)
			(xy 102.93934 -280.345821) (xy 102.977461 -280.314696) (xy 103.020082 -280.290089) (xy 103.066098 -280.272637)
			(xy 103.114317 -280.262793) (xy 103.163492 -280.260812) (xy 103.212347 -280.266744) (xy 103.259618 -280.280436)
			(xy 103.30408 -280.301534) (xy 103.344583 -280.32949) (xy 103.380076 -280.363582) (xy 103.409641 -280.402926)
			(xy 103.432512 -280.446503) (xy 103.448096 -280.493184) (xy 103.455991 -280.541761) (xy 103.456486 -280.566368)
			(xy 103.785174 -280.566368) (xy 103.789134 -280.517314) (xy 103.800911 -280.46953) (xy 103.820202 -280.424254)
			(xy 103.846505 -280.382658) (xy 103.87914 -280.345821) (xy 103.917261 -280.314696) (xy 103.959882 -280.290089)
			(xy 104.005898 -280.272637) (xy 104.054117 -280.262793) (xy 104.103292 -280.260812) (xy 104.152147 -280.266744)
			(xy 104.199418 -280.280436) (xy 104.24388 -280.301534) (xy 104.284383 -280.32949) (xy 104.319876 -280.363582)
			(xy 104.349441 -280.402926) (xy 104.372312 -280.446503) (xy 104.387896 -280.493184) (xy 104.395791 -280.541761)
			(xy 104.396286 -280.566368) (xy 104.725228 -280.566368) (xy 104.729188 -280.517314) (xy 104.740965 -280.46953)
			(xy 104.760256 -280.424254) (xy 104.786559 -280.382658) (xy 104.819194 -280.345821) (xy 104.857315 -280.314696)
			(xy 104.899936 -280.290089) (xy 104.945952 -280.272637) (xy 104.994171 -280.262793) (xy 105.043346 -280.260812)
			(xy 105.092201 -280.266744) (xy 105.139472 -280.280436) (xy 105.183934 -280.301534) (xy 105.224437 -280.32949)
			(xy 105.25993 -280.363582) (xy 105.289495 -280.402926) (xy 105.312366 -280.446503) (xy 105.32795 -280.493184)
			(xy 105.335845 -280.541761) (xy 105.33634 -280.566368) (xy 105.665282 -280.566368) (xy 105.669242 -280.517314)
			(xy 105.681019 -280.46953) (xy 105.70031 -280.424254) (xy 105.726613 -280.382658) (xy 105.759248 -280.345821)
			(xy 105.797369 -280.314696) (xy 105.83999 -280.290089) (xy 105.886006 -280.272637) (xy 105.934225 -280.262793)
			(xy 105.9834 -280.260812) (xy 106.032255 -280.266744) (xy 106.079526 -280.280436) (xy 106.123988 -280.301534)
			(xy 106.164491 -280.32949) (xy 106.199984 -280.363582) (xy 106.229549 -280.402926) (xy 106.25242 -280.446503)
			(xy 106.268004 -280.493184) (xy 106.275899 -280.541761) (xy 106.276394 -280.566368) (xy 106.605336 -280.566368)
			(xy 106.609296 -280.517314) (xy 106.621073 -280.46953) (xy 106.640364 -280.424254) (xy 106.666667 -280.382658)
			(xy 106.699302 -280.345821) (xy 106.737423 -280.314696) (xy 106.780044 -280.290089) (xy 106.82606 -280.272637)
			(xy 106.874279 -280.262793) (xy 106.923454 -280.260812) (xy 106.972309 -280.266744) (xy 107.01958 -280.280436)
			(xy 107.064042 -280.301534) (xy 107.104545 -280.32949) (xy 107.140038 -280.363582) (xy 107.169603 -280.402926)
			(xy 107.192474 -280.446503) (xy 107.208058 -280.493184) (xy 107.215953 -280.541761) (xy 107.216448 -280.566368)
			(xy 107.545136 -280.566368) (xy 107.549096 -280.517314) (xy 107.560873 -280.46953) (xy 107.580164 -280.424254)
			(xy 107.606467 -280.382658) (xy 107.639102 -280.345821) (xy 107.677223 -280.314696) (xy 107.719844 -280.290089)
			(xy 107.76586 -280.272637) (xy 107.814079 -280.262793) (xy 107.863254 -280.260812) (xy 107.912109 -280.266744)
			(xy 107.95938 -280.280436) (xy 108.003842 -280.301534) (xy 108.044345 -280.32949) (xy 108.079838 -280.363582)
			(xy 108.109403 -280.402926) (xy 108.132274 -280.446503) (xy 108.147858 -280.493184) (xy 108.155753 -280.541761)
			(xy 108.156248 -280.566368) (xy 110.365298 -280.566368) (xy 110.369258 -280.517314) (xy 110.381035 -280.46953)
			(xy 110.400326 -280.424254) (xy 110.426629 -280.382658) (xy 110.459264 -280.345821) (xy 110.497385 -280.314696)
			(xy 110.540006 -280.290089) (xy 110.586022 -280.272637) (xy 110.634241 -280.262793) (xy 110.683416 -280.260812)
			(xy 110.732271 -280.266744) (xy 110.779542 -280.280436) (xy 110.824004 -280.301534) (xy 110.864507 -280.32949)
			(xy 110.9 -280.363582) (xy 110.929565 -280.402926) (xy 110.952436 -280.446503) (xy 110.96802 -280.493184)
			(xy 110.975915 -280.541761) (xy 110.97641 -280.566368) (xy 113.178856 -280.566368) (xy 113.182816 -280.517314)
			(xy 113.194593 -280.46953) (xy 113.213884 -280.424254) (xy 113.240187 -280.382658) (xy 113.272822 -280.345821)
			(xy 113.310943 -280.314696) (xy 113.353564 -280.290089) (xy 113.39958 -280.272637) (xy 113.447799 -280.262793)
			(xy 113.496974 -280.260812) (xy 113.545829 -280.266744) (xy 113.5931 -280.280436) (xy 113.637562 -280.301534)
			(xy 113.678065 -280.32949) (xy 113.713558 -280.363582) (xy 113.743123 -280.402926) (xy 113.765994 -280.446503)
			(xy 113.781578 -280.493184) (xy 113.789473 -280.541761) (xy 113.789968 -280.566368) (xy 115.999018 -280.566368)
			(xy 116.002978 -280.517314) (xy 116.014755 -280.46953) (xy 116.034046 -280.424254) (xy 116.060349 -280.382658)
			(xy 116.092984 -280.345821) (xy 116.131105 -280.314696) (xy 116.173726 -280.290089) (xy 116.219742 -280.272637)
			(xy 116.267961 -280.262793) (xy 116.317136 -280.260812) (xy 116.365991 -280.266744) (xy 116.413262 -280.280436)
			(xy 116.457724 -280.301534) (xy 116.498227 -280.32949) (xy 116.53372 -280.363582) (xy 116.563285 -280.402926)
			(xy 116.586156 -280.446503) (xy 116.60174 -280.493184) (xy 116.609635 -280.541761) (xy 116.61013 -280.566368)
			(xy 116.938818 -280.566368) (xy 116.942778 -280.517314) (xy 116.954555 -280.46953) (xy 116.973846 -280.424254)
			(xy 117.000149 -280.382658) (xy 117.032784 -280.345821) (xy 117.070905 -280.314696) (xy 117.113526 -280.290089)
			(xy 117.159542 -280.272637) (xy 117.207761 -280.262793) (xy 117.256936 -280.260812) (xy 117.305791 -280.266744)
			(xy 117.353062 -280.280436) (xy 117.397524 -280.301534) (xy 117.438027 -280.32949) (xy 117.47352 -280.363582)
			(xy 117.503085 -280.402926) (xy 117.525956 -280.446503) (xy 117.54154 -280.493184) (xy 117.549435 -280.541761)
			(xy 117.54993 -280.566368) (xy 117.878872 -280.566368) (xy 117.882832 -280.517314) (xy 117.894609 -280.46953)
			(xy 117.9139 -280.424254) (xy 117.940203 -280.382658) (xy 117.972838 -280.345821) (xy 118.010959 -280.314696)
			(xy 118.05358 -280.290089) (xy 118.099596 -280.272637) (xy 118.147815 -280.262793) (xy 118.19699 -280.260812)
			(xy 118.245845 -280.266744) (xy 118.293116 -280.280436) (xy 118.337578 -280.301534) (xy 118.378081 -280.32949)
			(xy 118.413574 -280.363582) (xy 118.443139 -280.402926) (xy 118.46601 -280.446503) (xy 118.481594 -280.493184)
			(xy 118.489489 -280.541761) (xy 118.489984 -280.566368) (xy 118.818926 -280.566368) (xy 118.822886 -280.517314)
			(xy 118.834663 -280.46953) (xy 118.853954 -280.424254) (xy 118.880257 -280.382658) (xy 118.912892 -280.345821)
			(xy 118.951013 -280.314696) (xy 118.993634 -280.290089) (xy 119.03965 -280.272637) (xy 119.087869 -280.262793)
			(xy 119.137044 -280.260812) (xy 119.185899 -280.266744) (xy 119.23317 -280.280436) (xy 119.277632 -280.301534)
			(xy 119.318135 -280.32949) (xy 119.353628 -280.363582) (xy 119.383193 -280.402926) (xy 119.406064 -280.446503)
			(xy 119.421648 -280.493184) (xy 119.429543 -280.541761) (xy 119.430038 -280.566368) (xy 119.75898 -280.566368)
			(xy 119.76294 -280.517314) (xy 119.774717 -280.46953) (xy 119.794008 -280.424254) (xy 119.820311 -280.382658)
			(xy 119.852946 -280.345821) (xy 119.891067 -280.314696) (xy 119.933688 -280.290089) (xy 119.979704 -280.272637)
			(xy 120.027923 -280.262793) (xy 120.077098 -280.260812) (xy 120.125953 -280.266744) (xy 120.173224 -280.280436)
			(xy 120.217686 -280.301534) (xy 120.258189 -280.32949) (xy 120.293682 -280.363582) (xy 120.323247 -280.402926)
			(xy 120.346118 -280.446503) (xy 120.361702 -280.493184) (xy 120.369597 -280.541761) (xy 120.370092 -280.566368)
			(xy 120.699034 -280.566368) (xy 120.702994 -280.517314) (xy 120.714771 -280.46953) (xy 120.734062 -280.424254)
			(xy 120.760365 -280.382658) (xy 120.793 -280.345821) (xy 120.831121 -280.314696) (xy 120.873742 -280.290089)
			(xy 120.919758 -280.272637) (xy 120.967977 -280.262793) (xy 121.017152 -280.260812) (xy 121.066007 -280.266744)
			(xy 121.113278 -280.280436) (xy 121.15774 -280.301534) (xy 121.198243 -280.32949) (xy 121.233736 -280.363582)
			(xy 121.263301 -280.402926) (xy 121.286172 -280.446503) (xy 121.301756 -280.493184) (xy 121.309651 -280.541761)
			(xy 121.310146 -280.566368) (xy 121.638834 -280.566368) (xy 121.642794 -280.517314) (xy 121.654571 -280.46953)
			(xy 121.673862 -280.424254) (xy 121.700165 -280.382658) (xy 121.7328 -280.345821) (xy 121.770921 -280.314696)
			(xy 121.813542 -280.290089) (xy 121.859558 -280.272637) (xy 121.907777 -280.262793) (xy 121.956952 -280.260812)
			(xy 122.005807 -280.266744) (xy 122.053078 -280.280436) (xy 122.09754 -280.301534) (xy 122.138043 -280.32949)
			(xy 122.173536 -280.363582) (xy 122.203101 -280.402926) (xy 122.225972 -280.446503) (xy 122.241556 -280.493184)
			(xy 122.249451 -280.541761) (xy 122.249946 -280.566368) (xy 122.578888 -280.566368) (xy 122.582848 -280.517314)
			(xy 122.594625 -280.46953) (xy 122.613916 -280.424254) (xy 122.640219 -280.382658) (xy 122.672854 -280.345821)
			(xy 122.710975 -280.314696) (xy 122.753596 -280.290089) (xy 122.799612 -280.272637) (xy 122.847831 -280.262793)
			(xy 122.897006 -280.260812) (xy 122.945861 -280.266744) (xy 122.993132 -280.280436) (xy 123.037594 -280.301534)
			(xy 123.078097 -280.32949) (xy 123.11359 -280.363582) (xy 123.143155 -280.402926) (xy 123.166026 -280.446503)
			(xy 123.18161 -280.493184) (xy 123.189505 -280.541761) (xy 123.19 -280.566368) (xy 123.518942 -280.566368)
			(xy 123.522902 -280.517314) (xy 123.534679 -280.46953) (xy 123.55397 -280.424254) (xy 123.580273 -280.382658)
			(xy 123.612908 -280.345821) (xy 123.651029 -280.314696) (xy 123.69365 -280.290089) (xy 123.739666 -280.272637)
			(xy 123.787885 -280.262793) (xy 123.83706 -280.260812) (xy 123.885915 -280.266744) (xy 123.933186 -280.280436)
			(xy 123.977648 -280.301534) (xy 124.018151 -280.32949) (xy 124.053644 -280.363582) (xy 124.083209 -280.402926)
			(xy 124.10608 -280.446503) (xy 124.121664 -280.493184) (xy 124.129559 -280.541761) (xy 124.130054 -280.566368)
			(xy 124.458996 -280.566368) (xy 124.462956 -280.517314) (xy 124.474733 -280.46953) (xy 124.494024 -280.424254)
			(xy 124.520327 -280.382658) (xy 124.552962 -280.345821) (xy 124.591083 -280.314696) (xy 124.633704 -280.290089)
			(xy 124.67972 -280.272637) (xy 124.727939 -280.262793) (xy 124.777114 -280.260812) (xy 124.825969 -280.266744)
			(xy 124.87324 -280.280436) (xy 124.917702 -280.301534) (xy 124.958205 -280.32949) (xy 124.993698 -280.363582)
			(xy 125.023263 -280.402926) (xy 125.046134 -280.446503) (xy 125.061718 -280.493184) (xy 125.069613 -280.541761)
			(xy 125.070108 -280.566368) (xy 125.39905 -280.566368) (xy 125.40301 -280.517314) (xy 125.414787 -280.46953)
			(xy 125.434078 -280.424254) (xy 125.460381 -280.382658) (xy 125.493016 -280.345821) (xy 125.531137 -280.314696)
			(xy 125.573758 -280.290089) (xy 125.619774 -280.272637) (xy 125.667993 -280.262793) (xy 125.717168 -280.260812)
			(xy 125.766023 -280.266744) (xy 125.813294 -280.280436) (xy 125.857756 -280.301534) (xy 125.898259 -280.32949)
			(xy 125.933752 -280.363582) (xy 125.963317 -280.402926) (xy 125.986188 -280.446503) (xy 126.001772 -280.493184)
			(xy 126.009667 -280.541761) (xy 126.010162 -280.566368) (xy 126.33885 -280.566368) (xy 126.34281 -280.517314)
			(xy 126.354587 -280.46953) (xy 126.373878 -280.424254) (xy 126.400181 -280.382658) (xy 126.432816 -280.345821)
			(xy 126.470937 -280.314696) (xy 126.513558 -280.290089) (xy 126.559574 -280.272637) (xy 126.607793 -280.262793)
			(xy 126.656968 -280.260812) (xy 126.705823 -280.266744) (xy 126.753094 -280.280436) (xy 126.797556 -280.301534)
			(xy 126.838059 -280.32949) (xy 126.873552 -280.363582) (xy 126.903117 -280.402926) (xy 126.925988 -280.446503)
			(xy 126.941572 -280.493184) (xy 126.949467 -280.541761) (xy 126.949962 -280.566368) (xy 126.949467 -280.590975)
			(xy 126.941572 -280.639552) (xy 126.925988 -280.686233) (xy 126.903117 -280.72981) (xy 126.873552 -280.769154)
			(xy 126.838059 -280.803246) (xy 126.797556 -280.831202) (xy 126.753094 -280.8523) (xy 126.705823 -280.865992)
			(xy 126.656968 -280.871924) (xy 126.607793 -280.869943) (xy 126.559574 -280.860099) (xy 126.513558 -280.842647)
			(xy 126.470937 -280.81804) (xy 126.432816 -280.786915) (xy 126.400181 -280.750078) (xy 126.373878 -280.708482)
			(xy 126.354587 -280.663206) (xy 126.34281 -280.615422) (xy 126.33885 -280.566368) (xy 126.010162 -280.566368)
			(xy 126.009667 -280.590975) (xy 126.001772 -280.639552) (xy 125.986188 -280.686233) (xy 125.963317 -280.72981)
			(xy 125.933752 -280.769154) (xy 125.898259 -280.803246) (xy 125.857756 -280.831202) (xy 125.813294 -280.8523)
			(xy 125.766023 -280.865992) (xy 125.717168 -280.871924) (xy 125.667993 -280.869943) (xy 125.619774 -280.860099)
			(xy 125.573758 -280.842647) (xy 125.531137 -280.81804) (xy 125.493016 -280.786915) (xy 125.460381 -280.750078)
			(xy 125.434078 -280.708482) (xy 125.414787 -280.663206) (xy 125.40301 -280.615422) (xy 125.39905 -280.566368)
			(xy 125.070108 -280.566368) (xy 125.069613 -280.590975) (xy 125.061718 -280.639552) (xy 125.046134 -280.686233)
			(xy 125.023263 -280.72981) (xy 124.993698 -280.769154) (xy 124.958205 -280.803246) (xy 124.917702 -280.831202)
			(xy 124.87324 -280.8523) (xy 124.825969 -280.865992) (xy 124.777114 -280.871924) (xy 124.727939 -280.869943)
			(xy 124.67972 -280.860099) (xy 124.633704 -280.842647) (xy 124.591083 -280.81804) (xy 124.552962 -280.786915)
			(xy 124.520327 -280.750078) (xy 124.494024 -280.708482) (xy 124.474733 -280.663206) (xy 124.462956 -280.615422)
			(xy 124.458996 -280.566368) (xy 124.130054 -280.566368) (xy 124.129559 -280.590975) (xy 124.121664 -280.639552)
			(xy 124.10608 -280.686233) (xy 124.083209 -280.72981) (xy 124.053644 -280.769154) (xy 124.018151 -280.803246)
			(xy 123.977648 -280.831202) (xy 123.933186 -280.8523) (xy 123.885915 -280.865992) (xy 123.83706 -280.871924)
			(xy 123.787885 -280.869943) (xy 123.739666 -280.860099) (xy 123.69365 -280.842647) (xy 123.651029 -280.81804)
			(xy 123.612908 -280.786915) (xy 123.580273 -280.750078) (xy 123.55397 -280.708482) (xy 123.534679 -280.663206)
			(xy 123.522902 -280.615422) (xy 123.518942 -280.566368) (xy 123.19 -280.566368) (xy 123.189505 -280.590975)
			(xy 123.18161 -280.639552) (xy 123.166026 -280.686233) (xy 123.143155 -280.72981) (xy 123.11359 -280.769154)
			(xy 123.078097 -280.803246) (xy 123.037594 -280.831202) (xy 122.993132 -280.8523) (xy 122.945861 -280.865992)
			(xy 122.897006 -280.871924) (xy 122.847831 -280.869943) (xy 122.799612 -280.860099) (xy 122.753596 -280.842647)
			(xy 122.710975 -280.81804) (xy 122.672854 -280.786915) (xy 122.640219 -280.750078) (xy 122.613916 -280.708482)
			(xy 122.594625 -280.663206) (xy 122.582848 -280.615422) (xy 122.578888 -280.566368) (xy 122.249946 -280.566368)
			(xy 122.249451 -280.590975) (xy 122.241556 -280.639552) (xy 122.225972 -280.686233) (xy 122.203101 -280.72981)
			(xy 122.173536 -280.769154) (xy 122.138043 -280.803246) (xy 122.09754 -280.831202) (xy 122.053078 -280.8523)
			(xy 122.005807 -280.865992) (xy 121.956952 -280.871924) (xy 121.907777 -280.869943) (xy 121.859558 -280.860099)
			(xy 121.813542 -280.842647) (xy 121.770921 -280.81804) (xy 121.7328 -280.786915) (xy 121.700165 -280.750078)
			(xy 121.673862 -280.708482) (xy 121.654571 -280.663206) (xy 121.642794 -280.615422) (xy 121.638834 -280.566368)
			(xy 121.310146 -280.566368) (xy 121.309651 -280.590975) (xy 121.301756 -280.639552) (xy 121.286172 -280.686233)
			(xy 121.263301 -280.72981) (xy 121.233736 -280.769154) (xy 121.198243 -280.803246) (xy 121.15774 -280.831202)
			(xy 121.113278 -280.8523) (xy 121.066007 -280.865992) (xy 121.017152 -280.871924) (xy 120.967977 -280.869943)
			(xy 120.919758 -280.860099) (xy 120.873742 -280.842647) (xy 120.831121 -280.81804) (xy 120.793 -280.786915)
			(xy 120.760365 -280.750078) (xy 120.734062 -280.708482) (xy 120.714771 -280.663206) (xy 120.702994 -280.615422)
			(xy 120.699034 -280.566368) (xy 120.370092 -280.566368) (xy 120.369597 -280.590975) (xy 120.361702 -280.639552)
			(xy 120.346118 -280.686233) (xy 120.323247 -280.72981) (xy 120.293682 -280.769154) (xy 120.258189 -280.803246)
			(xy 120.217686 -280.831202) (xy 120.173224 -280.8523) (xy 120.125953 -280.865992) (xy 120.077098 -280.871924)
			(xy 120.027923 -280.869943) (xy 119.979704 -280.860099) (xy 119.933688 -280.842647) (xy 119.891067 -280.81804)
			(xy 119.852946 -280.786915) (xy 119.820311 -280.750078) (xy 119.794008 -280.708482) (xy 119.774717 -280.663206)
			(xy 119.76294 -280.615422) (xy 119.75898 -280.566368) (xy 119.430038 -280.566368) (xy 119.429543 -280.590975)
			(xy 119.421648 -280.639552) (xy 119.406064 -280.686233) (xy 119.383193 -280.72981) (xy 119.353628 -280.769154)
			(xy 119.318135 -280.803246) (xy 119.277632 -280.831202) (xy 119.23317 -280.8523) (xy 119.185899 -280.865992)
			(xy 119.137044 -280.871924) (xy 119.087869 -280.869943) (xy 119.03965 -280.860099) (xy 118.993634 -280.842647)
			(xy 118.951013 -280.81804) (xy 118.912892 -280.786915) (xy 118.880257 -280.750078) (xy 118.853954 -280.708482)
			(xy 118.834663 -280.663206) (xy 118.822886 -280.615422) (xy 118.818926 -280.566368) (xy 118.489984 -280.566368)
			(xy 118.489489 -280.590975) (xy 118.481594 -280.639552) (xy 118.46601 -280.686233) (xy 118.443139 -280.72981)
			(xy 118.413574 -280.769154) (xy 118.378081 -280.803246) (xy 118.337578 -280.831202) (xy 118.293116 -280.8523)
			(xy 118.245845 -280.865992) (xy 118.19699 -280.871924) (xy 118.147815 -280.869943) (xy 118.099596 -280.860099)
			(xy 118.05358 -280.842647) (xy 118.010959 -280.81804) (xy 117.972838 -280.786915) (xy 117.940203 -280.750078)
			(xy 117.9139 -280.708482) (xy 117.894609 -280.663206) (xy 117.882832 -280.615422) (xy 117.878872 -280.566368)
			(xy 117.54993 -280.566368) (xy 117.549435 -280.590975) (xy 117.54154 -280.639552) (xy 117.525956 -280.686233)
			(xy 117.503085 -280.72981) (xy 117.47352 -280.769154) (xy 117.438027 -280.803246) (xy 117.397524 -280.831202)
			(xy 117.353062 -280.8523) (xy 117.305791 -280.865992) (xy 117.256936 -280.871924) (xy 117.207761 -280.869943)
			(xy 117.159542 -280.860099) (xy 117.113526 -280.842647) (xy 117.070905 -280.81804) (xy 117.032784 -280.786915)
			(xy 117.000149 -280.750078) (xy 116.973846 -280.708482) (xy 116.954555 -280.663206) (xy 116.942778 -280.615422)
			(xy 116.938818 -280.566368) (xy 116.61013 -280.566368) (xy 116.609635 -280.590975) (xy 116.60174 -280.639552)
			(xy 116.586156 -280.686233) (xy 116.563285 -280.72981) (xy 116.53372 -280.769154) (xy 116.498227 -280.803246)
			(xy 116.457724 -280.831202) (xy 116.413262 -280.8523) (xy 116.365991 -280.865992) (xy 116.317136 -280.871924)
			(xy 116.267961 -280.869943) (xy 116.219742 -280.860099) (xy 116.173726 -280.842647) (xy 116.131105 -280.81804)
			(xy 116.092984 -280.786915) (xy 116.060349 -280.750078) (xy 116.034046 -280.708482) (xy 116.014755 -280.663206)
			(xy 116.002978 -280.615422) (xy 115.999018 -280.566368) (xy 113.789968 -280.566368) (xy 113.789473 -280.590975)
			(xy 113.781578 -280.639552) (xy 113.765994 -280.686233) (xy 113.743123 -280.72981) (xy 113.713558 -280.769154)
			(xy 113.678065 -280.803246) (xy 113.637562 -280.831202) (xy 113.5931 -280.8523) (xy 113.545829 -280.865992)
			(xy 113.496974 -280.871924) (xy 113.447799 -280.869943) (xy 113.39958 -280.860099) (xy 113.353564 -280.842647)
			(xy 113.310943 -280.81804) (xy 113.272822 -280.786915) (xy 113.240187 -280.750078) (xy 113.213884 -280.708482)
			(xy 113.194593 -280.663206) (xy 113.182816 -280.615422) (xy 113.178856 -280.566368) (xy 110.97641 -280.566368)
			(xy 110.975915 -280.590975) (xy 110.96802 -280.639552) (xy 110.952436 -280.686233) (xy 110.929565 -280.72981)
			(xy 110.9 -280.769154) (xy 110.864507 -280.803246) (xy 110.824004 -280.831202) (xy 110.779542 -280.8523)
			(xy 110.732271 -280.865992) (xy 110.683416 -280.871924) (xy 110.634241 -280.869943) (xy 110.586022 -280.860099)
			(xy 110.540006 -280.842647) (xy 110.497385 -280.81804) (xy 110.459264 -280.786915) (xy 110.426629 -280.750078)
			(xy 110.400326 -280.708482) (xy 110.381035 -280.663206) (xy 110.369258 -280.615422) (xy 110.365298 -280.566368)
			(xy 108.156248 -280.566368) (xy 108.155753 -280.590975) (xy 108.147858 -280.639552) (xy 108.132274 -280.686233)
			(xy 108.109403 -280.72981) (xy 108.079838 -280.769154) (xy 108.044345 -280.803246) (xy 108.003842 -280.831202)
			(xy 107.95938 -280.8523) (xy 107.912109 -280.865992) (xy 107.863254 -280.871924) (xy 107.814079 -280.869943)
			(xy 107.76586 -280.860099) (xy 107.719844 -280.842647) (xy 107.677223 -280.81804) (xy 107.639102 -280.786915)
			(xy 107.606467 -280.750078) (xy 107.580164 -280.708482) (xy 107.560873 -280.663206) (xy 107.549096 -280.615422)
			(xy 107.545136 -280.566368) (xy 107.216448 -280.566368) (xy 107.215953 -280.590975) (xy 107.208058 -280.639552)
			(xy 107.192474 -280.686233) (xy 107.169603 -280.72981) (xy 107.140038 -280.769154) (xy 107.104545 -280.803246)
			(xy 107.064042 -280.831202) (xy 107.01958 -280.8523) (xy 106.972309 -280.865992) (xy 106.923454 -280.871924)
			(xy 106.874279 -280.869943) (xy 106.82606 -280.860099) (xy 106.780044 -280.842647) (xy 106.737423 -280.81804)
			(xy 106.699302 -280.786915) (xy 106.666667 -280.750078) (xy 106.640364 -280.708482) (xy 106.621073 -280.663206)
			(xy 106.609296 -280.615422) (xy 106.605336 -280.566368) (xy 106.276394 -280.566368) (xy 106.275899 -280.590975)
			(xy 106.268004 -280.639552) (xy 106.25242 -280.686233) (xy 106.229549 -280.72981) (xy 106.199984 -280.769154)
			(xy 106.164491 -280.803246) (xy 106.123988 -280.831202) (xy 106.079526 -280.8523) (xy 106.032255 -280.865992)
			(xy 105.9834 -280.871924) (xy 105.934225 -280.869943) (xy 105.886006 -280.860099) (xy 105.83999 -280.842647)
			(xy 105.797369 -280.81804) (xy 105.759248 -280.786915) (xy 105.726613 -280.750078) (xy 105.70031 -280.708482)
			(xy 105.681019 -280.663206) (xy 105.669242 -280.615422) (xy 105.665282 -280.566368) (xy 105.33634 -280.566368)
			(xy 105.335845 -280.590975) (xy 105.32795 -280.639552) (xy 105.312366 -280.686233) (xy 105.289495 -280.72981)
			(xy 105.25993 -280.769154) (xy 105.224437 -280.803246) (xy 105.183934 -280.831202) (xy 105.139472 -280.8523)
			(xy 105.092201 -280.865992) (xy 105.043346 -280.871924) (xy 104.994171 -280.869943) (xy 104.945952 -280.860099)
			(xy 104.899936 -280.842647) (xy 104.857315 -280.81804) (xy 104.819194 -280.786915) (xy 104.786559 -280.750078)
			(xy 104.760256 -280.708482) (xy 104.740965 -280.663206) (xy 104.729188 -280.615422) (xy 104.725228 -280.566368)
			(xy 104.396286 -280.566368) (xy 104.395791 -280.590975) (xy 104.387896 -280.639552) (xy 104.372312 -280.686233)
			(xy 104.349441 -280.72981) (xy 104.319876 -280.769154) (xy 104.284383 -280.803246) (xy 104.24388 -280.831202)
			(xy 104.199418 -280.8523) (xy 104.152147 -280.865992) (xy 104.103292 -280.871924) (xy 104.054117 -280.869943)
			(xy 104.005898 -280.860099) (xy 103.959882 -280.842647) (xy 103.917261 -280.81804) (xy 103.87914 -280.786915)
			(xy 103.846505 -280.750078) (xy 103.820202 -280.708482) (xy 103.800911 -280.663206) (xy 103.789134 -280.615422)
			(xy 103.785174 -280.566368) (xy 103.456486 -280.566368) (xy 103.455991 -280.590975) (xy 103.448096 -280.639552)
			(xy 103.432512 -280.686233) (xy 103.409641 -280.72981) (xy 103.380076 -280.769154) (xy 103.344583 -280.803246)
			(xy 103.30408 -280.831202) (xy 103.259618 -280.8523) (xy 103.212347 -280.865992) (xy 103.163492 -280.871924)
			(xy 103.114317 -280.869943) (xy 103.066098 -280.860099) (xy 103.020082 -280.842647) (xy 102.977461 -280.81804)
			(xy 102.93934 -280.786915) (xy 102.906705 -280.750078) (xy 102.880402 -280.708482) (xy 102.861111 -280.663206)
			(xy 102.849334 -280.615422) (xy 102.845374 -280.566368) (xy 102.516432 -280.566368) (xy 102.515937 -280.590975)
			(xy 102.508042 -280.639552) (xy 102.492458 -280.686233) (xy 102.469587 -280.72981) (xy 102.440022 -280.769154)
			(xy 102.404529 -280.803246) (xy 102.364026 -280.831202) (xy 102.319564 -280.8523) (xy 102.272293 -280.865992)
			(xy 102.223438 -280.871924) (xy 102.174263 -280.869943) (xy 102.126044 -280.860099) (xy 102.080028 -280.842647)
			(xy 102.037407 -280.81804) (xy 101.999286 -280.786915) (xy 101.966651 -280.750078) (xy 101.940348 -280.708482)
			(xy 101.921057 -280.663206) (xy 101.90928 -280.615422) (xy 101.90532 -280.566368) (xy 101.576378 -280.566368)
			(xy 101.575883 -280.590975) (xy 101.567988 -280.639552) (xy 101.552404 -280.686233) (xy 101.529533 -280.72981)
			(xy 101.499968 -280.769154) (xy 101.464475 -280.803246) (xy 101.423972 -280.831202) (xy 101.37951 -280.8523)
			(xy 101.332239 -280.865992) (xy 101.283384 -280.871924) (xy 101.234209 -280.869943) (xy 101.18599 -280.860099)
			(xy 101.139974 -280.842647) (xy 101.097353 -280.81804) (xy 101.059232 -280.786915) (xy 101.026597 -280.750078)
			(xy 101.000294 -280.708482) (xy 100.981003 -280.663206) (xy 100.969226 -280.615422) (xy 100.965266 -280.566368)
			(xy 100.636324 -280.566368) (xy 100.635829 -280.590975) (xy 100.627934 -280.639552) (xy 100.61235 -280.686233)
			(xy 100.589479 -280.72981) (xy 100.559914 -280.769154) (xy 100.524421 -280.803246) (xy 100.483918 -280.831202)
			(xy 100.439456 -280.8523) (xy 100.392185 -280.865992) (xy 100.34333 -280.871924) (xy 100.294155 -280.869943)
			(xy 100.245936 -280.860099) (xy 100.19992 -280.842647) (xy 100.157299 -280.81804) (xy 100.119178 -280.786915)
			(xy 100.086543 -280.750078) (xy 100.06024 -280.708482) (xy 100.040949 -280.663206) (xy 100.029172 -280.615422)
			(xy 100.025212 -280.566368) (xy 99.69627 -280.566368) (xy 99.695775 -280.590975) (xy 99.68788 -280.639552)
			(xy 99.672296 -280.686233) (xy 99.649425 -280.72981) (xy 99.61986 -280.769154) (xy 99.584367 -280.803246)
			(xy 99.543864 -280.831202) (xy 99.499402 -280.8523) (xy 99.452131 -280.865992) (xy 99.403276 -280.871924)
			(xy 99.354101 -280.869943) (xy 99.305882 -280.860099) (xy 99.259866 -280.842647) (xy 99.217245 -280.81804)
			(xy 99.179124 -280.786915) (xy 99.146489 -280.750078) (xy 99.120186 -280.708482) (xy 99.100895 -280.663206)
			(xy 99.089118 -280.615422) (xy 99.085158 -280.566368) (xy 98.75647 -280.566368) (xy 98.755975 -280.590975)
			(xy 98.74808 -280.639552) (xy 98.732496 -280.686233) (xy 98.709625 -280.72981) (xy 98.68006 -280.769154)
			(xy 98.644567 -280.803246) (xy 98.604064 -280.831202) (xy 98.559602 -280.8523) (xy 98.512331 -280.865992)
			(xy 98.463476 -280.871924) (xy 98.414301 -280.869943) (xy 98.366082 -280.860099) (xy 98.320066 -280.842647)
			(xy 98.277445 -280.81804) (xy 98.239324 -280.786915) (xy 98.206689 -280.750078) (xy 98.180386 -280.708482)
			(xy 98.161095 -280.663206) (xy 98.149318 -280.615422) (xy 98.145358 -280.566368) (xy 97.816416 -280.566368)
			(xy 97.815921 -280.590975) (xy 97.808026 -280.639552) (xy 97.792442 -280.686233) (xy 97.769571 -280.72981)
			(xy 97.740006 -280.769154) (xy 97.704513 -280.803246) (xy 97.66401 -280.831202) (xy 97.619548 -280.8523)
			(xy 97.572277 -280.865992) (xy 97.523422 -280.871924) (xy 97.474247 -280.869943) (xy 97.426028 -280.860099)
			(xy 97.380012 -280.842647) (xy 97.337391 -280.81804) (xy 97.29927 -280.786915) (xy 97.266635 -280.750078)
			(xy 97.240332 -280.708482) (xy 97.221041 -280.663206) (xy 97.209264 -280.615422) (xy 97.205304 -280.566368)
			(xy 96.876362 -280.566368) (xy 96.875896 -280.590973) (xy 96.868005 -280.639546) (xy 96.852422 -280.686224)
			(xy 96.829551 -280.729796) (xy 96.799984 -280.769134) (xy 96.764489 -280.803218) (xy 96.723985 -280.831164)
			(xy 96.679521 -280.85225) (xy 96.632249 -280.865927) (xy 96.607884 -280.86939) (xy 96.60509 -280.869644)
			(xy 96.599042 -280.870916) (xy 96.587748 -280.875929) (xy 96.582738 -280.87955) (xy 96.577658 -280.88336)
			(xy 96.573848 -280.88844) (xy 96.567244 -280.89987) (xy 96.533208 -280.98242) (xy 96.531272 -280.98831)
			(xy 96.529998 -281.00064) (xy 96.530668 -281.006804) (xy 96.532446 -281.019758) (xy 96.541082 -281.030934)
			(xy 96.565556 -281.063413) (xy 96.605852 -281.13405) (xy 96.621346 -281.17165) (xy 96.62414 -281.178508)
			(xy 96.63176 -281.188922) (xy 96.637348 -281.19324) (xy 96.642018 -281.196677) (xy 96.652535 -281.201551)
			(xy 96.658176 -281.202892) (xy 96.75114 -281.215084) (xy 96.754912 -281.215261) (xy 96.762436 -281.214617)
			(xy 96.766126 -281.213814) (xy 96.77527 -281.21102) (xy 96.787208 -281.205686) (xy 96.788478 -281.203908)
			(xy 96.795336 -281.194764) (xy 96.79559 -281.194256) (xy 96.810126 -281.175482) (xy 96.844024 -281.142239)
			(xy 96.882655 -281.114637) (xy 96.925088 -281.093339) (xy 96.970304 -281.078858) (xy 97.017215 -281.071541)
			(xy 97.040954 -281.071066) (xy 97.06495 -281.071509) (xy 97.112353 -281.07901) (xy 97.157998 -281.093834)
			(xy 97.200763 -281.115616) (xy 97.239593 -281.143821) (xy 97.273533 -281.177752) (xy 97.301746 -281.216576)
			(xy 97.323539 -281.259335) (xy 97.338374 -281.304977) (xy 97.345886 -281.352378) (xy 97.346262 -281.376374)
			(xy 97.346261 -281.3764) (xy 97.674859 -281.3764) (xy 97.679035 -281.32601) (xy 97.691448 -281.276995)
			(xy 97.711759 -281.230691) (xy 97.739414 -281.188362) (xy 97.77366 -281.151162) (xy 97.813561 -281.120107)
			(xy 97.85803 -281.096042) (xy 97.905853 -281.079626) (xy 97.955727 -281.071304) (xy 97.981008 -281.070812)
			(xy 98.921062 -281.070812) (xy 98.946341 -281.071354) (xy 98.996209 -281.07967) (xy 99.044029 -281.096081)
			(xy 99.088494 -281.12014) (xy 99.128393 -281.15119) (xy 99.162637 -281.188384) (xy 99.190291 -281.230707)
			(xy 99.210601 -281.277006) (xy 99.223013 -281.326016) (xy 99.227187 -281.376374) (xy 99.555312 -281.376374)
			(xy 99.559272 -281.32732) (xy 99.571049 -281.279536) (xy 99.59034 -281.23426) (xy 99.616643 -281.192664)
			(xy 99.649278 -281.155827) (xy 99.687399 -281.124702) (xy 99.73002 -281.100095) (xy 99.776036 -281.082643)
			(xy 99.824255 -281.072799) (xy 99.87343 -281.070818) (xy 99.922285 -281.07675) (xy 99.969556 -281.090442)
			(xy 100.014018 -281.11154) (xy 100.054521 -281.139496) (xy 100.090014 -281.173588) (xy 100.119579 -281.212932)
			(xy 100.14245 -281.256509) (xy 100.158034 -281.30319) (xy 100.165929 -281.351767) (xy 100.166424 -281.376374)
			(xy 100.166423 -281.3764) (xy 100.495088 -281.3764) (xy 100.499263 -281.326019) (xy 100.511672 -281.277012)
			(xy 100.531978 -281.230715) (xy 100.559627 -281.188392) (xy 100.593865 -281.151197) (xy 100.633757 -281.120144)
			(xy 100.678216 -281.09608) (xy 100.72603 -281.079662) (xy 100.775893 -281.071336) (xy 100.80117 -281.070812)
			(xy 101.741224 -281.070812) (xy 101.766497 -281.071388) (xy 101.816353 -281.079711) (xy 101.864159 -281.096126)
			(xy 101.908611 -281.120186) (xy 101.948498 -281.151233) (xy 101.98273 -281.188422) (xy 102.010375 -281.230738)
			(xy 102.030678 -281.277027) (xy 102.043086 -281.326027) (xy 102.047258 -281.376374) (xy 102.37522 -281.376374)
			(xy 102.37918 -281.32732) (xy 102.390957 -281.279536) (xy 102.410248 -281.23426) (xy 102.436551 -281.192664)
			(xy 102.469186 -281.155827) (xy 102.507307 -281.124702) (xy 102.549928 -281.100095) (xy 102.595944 -281.082643)
			(xy 102.644163 -281.072799) (xy 102.693338 -281.070818) (xy 102.742193 -281.07675) (xy 102.789464 -281.090442)
			(xy 102.833926 -281.11154) (xy 102.874429 -281.139496) (xy 102.909922 -281.173588) (xy 102.939487 -281.212932)
			(xy 102.962358 -281.256509) (xy 102.977942 -281.30319) (xy 102.985837 -281.351767) (xy 102.986332 -281.376374)
			(xy 105.195128 -281.376374) (xy 105.199088 -281.32732) (xy 105.210865 -281.279536) (xy 105.230156 -281.23426)
			(xy 105.256459 -281.192664) (xy 105.289094 -281.155827) (xy 105.327215 -281.124702) (xy 105.369836 -281.100095)
			(xy 105.415852 -281.082643) (xy 105.464071 -281.072799) (xy 105.513246 -281.070818) (xy 105.562101 -281.07675)
			(xy 105.609372 -281.090442) (xy 105.653834 -281.11154) (xy 105.694337 -281.139496) (xy 105.72983 -281.173588)
			(xy 105.759395 -281.212932) (xy 105.782266 -281.256509) (xy 105.79785 -281.30319) (xy 105.805745 -281.351767)
			(xy 105.80624 -281.376374) (xy 108.01529 -281.376374) (xy 108.01925 -281.32732) (xy 108.031027 -281.279536)
			(xy 108.050318 -281.23426) (xy 108.076621 -281.192664) (xy 108.109256 -281.155827) (xy 108.147377 -281.124702)
			(xy 108.189998 -281.100095) (xy 108.236014 -281.082643) (xy 108.284233 -281.072799) (xy 108.333408 -281.070818)
			(xy 108.382263 -281.07675) (xy 108.429534 -281.090442) (xy 108.473996 -281.11154) (xy 108.514499 -281.139496)
			(xy 108.549992 -281.173588) (xy 108.579557 -281.212932) (xy 108.602428 -281.256509) (xy 108.618012 -281.30319)
			(xy 108.625907 -281.351767) (xy 108.626402 -281.376374) (xy 108.955344 -281.376374) (xy 108.959304 -281.32732)
			(xy 108.971081 -281.279536) (xy 108.990372 -281.23426) (xy 109.016675 -281.192664) (xy 109.04931 -281.155827)
			(xy 109.087431 -281.124702) (xy 109.130052 -281.100095) (xy 109.176068 -281.082643) (xy 109.224287 -281.072799)
			(xy 109.273462 -281.070818) (xy 109.322317 -281.07675) (xy 109.369588 -281.090442) (xy 109.41405 -281.11154)
			(xy 109.454553 -281.139496) (xy 109.490046 -281.173588) (xy 109.519611 -281.212932) (xy 109.542482 -281.256509)
			(xy 109.558066 -281.30319) (xy 109.565961 -281.351767) (xy 109.566456 -281.376374) (xy 109.895144 -281.376374)
			(xy 109.899104 -281.32732) (xy 109.910881 -281.279536) (xy 109.930172 -281.23426) (xy 109.956475 -281.192664)
			(xy 109.98911 -281.155827) (xy 110.027231 -281.124702) (xy 110.069852 -281.100095) (xy 110.115868 -281.082643)
			(xy 110.164087 -281.072799) (xy 110.213262 -281.070818) (xy 110.262117 -281.07675) (xy 110.309388 -281.090442)
			(xy 110.35385 -281.11154) (xy 110.394353 -281.139496) (xy 110.429846 -281.173588) (xy 110.459411 -281.212932)
			(xy 110.482282 -281.256509) (xy 110.497866 -281.30319) (xy 110.505761 -281.351767) (xy 110.506256 -281.376374)
			(xy 113.64901 -281.376374) (xy 113.65297 -281.32732) (xy 113.664747 -281.279536) (xy 113.684038 -281.23426)
			(xy 113.710341 -281.192664) (xy 113.742976 -281.155827) (xy 113.781097 -281.124702) (xy 113.823718 -281.100095)
			(xy 113.869734 -281.082643) (xy 113.917953 -281.072799) (xy 113.967128 -281.070818) (xy 114.015983 -281.07675)
			(xy 114.063254 -281.090442) (xy 114.107716 -281.11154) (xy 114.148219 -281.139496) (xy 114.183712 -281.173588)
			(xy 114.213277 -281.212932) (xy 114.236148 -281.256509) (xy 114.251732 -281.30319) (xy 114.259627 -281.351767)
			(xy 114.260122 -281.376374) (xy 114.58881 -281.376374) (xy 114.59277 -281.32732) (xy 114.604547 -281.279536)
			(xy 114.623838 -281.23426) (xy 114.650141 -281.192664) (xy 114.682776 -281.155827) (xy 114.720897 -281.124702)
			(xy 114.763518 -281.100095) (xy 114.809534 -281.082643) (xy 114.857753 -281.072799) (xy 114.906928 -281.070818)
			(xy 114.955783 -281.07675) (xy 115.003054 -281.090442) (xy 115.047516 -281.11154) (xy 115.088019 -281.139496)
			(xy 115.123512 -281.173588) (xy 115.153077 -281.212932) (xy 115.175948 -281.256509) (xy 115.191532 -281.30319)
			(xy 115.199427 -281.351767) (xy 115.199922 -281.376374) (xy 115.528864 -281.376374) (xy 115.532824 -281.32732)
			(xy 115.544601 -281.279536) (xy 115.563892 -281.23426) (xy 115.590195 -281.192664) (xy 115.62283 -281.155827)
			(xy 115.660951 -281.124702) (xy 115.703572 -281.100095) (xy 115.749588 -281.082643) (xy 115.797807 -281.072799)
			(xy 115.846982 -281.070818) (xy 115.895837 -281.07675) (xy 115.943108 -281.090442) (xy 115.98757 -281.11154)
			(xy 116.028073 -281.139496) (xy 116.063566 -281.173588) (xy 116.093131 -281.212932) (xy 116.116002 -281.256509)
			(xy 116.131586 -281.30319) (xy 116.139481 -281.351767) (xy 116.139976 -281.376374) (xy 118.349026 -281.376374)
			(xy 118.352986 -281.32732) (xy 118.364763 -281.279536) (xy 118.384054 -281.23426) (xy 118.410357 -281.192664)
			(xy 118.442992 -281.155827) (xy 118.481113 -281.124702) (xy 118.523734 -281.100095) (xy 118.56975 -281.082643)
			(xy 118.617969 -281.072799) (xy 118.667144 -281.070818) (xy 118.715999 -281.07675) (xy 118.76327 -281.090442)
			(xy 118.807732 -281.11154) (xy 118.848235 -281.139496) (xy 118.883728 -281.173588) (xy 118.913293 -281.212932)
			(xy 118.936164 -281.256509) (xy 118.951748 -281.30319) (xy 118.959643 -281.351767) (xy 118.960138 -281.376374)
			(xy 121.168934 -281.376374) (xy 121.172894 -281.32732) (xy 121.184671 -281.279536) (xy 121.203962 -281.23426)
			(xy 121.230265 -281.192664) (xy 121.2629 -281.155827) (xy 121.301021 -281.124702) (xy 121.343642 -281.100095)
			(xy 121.389658 -281.082643) (xy 121.437877 -281.072799) (xy 121.487052 -281.070818) (xy 121.535907 -281.07675)
			(xy 121.583178 -281.090442) (xy 121.62764 -281.11154) (xy 121.668143 -281.139496) (xy 121.703636 -281.173588)
			(xy 121.733201 -281.212932) (xy 121.756072 -281.256509) (xy 121.771656 -281.30319) (xy 121.779551 -281.351767)
			(xy 121.780046 -281.376374) (xy 121.780045 -281.3764) (xy 122.108688 -281.3764) (xy 122.112863 -281.326017)
			(xy 122.125274 -281.277007) (xy 122.145582 -281.230709) (xy 122.173233 -281.188385) (xy 122.207473 -281.151189)
			(xy 122.247369 -281.120136) (xy 122.291831 -281.096074) (xy 122.339648 -281.079657) (xy 122.389514 -281.071335)
			(xy 122.414792 -281.070812) (xy 123.354846 -281.070812) (xy 123.380118 -281.071389) (xy 123.429971 -281.079715)
			(xy 123.477774 -281.096133) (xy 123.522223 -281.120193) (xy 123.562106 -281.151241) (xy 123.596336 -281.18843)
			(xy 123.623978 -281.230745) (xy 123.64428 -281.277032) (xy 123.656686 -281.326029) (xy 123.660858 -281.376374)
			(xy 123.988842 -281.376374) (xy 123.992802 -281.32732) (xy 124.004579 -281.279536) (xy 124.02387 -281.23426)
			(xy 124.050173 -281.192664) (xy 124.082808 -281.155827) (xy 124.120929 -281.124702) (xy 124.16355 -281.100095)
			(xy 124.209566 -281.082643) (xy 124.257785 -281.072799) (xy 124.30696 -281.070818) (xy 124.355815 -281.07675)
			(xy 124.403086 -281.090442) (xy 124.447548 -281.11154) (xy 124.488051 -281.139496) (xy 124.523544 -281.173588)
			(xy 124.553109 -281.212932) (xy 124.57598 -281.256509) (xy 124.591564 -281.30319) (xy 124.599459 -281.351767)
			(xy 124.599954 -281.376374) (xy 124.599953 -281.3764) (xy 124.928589 -281.3764) (xy 124.932763 -281.326016)
			(xy 124.945174 -281.277006) (xy 124.965483 -281.230707) (xy 124.993135 -281.188382) (xy 125.027376 -281.151186)
			(xy 125.067273 -281.120134) (xy 125.111736 -281.096071) (xy 125.159554 -281.079655) (xy 125.209422 -281.071334)
			(xy 125.2347 -281.070812) (xy 126.174754 -281.070812) (xy 126.200033 -281.071353) (xy 126.249903 -281.079668)
			(xy 126.297723 -281.096079) (xy 126.34219 -281.120137) (xy 126.38209 -281.151187) (xy 126.416335 -281.188381)
			(xy 126.44399 -281.230705) (xy 126.464301 -281.277004) (xy 126.476713 -281.326015) (xy 126.480889 -281.3764)
			(xy 126.476713 -281.426785) (xy 126.464301 -281.475796) (xy 126.44399 -281.522095) (xy 126.416335 -281.564419)
			(xy 126.38209 -281.601613) (xy 126.34219 -281.632663) (xy 126.297723 -281.656721) (xy 126.249903 -281.673132)
			(xy 126.200033 -281.681447) (xy 126.174754 -281.681936) (xy 125.2347 -281.681936) (xy 125.209422 -281.681466)
			(xy 125.159554 -281.673145) (xy 125.111736 -281.656729) (xy 125.067273 -281.632666) (xy 125.027376 -281.601614)
			(xy 124.993135 -281.564418) (xy 124.965483 -281.522093) (xy 124.945174 -281.475794) (xy 124.932763 -281.426784)
			(xy 124.928589 -281.3764) (xy 124.599953 -281.3764) (xy 124.599459 -281.400981) (xy 124.591564 -281.449558)
			(xy 124.57598 -281.496239) (xy 124.553109 -281.539816) (xy 124.523544 -281.57916) (xy 124.488051 -281.613252)
			(xy 124.447548 -281.641208) (xy 124.403086 -281.662306) (xy 124.355815 -281.675998) (xy 124.30696 -281.68193)
			(xy 124.257785 -281.679949) (xy 124.209566 -281.670105) (xy 124.16355 -281.652653) (xy 124.120929 -281.628046)
			(xy 124.082808 -281.596921) (xy 124.050173 -281.560084) (xy 124.02387 -281.518488) (xy 124.004579 -281.473212)
			(xy 123.992802 -281.425428) (xy 123.988842 -281.376374) (xy 123.660858 -281.376374) (xy 123.66086 -281.3764)
			(xy 123.656686 -281.426771) (xy 123.64428 -281.475768) (xy 123.623978 -281.522055) (xy 123.596336 -281.56437)
			(xy 123.562106 -281.601559) (xy 123.522223 -281.632607) (xy 123.477774 -281.656667) (xy 123.429971 -281.673085)
			(xy 123.380118 -281.681411) (xy 123.354846 -281.681936) (xy 122.414792 -281.681936) (xy 122.389514 -281.681465)
			(xy 122.339648 -281.673143) (xy 122.291831 -281.656726) (xy 122.247369 -281.632664) (xy 122.207473 -281.601611)
			(xy 122.173233 -281.564415) (xy 122.145582 -281.522091) (xy 122.125274 -281.475793) (xy 122.112863 -281.426783)
			(xy 122.108688 -281.3764) (xy 121.780045 -281.3764) (xy 121.779551 -281.400981) (xy 121.771656 -281.449558)
			(xy 121.756072 -281.496239) (xy 121.733201 -281.539816) (xy 121.703636 -281.57916) (xy 121.668143 -281.613252)
			(xy 121.62764 -281.641208) (xy 121.583178 -281.662306) (xy 121.535907 -281.675998) (xy 121.487052 -281.68193)
			(xy 121.437877 -281.679949) (xy 121.389658 -281.670105) (xy 121.343642 -281.652653) (xy 121.301021 -281.628046)
			(xy 121.2629 -281.596921) (xy 121.230265 -281.560084) (xy 121.203962 -281.518488) (xy 121.184671 -281.473212)
			(xy 121.172894 -281.425428) (xy 121.168934 -281.376374) (xy 118.960138 -281.376374) (xy 118.959643 -281.400981)
			(xy 118.951748 -281.449558) (xy 118.936164 -281.496239) (xy 118.913293 -281.539816) (xy 118.883728 -281.57916)
			(xy 118.848235 -281.613252) (xy 118.807732 -281.641208) (xy 118.76327 -281.662306) (xy 118.715999 -281.675998)
			(xy 118.667144 -281.68193) (xy 118.617969 -281.679949) (xy 118.56975 -281.670105) (xy 118.523734 -281.652653)
			(xy 118.481113 -281.628046) (xy 118.442992 -281.596921) (xy 118.410357 -281.560084) (xy 118.384054 -281.518488)
			(xy 118.364763 -281.473212) (xy 118.352986 -281.425428) (xy 118.349026 -281.376374) (xy 116.139976 -281.376374)
			(xy 116.139481 -281.400981) (xy 116.131586 -281.449558) (xy 116.116002 -281.496239) (xy 116.093131 -281.539816)
			(xy 116.063566 -281.57916) (xy 116.028073 -281.613252) (xy 115.98757 -281.641208) (xy 115.943108 -281.662306)
			(xy 115.895837 -281.675998) (xy 115.846982 -281.68193) (xy 115.797807 -281.679949) (xy 115.749588 -281.670105)
			(xy 115.703572 -281.652653) (xy 115.660951 -281.628046) (xy 115.62283 -281.596921) (xy 115.590195 -281.560084)
			(xy 115.563892 -281.518488) (xy 115.544601 -281.473212) (xy 115.532824 -281.425428) (xy 115.528864 -281.376374)
			(xy 115.199922 -281.376374) (xy 115.199427 -281.400981) (xy 115.191532 -281.449558) (xy 115.175948 -281.496239)
			(xy 115.153077 -281.539816) (xy 115.123512 -281.57916) (xy 115.088019 -281.613252) (xy 115.047516 -281.641208)
			(xy 115.003054 -281.662306) (xy 114.955783 -281.675998) (xy 114.906928 -281.68193) (xy 114.857753 -281.679949)
			(xy 114.809534 -281.670105) (xy 114.763518 -281.652653) (xy 114.720897 -281.628046) (xy 114.682776 -281.596921)
			(xy 114.650141 -281.560084) (xy 114.623838 -281.518488) (xy 114.604547 -281.473212) (xy 114.59277 -281.425428)
			(xy 114.58881 -281.376374) (xy 114.260122 -281.376374) (xy 114.259627 -281.400981) (xy 114.251732 -281.449558)
			(xy 114.236148 -281.496239) (xy 114.213277 -281.539816) (xy 114.183712 -281.57916) (xy 114.148219 -281.613252)
			(xy 114.107716 -281.641208) (xy 114.063254 -281.662306) (xy 114.015983 -281.675998) (xy 113.967128 -281.68193)
			(xy 113.917953 -281.679949) (xy 113.869734 -281.670105) (xy 113.823718 -281.652653) (xy 113.781097 -281.628046)
			(xy 113.742976 -281.596921) (xy 113.710341 -281.560084) (xy 113.684038 -281.518488) (xy 113.664747 -281.473212)
			(xy 113.65297 -281.425428) (xy 113.64901 -281.376374) (xy 110.506256 -281.376374) (xy 110.505761 -281.400981)
			(xy 110.497866 -281.449558) (xy 110.482282 -281.496239) (xy 110.459411 -281.539816) (xy 110.429846 -281.57916)
			(xy 110.394353 -281.613252) (xy 110.35385 -281.641208) (xy 110.309388 -281.662306) (xy 110.262117 -281.675998)
			(xy 110.213262 -281.68193) (xy 110.164087 -281.679949) (xy 110.115868 -281.670105) (xy 110.069852 -281.652653)
			(xy 110.027231 -281.628046) (xy 109.98911 -281.596921) (xy 109.956475 -281.560084) (xy 109.930172 -281.518488)
			(xy 109.910881 -281.473212) (xy 109.899104 -281.425428) (xy 109.895144 -281.376374) (xy 109.566456 -281.376374)
			(xy 109.565961 -281.400981) (xy 109.558066 -281.449558) (xy 109.542482 -281.496239) (xy 109.519611 -281.539816)
			(xy 109.490046 -281.57916) (xy 109.454553 -281.613252) (xy 109.41405 -281.641208) (xy 109.369588 -281.662306)
			(xy 109.322317 -281.675998) (xy 109.273462 -281.68193) (xy 109.224287 -281.679949) (xy 109.176068 -281.670105)
			(xy 109.130052 -281.652653) (xy 109.087431 -281.628046) (xy 109.04931 -281.596921) (xy 109.016675 -281.560084)
			(xy 108.990372 -281.518488) (xy 108.971081 -281.473212) (xy 108.959304 -281.425428) (xy 108.955344 -281.376374)
			(xy 108.626402 -281.376374) (xy 108.625907 -281.400981) (xy 108.618012 -281.449558) (xy 108.602428 -281.496239)
			(xy 108.579557 -281.539816) (xy 108.549992 -281.57916) (xy 108.514499 -281.613252) (xy 108.473996 -281.641208)
			(xy 108.429534 -281.662306) (xy 108.382263 -281.675998) (xy 108.333408 -281.68193) (xy 108.284233 -281.679949)
			(xy 108.236014 -281.670105) (xy 108.189998 -281.652653) (xy 108.147377 -281.628046) (xy 108.109256 -281.596921)
			(xy 108.076621 -281.560084) (xy 108.050318 -281.518488) (xy 108.031027 -281.473212) (xy 108.01925 -281.425428)
			(xy 108.01529 -281.376374) (xy 105.80624 -281.376374) (xy 105.805745 -281.400981) (xy 105.79785 -281.449558)
			(xy 105.782266 -281.496239) (xy 105.759395 -281.539816) (xy 105.72983 -281.57916) (xy 105.694337 -281.613252)
			(xy 105.653834 -281.641208) (xy 105.609372 -281.662306) (xy 105.562101 -281.675998) (xy 105.513246 -281.68193)
			(xy 105.464071 -281.679949) (xy 105.415852 -281.670105) (xy 105.369836 -281.652653) (xy 105.327215 -281.628046)
			(xy 105.289094 -281.596921) (xy 105.256459 -281.560084) (xy 105.230156 -281.518488) (xy 105.210865 -281.473212)
			(xy 105.199088 -281.425428) (xy 105.195128 -281.376374) (xy 102.986332 -281.376374) (xy 102.985837 -281.400981)
			(xy 102.977942 -281.449558) (xy 102.962358 -281.496239) (xy 102.939487 -281.539816) (xy 102.909922 -281.57916)
			(xy 102.874429 -281.613252) (xy 102.833926 -281.641208) (xy 102.789464 -281.662306) (xy 102.742193 -281.675998)
			(xy 102.693338 -281.68193) (xy 102.644163 -281.679949) (xy 102.595944 -281.670105) (xy 102.549928 -281.652653)
			(xy 102.507307 -281.628046) (xy 102.469186 -281.596921) (xy 102.436551 -281.560084) (xy 102.410248 -281.518488)
			(xy 102.390957 -281.473212) (xy 102.37918 -281.425428) (xy 102.37522 -281.376374) (xy 102.047258 -281.376374)
			(xy 102.04726 -281.3764) (xy 102.043086 -281.426773) (xy 102.030678 -281.475773) (xy 102.010375 -281.522062)
			(xy 101.98273 -281.564378) (xy 101.948498 -281.601567) (xy 101.908611 -281.632614) (xy 101.864159 -281.656674)
			(xy 101.816353 -281.673089) (xy 101.766497 -281.681412) (xy 101.741224 -281.681936) (xy 100.80117 -281.681936)
			(xy 100.775893 -281.681464) (xy 100.72603 -281.673138) (xy 100.678216 -281.65672) (xy 100.633757 -281.632656)
			(xy 100.593865 -281.601603) (xy 100.559627 -281.564408) (xy 100.531978 -281.522085) (xy 100.511672 -281.475788)
			(xy 100.499263 -281.426781) (xy 100.495088 -281.3764) (xy 100.166423 -281.3764) (xy 100.165929 -281.400981)
			(xy 100.158034 -281.449558) (xy 100.14245 -281.496239) (xy 100.119579 -281.539816) (xy 100.090014 -281.57916)
			(xy 100.054521 -281.613252) (xy 100.014018 -281.641208) (xy 99.969556 -281.662306) (xy 99.922285 -281.675998)
			(xy 99.87343 -281.68193) (xy 99.824255 -281.679949) (xy 99.776036 -281.670105) (xy 99.73002 -281.652653)
			(xy 99.687399 -281.628046) (xy 99.649278 -281.596921) (xy 99.616643 -281.560084) (xy 99.59034 -281.518488)
			(xy 99.571049 -281.473212) (xy 99.559272 -281.425428) (xy 99.555312 -281.376374) (xy 99.227187 -281.376374)
			(xy 99.227189 -281.3764) (xy 99.223013 -281.426784) (xy 99.210601 -281.475794) (xy 99.190291 -281.522093)
			(xy 99.162637 -281.564416) (xy 99.128393 -281.60161) (xy 99.088494 -281.63266) (xy 99.044029 -281.656719)
			(xy 98.996209 -281.67313) (xy 98.946341 -281.681446) (xy 98.921062 -281.681936) (xy 97.981008 -281.681936)
			(xy 97.955727 -281.681496) (xy 97.905853 -281.673174) (xy 97.85803 -281.656758) (xy 97.813561 -281.632693)
			(xy 97.77366 -281.601638) (xy 97.739414 -281.564438) (xy 97.711759 -281.522109) (xy 97.691448 -281.475805)
			(xy 97.679035 -281.42679) (xy 97.674859 -281.3764) (xy 97.346261 -281.3764) (xy 97.345792 -281.40061)
			(xy 97.338125 -281.448473) (xy 97.322995 -281.494525) (xy 97.300781 -281.537609) (xy 97.272043 -281.576644)
			(xy 97.2375 -281.61065) (xy 97.19802 -281.638775) (xy 97.154593 -281.660311) (xy 97.108311 -281.674718)
			(xy 97.084388 -281.678634) (xy 97.071942 -281.680412) (xy 97.040954 -281.681936) (xy 97.017459 -281.681503)
			(xy 96.971021 -281.674308) (xy 96.926231 -281.660095) (xy 96.884142 -281.639199) (xy 96.845745 -281.61211)
			(xy 96.811943 -281.579467) (xy 96.797368 -281.561032) (xy 96.795336 -281.558238) (xy 96.795082 -281.557984)
			(xy 96.790946 -281.55261) (xy 96.780391 -281.544103) (xy 96.774254 -281.54122) (xy 96.768412 -281.538934)
			(xy 96.755204 -281.537156) (xy 96.661986 -281.549348) (xy 96.655309 -281.550394) (xy 96.642819 -281.555541)
			(xy 96.637348 -281.559508) (xy 96.63176 -281.563826) (xy 96.62414 -281.57424) (xy 96.621346 -281.581352)
			(xy 96.613469 -281.600923) (xy 96.595162 -281.638938) (xy 96.58477 -281.657298) (xy 96.539812 -281.734768)
			(xy 96.534217 -281.745837) (xy 96.533431 -281.770598) (xy 96.538288 -281.782012) (xy 96.552766 -281.811476)
			(xy 96.576388 -281.858974) (xy 96.57715 -281.860244) (xy 96.579847 -281.864486) (xy 96.586633 -281.871902)
			(xy 96.590612 -281.874976) (xy 96.600518 -281.882088) (xy 96.613218 -281.883866) (xy 96.637223 -281.887713)
			(xy 96.683685 -281.902012) (xy 96.727298 -281.923487) (xy 96.766962 -281.951595) (xy 96.801675 -281.985628)
			(xy 96.830563 -282.024727) (xy 96.852896 -282.067906) (xy 96.868112 -282.114077) (xy 96.875827 -282.162074)
			(xy 96.876362 -282.18638) (xy 97.205304 -282.18638) (xy 97.209264 -282.137326) (xy 97.221041 -282.089542)
			(xy 97.240332 -282.044266) (xy 97.266635 -282.00267) (xy 97.29927 -281.965833) (xy 97.337391 -281.934708)
			(xy 97.380012 -281.910101) (xy 97.426028 -281.892649) (xy 97.474247 -281.882805) (xy 97.523422 -281.880824)
			(xy 97.572277 -281.886756) (xy 97.619548 -281.900448) (xy 97.66401 -281.921546) (xy 97.704513 -281.949502)
			(xy 97.740006 -281.983594) (xy 97.769571 -282.022938) (xy 97.792442 -282.066515) (xy 97.808026 -282.113196)
			(xy 97.815921 -282.161773) (xy 97.816416 -282.18638) (xy 98.145358 -282.18638) (xy 98.149318 -282.137326)
			(xy 98.161095 -282.089542) (xy 98.180386 -282.044266) (xy 98.206689 -282.00267) (xy 98.239324 -281.965833)
			(xy 98.277445 -281.934708) (xy 98.320066 -281.910101) (xy 98.366082 -281.892649) (xy 98.414301 -281.882805)
			(xy 98.463476 -281.880824) (xy 98.512331 -281.886756) (xy 98.559602 -281.900448) (xy 98.604064 -281.921546)
			(xy 98.644567 -281.949502) (xy 98.68006 -281.983594) (xy 98.709625 -282.022938) (xy 98.732496 -282.066515)
			(xy 98.74808 -282.113196) (xy 98.755975 -282.161773) (xy 98.75647 -282.18638) (xy 99.085158 -282.18638)
			(xy 99.089118 -282.137326) (xy 99.100895 -282.089542) (xy 99.120186 -282.044266) (xy 99.146489 -282.00267)
			(xy 99.179124 -281.965833) (xy 99.217245 -281.934708) (xy 99.259866 -281.910101) (xy 99.305882 -281.892649)
			(xy 99.354101 -281.882805) (xy 99.403276 -281.880824) (xy 99.452131 -281.886756) (xy 99.499402 -281.900448)
			(xy 99.543864 -281.921546) (xy 99.584367 -281.949502) (xy 99.61986 -281.983594) (xy 99.649425 -282.022938)
			(xy 99.672296 -282.066515) (xy 99.68788 -282.113196) (xy 99.695775 -282.161773) (xy 99.69627 -282.18638)
			(xy 100.025212 -282.18638) (xy 100.029172 -282.137326) (xy 100.040949 -282.089542) (xy 100.06024 -282.044266)
			(xy 100.086543 -282.00267) (xy 100.119178 -281.965833) (xy 100.157299 -281.934708) (xy 100.19992 -281.910101)
			(xy 100.245936 -281.892649) (xy 100.294155 -281.882805) (xy 100.34333 -281.880824) (xy 100.392185 -281.886756)
			(xy 100.439456 -281.900448) (xy 100.483918 -281.921546) (xy 100.524421 -281.949502) (xy 100.559914 -281.983594)
			(xy 100.589479 -282.022938) (xy 100.61235 -282.066515) (xy 100.627934 -282.113196) (xy 100.635829 -282.161773)
			(xy 100.636324 -282.18638) (xy 100.965266 -282.18638) (xy 100.969226 -282.137326) (xy 100.981003 -282.089542)
			(xy 101.000294 -282.044266) (xy 101.026597 -282.00267) (xy 101.059232 -281.965833) (xy 101.097353 -281.934708)
			(xy 101.139974 -281.910101) (xy 101.18599 -281.892649) (xy 101.234209 -281.882805) (xy 101.283384 -281.880824)
			(xy 101.332239 -281.886756) (xy 101.37951 -281.900448) (xy 101.423972 -281.921546) (xy 101.464475 -281.949502)
			(xy 101.499968 -281.983594) (xy 101.529533 -282.022938) (xy 101.552404 -282.066515) (xy 101.567988 -282.113196)
			(xy 101.575883 -282.161773) (xy 101.576378 -282.18638) (xy 101.90532 -282.18638) (xy 101.90928 -282.137326)
			(xy 101.921057 -282.089542) (xy 101.940348 -282.044266) (xy 101.966651 -282.00267) (xy 101.999286 -281.965833)
			(xy 102.037407 -281.934708) (xy 102.080028 -281.910101) (xy 102.126044 -281.892649) (xy 102.174263 -281.882805)
			(xy 102.223438 -281.880824) (xy 102.272293 -281.886756) (xy 102.319564 -281.900448) (xy 102.364026 -281.921546)
			(xy 102.404529 -281.949502) (xy 102.440022 -281.983594) (xy 102.469587 -282.022938) (xy 102.492458 -282.066515)
			(xy 102.508042 -282.113196) (xy 102.515937 -282.161773) (xy 102.516432 -282.18638) (xy 102.845374 -282.18638)
			(xy 102.849334 -282.137326) (xy 102.861111 -282.089542) (xy 102.880402 -282.044266) (xy 102.906705 -282.00267)
			(xy 102.93934 -281.965833) (xy 102.977461 -281.934708) (xy 103.020082 -281.910101) (xy 103.066098 -281.892649)
			(xy 103.114317 -281.882805) (xy 103.163492 -281.880824) (xy 103.212347 -281.886756) (xy 103.259618 -281.900448)
			(xy 103.30408 -281.921546) (xy 103.344583 -281.949502) (xy 103.380076 -281.983594) (xy 103.409641 -282.022938)
			(xy 103.432512 -282.066515) (xy 103.448096 -282.113196) (xy 103.455991 -282.161773) (xy 103.456486 -282.18638)
			(xy 103.785174 -282.18638) (xy 103.789134 -282.137326) (xy 103.800911 -282.089542) (xy 103.820202 -282.044266)
			(xy 103.846505 -282.00267) (xy 103.87914 -281.965833) (xy 103.917261 -281.934708) (xy 103.959882 -281.910101)
			(xy 104.005898 -281.892649) (xy 104.054117 -281.882805) (xy 104.103292 -281.880824) (xy 104.152147 -281.886756)
			(xy 104.199418 -281.900448) (xy 104.24388 -281.921546) (xy 104.284383 -281.949502) (xy 104.319876 -281.983594)
			(xy 104.349441 -282.022938) (xy 104.372312 -282.066515) (xy 104.387896 -282.113196) (xy 104.395791 -282.161773)
			(xy 104.396286 -282.18638) (xy 104.725228 -282.18638) (xy 104.729188 -282.137326) (xy 104.740965 -282.089542)
			(xy 104.760256 -282.044266) (xy 104.786559 -282.00267) (xy 104.819194 -281.965833) (xy 104.857315 -281.934708)
			(xy 104.899936 -281.910101) (xy 104.945952 -281.892649) (xy 104.994171 -281.882805) (xy 105.043346 -281.880824)
			(xy 105.092201 -281.886756) (xy 105.139472 -281.900448) (xy 105.183934 -281.921546) (xy 105.224437 -281.949502)
			(xy 105.25993 -281.983594) (xy 105.289495 -282.022938) (xy 105.312366 -282.066515) (xy 105.32795 -282.113196)
			(xy 105.335845 -282.161773) (xy 105.33634 -282.18638) (xy 105.665282 -282.18638) (xy 105.669242 -282.137326)
			(xy 105.681019 -282.089542) (xy 105.70031 -282.044266) (xy 105.726613 -282.00267) (xy 105.759248 -281.965833)
			(xy 105.797369 -281.934708) (xy 105.83999 -281.910101) (xy 105.886006 -281.892649) (xy 105.934225 -281.882805)
			(xy 105.9834 -281.880824) (xy 106.032255 -281.886756) (xy 106.079526 -281.900448) (xy 106.123988 -281.921546)
			(xy 106.164491 -281.949502) (xy 106.199984 -281.983594) (xy 106.229549 -282.022938) (xy 106.25242 -282.066515)
			(xy 106.268004 -282.113196) (xy 106.275899 -282.161773) (xy 106.276394 -282.18638) (xy 106.605336 -282.18638)
			(xy 106.609296 -282.137326) (xy 106.621073 -282.089542) (xy 106.640364 -282.044266) (xy 106.666667 -282.00267)
			(xy 106.699302 -281.965833) (xy 106.737423 -281.934708) (xy 106.780044 -281.910101) (xy 106.82606 -281.892649)
			(xy 106.874279 -281.882805) (xy 106.923454 -281.880824) (xy 106.972309 -281.886756) (xy 107.01958 -281.900448)
			(xy 107.064042 -281.921546) (xy 107.104545 -281.949502) (xy 107.140038 -281.983594) (xy 107.169603 -282.022938)
			(xy 107.192474 -282.066515) (xy 107.208058 -282.113196) (xy 107.215953 -282.161773) (xy 107.216448 -282.18638)
			(xy 107.545136 -282.18638) (xy 107.549096 -282.137326) (xy 107.560873 -282.089542) (xy 107.580164 -282.044266)
			(xy 107.606467 -282.00267) (xy 107.639102 -281.965833) (xy 107.677223 -281.934708) (xy 107.719844 -281.910101)
			(xy 107.76586 -281.892649) (xy 107.814079 -281.882805) (xy 107.863254 -281.880824) (xy 107.912109 -281.886756)
			(xy 107.95938 -281.900448) (xy 108.003842 -281.921546) (xy 108.044345 -281.949502) (xy 108.079838 -281.983594)
			(xy 108.109403 -282.022938) (xy 108.132274 -282.066515) (xy 108.147858 -282.113196) (xy 108.155753 -282.161773)
			(xy 108.156248 -282.18638) (xy 108.156248 -282.1864) (xy 108.485149 -282.1864) (xy 108.48932 -282.136059)
			(xy 108.50172 -282.087092) (xy 108.522011 -282.040833) (xy 108.549639 -281.998544) (xy 108.58385 -281.96138)
			(xy 108.623712 -281.930354) (xy 108.668137 -281.906312) (xy 108.715913 -281.889909) (xy 108.765737 -281.881594)
			(xy 108.790994 -281.881072) (xy 109.731048 -281.881072) (xy 109.756299 -281.881637) (xy 109.806111 -281.889957)
			(xy 109.853875 -281.906361) (xy 109.898288 -281.930402) (xy 109.938139 -281.961425) (xy 109.97234 -281.998583)
			(xy 109.99996 -282.040863) (xy 110.020245 -282.087113) (xy 110.032641 -282.13607) (xy 110.036809 -282.18638)
			(xy 110.365298 -282.18638) (xy 110.369258 -282.137326) (xy 110.381035 -282.089542) (xy 110.400326 -282.044266)
			(xy 110.426629 -282.00267) (xy 110.459264 -281.965833) (xy 110.497385 -281.934708) (xy 110.540006 -281.910101)
			(xy 110.586022 -281.892649) (xy 110.634241 -281.882805) (xy 110.683416 -281.880824) (xy 110.732271 -281.886756)
			(xy 110.779542 -281.900448) (xy 110.824004 -281.921546) (xy 110.864507 -281.949502) (xy 110.9 -281.983594)
			(xy 110.929565 -282.022938) (xy 110.952436 -282.066515) (xy 110.96802 -282.113196) (xy 110.975915 -282.161773)
			(xy 110.97641 -282.18638) (xy 113.178856 -282.18638) (xy 113.182816 -282.137326) (xy 113.194593 -282.089542)
			(xy 113.213884 -282.044266) (xy 113.240187 -282.00267) (xy 113.272822 -281.965833) (xy 113.310943 -281.934708)
			(xy 113.353564 -281.910101) (xy 113.39958 -281.892649) (xy 113.447799 -281.882805) (xy 113.496974 -281.880824)
			(xy 113.545829 -281.886756) (xy 113.5931 -281.900448) (xy 113.637562 -281.921546) (xy 113.678065 -281.949502)
			(xy 113.713558 -281.983594) (xy 113.743123 -282.022938) (xy 113.765994 -282.066515) (xy 113.781578 -282.113196)
			(xy 113.789473 -282.161773) (xy 113.789968 -282.18638) (xy 113.789968 -282.1864) (xy 114.11882 -282.1864)
			(xy 114.122992 -282.136052) (xy 114.135394 -282.087078) (xy 114.155689 -282.040813) (xy 114.183321 -281.99852)
			(xy 114.217539 -281.961352) (xy 114.257407 -281.930323) (xy 114.301839 -281.906279) (xy 114.349622 -281.889877)
			(xy 114.399454 -281.881564) (xy 114.424714 -281.881072) (xy 115.364768 -281.881072) (xy 115.390026 -281.881602)
			(xy 115.439853 -281.889912) (xy 115.487633 -281.90631) (xy 115.532062 -281.93035) (xy 115.571927 -281.961375)
			(xy 115.606142 -281.998539) (xy 115.633773 -282.040827) (xy 115.654067 -282.087088) (xy 115.666468 -282.136057)
			(xy 115.670638 -282.18638) (xy 115.999018 -282.18638) (xy 116.002978 -282.137326) (xy 116.014755 -282.089542)
			(xy 116.034046 -282.044266) (xy 116.060349 -282.00267) (xy 116.092984 -281.965833) (xy 116.131105 -281.934708)
			(xy 116.173726 -281.910101) (xy 116.219742 -281.892649) (xy 116.267961 -281.882805) (xy 116.317136 -281.880824)
			(xy 116.365991 -281.886756) (xy 116.413262 -281.900448) (xy 116.457724 -281.921546) (xy 116.498227 -281.949502)
			(xy 116.53372 -281.983594) (xy 116.563285 -282.022938) (xy 116.586156 -282.066515) (xy 116.60174 -282.113196)
			(xy 116.609635 -282.161773) (xy 116.61013 -282.18638) (xy 116.938818 -282.18638) (xy 116.942778 -282.137326)
			(xy 116.954555 -282.089542) (xy 116.973846 -282.044266) (xy 117.000149 -282.00267) (xy 117.032784 -281.965833)
			(xy 117.070905 -281.934708) (xy 117.113526 -281.910101) (xy 117.159542 -281.892649) (xy 117.207761 -281.882805)
			(xy 117.256936 -281.880824) (xy 117.305791 -281.886756) (xy 117.353062 -281.900448) (xy 117.397524 -281.921546)
			(xy 117.438027 -281.949502) (xy 117.47352 -281.983594) (xy 117.503085 -282.022938) (xy 117.525956 -282.066515)
			(xy 117.54154 -282.113196) (xy 117.549435 -282.161773) (xy 117.54993 -282.18638) (xy 117.878872 -282.18638)
			(xy 117.882832 -282.137326) (xy 117.894609 -282.089542) (xy 117.9139 -282.044266) (xy 117.940203 -282.00267)
			(xy 117.972838 -281.965833) (xy 118.010959 -281.934708) (xy 118.05358 -281.910101) (xy 118.099596 -281.892649)
			(xy 118.147815 -281.882805) (xy 118.19699 -281.880824) (xy 118.245845 -281.886756) (xy 118.293116 -281.900448)
			(xy 118.337578 -281.921546) (xy 118.378081 -281.949502) (xy 118.413574 -281.983594) (xy 118.443139 -282.022938)
			(xy 118.46601 -282.066515) (xy 118.481594 -282.113196) (xy 118.489489 -282.161773) (xy 118.489984 -282.18638)
			(xy 118.818926 -282.18638) (xy 118.822886 -282.137326) (xy 118.834663 -282.089542) (xy 118.853954 -282.044266)
			(xy 118.880257 -282.00267) (xy 118.912892 -281.965833) (xy 118.951013 -281.934708) (xy 118.993634 -281.910101)
			(xy 119.03965 -281.892649) (xy 119.087869 -281.882805) (xy 119.137044 -281.880824) (xy 119.185899 -281.886756)
			(xy 119.23317 -281.900448) (xy 119.277632 -281.921546) (xy 119.318135 -281.949502) (xy 119.353628 -281.983594)
			(xy 119.383193 -282.022938) (xy 119.406064 -282.066515) (xy 119.421648 -282.113196) (xy 119.429543 -282.161773)
			(xy 119.430038 -282.18638) (xy 119.75898 -282.18638) (xy 119.76294 -282.137326) (xy 119.774717 -282.089542)
			(xy 119.794008 -282.044266) (xy 119.820311 -282.00267) (xy 119.852946 -281.965833) (xy 119.891067 -281.934708)
			(xy 119.933688 -281.910101) (xy 119.979704 -281.892649) (xy 120.027923 -281.882805) (xy 120.077098 -281.880824)
			(xy 120.125953 -281.886756) (xy 120.173224 -281.900448) (xy 120.217686 -281.921546) (xy 120.258189 -281.949502)
			(xy 120.293682 -281.983594) (xy 120.323247 -282.022938) (xy 120.346118 -282.066515) (xy 120.361702 -282.113196)
			(xy 120.369597 -282.161773) (xy 120.370092 -282.18638) (xy 120.699034 -282.18638) (xy 120.702994 -282.137326)
			(xy 120.714771 -282.089542) (xy 120.734062 -282.044266) (xy 120.760365 -282.00267) (xy 120.793 -281.965833)
			(xy 120.831121 -281.934708) (xy 120.873742 -281.910101) (xy 120.919758 -281.892649) (xy 120.967977 -281.882805)
			(xy 121.017152 -281.880824) (xy 121.066007 -281.886756) (xy 121.113278 -281.900448) (xy 121.15774 -281.921546)
			(xy 121.198243 -281.949502) (xy 121.233736 -281.983594) (xy 121.263301 -282.022938) (xy 121.286172 -282.066515)
			(xy 121.301756 -282.113196) (xy 121.309651 -282.161773) (xy 121.310146 -282.18638) (xy 121.638834 -282.18638)
			(xy 121.642794 -282.137326) (xy 121.654571 -282.089542) (xy 121.673862 -282.044266) (xy 121.700165 -282.00267)
			(xy 121.7328 -281.965833) (xy 121.770921 -281.934708) (xy 121.813542 -281.910101) (xy 121.859558 -281.892649)
			(xy 121.907777 -281.882805) (xy 121.956952 -281.880824) (xy 122.005807 -281.886756) (xy 122.053078 -281.900448)
			(xy 122.09754 -281.921546) (xy 122.138043 -281.949502) (xy 122.173536 -281.983594) (xy 122.203101 -282.022938)
			(xy 122.225972 -282.066515) (xy 122.241556 -282.113196) (xy 122.249451 -282.161773) (xy 122.249946 -282.18638)
			(xy 122.578888 -282.18638) (xy 122.582848 -282.137326) (xy 122.594625 -282.089542) (xy 122.613916 -282.044266)
			(xy 122.640219 -282.00267) (xy 122.672854 -281.965833) (xy 122.710975 -281.934708) (xy 122.753596 -281.910101)
			(xy 122.799612 -281.892649) (xy 122.847831 -281.882805) (xy 122.897006 -281.880824) (xy 122.945861 -281.886756)
			(xy 122.993132 -281.900448) (xy 123.037594 -281.921546) (xy 123.078097 -281.949502) (xy 123.11359 -281.983594)
			(xy 123.143155 -282.022938) (xy 123.166026 -282.066515) (xy 123.18161 -282.113196) (xy 123.189505 -282.161773)
			(xy 123.19 -282.18638) (xy 123.518942 -282.18638) (xy 123.522902 -282.137326) (xy 123.534679 -282.089542)
			(xy 123.55397 -282.044266) (xy 123.580273 -282.00267) (xy 123.612908 -281.965833) (xy 123.651029 -281.934708)
			(xy 123.69365 -281.910101) (xy 123.739666 -281.892649) (xy 123.787885 -281.882805) (xy 123.83706 -281.880824)
			(xy 123.885915 -281.886756) (xy 123.933186 -281.900448) (xy 123.977648 -281.921546) (xy 124.018151 -281.949502)
			(xy 124.053644 -281.983594) (xy 124.083209 -282.022938) (xy 124.10608 -282.066515) (xy 124.121664 -282.113196)
			(xy 124.129559 -282.161773) (xy 124.130054 -282.18638) (xy 124.458996 -282.18638) (xy 124.462956 -282.137326)
			(xy 124.474733 -282.089542) (xy 124.494024 -282.044266) (xy 124.520327 -282.00267) (xy 124.552962 -281.965833)
			(xy 124.591083 -281.934708) (xy 124.633704 -281.910101) (xy 124.67972 -281.892649) (xy 124.727939 -281.882805)
			(xy 124.777114 -281.880824) (xy 124.825969 -281.886756) (xy 124.87324 -281.900448) (xy 124.917702 -281.921546)
			(xy 124.958205 -281.949502) (xy 124.993698 -281.983594) (xy 125.023263 -282.022938) (xy 125.046134 -282.066515)
			(xy 125.061718 -282.113196) (xy 125.069613 -282.161773) (xy 125.070108 -282.18638) (xy 125.39905 -282.18638)
			(xy 125.40301 -282.137326) (xy 125.414787 -282.089542) (xy 125.434078 -282.044266) (xy 125.460381 -282.00267)
			(xy 125.493016 -281.965833) (xy 125.531137 -281.934708) (xy 125.573758 -281.910101) (xy 125.619774 -281.892649)
			(xy 125.667993 -281.882805) (xy 125.717168 -281.880824) (xy 125.766023 -281.886756) (xy 125.813294 -281.900448)
			(xy 125.857756 -281.921546) (xy 125.898259 -281.949502) (xy 125.933752 -281.983594) (xy 125.963317 -282.022938)
			(xy 125.986188 -282.066515) (xy 126.001772 -282.113196) (xy 126.009667 -282.161773) (xy 126.010162 -282.18638)
			(xy 126.33885 -282.18638) (xy 126.34281 -282.137326) (xy 126.354587 -282.089542) (xy 126.373878 -282.044266)
			(xy 126.400181 -282.00267) (xy 126.432816 -281.965833) (xy 126.470937 -281.934708) (xy 126.513558 -281.910101)
			(xy 126.559574 -281.892649) (xy 126.607793 -281.882805) (xy 126.656968 -281.880824) (xy 126.705823 -281.886756)
			(xy 126.753094 -281.900448) (xy 126.797556 -281.921546) (xy 126.838059 -281.949502) (xy 126.873552 -281.983594)
			(xy 126.903117 -282.022938) (xy 126.925988 -282.066515) (xy 126.941572 -282.113196) (xy 126.949467 -282.161773)
			(xy 126.949962 -282.18638) (xy 126.949467 -282.210987) (xy 126.941572 -282.259564) (xy 126.925988 -282.306245)
			(xy 126.903117 -282.349822) (xy 126.873552 -282.389166) (xy 126.838059 -282.423258) (xy 126.797556 -282.451214)
			(xy 126.753094 -282.472312) (xy 126.705823 -282.486004) (xy 126.656968 -282.491936) (xy 126.607793 -282.489955)
			(xy 126.559574 -282.480111) (xy 126.513558 -282.462659) (xy 126.470937 -282.438052) (xy 126.432816 -282.406927)
			(xy 126.400181 -282.37009) (xy 126.373878 -282.328494) (xy 126.354587 -282.283218) (xy 126.34281 -282.235434)
			(xy 126.33885 -282.18638) (xy 126.010162 -282.18638) (xy 126.009667 -282.210987) (xy 126.001772 -282.259564)
			(xy 125.986188 -282.306245) (xy 125.963317 -282.349822) (xy 125.933752 -282.389166) (xy 125.898259 -282.423258)
			(xy 125.857756 -282.451214) (xy 125.813294 -282.472312) (xy 125.766023 -282.486004) (xy 125.717168 -282.491936)
			(xy 125.667993 -282.489955) (xy 125.619774 -282.480111) (xy 125.573758 -282.462659) (xy 125.531137 -282.438052)
			(xy 125.493016 -282.406927) (xy 125.460381 -282.37009) (xy 125.434078 -282.328494) (xy 125.414787 -282.283218)
			(xy 125.40301 -282.235434) (xy 125.39905 -282.18638) (xy 125.070108 -282.18638) (xy 125.069613 -282.210987)
			(xy 125.061718 -282.259564) (xy 125.046134 -282.306245) (xy 125.023263 -282.349822) (xy 124.993698 -282.389166)
			(xy 124.958205 -282.423258) (xy 124.917702 -282.451214) (xy 124.87324 -282.472312) (xy 124.825969 -282.486004)
			(xy 124.777114 -282.491936) (xy 124.727939 -282.489955) (xy 124.67972 -282.480111) (xy 124.633704 -282.462659)
			(xy 124.591083 -282.438052) (xy 124.552962 -282.406927) (xy 124.520327 -282.37009) (xy 124.494024 -282.328494)
			(xy 124.474733 -282.283218) (xy 124.462956 -282.235434) (xy 124.458996 -282.18638) (xy 124.130054 -282.18638)
			(xy 124.129559 -282.210987) (xy 124.121664 -282.259564) (xy 124.10608 -282.306245) (xy 124.083209 -282.349822)
			(xy 124.053644 -282.389166) (xy 124.018151 -282.423258) (xy 123.977648 -282.451214) (xy 123.933186 -282.472312)
			(xy 123.885915 -282.486004) (xy 123.83706 -282.491936) (xy 123.787885 -282.489955) (xy 123.739666 -282.480111)
			(xy 123.69365 -282.462659) (xy 123.651029 -282.438052) (xy 123.612908 -282.406927) (xy 123.580273 -282.37009)
			(xy 123.55397 -282.328494) (xy 123.534679 -282.283218) (xy 123.522902 -282.235434) (xy 123.518942 -282.18638)
			(xy 123.19 -282.18638) (xy 123.189505 -282.210987) (xy 123.18161 -282.259564) (xy 123.166026 -282.306245)
			(xy 123.143155 -282.349822) (xy 123.11359 -282.389166) (xy 123.078097 -282.423258) (xy 123.037594 -282.451214)
			(xy 122.993132 -282.472312) (xy 122.945861 -282.486004) (xy 122.897006 -282.491936) (xy 122.847831 -282.489955)
			(xy 122.799612 -282.480111) (xy 122.753596 -282.462659) (xy 122.710975 -282.438052) (xy 122.672854 -282.406927)
			(xy 122.640219 -282.37009) (xy 122.613916 -282.328494) (xy 122.594625 -282.283218) (xy 122.582848 -282.235434)
			(xy 122.578888 -282.18638) (xy 122.249946 -282.18638) (xy 122.249451 -282.210987) (xy 122.241556 -282.259564)
			(xy 122.225972 -282.306245) (xy 122.203101 -282.349822) (xy 122.173536 -282.389166) (xy 122.138043 -282.423258)
			(xy 122.09754 -282.451214) (xy 122.053078 -282.472312) (xy 122.005807 -282.486004) (xy 121.956952 -282.491936)
			(xy 121.907777 -282.489955) (xy 121.859558 -282.480111) (xy 121.813542 -282.462659) (xy 121.770921 -282.438052)
			(xy 121.7328 -282.406927) (xy 121.700165 -282.37009) (xy 121.673862 -282.328494) (xy 121.654571 -282.283218)
			(xy 121.642794 -282.235434) (xy 121.638834 -282.18638) (xy 121.310146 -282.18638) (xy 121.309651 -282.210987)
			(xy 121.301756 -282.259564) (xy 121.286172 -282.306245) (xy 121.263301 -282.349822) (xy 121.233736 -282.389166)
			(xy 121.198243 -282.423258) (xy 121.15774 -282.451214) (xy 121.113278 -282.472312) (xy 121.066007 -282.486004)
			(xy 121.017152 -282.491936) (xy 120.967977 -282.489955) (xy 120.919758 -282.480111) (xy 120.873742 -282.462659)
			(xy 120.831121 -282.438052) (xy 120.793 -282.406927) (xy 120.760365 -282.37009) (xy 120.734062 -282.328494)
			(xy 120.714771 -282.283218) (xy 120.702994 -282.235434) (xy 120.699034 -282.18638) (xy 120.370092 -282.18638)
			(xy 120.369597 -282.210987) (xy 120.361702 -282.259564) (xy 120.346118 -282.306245) (xy 120.323247 -282.349822)
			(xy 120.293682 -282.389166) (xy 120.258189 -282.423258) (xy 120.217686 -282.451214) (xy 120.173224 -282.472312)
			(xy 120.125953 -282.486004) (xy 120.077098 -282.491936) (xy 120.027923 -282.489955) (xy 119.979704 -282.480111)
			(xy 119.933688 -282.462659) (xy 119.891067 -282.438052) (xy 119.852946 -282.406927) (xy 119.820311 -282.37009)
			(xy 119.794008 -282.328494) (xy 119.774717 -282.283218) (xy 119.76294 -282.235434) (xy 119.75898 -282.18638)
			(xy 119.430038 -282.18638) (xy 119.429543 -282.210987) (xy 119.421648 -282.259564) (xy 119.406064 -282.306245)
			(xy 119.383193 -282.349822) (xy 119.353628 -282.389166) (xy 119.318135 -282.423258) (xy 119.277632 -282.451214)
			(xy 119.23317 -282.472312) (xy 119.185899 -282.486004) (xy 119.137044 -282.491936) (xy 119.087869 -282.489955)
			(xy 119.03965 -282.480111) (xy 118.993634 -282.462659) (xy 118.951013 -282.438052) (xy 118.912892 -282.406927)
			(xy 118.880257 -282.37009) (xy 118.853954 -282.328494) (xy 118.834663 -282.283218) (xy 118.822886 -282.235434)
			(xy 118.818926 -282.18638) (xy 118.489984 -282.18638) (xy 118.489489 -282.210987) (xy 118.481594 -282.259564)
			(xy 118.46601 -282.306245) (xy 118.443139 -282.349822) (xy 118.413574 -282.389166) (xy 118.378081 -282.423258)
			(xy 118.337578 -282.451214) (xy 118.293116 -282.472312) (xy 118.245845 -282.486004) (xy 118.19699 -282.491936)
			(xy 118.147815 -282.489955) (xy 118.099596 -282.480111) (xy 118.05358 -282.462659) (xy 118.010959 -282.438052)
			(xy 117.972838 -282.406927) (xy 117.940203 -282.37009) (xy 117.9139 -282.328494) (xy 117.894609 -282.283218)
			(xy 117.882832 -282.235434) (xy 117.878872 -282.18638) (xy 117.54993 -282.18638) (xy 117.549435 -282.210987)
			(xy 117.54154 -282.259564) (xy 117.525956 -282.306245) (xy 117.503085 -282.349822) (xy 117.47352 -282.389166)
			(xy 117.438027 -282.423258) (xy 117.397524 -282.451214) (xy 117.353062 -282.472312) (xy 117.305791 -282.486004)
			(xy 117.256936 -282.491936) (xy 117.207761 -282.489955) (xy 117.159542 -282.480111) (xy 117.113526 -282.462659)
			(xy 117.070905 -282.438052) (xy 117.032784 -282.406927) (xy 117.000149 -282.37009) (xy 116.973846 -282.328494)
			(xy 116.954555 -282.283218) (xy 116.942778 -282.235434) (xy 116.938818 -282.18638) (xy 116.61013 -282.18638)
			(xy 116.609635 -282.210987) (xy 116.60174 -282.259564) (xy 116.586156 -282.306245) (xy 116.563285 -282.349822)
			(xy 116.53372 -282.389166) (xy 116.498227 -282.423258) (xy 116.457724 -282.451214) (xy 116.413262 -282.472312)
			(xy 116.365991 -282.486004) (xy 116.317136 -282.491936) (xy 116.267961 -282.489955) (xy 116.219742 -282.480111)
			(xy 116.173726 -282.462659) (xy 116.131105 -282.438052) (xy 116.092984 -282.406927) (xy 116.060349 -282.37009)
			(xy 116.034046 -282.328494) (xy 116.014755 -282.283218) (xy 116.002978 -282.235434) (xy 115.999018 -282.18638)
			(xy 115.670638 -282.18638) (xy 115.67064 -282.1864) (xy 115.666468 -282.236743) (xy 115.654067 -282.285712)
			(xy 115.633773 -282.331973) (xy 115.606142 -282.374261) (xy 115.571927 -282.411425) (xy 115.532062 -282.44245)
			(xy 115.487633 -282.46649) (xy 115.439853 -282.482888) (xy 115.390026 -282.491198) (xy 115.364768 -282.491688)
			(xy 114.424714 -282.491688) (xy 114.399454 -282.491236) (xy 114.349622 -282.482923) (xy 114.301839 -282.466521)
			(xy 114.257407 -282.442477) (xy 114.217539 -282.411448) (xy 114.183321 -282.37428) (xy 114.155689 -282.331987)
			(xy 114.135394 -282.285722) (xy 114.122992 -282.236748) (xy 114.11882 -282.1864) (xy 113.789968 -282.1864)
			(xy 113.789473 -282.210987) (xy 113.781578 -282.259564) (xy 113.765994 -282.306245) (xy 113.743123 -282.349822)
			(xy 113.713558 -282.389166) (xy 113.678065 -282.423258) (xy 113.637562 -282.451214) (xy 113.5931 -282.472312)
			(xy 113.545829 -282.486004) (xy 113.496974 -282.491936) (xy 113.447799 -282.489955) (xy 113.39958 -282.480111)
			(xy 113.353564 -282.462659) (xy 113.310943 -282.438052) (xy 113.272822 -282.406927) (xy 113.240187 -282.37009)
			(xy 113.213884 -282.328494) (xy 113.194593 -282.283218) (xy 113.182816 -282.235434) (xy 113.178856 -282.18638)
			(xy 110.97641 -282.18638) (xy 110.975915 -282.210987) (xy 110.96802 -282.259564) (xy 110.952436 -282.306245)
			(xy 110.929565 -282.349822) (xy 110.9 -282.389166) (xy 110.864507 -282.423258) (xy 110.824004 -282.451214)
			(xy 110.779542 -282.472312) (xy 110.732271 -282.486004) (xy 110.683416 -282.491936) (xy 110.634241 -282.489955)
			(xy 110.586022 -282.480111) (xy 110.540006 -282.462659) (xy 110.497385 -282.438052) (xy 110.459264 -282.406927)
			(xy 110.426629 -282.37009) (xy 110.400326 -282.328494) (xy 110.381035 -282.283218) (xy 110.369258 -282.235434)
			(xy 110.365298 -282.18638) (xy 110.036809 -282.18638) (xy 110.036811 -282.1864) (xy 110.032641 -282.23673)
			(xy 110.020245 -282.285687) (xy 109.99996 -282.331937) (xy 109.97234 -282.374217) (xy 109.938139 -282.411375)
			(xy 109.898288 -282.442398) (xy 109.853875 -282.466439) (xy 109.806111 -282.482843) (xy 109.756299 -282.491163)
			(xy 109.731048 -282.491688) (xy 108.790994 -282.491688) (xy 108.765737 -282.491206) (xy 108.715913 -282.482891)
			(xy 108.668137 -282.466488) (xy 108.623712 -282.442446) (xy 108.58385 -282.41142) (xy 108.549639 -282.374256)
			(xy 108.522011 -282.331967) (xy 108.50172 -282.285708) (xy 108.48932 -282.236741) (xy 108.485149 -282.1864)
			(xy 108.156248 -282.1864) (xy 108.155753 -282.210987) (xy 108.147858 -282.259564) (xy 108.132274 -282.306245)
			(xy 108.109403 -282.349822) (xy 108.079838 -282.389166) (xy 108.044345 -282.423258) (xy 108.003842 -282.451214)
			(xy 107.95938 -282.472312) (xy 107.912109 -282.486004) (xy 107.863254 -282.491936) (xy 107.814079 -282.489955)
			(xy 107.76586 -282.480111) (xy 107.719844 -282.462659) (xy 107.677223 -282.438052) (xy 107.639102 -282.406927)
			(xy 107.606467 -282.37009) (xy 107.580164 -282.328494) (xy 107.560873 -282.283218) (xy 107.549096 -282.235434)
			(xy 107.545136 -282.18638) (xy 107.216448 -282.18638) (xy 107.215953 -282.210987) (xy 107.208058 -282.259564)
			(xy 107.192474 -282.306245) (xy 107.169603 -282.349822) (xy 107.140038 -282.389166) (xy 107.104545 -282.423258)
			(xy 107.064042 -282.451214) (xy 107.01958 -282.472312) (xy 106.972309 -282.486004) (xy 106.923454 -282.491936)
			(xy 106.874279 -282.489955) (xy 106.82606 -282.480111) (xy 106.780044 -282.462659) (xy 106.737423 -282.438052)
			(xy 106.699302 -282.406927) (xy 106.666667 -282.37009) (xy 106.640364 -282.328494) (xy 106.621073 -282.283218)
			(xy 106.609296 -282.235434) (xy 106.605336 -282.18638) (xy 106.276394 -282.18638) (xy 106.275899 -282.210987)
			(xy 106.268004 -282.259564) (xy 106.25242 -282.306245) (xy 106.229549 -282.349822) (xy 106.199984 -282.389166)
			(xy 106.164491 -282.423258) (xy 106.123988 -282.451214) (xy 106.079526 -282.472312) (xy 106.032255 -282.486004)
			(xy 105.9834 -282.491936) (xy 105.934225 -282.489955) (xy 105.886006 -282.480111) (xy 105.83999 -282.462659)
			(xy 105.797369 -282.438052) (xy 105.759248 -282.406927) (xy 105.726613 -282.37009) (xy 105.70031 -282.328494)
			(xy 105.681019 -282.283218) (xy 105.669242 -282.235434) (xy 105.665282 -282.18638) (xy 105.33634 -282.18638)
			(xy 105.335845 -282.210987) (xy 105.32795 -282.259564) (xy 105.312366 -282.306245) (xy 105.289495 -282.349822)
			(xy 105.25993 -282.389166) (xy 105.224437 -282.423258) (xy 105.183934 -282.451214) (xy 105.139472 -282.472312)
			(xy 105.092201 -282.486004) (xy 105.043346 -282.491936) (xy 104.994171 -282.489955) (xy 104.945952 -282.480111)
			(xy 104.899936 -282.462659) (xy 104.857315 -282.438052) (xy 104.819194 -282.406927) (xy 104.786559 -282.37009)
			(xy 104.760256 -282.328494) (xy 104.740965 -282.283218) (xy 104.729188 -282.235434) (xy 104.725228 -282.18638)
			(xy 104.396286 -282.18638) (xy 104.395791 -282.210987) (xy 104.387896 -282.259564) (xy 104.372312 -282.306245)
			(xy 104.349441 -282.349822) (xy 104.319876 -282.389166) (xy 104.284383 -282.423258) (xy 104.24388 -282.451214)
			(xy 104.199418 -282.472312) (xy 104.152147 -282.486004) (xy 104.103292 -282.491936) (xy 104.054117 -282.489955)
			(xy 104.005898 -282.480111) (xy 103.959882 -282.462659) (xy 103.917261 -282.438052) (xy 103.87914 -282.406927)
			(xy 103.846505 -282.37009) (xy 103.820202 -282.328494) (xy 103.800911 -282.283218) (xy 103.789134 -282.235434)
			(xy 103.785174 -282.18638) (xy 103.456486 -282.18638) (xy 103.455991 -282.210987) (xy 103.448096 -282.259564)
			(xy 103.432512 -282.306245) (xy 103.409641 -282.349822) (xy 103.380076 -282.389166) (xy 103.344583 -282.423258)
			(xy 103.30408 -282.451214) (xy 103.259618 -282.472312) (xy 103.212347 -282.486004) (xy 103.163492 -282.491936)
			(xy 103.114317 -282.489955) (xy 103.066098 -282.480111) (xy 103.020082 -282.462659) (xy 102.977461 -282.438052)
			(xy 102.93934 -282.406927) (xy 102.906705 -282.37009) (xy 102.880402 -282.328494) (xy 102.861111 -282.283218)
			(xy 102.849334 -282.235434) (xy 102.845374 -282.18638) (xy 102.516432 -282.18638) (xy 102.515937 -282.210987)
			(xy 102.508042 -282.259564) (xy 102.492458 -282.306245) (xy 102.469587 -282.349822) (xy 102.440022 -282.389166)
			(xy 102.404529 -282.423258) (xy 102.364026 -282.451214) (xy 102.319564 -282.472312) (xy 102.272293 -282.486004)
			(xy 102.223438 -282.491936) (xy 102.174263 -282.489955) (xy 102.126044 -282.480111) (xy 102.080028 -282.462659)
			(xy 102.037407 -282.438052) (xy 101.999286 -282.406927) (xy 101.966651 -282.37009) (xy 101.940348 -282.328494)
			(xy 101.921057 -282.283218) (xy 101.90928 -282.235434) (xy 101.90532 -282.18638) (xy 101.576378 -282.18638)
			(xy 101.575883 -282.210987) (xy 101.567988 -282.259564) (xy 101.552404 -282.306245) (xy 101.529533 -282.349822)
			(xy 101.499968 -282.389166) (xy 101.464475 -282.423258) (xy 101.423972 -282.451214) (xy 101.37951 -282.472312)
			(xy 101.332239 -282.486004) (xy 101.283384 -282.491936) (xy 101.234209 -282.489955) (xy 101.18599 -282.480111)
			(xy 101.139974 -282.462659) (xy 101.097353 -282.438052) (xy 101.059232 -282.406927) (xy 101.026597 -282.37009)
			(xy 101.000294 -282.328494) (xy 100.981003 -282.283218) (xy 100.969226 -282.235434) (xy 100.965266 -282.18638)
			(xy 100.636324 -282.18638) (xy 100.635829 -282.210987) (xy 100.627934 -282.259564) (xy 100.61235 -282.306245)
			(xy 100.589479 -282.349822) (xy 100.559914 -282.389166) (xy 100.524421 -282.423258) (xy 100.483918 -282.451214)
			(xy 100.439456 -282.472312) (xy 100.392185 -282.486004) (xy 100.34333 -282.491936) (xy 100.294155 -282.489955)
			(xy 100.245936 -282.480111) (xy 100.19992 -282.462659) (xy 100.157299 -282.438052) (xy 100.119178 -282.406927)
			(xy 100.086543 -282.37009) (xy 100.06024 -282.328494) (xy 100.040949 -282.283218) (xy 100.029172 -282.235434)
			(xy 100.025212 -282.18638) (xy 99.69627 -282.18638) (xy 99.695775 -282.210987) (xy 99.68788 -282.259564)
			(xy 99.672296 -282.306245) (xy 99.649425 -282.349822) (xy 99.61986 -282.389166) (xy 99.584367 -282.423258)
			(xy 99.543864 -282.451214) (xy 99.499402 -282.472312) (xy 99.452131 -282.486004) (xy 99.403276 -282.491936)
			(xy 99.354101 -282.489955) (xy 99.305882 -282.480111) (xy 99.259866 -282.462659) (xy 99.217245 -282.438052)
			(xy 99.179124 -282.406927) (xy 99.146489 -282.37009) (xy 99.120186 -282.328494) (xy 99.100895 -282.283218)
			(xy 99.089118 -282.235434) (xy 99.085158 -282.18638) (xy 98.75647 -282.18638) (xy 98.755975 -282.210987)
			(xy 98.74808 -282.259564) (xy 98.732496 -282.306245) (xy 98.709625 -282.349822) (xy 98.68006 -282.389166)
			(xy 98.644567 -282.423258) (xy 98.604064 -282.451214) (xy 98.559602 -282.472312) (xy 98.512331 -282.486004)
			(xy 98.463476 -282.491936) (xy 98.414301 -282.489955) (xy 98.366082 -282.480111) (xy 98.320066 -282.462659)
			(xy 98.277445 -282.438052) (xy 98.239324 -282.406927) (xy 98.206689 -282.37009) (xy 98.180386 -282.328494)
			(xy 98.161095 -282.283218) (xy 98.149318 -282.235434) (xy 98.145358 -282.18638) (xy 97.816416 -282.18638)
			(xy 97.815921 -282.210987) (xy 97.808026 -282.259564) (xy 97.792442 -282.306245) (xy 97.769571 -282.349822)
			(xy 97.740006 -282.389166) (xy 97.704513 -282.423258) (xy 97.66401 -282.451214) (xy 97.619548 -282.472312)
			(xy 97.572277 -282.486004) (xy 97.523422 -282.491936) (xy 97.474247 -282.489955) (xy 97.426028 -282.480111)
			(xy 97.380012 -282.462659) (xy 97.337391 -282.438052) (xy 97.29927 -282.406927) (xy 97.266635 -282.37009)
			(xy 97.240332 -282.328494) (xy 97.221041 -282.283218) (xy 97.209264 -282.235434) (xy 97.205304 -282.18638)
			(xy 96.876362 -282.18638) (xy 96.875895 -282.210984) (xy 96.868002 -282.259556) (xy 96.852418 -282.306232)
			(xy 96.829546 -282.349803) (xy 96.79998 -282.389139) (xy 96.764485 -282.423221) (xy 96.723981 -282.451167)
			(xy 96.679518 -282.472251) (xy 96.632247 -282.485927) (xy 96.607884 -282.489402) (xy 96.60509 -282.489656)
			(xy 96.599042 -282.490929) (xy 96.587748 -282.495942) (xy 96.582738 -282.499562) (xy 96.577658 -282.503372)
			(xy 96.573848 -282.508452) (xy 96.567244 -282.519882) (xy 96.533208 -282.602432) (xy 96.531261 -282.608321)
			(xy 96.529966 -282.620654) (xy 96.530668 -282.626816) (xy 96.532446 -282.63977) (xy 96.541082 -282.650946)
			(xy 96.565555 -282.683426) (xy 96.60585 -282.754063) (xy 96.621346 -282.791662) (xy 96.62414 -282.79852)
			(xy 96.63176 -282.808934) (xy 96.637348 -282.813252) (xy 96.642018 -282.816688) (xy 96.652536 -282.821561)
			(xy 96.658176 -282.822904) (xy 96.75114 -282.835096) (xy 96.754912 -282.835273) (xy 96.762436 -282.834628)
			(xy 96.766126 -282.833826) (xy 96.77527 -282.831032) (xy 96.787208 -282.825698) (xy 96.788478 -282.82392)
			(xy 96.795336 -282.814776) (xy 96.79559 -282.814268) (xy 96.810126 -282.795494) (xy 96.844023 -282.76225)
			(xy 96.882653 -282.734646) (xy 96.925087 -282.713347) (xy 96.970303 -282.698865) (xy 97.017214 -282.691548)
			(xy 97.040954 -282.691078) (xy 97.06495 -282.691521) (xy 97.112352 -282.699022) (xy 97.157997 -282.713846)
			(xy 97.20076 -282.735629) (xy 97.239589 -282.763833) (xy 97.273528 -282.797765) (xy 97.30174 -282.836589)
			(xy 97.323531 -282.879348) (xy 97.338364 -282.92499) (xy 97.345875 -282.97239) (xy 97.346262 -282.996386)
			(xy 97.346262 -282.9964) (xy 97.674871 -282.9964) (xy 97.679047 -282.946012) (xy 97.691459 -282.896999)
			(xy 97.711769 -282.850697) (xy 97.739424 -282.808369) (xy 97.773668 -282.771171) (xy 97.813568 -282.740117)
			(xy 97.858035 -282.716053) (xy 97.905856 -282.699637) (xy 97.955728 -282.691316) (xy 97.981008 -282.690824)
			(xy 98.921062 -282.690824) (xy 98.946342 -282.691342) (xy 98.996212 -282.699658) (xy 99.044033 -282.71607)
			(xy 99.088501 -282.74013) (xy 99.128401 -282.771181) (xy 99.162646 -282.808377) (xy 99.190302 -282.850702)
			(xy 99.210613 -282.897002) (xy 99.223025 -282.946014) (xy 99.2272 -282.996386) (xy 99.555312 -282.996386)
			(xy 99.559272 -282.947332) (xy 99.571049 -282.899548) (xy 99.59034 -282.854272) (xy 99.616643 -282.812676)
			(xy 99.649278 -282.775839) (xy 99.687399 -282.744714) (xy 99.73002 -282.720107) (xy 99.776036 -282.702655)
			(xy 99.824255 -282.692811) (xy 99.87343 -282.69083) (xy 99.922285 -282.696762) (xy 99.969556 -282.710454)
			(xy 100.014018 -282.731552) (xy 100.054521 -282.759508) (xy 100.090014 -282.7936) (xy 100.119579 -282.832944)
			(xy 100.14245 -282.876521) (xy 100.158034 -282.923202) (xy 100.165929 -282.971779) (xy 100.166424 -282.996386)
			(xy 100.166424 -282.9964) (xy 100.4951 -282.9964) (xy 100.499275 -282.946021) (xy 100.511684 -282.897016)
			(xy 100.531989 -282.850721) (xy 100.559637 -282.8084) (xy 100.593873 -282.771206) (xy 100.633764 -282.740154)
			(xy 100.678221 -282.716091) (xy 100.726032 -282.699673) (xy 100.775894 -282.691348) (xy 100.80117 -282.690824)
			(xy 101.741224 -282.690824) (xy 101.766498 -282.691376) (xy 101.816356 -282.699699) (xy 101.864164 -282.716115)
			(xy 101.908618 -282.740176) (xy 101.948506 -282.771224) (xy 101.98274 -282.808415) (xy 102.010385 -282.850733)
			(xy 102.030689 -282.897024) (xy 102.043098 -282.946025) (xy 102.047271 -282.996386) (xy 102.37522 -282.996386)
			(xy 102.37918 -282.947332) (xy 102.390957 -282.899548) (xy 102.410248 -282.854272) (xy 102.436551 -282.812676)
			(xy 102.469186 -282.775839) (xy 102.507307 -282.744714) (xy 102.549928 -282.720107) (xy 102.595944 -282.702655)
			(xy 102.644163 -282.692811) (xy 102.693338 -282.69083) (xy 102.742193 -282.696762) (xy 102.789464 -282.710454)
			(xy 102.833926 -282.731552) (xy 102.874429 -282.759508) (xy 102.909922 -282.7936) (xy 102.939487 -282.832944)
			(xy 102.962358 -282.876521) (xy 102.977942 -282.923202) (xy 102.985837 -282.971779) (xy 102.986332 -282.996386)
			(xy 102.986332 -282.9964) (xy 103.315 -282.9964) (xy 103.319175 -282.94602) (xy 103.331584 -282.897014)
			(xy 103.35189 -282.850719) (xy 103.379539 -282.808397) (xy 103.413776 -282.771203) (xy 103.453668 -282.740151)
			(xy 103.498126 -282.716089) (xy 103.545939 -282.699672) (xy 103.595802 -282.691348) (xy 103.621078 -282.690824)
			(xy 104.561132 -282.690824) (xy 104.586405 -282.691376) (xy 104.636262 -282.699701) (xy 104.684069 -282.716117)
			(xy 104.728522 -282.740178) (xy 104.768409 -282.771227) (xy 104.802642 -282.808418) (xy 104.830287 -282.850735)
			(xy 104.85059 -282.897025) (xy 104.862998 -282.946026) (xy 104.867171 -282.996386) (xy 105.195128 -282.996386)
			(xy 105.199088 -282.947332) (xy 105.210865 -282.899548) (xy 105.230156 -282.854272) (xy 105.256459 -282.812676)
			(xy 105.289094 -282.775839) (xy 105.327215 -282.744714) (xy 105.369836 -282.720107) (xy 105.415852 -282.702655)
			(xy 105.464071 -282.692811) (xy 105.513246 -282.69083) (xy 105.562101 -282.696762) (xy 105.609372 -282.710454)
			(xy 105.653834 -282.731552) (xy 105.694337 -282.759508) (xy 105.72983 -282.7936) (xy 105.759395 -282.832944)
			(xy 105.782266 -282.876521) (xy 105.79785 -282.923202) (xy 105.805745 -282.971779) (xy 105.80624 -282.996386)
			(xy 105.80624 -282.9964) (xy 106.1349 -282.9964) (xy 106.139075 -282.946019) (xy 106.151485 -282.897012)
			(xy 106.171791 -282.850717) (xy 106.199441 -282.808394) (xy 106.233679 -282.7712) (xy 106.273572 -282.740149)
			(xy 106.318032 -282.716086) (xy 106.365846 -282.69967) (xy 106.415709 -282.691347) (xy 106.440986 -282.690824)
			(xy 107.38104 -282.690824) (xy 107.406313 -282.691377) (xy 107.456169 -282.699702) (xy 107.503975 -282.71612)
			(xy 107.548426 -282.740181) (xy 107.588312 -282.77123) (xy 107.622544 -282.80842) (xy 107.650188 -282.850737)
			(xy 107.67049 -282.897027) (xy 107.682898 -282.946026) (xy 107.687071 -282.996386) (xy 108.01529 -282.996386)
			(xy 108.01925 -282.947332) (xy 108.031027 -282.899548) (xy 108.050318 -282.854272) (xy 108.076621 -282.812676)
			(xy 108.109256 -282.775839) (xy 108.147377 -282.744714) (xy 108.189998 -282.720107) (xy 108.236014 -282.702655)
			(xy 108.284233 -282.692811) (xy 108.333408 -282.69083) (xy 108.382263 -282.696762) (xy 108.429534 -282.710454)
			(xy 108.473996 -282.731552) (xy 108.514499 -282.759508) (xy 108.549992 -282.7936) (xy 108.579557 -282.832944)
			(xy 108.602428 -282.876521) (xy 108.618012 -282.923202) (xy 108.625907 -282.971779) (xy 108.626402 -282.996386)
			(xy 115.528864 -282.996386) (xy 115.532824 -282.947332) (xy 115.544601 -282.899548) (xy 115.563892 -282.854272)
			(xy 115.590195 -282.812676) (xy 115.62283 -282.775839) (xy 115.660951 -282.744714) (xy 115.703572 -282.720107)
			(xy 115.749588 -282.702655) (xy 115.797807 -282.692811) (xy 115.846982 -282.69083) (xy 115.895837 -282.696762)
			(xy 115.943108 -282.710454) (xy 115.98757 -282.731552) (xy 116.028073 -282.759508) (xy 116.063566 -282.7936)
			(xy 116.093131 -282.832944) (xy 116.116002 -282.876521) (xy 116.131586 -282.923202) (xy 116.139481 -282.971779)
			(xy 116.139976 -282.996386) (xy 116.139976 -282.9964) (xy 116.468571 -282.9964) (xy 116.472747 -282.946011)
			(xy 116.48516 -282.896996) (xy 116.505471 -282.850693) (xy 116.533127 -282.808365) (xy 116.567373 -282.771166)
			(xy 116.607275 -282.740112) (xy 116.651744 -282.716049) (xy 116.699568 -282.699634) (xy 116.749441 -282.691315)
			(xy 116.774722 -282.690824) (xy 117.714776 -282.690824) (xy 117.740055 -282.691343) (xy 117.789924 -282.699661)
			(xy 117.837743 -282.716074) (xy 117.882208 -282.740135) (xy 117.922107 -282.771186) (xy 117.95635 -282.808381)
			(xy 117.984004 -282.850706) (xy 118.004313 -282.897005) (xy 118.016725 -282.946015) (xy 118.0209 -282.996386)
			(xy 118.349026 -282.996386) (xy 118.352986 -282.947332) (xy 118.364763 -282.899548) (xy 118.384054 -282.854272)
			(xy 118.410357 -282.812676) (xy 118.442992 -282.775839) (xy 118.481113 -282.744714) (xy 118.523734 -282.720107)
			(xy 118.56975 -282.702655) (xy 118.617969 -282.692811) (xy 118.667144 -282.69083) (xy 118.715999 -282.696762)
			(xy 118.76327 -282.710454) (xy 118.807732 -282.731552) (xy 118.848235 -282.759508) (xy 118.883728 -282.7936)
			(xy 118.913293 -282.832944) (xy 118.936164 -282.876521) (xy 118.951748 -282.923202) (xy 118.959643 -282.971779)
			(xy 118.960138 -282.996386) (xy 118.960138 -282.9964) (xy 119.288471 -282.9964) (xy 119.292647 -282.94601)
			(xy 119.30506 -282.896994) (xy 119.325373 -282.850691) (xy 119.353029 -282.808362) (xy 119.387276 -282.771163)
			(xy 119.427179 -282.740109) (xy 119.47165 -282.716047) (xy 119.519474 -282.699633) (xy 119.569348 -282.691315)
			(xy 119.59463 -282.690824) (xy 120.534684 -282.690824) (xy 120.559962 -282.691344) (xy 120.60983 -282.699663)
			(xy 120.657648 -282.716077) (xy 120.702113 -282.740137) (xy 120.74201 -282.771189) (xy 120.776252 -282.808384)
			(xy 120.803905 -282.850708) (xy 120.824214 -282.897006) (xy 120.836625 -282.946016) (xy 120.8408 -282.996386)
			(xy 121.168934 -282.996386) (xy 121.172894 -282.947332) (xy 121.184671 -282.899548) (xy 121.203962 -282.854272)
			(xy 121.230265 -282.812676) (xy 121.2629 -282.775839) (xy 121.301021 -282.744714) (xy 121.343642 -282.720107)
			(xy 121.389658 -282.702655) (xy 121.437877 -282.692811) (xy 121.487052 -282.69083) (xy 121.535907 -282.696762)
			(xy 121.583178 -282.710454) (xy 121.62764 -282.731552) (xy 121.668143 -282.759508) (xy 121.703636 -282.7936)
			(xy 121.733201 -282.832944) (xy 121.756072 -282.876521) (xy 121.771656 -282.923202) (xy 121.779551 -282.971779)
			(xy 121.780046 -282.996386) (xy 121.780046 -282.9964) (xy 122.1087 -282.9964) (xy 122.112875 -282.946019)
			(xy 122.125285 -282.897011) (xy 122.145592 -282.850715) (xy 122.173242 -282.808392) (xy 122.207481 -282.771198)
			(xy 122.247375 -282.740147) (xy 122.291836 -282.716085) (xy 122.33965 -282.699669) (xy 122.389515 -282.691347)
			(xy 122.414792 -282.690824) (xy 123.354846 -282.690824) (xy 123.380119 -282.691377) (xy 123.429974 -282.699704)
			(xy 123.477779 -282.716122) (xy 123.52223 -282.740183) (xy 123.562114 -282.771232) (xy 123.596345 -282.808422)
			(xy 123.623989 -282.850739) (xy 123.644291 -282.897028) (xy 123.656698 -282.946027) (xy 123.660871 -282.996386)
			(xy 123.988842 -282.996386) (xy 123.992802 -282.947332) (xy 124.004579 -282.899548) (xy 124.02387 -282.854272)
			(xy 124.050173 -282.812676) (xy 124.082808 -282.775839) (xy 124.120929 -282.744714) (xy 124.16355 -282.720107)
			(xy 124.209566 -282.702655) (xy 124.257785 -282.692811) (xy 124.30696 -282.69083) (xy 124.355815 -282.696762)
			(xy 124.403086 -282.710454) (xy 124.447548 -282.731552) (xy 124.488051 -282.759508) (xy 124.523544 -282.7936)
			(xy 124.553109 -282.832944) (xy 124.57598 -282.876521) (xy 124.591564 -282.923202) (xy 124.599459 -282.971779)
			(xy 124.599954 -282.996386) (xy 124.599954 -282.9964) (xy 124.928601 -282.9964) (xy 124.932775 -282.946018)
			(xy 124.945186 -282.89701) (xy 124.965494 -282.850713) (xy 124.993144 -282.80839) (xy 125.027384 -282.771195)
			(xy 125.067279 -282.740144) (xy 125.111741 -282.716082) (xy 125.159557 -282.699667) (xy 125.209423 -282.691346)
			(xy 125.2347 -282.690824) (xy 126.174754 -282.690824) (xy 126.200034 -282.691341) (xy 126.249906 -282.699657)
			(xy 126.297728 -282.716068) (xy 126.342197 -282.740127) (xy 126.382098 -282.771178) (xy 126.416344 -282.808374)
			(xy 126.444 -282.850699) (xy 126.464312 -282.897) (xy 126.476725 -282.946013) (xy 126.480901 -282.9964)
			(xy 126.476725 -283.046787) (xy 126.464312 -283.0958) (xy 126.444 -283.142101) (xy 126.416344 -283.184426)
			(xy 126.382098 -283.221622) (xy 126.342197 -283.252673) (xy 126.297728 -283.276732) (xy 126.249906 -283.293143)
			(xy 126.200034 -283.301459) (xy 126.174754 -283.301948) (xy 125.2347 -283.301948) (xy 125.209423 -283.301454)
			(xy 125.159557 -283.293133) (xy 125.111741 -283.276718) (xy 125.067279 -283.252656) (xy 125.027384 -283.221605)
			(xy 124.993144 -283.18441) (xy 124.965494 -283.142087) (xy 124.945186 -283.09579) (xy 124.932775 -283.046782)
			(xy 124.928601 -282.9964) (xy 124.599954 -282.9964) (xy 124.599459 -283.020993) (xy 124.591564 -283.06957)
			(xy 124.57598 -283.116251) (xy 124.553109 -283.159828) (xy 124.523544 -283.199172) (xy 124.488051 -283.233264)
			(xy 124.447548 -283.26122) (xy 124.403086 -283.282318) (xy 124.355815 -283.29601) (xy 124.30696 -283.301942)
			(xy 124.257785 -283.299961) (xy 124.209566 -283.290117) (xy 124.16355 -283.272665) (xy 124.120929 -283.248058)
			(xy 124.082808 -283.216933) (xy 124.050173 -283.180096) (xy 124.02387 -283.1385) (xy 124.004579 -283.093224)
			(xy 123.992802 -283.04544) (xy 123.988842 -282.996386) (xy 123.660871 -282.996386) (xy 123.660872 -282.9964)
			(xy 123.656698 -283.046773) (xy 123.644291 -283.095772) (xy 123.623989 -283.142061) (xy 123.596345 -283.184378)
			(xy 123.562114 -283.221568) (xy 123.52223 -283.252617) (xy 123.477779 -283.276678) (xy 123.429974 -283.293096)
			(xy 123.380119 -283.301423) (xy 123.354846 -283.301948) (xy 122.414792 -283.301948) (xy 122.389515 -283.301453)
			(xy 122.33965 -283.293131) (xy 122.291836 -283.276715) (xy 122.247375 -283.252653) (xy 122.207481 -283.221602)
			(xy 122.173242 -283.184408) (xy 122.145592 -283.142085) (xy 122.125285 -283.095789) (xy 122.112875 -283.046781)
			(xy 122.1087 -282.9964) (xy 121.780046 -282.9964) (xy 121.779551 -283.020993) (xy 121.771656 -283.06957)
			(xy 121.756072 -283.116251) (xy 121.733201 -283.159828) (xy 121.703636 -283.199172) (xy 121.668143 -283.233264)
			(xy 121.62764 -283.26122) (xy 121.583178 -283.282318) (xy 121.535907 -283.29601) (xy 121.487052 -283.301942)
			(xy 121.437877 -283.299961) (xy 121.389658 -283.290117) (xy 121.343642 -283.272665) (xy 121.301021 -283.248058)
			(xy 121.2629 -283.216933) (xy 121.230265 -283.180096) (xy 121.203962 -283.1385) (xy 121.184671 -283.093224)
			(xy 121.172894 -283.04544) (xy 121.168934 -282.996386) (xy 120.8408 -282.996386) (xy 120.840801 -282.9964)
			(xy 120.836625 -283.046784) (xy 120.824214 -283.095794) (xy 120.803905 -283.142092) (xy 120.776252 -283.184416)
			(xy 120.74201 -283.221611) (xy 120.702113 -283.252663) (xy 120.657648 -283.276723) (xy 120.60983 -283.293137)
			(xy 120.559962 -283.301456) (xy 120.534684 -283.301948) (xy 119.59463 -283.301948) (xy 119.569348 -283.301485)
			(xy 119.519474 -283.293167) (xy 119.47165 -283.276753) (xy 119.427179 -283.252691) (xy 119.387276 -283.221637)
			(xy 119.353029 -283.184438) (xy 119.325373 -283.142109) (xy 119.30506 -283.095806) (xy 119.292647 -283.04679)
			(xy 119.288471 -282.9964) (xy 118.960138 -282.9964) (xy 118.959643 -283.020993) (xy 118.951748 -283.06957)
			(xy 118.936164 -283.116251) (xy 118.913293 -283.159828) (xy 118.883728 -283.199172) (xy 118.848235 -283.233264)
			(xy 118.807732 -283.26122) (xy 118.76327 -283.282318) (xy 118.715999 -283.29601) (xy 118.667144 -283.301942)
			(xy 118.617969 -283.299961) (xy 118.56975 -283.290117) (xy 118.523734 -283.272665) (xy 118.481113 -283.248058)
			(xy 118.442992 -283.216933) (xy 118.410357 -283.180096) (xy 118.384054 -283.1385) (xy 118.364763 -283.093224)
			(xy 118.352986 -283.04544) (xy 118.349026 -282.996386) (xy 118.0209 -282.996386) (xy 118.020901 -282.9964)
			(xy 118.016725 -283.046785) (xy 118.004313 -283.095795) (xy 117.984004 -283.142094) (xy 117.95635 -283.184419)
			(xy 117.922107 -283.221614) (xy 117.882208 -283.252665) (xy 117.837743 -283.276726) (xy 117.789924 -283.293139)
			(xy 117.740055 -283.301457) (xy 117.714776 -283.301948) (xy 116.774722 -283.301948) (xy 116.749441 -283.301485)
			(xy 116.699568 -283.293166) (xy 116.651744 -283.276751) (xy 116.607275 -283.252688) (xy 116.567373 -283.221634)
			(xy 116.533127 -283.184435) (xy 116.505471 -283.142107) (xy 116.48516 -283.095804) (xy 116.472747 -283.046789)
			(xy 116.468571 -282.9964) (xy 116.139976 -282.9964) (xy 116.139481 -283.020993) (xy 116.131586 -283.06957)
			(xy 116.116002 -283.116251) (xy 116.093131 -283.159828) (xy 116.063566 -283.199172) (xy 116.028073 -283.233264)
			(xy 115.98757 -283.26122) (xy 115.943108 -283.282318) (xy 115.895837 -283.29601) (xy 115.846982 -283.301942)
			(xy 115.797807 -283.299961) (xy 115.749588 -283.290117) (xy 115.703572 -283.272665) (xy 115.660951 -283.248058)
			(xy 115.62283 -283.216933) (xy 115.590195 -283.180096) (xy 115.563892 -283.1385) (xy 115.544601 -283.093224)
			(xy 115.532824 -283.04544) (xy 115.528864 -282.996386) (xy 108.626402 -282.996386) (xy 108.625907 -283.020993)
			(xy 108.618012 -283.06957) (xy 108.602428 -283.116251) (xy 108.579557 -283.159828) (xy 108.549992 -283.199172)
			(xy 108.514499 -283.233264) (xy 108.473996 -283.26122) (xy 108.429534 -283.282318) (xy 108.382263 -283.29601)
			(xy 108.333408 -283.301942) (xy 108.284233 -283.299961) (xy 108.236014 -283.290117) (xy 108.189998 -283.272665)
			(xy 108.147377 -283.248058) (xy 108.109256 -283.216933) (xy 108.076621 -283.180096) (xy 108.050318 -283.1385)
			(xy 108.031027 -283.093224) (xy 108.01925 -283.04544) (xy 108.01529 -282.996386) (xy 107.687071 -282.996386)
			(xy 107.687072 -282.9964) (xy 107.682898 -283.046774) (xy 107.67049 -283.095773) (xy 107.650188 -283.142063)
			(xy 107.622544 -283.18438) (xy 107.588312 -283.22157) (xy 107.548426 -283.252619) (xy 107.503975 -283.27668)
			(xy 107.456169 -283.293098) (xy 107.406313 -283.301423) (xy 107.38104 -283.301948) (xy 106.440986 -283.301948)
			(xy 106.415709 -283.301453) (xy 106.365846 -283.29313) (xy 106.318032 -283.276714) (xy 106.273572 -283.252651)
			(xy 106.233679 -283.2216) (xy 106.199441 -283.184406) (xy 106.171791 -283.142083) (xy 106.151485 -283.095788)
			(xy 106.139075 -283.046781) (xy 106.1349 -282.9964) (xy 105.80624 -282.9964) (xy 105.805745 -283.020993)
			(xy 105.79785 -283.06957) (xy 105.782266 -283.116251) (xy 105.759395 -283.159828) (xy 105.72983 -283.199172)
			(xy 105.694337 -283.233264) (xy 105.653834 -283.26122) (xy 105.609372 -283.282318) (xy 105.562101 -283.29601)
			(xy 105.513246 -283.301942) (xy 105.464071 -283.299961) (xy 105.415852 -283.290117) (xy 105.369836 -283.272665)
			(xy 105.327215 -283.248058) (xy 105.289094 -283.216933) (xy 105.256459 -283.180096) (xy 105.230156 -283.1385)
			(xy 105.210865 -283.093224) (xy 105.199088 -283.04544) (xy 105.195128 -282.996386) (xy 104.867171 -282.996386)
			(xy 104.867172 -282.9964) (xy 104.862998 -283.046774) (xy 104.85059 -283.095775) (xy 104.830287 -283.142065)
			(xy 104.802642 -283.184382) (xy 104.768409 -283.221573) (xy 104.728522 -283.252622) (xy 104.684069 -283.276683)
			(xy 104.636262 -283.293099) (xy 104.586405 -283.301424) (xy 104.561132 -283.301948) (xy 103.621078 -283.301948)
			(xy 103.595802 -283.301452) (xy 103.545939 -283.293128) (xy 103.498126 -283.276711) (xy 103.453668 -283.252649)
			(xy 103.413776 -283.221597) (xy 103.379539 -283.184403) (xy 103.35189 -283.142081) (xy 103.331584 -283.095786)
			(xy 103.319175 -283.04678) (xy 103.315 -282.9964) (xy 102.986332 -282.9964) (xy 102.985837 -283.020993)
			(xy 102.977942 -283.06957) (xy 102.962358 -283.116251) (xy 102.939487 -283.159828) (xy 102.909922 -283.199172)
			(xy 102.874429 -283.233264) (xy 102.833926 -283.26122) (xy 102.789464 -283.282318) (xy 102.742193 -283.29601)
			(xy 102.693338 -283.301942) (xy 102.644163 -283.299961) (xy 102.595944 -283.290117) (xy 102.549928 -283.272665)
			(xy 102.507307 -283.248058) (xy 102.469186 -283.216933) (xy 102.436551 -283.180096) (xy 102.410248 -283.1385)
			(xy 102.390957 -283.093224) (xy 102.37918 -283.04544) (xy 102.37522 -282.996386) (xy 102.047271 -282.996386)
			(xy 102.047272 -282.9964) (xy 102.043098 -283.046775) (xy 102.030689 -283.095776) (xy 102.010385 -283.142067)
			(xy 101.98274 -283.184385) (xy 101.948506 -283.221576) (xy 101.908618 -283.252624) (xy 101.864164 -283.276685)
			(xy 101.816356 -283.293101) (xy 101.766498 -283.301424) (xy 101.741224 -283.301948) (xy 100.80117 -283.301948)
			(xy 100.775894 -283.301452) (xy 100.726032 -283.293127) (xy 100.678221 -283.276709) (xy 100.633764 -283.252646)
			(xy 100.593873 -283.221594) (xy 100.559637 -283.1844) (xy 100.531989 -283.142079) (xy 100.511684 -283.095784)
			(xy 100.499275 -283.046779) (xy 100.4951 -282.9964) (xy 100.166424 -282.9964) (xy 100.165929 -283.020993)
			(xy 100.158034 -283.06957) (xy 100.14245 -283.116251) (xy 100.119579 -283.159828) (xy 100.090014 -283.199172)
			(xy 100.054521 -283.233264) (xy 100.014018 -283.26122) (xy 99.969556 -283.282318) (xy 99.922285 -283.29601)
			(xy 99.87343 -283.301942) (xy 99.824255 -283.299961) (xy 99.776036 -283.290117) (xy 99.73002 -283.272665)
			(xy 99.687399 -283.248058) (xy 99.649278 -283.216933) (xy 99.616643 -283.180096) (xy 99.59034 -283.1385)
			(xy 99.571049 -283.093224) (xy 99.559272 -283.04544) (xy 99.555312 -282.996386) (xy 99.2272 -282.996386)
			(xy 99.227201 -282.9964) (xy 99.223025 -283.046786) (xy 99.210613 -283.095798) (xy 99.190302 -283.142098)
			(xy 99.162646 -283.184423) (xy 99.128401 -283.221619) (xy 99.088501 -283.25267) (xy 99.044033 -283.27673)
			(xy 98.996212 -283.293142) (xy 98.946342 -283.301458) (xy 98.921062 -283.301948) (xy 97.981008 -283.301948)
			(xy 97.955728 -283.301484) (xy 97.905856 -283.293163) (xy 97.858035 -283.276747) (xy 97.813568 -283.252683)
			(xy 97.773668 -283.221629) (xy 97.739424 -283.184431) (xy 97.711769 -283.142103) (xy 97.691459 -283.095801)
			(xy 97.679047 -283.046788) (xy 97.674871 -282.9964) (xy 97.346262 -282.9964) (xy 97.345791 -283.020622)
			(xy 97.338122 -283.068484) (xy 97.322991 -283.114533) (xy 97.300777 -283.157616) (xy 97.272038 -283.196649)
			(xy 97.237495 -283.230654) (xy 97.198016 -283.258777) (xy 97.15459 -283.280312) (xy 97.108308 -283.294718)
			(xy 97.084388 -283.298646) (xy 97.071942 -283.300424) (xy 97.040954 -283.301948) (xy 97.017458 -283.301515)
			(xy 96.971021 -283.294321) (xy 96.926231 -283.280108) (xy 96.884141 -283.259212) (xy 96.845743 -283.232124)
			(xy 96.81194 -283.199481) (xy 96.797368 -283.181044) (xy 96.795336 -283.17825) (xy 96.795082 -283.177996)
			(xy 96.79094 -283.172629) (xy 96.78038 -283.164137) (xy 96.774254 -283.161232) (xy 96.768412 -283.158946)
			(xy 96.755204 -283.157168) (xy 96.661986 -283.16936) (xy 96.65531 -283.170406) (xy 96.64282 -283.175554)
			(xy 96.637348 -283.17952) (xy 96.63176 -283.183838) (xy 96.62414 -283.194252) (xy 96.621346 -283.201364)
			(xy 96.613468 -283.220935) (xy 96.595161 -283.258949) (xy 96.58477 -283.27731) (xy 96.540066 -283.354272)
			(xy 96.538288 -283.357574) (xy 96.538288 -283.430472) (xy 96.538542 -283.43606) (xy 96.539774 -283.444266)
			(xy 96.546771 -283.4593) (xy 96.552258 -283.465524) (xy 96.572832 -283.487368) (xy 96.582484 -283.495496)
			(xy 96.586561 -283.497908) (xy 96.595378 -283.501364) (xy 96.60001 -283.502354) (xy 96.604074 -283.502862)
			(xy 96.6287 -283.506026) (xy 96.676541 -283.519303) (xy 96.721602 -283.540146) (xy 96.762698 -283.568004)
			(xy 96.798745 -283.602145) (xy 96.828793 -283.641668) (xy 96.85205 -283.685532) (xy 96.867905 -283.732581)
			(xy 96.875938 -283.781575) (xy 96.875938 -283.806392) (xy 99.085158 -283.806392) (xy 99.089118 -283.757338)
			(xy 99.100895 -283.709554) (xy 99.120186 -283.664278) (xy 99.146489 -283.622682) (xy 99.179124 -283.585845)
			(xy 99.217245 -283.55472) (xy 99.259866 -283.530113) (xy 99.305882 -283.512661) (xy 99.354101 -283.502817)
			(xy 99.403276 -283.500836) (xy 99.452131 -283.506768) (xy 99.499402 -283.52046) (xy 99.543864 -283.541558)
			(xy 99.584367 -283.569514) (xy 99.61986 -283.603606) (xy 99.649425 -283.64295) (xy 99.672296 -283.686527)
			(xy 99.68788 -283.733208) (xy 99.695775 -283.781785) (xy 99.69627 -283.806392) (xy 101.90532 -283.806392)
			(xy 101.90928 -283.757338) (xy 101.921057 -283.709554) (xy 101.940348 -283.664278) (xy 101.966651 -283.622682)
			(xy 101.999286 -283.585845) (xy 102.037407 -283.55472) (xy 102.080028 -283.530113) (xy 102.126044 -283.512661)
			(xy 102.174263 -283.502817) (xy 102.223438 -283.500836) (xy 102.272293 -283.506768) (xy 102.319564 -283.52046)
			(xy 102.364026 -283.541558) (xy 102.404529 -283.569514) (xy 102.440022 -283.603606) (xy 102.469587 -283.64295)
			(xy 102.492458 -283.686527) (xy 102.508042 -283.733208) (xy 102.515937 -283.781785) (xy 102.516432 -283.806392)
			(xy 104.725228 -283.806392) (xy 104.729188 -283.757338) (xy 104.740965 -283.709554) (xy 104.760256 -283.664278)
			(xy 104.786559 -283.622682) (xy 104.819194 -283.585845) (xy 104.857315 -283.55472) (xy 104.899936 -283.530113)
			(xy 104.945952 -283.512661) (xy 104.994171 -283.502817) (xy 105.043346 -283.500836) (xy 105.092201 -283.506768)
			(xy 105.139472 -283.52046) (xy 105.183934 -283.541558) (xy 105.224437 -283.569514) (xy 105.25993 -283.603606)
			(xy 105.289495 -283.64295) (xy 105.312366 -283.686527) (xy 105.32795 -283.733208) (xy 105.335845 -283.781785)
			(xy 105.33634 -283.806392) (xy 107.545136 -283.806392) (xy 107.549096 -283.757338) (xy 107.560873 -283.709554)
			(xy 107.580164 -283.664278) (xy 107.606467 -283.622682) (xy 107.639102 -283.585845) (xy 107.677223 -283.55472)
			(xy 107.719844 -283.530113) (xy 107.76586 -283.512661) (xy 107.814079 -283.502817) (xy 107.863254 -283.500836)
			(xy 107.912109 -283.506768) (xy 107.95938 -283.52046) (xy 108.003842 -283.541558) (xy 108.044345 -283.569514)
			(xy 108.079838 -283.603606) (xy 108.109403 -283.64295) (xy 108.132274 -283.686527) (xy 108.147858 -283.733208)
			(xy 108.155753 -283.781785) (xy 108.156248 -283.806392) (xy 108.156248 -283.8064) (xy 108.485161 -283.8064)
			(xy 108.489332 -283.756061) (xy 108.501732 -283.707095) (xy 108.522022 -283.660838) (xy 108.549649 -283.618552)
			(xy 108.583859 -283.581389) (xy 108.623719 -283.550364) (xy 108.668142 -283.526323) (xy 108.715916 -283.509921)
			(xy 108.765738 -283.501606) (xy 108.790994 -283.501084) (xy 109.731048 -283.501084) (xy 109.7563 -283.501625)
			(xy 109.806114 -283.509945) (xy 109.85388 -283.52635) (xy 109.898295 -283.550392) (xy 109.938147 -283.581416)
			(xy 109.97235 -283.618576) (xy 109.999971 -283.660858) (xy 110.020256 -283.707109) (xy 110.032653 -283.756068)
			(xy 110.036822 -283.806392) (xy 110.365298 -283.806392) (xy 110.369258 -283.757338) (xy 110.381035 -283.709554)
			(xy 110.400326 -283.664278) (xy 110.426629 -283.622682) (xy 110.459264 -283.585845) (xy 110.497385 -283.55472)
			(xy 110.540006 -283.530113) (xy 110.586022 -283.512661) (xy 110.634241 -283.502817) (xy 110.683416 -283.500836)
			(xy 110.732271 -283.506768) (xy 110.779542 -283.52046) (xy 110.824004 -283.541558) (xy 110.864507 -283.569514)
			(xy 110.9 -283.603606) (xy 110.929565 -283.64295) (xy 110.952436 -283.686527) (xy 110.96802 -283.733208)
			(xy 110.975915 -283.781785) (xy 110.97641 -283.806392) (xy 113.178856 -283.806392) (xy 113.182816 -283.757338)
			(xy 113.194593 -283.709554) (xy 113.213884 -283.664278) (xy 113.240187 -283.622682) (xy 113.272822 -283.585845)
			(xy 113.310943 -283.55472) (xy 113.353564 -283.530113) (xy 113.39958 -283.512661) (xy 113.447799 -283.502817)
			(xy 113.496974 -283.500836) (xy 113.545829 -283.506768) (xy 113.5931 -283.52046) (xy 113.637562 -283.541558)
			(xy 113.678065 -283.569514) (xy 113.713558 -283.603606) (xy 113.743123 -283.64295) (xy 113.765994 -283.686527)
			(xy 113.781578 -283.733208) (xy 113.789473 -283.781785) (xy 113.789968 -283.806392) (xy 113.789968 -283.8064)
			(xy 114.118832 -283.8064) (xy 114.123004 -283.756054) (xy 114.135406 -283.707082) (xy 114.155699 -283.660819)
			(xy 114.183331 -283.618527) (xy 114.217547 -283.581361) (xy 114.257413 -283.550333) (xy 114.301844 -283.52629)
			(xy 114.349625 -283.509889) (xy 114.399455 -283.501576) (xy 114.424714 -283.501084) (xy 115.364768 -283.501084)
			(xy 115.390027 -283.50159) (xy 115.439856 -283.5099) (xy 115.487638 -283.526299) (xy 115.532068 -283.55034)
			(xy 115.571936 -283.581366) (xy 115.606152 -283.618531) (xy 115.633784 -283.660822) (xy 115.654078 -283.707084)
			(xy 115.66648 -283.756055) (xy 115.670651 -283.806392) (xy 115.999018 -283.806392) (xy 116.002978 -283.757338)
			(xy 116.014755 -283.709554) (xy 116.034046 -283.664278) (xy 116.060349 -283.622682) (xy 116.092984 -283.585845)
			(xy 116.131105 -283.55472) (xy 116.173726 -283.530113) (xy 116.219742 -283.512661) (xy 116.267961 -283.502817)
			(xy 116.317136 -283.500836) (xy 116.365991 -283.506768) (xy 116.413262 -283.52046) (xy 116.457724 -283.541558)
			(xy 116.498227 -283.569514) (xy 116.53372 -283.603606) (xy 116.563285 -283.64295) (xy 116.586156 -283.686527)
			(xy 116.60174 -283.733208) (xy 116.609635 -283.781785) (xy 116.61013 -283.806392) (xy 118.818926 -283.806392)
			(xy 118.822886 -283.757338) (xy 118.834663 -283.709554) (xy 118.853954 -283.664278) (xy 118.880257 -283.622682)
			(xy 118.912892 -283.585845) (xy 118.951013 -283.55472) (xy 118.993634 -283.530113) (xy 119.03965 -283.512661)
			(xy 119.087869 -283.502817) (xy 119.137044 -283.500836) (xy 119.185899 -283.506768) (xy 119.23317 -283.52046)
			(xy 119.277632 -283.541558) (xy 119.318135 -283.569514) (xy 119.353628 -283.603606) (xy 119.383193 -283.64295)
			(xy 119.406064 -283.686527) (xy 119.421648 -283.733208) (xy 119.429543 -283.781785) (xy 119.430038 -283.806392)
			(xy 121.638834 -283.806392) (xy 121.642794 -283.757338) (xy 121.654571 -283.709554) (xy 121.673862 -283.664278)
			(xy 121.700165 -283.622682) (xy 121.7328 -283.585845) (xy 121.770921 -283.55472) (xy 121.813542 -283.530113)
			(xy 121.859558 -283.512661) (xy 121.907777 -283.502817) (xy 121.956952 -283.500836) (xy 122.005807 -283.506768)
			(xy 122.053078 -283.52046) (xy 122.09754 -283.541558) (xy 122.138043 -283.569514) (xy 122.173536 -283.603606)
			(xy 122.203101 -283.64295) (xy 122.225972 -283.686527) (xy 122.241556 -283.733208) (xy 122.249451 -283.781785)
			(xy 122.249946 -283.806392) (xy 124.458996 -283.806392) (xy 124.462956 -283.757338) (xy 124.474733 -283.709554)
			(xy 124.494024 -283.664278) (xy 124.520327 -283.622682) (xy 124.552962 -283.585845) (xy 124.591083 -283.55472)
			(xy 124.633704 -283.530113) (xy 124.67972 -283.512661) (xy 124.727939 -283.502817) (xy 124.777114 -283.500836)
			(xy 124.825969 -283.506768) (xy 124.87324 -283.52046) (xy 124.917702 -283.541558) (xy 124.958205 -283.569514)
			(xy 124.993698 -283.603606) (xy 125.023263 -283.64295) (xy 125.046134 -283.686527) (xy 125.061718 -283.733208)
			(xy 125.069613 -283.781785) (xy 125.070108 -283.806392) (xy 125.069613 -283.830999) (xy 125.061718 -283.879576)
			(xy 125.046134 -283.926257) (xy 125.023263 -283.969834) (xy 124.993698 -284.009178) (xy 124.958205 -284.04327)
			(xy 124.917702 -284.071226) (xy 124.87324 -284.092324) (xy 124.825969 -284.106016) (xy 124.777114 -284.111948)
			(xy 124.727939 -284.109967) (xy 124.67972 -284.100123) (xy 124.633704 -284.082671) (xy 124.591083 -284.058064)
			(xy 124.552962 -284.026939) (xy 124.520327 -283.990102) (xy 124.494024 -283.948506) (xy 124.474733 -283.90323)
			(xy 124.462956 -283.855446) (xy 124.458996 -283.806392) (xy 122.249946 -283.806392) (xy 122.249451 -283.830999)
			(xy 122.241556 -283.879576) (xy 122.225972 -283.926257) (xy 122.203101 -283.969834) (xy 122.173536 -284.009178)
			(xy 122.138043 -284.04327) (xy 122.09754 -284.071226) (xy 122.053078 -284.092324) (xy 122.005807 -284.106016)
			(xy 121.956952 -284.111948) (xy 121.907777 -284.109967) (xy 121.859558 -284.100123) (xy 121.813542 -284.082671)
			(xy 121.770921 -284.058064) (xy 121.7328 -284.026939) (xy 121.700165 -283.990102) (xy 121.673862 -283.948506)
			(xy 121.654571 -283.90323) (xy 121.642794 -283.855446) (xy 121.638834 -283.806392) (xy 119.430038 -283.806392)
			(xy 119.429543 -283.830999) (xy 119.421648 -283.879576) (xy 119.406064 -283.926257) (xy 119.383193 -283.969834)
			(xy 119.353628 -284.009178) (xy 119.318135 -284.04327) (xy 119.277632 -284.071226) (xy 119.23317 -284.092324)
			(xy 119.185899 -284.106016) (xy 119.137044 -284.111948) (xy 119.087869 -284.109967) (xy 119.03965 -284.100123)
			(xy 118.993634 -284.082671) (xy 118.951013 -284.058064) (xy 118.912892 -284.026939) (xy 118.880257 -283.990102)
			(xy 118.853954 -283.948506) (xy 118.834663 -283.90323) (xy 118.822886 -283.855446) (xy 118.818926 -283.806392)
			(xy 116.61013 -283.806392) (xy 116.609635 -283.830999) (xy 116.60174 -283.879576) (xy 116.586156 -283.926257)
			(xy 116.563285 -283.969834) (xy 116.53372 -284.009178) (xy 116.498227 -284.04327) (xy 116.457724 -284.071226)
			(xy 116.413262 -284.092324) (xy 116.365991 -284.106016) (xy 116.317136 -284.111948) (xy 116.267961 -284.109967)
			(xy 116.219742 -284.100123) (xy 116.173726 -284.082671) (xy 116.131105 -284.058064) (xy 116.092984 -284.026939)
			(xy 116.060349 -283.990102) (xy 116.034046 -283.948506) (xy 116.014755 -283.90323) (xy 116.002978 -283.855446)
			(xy 115.999018 -283.806392) (xy 115.670651 -283.806392) (xy 115.670652 -283.8064) (xy 115.66648 -283.856745)
			(xy 115.654078 -283.905716) (xy 115.633784 -283.951978) (xy 115.606152 -283.994269) (xy 115.571936 -284.031434)
			(xy 115.532068 -284.06246) (xy 115.487638 -284.086501) (xy 115.439856 -284.1029) (xy 115.390027 -284.11121)
			(xy 115.364768 -284.1117) (xy 114.424714 -284.1117) (xy 114.399455 -284.111224) (xy 114.349625 -284.102911)
			(xy 114.301844 -284.08651) (xy 114.257413 -284.062467) (xy 114.217547 -284.031439) (xy 114.183331 -283.994273)
			(xy 114.155699 -283.951981) (xy 114.135406 -283.905718) (xy 114.123004 -283.856746) (xy 114.118832 -283.8064)
			(xy 113.789968 -283.8064) (xy 113.789473 -283.830999) (xy 113.781578 -283.879576) (xy 113.765994 -283.926257)
			(xy 113.743123 -283.969834) (xy 113.713558 -284.009178) (xy 113.678065 -284.04327) (xy 113.637562 -284.071226)
			(xy 113.5931 -284.092324) (xy 113.545829 -284.106016) (xy 113.496974 -284.111948) (xy 113.447799 -284.109967)
			(xy 113.39958 -284.100123) (xy 113.353564 -284.082671) (xy 113.310943 -284.058064) (xy 113.272822 -284.026939)
			(xy 113.240187 -283.990102) (xy 113.213884 -283.948506) (xy 113.194593 -283.90323) (xy 113.182816 -283.855446)
			(xy 113.178856 -283.806392) (xy 110.97641 -283.806392) (xy 110.975915 -283.830999) (xy 110.96802 -283.879576)
			(xy 110.952436 -283.926257) (xy 110.929565 -283.969834) (xy 110.9 -284.009178) (xy 110.864507 -284.04327)
			(xy 110.824004 -284.071226) (xy 110.779542 -284.092324) (xy 110.732271 -284.106016) (xy 110.683416 -284.111948)
			(xy 110.634241 -284.109967) (xy 110.586022 -284.100123) (xy 110.540006 -284.082671) (xy 110.497385 -284.058064)
			(xy 110.459264 -284.026939) (xy 110.426629 -283.990102) (xy 110.400326 -283.948506) (xy 110.381035 -283.90323)
			(xy 110.369258 -283.855446) (xy 110.365298 -283.806392) (xy 110.036822 -283.806392) (xy 110.036823 -283.8064)
			(xy 110.032653 -283.856732) (xy 110.020256 -283.905691) (xy 109.999971 -283.951942) (xy 109.97235 -283.994224)
			(xy 109.938147 -284.031384) (xy 109.898295 -284.062408) (xy 109.85388 -284.08645) (xy 109.806114 -284.102855)
			(xy 109.7563 -284.111175) (xy 109.731048 -284.1117) (xy 108.790994 -284.1117) (xy 108.765738 -284.111194)
			(xy 108.715916 -284.102879) (xy 108.668142 -284.086477) (xy 108.623719 -284.062436) (xy 108.583859 -284.031411)
			(xy 108.549649 -283.994248) (xy 108.522022 -283.951962) (xy 108.501732 -283.905705) (xy 108.489332 -283.856739)
			(xy 108.485161 -283.8064) (xy 108.156248 -283.8064) (xy 108.155753 -283.830999) (xy 108.147858 -283.879576)
			(xy 108.132274 -283.926257) (xy 108.109403 -283.969834) (xy 108.079838 -284.009178) (xy 108.044345 -284.04327)
			(xy 108.003842 -284.071226) (xy 107.95938 -284.092324) (xy 107.912109 -284.106016) (xy 107.863254 -284.111948)
			(xy 107.814079 -284.109967) (xy 107.76586 -284.100123) (xy 107.719844 -284.082671) (xy 107.677223 -284.058064)
			(xy 107.639102 -284.026939) (xy 107.606467 -283.990102) (xy 107.580164 -283.948506) (xy 107.560873 -283.90323)
			(xy 107.549096 -283.855446) (xy 107.545136 -283.806392) (xy 105.33634 -283.806392) (xy 105.335845 -283.830999)
			(xy 105.32795 -283.879576) (xy 105.312366 -283.926257) (xy 105.289495 -283.969834) (xy 105.25993 -284.009178)
			(xy 105.224437 -284.04327) (xy 105.183934 -284.071226) (xy 105.139472 -284.092324) (xy 105.092201 -284.106016)
			(xy 105.043346 -284.111948) (xy 104.994171 -284.109967) (xy 104.945952 -284.100123) (xy 104.899936 -284.082671)
			(xy 104.857315 -284.058064) (xy 104.819194 -284.026939) (xy 104.786559 -283.990102) (xy 104.760256 -283.948506)
			(xy 104.740965 -283.90323) (xy 104.729188 -283.855446) (xy 104.725228 -283.806392) (xy 102.516432 -283.806392)
			(xy 102.515937 -283.830999) (xy 102.508042 -283.879576) (xy 102.492458 -283.926257) (xy 102.469587 -283.969834)
			(xy 102.440022 -284.009178) (xy 102.404529 -284.04327) (xy 102.364026 -284.071226) (xy 102.319564 -284.092324)
			(xy 102.272293 -284.106016) (xy 102.223438 -284.111948) (xy 102.174263 -284.109967) (xy 102.126044 -284.100123)
			(xy 102.080028 -284.082671) (xy 102.037407 -284.058064) (xy 101.999286 -284.026939) (xy 101.966651 -283.990102)
			(xy 101.940348 -283.948506) (xy 101.921057 -283.90323) (xy 101.90928 -283.855446) (xy 101.90532 -283.806392)
			(xy 99.69627 -283.806392) (xy 99.695775 -283.830999) (xy 99.68788 -283.879576) (xy 99.672296 -283.926257)
			(xy 99.649425 -283.969834) (xy 99.61986 -284.009178) (xy 99.584367 -284.04327) (xy 99.543864 -284.071226)
			(xy 99.499402 -284.092324) (xy 99.452131 -284.106016) (xy 99.403276 -284.111948) (xy 99.354101 -284.109967)
			(xy 99.305882 -284.100123) (xy 99.259866 -284.082671) (xy 99.217245 -284.058064) (xy 99.179124 -284.026939)
			(xy 99.146489 -283.990102) (xy 99.120186 -283.948506) (xy 99.100895 -283.90323) (xy 99.089118 -283.855446)
			(xy 99.085158 -283.806392) (xy 96.875938 -283.806392) (xy 96.875938 -283.831223) (xy 96.867905 -283.880218)
			(xy 96.852051 -283.927267) (xy 96.828794 -283.971131) (xy 96.798746 -284.010654) (xy 96.762699 -284.044795)
			(xy 96.721604 -284.072653) (xy 96.676542 -284.093496) (xy 96.628702 -284.106773) (xy 96.604074 -284.109922)
			(xy 96.60001 -284.11043) (xy 96.595374 -284.111406) (xy 96.586553 -284.114861) (xy 96.582484 -284.117288)
			(xy 96.572832 -284.125416) (xy 96.552258 -284.14726) (xy 96.546777 -284.153489) (xy 96.539774 -284.168519)
			(xy 96.538542 -284.176724) (xy 96.538288 -284.182312) (xy 96.538288 -284.261306) (xy 96.538542 -284.265624)
			(xy 96.539223 -284.271825) (xy 96.543205 -284.283644) (xy 96.546416 -284.288992) (xy 96.54794 -284.291024)
			(xy 96.560714 -284.308874) (xy 96.583728 -284.346256) (xy 96.593914 -284.3657) (xy 96.600036 -284.3779)
			(xy 96.611217 -284.402803) (xy 96.616266 -284.415484) (xy 96.616266 -284.415738) (xy 96.618896 -284.421925)
			(xy 96.626874 -284.432741) (xy 96.632014 -284.437074) (xy 96.637602 -284.441392) (xy 96.650302 -284.446472)
			(xy 96.712024 -284.454346) (xy 96.745552 -284.458664) (xy 96.755087 -284.459462) (xy 96.773623 -284.454771)
			(xy 96.78162 -284.44952) (xy 96.793304 -284.437836) (xy 96.795336 -284.434788) (xy 96.809867 -284.415957)
			(xy 96.843772 -284.382602) (xy 96.88243 -284.354895) (xy 96.92491 -284.333503) (xy 96.970188 -284.318941)
			(xy 97.017173 -284.31156) (xy 97.040954 -284.31109) (xy 97.066214 -284.311579) (xy 97.116047 -284.319888)
			(xy 97.163832 -284.336286) (xy 97.208266 -284.360327) (xy 97.248137 -284.391354) (xy 97.282356 -284.42852)
			(xy 97.309991 -284.470813) (xy 97.330286 -284.517078) (xy 97.34269 -284.566052) (xy 97.346862 -284.6164)
			(xy 97.674883 -284.6164) (xy 97.679059 -284.566014) (xy 97.69147 -284.517003) (xy 97.71178 -284.470702)
			(xy 97.739433 -284.428377) (xy 97.773676 -284.39118) (xy 97.813574 -284.360127) (xy 97.85804 -284.336064)
			(xy 97.905859 -284.319649) (xy 97.955729 -284.311328) (xy 97.981008 -284.310836) (xy 98.921062 -284.310836)
			(xy 98.946343 -284.31133) (xy 98.996215 -284.319647) (xy 99.044038 -284.336059) (xy 99.088508 -284.36012)
			(xy 99.12841 -284.391172) (xy 99.162656 -284.428369) (xy 99.190312 -284.470696) (xy 99.210624 -284.516998)
			(xy 99.223037 -284.566012) (xy 99.227213 -284.616398) (xy 99.555312 -284.616398) (xy 99.559272 -284.567344)
			(xy 99.571049 -284.51956) (xy 99.59034 -284.474284) (xy 99.616643 -284.432688) (xy 99.649278 -284.395851)
			(xy 99.687399 -284.364726) (xy 99.73002 -284.340119) (xy 99.776036 -284.322667) (xy 99.824255 -284.312823)
			(xy 99.87343 -284.310842) (xy 99.922285 -284.316774) (xy 99.969556 -284.330466) (xy 100.014018 -284.351564)
			(xy 100.054521 -284.37952) (xy 100.090014 -284.413612) (xy 100.119579 -284.452956) (xy 100.14245 -284.496533)
			(xy 100.158034 -284.543214) (xy 100.165929 -284.591791) (xy 100.166424 -284.616398) (xy 100.166424 -284.6164)
			(xy 100.495112 -284.6164) (xy 100.499287 -284.566023) (xy 100.511695 -284.51702) (xy 100.532 -284.470727)
			(xy 100.559646 -284.428407) (xy 100.593881 -284.391215) (xy 100.63377 -284.360164) (xy 100.678226 -284.336102)
			(xy 100.726035 -284.319685) (xy 100.775895 -284.31136) (xy 100.80117 -284.310836) (xy 101.741224 -284.310836)
			(xy 101.766499 -284.311364) (xy 101.816359 -284.319688) (xy 101.864169 -284.336104) (xy 101.908625 -284.360165)
			(xy 101.948514 -284.391216) (xy 101.982749 -284.428408) (xy 102.010396 -284.470727) (xy 102.030701 -284.51702)
			(xy 102.043109 -284.566023) (xy 102.047284 -284.616398) (xy 102.37522 -284.616398) (xy 102.37918 -284.567344)
			(xy 102.390957 -284.51956) (xy 102.410248 -284.474284) (xy 102.436551 -284.432688) (xy 102.469186 -284.395851)
			(xy 102.507307 -284.364726) (xy 102.549928 -284.340119) (xy 102.595944 -284.322667) (xy 102.644163 -284.312823)
			(xy 102.693338 -284.310842) (xy 102.742193 -284.316774) (xy 102.789464 -284.330466) (xy 102.833926 -284.351564)
			(xy 102.874429 -284.37952) (xy 102.909922 -284.413612) (xy 102.939487 -284.452956) (xy 102.962358 -284.496533)
			(xy 102.977942 -284.543214) (xy 102.985837 -284.591791) (xy 102.986332 -284.616398) (xy 102.986332 -284.6164)
			(xy 103.315012 -284.6164) (xy 103.319187 -284.566022) (xy 103.331596 -284.517018) (xy 103.351901 -284.470725)
			(xy 103.379548 -284.428404) (xy 103.413784 -284.391212) (xy 103.453674 -284.360161) (xy 103.498131 -284.3361)
			(xy 103.545942 -284.319683) (xy 103.595803 -284.31136) (xy 103.621078 -284.310836) (xy 104.561132 -284.310836)
			(xy 104.586406 -284.311364) (xy 104.636265 -284.319689) (xy 104.684074 -284.336106) (xy 104.728529 -284.360168)
			(xy 104.768417 -284.391218) (xy 104.802651 -284.42841) (xy 104.830297 -284.470729) (xy 104.850601 -284.517021)
			(xy 104.863009 -284.566024) (xy 104.867184 -284.616398) (xy 105.195128 -284.616398) (xy 105.199088 -284.567344)
			(xy 105.210865 -284.51956) (xy 105.230156 -284.474284) (xy 105.256459 -284.432688) (xy 105.289094 -284.395851)
			(xy 105.327215 -284.364726) (xy 105.369836 -284.340119) (xy 105.415852 -284.322667) (xy 105.464071 -284.312823)
			(xy 105.513246 -284.310842) (xy 105.562101 -284.316774) (xy 105.609372 -284.330466) (xy 105.653834 -284.351564)
			(xy 105.694337 -284.37952) (xy 105.72983 -284.413612) (xy 105.759395 -284.452956) (xy 105.782266 -284.496533)
			(xy 105.79785 -284.543214) (xy 105.805745 -284.591791) (xy 105.80624 -284.616398) (xy 105.80624 -284.6164)
			(xy 106.134912 -284.6164) (xy 106.139087 -284.566021) (xy 106.151496 -284.517016) (xy 106.171802 -284.470722)
			(xy 106.19945 -284.428402) (xy 106.233687 -284.391209) (xy 106.273579 -284.360159) (xy 106.318037 -284.336097)
			(xy 106.365849 -284.319682) (xy 106.41571 -284.311359) (xy 106.440986 -284.310836) (xy 107.38104 -284.310836)
			(xy 107.406314 -284.311365) (xy 107.456172 -284.319691) (xy 107.503979 -284.336109) (xy 107.548433 -284.360171)
			(xy 107.58832 -284.391221) (xy 107.622553 -284.428413) (xy 107.650198 -284.470731) (xy 107.670502 -284.517023)
			(xy 107.68291 -284.566024) (xy 107.687084 -284.616398) (xy 108.01529 -284.616398) (xy 108.01925 -284.567344)
			(xy 108.031027 -284.51956) (xy 108.050318 -284.474284) (xy 108.076621 -284.432688) (xy 108.109256 -284.395851)
			(xy 108.147377 -284.364726) (xy 108.189998 -284.340119) (xy 108.236014 -284.322667) (xy 108.284233 -284.312823)
			(xy 108.333408 -284.310842) (xy 108.382263 -284.316774) (xy 108.429534 -284.330466) (xy 108.473996 -284.351564)
			(xy 108.514499 -284.37952) (xy 108.549992 -284.413612) (xy 108.579557 -284.452956) (xy 108.602428 -284.496533)
			(xy 108.618012 -284.543214) (xy 108.625907 -284.591791) (xy 108.626402 -284.616398) (xy 108.955344 -284.616398)
			(xy 108.959304 -284.567344) (xy 108.971081 -284.51956) (xy 108.990372 -284.474284) (xy 109.016675 -284.432688)
			(xy 109.04931 -284.395851) (xy 109.087431 -284.364726) (xy 109.130052 -284.340119) (xy 109.176068 -284.322667)
			(xy 109.224287 -284.312823) (xy 109.273462 -284.310842) (xy 109.322317 -284.316774) (xy 109.369588 -284.330466)
			(xy 109.41405 -284.351564) (xy 109.454553 -284.37952) (xy 109.490046 -284.413612) (xy 109.519611 -284.452956)
			(xy 109.542482 -284.496533) (xy 109.558066 -284.543214) (xy 109.565961 -284.591791) (xy 109.566456 -284.616398)
			(xy 109.895144 -284.616398) (xy 109.899104 -284.567344) (xy 109.910881 -284.51956) (xy 109.930172 -284.474284)
			(xy 109.956475 -284.432688) (xy 109.98911 -284.395851) (xy 110.027231 -284.364726) (xy 110.069852 -284.340119)
			(xy 110.115868 -284.322667) (xy 110.164087 -284.312823) (xy 110.213262 -284.310842) (xy 110.262117 -284.316774)
			(xy 110.309388 -284.330466) (xy 110.35385 -284.351564) (xy 110.394353 -284.37952) (xy 110.429846 -284.413612)
			(xy 110.459411 -284.452956) (xy 110.482282 -284.496533) (xy 110.497866 -284.543214) (xy 110.505761 -284.591791)
			(xy 110.506256 -284.616398) (xy 113.64901 -284.616398) (xy 113.65297 -284.567344) (xy 113.664747 -284.51956)
			(xy 113.684038 -284.474284) (xy 113.710341 -284.432688) (xy 113.742976 -284.395851) (xy 113.781097 -284.364726)
			(xy 113.823718 -284.340119) (xy 113.869734 -284.322667) (xy 113.917953 -284.312823) (xy 113.967128 -284.310842)
			(xy 114.015983 -284.316774) (xy 114.063254 -284.330466) (xy 114.107716 -284.351564) (xy 114.148219 -284.37952)
			(xy 114.183712 -284.413612) (xy 114.213277 -284.452956) (xy 114.236148 -284.496533) (xy 114.251732 -284.543214)
			(xy 114.259627 -284.591791) (xy 114.260122 -284.616398) (xy 114.58881 -284.616398) (xy 114.59277 -284.567344)
			(xy 114.604547 -284.51956) (xy 114.623838 -284.474284) (xy 114.650141 -284.432688) (xy 114.682776 -284.395851)
			(xy 114.720897 -284.364726) (xy 114.763518 -284.340119) (xy 114.809534 -284.322667) (xy 114.857753 -284.312823)
			(xy 114.906928 -284.310842) (xy 114.955783 -284.316774) (xy 115.003054 -284.330466) (xy 115.047516 -284.351564)
			(xy 115.088019 -284.37952) (xy 115.123512 -284.413612) (xy 115.153077 -284.452956) (xy 115.175948 -284.496533)
			(xy 115.191532 -284.543214) (xy 115.199427 -284.591791) (xy 115.199922 -284.616398) (xy 115.528864 -284.616398)
			(xy 115.532824 -284.567344) (xy 115.544601 -284.51956) (xy 115.563892 -284.474284) (xy 115.590195 -284.432688)
			(xy 115.62283 -284.395851) (xy 115.660951 -284.364726) (xy 115.703572 -284.340119) (xy 115.749588 -284.322667)
			(xy 115.797807 -284.312823) (xy 115.846982 -284.310842) (xy 115.895837 -284.316774) (xy 115.943108 -284.330466)
			(xy 115.98757 -284.351564) (xy 116.028073 -284.37952) (xy 116.063566 -284.413612) (xy 116.093131 -284.452956)
			(xy 116.116002 -284.496533) (xy 116.131586 -284.543214) (xy 116.139481 -284.591791) (xy 116.139976 -284.616398)
			(xy 116.139976 -284.6164) (xy 116.468583 -284.6164) (xy 116.472759 -284.566013) (xy 116.485171 -284.517)
			(xy 116.505482 -284.470699) (xy 116.533137 -284.428372) (xy 116.567381 -284.391175) (xy 116.607282 -284.360122)
			(xy 116.651749 -284.33606) (xy 116.699571 -284.319646) (xy 116.749442 -284.311327) (xy 116.774722 -284.310836)
			(xy 117.714776 -284.310836) (xy 117.740056 -284.311331) (xy 117.789927 -284.319649) (xy 117.837748 -284.336063)
			(xy 117.882215 -284.360125) (xy 117.922115 -284.391177) (xy 117.95636 -284.428374) (xy 117.984014 -284.4707)
			(xy 118.004325 -284.517001) (xy 118.016737 -284.566013) (xy 118.020913 -284.616398) (xy 118.349026 -284.616398)
			(xy 118.352986 -284.567344) (xy 118.364763 -284.51956) (xy 118.384054 -284.474284) (xy 118.410357 -284.432688)
			(xy 118.442992 -284.395851) (xy 118.481113 -284.364726) (xy 118.523734 -284.340119) (xy 118.56975 -284.322667)
			(xy 118.617969 -284.312823) (xy 118.667144 -284.310842) (xy 118.715999 -284.316774) (xy 118.76327 -284.330466)
			(xy 118.807732 -284.351564) (xy 118.848235 -284.37952) (xy 118.883728 -284.413612) (xy 118.913293 -284.452956)
			(xy 118.936164 -284.496533) (xy 118.951748 -284.543214) (xy 118.959643 -284.591791) (xy 118.960138 -284.616398)
			(xy 118.960138 -284.6164) (xy 119.288483 -284.6164) (xy 119.292659 -284.566012) (xy 119.305072 -284.516998)
			(xy 119.325383 -284.470696) (xy 119.353039 -284.428369) (xy 119.387285 -284.391172) (xy 119.427186 -284.360119)
			(xy 119.471655 -284.336058) (xy 119.519477 -284.319644) (xy 119.569349 -284.311327) (xy 119.59463 -284.310836)
			(xy 120.534684 -284.310836) (xy 120.559963 -284.311332) (xy 120.609833 -284.319651) (xy 120.657653 -284.336066)
			(xy 120.702119 -284.360127) (xy 120.742018 -284.39118) (xy 120.776262 -284.428376) (xy 120.803915 -284.470702)
			(xy 120.824225 -284.517002) (xy 120.836637 -284.566014) (xy 120.840813 -284.616398) (xy 121.168934 -284.616398)
			(xy 121.172894 -284.567344) (xy 121.184671 -284.51956) (xy 121.203962 -284.474284) (xy 121.230265 -284.432688)
			(xy 121.2629 -284.395851) (xy 121.301021 -284.364726) (xy 121.343642 -284.340119) (xy 121.389658 -284.322667)
			(xy 121.437877 -284.312823) (xy 121.487052 -284.310842) (xy 121.535907 -284.316774) (xy 121.583178 -284.330466)
			(xy 121.62764 -284.351564) (xy 121.668143 -284.37952) (xy 121.703636 -284.413612) (xy 121.733201 -284.452956)
			(xy 121.756072 -284.496533) (xy 121.771656 -284.543214) (xy 121.779551 -284.591791) (xy 121.780046 -284.616398)
			(xy 121.780046 -284.6164) (xy 122.108712 -284.6164) (xy 122.112887 -284.56602) (xy 122.125297 -284.517015)
			(xy 122.145603 -284.470721) (xy 122.173252 -284.4284) (xy 122.207489 -284.391207) (xy 122.247382 -284.360157)
			(xy 122.291841 -284.336096) (xy 122.339653 -284.31968) (xy 122.389516 -284.311359) (xy 122.414792 -284.310836)
			(xy 123.354846 -284.310836) (xy 123.38012 -284.311366) (xy 123.429977 -284.319692) (xy 123.477783 -284.336111)
			(xy 123.522236 -284.360173) (xy 123.562123 -284.391223) (xy 123.596355 -284.428415) (xy 123.623999 -284.470733)
			(xy 123.644302 -284.517024) (xy 123.65671 -284.566025) (xy 123.660884 -284.616398) (xy 123.988842 -284.616398)
			(xy 123.992802 -284.567344) (xy 124.004579 -284.51956) (xy 124.02387 -284.474284) (xy 124.050173 -284.432688)
			(xy 124.082808 -284.395851) (xy 124.120929 -284.364726) (xy 124.16355 -284.340119) (xy 124.209566 -284.322667)
			(xy 124.257785 -284.312823) (xy 124.30696 -284.310842) (xy 124.355815 -284.316774) (xy 124.403086 -284.330466)
			(xy 124.447548 -284.351564) (xy 124.488051 -284.37952) (xy 124.523544 -284.413612) (xy 124.553109 -284.452956)
			(xy 124.57598 -284.496533) (xy 124.591564 -284.543214) (xy 124.599459 -284.591791) (xy 124.599954 -284.616398)
			(xy 124.599954 -284.6164) (xy 124.928613 -284.6164) (xy 124.932787 -284.56602) (xy 124.945197 -284.517014)
			(xy 124.965504 -284.470718) (xy 124.993154 -284.428397) (xy 125.027393 -284.391204) (xy 125.067286 -284.360154)
			(xy 125.111746 -284.336093) (xy 125.15956 -284.319679) (xy 125.209423 -284.311358) (xy 125.2347 -284.310836)
			(xy 126.174754 -284.310836) (xy 126.200035 -284.311329) (xy 126.249909 -284.319645) (xy 126.297733 -284.336057)
			(xy 126.342203 -284.360117) (xy 126.382107 -284.391169) (xy 126.416354 -284.428366) (xy 126.444011 -284.470694)
			(xy 126.464323 -284.516996) (xy 126.476737 -284.566011) (xy 126.480913 -284.6164) (xy 126.476737 -284.666789)
			(xy 126.464323 -284.715804) (xy 126.444011 -284.762106) (xy 126.416354 -284.804434) (xy 126.382107 -284.841631)
			(xy 126.342203 -284.872683) (xy 126.297733 -284.896743) (xy 126.249909 -284.913155) (xy 126.200035 -284.921471)
			(xy 126.174754 -284.92196) (xy 125.2347 -284.92196) (xy 125.209423 -284.921442) (xy 125.15956 -284.913121)
			(xy 125.111746 -284.896707) (xy 125.067286 -284.872646) (xy 125.027393 -284.841596) (xy 124.993154 -284.804403)
			(xy 124.965504 -284.762082) (xy 124.945197 -284.715786) (xy 124.932787 -284.66678) (xy 124.928613 -284.6164)
			(xy 124.599954 -284.6164) (xy 124.599459 -284.641005) (xy 124.591564 -284.689582) (xy 124.57598 -284.736263)
			(xy 124.553109 -284.77984) (xy 124.523544 -284.819184) (xy 124.488051 -284.853276) (xy 124.447548 -284.881232)
			(xy 124.403086 -284.90233) (xy 124.355815 -284.916022) (xy 124.30696 -284.921954) (xy 124.257785 -284.919973)
			(xy 124.209566 -284.910129) (xy 124.16355 -284.892677) (xy 124.120929 -284.86807) (xy 124.082808 -284.836945)
			(xy 124.050173 -284.800108) (xy 124.02387 -284.758512) (xy 124.004579 -284.713236) (xy 123.992802 -284.665452)
			(xy 123.988842 -284.616398) (xy 123.660884 -284.616398) (xy 123.660884 -284.6164) (xy 123.65671 -284.666775)
			(xy 123.644302 -284.715776) (xy 123.623999 -284.762067) (xy 123.596355 -284.804385) (xy 123.562123 -284.841577)
			(xy 123.522236 -284.872627) (xy 123.477783 -284.896689) (xy 123.429977 -284.913108) (xy 123.38012 -284.921434)
			(xy 123.354846 -284.92196) (xy 122.414792 -284.92196) (xy 122.389516 -284.921441) (xy 122.339653 -284.91312)
			(xy 122.291841 -284.896704) (xy 122.247382 -284.872643) (xy 122.207489 -284.841593) (xy 122.173252 -284.8044)
			(xy 122.145603 -284.762079) (xy 122.125297 -284.715785) (xy 122.112887 -284.66678) (xy 122.108712 -284.6164)
			(xy 121.780046 -284.6164) (xy 121.779551 -284.641005) (xy 121.771656 -284.689582) (xy 121.756072 -284.736263)
			(xy 121.733201 -284.77984) (xy 121.703636 -284.819184) (xy 121.668143 -284.853276) (xy 121.62764 -284.881232)
			(xy 121.583178 -284.90233) (xy 121.535907 -284.916022) (xy 121.487052 -284.921954) (xy 121.437877 -284.919973)
			(xy 121.389658 -284.910129) (xy 121.343642 -284.892677) (xy 121.301021 -284.86807) (xy 121.2629 -284.836945)
			(xy 121.230265 -284.800108) (xy 121.203962 -284.758512) (xy 121.184671 -284.713236) (xy 121.172894 -284.665452)
			(xy 121.168934 -284.616398) (xy 120.840813 -284.616398) (xy 120.840813 -284.6164) (xy 120.836637 -284.666786)
			(xy 120.824225 -284.715798) (xy 120.803915 -284.762098) (xy 120.776262 -284.804424) (xy 120.742018 -284.84162)
			(xy 120.702119 -284.872673) (xy 120.657653 -284.896734) (xy 120.609833 -284.913149) (xy 120.559963 -284.921468)
			(xy 120.534684 -284.92196) (xy 119.59463 -284.92196) (xy 119.569349 -284.921473) (xy 119.519477 -284.913156)
			(xy 119.471655 -284.896742) (xy 119.427186 -284.872681) (xy 119.387285 -284.841628) (xy 119.353039 -284.804431)
			(xy 119.325383 -284.762104) (xy 119.305072 -284.715802) (xy 119.292659 -284.666788) (xy 119.288483 -284.6164)
			(xy 118.960138 -284.6164) (xy 118.959643 -284.641005) (xy 118.951748 -284.689582) (xy 118.936164 -284.736263)
			(xy 118.913293 -284.77984) (xy 118.883728 -284.819184) (xy 118.848235 -284.853276) (xy 118.807732 -284.881232)
			(xy 118.76327 -284.90233) (xy 118.715999 -284.916022) (xy 118.667144 -284.921954) (xy 118.617969 -284.919973)
			(xy 118.56975 -284.910129) (xy 118.523734 -284.892677) (xy 118.481113 -284.86807) (xy 118.442992 -284.836945)
			(xy 118.410357 -284.800108) (xy 118.384054 -284.758512) (xy 118.364763 -284.713236) (xy 118.352986 -284.665452)
			(xy 118.349026 -284.616398) (xy 118.020913 -284.616398) (xy 118.020913 -284.6164) (xy 118.016737 -284.666787)
			(xy 118.004325 -284.715799) (xy 117.984014 -284.7621) (xy 117.95636 -284.804426) (xy 117.922115 -284.841623)
			(xy 117.882215 -284.872675) (xy 117.837748 -284.896737) (xy 117.789927 -284.913151) (xy 117.740056 -284.921469)
			(xy 117.714776 -284.92196) (xy 116.774722 -284.92196) (xy 116.749442 -284.921473) (xy 116.699571 -284.913154)
			(xy 116.651749 -284.89674) (xy 116.607282 -284.872678) (xy 116.567381 -284.841625) (xy 116.533137 -284.804428)
			(xy 116.505482 -284.762101) (xy 116.485171 -284.7158) (xy 116.472759 -284.666787) (xy 116.468583 -284.6164)
			(xy 116.139976 -284.6164) (xy 116.139481 -284.641005) (xy 116.131586 -284.689582) (xy 116.116002 -284.736263)
			(xy 116.093131 -284.77984) (xy 116.063566 -284.819184) (xy 116.028073 -284.853276) (xy 115.98757 -284.881232)
			(xy 115.943108 -284.90233) (xy 115.895837 -284.916022) (xy 115.846982 -284.921954) (xy 115.797807 -284.919973)
			(xy 115.749588 -284.910129) (xy 115.703572 -284.892677) (xy 115.660951 -284.86807) (xy 115.62283 -284.836945)
			(xy 115.590195 -284.800108) (xy 115.563892 -284.758512) (xy 115.544601 -284.713236) (xy 115.532824 -284.665452)
			(xy 115.528864 -284.616398) (xy 115.199922 -284.616398) (xy 115.199427 -284.641005) (xy 115.191532 -284.689582)
			(xy 115.175948 -284.736263) (xy 115.153077 -284.77984) (xy 115.123512 -284.819184) (xy 115.088019 -284.853276)
			(xy 115.047516 -284.881232) (xy 115.003054 -284.90233) (xy 114.955783 -284.916022) (xy 114.906928 -284.921954)
			(xy 114.857753 -284.919973) (xy 114.809534 -284.910129) (xy 114.763518 -284.892677) (xy 114.720897 -284.86807)
			(xy 114.682776 -284.836945) (xy 114.650141 -284.800108) (xy 114.623838 -284.758512) (xy 114.604547 -284.713236)
			(xy 114.59277 -284.665452) (xy 114.58881 -284.616398) (xy 114.260122 -284.616398) (xy 114.259627 -284.641005)
			(xy 114.251732 -284.689582) (xy 114.236148 -284.736263) (xy 114.213277 -284.77984) (xy 114.183712 -284.819184)
			(xy 114.148219 -284.853276) (xy 114.107716 -284.881232) (xy 114.063254 -284.90233) (xy 114.015983 -284.916022)
			(xy 113.967128 -284.921954) (xy 113.917953 -284.919973) (xy 113.869734 -284.910129) (xy 113.823718 -284.892677)
			(xy 113.781097 -284.86807) (xy 113.742976 -284.836945) (xy 113.710341 -284.800108) (xy 113.684038 -284.758512)
			(xy 113.664747 -284.713236) (xy 113.65297 -284.665452) (xy 113.64901 -284.616398) (xy 110.506256 -284.616398)
			(xy 110.505761 -284.641005) (xy 110.497866 -284.689582) (xy 110.482282 -284.736263) (xy 110.459411 -284.77984)
			(xy 110.429846 -284.819184) (xy 110.394353 -284.853276) (xy 110.35385 -284.881232) (xy 110.309388 -284.90233)
			(xy 110.262117 -284.916022) (xy 110.213262 -284.921954) (xy 110.164087 -284.919973) (xy 110.115868 -284.910129)
			(xy 110.069852 -284.892677) (xy 110.027231 -284.86807) (xy 109.98911 -284.836945) (xy 109.956475 -284.800108)
			(xy 109.930172 -284.758512) (xy 109.910881 -284.713236) (xy 109.899104 -284.665452) (xy 109.895144 -284.616398)
			(xy 109.566456 -284.616398) (xy 109.565961 -284.641005) (xy 109.558066 -284.689582) (xy 109.542482 -284.736263)
			(xy 109.519611 -284.77984) (xy 109.490046 -284.819184) (xy 109.454553 -284.853276) (xy 109.41405 -284.881232)
			(xy 109.369588 -284.90233) (xy 109.322317 -284.916022) (xy 109.273462 -284.921954) (xy 109.224287 -284.919973)
			(xy 109.176068 -284.910129) (xy 109.130052 -284.892677) (xy 109.087431 -284.86807) (xy 109.04931 -284.836945)
			(xy 109.016675 -284.800108) (xy 108.990372 -284.758512) (xy 108.971081 -284.713236) (xy 108.959304 -284.665452)
			(xy 108.955344 -284.616398) (xy 108.626402 -284.616398) (xy 108.625907 -284.641005) (xy 108.618012 -284.689582)
			(xy 108.602428 -284.736263) (xy 108.579557 -284.77984) (xy 108.549992 -284.819184) (xy 108.514499 -284.853276)
			(xy 108.473996 -284.881232) (xy 108.429534 -284.90233) (xy 108.382263 -284.916022) (xy 108.333408 -284.921954)
			(xy 108.284233 -284.919973) (xy 108.236014 -284.910129) (xy 108.189998 -284.892677) (xy 108.147377 -284.86807)
			(xy 108.109256 -284.836945) (xy 108.076621 -284.800108) (xy 108.050318 -284.758512) (xy 108.031027 -284.713236)
			(xy 108.01925 -284.665452) (xy 108.01529 -284.616398) (xy 107.687084 -284.616398) (xy 107.687084 -284.6164)
			(xy 107.68291 -284.666776) (xy 107.670502 -284.715777) (xy 107.650198 -284.762069) (xy 107.622553 -284.804387)
			(xy 107.58832 -284.841579) (xy 107.548433 -284.872629) (xy 107.503979 -284.896691) (xy 107.456172 -284.913109)
			(xy 107.406314 -284.921435) (xy 107.38104 -284.92196) (xy 106.440986 -284.92196) (xy 106.41571 -284.921441)
			(xy 106.365849 -284.913118) (xy 106.318037 -284.896703) (xy 106.273579 -284.872641) (xy 106.233687 -284.841591)
			(xy 106.19945 -284.804398) (xy 106.171802 -284.762078) (xy 106.151496 -284.715784) (xy 106.139087 -284.666779)
			(xy 106.134912 -284.6164) (xy 105.80624 -284.6164) (xy 105.805745 -284.641005) (xy 105.79785 -284.689582)
			(xy 105.782266 -284.736263) (xy 105.759395 -284.77984) (xy 105.72983 -284.819184) (xy 105.694337 -284.853276)
			(xy 105.653834 -284.881232) (xy 105.609372 -284.90233) (xy 105.562101 -284.916022) (xy 105.513246 -284.921954)
			(xy 105.464071 -284.919973) (xy 105.415852 -284.910129) (xy 105.369836 -284.892677) (xy 105.327215 -284.86807)
			(xy 105.289094 -284.836945) (xy 105.256459 -284.800108) (xy 105.230156 -284.758512) (xy 105.210865 -284.713236)
			(xy 105.199088 -284.665452) (xy 105.195128 -284.616398) (xy 104.867184 -284.616398) (xy 104.867184 -284.6164)
			(xy 104.863009 -284.666776) (xy 104.850601 -284.715779) (xy 104.830297 -284.762071) (xy 104.802651 -284.80439)
			(xy 104.768417 -284.841582) (xy 104.728529 -284.872632) (xy 104.684074 -284.896694) (xy 104.636265 -284.913111)
			(xy 104.586406 -284.921436) (xy 104.561132 -284.92196) (xy 103.621078 -284.92196) (xy 103.595803 -284.92144)
			(xy 103.545942 -284.913117) (xy 103.498131 -284.8967) (xy 103.453674 -284.872639) (xy 103.413784 -284.841588)
			(xy 103.379548 -284.804396) (xy 103.351901 -284.762075) (xy 103.331596 -284.715782) (xy 103.319187 -284.666778)
			(xy 103.315012 -284.6164) (xy 102.986332 -284.6164) (xy 102.985837 -284.641005) (xy 102.977942 -284.689582)
			(xy 102.962358 -284.736263) (xy 102.939487 -284.77984) (xy 102.909922 -284.819184) (xy 102.874429 -284.853276)
			(xy 102.833926 -284.881232) (xy 102.789464 -284.90233) (xy 102.742193 -284.916022) (xy 102.693338 -284.921954)
			(xy 102.644163 -284.919973) (xy 102.595944 -284.910129) (xy 102.549928 -284.892677) (xy 102.507307 -284.86807)
			(xy 102.469186 -284.836945) (xy 102.436551 -284.800108) (xy 102.410248 -284.758512) (xy 102.390957 -284.713236)
			(xy 102.37918 -284.665452) (xy 102.37522 -284.616398) (xy 102.047284 -284.616398) (xy 102.047284 -284.6164)
			(xy 102.043109 -284.666777) (xy 102.030701 -284.71578) (xy 102.010396 -284.762073) (xy 101.982749 -284.804392)
			(xy 101.948514 -284.841584) (xy 101.908625 -284.872635) (xy 101.864169 -284.896696) (xy 101.816359 -284.913112)
			(xy 101.766499 -284.921436) (xy 101.741224 -284.92196) (xy 100.80117 -284.92196) (xy 100.775895 -284.92144)
			(xy 100.726035 -284.913115) (xy 100.678226 -284.896698) (xy 100.63377 -284.872636) (xy 100.593881 -284.841585)
			(xy 100.559646 -284.804393) (xy 100.532 -284.762073) (xy 100.511695 -284.71578) (xy 100.499287 -284.666777)
			(xy 100.495112 -284.6164) (xy 100.166424 -284.6164) (xy 100.165929 -284.641005) (xy 100.158034 -284.689582)
			(xy 100.14245 -284.736263) (xy 100.119579 -284.77984) (xy 100.090014 -284.819184) (xy 100.054521 -284.853276)
			(xy 100.014018 -284.881232) (xy 99.969556 -284.90233) (xy 99.922285 -284.916022) (xy 99.87343 -284.921954)
			(xy 99.824255 -284.919973) (xy 99.776036 -284.910129) (xy 99.73002 -284.892677) (xy 99.687399 -284.86807)
			(xy 99.649278 -284.836945) (xy 99.616643 -284.800108) (xy 99.59034 -284.758512) (xy 99.571049 -284.713236)
			(xy 99.559272 -284.665452) (xy 99.555312 -284.616398) (xy 99.227213 -284.616398) (xy 99.227213 -284.6164)
			(xy 99.223037 -284.666788) (xy 99.210624 -284.715802) (xy 99.190312 -284.762104) (xy 99.162656 -284.804431)
			(xy 99.12841 -284.841628) (xy 99.088508 -284.87268) (xy 99.044038 -284.896741) (xy 98.996215 -284.913153)
			(xy 98.946343 -284.92147) (xy 98.921062 -284.92196) (xy 97.981008 -284.92196) (xy 97.955729 -284.921472)
			(xy 97.905859 -284.913151) (xy 97.85804 -284.896736) (xy 97.813574 -284.872673) (xy 97.773676 -284.84162)
			(xy 97.739433 -284.804423) (xy 97.71178 -284.762098) (xy 97.69147 -284.715797) (xy 97.679059 -284.666786)
			(xy 97.674883 -284.6164) (xy 97.346862 -284.6164) (xy 97.34269 -284.666748) (xy 97.330286 -284.715722)
			(xy 97.309991 -284.761987) (xy 97.282356 -284.80428) (xy 97.248137 -284.841446) (xy 97.208266 -284.872473)
			(xy 97.163832 -284.896514) (xy 97.116047 -284.912912) (xy 97.066214 -284.921221) (xy 97.040954 -284.921706)
			(xy 97.01717 -284.921257) (xy 96.970176 -284.913895) (xy 96.924889 -284.899341) (xy 96.882405 -284.877946)
			(xy 96.843748 -284.850227) (xy 96.809853 -284.816852) (xy 96.795336 -284.798008) (xy 96.793304 -284.79496)
			(xy 96.78162 -284.783276) (xy 96.773632 -284.777999) (xy 96.755089 -284.773298) (xy 96.745552 -284.774132)
			(xy 96.712024 -284.77845) (xy 96.65716 -284.785308) (xy 96.650329 -284.78645) (xy 96.637589 -284.791866)
			(xy 96.632014 -284.795976) (xy 96.62668 -284.80004) (xy 96.618806 -284.810708) (xy 96.616266 -284.817312)
			(xy 96.610799 -284.83105) (xy 96.598597 -284.857987) (xy 96.591882 -284.87116) (xy 96.579182 -284.89402)
			(xy 96.543876 -284.954726) (xy 96.541499 -284.959621) (xy 96.538672 -284.970126) (xy 96.538288 -284.975554)
			(xy 96.538288 -285.050484) (xy 96.538542 -285.056072) (xy 96.539776 -285.064277) (xy 96.546776 -285.079308)
			(xy 96.552258 -285.085536) (xy 96.572832 -285.10738) (xy 96.582484 -285.115508) (xy 96.586561 -285.11792)
			(xy 96.595378 -285.121375) (xy 96.60001 -285.122366) (xy 96.604074 -285.122874) (xy 96.6287 -285.126038)
			(xy 96.676538 -285.139315) (xy 96.721597 -285.160157) (xy 96.762691 -285.188014) (xy 96.798737 -285.222154)
			(xy 96.828783 -285.261675) (xy 96.85204 -285.305538) (xy 96.867893 -285.352585) (xy 96.875926 -285.401577)
			(xy 96.875926 -285.426404) (xy 97.205304 -285.426404) (xy 97.209264 -285.37735) (xy 97.221041 -285.329566)
			(xy 97.240332 -285.28429) (xy 97.266635 -285.242694) (xy 97.29927 -285.205857) (xy 97.337391 -285.174732)
			(xy 97.380012 -285.150125) (xy 97.426028 -285.132673) (xy 97.474247 -285.122829) (xy 97.523422 -285.120848)
			(xy 97.572277 -285.12678) (xy 97.619548 -285.140472) (xy 97.66401 -285.16157) (xy 97.704513 -285.189526)
			(xy 97.740006 -285.223618) (xy 97.769571 -285.262962) (xy 97.792442 -285.306539) (xy 97.808026 -285.35322)
			(xy 97.815921 -285.401797) (xy 97.816416 -285.426404) (xy 98.145358 -285.426404) (xy 98.149318 -285.37735)
			(xy 98.161095 -285.329566) (xy 98.180386 -285.28429) (xy 98.206689 -285.242694) (xy 98.239324 -285.205857)
			(xy 98.277445 -285.174732) (xy 98.320066 -285.150125) (xy 98.366082 -285.132673) (xy 98.414301 -285.122829)
			(xy 98.463476 -285.120848) (xy 98.512331 -285.12678) (xy 98.559602 -285.140472) (xy 98.604064 -285.16157)
			(xy 98.644567 -285.189526) (xy 98.68006 -285.223618) (xy 98.709625 -285.262962) (xy 98.732496 -285.306539)
			(xy 98.74808 -285.35322) (xy 98.755975 -285.401797) (xy 98.75647 -285.426404) (xy 99.085158 -285.426404)
			(xy 99.089118 -285.37735) (xy 99.100895 -285.329566) (xy 99.120186 -285.28429) (xy 99.146489 -285.242694)
			(xy 99.179124 -285.205857) (xy 99.217245 -285.174732) (xy 99.259866 -285.150125) (xy 99.305882 -285.132673)
			(xy 99.354101 -285.122829) (xy 99.403276 -285.120848) (xy 99.452131 -285.12678) (xy 99.499402 -285.140472)
			(xy 99.543864 -285.16157) (xy 99.584367 -285.189526) (xy 99.61986 -285.223618) (xy 99.649425 -285.262962)
			(xy 99.672296 -285.306539) (xy 99.68788 -285.35322) (xy 99.695775 -285.401797) (xy 99.69627 -285.426404)
			(xy 100.025212 -285.426404) (xy 100.029172 -285.37735) (xy 100.040949 -285.329566) (xy 100.06024 -285.28429)
			(xy 100.086543 -285.242694) (xy 100.119178 -285.205857) (xy 100.157299 -285.174732) (xy 100.19992 -285.150125)
			(xy 100.245936 -285.132673) (xy 100.294155 -285.122829) (xy 100.34333 -285.120848) (xy 100.392185 -285.12678)
			(xy 100.439456 -285.140472) (xy 100.483918 -285.16157) (xy 100.524421 -285.189526) (xy 100.559914 -285.223618)
			(xy 100.589479 -285.262962) (xy 100.61235 -285.306539) (xy 100.627934 -285.35322) (xy 100.635829 -285.401797)
			(xy 100.636324 -285.426404) (xy 100.965266 -285.426404) (xy 100.969226 -285.37735) (xy 100.981003 -285.329566)
			(xy 101.000294 -285.28429) (xy 101.026597 -285.242694) (xy 101.059232 -285.205857) (xy 101.097353 -285.174732)
			(xy 101.139974 -285.150125) (xy 101.18599 -285.132673) (xy 101.234209 -285.122829) (xy 101.283384 -285.120848)
			(xy 101.332239 -285.12678) (xy 101.37951 -285.140472) (xy 101.423972 -285.16157) (xy 101.464475 -285.189526)
			(xy 101.499968 -285.223618) (xy 101.529533 -285.262962) (xy 101.552404 -285.306539) (xy 101.567988 -285.35322)
			(xy 101.575883 -285.401797) (xy 101.576378 -285.426404) (xy 101.90532 -285.426404) (xy 101.90928 -285.37735)
			(xy 101.921057 -285.329566) (xy 101.940348 -285.28429) (xy 101.966651 -285.242694) (xy 101.999286 -285.205857)
			(xy 102.037407 -285.174732) (xy 102.080028 -285.150125) (xy 102.126044 -285.132673) (xy 102.174263 -285.122829)
			(xy 102.223438 -285.120848) (xy 102.272293 -285.12678) (xy 102.319564 -285.140472) (xy 102.364026 -285.16157)
			(xy 102.404529 -285.189526) (xy 102.440022 -285.223618) (xy 102.469587 -285.262962) (xy 102.492458 -285.306539)
			(xy 102.508042 -285.35322) (xy 102.515937 -285.401797) (xy 102.516432 -285.426404) (xy 102.845374 -285.426404)
			(xy 102.849334 -285.37735) (xy 102.861111 -285.329566) (xy 102.880402 -285.28429) (xy 102.906705 -285.242694)
			(xy 102.93934 -285.205857) (xy 102.977461 -285.174732) (xy 103.020082 -285.150125) (xy 103.066098 -285.132673)
			(xy 103.114317 -285.122829) (xy 103.163492 -285.120848) (xy 103.212347 -285.12678) (xy 103.259618 -285.140472)
			(xy 103.30408 -285.16157) (xy 103.344583 -285.189526) (xy 103.380076 -285.223618) (xy 103.409641 -285.262962)
			(xy 103.432512 -285.306539) (xy 103.448096 -285.35322) (xy 103.455991 -285.401797) (xy 103.456486 -285.426404)
			(xy 103.785174 -285.426404) (xy 103.789134 -285.37735) (xy 103.800911 -285.329566) (xy 103.820202 -285.28429)
			(xy 103.846505 -285.242694) (xy 103.87914 -285.205857) (xy 103.917261 -285.174732) (xy 103.959882 -285.150125)
			(xy 104.005898 -285.132673) (xy 104.054117 -285.122829) (xy 104.103292 -285.120848) (xy 104.152147 -285.12678)
			(xy 104.199418 -285.140472) (xy 104.24388 -285.16157) (xy 104.284383 -285.189526) (xy 104.319876 -285.223618)
			(xy 104.349441 -285.262962) (xy 104.372312 -285.306539) (xy 104.387896 -285.35322) (xy 104.395791 -285.401797)
			(xy 104.396286 -285.426404) (xy 104.725228 -285.426404) (xy 104.729188 -285.37735) (xy 104.740965 -285.329566)
			(xy 104.760256 -285.28429) (xy 104.786559 -285.242694) (xy 104.819194 -285.205857) (xy 104.857315 -285.174732)
			(xy 104.899936 -285.150125) (xy 104.945952 -285.132673) (xy 104.994171 -285.122829) (xy 105.043346 -285.120848)
			(xy 105.092201 -285.12678) (xy 105.139472 -285.140472) (xy 105.183934 -285.16157) (xy 105.224437 -285.189526)
			(xy 105.25993 -285.223618) (xy 105.289495 -285.262962) (xy 105.312366 -285.306539) (xy 105.32795 -285.35322)
			(xy 105.335845 -285.401797) (xy 105.33634 -285.426404) (xy 105.665282 -285.426404) (xy 105.669242 -285.37735)
			(xy 105.681019 -285.329566) (xy 105.70031 -285.28429) (xy 105.726613 -285.242694) (xy 105.759248 -285.205857)
			(xy 105.797369 -285.174732) (xy 105.83999 -285.150125) (xy 105.886006 -285.132673) (xy 105.934225 -285.122829)
			(xy 105.9834 -285.120848) (xy 106.032255 -285.12678) (xy 106.079526 -285.140472) (xy 106.123988 -285.16157)
			(xy 106.164491 -285.189526) (xy 106.199984 -285.223618) (xy 106.229549 -285.262962) (xy 106.25242 -285.306539)
			(xy 106.268004 -285.35322) (xy 106.275899 -285.401797) (xy 106.276394 -285.426404) (xy 106.605336 -285.426404)
			(xy 106.609296 -285.37735) (xy 106.621073 -285.329566) (xy 106.640364 -285.28429) (xy 106.666667 -285.242694)
			(xy 106.699302 -285.205857) (xy 106.737423 -285.174732) (xy 106.780044 -285.150125) (xy 106.82606 -285.132673)
			(xy 106.874279 -285.122829) (xy 106.923454 -285.120848) (xy 106.972309 -285.12678) (xy 107.01958 -285.140472)
			(xy 107.064042 -285.16157) (xy 107.104545 -285.189526) (xy 107.140038 -285.223618) (xy 107.169603 -285.262962)
			(xy 107.192474 -285.306539) (xy 107.208058 -285.35322) (xy 107.215953 -285.401797) (xy 107.216448 -285.426404)
			(xy 107.545136 -285.426404) (xy 107.549096 -285.37735) (xy 107.560873 -285.329566) (xy 107.580164 -285.28429)
			(xy 107.606467 -285.242694) (xy 107.639102 -285.205857) (xy 107.677223 -285.174732) (xy 107.719844 -285.150125)
			(xy 107.76586 -285.132673) (xy 107.814079 -285.122829) (xy 107.863254 -285.120848) (xy 107.912109 -285.12678)
			(xy 107.95938 -285.140472) (xy 108.003842 -285.16157) (xy 108.044345 -285.189526) (xy 108.079838 -285.223618)
			(xy 108.109403 -285.262962) (xy 108.132274 -285.306539) (xy 108.147858 -285.35322) (xy 108.155753 -285.401797)
			(xy 108.156248 -285.4264) (xy 108.485173 -285.4264) (xy 108.489344 -285.376063) (xy 108.501743 -285.327099)
			(xy 108.522032 -285.280844) (xy 108.549658 -285.238559) (xy 108.583867 -285.201398) (xy 108.623725 -285.170374)
			(xy 108.668147 -285.146334) (xy 108.715919 -285.129932) (xy 108.765739 -285.121618) (xy 108.790994 -285.121096)
			(xy 109.731048 -285.121096) (xy 109.756301 -285.121613) (xy 109.806117 -285.129933) (xy 109.853885 -285.146339)
			(xy 109.898301 -285.170382) (xy 109.938155 -285.201407) (xy 109.972359 -285.238568) (xy 109.999981 -285.280852)
			(xy 110.020267 -285.327105) (xy 110.032665 -285.376066) (xy 110.036835 -285.4264) (xy 110.036835 -285.426404)
			(xy 110.365298 -285.426404) (xy 110.369258 -285.37735) (xy 110.381035 -285.329566) (xy 110.400326 -285.28429)
			(xy 110.426629 -285.242694) (xy 110.459264 -285.205857) (xy 110.497385 -285.174732) (xy 110.540006 -285.150125)
			(xy 110.586022 -285.132673) (xy 110.634241 -285.122829) (xy 110.683416 -285.120848) (xy 110.732271 -285.12678)
			(xy 110.779542 -285.140472) (xy 110.824004 -285.16157) (xy 110.864507 -285.189526) (xy 110.9 -285.223618)
			(xy 110.929565 -285.262962) (xy 110.952436 -285.306539) (xy 110.96802 -285.35322) (xy 110.975915 -285.401797)
			(xy 110.97641 -285.426404) (xy 113.178856 -285.426404) (xy 113.182816 -285.37735) (xy 113.194593 -285.329566)
			(xy 113.213884 -285.28429) (xy 113.240187 -285.242694) (xy 113.272822 -285.205857) (xy 113.310943 -285.174732)
			(xy 113.353564 -285.150125) (xy 113.39958 -285.132673) (xy 113.447799 -285.122829) (xy 113.496974 -285.120848)
			(xy 113.545829 -285.12678) (xy 113.5931 -285.140472) (xy 113.637562 -285.16157) (xy 113.678065 -285.189526)
			(xy 113.713558 -285.223618) (xy 113.743123 -285.262962) (xy 113.765994 -285.306539) (xy 113.781578 -285.35322)
			(xy 113.789473 -285.401797) (xy 113.789968 -285.4264) (xy 114.118844 -285.4264) (xy 114.123016 -285.376056)
			(xy 114.135417 -285.327086) (xy 114.15571 -285.280825) (xy 114.18334 -285.238535) (xy 114.217555 -285.201369)
			(xy 114.25742 -285.170343) (xy 114.301849 -285.146301) (xy 114.349628 -285.1299) (xy 114.399456 -285.121588)
			(xy 114.424714 -285.121096) (xy 115.364768 -285.121096) (xy 115.390028 -285.121578) (xy 115.439859 -285.129889)
			(xy 115.487643 -285.146288) (xy 115.532075 -285.17033) (xy 115.571944 -285.201357) (xy 115.606161 -285.238524)
			(xy 115.633795 -285.280816) (xy 115.654089 -285.32708) (xy 115.666492 -285.376053) (xy 115.670664 -285.4264)
			(xy 115.670664 -285.426404) (xy 115.999018 -285.426404) (xy 116.002978 -285.37735) (xy 116.014755 -285.329566)
			(xy 116.034046 -285.28429) (xy 116.060349 -285.242694) (xy 116.092984 -285.205857) (xy 116.131105 -285.174732)
			(xy 116.173726 -285.150125) (xy 116.219742 -285.132673) (xy 116.267961 -285.122829) (xy 116.317136 -285.120848)
			(xy 116.365991 -285.12678) (xy 116.413262 -285.140472) (xy 116.457724 -285.16157) (xy 116.498227 -285.189526)
			(xy 116.53372 -285.223618) (xy 116.563285 -285.262962) (xy 116.586156 -285.306539) (xy 116.60174 -285.35322)
			(xy 116.609635 -285.401797) (xy 116.61013 -285.426404) (xy 116.938818 -285.426404) (xy 116.942778 -285.37735)
			(xy 116.954555 -285.329566) (xy 116.973846 -285.28429) (xy 117.000149 -285.242694) (xy 117.032784 -285.205857)
			(xy 117.070905 -285.174732) (xy 117.113526 -285.150125) (xy 117.159542 -285.132673) (xy 117.207761 -285.122829)
			(xy 117.256936 -285.120848) (xy 117.305791 -285.12678) (xy 117.353062 -285.140472) (xy 117.397524 -285.16157)
			(xy 117.438027 -285.189526) (xy 117.47352 -285.223618) (xy 117.503085 -285.262962) (xy 117.525956 -285.306539)
			(xy 117.54154 -285.35322) (xy 117.549435 -285.401797) (xy 117.54993 -285.426404) (xy 117.878872 -285.426404)
			(xy 117.882832 -285.37735) (xy 117.894609 -285.329566) (xy 117.9139 -285.28429) (xy 117.940203 -285.242694)
			(xy 117.972838 -285.205857) (xy 118.010959 -285.174732) (xy 118.05358 -285.150125) (xy 118.099596 -285.132673)
			(xy 118.147815 -285.122829) (xy 118.19699 -285.120848) (xy 118.245845 -285.12678) (xy 118.293116 -285.140472)
			(xy 118.337578 -285.16157) (xy 118.378081 -285.189526) (xy 118.413574 -285.223618) (xy 118.443139 -285.262962)
			(xy 118.46601 -285.306539) (xy 118.481594 -285.35322) (xy 118.489489 -285.401797) (xy 118.489984 -285.426404)
			(xy 118.818926 -285.426404) (xy 118.822886 -285.37735) (xy 118.834663 -285.329566) (xy 118.853954 -285.28429)
			(xy 118.880257 -285.242694) (xy 118.912892 -285.205857) (xy 118.951013 -285.174732) (xy 118.993634 -285.150125)
			(xy 119.03965 -285.132673) (xy 119.087869 -285.122829) (xy 119.137044 -285.120848) (xy 119.185899 -285.12678)
			(xy 119.23317 -285.140472) (xy 119.277632 -285.16157) (xy 119.318135 -285.189526) (xy 119.353628 -285.223618)
			(xy 119.383193 -285.262962) (xy 119.406064 -285.306539) (xy 119.421648 -285.35322) (xy 119.429543 -285.401797)
			(xy 119.430038 -285.426404) (xy 119.75898 -285.426404) (xy 119.76294 -285.37735) (xy 119.774717 -285.329566)
			(xy 119.794008 -285.28429) (xy 119.820311 -285.242694) (xy 119.852946 -285.205857) (xy 119.891067 -285.174732)
			(xy 119.933688 -285.150125) (xy 119.979704 -285.132673) (xy 120.027923 -285.122829) (xy 120.077098 -285.120848)
			(xy 120.125953 -285.12678) (xy 120.173224 -285.140472) (xy 120.217686 -285.16157) (xy 120.258189 -285.189526)
			(xy 120.293682 -285.223618) (xy 120.323247 -285.262962) (xy 120.346118 -285.306539) (xy 120.361702 -285.35322)
			(xy 120.369597 -285.401797) (xy 120.370092 -285.426404) (xy 120.699034 -285.426404) (xy 120.702994 -285.37735)
			(xy 120.714771 -285.329566) (xy 120.734062 -285.28429) (xy 120.760365 -285.242694) (xy 120.793 -285.205857)
			(xy 120.831121 -285.174732) (xy 120.873742 -285.150125) (xy 120.919758 -285.132673) (xy 120.967977 -285.122829)
			(xy 121.017152 -285.120848) (xy 121.066007 -285.12678) (xy 121.113278 -285.140472) (xy 121.15774 -285.16157)
			(xy 121.198243 -285.189526) (xy 121.233736 -285.223618) (xy 121.263301 -285.262962) (xy 121.286172 -285.306539)
			(xy 121.301756 -285.35322) (xy 121.309651 -285.401797) (xy 121.310146 -285.426404) (xy 121.638834 -285.426404)
			(xy 121.642794 -285.37735) (xy 121.654571 -285.329566) (xy 121.673862 -285.28429) (xy 121.700165 -285.242694)
			(xy 121.7328 -285.205857) (xy 121.770921 -285.174732) (xy 121.813542 -285.150125) (xy 121.859558 -285.132673)
			(xy 121.907777 -285.122829) (xy 121.956952 -285.120848) (xy 122.005807 -285.12678) (xy 122.053078 -285.140472)
			(xy 122.09754 -285.16157) (xy 122.138043 -285.189526) (xy 122.173536 -285.223618) (xy 122.203101 -285.262962)
			(xy 122.225972 -285.306539) (xy 122.241556 -285.35322) (xy 122.249451 -285.401797) (xy 122.249946 -285.426404)
			(xy 122.578888 -285.426404) (xy 122.582848 -285.37735) (xy 122.594625 -285.329566) (xy 122.613916 -285.28429)
			(xy 122.640219 -285.242694) (xy 122.672854 -285.205857) (xy 122.710975 -285.174732) (xy 122.753596 -285.150125)
			(xy 122.799612 -285.132673) (xy 122.847831 -285.122829) (xy 122.897006 -285.120848) (xy 122.945861 -285.12678)
			(xy 122.993132 -285.140472) (xy 123.037594 -285.16157) (xy 123.078097 -285.189526) (xy 123.11359 -285.223618)
			(xy 123.143155 -285.262962) (xy 123.166026 -285.306539) (xy 123.18161 -285.35322) (xy 123.189505 -285.401797)
			(xy 123.19 -285.426404) (xy 123.518942 -285.426404) (xy 123.522902 -285.37735) (xy 123.534679 -285.329566)
			(xy 123.55397 -285.28429) (xy 123.580273 -285.242694) (xy 123.612908 -285.205857) (xy 123.651029 -285.174732)
			(xy 123.69365 -285.150125) (xy 123.739666 -285.132673) (xy 123.787885 -285.122829) (xy 123.83706 -285.120848)
			(xy 123.885915 -285.12678) (xy 123.933186 -285.140472) (xy 123.977648 -285.16157) (xy 124.018151 -285.189526)
			(xy 124.053644 -285.223618) (xy 124.083209 -285.262962) (xy 124.10608 -285.306539) (xy 124.121664 -285.35322)
			(xy 124.129559 -285.401797) (xy 124.130054 -285.426404) (xy 124.458996 -285.426404) (xy 124.462956 -285.37735)
			(xy 124.474733 -285.329566) (xy 124.494024 -285.28429) (xy 124.520327 -285.242694) (xy 124.552962 -285.205857)
			(xy 124.591083 -285.174732) (xy 124.633704 -285.150125) (xy 124.67972 -285.132673) (xy 124.727939 -285.122829)
			(xy 124.777114 -285.120848) (xy 124.825969 -285.12678) (xy 124.87324 -285.140472) (xy 124.917702 -285.16157)
			(xy 124.958205 -285.189526) (xy 124.993698 -285.223618) (xy 125.023263 -285.262962) (xy 125.046134 -285.306539)
			(xy 125.061718 -285.35322) (xy 125.069613 -285.401797) (xy 125.070108 -285.426404) (xy 125.39905 -285.426404)
			(xy 125.40301 -285.37735) (xy 125.414787 -285.329566) (xy 125.434078 -285.28429) (xy 125.460381 -285.242694)
			(xy 125.493016 -285.205857) (xy 125.531137 -285.174732) (xy 125.573758 -285.150125) (xy 125.619774 -285.132673)
			(xy 125.667993 -285.122829) (xy 125.717168 -285.120848) (xy 125.766023 -285.12678) (xy 125.813294 -285.140472)
			(xy 125.857756 -285.16157) (xy 125.898259 -285.189526) (xy 125.933752 -285.223618) (xy 125.963317 -285.262962)
			(xy 125.986188 -285.306539) (xy 126.001772 -285.35322) (xy 126.009667 -285.401797) (xy 126.010162 -285.426404)
			(xy 126.33885 -285.426404) (xy 126.34281 -285.37735) (xy 126.354587 -285.329566) (xy 126.373878 -285.28429)
			(xy 126.400181 -285.242694) (xy 126.432816 -285.205857) (xy 126.470937 -285.174732) (xy 126.513558 -285.150125)
			(xy 126.559574 -285.132673) (xy 126.607793 -285.122829) (xy 126.656968 -285.120848) (xy 126.705823 -285.12678)
			(xy 126.753094 -285.140472) (xy 126.797556 -285.16157) (xy 126.838059 -285.189526) (xy 126.873552 -285.223618)
			(xy 126.903117 -285.262962) (xy 126.925988 -285.306539) (xy 126.941572 -285.35322) (xy 126.949467 -285.401797)
			(xy 126.949962 -285.426404) (xy 126.949467 -285.451011) (xy 126.941572 -285.499588) (xy 126.925988 -285.546269)
			(xy 126.903117 -285.589846) (xy 126.873552 -285.62919) (xy 126.838059 -285.663282) (xy 126.797556 -285.691238)
			(xy 126.753094 -285.712336) (xy 126.705823 -285.726028) (xy 126.656968 -285.73196) (xy 126.607793 -285.729979)
			(xy 126.559574 -285.720135) (xy 126.513558 -285.702683) (xy 126.470937 -285.678076) (xy 126.432816 -285.646951)
			(xy 126.400181 -285.610114) (xy 126.373878 -285.568518) (xy 126.354587 -285.523242) (xy 126.34281 -285.475458)
			(xy 126.33885 -285.426404) (xy 126.010162 -285.426404) (xy 126.009667 -285.451011) (xy 126.001772 -285.499588)
			(xy 125.986188 -285.546269) (xy 125.963317 -285.589846) (xy 125.933752 -285.62919) (xy 125.898259 -285.663282)
			(xy 125.857756 -285.691238) (xy 125.813294 -285.712336) (xy 125.766023 -285.726028) (xy 125.717168 -285.73196)
			(xy 125.667993 -285.729979) (xy 125.619774 -285.720135) (xy 125.573758 -285.702683) (xy 125.531137 -285.678076)
			(xy 125.493016 -285.646951) (xy 125.460381 -285.610114) (xy 125.434078 -285.568518) (xy 125.414787 -285.523242)
			(xy 125.40301 -285.475458) (xy 125.39905 -285.426404) (xy 125.070108 -285.426404) (xy 125.069613 -285.451011)
			(xy 125.061718 -285.499588) (xy 125.046134 -285.546269) (xy 125.023263 -285.589846) (xy 124.993698 -285.62919)
			(xy 124.958205 -285.663282) (xy 124.917702 -285.691238) (xy 124.87324 -285.712336) (xy 124.825969 -285.726028)
			(xy 124.777114 -285.73196) (xy 124.727939 -285.729979) (xy 124.67972 -285.720135) (xy 124.633704 -285.702683)
			(xy 124.591083 -285.678076) (xy 124.552962 -285.646951) (xy 124.520327 -285.610114) (xy 124.494024 -285.568518)
			(xy 124.474733 -285.523242) (xy 124.462956 -285.475458) (xy 124.458996 -285.426404) (xy 124.130054 -285.426404)
			(xy 124.129559 -285.451011) (xy 124.121664 -285.499588) (xy 124.10608 -285.546269) (xy 124.083209 -285.589846)
			(xy 124.053644 -285.62919) (xy 124.018151 -285.663282) (xy 123.977648 -285.691238) (xy 123.933186 -285.712336)
			(xy 123.885915 -285.726028) (xy 123.83706 -285.73196) (xy 123.787885 -285.729979) (xy 123.739666 -285.720135)
			(xy 123.69365 -285.702683) (xy 123.651029 -285.678076) (xy 123.612908 -285.646951) (xy 123.580273 -285.610114)
			(xy 123.55397 -285.568518) (xy 123.534679 -285.523242) (xy 123.522902 -285.475458) (xy 123.518942 -285.426404)
			(xy 123.19 -285.426404) (xy 123.189505 -285.451011) (xy 123.18161 -285.499588) (xy 123.166026 -285.546269)
			(xy 123.143155 -285.589846) (xy 123.11359 -285.62919) (xy 123.078097 -285.663282) (xy 123.037594 -285.691238)
			(xy 122.993132 -285.712336) (xy 122.945861 -285.726028) (xy 122.897006 -285.73196) (xy 122.847831 -285.729979)
			(xy 122.799612 -285.720135) (xy 122.753596 -285.702683) (xy 122.710975 -285.678076) (xy 122.672854 -285.646951)
			(xy 122.640219 -285.610114) (xy 122.613916 -285.568518) (xy 122.594625 -285.523242) (xy 122.582848 -285.475458)
			(xy 122.578888 -285.426404) (xy 122.249946 -285.426404) (xy 122.249451 -285.451011) (xy 122.241556 -285.499588)
			(xy 122.225972 -285.546269) (xy 122.203101 -285.589846) (xy 122.173536 -285.62919) (xy 122.138043 -285.663282)
			(xy 122.09754 -285.691238) (xy 122.053078 -285.712336) (xy 122.005807 -285.726028) (xy 121.956952 -285.73196)
			(xy 121.907777 -285.729979) (xy 121.859558 -285.720135) (xy 121.813542 -285.702683) (xy 121.770921 -285.678076)
			(xy 121.7328 -285.646951) (xy 121.700165 -285.610114) (xy 121.673862 -285.568518) (xy 121.654571 -285.523242)
			(xy 121.642794 -285.475458) (xy 121.638834 -285.426404) (xy 121.310146 -285.426404) (xy 121.309651 -285.451011)
			(xy 121.301756 -285.499588) (xy 121.286172 -285.546269) (xy 121.263301 -285.589846) (xy 121.233736 -285.62919)
			(xy 121.198243 -285.663282) (xy 121.15774 -285.691238) (xy 121.113278 -285.712336) (xy 121.066007 -285.726028)
			(xy 121.017152 -285.73196) (xy 120.967977 -285.729979) (xy 120.919758 -285.720135) (xy 120.873742 -285.702683)
			(xy 120.831121 -285.678076) (xy 120.793 -285.646951) (xy 120.760365 -285.610114) (xy 120.734062 -285.568518)
			(xy 120.714771 -285.523242) (xy 120.702994 -285.475458) (xy 120.699034 -285.426404) (xy 120.370092 -285.426404)
			(xy 120.369597 -285.451011) (xy 120.361702 -285.499588) (xy 120.346118 -285.546269) (xy 120.323247 -285.589846)
			(xy 120.293682 -285.62919) (xy 120.258189 -285.663282) (xy 120.217686 -285.691238) (xy 120.173224 -285.712336)
			(xy 120.125953 -285.726028) (xy 120.077098 -285.73196) (xy 120.027923 -285.729979) (xy 119.979704 -285.720135)
			(xy 119.933688 -285.702683) (xy 119.891067 -285.678076) (xy 119.852946 -285.646951) (xy 119.820311 -285.610114)
			(xy 119.794008 -285.568518) (xy 119.774717 -285.523242) (xy 119.76294 -285.475458) (xy 119.75898 -285.426404)
			(xy 119.430038 -285.426404) (xy 119.429543 -285.451011) (xy 119.421648 -285.499588) (xy 119.406064 -285.546269)
			(xy 119.383193 -285.589846) (xy 119.353628 -285.62919) (xy 119.318135 -285.663282) (xy 119.277632 -285.691238)
			(xy 119.23317 -285.712336) (xy 119.185899 -285.726028) (xy 119.137044 -285.73196) (xy 119.087869 -285.729979)
			(xy 119.03965 -285.720135) (xy 118.993634 -285.702683) (xy 118.951013 -285.678076) (xy 118.912892 -285.646951)
			(xy 118.880257 -285.610114) (xy 118.853954 -285.568518) (xy 118.834663 -285.523242) (xy 118.822886 -285.475458)
			(xy 118.818926 -285.426404) (xy 118.489984 -285.426404) (xy 118.489489 -285.451011) (xy 118.481594 -285.499588)
			(xy 118.46601 -285.546269) (xy 118.443139 -285.589846) (xy 118.413574 -285.62919) (xy 118.378081 -285.663282)
			(xy 118.337578 -285.691238) (xy 118.293116 -285.712336) (xy 118.245845 -285.726028) (xy 118.19699 -285.73196)
			(xy 118.147815 -285.729979) (xy 118.099596 -285.720135) (xy 118.05358 -285.702683) (xy 118.010959 -285.678076)
			(xy 117.972838 -285.646951) (xy 117.940203 -285.610114) (xy 117.9139 -285.568518) (xy 117.894609 -285.523242)
			(xy 117.882832 -285.475458) (xy 117.878872 -285.426404) (xy 117.54993 -285.426404) (xy 117.549435 -285.451011)
			(xy 117.54154 -285.499588) (xy 117.525956 -285.546269) (xy 117.503085 -285.589846) (xy 117.47352 -285.62919)
			(xy 117.438027 -285.663282) (xy 117.397524 -285.691238) (xy 117.353062 -285.712336) (xy 117.305791 -285.726028)
			(xy 117.256936 -285.73196) (xy 117.207761 -285.729979) (xy 117.159542 -285.720135) (xy 117.113526 -285.702683)
			(xy 117.070905 -285.678076) (xy 117.032784 -285.646951) (xy 117.000149 -285.610114) (xy 116.973846 -285.568518)
			(xy 116.954555 -285.523242) (xy 116.942778 -285.475458) (xy 116.938818 -285.426404) (xy 116.61013 -285.426404)
			(xy 116.609635 -285.451011) (xy 116.60174 -285.499588) (xy 116.586156 -285.546269) (xy 116.563285 -285.589846)
			(xy 116.53372 -285.62919) (xy 116.498227 -285.663282) (xy 116.457724 -285.691238) (xy 116.413262 -285.712336)
			(xy 116.365991 -285.726028) (xy 116.317136 -285.73196) (xy 116.267961 -285.729979) (xy 116.219742 -285.720135)
			(xy 116.173726 -285.702683) (xy 116.131105 -285.678076) (xy 116.092984 -285.646951) (xy 116.060349 -285.610114)
			(xy 116.034046 -285.568518) (xy 116.014755 -285.523242) (xy 116.002978 -285.475458) (xy 115.999018 -285.426404)
			(xy 115.670664 -285.426404) (xy 115.666492 -285.476747) (xy 115.654089 -285.52572) (xy 115.633795 -285.571984)
			(xy 115.606161 -285.614276) (xy 115.571944 -285.651443) (xy 115.532075 -285.68247) (xy 115.487643 -285.706512)
			(xy 115.439859 -285.722911) (xy 115.390028 -285.731222) (xy 115.364768 -285.731712) (xy 114.424714 -285.731712)
			(xy 114.399456 -285.731212) (xy 114.349628 -285.7229) (xy 114.301849 -285.706499) (xy 114.25742 -285.682457)
			(xy 114.217555 -285.651431) (xy 114.18334 -285.614265) (xy 114.15571 -285.571975) (xy 114.135417 -285.525714)
			(xy 114.123016 -285.476744) (xy 114.118844 -285.4264) (xy 113.789968 -285.4264) (xy 113.789968 -285.426404)
			(xy 113.789473 -285.451011) (xy 113.781578 -285.499588) (xy 113.765994 -285.546269) (xy 113.743123 -285.589846)
			(xy 113.713558 -285.62919) (xy 113.678065 -285.663282) (xy 113.637562 -285.691238) (xy 113.5931 -285.712336)
			(xy 113.545829 -285.726028) (xy 113.496974 -285.73196) (xy 113.447799 -285.729979) (xy 113.39958 -285.720135)
			(xy 113.353564 -285.702683) (xy 113.310943 -285.678076) (xy 113.272822 -285.646951) (xy 113.240187 -285.610114)
			(xy 113.213884 -285.568518) (xy 113.194593 -285.523242) (xy 113.182816 -285.475458) (xy 113.178856 -285.426404)
			(xy 110.97641 -285.426404) (xy 110.975915 -285.451011) (xy 110.96802 -285.499588) (xy 110.952436 -285.546269)
			(xy 110.929565 -285.589846) (xy 110.9 -285.62919) (xy 110.864507 -285.663282) (xy 110.824004 -285.691238)
			(xy 110.779542 -285.712336) (xy 110.732271 -285.726028) (xy 110.683416 -285.73196) (xy 110.634241 -285.729979)
			(xy 110.586022 -285.720135) (xy 110.540006 -285.702683) (xy 110.497385 -285.678076) (xy 110.459264 -285.646951)
			(xy 110.426629 -285.610114) (xy 110.400326 -285.568518) (xy 110.381035 -285.523242) (xy 110.369258 -285.475458)
			(xy 110.365298 -285.426404) (xy 110.036835 -285.426404) (xy 110.032665 -285.476734) (xy 110.020267 -285.525695)
			(xy 109.999981 -285.571948) (xy 109.972359 -285.614232) (xy 109.938155 -285.651393) (xy 109.898301 -285.682418)
			(xy 109.853885 -285.706461) (xy 109.806117 -285.722867) (xy 109.756301 -285.731187) (xy 109.731048 -285.731712)
			(xy 108.790994 -285.731712) (xy 108.765739 -285.731182) (xy 108.715919 -285.722868) (xy 108.668147 -285.706466)
			(xy 108.623725 -285.682426) (xy 108.583867 -285.651402) (xy 108.549658 -285.614241) (xy 108.522032 -285.571956)
			(xy 108.501743 -285.525701) (xy 108.489344 -285.476737) (xy 108.485173 -285.4264) (xy 108.156248 -285.4264)
			(xy 108.156248 -285.426404) (xy 108.155753 -285.451011) (xy 108.147858 -285.499588) (xy 108.132274 -285.546269)
			(xy 108.109403 -285.589846) (xy 108.079838 -285.62919) (xy 108.044345 -285.663282) (xy 108.003842 -285.691238)
			(xy 107.95938 -285.712336) (xy 107.912109 -285.726028) (xy 107.863254 -285.73196) (xy 107.814079 -285.729979)
			(xy 107.76586 -285.720135) (xy 107.719844 -285.702683) (xy 107.677223 -285.678076) (xy 107.639102 -285.646951)
			(xy 107.606467 -285.610114) (xy 107.580164 -285.568518) (xy 107.560873 -285.523242) (xy 107.549096 -285.475458)
			(xy 107.545136 -285.426404) (xy 107.216448 -285.426404) (xy 107.215953 -285.451011) (xy 107.208058 -285.499588)
			(xy 107.192474 -285.546269) (xy 107.169603 -285.589846) (xy 107.140038 -285.62919) (xy 107.104545 -285.663282)
			(xy 107.064042 -285.691238) (xy 107.01958 -285.712336) (xy 106.972309 -285.726028) (xy 106.923454 -285.73196)
			(xy 106.874279 -285.729979) (xy 106.82606 -285.720135) (xy 106.780044 -285.702683) (xy 106.737423 -285.678076)
			(xy 106.699302 -285.646951) (xy 106.666667 -285.610114) (xy 106.640364 -285.568518) (xy 106.621073 -285.523242)
			(xy 106.609296 -285.475458) (xy 106.605336 -285.426404) (xy 106.276394 -285.426404) (xy 106.275899 -285.451011)
			(xy 106.268004 -285.499588) (xy 106.25242 -285.546269) (xy 106.229549 -285.589846) (xy 106.199984 -285.62919)
			(xy 106.164491 -285.663282) (xy 106.123988 -285.691238) (xy 106.079526 -285.712336) (xy 106.032255 -285.726028)
			(xy 105.9834 -285.73196) (xy 105.934225 -285.729979) (xy 105.886006 -285.720135) (xy 105.83999 -285.702683)
			(xy 105.797369 -285.678076) (xy 105.759248 -285.646951) (xy 105.726613 -285.610114) (xy 105.70031 -285.568518)
			(xy 105.681019 -285.523242) (xy 105.669242 -285.475458) (xy 105.665282 -285.426404) (xy 105.33634 -285.426404)
			(xy 105.335845 -285.451011) (xy 105.32795 -285.499588) (xy 105.312366 -285.546269) (xy 105.289495 -285.589846)
			(xy 105.25993 -285.62919) (xy 105.224437 -285.663282) (xy 105.183934 -285.691238) (xy 105.139472 -285.712336)
			(xy 105.092201 -285.726028) (xy 105.043346 -285.73196) (xy 104.994171 -285.729979) (xy 104.945952 -285.720135)
			(xy 104.899936 -285.702683) (xy 104.857315 -285.678076) (xy 104.819194 -285.646951) (xy 104.786559 -285.610114)
			(xy 104.760256 -285.568518) (xy 104.740965 -285.523242) (xy 104.729188 -285.475458) (xy 104.725228 -285.426404)
			(xy 104.396286 -285.426404) (xy 104.395791 -285.451011) (xy 104.387896 -285.499588) (xy 104.372312 -285.546269)
			(xy 104.349441 -285.589846) (xy 104.319876 -285.62919) (xy 104.284383 -285.663282) (xy 104.24388 -285.691238)
			(xy 104.199418 -285.712336) (xy 104.152147 -285.726028) (xy 104.103292 -285.73196) (xy 104.054117 -285.729979)
			(xy 104.005898 -285.720135) (xy 103.959882 -285.702683) (xy 103.917261 -285.678076) (xy 103.87914 -285.646951)
			(xy 103.846505 -285.610114) (xy 103.820202 -285.568518) (xy 103.800911 -285.523242) (xy 103.789134 -285.475458)
			(xy 103.785174 -285.426404) (xy 103.456486 -285.426404) (xy 103.455991 -285.451011) (xy 103.448096 -285.499588)
			(xy 103.432512 -285.546269) (xy 103.409641 -285.589846) (xy 103.380076 -285.62919) (xy 103.344583 -285.663282)
			(xy 103.30408 -285.691238) (xy 103.259618 -285.712336) (xy 103.212347 -285.726028) (xy 103.163492 -285.73196)
			(xy 103.114317 -285.729979) (xy 103.066098 -285.720135) (xy 103.020082 -285.702683) (xy 102.977461 -285.678076)
			(xy 102.93934 -285.646951) (xy 102.906705 -285.610114) (xy 102.880402 -285.568518) (xy 102.861111 -285.523242)
			(xy 102.849334 -285.475458) (xy 102.845374 -285.426404) (xy 102.516432 -285.426404) (xy 102.515937 -285.451011)
			(xy 102.508042 -285.499588) (xy 102.492458 -285.546269) (xy 102.469587 -285.589846) (xy 102.440022 -285.62919)
			(xy 102.404529 -285.663282) (xy 102.364026 -285.691238) (xy 102.319564 -285.712336) (xy 102.272293 -285.726028)
			(xy 102.223438 -285.73196) (xy 102.174263 -285.729979) (xy 102.126044 -285.720135) (xy 102.080028 -285.702683)
			(xy 102.037407 -285.678076) (xy 101.999286 -285.646951) (xy 101.966651 -285.610114) (xy 101.940348 -285.568518)
			(xy 101.921057 -285.523242) (xy 101.90928 -285.475458) (xy 101.90532 -285.426404) (xy 101.576378 -285.426404)
			(xy 101.575883 -285.451011) (xy 101.567988 -285.499588) (xy 101.552404 -285.546269) (xy 101.529533 -285.589846)
			(xy 101.499968 -285.62919) (xy 101.464475 -285.663282) (xy 101.423972 -285.691238) (xy 101.37951 -285.712336)
			(xy 101.332239 -285.726028) (xy 101.283384 -285.73196) (xy 101.234209 -285.729979) (xy 101.18599 -285.720135)
			(xy 101.139974 -285.702683) (xy 101.097353 -285.678076) (xy 101.059232 -285.646951) (xy 101.026597 -285.610114)
			(xy 101.000294 -285.568518) (xy 100.981003 -285.523242) (xy 100.969226 -285.475458) (xy 100.965266 -285.426404)
			(xy 100.636324 -285.426404) (xy 100.635829 -285.451011) (xy 100.627934 -285.499588) (xy 100.61235 -285.546269)
			(xy 100.589479 -285.589846) (xy 100.559914 -285.62919) (xy 100.524421 -285.663282) (xy 100.483918 -285.691238)
			(xy 100.439456 -285.712336) (xy 100.392185 -285.726028) (xy 100.34333 -285.73196) (xy 100.294155 -285.729979)
			(xy 100.245936 -285.720135) (xy 100.19992 -285.702683) (xy 100.157299 -285.678076) (xy 100.119178 -285.646951)
			(xy 100.086543 -285.610114) (xy 100.06024 -285.568518) (xy 100.040949 -285.523242) (xy 100.029172 -285.475458)
			(xy 100.025212 -285.426404) (xy 99.69627 -285.426404) (xy 99.695775 -285.451011) (xy 99.68788 -285.499588)
			(xy 99.672296 -285.546269) (xy 99.649425 -285.589846) (xy 99.61986 -285.62919) (xy 99.584367 -285.663282)
			(xy 99.543864 -285.691238) (xy 99.499402 -285.712336) (xy 99.452131 -285.726028) (xy 99.403276 -285.73196)
			(xy 99.354101 -285.729979) (xy 99.305882 -285.720135) (xy 99.259866 -285.702683) (xy 99.217245 -285.678076)
			(xy 99.179124 -285.646951) (xy 99.146489 -285.610114) (xy 99.120186 -285.568518) (xy 99.100895 -285.523242)
			(xy 99.089118 -285.475458) (xy 99.085158 -285.426404) (xy 98.75647 -285.426404) (xy 98.755975 -285.451011)
			(xy 98.74808 -285.499588) (xy 98.732496 -285.546269) (xy 98.709625 -285.589846) (xy 98.68006 -285.62919)
			(xy 98.644567 -285.663282) (xy 98.604064 -285.691238) (xy 98.559602 -285.712336) (xy 98.512331 -285.726028)
			(xy 98.463476 -285.73196) (xy 98.414301 -285.729979) (xy 98.366082 -285.720135) (xy 98.320066 -285.702683)
			(xy 98.277445 -285.678076) (xy 98.239324 -285.646951) (xy 98.206689 -285.610114) (xy 98.180386 -285.568518)
			(xy 98.161095 -285.523242) (xy 98.149318 -285.475458) (xy 98.145358 -285.426404) (xy 97.816416 -285.426404)
			(xy 97.815921 -285.451011) (xy 97.808026 -285.499588) (xy 97.792442 -285.546269) (xy 97.769571 -285.589846)
			(xy 97.740006 -285.62919) (xy 97.704513 -285.663282) (xy 97.66401 -285.691238) (xy 97.619548 -285.712336)
			(xy 97.572277 -285.726028) (xy 97.523422 -285.73196) (xy 97.474247 -285.729979) (xy 97.426028 -285.720135)
			(xy 97.380012 -285.702683) (xy 97.337391 -285.678076) (xy 97.29927 -285.646951) (xy 97.266635 -285.610114)
			(xy 97.240332 -285.568518) (xy 97.221041 -285.523242) (xy 97.209264 -285.475458) (xy 97.205304 -285.426404)
			(xy 96.875926 -285.426404) (xy 96.875926 -285.451224) (xy 96.867893 -285.500216) (xy 96.85204 -285.547263)
			(xy 96.828783 -285.591125) (xy 96.798736 -285.630647) (xy 96.762691 -285.664786) (xy 96.721597 -285.692644)
			(xy 96.676537 -285.713485) (xy 96.628699 -285.726762) (xy 96.604074 -285.729934) (xy 96.60001 -285.730442)
			(xy 96.595374 -285.731419) (xy 96.586554 -285.734874) (xy 96.582484 -285.7373) (xy 96.572832 -285.745428)
			(xy 96.552258 -285.767272) (xy 96.546778 -285.773501) (xy 96.539779 -285.788532) (xy 96.538542 -285.796736)
			(xy 96.538288 -285.802324) (xy 96.538288 -285.875984) (xy 96.538657 -285.884018) (xy 96.543714 -285.899275)
			(xy 96.548194 -285.905956) (xy 96.561889 -285.924775) (xy 96.586434 -285.964323) (xy 96.597216 -285.98495)
			(xy 96.603819 -285.998252) (xy 96.615766 -286.025444) (xy 96.621092 -286.039306) (xy 96.623632 -286.045656)
			(xy 96.6343 -286.054038) (xy 96.63982 -286.058083) (xy 96.652435 -286.063371) (xy 96.659192 -286.064452)
			(xy 96.74733 -286.075882) (xy 96.756064 -286.076655) (xy 96.773189 -286.072951) (xy 96.788082 -286.063721)
			(xy 96.793812 -286.057086) (xy 96.808275 -286.037916) (xy 96.842216 -286.003946) (xy 96.881057 -285.975712)
			(xy 96.923842 -285.953909) (xy 96.969513 -285.939076) (xy 97.016944 -285.931579) (xy 97.040954 -285.931102)
			(xy 97.066213 -285.931591) (xy 97.116044 -285.939899) (xy 97.163827 -285.956297) (xy 97.20826 -285.980337)
			(xy 97.248129 -286.011362) (xy 97.282347 -286.048528) (xy 97.30998 -286.090819) (xy 97.330275 -286.137081)
			(xy 97.342678 -286.186054) (xy 97.34685 -286.2364) (xy 97.674895 -286.2364) (xy 97.679071 -286.186016)
			(xy 97.691482 -286.137006) (xy 97.71179 -286.090708) (xy 97.739443 -286.048384) (xy 97.773684 -286.011189)
			(xy 97.813581 -285.980137) (xy 97.858045 -285.956075) (xy 97.905862 -285.939661) (xy 97.95573 -285.93134)
			(xy 97.981008 -285.930848) (xy 98.921062 -285.930848) (xy 98.946344 -285.931318) (xy 98.996218 -285.939635)
			(xy 99.044043 -285.956048) (xy 99.088514 -285.98011) (xy 99.128418 -286.011163) (xy 99.162665 -286.048362)
			(xy 99.190323 -286.09069) (xy 99.210635 -286.136994) (xy 99.223049 -286.18601) (xy 99.227225 -286.2364)
			(xy 99.227224 -286.23641) (xy 99.555312 -286.23641) (xy 99.559272 -286.187356) (xy 99.571049 -286.139572)
			(xy 99.59034 -286.094296) (xy 99.616643 -286.0527) (xy 99.649278 -286.015863) (xy 99.687399 -285.984738)
			(xy 99.73002 -285.960131) (xy 99.776036 -285.942679) (xy 99.824255 -285.932835) (xy 99.87343 -285.930854)
			(xy 99.922285 -285.936786) (xy 99.969556 -285.950478) (xy 100.014018 -285.971576) (xy 100.054521 -285.999532)
			(xy 100.090014 -286.033624) (xy 100.119579 -286.072968) (xy 100.14245 -286.116545) (xy 100.158034 -286.163226)
			(xy 100.165929 -286.211803) (xy 100.166424 -286.2364) (xy 100.495124 -286.2364) (xy 100.499298 -286.186025)
			(xy 100.511706 -286.137023) (xy 100.53201 -286.090733) (xy 100.559656 -286.048415) (xy 100.593889 -286.011224)
			(xy 100.633777 -285.980174) (xy 100.678231 -285.956113) (xy 100.726038 -285.939697) (xy 100.775896 -285.931372)
			(xy 100.80117 -285.930848) (xy 101.741224 -285.930848) (xy 101.7665 -285.931352) (xy 101.816362 -285.939676)
			(xy 101.864173 -285.956093) (xy 101.908631 -285.980155) (xy 101.948522 -286.011207) (xy 101.982759 -286.0484)
			(xy 102.010407 -286.090721) (xy 102.030712 -286.137016) (xy 102.043121 -286.186021) (xy 102.047296 -286.2364)
			(xy 102.047295 -286.23641) (xy 102.37522 -286.23641) (xy 102.37918 -286.187356) (xy 102.390957 -286.139572)
			(xy 102.410248 -286.094296) (xy 102.436551 -286.0527) (xy 102.469186 -286.015863) (xy 102.507307 -285.984738)
			(xy 102.549928 -285.960131) (xy 102.595944 -285.942679) (xy 102.644163 -285.932835) (xy 102.693338 -285.930854)
			(xy 102.742193 -285.936786) (xy 102.789464 -285.950478) (xy 102.833926 -285.971576) (xy 102.874429 -285.999532)
			(xy 102.909922 -286.033624) (xy 102.939487 -286.072968) (xy 102.962358 -286.116545) (xy 102.977942 -286.163226)
			(xy 102.985837 -286.211803) (xy 102.986332 -286.2364) (xy 103.315024 -286.2364) (xy 103.319199 -286.186024)
			(xy 103.331607 -286.137022) (xy 103.351911 -286.09073) (xy 103.379558 -286.048412) (xy 103.413792 -286.011221)
			(xy 103.453681 -285.980171) (xy 103.498136 -285.956111) (xy 103.545945 -285.939695) (xy 103.595804 -285.931372)
			(xy 103.621078 -285.930848) (xy 104.561132 -285.930848) (xy 104.586407 -285.931352) (xy 104.636268 -285.939678)
			(xy 104.684079 -285.956095) (xy 104.728535 -285.980158) (xy 104.768425 -286.01121) (xy 104.802661 -286.048403)
			(xy 104.830308 -286.090724) (xy 104.850613 -286.137017) (xy 104.863021 -286.186022) (xy 104.867196 -286.2364)
			(xy 104.867195 -286.23641) (xy 105.195128 -286.23641) (xy 105.199088 -286.187356) (xy 105.210865 -286.139572)
			(xy 105.230156 -286.094296) (xy 105.256459 -286.0527) (xy 105.289094 -286.015863) (xy 105.327215 -285.984738)
			(xy 105.369836 -285.960131) (xy 105.415852 -285.942679) (xy 105.464071 -285.932835) (xy 105.513246 -285.930854)
			(xy 105.562101 -285.936786) (xy 105.609372 -285.950478) (xy 105.653834 -285.971576) (xy 105.694337 -285.999532)
			(xy 105.72983 -286.033624) (xy 105.759395 -286.072968) (xy 105.782266 -286.116545) (xy 105.79785 -286.163226)
			(xy 105.805745 -286.211803) (xy 105.80624 -286.2364) (xy 106.134924 -286.2364) (xy 106.139099 -286.186023)
			(xy 106.151508 -286.13702) (xy 106.171813 -286.090728) (xy 106.19946 -286.048409) (xy 106.233695 -286.011218)
			(xy 106.273585 -285.980169) (xy 106.318041 -285.956108) (xy 106.365851 -285.939693) (xy 106.415711 -285.931371)
			(xy 106.440986 -285.930848) (xy 107.38104 -285.930848) (xy 107.406315 -285.931353) (xy 107.456175 -285.939679)
			(xy 107.503984 -285.956098) (xy 107.54844 -285.980161) (xy 107.588328 -286.011213) (xy 107.622563 -286.048406)
			(xy 107.650209 -286.090726) (xy 107.670513 -286.137019) (xy 107.682921 -286.186022) (xy 107.687096 -286.2364)
			(xy 107.687095 -286.23641) (xy 108.01529 -286.23641) (xy 108.01925 -286.187356) (xy 108.031027 -286.139572)
			(xy 108.050318 -286.094296) (xy 108.076621 -286.0527) (xy 108.109256 -286.015863) (xy 108.147377 -285.984738)
			(xy 108.189998 -285.960131) (xy 108.236014 -285.942679) (xy 108.284233 -285.932835) (xy 108.333408 -285.930854)
			(xy 108.382263 -285.936786) (xy 108.429534 -285.950478) (xy 108.473996 -285.971576) (xy 108.514499 -285.999532)
			(xy 108.549992 -286.033624) (xy 108.579557 -286.072968) (xy 108.602428 -286.116545) (xy 108.618012 -286.163226)
			(xy 108.625907 -286.211803) (xy 108.626402 -286.23641) (xy 115.528864 -286.23641) (xy 115.532824 -286.187356)
			(xy 115.544601 -286.139572) (xy 115.563892 -286.094296) (xy 115.590195 -286.0527) (xy 115.62283 -286.015863)
			(xy 115.660951 -285.984738) (xy 115.703572 -285.960131) (xy 115.749588 -285.942679) (xy 115.797807 -285.932835)
			(xy 115.846982 -285.930854) (xy 115.895837 -285.936786) (xy 115.943108 -285.950478) (xy 115.98757 -285.971576)
			(xy 116.028073 -285.999532) (xy 116.063566 -286.033624) (xy 116.093131 -286.072968) (xy 116.116002 -286.116545)
			(xy 116.131586 -286.163226) (xy 116.139481 -286.211803) (xy 116.139976 -286.2364) (xy 116.468595 -286.2364)
			(xy 116.472771 -286.186015) (xy 116.485183 -286.137004) (xy 116.505492 -286.090704) (xy 116.533146 -286.048379)
			(xy 116.56739 -286.011184) (xy 116.607288 -285.980132) (xy 116.651754 -285.956071) (xy 116.699574 -285.939658)
			(xy 116.749443 -285.931339) (xy 116.774722 -285.930848) (xy 117.714776 -285.930848) (xy 117.740057 -285.931319)
			(xy 117.789929 -285.939638) (xy 117.837753 -285.956052) (xy 117.882222 -285.980115) (xy 117.922123 -286.011168)
			(xy 117.956369 -286.048366) (xy 117.984025 -286.090694) (xy 118.004336 -286.136997) (xy 118.016749 -286.186011)
			(xy 118.020925 -286.2364) (xy 118.020924 -286.23641) (xy 118.349026 -286.23641) (xy 118.352986 -286.187356)
			(xy 118.364763 -286.139572) (xy 118.384054 -286.094296) (xy 118.410357 -286.0527) (xy 118.442992 -286.015863)
			(xy 118.481113 -285.984738) (xy 118.523734 -285.960131) (xy 118.56975 -285.942679) (xy 118.617969 -285.932835)
			(xy 118.667144 -285.930854) (xy 118.715999 -285.936786) (xy 118.76327 -285.950478) (xy 118.807732 -285.971576)
			(xy 118.848235 -285.999532) (xy 118.883728 -286.033624) (xy 118.913293 -286.072968) (xy 118.936164 -286.116545)
			(xy 118.951748 -286.163226) (xy 118.959643 -286.211803) (xy 118.960138 -286.2364) (xy 119.288495 -286.2364)
			(xy 119.292671 -286.186014) (xy 119.305083 -286.137002) (xy 119.325394 -286.090702) (xy 119.353048 -286.048377)
			(xy 119.387293 -286.011181) (xy 119.427193 -285.980129) (xy 119.47166 -285.956069) (xy 119.51948 -285.939656)
			(xy 119.56935 -285.931339) (xy 119.59463 -285.930848) (xy 120.534684 -285.930848) (xy 120.559964 -285.93132)
			(xy 120.609836 -285.93964) (xy 120.657658 -285.956055) (xy 120.702126 -285.980117) (xy 120.742026 -286.011171)
			(xy 120.776271 -286.048369) (xy 120.803926 -286.090696) (xy 120.824237 -286.136998) (xy 120.836649 -286.186012)
			(xy 120.840825 -286.2364) (xy 120.840824 -286.23641) (xy 121.168934 -286.23641) (xy 121.172894 -286.187356)
			(xy 121.184671 -286.139572) (xy 121.203962 -286.094296) (xy 121.230265 -286.0527) (xy 121.2629 -286.015863)
			(xy 121.301021 -285.984738) (xy 121.343642 -285.960131) (xy 121.389658 -285.942679) (xy 121.437877 -285.932835)
			(xy 121.487052 -285.930854) (xy 121.535907 -285.936786) (xy 121.583178 -285.950478) (xy 121.62764 -285.971576)
			(xy 121.668143 -285.999532) (xy 121.703636 -286.033624) (xy 121.733201 -286.072968) (xy 121.756072 -286.116545)
			(xy 121.771656 -286.163226) (xy 121.779551 -286.211803) (xy 121.780046 -286.2364) (xy 122.108724 -286.2364)
			(xy 122.112899 -286.186022) (xy 122.125308 -286.137019) (xy 122.145613 -286.090726) (xy 122.173261 -286.048407)
			(xy 122.207498 -286.011216) (xy 122.247388 -285.980167) (xy 122.291845 -285.956107) (xy 122.339656 -285.939692)
			(xy 122.389517 -285.931371) (xy 122.414792 -285.930848) (xy 123.354846 -285.930848) (xy 123.380121 -285.931354)
			(xy 123.42998 -285.93968) (xy 123.477788 -285.9561) (xy 123.522243 -285.980163) (xy 123.562131 -286.011215)
			(xy 123.596364 -286.048408) (xy 123.62401 -286.090727) (xy 123.644314 -286.13702) (xy 123.656722 -286.186023)
			(xy 123.660896 -286.2364) (xy 123.660895 -286.23641) (xy 123.988842 -286.23641) (xy 123.992802 -286.187356)
			(xy 124.004579 -286.139572) (xy 124.02387 -286.094296) (xy 124.050173 -286.0527) (xy 124.082808 -286.015863)
			(xy 124.120929 -285.984738) (xy 124.16355 -285.960131) (xy 124.209566 -285.942679) (xy 124.257785 -285.932835)
			(xy 124.30696 -285.930854) (xy 124.355815 -285.936786) (xy 124.403086 -285.950478) (xy 124.447548 -285.971576)
			(xy 124.488051 -285.999532) (xy 124.523544 -286.033624) (xy 124.553109 -286.072968) (xy 124.57598 -286.116545)
			(xy 124.591564 -286.163226) (xy 124.599459 -286.211803) (xy 124.599954 -286.2364) (xy 124.928625 -286.2364)
			(xy 124.932799 -286.186022) (xy 124.945209 -286.137017) (xy 124.965515 -286.090724) (xy 124.993163 -286.048405)
			(xy 125.027401 -286.011213) (xy 125.067293 -285.980164) (xy 125.111751 -285.956104) (xy 125.159563 -285.93969)
			(xy 125.209424 -285.93137) (xy 125.2347 -285.930848) (xy 126.174754 -285.930848) (xy 126.200036 -285.931317)
			(xy 126.249912 -285.939633) (xy 126.297738 -285.956046) (xy 126.34221 -285.980107) (xy 126.382115 -286.01116)
			(xy 126.416363 -286.048359) (xy 126.444022 -286.090688) (xy 126.464335 -286.136992) (xy 126.476749 -286.186009)
			(xy 126.480925 -286.2364) (xy 126.476749 -286.286791) (xy 126.464335 -286.335808) (xy 126.444022 -286.382112)
			(xy 126.416363 -286.424441) (xy 126.382115 -286.46164) (xy 126.34221 -286.492693) (xy 126.297738 -286.516754)
			(xy 126.249912 -286.533167) (xy 126.200036 -286.541483) (xy 126.174754 -286.541972) (xy 125.2347 -286.541972)
			(xy 125.209424 -286.54143) (xy 125.159563 -286.53311) (xy 125.111751 -286.516696) (xy 125.067293 -286.492636)
			(xy 125.027401 -286.461587) (xy 124.993163 -286.424395) (xy 124.965515 -286.382076) (xy 124.945209 -286.335783)
			(xy 124.932799 -286.286778) (xy 124.928625 -286.2364) (xy 124.599954 -286.2364) (xy 124.599954 -286.23641)
			(xy 124.599459 -286.261017) (xy 124.591564 -286.309594) (xy 124.57598 -286.356275) (xy 124.553109 -286.399852)
			(xy 124.523544 -286.439196) (xy 124.488051 -286.473288) (xy 124.447548 -286.501244) (xy 124.403086 -286.522342)
			(xy 124.355815 -286.536034) (xy 124.30696 -286.541966) (xy 124.257785 -286.539985) (xy 124.209566 -286.530141)
			(xy 124.16355 -286.512689) (xy 124.120929 -286.488082) (xy 124.082808 -286.456957) (xy 124.050173 -286.42012)
			(xy 124.02387 -286.378524) (xy 124.004579 -286.333248) (xy 123.992802 -286.285464) (xy 123.988842 -286.23641)
			(xy 123.660895 -286.23641) (xy 123.656722 -286.286777) (xy 123.644314 -286.33578) (xy 123.62401 -286.382073)
			(xy 123.596364 -286.424392) (xy 123.562131 -286.461585) (xy 123.522243 -286.492637) (xy 123.477788 -286.5167)
			(xy 123.42998 -286.53312) (xy 123.380121 -286.541446) (xy 123.354846 -286.541972) (xy 122.414792 -286.541972)
			(xy 122.389517 -286.541429) (xy 122.339656 -286.533108) (xy 122.291845 -286.516693) (xy 122.247388 -286.492633)
			(xy 122.207498 -286.461584) (xy 122.173261 -286.424393) (xy 122.145613 -286.382074) (xy 122.125308 -286.335781)
			(xy 122.112899 -286.286778) (xy 122.108724 -286.2364) (xy 121.780046 -286.2364) (xy 121.780046 -286.23641)
			(xy 121.779551 -286.261017) (xy 121.771656 -286.309594) (xy 121.756072 -286.356275) (xy 121.733201 -286.399852)
			(xy 121.703636 -286.439196) (xy 121.668143 -286.473288) (xy 121.62764 -286.501244) (xy 121.583178 -286.522342)
			(xy 121.535907 -286.536034) (xy 121.487052 -286.541966) (xy 121.437877 -286.539985) (xy 121.389658 -286.530141)
			(xy 121.343642 -286.512689) (xy 121.301021 -286.488082) (xy 121.2629 -286.456957) (xy 121.230265 -286.42012)
			(xy 121.203962 -286.378524) (xy 121.184671 -286.333248) (xy 121.172894 -286.285464) (xy 121.168934 -286.23641)
			(xy 120.840824 -286.23641) (xy 120.836649 -286.286788) (xy 120.824237 -286.335802) (xy 120.803926 -286.382104)
			(xy 120.776271 -286.424431) (xy 120.742026 -286.461629) (xy 120.702126 -286.492683) (xy 120.657658 -286.516745)
			(xy 120.609836 -286.53316) (xy 120.559964 -286.54148) (xy 120.534684 -286.541972) (xy 119.59463 -286.541972)
			(xy 119.56935 -286.541461) (xy 119.51948 -286.533144) (xy 119.47166 -286.516731) (xy 119.427193 -286.492671)
			(xy 119.387293 -286.461619) (xy 119.353048 -286.424423) (xy 119.325394 -286.382098) (xy 119.305083 -286.335798)
			(xy 119.292671 -286.286786) (xy 119.288495 -286.2364) (xy 118.960138 -286.2364) (xy 118.960138 -286.23641)
			(xy 118.959643 -286.261017) (xy 118.951748 -286.309594) (xy 118.936164 -286.356275) (xy 118.913293 -286.399852)
			(xy 118.883728 -286.439196) (xy 118.848235 -286.473288) (xy 118.807732 -286.501244) (xy 118.76327 -286.522342)
			(xy 118.715999 -286.536034) (xy 118.667144 -286.541966) (xy 118.617969 -286.539985) (xy 118.56975 -286.530141)
			(xy 118.523734 -286.512689) (xy 118.481113 -286.488082) (xy 118.442992 -286.456957) (xy 118.410357 -286.42012)
			(xy 118.384054 -286.378524) (xy 118.364763 -286.333248) (xy 118.352986 -286.285464) (xy 118.349026 -286.23641)
			(xy 118.020924 -286.23641) (xy 118.016749 -286.286789) (xy 118.004336 -286.335803) (xy 117.984025 -286.382106)
			(xy 117.956369 -286.424434) (xy 117.922123 -286.461632) (xy 117.882222 -286.492685) (xy 117.837753 -286.516748)
			(xy 117.789929 -286.533162) (xy 117.740057 -286.541481) (xy 117.714776 -286.541972) (xy 116.774722 -286.541972)
			(xy 116.749443 -286.541461) (xy 116.699574 -286.533142) (xy 116.651754 -286.516729) (xy 116.607288 -286.492668)
			(xy 116.56739 -286.461616) (xy 116.533146 -286.424421) (xy 116.505492 -286.382096) (xy 116.485183 -286.335796)
			(xy 116.472771 -286.286785) (xy 116.468595 -286.2364) (xy 116.139976 -286.2364) (xy 116.139976 -286.23641)
			(xy 116.139481 -286.261017) (xy 116.131586 -286.309594) (xy 116.116002 -286.356275) (xy 116.093131 -286.399852)
			(xy 116.063566 -286.439196) (xy 116.028073 -286.473288) (xy 115.98757 -286.501244) (xy 115.943108 -286.522342)
			(xy 115.895837 -286.536034) (xy 115.846982 -286.541966) (xy 115.797807 -286.539985) (xy 115.749588 -286.530141)
			(xy 115.703572 -286.512689) (xy 115.660951 -286.488082) (xy 115.62283 -286.456957) (xy 115.590195 -286.42012)
			(xy 115.563892 -286.378524) (xy 115.544601 -286.333248) (xy 115.532824 -286.285464) (xy 115.528864 -286.23641)
			(xy 108.626402 -286.23641) (xy 108.625907 -286.261017) (xy 108.618012 -286.309594) (xy 108.602428 -286.356275)
			(xy 108.579557 -286.399852) (xy 108.549992 -286.439196) (xy 108.514499 -286.473288) (xy 108.473996 -286.501244)
			(xy 108.429534 -286.522342) (xy 108.382263 -286.536034) (xy 108.333408 -286.541966) (xy 108.284233 -286.539985)
			(xy 108.236014 -286.530141) (xy 108.189998 -286.512689) (xy 108.147377 -286.488082) (xy 108.109256 -286.456957)
			(xy 108.076621 -286.42012) (xy 108.050318 -286.378524) (xy 108.031027 -286.333248) (xy 108.01925 -286.285464)
			(xy 108.01529 -286.23641) (xy 107.687095 -286.23641) (xy 107.682921 -286.286778) (xy 107.670513 -286.335781)
			(xy 107.650209 -286.382074) (xy 107.622563 -286.424394) (xy 107.588328 -286.461587) (xy 107.54844 -286.492639)
			(xy 107.503984 -286.516702) (xy 107.456175 -286.533121) (xy 107.406315 -286.541447) (xy 107.38104 -286.541972)
			(xy 106.440986 -286.541972) (xy 106.415711 -286.541429) (xy 106.365851 -286.533107) (xy 106.318041 -286.516692)
			(xy 106.273585 -286.492631) (xy 106.233695 -286.461582) (xy 106.19946 -286.424391) (xy 106.171813 -286.382072)
			(xy 106.151508 -286.33578) (xy 106.139099 -286.286777) (xy 106.134924 -286.2364) (xy 105.80624 -286.2364)
			(xy 105.80624 -286.23641) (xy 105.805745 -286.261017) (xy 105.79785 -286.309594) (xy 105.782266 -286.356275)
			(xy 105.759395 -286.399852) (xy 105.72983 -286.439196) (xy 105.694337 -286.473288) (xy 105.653834 -286.501244)
			(xy 105.609372 -286.522342) (xy 105.562101 -286.536034) (xy 105.513246 -286.541966) (xy 105.464071 -286.539985)
			(xy 105.415852 -286.530141) (xy 105.369836 -286.512689) (xy 105.327215 -286.488082) (xy 105.289094 -286.456957)
			(xy 105.256459 -286.42012) (xy 105.230156 -286.378524) (xy 105.210865 -286.333248) (xy 105.199088 -286.285464)
			(xy 105.195128 -286.23641) (xy 104.867195 -286.23641) (xy 104.863021 -286.286778) (xy 104.850613 -286.335783)
			(xy 104.830308 -286.382076) (xy 104.802661 -286.424397) (xy 104.768425 -286.46159) (xy 104.728535 -286.492642)
			(xy 104.684079 -286.516705) (xy 104.636268 -286.533122) (xy 104.586407 -286.541448) (xy 104.561132 -286.541972)
			(xy 103.621078 -286.541972) (xy 103.595804 -286.541428) (xy 103.545945 -286.533105) (xy 103.498136 -286.516689)
			(xy 103.453681 -286.492629) (xy 103.413792 -286.461579) (xy 103.379558 -286.424388) (xy 103.351911 -286.38207)
			(xy 103.331607 -286.335778) (xy 103.319199 -286.286776) (xy 103.315024 -286.2364) (xy 102.986332 -286.2364)
			(xy 102.986332 -286.23641) (xy 102.985837 -286.261017) (xy 102.977942 -286.309594) (xy 102.962358 -286.356275)
			(xy 102.939487 -286.399852) (xy 102.909922 -286.439196) (xy 102.874429 -286.473288) (xy 102.833926 -286.501244)
			(xy 102.789464 -286.522342) (xy 102.742193 -286.536034) (xy 102.693338 -286.541966) (xy 102.644163 -286.539985)
			(xy 102.595944 -286.530141) (xy 102.549928 -286.512689) (xy 102.507307 -286.488082) (xy 102.469186 -286.456957)
			(xy 102.436551 -286.42012) (xy 102.410248 -286.378524) (xy 102.390957 -286.333248) (xy 102.37918 -286.285464)
			(xy 102.37522 -286.23641) (xy 102.047295 -286.23641) (xy 102.043121 -286.286779) (xy 102.030712 -286.335784)
			(xy 102.010407 -286.382079) (xy 101.982759 -286.4244) (xy 101.948522 -286.461593) (xy 101.908631 -286.492645)
			(xy 101.864173 -286.516707) (xy 101.816362 -286.533124) (xy 101.7665 -286.541448) (xy 101.741224 -286.541972)
			(xy 100.80117 -286.541972) (xy 100.775896 -286.541428) (xy 100.726038 -286.533103) (xy 100.678231 -286.516687)
			(xy 100.633777 -286.492626) (xy 100.593889 -286.461576) (xy 100.559656 -286.424385) (xy 100.53201 -286.382067)
			(xy 100.511706 -286.335777) (xy 100.499298 -286.286775) (xy 100.495124 -286.2364) (xy 100.166424 -286.2364)
			(xy 100.166424 -286.23641) (xy 100.165929 -286.261017) (xy 100.158034 -286.309594) (xy 100.14245 -286.356275)
			(xy 100.119579 -286.399852) (xy 100.090014 -286.439196) (xy 100.054521 -286.473288) (xy 100.014018 -286.501244)
			(xy 99.969556 -286.522342) (xy 99.922285 -286.536034) (xy 99.87343 -286.541966) (xy 99.824255 -286.539985)
			(xy 99.776036 -286.530141) (xy 99.73002 -286.512689) (xy 99.687399 -286.488082) (xy 99.649278 -286.456957)
			(xy 99.616643 -286.42012) (xy 99.59034 -286.378524) (xy 99.571049 -286.333248) (xy 99.559272 -286.285464)
			(xy 99.555312 -286.23641) (xy 99.227224 -286.23641) (xy 99.223049 -286.28679) (xy 99.210635 -286.335806)
			(xy 99.190323 -286.38211) (xy 99.162665 -286.424438) (xy 99.128418 -286.461637) (xy 99.088514 -286.49269)
			(xy 99.044043 -286.516752) (xy 98.996218 -286.533165) (xy 98.946344 -286.541482) (xy 98.921062 -286.541972)
			(xy 97.981008 -286.541972) (xy 97.95573 -286.54146) (xy 97.905862 -286.533139) (xy 97.858045 -286.516725)
			(xy 97.813581 -286.492663) (xy 97.773684 -286.461611) (xy 97.739443 -286.424416) (xy 97.71179 -286.382092)
			(xy 97.691482 -286.335794) (xy 97.679071 -286.286784) (xy 97.674895 -286.2364) (xy 97.34685 -286.2364)
			(xy 97.342678 -286.286746) (xy 97.330275 -286.335719) (xy 97.30998 -286.381981) (xy 97.282347 -286.424272)
			(xy 97.248129 -286.461438) (xy 97.20826 -286.492463) (xy 97.163827 -286.516503) (xy 97.116044 -286.532901)
			(xy 97.066213 -286.541209) (xy 97.040954 -286.541718) (xy 97.017097 -286.541256) (xy 96.969965 -286.533834)
			(xy 96.924558 -286.519177) (xy 96.881981 -286.497642) (xy 96.843268 -286.469752) (xy 96.809359 -286.436185)
			(xy 96.794828 -286.417258) (xy 96.794828 -286.417004) (xy 96.787716 -286.409384) (xy 96.779254 -286.402503)
			(xy 96.758451 -286.39603) (xy 96.747584 -286.396938) (xy 96.648524 -286.409638) (xy 96.645222 -286.410146)
			(xy 96.634554 -286.418528) (xy 96.629355 -286.422849) (xy 96.621255 -286.433667) (xy 96.618552 -286.439864)
			(xy 96.618552 -286.440118) (xy 96.61071 -286.459488) (xy 96.592527 -286.497118) (xy 96.58223 -286.515302)
			(xy 96.548194 -286.573722) (xy 96.544384 -286.58058) (xy 96.541584 -286.58615) (xy 96.538504 -286.598226)
			(xy 96.538288 -286.604456) (xy 96.538288 -286.670242) (xy 96.538542 -286.67583) (xy 96.53977 -286.684038)
			(xy 96.54676 -286.699078) (xy 96.552258 -286.705294) (xy 96.572832 -286.727138) (xy 96.582484 -286.735266)
			(xy 96.58656 -286.737679) (xy 96.595377 -286.741137) (xy 96.60001 -286.742124) (xy 96.604074 -286.742632)
			(xy 96.628703 -286.745796) (xy 96.676548 -286.759074) (xy 96.721614 -286.779918) (xy 96.762714 -286.807779)
			(xy 96.798765 -286.841922) (xy 96.828817 -286.881449) (xy 96.852077 -286.925317) (xy 96.867933 -286.97237)
			(xy 96.875968 -287.021369) (xy 96.875968 -287.04667) (xy 99.085412 -287.04667) (xy 99.089372 -286.997616)
			(xy 99.101149 -286.949832) (xy 99.12044 -286.904556) (xy 99.146743 -286.86296) (xy 99.179378 -286.826123)
			(xy 99.217499 -286.794998) (xy 99.26012 -286.770391) (xy 99.306136 -286.752939) (xy 99.354355 -286.743095)
			(xy 99.40353 -286.741114) (xy 99.452385 -286.747046) (xy 99.499656 -286.760738) (xy 99.544118 -286.781836)
			(xy 99.584621 -286.809792) (xy 99.620114 -286.843884) (xy 99.649679 -286.883228) (xy 99.67255 -286.926805)
			(xy 99.688134 -286.973486) (xy 99.696029 -287.022063) (xy 99.696514 -287.046162) (xy 101.90532 -287.046162)
			(xy 101.90928 -286.997108) (xy 101.921057 -286.949324) (xy 101.940348 -286.904048) (xy 101.966651 -286.862452)
			(xy 101.999286 -286.825615) (xy 102.037407 -286.79449) (xy 102.080028 -286.769883) (xy 102.126044 -286.752431)
			(xy 102.174263 -286.742587) (xy 102.223438 -286.740606) (xy 102.272293 -286.746538) (xy 102.319564 -286.76023)
			(xy 102.364026 -286.781328) (xy 102.404529 -286.809284) (xy 102.440022 -286.843376) (xy 102.469587 -286.88272)
			(xy 102.492458 -286.926297) (xy 102.508042 -286.972978) (xy 102.515937 -287.021555) (xy 102.516432 -287.046162)
			(xy 104.725228 -287.046162) (xy 104.729188 -286.997108) (xy 104.740965 -286.949324) (xy 104.760256 -286.904048)
			(xy 104.786559 -286.862452) (xy 104.819194 -286.825615) (xy 104.857315 -286.79449) (xy 104.899936 -286.769883)
			(xy 104.945952 -286.752431) (xy 104.994171 -286.742587) (xy 105.043346 -286.740606) (xy 105.092201 -286.746538)
			(xy 105.139472 -286.76023) (xy 105.183934 -286.781328) (xy 105.224437 -286.809284) (xy 105.25993 -286.843376)
			(xy 105.289495 -286.88272) (xy 105.312366 -286.926297) (xy 105.32795 -286.972978) (xy 105.335845 -287.021555)
			(xy 105.33634 -287.046162) (xy 105.33633 -287.04667) (xy 107.54539 -287.04667) (xy 107.54935 -286.997616)
			(xy 107.561127 -286.949832) (xy 107.580418 -286.904556) (xy 107.606721 -286.86296) (xy 107.639356 -286.826123)
			(xy 107.677477 -286.794998) (xy 107.720098 -286.770391) (xy 107.766114 -286.752939) (xy 107.814333 -286.743095)
			(xy 107.863508 -286.741114) (xy 107.912363 -286.747046) (xy 107.959634 -286.760738) (xy 108.004096 -286.781836)
			(xy 108.044599 -286.809792) (xy 108.080092 -286.843884) (xy 108.109657 -286.883228) (xy 108.132528 -286.926805)
			(xy 108.148112 -286.973486) (xy 108.156007 -287.022063) (xy 108.156493 -287.0462) (xy 108.484876 -287.0462)
			(xy 108.489052 -286.995814) (xy 108.501463 -286.946803) (xy 108.521772 -286.900503) (xy 108.549424 -286.858177)
			(xy 108.583666 -286.82098) (xy 108.623563 -286.789926) (xy 108.668028 -286.765862) (xy 108.715846 -286.749445)
			(xy 108.765715 -286.741123) (xy 108.790994 -286.7406) (xy 109.731048 -286.7406) (xy 109.756319 -286.741202)
			(xy 109.806169 -286.749527) (xy 109.85397 -286.765944) (xy 109.898418 -286.790004) (xy 109.938299 -286.821051)
			(xy 109.972527 -286.858238) (xy 110.000168 -286.900551) (xy 110.020468 -286.946836) (xy 110.032874 -286.995831)
			(xy 110.037045 -287.046162) (xy 110.365298 -287.046162) (xy 110.369258 -286.997108) (xy 110.381035 -286.949324)
			(xy 110.400326 -286.904048) (xy 110.426629 -286.862452) (xy 110.459264 -286.825615) (xy 110.497385 -286.79449)
			(xy 110.540006 -286.769883) (xy 110.586022 -286.752431) (xy 110.634241 -286.742587) (xy 110.683416 -286.740606)
			(xy 110.732271 -286.746538) (xy 110.779542 -286.76023) (xy 110.824004 -286.781328) (xy 110.864507 -286.809284)
			(xy 110.9 -286.843376) (xy 110.929565 -286.88272) (xy 110.952436 -286.926297) (xy 110.96802 -286.972978)
			(xy 110.975915 -287.021555) (xy 110.97641 -287.046162) (xy 113.178856 -287.046162) (xy 113.182816 -286.997108)
			(xy 113.194593 -286.949324) (xy 113.213884 -286.904048) (xy 113.240187 -286.862452) (xy 113.272822 -286.825615)
			(xy 113.310943 -286.79449) (xy 113.353564 -286.769883) (xy 113.39958 -286.752431) (xy 113.447799 -286.742587)
			(xy 113.496974 -286.740606) (xy 113.545829 -286.746538) (xy 113.5931 -286.76023) (xy 113.637562 -286.781328)
			(xy 113.678065 -286.809284) (xy 113.713558 -286.843376) (xy 113.743123 -286.88272) (xy 113.765994 -286.926297)
			(xy 113.781578 -286.972978) (xy 113.789473 -287.021555) (xy 113.789968 -287.046162) (xy 113.789967 -287.0462)
			(xy 114.118547 -287.0462) (xy 114.122723 -286.995807) (xy 114.135137 -286.94679) (xy 114.155449 -286.900484)
			(xy 114.183106 -286.858153) (xy 114.217354 -286.820951) (xy 114.257258 -286.789895) (xy 114.301729 -286.76583)
			(xy 114.349555 -286.749413) (xy 114.399431 -286.741092) (xy 114.424714 -286.7406) (xy 115.364768 -286.7406)
			(xy 115.390045 -286.741166) (xy 115.439911 -286.749483) (xy 115.487728 -286.765894) (xy 115.532191 -286.789952)
			(xy 115.572088 -286.821001) (xy 115.606329 -286.858193) (xy 115.633981 -286.900515) (xy 115.65429 -286.946811)
			(xy 115.666701 -286.995818) (xy 115.670877 -287.0462) (xy 115.670859 -287.046416) (xy 115.999018 -287.046416)
			(xy 116.002978 -286.997362) (xy 116.014755 -286.949578) (xy 116.034046 -286.904302) (xy 116.060349 -286.862706)
			(xy 116.092984 -286.825869) (xy 116.131105 -286.794744) (xy 116.173726 -286.770137) (xy 116.219742 -286.752685)
			(xy 116.267961 -286.742841) (xy 116.317136 -286.74086) (xy 116.365991 -286.746792) (xy 116.413262 -286.760484)
			(xy 116.457724 -286.781582) (xy 116.498227 -286.809538) (xy 116.53372 -286.84363) (xy 116.563285 -286.882974)
			(xy 116.586156 -286.926551) (xy 116.60174 -286.973232) (xy 116.609635 -287.021809) (xy 116.610125 -287.046162)
			(xy 118.818926 -287.046162) (xy 118.822886 -286.997108) (xy 118.834663 -286.949324) (xy 118.853954 -286.904048)
			(xy 118.880257 -286.862452) (xy 118.912892 -286.825615) (xy 118.951013 -286.79449) (xy 118.993634 -286.769883)
			(xy 119.03965 -286.752431) (xy 119.087869 -286.742587) (xy 119.137044 -286.740606) (xy 119.185899 -286.746538)
			(xy 119.23317 -286.76023) (xy 119.277632 -286.781328) (xy 119.318135 -286.809284) (xy 119.353628 -286.843376)
			(xy 119.383193 -286.88272) (xy 119.406064 -286.926297) (xy 119.421648 -286.972978) (xy 119.429543 -287.021555)
			(xy 119.430038 -287.046162) (xy 121.638834 -287.046162) (xy 121.642794 -286.997108) (xy 121.654571 -286.949324)
			(xy 121.673862 -286.904048) (xy 121.700165 -286.862452) (xy 121.7328 -286.825615) (xy 121.770921 -286.79449)
			(xy 121.813542 -286.769883) (xy 121.859558 -286.752431) (xy 121.907777 -286.742587) (xy 121.956952 -286.740606)
			(xy 122.005807 -286.746538) (xy 122.053078 -286.76023) (xy 122.09754 -286.781328) (xy 122.138043 -286.809284)
			(xy 122.173536 -286.843376) (xy 122.203101 -286.88272) (xy 122.225972 -286.926297) (xy 122.241556 -286.972978)
			(xy 122.249451 -287.021555) (xy 122.249946 -287.046162) (xy 124.458996 -287.046162) (xy 124.462956 -286.997108)
			(xy 124.474733 -286.949324) (xy 124.494024 -286.904048) (xy 124.520327 -286.862452) (xy 124.552962 -286.825615)
			(xy 124.591083 -286.79449) (xy 124.633704 -286.769883) (xy 124.67972 -286.752431) (xy 124.727939 -286.742587)
			(xy 124.777114 -286.740606) (xy 124.825969 -286.746538) (xy 124.87324 -286.76023) (xy 124.917702 -286.781328)
			(xy 124.958205 -286.809284) (xy 124.993698 -286.843376) (xy 125.023263 -286.88272) (xy 125.046134 -286.926297)
			(xy 125.061718 -286.972978) (xy 125.069613 -287.021555) (xy 125.070108 -287.046162) (xy 125.069613 -287.070769)
			(xy 125.061718 -287.119346) (xy 125.046134 -287.166027) (xy 125.023263 -287.209604) (xy 124.993698 -287.248948)
			(xy 124.958205 -287.28304) (xy 124.917702 -287.310996) (xy 124.87324 -287.332094) (xy 124.825969 -287.345786)
			(xy 124.777114 -287.351718) (xy 124.727939 -287.349737) (xy 124.67972 -287.339893) (xy 124.633704 -287.322441)
			(xy 124.591083 -287.297834) (xy 124.552962 -287.266709) (xy 124.520327 -287.229872) (xy 124.494024 -287.188276)
			(xy 124.474733 -287.143) (xy 124.462956 -287.095216) (xy 124.458996 -287.046162) (xy 122.249946 -287.046162)
			(xy 122.249451 -287.070769) (xy 122.241556 -287.119346) (xy 122.225972 -287.166027) (xy 122.203101 -287.209604)
			(xy 122.173536 -287.248948) (xy 122.138043 -287.28304) (xy 122.09754 -287.310996) (xy 122.053078 -287.332094)
			(xy 122.005807 -287.345786) (xy 121.956952 -287.351718) (xy 121.907777 -287.349737) (xy 121.859558 -287.339893)
			(xy 121.813542 -287.322441) (xy 121.770921 -287.297834) (xy 121.7328 -287.266709) (xy 121.700165 -287.229872)
			(xy 121.673862 -287.188276) (xy 121.654571 -287.143) (xy 121.642794 -287.095216) (xy 121.638834 -287.046162)
			(xy 119.430038 -287.046162) (xy 119.429543 -287.070769) (xy 119.421648 -287.119346) (xy 119.406064 -287.166027)
			(xy 119.383193 -287.209604) (xy 119.353628 -287.248948) (xy 119.318135 -287.28304) (xy 119.277632 -287.310996)
			(xy 119.23317 -287.332094) (xy 119.185899 -287.345786) (xy 119.137044 -287.351718) (xy 119.087869 -287.349737)
			(xy 119.03965 -287.339893) (xy 118.993634 -287.322441) (xy 118.951013 -287.297834) (xy 118.912892 -287.266709)
			(xy 118.880257 -287.229872) (xy 118.853954 -287.188276) (xy 118.834663 -287.143) (xy 118.822886 -287.095216)
			(xy 118.818926 -287.046162) (xy 116.610125 -287.046162) (xy 116.61013 -287.046416) (xy 116.609635 -287.071023)
			(xy 116.60174 -287.1196) (xy 116.586156 -287.166281) (xy 116.563285 -287.209858) (xy 116.53372 -287.249202)
			(xy 116.498227 -287.283294) (xy 116.457724 -287.31125) (xy 116.413262 -287.332348) (xy 116.365991 -287.34604)
			(xy 116.317136 -287.351972) (xy 116.267961 -287.349991) (xy 116.219742 -287.340147) (xy 116.173726 -287.322695)
			(xy 116.131105 -287.298088) (xy 116.092984 -287.266963) (xy 116.060349 -287.230126) (xy 116.034046 -287.18853)
			(xy 116.014755 -287.143254) (xy 116.002978 -287.09547) (xy 115.999018 -287.046416) (xy 115.670859 -287.046416)
			(xy 115.666701 -287.096582) (xy 115.65429 -287.145589) (xy 115.633981 -287.191885) (xy 115.606329 -287.234207)
			(xy 115.572088 -287.271399) (xy 115.532191 -287.302448) (xy 115.487728 -287.326506) (xy 115.439911 -287.342917)
			(xy 115.390045 -287.351234) (xy 115.364768 -287.351724) (xy 114.424714 -287.351724) (xy 114.399431 -287.351308)
			(xy 114.349555 -287.342987) (xy 114.301729 -287.32657) (xy 114.257258 -287.302505) (xy 114.217354 -287.271449)
			(xy 114.183106 -287.234247) (xy 114.155449 -287.191916) (xy 114.135137 -287.14561) (xy 114.122723 -287.096593)
			(xy 114.118547 -287.0462) (xy 113.789967 -287.0462) (xy 113.789473 -287.070769) (xy 113.781578 -287.119346)
			(xy 113.765994 -287.166027) (xy 113.743123 -287.209604) (xy 113.713558 -287.248948) (xy 113.678065 -287.28304)
			(xy 113.637562 -287.310996) (xy 113.5931 -287.332094) (xy 113.545829 -287.345786) (xy 113.496974 -287.351718)
			(xy 113.447799 -287.349737) (xy 113.39958 -287.339893) (xy 113.353564 -287.322441) (xy 113.310943 -287.297834)
			(xy 113.272822 -287.266709) (xy 113.240187 -287.229872) (xy 113.213884 -287.188276) (xy 113.194593 -287.143)
			(xy 113.182816 -287.095216) (xy 113.178856 -287.046162) (xy 110.97641 -287.046162) (xy 110.975915 -287.070769)
			(xy 110.96802 -287.119346) (xy 110.952436 -287.166027) (xy 110.929565 -287.209604) (xy 110.9 -287.248948)
			(xy 110.864507 -287.28304) (xy 110.824004 -287.310996) (xy 110.779542 -287.332094) (xy 110.732271 -287.345786)
			(xy 110.683416 -287.351718) (xy 110.634241 -287.349737) (xy 110.586022 -287.339893) (xy 110.540006 -287.322441)
			(xy 110.497385 -287.297834) (xy 110.459264 -287.266709) (xy 110.426629 -287.229872) (xy 110.400326 -287.188276)
			(xy 110.381035 -287.143) (xy 110.369258 -287.095216) (xy 110.365298 -287.046162) (xy 110.037045 -287.046162)
			(xy 110.037048 -287.0462) (xy 110.032874 -287.096569) (xy 110.020468 -287.145564) (xy 110.000168 -287.191849)
			(xy 109.972527 -287.234162) (xy 109.938299 -287.271349) (xy 109.898418 -287.302396) (xy 109.85397 -287.326456)
			(xy 109.806169 -287.342873) (xy 109.756319 -287.351198) (xy 109.731048 -287.351724) (xy 108.790994 -287.351724)
			(xy 108.765715 -287.351277) (xy 108.715846 -287.342955) (xy 108.668028 -287.326538) (xy 108.623563 -287.302474)
			(xy 108.583666 -287.27142) (xy 108.549424 -287.234223) (xy 108.521772 -287.191897) (xy 108.501463 -287.145597)
			(xy 108.489052 -287.096586) (xy 108.484876 -287.0462) (xy 108.156493 -287.0462) (xy 108.156502 -287.04667)
			(xy 108.156007 -287.071277) (xy 108.148112 -287.119854) (xy 108.132528 -287.166535) (xy 108.109657 -287.210112)
			(xy 108.080092 -287.249456) (xy 108.044599 -287.283548) (xy 108.004096 -287.311504) (xy 107.959634 -287.332602)
			(xy 107.912363 -287.346294) (xy 107.863508 -287.352226) (xy 107.814333 -287.350245) (xy 107.766114 -287.340401)
			(xy 107.720098 -287.322949) (xy 107.677477 -287.298342) (xy 107.639356 -287.267217) (xy 107.606721 -287.23038)
			(xy 107.580418 -287.188784) (xy 107.561127 -287.143508) (xy 107.54935 -287.095724) (xy 107.54539 -287.04667)
			(xy 105.33633 -287.04667) (xy 105.335845 -287.070769) (xy 105.32795 -287.119346) (xy 105.312366 -287.166027)
			(xy 105.289495 -287.209604) (xy 105.25993 -287.248948) (xy 105.224437 -287.28304) (xy 105.183934 -287.310996)
			(xy 105.139472 -287.332094) (xy 105.092201 -287.345786) (xy 105.043346 -287.351718) (xy 104.994171 -287.349737)
			(xy 104.945952 -287.339893) (xy 104.899936 -287.322441) (xy 104.857315 -287.297834) (xy 104.819194 -287.266709)
			(xy 104.786559 -287.229872) (xy 104.760256 -287.188276) (xy 104.740965 -287.143) (xy 104.729188 -287.095216)
			(xy 104.725228 -287.046162) (xy 102.516432 -287.046162) (xy 102.515937 -287.070769) (xy 102.508042 -287.119346)
			(xy 102.492458 -287.166027) (xy 102.469587 -287.209604) (xy 102.440022 -287.248948) (xy 102.404529 -287.28304)
			(xy 102.364026 -287.310996) (xy 102.319564 -287.332094) (xy 102.272293 -287.345786) (xy 102.223438 -287.351718)
			(xy 102.174263 -287.349737) (xy 102.126044 -287.339893) (xy 102.080028 -287.322441) (xy 102.037407 -287.297834)
			(xy 101.999286 -287.266709) (xy 101.966651 -287.229872) (xy 101.940348 -287.188276) (xy 101.921057 -287.143)
			(xy 101.90928 -287.095216) (xy 101.90532 -287.046162) (xy 99.696514 -287.046162) (xy 99.696524 -287.04667)
			(xy 99.696029 -287.071277) (xy 99.688134 -287.119854) (xy 99.67255 -287.166535) (xy 99.649679 -287.210112)
			(xy 99.620114 -287.249456) (xy 99.584621 -287.283548) (xy 99.544118 -287.311504) (xy 99.499656 -287.332602)
			(xy 99.452385 -287.346294) (xy 99.40353 -287.352226) (xy 99.354355 -287.350245) (xy 99.306136 -287.340401)
			(xy 99.26012 -287.322949) (xy 99.217499 -287.298342) (xy 99.179378 -287.267217) (xy 99.146743 -287.23038)
			(xy 99.12044 -287.188784) (xy 99.101149 -287.143508) (xy 99.089372 -287.095724) (xy 99.085412 -287.04667)
			(xy 96.875968 -287.04667) (xy 96.875968 -287.071023) (xy 96.867935 -287.120022) (xy 96.85208 -287.167076)
			(xy 96.828821 -287.210944) (xy 96.798771 -287.250472) (xy 96.762721 -287.284616) (xy 96.721621 -287.312478)
			(xy 96.676556 -287.333323) (xy 96.628711 -287.346603) (xy 96.604074 -287.349692) (xy 96.60001 -287.3502)
			(xy 96.595374 -287.351176) (xy 96.586552 -287.354629) (xy 96.582484 -287.357058) (xy 96.572832 -287.365186)
			(xy 96.552258 -287.38703) (xy 96.546786 -287.393262) (xy 96.539803 -287.408295) (xy 96.538542 -287.416494)
			(xy 96.538288 -287.422082) (xy 96.538288 -287.50133) (xy 96.538542 -287.505648) (xy 96.539226 -287.511848)
			(xy 96.543213 -287.523664) (xy 96.546416 -287.529016) (xy 96.54794 -287.531048) (xy 96.560714 -287.548899)
			(xy 96.583726 -287.586282) (xy 96.593914 -287.605724) (xy 96.600035 -287.617924) (xy 96.611215 -287.642828)
			(xy 96.616266 -287.655508) (xy 96.616266 -287.655762) (xy 96.618899 -287.661947) (xy 96.62688 -287.672759)
			(xy 96.632014 -287.677098) (xy 96.637602 -287.681416) (xy 96.650302 -287.686496) (xy 96.712024 -287.69437)
			(xy 96.745552 -287.698688) (xy 96.755087 -287.699486) (xy 96.773624 -287.694798) (xy 96.78162 -287.689544)
			(xy 96.793304 -287.67786) (xy 96.795336 -287.674812) (xy 96.809866 -287.65598) (xy 96.84377 -287.622623)
			(xy 96.882428 -287.594913) (xy 96.924908 -287.573519) (xy 96.970186 -287.558956) (xy 97.017173 -287.551574)
			(xy 97.040954 -287.551114) (xy 97.066212 -287.551603) (xy 97.116041 -287.559911) (xy 97.163823 -287.576308)
			(xy 97.208253 -287.600347) (xy 97.248121 -287.631371) (xy 97.282337 -287.668535) (xy 97.30997 -287.710824)
			(xy 97.330264 -287.757085) (xy 97.342666 -287.806056) (xy 97.346838 -287.8564) (xy 97.674907 -287.8564)
			(xy 97.679082 -287.806018) (xy 97.691493 -287.75701) (xy 97.711801 -287.710714) (xy 97.739452 -287.668391)
			(xy 97.773692 -287.631198) (xy 97.813588 -287.600147) (xy 97.858049 -287.576086) (xy 97.905865 -287.559672)
			(xy 97.955731 -287.551352) (xy 97.981008 -287.55086) (xy 98.921062 -287.55086) (xy 98.946345 -287.551306)
			(xy 98.996221 -287.559623) (xy 99.044048 -287.576037) (xy 99.088521 -287.6001) (xy 99.128426 -287.631154)
			(xy 99.162675 -287.668354) (xy 99.190333 -287.710685) (xy 99.210647 -287.75699) (xy 99.223061 -287.806008)
			(xy 99.227237 -287.8564) (xy 99.227235 -287.856422) (xy 99.555312 -287.856422) (xy 99.559272 -287.807368)
			(xy 99.571049 -287.759584) (xy 99.59034 -287.714308) (xy 99.616643 -287.672712) (xy 99.649278 -287.635875)
			(xy 99.687399 -287.60475) (xy 99.73002 -287.580143) (xy 99.776036 -287.562691) (xy 99.824255 -287.552847)
			(xy 99.87343 -287.550866) (xy 99.922285 -287.556798) (xy 99.969556 -287.57049) (xy 100.014018 -287.591588)
			(xy 100.054521 -287.619544) (xy 100.090014 -287.653636) (xy 100.119579 -287.69298) (xy 100.14245 -287.736557)
			(xy 100.158034 -287.783238) (xy 100.165929 -287.831815) (xy 100.166424 -287.8564) (xy 100.495136 -287.8564)
			(xy 100.49931 -287.806027) (xy 100.511718 -287.757027) (xy 100.532021 -287.710738) (xy 100.559665 -287.668422)
			(xy 100.593897 -287.631232) (xy 100.633783 -287.600184) (xy 100.678235 -287.576124) (xy 100.726041 -287.559708)
			(xy 100.775897 -287.551384) (xy 100.80117 -287.55086) (xy 101.741224 -287.55086) (xy 101.766501 -287.55134)
			(xy 101.816365 -287.559664) (xy 101.864178 -287.576082) (xy 101.908638 -287.600145) (xy 101.94853 -287.631198)
			(xy 101.982768 -287.668393) (xy 102.010417 -287.710716) (xy 102.030723 -287.757012) (xy 102.043133 -287.806019)
			(xy 102.047308 -287.8564) (xy 102.047306 -287.856422) (xy 102.37522 -287.856422) (xy 102.37918 -287.807368)
			(xy 102.390957 -287.759584) (xy 102.410248 -287.714308) (xy 102.436551 -287.672712) (xy 102.469186 -287.635875)
			(xy 102.507307 -287.60475) (xy 102.549928 -287.580143) (xy 102.595944 -287.562691) (xy 102.644163 -287.552847)
			(xy 102.693338 -287.550866) (xy 102.742193 -287.556798) (xy 102.789464 -287.57049) (xy 102.833926 -287.591588)
			(xy 102.874429 -287.619544) (xy 102.909922 -287.653636) (xy 102.939487 -287.69298) (xy 102.962358 -287.736557)
			(xy 102.977942 -287.783238) (xy 102.985837 -287.831815) (xy 102.986332 -287.8564) (xy 103.315036 -287.8564)
			(xy 103.31921 -287.806026) (xy 103.331618 -287.757026) (xy 103.351922 -287.710736) (xy 103.379567 -287.668419)
			(xy 103.4138 -287.63123) (xy 103.453687 -287.600182) (xy 103.498141 -287.576122) (xy 103.545948 -287.559707)
			(xy 103.595805 -287.551384) (xy 103.621078 -287.55086) (xy 104.561132 -287.55086) (xy 104.586408 -287.551341)
			(xy 104.636271 -287.559666) (xy 104.684084 -287.576084) (xy 104.728542 -287.600148) (xy 104.768433 -287.631201)
			(xy 104.80267 -287.668396) (xy 104.830318 -287.710718) (xy 104.850624 -287.757013) (xy 104.863033 -287.80602)
			(xy 104.867208 -287.8564) (xy 104.867206 -287.856422) (xy 105.195128 -287.856422) (xy 105.199088 -287.807368)
			(xy 105.210865 -287.759584) (xy 105.230156 -287.714308) (xy 105.256459 -287.672712) (xy 105.289094 -287.635875)
			(xy 105.327215 -287.60475) (xy 105.369836 -287.580143) (xy 105.415852 -287.562691) (xy 105.464071 -287.552847)
			(xy 105.513246 -287.550866) (xy 105.562101 -287.556798) (xy 105.609372 -287.57049) (xy 105.653834 -287.591588)
			(xy 105.694337 -287.619544) (xy 105.72983 -287.653636) (xy 105.759395 -287.69298) (xy 105.782266 -287.736557)
			(xy 105.79785 -287.783238) (xy 105.805745 -287.831815) (xy 105.80624 -287.8564) (xy 106.134936 -287.8564)
			(xy 106.139111 -287.806025) (xy 106.151519 -287.757024) (xy 106.171823 -287.710734) (xy 106.199469 -287.668417)
			(xy 106.233703 -287.631227) (xy 106.273592 -287.600179) (xy 106.318046 -287.576119) (xy 106.365854 -287.559705)
			(xy 106.415712 -287.551383) (xy 106.440986 -287.55086) (xy 107.38104 -287.55086) (xy 107.406316 -287.551341)
			(xy 107.456178 -287.559668) (xy 107.503989 -287.576087) (xy 107.548446 -287.600151) (xy 107.588336 -287.631204)
			(xy 107.622572 -287.668398) (xy 107.65022 -287.71072) (xy 107.670524 -287.757015) (xy 107.682933 -287.806021)
			(xy 107.687108 -287.8564) (xy 107.687106 -287.856422) (xy 108.01529 -287.856422) (xy 108.01925 -287.807368)
			(xy 108.031027 -287.759584) (xy 108.050318 -287.714308) (xy 108.076621 -287.672712) (xy 108.109256 -287.635875)
			(xy 108.147377 -287.60475) (xy 108.189998 -287.580143) (xy 108.236014 -287.562691) (xy 108.284233 -287.552847)
			(xy 108.333408 -287.550866) (xy 108.382263 -287.556798) (xy 108.429534 -287.57049) (xy 108.473996 -287.591588)
			(xy 108.514499 -287.619544) (xy 108.549992 -287.653636) (xy 108.579557 -287.69298) (xy 108.602428 -287.736557)
			(xy 108.618012 -287.783238) (xy 108.625907 -287.831815) (xy 108.626402 -287.856422) (xy 108.955344 -287.856422)
			(xy 108.959304 -287.807368) (xy 108.971081 -287.759584) (xy 108.990372 -287.714308) (xy 109.016675 -287.672712)
			(xy 109.04931 -287.635875) (xy 109.087431 -287.60475) (xy 109.130052 -287.580143) (xy 109.176068 -287.562691)
			(xy 109.224287 -287.552847) (xy 109.273462 -287.550866) (xy 109.322317 -287.556798) (xy 109.369588 -287.57049)
			(xy 109.41405 -287.591588) (xy 109.454553 -287.619544) (xy 109.490046 -287.653636) (xy 109.519611 -287.69298)
			(xy 109.542482 -287.736557) (xy 109.558066 -287.783238) (xy 109.565961 -287.831815) (xy 109.566456 -287.856422)
			(xy 109.895144 -287.856422) (xy 109.899104 -287.807368) (xy 109.910881 -287.759584) (xy 109.930172 -287.714308)
			(xy 109.956475 -287.672712) (xy 109.98911 -287.635875) (xy 110.027231 -287.60475) (xy 110.069852 -287.580143)
			(xy 110.115868 -287.562691) (xy 110.164087 -287.552847) (xy 110.213262 -287.550866) (xy 110.262117 -287.556798)
			(xy 110.309388 -287.57049) (xy 110.35385 -287.591588) (xy 110.394353 -287.619544) (xy 110.429846 -287.653636)
			(xy 110.459411 -287.69298) (xy 110.482282 -287.736557) (xy 110.497866 -287.783238) (xy 110.505761 -287.831815)
			(xy 110.506256 -287.856422) (xy 113.64901 -287.856422) (xy 113.65297 -287.807368) (xy 113.664747 -287.759584)
			(xy 113.684038 -287.714308) (xy 113.710341 -287.672712) (xy 113.742976 -287.635875) (xy 113.781097 -287.60475)
			(xy 113.823718 -287.580143) (xy 113.869734 -287.562691) (xy 113.917953 -287.552847) (xy 113.967128 -287.550866)
			(xy 114.015983 -287.556798) (xy 114.063254 -287.57049) (xy 114.107716 -287.591588) (xy 114.148219 -287.619544)
			(xy 114.183712 -287.653636) (xy 114.213277 -287.69298) (xy 114.236148 -287.736557) (xy 114.251732 -287.783238)
			(xy 114.259627 -287.831815) (xy 114.260122 -287.856422) (xy 114.58881 -287.856422) (xy 114.59277 -287.807368)
			(xy 114.604547 -287.759584) (xy 114.623838 -287.714308) (xy 114.650141 -287.672712) (xy 114.682776 -287.635875)
			(xy 114.720897 -287.60475) (xy 114.763518 -287.580143) (xy 114.809534 -287.562691) (xy 114.857753 -287.552847)
			(xy 114.906928 -287.550866) (xy 114.955783 -287.556798) (xy 115.003054 -287.57049) (xy 115.047516 -287.591588)
			(xy 115.088019 -287.619544) (xy 115.123512 -287.653636) (xy 115.153077 -287.69298) (xy 115.175948 -287.736557)
			(xy 115.191532 -287.783238) (xy 115.199427 -287.831815) (xy 115.199922 -287.856422) (xy 115.528864 -287.856422)
			(xy 115.532824 -287.807368) (xy 115.544601 -287.759584) (xy 115.563892 -287.714308) (xy 115.590195 -287.672712)
			(xy 115.62283 -287.635875) (xy 115.660951 -287.60475) (xy 115.703572 -287.580143) (xy 115.749588 -287.562691)
			(xy 115.797807 -287.552847) (xy 115.846982 -287.550866) (xy 115.895837 -287.556798) (xy 115.943108 -287.57049)
			(xy 115.98757 -287.591588) (xy 116.028073 -287.619544) (xy 116.063566 -287.653636) (xy 116.093131 -287.69298)
			(xy 116.116002 -287.736557) (xy 116.131586 -287.783238) (xy 116.139481 -287.831815) (xy 116.139976 -287.8564)
			(xy 116.468607 -287.8564) (xy 116.472783 -287.806017) (xy 116.485194 -287.757008) (xy 116.505503 -287.71071)
			(xy 116.533156 -287.668387) (xy 116.567398 -287.631193) (xy 116.607295 -287.600142) (xy 116.651759 -287.576082)
			(xy 116.699577 -287.559669) (xy 116.749444 -287.551351) (xy 116.774722 -287.55086) (xy 117.714776 -287.55086)
			(xy 117.740058 -287.551307) (xy 117.789932 -287.559626) (xy 117.837757 -287.576041) (xy 117.882228 -287.600104)
			(xy 117.922131 -287.631159) (xy 117.956378 -287.668359) (xy 117.984035 -287.710688) (xy 118.004348 -287.756993)
			(xy 118.016761 -287.806009) (xy 118.020937 -287.8564) (xy 118.020935 -287.856422) (xy 118.349026 -287.856422)
			(xy 118.352986 -287.807368) (xy 118.364763 -287.759584) (xy 118.384054 -287.714308) (xy 118.410357 -287.672712)
			(xy 118.442992 -287.635875) (xy 118.481113 -287.60475) (xy 118.523734 -287.580143) (xy 118.56975 -287.562691)
			(xy 118.617969 -287.552847) (xy 118.667144 -287.550866) (xy 118.715999 -287.556798) (xy 118.76327 -287.57049)
			(xy 118.807732 -287.591588) (xy 118.848235 -287.619544) (xy 118.883728 -287.653636) (xy 118.913293 -287.69298)
			(xy 118.936164 -287.736557) (xy 118.951748 -287.783238) (xy 118.959643 -287.831815) (xy 118.960138 -287.8564)
			(xy 119.288507 -287.8564) (xy 119.292683 -287.806016) (xy 119.305094 -287.757006) (xy 119.325404 -287.710708)
			(xy 119.353058 -287.668384) (xy 119.387301 -287.63119) (xy 119.427199 -287.600139) (xy 119.471664 -287.57608)
			(xy 119.519483 -287.559668) (xy 119.569351 -287.551351) (xy 119.59463 -287.55086) (xy 120.534684 -287.55086)
			(xy 120.559965 -287.551308) (xy 120.609839 -287.559628) (xy 120.657663 -287.576044) (xy 120.702132 -287.600107)
			(xy 120.742034 -287.631162) (xy 120.776281 -287.668362) (xy 120.803937 -287.710691) (xy 120.824248 -287.756994)
			(xy 120.836661 -287.80601) (xy 120.840837 -287.8564) (xy 120.840835 -287.856422) (xy 121.168934 -287.856422)
			(xy 121.172894 -287.807368) (xy 121.184671 -287.759584) (xy 121.203962 -287.714308) (xy 121.230265 -287.672712)
			(xy 121.2629 -287.635875) (xy 121.301021 -287.60475) (xy 121.343642 -287.580143) (xy 121.389658 -287.562691)
			(xy 121.437877 -287.552847) (xy 121.487052 -287.550866) (xy 121.535907 -287.556798) (xy 121.583178 -287.57049)
			(xy 121.62764 -287.591588) (xy 121.668143 -287.619544) (xy 121.703636 -287.653636) (xy 121.733201 -287.69298)
			(xy 121.756072 -287.736557) (xy 121.771656 -287.783238) (xy 121.779551 -287.831815) (xy 121.780046 -287.8564)
			(xy 122.108736 -287.8564) (xy 122.112911 -287.806024) (xy 122.125319 -287.757023) (xy 122.145624 -287.710732)
			(xy 122.173271 -287.668415) (xy 122.207506 -287.631225) (xy 122.247395 -287.600177) (xy 122.29185 -287.576118)
			(xy 122.339659 -287.559704) (xy 122.389518 -287.551382) (xy 122.414792 -287.55086) (xy 123.354846 -287.55086)
			(xy 123.380122 -287.551342) (xy 123.429983 -287.559669) (xy 123.477793 -287.576089) (xy 123.522249 -287.600153)
			(xy 123.562139 -287.631206) (xy 123.596374 -287.6684) (xy 123.62402 -287.710722) (xy 123.644325 -287.757016)
			(xy 123.656733 -287.806021) (xy 123.660908 -287.8564) (xy 123.660906 -287.856422) (xy 123.988842 -287.856422)
			(xy 123.992802 -287.807368) (xy 124.004579 -287.759584) (xy 124.02387 -287.714308) (xy 124.050173 -287.672712)
			(xy 124.082808 -287.635875) (xy 124.120929 -287.60475) (xy 124.16355 -287.580143) (xy 124.209566 -287.562691)
			(xy 124.257785 -287.552847) (xy 124.30696 -287.550866) (xy 124.355815 -287.556798) (xy 124.403086 -287.57049)
			(xy 124.447548 -287.591588) (xy 124.488051 -287.619544) (xy 124.523544 -287.653636) (xy 124.553109 -287.69298)
			(xy 124.57598 -287.736557) (xy 124.591564 -287.783238) (xy 124.599459 -287.831815) (xy 124.599954 -287.8564)
			(xy 124.928637 -287.8564) (xy 124.932811 -287.806024) (xy 124.94522 -287.757021) (xy 124.965525 -287.71073)
			(xy 124.993173 -287.668412) (xy 125.027409 -287.631222) (xy 125.067299 -287.600174) (xy 125.111756 -287.576115)
			(xy 125.159566 -287.559702) (xy 125.209425 -287.551382) (xy 125.2347 -287.55086) (xy 126.174754 -287.55086)
			(xy 126.200037 -287.551306) (xy 126.249914 -287.559622) (xy 126.297743 -287.576035) (xy 126.342216 -287.600097)
			(xy 126.382123 -287.631152) (xy 126.416373 -287.668352) (xy 126.444032 -287.710682) (xy 126.464346 -287.756988)
			(xy 126.47676 -287.806007) (xy 126.480937 -287.8564) (xy 126.47676 -287.906793) (xy 126.464346 -287.955812)
			(xy 126.444032 -288.002118) (xy 126.416373 -288.044448) (xy 126.382123 -288.081648) (xy 126.342216 -288.112703)
			(xy 126.297743 -288.136765) (xy 126.249914 -288.153178) (xy 126.200037 -288.161494) (xy 126.174754 -288.161984)
			(xy 125.2347 -288.161984) (xy 125.209425 -288.161418) (xy 125.159566 -288.153098) (xy 125.111756 -288.136685)
			(xy 125.067299 -288.112626) (xy 125.027409 -288.081578) (xy 124.993173 -288.044388) (xy 124.965525 -288.00207)
			(xy 124.94522 -287.955779) (xy 124.932811 -287.906776) (xy 124.928637 -287.8564) (xy 124.599954 -287.8564)
			(xy 124.599954 -287.856422) (xy 124.599459 -287.881029) (xy 124.591564 -287.929606) (xy 124.57598 -287.976287)
			(xy 124.553109 -288.019864) (xy 124.523544 -288.059208) (xy 124.488051 -288.0933) (xy 124.447548 -288.121256)
			(xy 124.403086 -288.142354) (xy 124.355815 -288.156046) (xy 124.30696 -288.161978) (xy 124.257785 -288.159997)
			(xy 124.209566 -288.150153) (xy 124.16355 -288.132701) (xy 124.120929 -288.108094) (xy 124.082808 -288.076969)
			(xy 124.050173 -288.040132) (xy 124.02387 -287.998536) (xy 124.004579 -287.95326) (xy 123.992802 -287.905476)
			(xy 123.988842 -287.856422) (xy 123.660906 -287.856422) (xy 123.656733 -287.906779) (xy 123.644325 -287.955784)
			(xy 123.62402 -288.002078) (xy 123.596374 -288.0444) (xy 123.562139 -288.081594) (xy 123.522249 -288.112647)
			(xy 123.477793 -288.136711) (xy 123.429983 -288.153131) (xy 123.380122 -288.161458) (xy 123.354846 -288.161984)
			(xy 122.414792 -288.161984) (xy 122.389518 -288.161418) (xy 122.339659 -288.153096) (xy 122.29185 -288.136682)
			(xy 122.247395 -288.112623) (xy 122.207506 -288.081575) (xy 122.173271 -288.044385) (xy 122.145624 -288.002068)
			(xy 122.125319 -287.955777) (xy 122.112911 -287.906776) (xy 122.108736 -287.8564) (xy 121.780046 -287.8564)
			(xy 121.780046 -287.856422) (xy 121.779551 -287.881029) (xy 121.771656 -287.929606) (xy 121.756072 -287.976287)
			(xy 121.733201 -288.019864) (xy 121.703636 -288.059208) (xy 121.668143 -288.0933) (xy 121.62764 -288.121256)
			(xy 121.583178 -288.142354) (xy 121.535907 -288.156046) (xy 121.487052 -288.161978) (xy 121.437877 -288.159997)
			(xy 121.389658 -288.150153) (xy 121.343642 -288.132701) (xy 121.301021 -288.108094) (xy 121.2629 -288.076969)
			(xy 121.230265 -288.040132) (xy 121.203962 -287.998536) (xy 121.184671 -287.95326) (xy 121.172894 -287.905476)
			(xy 121.168934 -287.856422) (xy 120.840835 -287.856422) (xy 120.836661 -287.90679) (xy 120.824248 -287.955806)
			(xy 120.803937 -288.002109) (xy 120.776281 -288.044438) (xy 120.742034 -288.081638) (xy 120.702132 -288.112693)
			(xy 120.657663 -288.136756) (xy 120.609839 -288.153172) (xy 120.559965 -288.161492) (xy 120.534684 -288.161984)
			(xy 119.59463 -288.161984) (xy 119.569351 -288.161449) (xy 119.519483 -288.153132) (xy 119.471664 -288.13672)
			(xy 119.427199 -288.112661) (xy 119.387301 -288.08161) (xy 119.353058 -288.044416) (xy 119.325404 -288.002092)
			(xy 119.305094 -287.955794) (xy 119.292683 -287.906784) (xy 119.288507 -287.8564) (xy 118.960138 -287.8564)
			(xy 118.960138 -287.856422) (xy 118.959643 -287.881029) (xy 118.951748 -287.929606) (xy 118.936164 -287.976287)
			(xy 118.913293 -288.019864) (xy 118.883728 -288.059208) (xy 118.848235 -288.0933) (xy 118.807732 -288.121256)
			(xy 118.76327 -288.142354) (xy 118.715999 -288.156046) (xy 118.667144 -288.161978) (xy 118.617969 -288.159997)
			(xy 118.56975 -288.150153) (xy 118.523734 -288.132701) (xy 118.481113 -288.108094) (xy 118.442992 -288.076969)
			(xy 118.410357 -288.040132) (xy 118.384054 -287.998536) (xy 118.364763 -287.95326) (xy 118.352986 -287.905476)
			(xy 118.349026 -287.856422) (xy 118.020935 -287.856422) (xy 118.016761 -287.906791) (xy 118.004348 -287.955807)
			(xy 117.984035 -288.002112) (xy 117.956378 -288.044441) (xy 117.922131 -288.081641) (xy 117.882228 -288.112696)
			(xy 117.837757 -288.136759) (xy 117.789932 -288.153174) (xy 117.740058 -288.161493) (xy 117.714776 -288.161984)
			(xy 116.774722 -288.161984) (xy 116.749444 -288.161449) (xy 116.699577 -288.153131) (xy 116.651759 -288.136718)
			(xy 116.607295 -288.112658) (xy 116.567398 -288.081607) (xy 116.533156 -288.044413) (xy 116.505503 -288.00209)
			(xy 116.485194 -287.955792) (xy 116.472783 -287.906783) (xy 116.468607 -287.8564) (xy 116.139976 -287.8564)
			(xy 116.139976 -287.856422) (xy 116.139481 -287.881029) (xy 116.131586 -287.929606) (xy 116.116002 -287.976287)
			(xy 116.093131 -288.019864) (xy 116.063566 -288.059208) (xy 116.028073 -288.0933) (xy 115.98757 -288.121256)
			(xy 115.943108 -288.142354) (xy 115.895837 -288.156046) (xy 115.846982 -288.161978) (xy 115.797807 -288.159997)
			(xy 115.749588 -288.150153) (xy 115.703572 -288.132701) (xy 115.660951 -288.108094) (xy 115.62283 -288.076969)
			(xy 115.590195 -288.040132) (xy 115.563892 -287.998536) (xy 115.544601 -287.95326) (xy 115.532824 -287.905476)
			(xy 115.528864 -287.856422) (xy 115.199922 -287.856422) (xy 115.199427 -287.881029) (xy 115.191532 -287.929606)
			(xy 115.175948 -287.976287) (xy 115.153077 -288.019864) (xy 115.123512 -288.059208) (xy 115.088019 -288.0933)
			(xy 115.047516 -288.121256) (xy 115.003054 -288.142354) (xy 114.955783 -288.156046) (xy 114.906928 -288.161978)
			(xy 114.857753 -288.159997) (xy 114.809534 -288.150153) (xy 114.763518 -288.132701) (xy 114.720897 -288.108094)
			(xy 114.682776 -288.076969) (xy 114.650141 -288.040132) (xy 114.623838 -287.998536) (xy 114.604547 -287.95326)
			(xy 114.59277 -287.905476) (xy 114.58881 -287.856422) (xy 114.260122 -287.856422) (xy 114.259627 -287.881029)
			(xy 114.251732 -287.929606) (xy 114.236148 -287.976287) (xy 114.213277 -288.019864) (xy 114.183712 -288.059208)
			(xy 114.148219 -288.0933) (xy 114.107716 -288.121256) (xy 114.063254 -288.142354) (xy 114.015983 -288.156046)
			(xy 113.967128 -288.161978) (xy 113.917953 -288.159997) (xy 113.869734 -288.150153) (xy 113.823718 -288.132701)
			(xy 113.781097 -288.108094) (xy 113.742976 -288.076969) (xy 113.710341 -288.040132) (xy 113.684038 -287.998536)
			(xy 113.664747 -287.95326) (xy 113.65297 -287.905476) (xy 113.64901 -287.856422) (xy 110.506256 -287.856422)
			(xy 110.505761 -287.881029) (xy 110.497866 -287.929606) (xy 110.482282 -287.976287) (xy 110.459411 -288.019864)
			(xy 110.429846 -288.059208) (xy 110.394353 -288.0933) (xy 110.35385 -288.121256) (xy 110.309388 -288.142354)
			(xy 110.262117 -288.156046) (xy 110.213262 -288.161978) (xy 110.164087 -288.159997) (xy 110.115868 -288.150153)
			(xy 110.069852 -288.132701) (xy 110.027231 -288.108094) (xy 109.98911 -288.076969) (xy 109.956475 -288.040132)
			(xy 109.930172 -287.998536) (xy 109.910881 -287.95326) (xy 109.899104 -287.905476) (xy 109.895144 -287.856422)
			(xy 109.566456 -287.856422) (xy 109.565961 -287.881029) (xy 109.558066 -287.929606) (xy 109.542482 -287.976287)
			(xy 109.519611 -288.019864) (xy 109.490046 -288.059208) (xy 109.454553 -288.0933) (xy 109.41405 -288.121256)
			(xy 109.369588 -288.142354) (xy 109.322317 -288.156046) (xy 109.273462 -288.161978) (xy 109.224287 -288.159997)
			(xy 109.176068 -288.150153) (xy 109.130052 -288.132701) (xy 109.087431 -288.108094) (xy 109.04931 -288.076969)
			(xy 109.016675 -288.040132) (xy 108.990372 -287.998536) (xy 108.971081 -287.95326) (xy 108.959304 -287.905476)
			(xy 108.955344 -287.856422) (xy 108.626402 -287.856422) (xy 108.625907 -287.881029) (xy 108.618012 -287.929606)
			(xy 108.602428 -287.976287) (xy 108.579557 -288.019864) (xy 108.549992 -288.059208) (xy 108.514499 -288.0933)
			(xy 108.473996 -288.121256) (xy 108.429534 -288.142354) (xy 108.382263 -288.156046) (xy 108.333408 -288.161978)
			(xy 108.284233 -288.159997) (xy 108.236014 -288.150153) (xy 108.189998 -288.132701) (xy 108.147377 -288.108094)
			(xy 108.109256 -288.076969) (xy 108.076621 -288.040132) (xy 108.050318 -287.998536) (xy 108.031027 -287.95326)
			(xy 108.01925 -287.905476) (xy 108.01529 -287.856422) (xy 107.687106 -287.856422) (xy 107.682933 -287.906779)
			(xy 107.670524 -287.955785) (xy 107.65022 -288.00208) (xy 107.622572 -288.044402) (xy 107.588336 -288.081596)
			(xy 107.548446 -288.112649) (xy 107.503989 -288.136713) (xy 107.456178 -288.153132) (xy 107.406316 -288.161459)
			(xy 107.38104 -288.161984) (xy 106.440986 -288.161984) (xy 106.415712 -288.161417) (xy 106.365854 -288.153095)
			(xy 106.318046 -288.136681) (xy 106.273592 -288.112621) (xy 106.233703 -288.081573) (xy 106.199469 -288.044383)
			(xy 106.171823 -288.002066) (xy 106.151519 -287.955776) (xy 106.139111 -287.906775) (xy 106.134936 -287.8564)
			(xy 105.80624 -287.8564) (xy 105.80624 -287.856422) (xy 105.805745 -287.881029) (xy 105.79785 -287.929606)
			(xy 105.782266 -287.976287) (xy 105.759395 -288.019864) (xy 105.72983 -288.059208) (xy 105.694337 -288.0933)
			(xy 105.653834 -288.121256) (xy 105.609372 -288.142354) (xy 105.562101 -288.156046) (xy 105.513246 -288.161978)
			(xy 105.464071 -288.159997) (xy 105.415852 -288.150153) (xy 105.369836 -288.132701) (xy 105.327215 -288.108094)
			(xy 105.289094 -288.076969) (xy 105.256459 -288.040132) (xy 105.230156 -287.998536) (xy 105.210865 -287.95326)
			(xy 105.199088 -287.905476) (xy 105.195128 -287.856422) (xy 104.867206 -287.856422) (xy 104.863033 -287.90678)
			(xy 104.850624 -287.955787) (xy 104.830318 -288.002082) (xy 104.80267 -288.044404) (xy 104.768433 -288.081599)
			(xy 104.728542 -288.112652) (xy 104.684084 -288.136716) (xy 104.636271 -288.153134) (xy 104.586408 -288.161459)
			(xy 104.561132 -288.161984) (xy 103.621078 -288.161984) (xy 103.595805 -288.161416) (xy 103.545948 -288.153093)
			(xy 103.498141 -288.136678) (xy 103.453687 -288.112618) (xy 103.4138 -288.08157) (xy 103.379567 -288.044381)
			(xy 103.351922 -288.002064) (xy 103.331618 -287.955774) (xy 103.31921 -287.906774) (xy 103.315036 -287.8564)
			(xy 102.986332 -287.8564) (xy 102.986332 -287.856422) (xy 102.985837 -287.881029) (xy 102.977942 -287.929606)
			(xy 102.962358 -287.976287) (xy 102.939487 -288.019864) (xy 102.909922 -288.059208) (xy 102.874429 -288.0933)
			(xy 102.833926 -288.121256) (xy 102.789464 -288.142354) (xy 102.742193 -288.156046) (xy 102.693338 -288.161978)
			(xy 102.644163 -288.159997) (xy 102.595944 -288.150153) (xy 102.549928 -288.132701) (xy 102.507307 -288.108094)
			(xy 102.469186 -288.076969) (xy 102.436551 -288.040132) (xy 102.410248 -287.998536) (xy 102.390957 -287.95326)
			(xy 102.37918 -287.905476) (xy 102.37522 -287.856422) (xy 102.047306 -287.856422) (xy 102.043133 -287.906781)
			(xy 102.030723 -287.955788) (xy 102.010417 -288.002084) (xy 101.982768 -288.044407) (xy 101.94853 -288.081602)
			(xy 101.908638 -288.112655) (xy 101.864178 -288.136718) (xy 101.816365 -288.153136) (xy 101.766501 -288.16146)
			(xy 101.741224 -288.161984) (xy 100.80117 -288.161984) (xy 100.775897 -288.161416) (xy 100.726041 -288.153092)
			(xy 100.678235 -288.136676) (xy 100.633783 -288.112616) (xy 100.593897 -288.081568) (xy 100.559665 -288.044378)
			(xy 100.532021 -288.002062) (xy 100.511718 -287.955773) (xy 100.49931 -287.906773) (xy 100.495136 -287.8564)
			(xy 100.166424 -287.8564) (xy 100.166424 -287.856422) (xy 100.165929 -287.881029) (xy 100.158034 -287.929606)
			(xy 100.14245 -287.976287) (xy 100.119579 -288.019864) (xy 100.090014 -288.059208) (xy 100.054521 -288.0933)
			(xy 100.014018 -288.121256) (xy 99.969556 -288.142354) (xy 99.922285 -288.156046) (xy 99.87343 -288.161978)
			(xy 99.824255 -288.159997) (xy 99.776036 -288.150153) (xy 99.73002 -288.132701) (xy 99.687399 -288.108094)
			(xy 99.649278 -288.076969) (xy 99.616643 -288.040132) (xy 99.59034 -287.998536) (xy 99.571049 -287.95326)
			(xy 99.559272 -287.905476) (xy 99.555312 -287.856422) (xy 99.227235 -287.856422) (xy 99.223061 -287.906792)
			(xy 99.210647 -287.95581) (xy 99.190333 -288.002115) (xy 99.162675 -288.044446) (xy 99.128426 -288.081646)
			(xy 99.088521 -288.1127) (xy 99.044048 -288.136763) (xy 98.996221 -288.153177) (xy 98.946345 -288.161494)
			(xy 98.921062 -288.161984) (xy 97.981008 -288.161984) (xy 97.955731 -288.161448) (xy 97.905865 -288.153128)
			(xy 97.858049 -288.136714) (xy 97.813588 -288.112653) (xy 97.773692 -288.081602) (xy 97.739452 -288.044409)
			(xy 97.711801 -288.002086) (xy 97.691493 -287.95579) (xy 97.679082 -287.906782) (xy 97.674907 -287.8564)
			(xy 97.346838 -287.8564) (xy 97.342666 -287.906744) (xy 97.330264 -287.955715) (xy 97.30997 -288.001976)
			(xy 97.282337 -288.044265) (xy 97.248121 -288.081429) (xy 97.208253 -288.112453) (xy 97.163823 -288.136492)
			(xy 97.116041 -288.152889) (xy 97.066212 -288.161197) (xy 97.040954 -288.16173) (xy 97.01717 -288.161281)
			(xy 96.970175 -288.15392) (xy 96.924888 -288.139366) (xy 96.882402 -288.117972) (xy 96.843744 -288.090254)
			(xy 96.809847 -288.056882) (xy 96.795336 -288.038032) (xy 96.793304 -288.034984) (xy 96.78162 -288.0233)
			(xy 96.773632 -288.018021) (xy 96.755089 -288.013317) (xy 96.745552 -288.014156) (xy 96.712024 -288.018474)
			(xy 96.65716 -288.025332) (xy 96.65033 -288.026475) (xy 96.637591 -288.031893) (xy 96.632014 -288.036)
			(xy 96.62668 -288.040064) (xy 96.618806 -288.050732) (xy 96.616266 -288.057336) (xy 96.6108 -288.071075)
			(xy 96.598602 -288.098013) (xy 96.591882 -288.111184) (xy 96.579182 -288.134044) (xy 96.543876 -288.19475)
			(xy 96.541501 -288.199645) (xy 96.538679 -288.210151) (xy 96.538288 -288.215578) (xy 96.538288 -288.290254)
			(xy 96.538542 -288.295842) (xy 96.539771 -288.304049) (xy 96.546765 -288.319087) (xy 96.552258 -288.325306)
			(xy 96.572832 -288.34715) (xy 96.582484 -288.355278) (xy 96.58656 -288.35769) (xy 96.595378 -288.361148)
			(xy 96.60001 -288.362136) (xy 96.604074 -288.362644) (xy 96.628702 -288.365808) (xy 96.676545 -288.379086)
			(xy 96.721609 -288.399929) (xy 96.762708 -288.427789) (xy 96.798757 -288.461932) (xy 96.828807 -288.501457)
			(xy 96.852066 -288.545323) (xy 96.867921 -288.592375) (xy 96.875955 -288.641372) (xy 96.875955 -288.666174)
			(xy 97.205304 -288.666174) (xy 97.209264 -288.61712) (xy 97.221041 -288.569336) (xy 97.240332 -288.52406)
			(xy 97.266635 -288.482464) (xy 97.29927 -288.445627) (xy 97.337391 -288.414502) (xy 97.380012 -288.389895)
			(xy 97.426028 -288.372443) (xy 97.474247 -288.362599) (xy 97.523422 -288.360618) (xy 97.572277 -288.36655)
			(xy 97.619548 -288.380242) (xy 97.66401 -288.40134) (xy 97.704513 -288.429296) (xy 97.740006 -288.463388)
			(xy 97.769571 -288.502732) (xy 97.792442 -288.546309) (xy 97.808026 -288.59299) (xy 97.815921 -288.641567)
			(xy 97.816416 -288.666174) (xy 98.145358 -288.666174) (xy 98.149318 -288.61712) (xy 98.161095 -288.569336)
			(xy 98.180386 -288.52406) (xy 98.206689 -288.482464) (xy 98.239324 -288.445627) (xy 98.277445 -288.414502)
			(xy 98.320066 -288.389895) (xy 98.366082 -288.372443) (xy 98.414301 -288.362599) (xy 98.463476 -288.360618)
			(xy 98.512331 -288.36655) (xy 98.559602 -288.380242) (xy 98.604064 -288.40134) (xy 98.644567 -288.429296)
			(xy 98.68006 -288.463388) (xy 98.709625 -288.502732) (xy 98.732496 -288.546309) (xy 98.74808 -288.59299)
			(xy 98.755975 -288.641567) (xy 98.75647 -288.666174) (xy 99.085158 -288.666174) (xy 99.089118 -288.61712)
			(xy 99.100895 -288.569336) (xy 99.120186 -288.52406) (xy 99.146489 -288.482464) (xy 99.179124 -288.445627)
			(xy 99.217245 -288.414502) (xy 99.259866 -288.389895) (xy 99.305882 -288.372443) (xy 99.354101 -288.362599)
			(xy 99.403276 -288.360618) (xy 99.452131 -288.36655) (xy 99.499402 -288.380242) (xy 99.543864 -288.40134)
			(xy 99.584367 -288.429296) (xy 99.61986 -288.463388) (xy 99.649425 -288.502732) (xy 99.672296 -288.546309)
			(xy 99.68788 -288.59299) (xy 99.695775 -288.641567) (xy 99.69627 -288.666174) (xy 100.025212 -288.666174)
			(xy 100.029172 -288.61712) (xy 100.040949 -288.569336) (xy 100.06024 -288.52406) (xy 100.086543 -288.482464)
			(xy 100.119178 -288.445627) (xy 100.157299 -288.414502) (xy 100.19992 -288.389895) (xy 100.245936 -288.372443)
			(xy 100.294155 -288.362599) (xy 100.34333 -288.360618) (xy 100.392185 -288.36655) (xy 100.439456 -288.380242)
			(xy 100.483918 -288.40134) (xy 100.524421 -288.429296) (xy 100.559914 -288.463388) (xy 100.589479 -288.502732)
			(xy 100.61235 -288.546309) (xy 100.627934 -288.59299) (xy 100.635829 -288.641567) (xy 100.636324 -288.666174)
			(xy 100.965266 -288.666174) (xy 100.969226 -288.61712) (xy 100.981003 -288.569336) (xy 101.000294 -288.52406)
			(xy 101.026597 -288.482464) (xy 101.059232 -288.445627) (xy 101.097353 -288.414502) (xy 101.139974 -288.389895)
			(xy 101.18599 -288.372443) (xy 101.234209 -288.362599) (xy 101.283384 -288.360618) (xy 101.332239 -288.36655)
			(xy 101.37951 -288.380242) (xy 101.423972 -288.40134) (xy 101.464475 -288.429296) (xy 101.499968 -288.463388)
			(xy 101.529533 -288.502732) (xy 101.552404 -288.546309) (xy 101.567988 -288.59299) (xy 101.575883 -288.641567)
			(xy 101.576378 -288.666174) (xy 101.90532 -288.666174) (xy 101.90928 -288.61712) (xy 101.921057 -288.569336)
			(xy 101.940348 -288.52406) (xy 101.966651 -288.482464) (xy 101.999286 -288.445627) (xy 102.037407 -288.414502)
			(xy 102.080028 -288.389895) (xy 102.126044 -288.372443) (xy 102.174263 -288.362599) (xy 102.223438 -288.360618)
			(xy 102.272293 -288.36655) (xy 102.319564 -288.380242) (xy 102.364026 -288.40134) (xy 102.404529 -288.429296)
			(xy 102.440022 -288.463388) (xy 102.469587 -288.502732) (xy 102.492458 -288.546309) (xy 102.508042 -288.59299)
			(xy 102.515937 -288.641567) (xy 102.516432 -288.666174) (xy 102.845374 -288.666174) (xy 102.849334 -288.61712)
			(xy 102.861111 -288.569336) (xy 102.880402 -288.52406) (xy 102.906705 -288.482464) (xy 102.93934 -288.445627)
			(xy 102.977461 -288.414502) (xy 103.020082 -288.389895) (xy 103.066098 -288.372443) (xy 103.114317 -288.362599)
			(xy 103.163492 -288.360618) (xy 103.212347 -288.36655) (xy 103.259618 -288.380242) (xy 103.30408 -288.40134)
			(xy 103.344583 -288.429296) (xy 103.380076 -288.463388) (xy 103.409641 -288.502732) (xy 103.432512 -288.546309)
			(xy 103.448096 -288.59299) (xy 103.455991 -288.641567) (xy 103.456486 -288.666174) (xy 103.785174 -288.666174)
			(xy 103.789134 -288.61712) (xy 103.800911 -288.569336) (xy 103.820202 -288.52406) (xy 103.846505 -288.482464)
			(xy 103.87914 -288.445627) (xy 103.917261 -288.414502) (xy 103.959882 -288.389895) (xy 104.005898 -288.372443)
			(xy 104.054117 -288.362599) (xy 104.103292 -288.360618) (xy 104.152147 -288.36655) (xy 104.199418 -288.380242)
			(xy 104.24388 -288.40134) (xy 104.284383 -288.429296) (xy 104.319876 -288.463388) (xy 104.349441 -288.502732)
			(xy 104.372312 -288.546309) (xy 104.387896 -288.59299) (xy 104.395791 -288.641567) (xy 104.396286 -288.666174)
			(xy 104.725228 -288.666174) (xy 104.729188 -288.61712) (xy 104.740965 -288.569336) (xy 104.760256 -288.52406)
			(xy 104.786559 -288.482464) (xy 104.819194 -288.445627) (xy 104.857315 -288.414502) (xy 104.899936 -288.389895)
			(xy 104.945952 -288.372443) (xy 104.994171 -288.362599) (xy 105.043346 -288.360618) (xy 105.092201 -288.36655)
			(xy 105.139472 -288.380242) (xy 105.183934 -288.40134) (xy 105.224437 -288.429296) (xy 105.25993 -288.463388)
			(xy 105.289495 -288.502732) (xy 105.312366 -288.546309) (xy 105.32795 -288.59299) (xy 105.335845 -288.641567)
			(xy 105.33634 -288.666174) (xy 105.665282 -288.666174) (xy 105.669242 -288.61712) (xy 105.681019 -288.569336)
			(xy 105.70031 -288.52406) (xy 105.726613 -288.482464) (xy 105.759248 -288.445627) (xy 105.797369 -288.414502)
			(xy 105.83999 -288.389895) (xy 105.886006 -288.372443) (xy 105.934225 -288.362599) (xy 105.9834 -288.360618)
			(xy 106.032255 -288.36655) (xy 106.079526 -288.380242) (xy 106.123988 -288.40134) (xy 106.164491 -288.429296)
			(xy 106.199984 -288.463388) (xy 106.229549 -288.502732) (xy 106.25242 -288.546309) (xy 106.268004 -288.59299)
			(xy 106.275899 -288.641567) (xy 106.276394 -288.666174) (xy 106.605336 -288.666174) (xy 106.609296 -288.61712)
			(xy 106.621073 -288.569336) (xy 106.640364 -288.52406) (xy 106.666667 -288.482464) (xy 106.699302 -288.445627)
			(xy 106.737423 -288.414502) (xy 106.780044 -288.389895) (xy 106.82606 -288.372443) (xy 106.874279 -288.362599)
			(xy 106.923454 -288.360618) (xy 106.972309 -288.36655) (xy 107.01958 -288.380242) (xy 107.064042 -288.40134)
			(xy 107.104545 -288.429296) (xy 107.140038 -288.463388) (xy 107.169603 -288.502732) (xy 107.192474 -288.546309)
			(xy 107.208058 -288.59299) (xy 107.215953 -288.641567) (xy 107.216448 -288.666174) (xy 107.545136 -288.666174)
			(xy 107.549096 -288.61712) (xy 107.560873 -288.569336) (xy 107.580164 -288.52406) (xy 107.606467 -288.482464)
			(xy 107.639102 -288.445627) (xy 107.677223 -288.414502) (xy 107.719844 -288.389895) (xy 107.76586 -288.372443)
			(xy 107.814079 -288.362599) (xy 107.863254 -288.360618) (xy 107.912109 -288.36655) (xy 107.95938 -288.380242)
			(xy 108.003842 -288.40134) (xy 108.044345 -288.429296) (xy 108.079838 -288.463388) (xy 108.109403 -288.502732)
			(xy 108.132274 -288.546309) (xy 108.147858 -288.59299) (xy 108.155753 -288.641567) (xy 108.156248 -288.666174)
			(xy 108.156247 -288.6662) (xy 108.484888 -288.6662) (xy 108.489063 -288.615816) (xy 108.501474 -288.566807)
			(xy 108.521782 -288.520509) (xy 108.549433 -288.478184) (xy 108.583674 -288.440989) (xy 108.62357 -288.409936)
			(xy 108.668032 -288.385873) (xy 108.715849 -288.369457) (xy 108.765716 -288.361134) (xy 108.790994 -288.360612)
			(xy 109.731048 -288.360612) (xy 109.75632 -288.36119) (xy 109.806172 -288.369516) (xy 109.853975 -288.385933)
			(xy 109.898424 -288.409994) (xy 109.938307 -288.441042) (xy 109.972536 -288.47823) (xy 110.000179 -288.520545)
			(xy 110.02048 -288.566832) (xy 110.032886 -288.615829) (xy 110.037058 -288.666174) (xy 110.365298 -288.666174)
			(xy 110.369258 -288.61712) (xy 110.381035 -288.569336) (xy 110.400326 -288.52406) (xy 110.426629 -288.482464)
			(xy 110.459264 -288.445627) (xy 110.497385 -288.414502) (xy 110.540006 -288.389895) (xy 110.586022 -288.372443)
			(xy 110.634241 -288.362599) (xy 110.683416 -288.360618) (xy 110.732271 -288.36655) (xy 110.779542 -288.380242)
			(xy 110.824004 -288.40134) (xy 110.864507 -288.429296) (xy 110.9 -288.463388) (xy 110.929565 -288.502732)
			(xy 110.952436 -288.546309) (xy 110.96802 -288.59299) (xy 110.975915 -288.641567) (xy 110.97641 -288.666174)
			(xy 113.178856 -288.666174) (xy 113.182816 -288.61712) (xy 113.194593 -288.569336) (xy 113.213884 -288.52406)
			(xy 113.240187 -288.482464) (xy 113.272822 -288.445627) (xy 113.310943 -288.414502) (xy 113.353564 -288.389895)
			(xy 113.39958 -288.372443) (xy 113.447799 -288.362599) (xy 113.496974 -288.360618) (xy 113.545829 -288.36655)
			(xy 113.5931 -288.380242) (xy 113.637562 -288.40134) (xy 113.678065 -288.429296) (xy 113.713558 -288.463388)
			(xy 113.743123 -288.502732) (xy 113.765994 -288.546309) (xy 113.781578 -288.59299) (xy 113.789473 -288.641567)
			(xy 113.789968 -288.666174) (xy 113.789967 -288.6662) (xy 114.118559 -288.6662) (xy 114.122735 -288.615809)
			(xy 114.135148 -288.566794) (xy 114.15546 -288.520489) (xy 114.183116 -288.47816) (xy 114.217362 -288.44096)
			(xy 114.257264 -288.409905) (xy 114.301734 -288.385841) (xy 114.349558 -288.369424) (xy 114.399432 -288.361104)
			(xy 114.424714 -288.360612) (xy 115.364768 -288.360612) (xy 115.390046 -288.361154) (xy 115.439914 -288.369471)
			(xy 115.487733 -288.385883) (xy 115.532198 -288.409942) (xy 115.572096 -288.440992) (xy 115.606339 -288.478186)
			(xy 115.633992 -288.520509) (xy 115.654302 -288.566807) (xy 115.666713 -288.615816) (xy 115.670887 -288.666174)
			(xy 115.999018 -288.666174) (xy 116.002978 -288.61712) (xy 116.014755 -288.569336) (xy 116.034046 -288.52406)
			(xy 116.060349 -288.482464) (xy 116.092984 -288.445627) (xy 116.131105 -288.414502) (xy 116.173726 -288.389895)
			(xy 116.219742 -288.372443) (xy 116.267961 -288.362599) (xy 116.317136 -288.360618) (xy 116.365991 -288.36655)
			(xy 116.413262 -288.380242) (xy 116.457724 -288.40134) (xy 116.498227 -288.429296) (xy 116.53372 -288.463388)
			(xy 116.563285 -288.502732) (xy 116.586156 -288.546309) (xy 116.60174 -288.59299) (xy 116.609635 -288.641567)
			(xy 116.61013 -288.666174) (xy 116.938818 -288.666174) (xy 116.942778 -288.61712) (xy 116.954555 -288.569336)
			(xy 116.973846 -288.52406) (xy 117.000149 -288.482464) (xy 117.032784 -288.445627) (xy 117.070905 -288.414502)
			(xy 117.113526 -288.389895) (xy 117.159542 -288.372443) (xy 117.207761 -288.362599) (xy 117.256936 -288.360618)
			(xy 117.305791 -288.36655) (xy 117.353062 -288.380242) (xy 117.397524 -288.40134) (xy 117.438027 -288.429296)
			(xy 117.47352 -288.463388) (xy 117.503085 -288.502732) (xy 117.525956 -288.546309) (xy 117.54154 -288.59299)
			(xy 117.549435 -288.641567) (xy 117.54993 -288.666174) (xy 117.878872 -288.666174) (xy 117.882832 -288.61712)
			(xy 117.894609 -288.569336) (xy 117.9139 -288.52406) (xy 117.940203 -288.482464) (xy 117.972838 -288.445627)
			(xy 118.010959 -288.414502) (xy 118.05358 -288.389895) (xy 118.099596 -288.372443) (xy 118.147815 -288.362599)
			(xy 118.19699 -288.360618) (xy 118.245845 -288.36655) (xy 118.293116 -288.380242) (xy 118.337578 -288.40134)
			(xy 118.378081 -288.429296) (xy 118.413574 -288.463388) (xy 118.443139 -288.502732) (xy 118.46601 -288.546309)
			(xy 118.481594 -288.59299) (xy 118.489489 -288.641567) (xy 118.489984 -288.666174) (xy 118.818926 -288.666174)
			(xy 118.822886 -288.61712) (xy 118.834663 -288.569336) (xy 118.853954 -288.52406) (xy 118.880257 -288.482464)
			(xy 118.912892 -288.445627) (xy 118.951013 -288.414502) (xy 118.993634 -288.389895) (xy 119.03965 -288.372443)
			(xy 119.087869 -288.362599) (xy 119.137044 -288.360618) (xy 119.185899 -288.36655) (xy 119.23317 -288.380242)
			(xy 119.277632 -288.40134) (xy 119.318135 -288.429296) (xy 119.353628 -288.463388) (xy 119.383193 -288.502732)
			(xy 119.406064 -288.546309) (xy 119.421648 -288.59299) (xy 119.429543 -288.641567) (xy 119.430038 -288.666174)
			(xy 119.75898 -288.666174) (xy 119.76294 -288.61712) (xy 119.774717 -288.569336) (xy 119.794008 -288.52406)
			(xy 119.820311 -288.482464) (xy 119.852946 -288.445627) (xy 119.891067 -288.414502) (xy 119.933688 -288.389895)
			(xy 119.979704 -288.372443) (xy 120.027923 -288.362599) (xy 120.077098 -288.360618) (xy 120.125953 -288.36655)
			(xy 120.173224 -288.380242) (xy 120.217686 -288.40134) (xy 120.258189 -288.429296) (xy 120.293682 -288.463388)
			(xy 120.323247 -288.502732) (xy 120.346118 -288.546309) (xy 120.361702 -288.59299) (xy 120.369597 -288.641567)
			(xy 120.370092 -288.666174) (xy 120.699034 -288.666174) (xy 120.702994 -288.61712) (xy 120.714771 -288.569336)
			(xy 120.734062 -288.52406) (xy 120.760365 -288.482464) (xy 120.793 -288.445627) (xy 120.831121 -288.414502)
			(xy 120.873742 -288.389895) (xy 120.919758 -288.372443) (xy 120.967977 -288.362599) (xy 121.017152 -288.360618)
			(xy 121.066007 -288.36655) (xy 121.113278 -288.380242) (xy 121.15774 -288.40134) (xy 121.198243 -288.429296)
			(xy 121.233736 -288.463388) (xy 121.263301 -288.502732) (xy 121.286172 -288.546309) (xy 121.301756 -288.59299)
			(xy 121.309651 -288.641567) (xy 121.310146 -288.666174) (xy 121.638834 -288.666174) (xy 121.642794 -288.61712)
			(xy 121.654571 -288.569336) (xy 121.673862 -288.52406) (xy 121.700165 -288.482464) (xy 121.7328 -288.445627)
			(xy 121.770921 -288.414502) (xy 121.813542 -288.389895) (xy 121.859558 -288.372443) (xy 121.907777 -288.362599)
			(xy 121.956952 -288.360618) (xy 122.005807 -288.36655) (xy 122.053078 -288.380242) (xy 122.09754 -288.40134)
			(xy 122.138043 -288.429296) (xy 122.173536 -288.463388) (xy 122.203101 -288.502732) (xy 122.225972 -288.546309)
			(xy 122.241556 -288.59299) (xy 122.249451 -288.641567) (xy 122.249946 -288.666174) (xy 122.578888 -288.666174)
			(xy 122.582848 -288.61712) (xy 122.594625 -288.569336) (xy 122.613916 -288.52406) (xy 122.640219 -288.482464)
			(xy 122.672854 -288.445627) (xy 122.710975 -288.414502) (xy 122.753596 -288.389895) (xy 122.799612 -288.372443)
			(xy 122.847831 -288.362599) (xy 122.897006 -288.360618) (xy 122.945861 -288.36655) (xy 122.993132 -288.380242)
			(xy 123.037594 -288.40134) (xy 123.078097 -288.429296) (xy 123.11359 -288.463388) (xy 123.143155 -288.502732)
			(xy 123.166026 -288.546309) (xy 123.18161 -288.59299) (xy 123.189505 -288.641567) (xy 123.19 -288.666174)
			(xy 123.518942 -288.666174) (xy 123.522902 -288.61712) (xy 123.534679 -288.569336) (xy 123.55397 -288.52406)
			(xy 123.580273 -288.482464) (xy 123.612908 -288.445627) (xy 123.651029 -288.414502) (xy 123.69365 -288.389895)
			(xy 123.739666 -288.372443) (xy 123.787885 -288.362599) (xy 123.83706 -288.360618) (xy 123.885915 -288.36655)
			(xy 123.933186 -288.380242) (xy 123.977648 -288.40134) (xy 124.018151 -288.429296) (xy 124.053644 -288.463388)
			(xy 124.083209 -288.502732) (xy 124.10608 -288.546309) (xy 124.121664 -288.59299) (xy 124.129559 -288.641567)
			(xy 124.130054 -288.666174) (xy 124.458996 -288.666174) (xy 124.462956 -288.61712) (xy 124.474733 -288.569336)
			(xy 124.494024 -288.52406) (xy 124.520327 -288.482464) (xy 124.552962 -288.445627) (xy 124.591083 -288.414502)
			(xy 124.633704 -288.389895) (xy 124.67972 -288.372443) (xy 124.727939 -288.362599) (xy 124.777114 -288.360618)
			(xy 124.825969 -288.36655) (xy 124.87324 -288.380242) (xy 124.917702 -288.40134) (xy 124.958205 -288.429296)
			(xy 124.993698 -288.463388) (xy 125.023263 -288.502732) (xy 125.046134 -288.546309) (xy 125.061718 -288.59299)
			(xy 125.069613 -288.641567) (xy 125.070108 -288.666174) (xy 125.39905 -288.666174) (xy 125.40301 -288.61712)
			(xy 125.414787 -288.569336) (xy 125.434078 -288.52406) (xy 125.460381 -288.482464) (xy 125.493016 -288.445627)
			(xy 125.531137 -288.414502) (xy 125.573758 -288.389895) (xy 125.619774 -288.372443) (xy 125.667993 -288.362599)
			(xy 125.717168 -288.360618) (xy 125.766023 -288.36655) (xy 125.813294 -288.380242) (xy 125.857756 -288.40134)
			(xy 125.898259 -288.429296) (xy 125.933752 -288.463388) (xy 125.963317 -288.502732) (xy 125.986188 -288.546309)
			(xy 126.001772 -288.59299) (xy 126.009667 -288.641567) (xy 126.010162 -288.666174) (xy 126.33885 -288.666174)
			(xy 126.34281 -288.61712) (xy 126.354587 -288.569336) (xy 126.373878 -288.52406) (xy 126.400181 -288.482464)
			(xy 126.432816 -288.445627) (xy 126.470937 -288.414502) (xy 126.513558 -288.389895) (xy 126.559574 -288.372443)
			(xy 126.607793 -288.362599) (xy 126.656968 -288.360618) (xy 126.705823 -288.36655) (xy 126.753094 -288.380242)
			(xy 126.797556 -288.40134) (xy 126.838059 -288.429296) (xy 126.873552 -288.463388) (xy 126.903117 -288.502732)
			(xy 126.925988 -288.546309) (xy 126.941572 -288.59299) (xy 126.949467 -288.641567) (xy 126.949962 -288.666174)
			(xy 126.949467 -288.690781) (xy 126.941572 -288.739358) (xy 126.925988 -288.786039) (xy 126.903117 -288.829616)
			(xy 126.873552 -288.86896) (xy 126.838059 -288.903052) (xy 126.797556 -288.931008) (xy 126.753094 -288.952106)
			(xy 126.705823 -288.965798) (xy 126.656968 -288.97173) (xy 126.607793 -288.969749) (xy 126.559574 -288.959905)
			(xy 126.513558 -288.942453) (xy 126.470937 -288.917846) (xy 126.432816 -288.886721) (xy 126.400181 -288.849884)
			(xy 126.373878 -288.808288) (xy 126.354587 -288.763012) (xy 126.34281 -288.715228) (xy 126.33885 -288.666174)
			(xy 126.010162 -288.666174) (xy 126.009667 -288.690781) (xy 126.001772 -288.739358) (xy 125.986188 -288.786039)
			(xy 125.963317 -288.829616) (xy 125.933752 -288.86896) (xy 125.898259 -288.903052) (xy 125.857756 -288.931008)
			(xy 125.813294 -288.952106) (xy 125.766023 -288.965798) (xy 125.717168 -288.97173) (xy 125.667993 -288.969749)
			(xy 125.619774 -288.959905) (xy 125.573758 -288.942453) (xy 125.531137 -288.917846) (xy 125.493016 -288.886721)
			(xy 125.460381 -288.849884) (xy 125.434078 -288.808288) (xy 125.414787 -288.763012) (xy 125.40301 -288.715228)
			(xy 125.39905 -288.666174) (xy 125.070108 -288.666174) (xy 125.069613 -288.690781) (xy 125.061718 -288.739358)
			(xy 125.046134 -288.786039) (xy 125.023263 -288.829616) (xy 124.993698 -288.86896) (xy 124.958205 -288.903052)
			(xy 124.917702 -288.931008) (xy 124.87324 -288.952106) (xy 124.825969 -288.965798) (xy 124.777114 -288.97173)
			(xy 124.727939 -288.969749) (xy 124.67972 -288.959905) (xy 124.633704 -288.942453) (xy 124.591083 -288.917846)
			(xy 124.552962 -288.886721) (xy 124.520327 -288.849884) (xy 124.494024 -288.808288) (xy 124.474733 -288.763012)
			(xy 124.462956 -288.715228) (xy 124.458996 -288.666174) (xy 124.130054 -288.666174) (xy 124.129559 -288.690781)
			(xy 124.121664 -288.739358) (xy 124.10608 -288.786039) (xy 124.083209 -288.829616) (xy 124.053644 -288.86896)
			(xy 124.018151 -288.903052) (xy 123.977648 -288.931008) (xy 123.933186 -288.952106) (xy 123.885915 -288.965798)
			(xy 123.83706 -288.97173) (xy 123.787885 -288.969749) (xy 123.739666 -288.959905) (xy 123.69365 -288.942453)
			(xy 123.651029 -288.917846) (xy 123.612908 -288.886721) (xy 123.580273 -288.849884) (xy 123.55397 -288.808288)
			(xy 123.534679 -288.763012) (xy 123.522902 -288.715228) (xy 123.518942 -288.666174) (xy 123.19 -288.666174)
			(xy 123.189505 -288.690781) (xy 123.18161 -288.739358) (xy 123.166026 -288.786039) (xy 123.143155 -288.829616)
			(xy 123.11359 -288.86896) (xy 123.078097 -288.903052) (xy 123.037594 -288.931008) (xy 122.993132 -288.952106)
			(xy 122.945861 -288.965798) (xy 122.897006 -288.97173) (xy 122.847831 -288.969749) (xy 122.799612 -288.959905)
			(xy 122.753596 -288.942453) (xy 122.710975 -288.917846) (xy 122.672854 -288.886721) (xy 122.640219 -288.849884)
			(xy 122.613916 -288.808288) (xy 122.594625 -288.763012) (xy 122.582848 -288.715228) (xy 122.578888 -288.666174)
			(xy 122.249946 -288.666174) (xy 122.249451 -288.690781) (xy 122.241556 -288.739358) (xy 122.225972 -288.786039)
			(xy 122.203101 -288.829616) (xy 122.173536 -288.86896) (xy 122.138043 -288.903052) (xy 122.09754 -288.931008)
			(xy 122.053078 -288.952106) (xy 122.005807 -288.965798) (xy 121.956952 -288.97173) (xy 121.907777 -288.969749)
			(xy 121.859558 -288.959905) (xy 121.813542 -288.942453) (xy 121.770921 -288.917846) (xy 121.7328 -288.886721)
			(xy 121.700165 -288.849884) (xy 121.673862 -288.808288) (xy 121.654571 -288.763012) (xy 121.642794 -288.715228)
			(xy 121.638834 -288.666174) (xy 121.310146 -288.666174) (xy 121.309651 -288.690781) (xy 121.301756 -288.739358)
			(xy 121.286172 -288.786039) (xy 121.263301 -288.829616) (xy 121.233736 -288.86896) (xy 121.198243 -288.903052)
			(xy 121.15774 -288.931008) (xy 121.113278 -288.952106) (xy 121.066007 -288.965798) (xy 121.017152 -288.97173)
			(xy 120.967977 -288.969749) (xy 120.919758 -288.959905) (xy 120.873742 -288.942453) (xy 120.831121 -288.917846)
			(xy 120.793 -288.886721) (xy 120.760365 -288.849884) (xy 120.734062 -288.808288) (xy 120.714771 -288.763012)
			(xy 120.702994 -288.715228) (xy 120.699034 -288.666174) (xy 120.370092 -288.666174) (xy 120.369597 -288.690781)
			(xy 120.361702 -288.739358) (xy 120.346118 -288.786039) (xy 120.323247 -288.829616) (xy 120.293682 -288.86896)
			(xy 120.258189 -288.903052) (xy 120.217686 -288.931008) (xy 120.173224 -288.952106) (xy 120.125953 -288.965798)
			(xy 120.077098 -288.97173) (xy 120.027923 -288.969749) (xy 119.979704 -288.959905) (xy 119.933688 -288.942453)
			(xy 119.891067 -288.917846) (xy 119.852946 -288.886721) (xy 119.820311 -288.849884) (xy 119.794008 -288.808288)
			(xy 119.774717 -288.763012) (xy 119.76294 -288.715228) (xy 119.75898 -288.666174) (xy 119.430038 -288.666174)
			(xy 119.429543 -288.690781) (xy 119.421648 -288.739358) (xy 119.406064 -288.786039) (xy 119.383193 -288.829616)
			(xy 119.353628 -288.86896) (xy 119.318135 -288.903052) (xy 119.277632 -288.931008) (xy 119.23317 -288.952106)
			(xy 119.185899 -288.965798) (xy 119.137044 -288.97173) (xy 119.087869 -288.969749) (xy 119.03965 -288.959905)
			(xy 118.993634 -288.942453) (xy 118.951013 -288.917846) (xy 118.912892 -288.886721) (xy 118.880257 -288.849884)
			(xy 118.853954 -288.808288) (xy 118.834663 -288.763012) (xy 118.822886 -288.715228) (xy 118.818926 -288.666174)
			(xy 118.489984 -288.666174) (xy 118.489489 -288.690781) (xy 118.481594 -288.739358) (xy 118.46601 -288.786039)
			(xy 118.443139 -288.829616) (xy 118.413574 -288.86896) (xy 118.378081 -288.903052) (xy 118.337578 -288.931008)
			(xy 118.293116 -288.952106) (xy 118.245845 -288.965798) (xy 118.19699 -288.97173) (xy 118.147815 -288.969749)
			(xy 118.099596 -288.959905) (xy 118.05358 -288.942453) (xy 118.010959 -288.917846) (xy 117.972838 -288.886721)
			(xy 117.940203 -288.849884) (xy 117.9139 -288.808288) (xy 117.894609 -288.763012) (xy 117.882832 -288.715228)
			(xy 117.878872 -288.666174) (xy 117.54993 -288.666174) (xy 117.549435 -288.690781) (xy 117.54154 -288.739358)
			(xy 117.525956 -288.786039) (xy 117.503085 -288.829616) (xy 117.47352 -288.86896) (xy 117.438027 -288.903052)
			(xy 117.397524 -288.931008) (xy 117.353062 -288.952106) (xy 117.305791 -288.965798) (xy 117.256936 -288.97173)
			(xy 117.207761 -288.969749) (xy 117.159542 -288.959905) (xy 117.113526 -288.942453) (xy 117.070905 -288.917846)
			(xy 117.032784 -288.886721) (xy 117.000149 -288.849884) (xy 116.973846 -288.808288) (xy 116.954555 -288.763012)
			(xy 116.942778 -288.715228) (xy 116.938818 -288.666174) (xy 116.61013 -288.666174) (xy 116.609635 -288.690781)
			(xy 116.60174 -288.739358) (xy 116.586156 -288.786039) (xy 116.563285 -288.829616) (xy 116.53372 -288.86896)
			(xy 116.498227 -288.903052) (xy 116.457724 -288.931008) (xy 116.413262 -288.952106) (xy 116.365991 -288.965798)
			(xy 116.317136 -288.97173) (xy 116.267961 -288.969749) (xy 116.219742 -288.959905) (xy 116.173726 -288.942453)
			(xy 116.131105 -288.917846) (xy 116.092984 -288.886721) (xy 116.060349 -288.849884) (xy 116.034046 -288.808288)
			(xy 116.014755 -288.763012) (xy 116.002978 -288.715228) (xy 115.999018 -288.666174) (xy 115.670887 -288.666174)
			(xy 115.670889 -288.6662) (xy 115.666713 -288.716584) (xy 115.654302 -288.765593) (xy 115.633992 -288.811891)
			(xy 115.606339 -288.854214) (xy 115.572096 -288.891408) (xy 115.532198 -288.922458) (xy 115.487733 -288.946517)
			(xy 115.439914 -288.962929) (xy 115.390046 -288.971246) (xy 115.364768 -288.971736) (xy 114.424714 -288.971736)
			(xy 114.399432 -288.971296) (xy 114.349558 -288.962976) (xy 114.301734 -288.946559) (xy 114.257264 -288.922495)
			(xy 114.217362 -288.89144) (xy 114.183116 -288.85424) (xy 114.15546 -288.811911) (xy 114.135148 -288.765606)
			(xy 114.122735 -288.716591) (xy 114.118559 -288.6662) (xy 113.789967 -288.6662) (xy 113.789473 -288.690781)
			(xy 113.781578 -288.739358) (xy 113.765994 -288.786039) (xy 113.743123 -288.829616) (xy 113.713558 -288.86896)
			(xy 113.678065 -288.903052) (xy 113.637562 -288.931008) (xy 113.5931 -288.952106) (xy 113.545829 -288.965798)
			(xy 113.496974 -288.97173) (xy 113.447799 -288.969749) (xy 113.39958 -288.959905) (xy 113.353564 -288.942453)
			(xy 113.310943 -288.917846) (xy 113.272822 -288.886721) (xy 113.240187 -288.849884) (xy 113.213884 -288.808288)
			(xy 113.194593 -288.763012) (xy 113.182816 -288.715228) (xy 113.178856 -288.666174) (xy 110.97641 -288.666174)
			(xy 110.975915 -288.690781) (xy 110.96802 -288.739358) (xy 110.952436 -288.786039) (xy 110.929565 -288.829616)
			(xy 110.9 -288.86896) (xy 110.864507 -288.903052) (xy 110.824004 -288.931008) (xy 110.779542 -288.952106)
			(xy 110.732271 -288.965798) (xy 110.683416 -288.97173) (xy 110.634241 -288.969749) (xy 110.586022 -288.959905)
			(xy 110.540006 -288.942453) (xy 110.497385 -288.917846) (xy 110.459264 -288.886721) (xy 110.426629 -288.849884)
			(xy 110.400326 -288.808288) (xy 110.381035 -288.763012) (xy 110.369258 -288.715228) (xy 110.365298 -288.666174)
			(xy 110.037058 -288.666174) (xy 110.03706 -288.6662) (xy 110.032886 -288.716571) (xy 110.02048 -288.765568)
			(xy 110.000179 -288.811855) (xy 109.972536 -288.85417) (xy 109.938307 -288.891358) (xy 109.898424 -288.922406)
			(xy 109.853975 -288.946467) (xy 109.806172 -288.962884) (xy 109.75632 -288.97121) (xy 109.731048 -288.971736)
			(xy 108.790994 -288.971736) (xy 108.765716 -288.971266) (xy 108.715849 -288.962943) (xy 108.668032 -288.946527)
			(xy 108.62357 -288.922464) (xy 108.583674 -288.891411) (xy 108.549433 -288.854216) (xy 108.521782 -288.811891)
			(xy 108.501474 -288.765593) (xy 108.489063 -288.716584) (xy 108.484888 -288.6662) (xy 108.156247 -288.6662)
			(xy 108.155753 -288.690781) (xy 108.147858 -288.739358) (xy 108.132274 -288.786039) (xy 108.109403 -288.829616)
			(xy 108.079838 -288.86896) (xy 108.044345 -288.903052) (xy 108.003842 -288.931008) (xy 107.95938 -288.952106)
			(xy 107.912109 -288.965798) (xy 107.863254 -288.97173) (xy 107.814079 -288.969749) (xy 107.76586 -288.959905)
			(xy 107.719844 -288.942453) (xy 107.677223 -288.917846) (xy 107.639102 -288.886721) (xy 107.606467 -288.849884)
			(xy 107.580164 -288.808288) (xy 107.560873 -288.763012) (xy 107.549096 -288.715228) (xy 107.545136 -288.666174)
			(xy 107.216448 -288.666174) (xy 107.215953 -288.690781) (xy 107.208058 -288.739358) (xy 107.192474 -288.786039)
			(xy 107.169603 -288.829616) (xy 107.140038 -288.86896) (xy 107.104545 -288.903052) (xy 107.064042 -288.931008)
			(xy 107.01958 -288.952106) (xy 106.972309 -288.965798) (xy 106.923454 -288.97173) (xy 106.874279 -288.969749)
			(xy 106.82606 -288.959905) (xy 106.780044 -288.942453) (xy 106.737423 -288.917846) (xy 106.699302 -288.886721)
			(xy 106.666667 -288.849884) (xy 106.640364 -288.808288) (xy 106.621073 -288.763012) (xy 106.609296 -288.715228)
			(xy 106.605336 -288.666174) (xy 106.276394 -288.666174) (xy 106.275899 -288.690781) (xy 106.268004 -288.739358)
			(xy 106.25242 -288.786039) (xy 106.229549 -288.829616) (xy 106.199984 -288.86896) (xy 106.164491 -288.903052)
			(xy 106.123988 -288.931008) (xy 106.079526 -288.952106) (xy 106.032255 -288.965798) (xy 105.9834 -288.97173)
			(xy 105.934225 -288.969749) (xy 105.886006 -288.959905) (xy 105.83999 -288.942453) (xy 105.797369 -288.917846)
			(xy 105.759248 -288.886721) (xy 105.726613 -288.849884) (xy 105.70031 -288.808288) (xy 105.681019 -288.763012)
			(xy 105.669242 -288.715228) (xy 105.665282 -288.666174) (xy 105.33634 -288.666174) (xy 105.335845 -288.690781)
			(xy 105.32795 -288.739358) (xy 105.312366 -288.786039) (xy 105.289495 -288.829616) (xy 105.25993 -288.86896)
			(xy 105.224437 -288.903052) (xy 105.183934 -288.931008) (xy 105.139472 -288.952106) (xy 105.092201 -288.965798)
			(xy 105.043346 -288.97173) (xy 104.994171 -288.969749) (xy 104.945952 -288.959905) (xy 104.899936 -288.942453)
			(xy 104.857315 -288.917846) (xy 104.819194 -288.886721) (xy 104.786559 -288.849884) (xy 104.760256 -288.808288)
			(xy 104.740965 -288.763012) (xy 104.729188 -288.715228) (xy 104.725228 -288.666174) (xy 104.396286 -288.666174)
			(xy 104.395791 -288.690781) (xy 104.387896 -288.739358) (xy 104.372312 -288.786039) (xy 104.349441 -288.829616)
			(xy 104.319876 -288.86896) (xy 104.284383 -288.903052) (xy 104.24388 -288.931008) (xy 104.199418 -288.952106)
			(xy 104.152147 -288.965798) (xy 104.103292 -288.97173) (xy 104.054117 -288.969749) (xy 104.005898 -288.959905)
			(xy 103.959882 -288.942453) (xy 103.917261 -288.917846) (xy 103.87914 -288.886721) (xy 103.846505 -288.849884)
			(xy 103.820202 -288.808288) (xy 103.800911 -288.763012) (xy 103.789134 -288.715228) (xy 103.785174 -288.666174)
			(xy 103.456486 -288.666174) (xy 103.455991 -288.690781) (xy 103.448096 -288.739358) (xy 103.432512 -288.786039)
			(xy 103.409641 -288.829616) (xy 103.380076 -288.86896) (xy 103.344583 -288.903052) (xy 103.30408 -288.931008)
			(xy 103.259618 -288.952106) (xy 103.212347 -288.965798) (xy 103.163492 -288.97173) (xy 103.114317 -288.969749)
			(xy 103.066098 -288.959905) (xy 103.020082 -288.942453) (xy 102.977461 -288.917846) (xy 102.93934 -288.886721)
			(xy 102.906705 -288.849884) (xy 102.880402 -288.808288) (xy 102.861111 -288.763012) (xy 102.849334 -288.715228)
			(xy 102.845374 -288.666174) (xy 102.516432 -288.666174) (xy 102.515937 -288.690781) (xy 102.508042 -288.739358)
			(xy 102.492458 -288.786039) (xy 102.469587 -288.829616) (xy 102.440022 -288.86896) (xy 102.404529 -288.903052)
			(xy 102.364026 -288.931008) (xy 102.319564 -288.952106) (xy 102.272293 -288.965798) (xy 102.223438 -288.97173)
			(xy 102.174263 -288.969749) (xy 102.126044 -288.959905) (xy 102.080028 -288.942453) (xy 102.037407 -288.917846)
			(xy 101.999286 -288.886721) (xy 101.966651 -288.849884) (xy 101.940348 -288.808288) (xy 101.921057 -288.763012)
			(xy 101.90928 -288.715228) (xy 101.90532 -288.666174) (xy 101.576378 -288.666174) (xy 101.575883 -288.690781)
			(xy 101.567988 -288.739358) (xy 101.552404 -288.786039) (xy 101.529533 -288.829616) (xy 101.499968 -288.86896)
			(xy 101.464475 -288.903052) (xy 101.423972 -288.931008) (xy 101.37951 -288.952106) (xy 101.332239 -288.965798)
			(xy 101.283384 -288.97173) (xy 101.234209 -288.969749) (xy 101.18599 -288.959905) (xy 101.139974 -288.942453)
			(xy 101.097353 -288.917846) (xy 101.059232 -288.886721) (xy 101.026597 -288.849884) (xy 101.000294 -288.808288)
			(xy 100.981003 -288.763012) (xy 100.969226 -288.715228) (xy 100.965266 -288.666174) (xy 100.636324 -288.666174)
			(xy 100.635829 -288.690781) (xy 100.627934 -288.739358) (xy 100.61235 -288.786039) (xy 100.589479 -288.829616)
			(xy 100.559914 -288.86896) (xy 100.524421 -288.903052) (xy 100.483918 -288.931008) (xy 100.439456 -288.952106)
			(xy 100.392185 -288.965798) (xy 100.34333 -288.97173) (xy 100.294155 -288.969749) (xy 100.245936 -288.959905)
			(xy 100.19992 -288.942453) (xy 100.157299 -288.917846) (xy 100.119178 -288.886721) (xy 100.086543 -288.849884)
			(xy 100.06024 -288.808288) (xy 100.040949 -288.763012) (xy 100.029172 -288.715228) (xy 100.025212 -288.666174)
			(xy 99.69627 -288.666174) (xy 99.695775 -288.690781) (xy 99.68788 -288.739358) (xy 99.672296 -288.786039)
			(xy 99.649425 -288.829616) (xy 99.61986 -288.86896) (xy 99.584367 -288.903052) (xy 99.543864 -288.931008)
			(xy 99.499402 -288.952106) (xy 99.452131 -288.965798) (xy 99.403276 -288.97173) (xy 99.354101 -288.969749)
			(xy 99.305882 -288.959905) (xy 99.259866 -288.942453) (xy 99.217245 -288.917846) (xy 99.179124 -288.886721)
			(xy 99.146489 -288.849884) (xy 99.120186 -288.808288) (xy 99.100895 -288.763012) (xy 99.089118 -288.715228)
			(xy 99.085158 -288.666174) (xy 98.75647 -288.666174) (xy 98.755975 -288.690781) (xy 98.74808 -288.739358)
			(xy 98.732496 -288.786039) (xy 98.709625 -288.829616) (xy 98.68006 -288.86896) (xy 98.644567 -288.903052)
			(xy 98.604064 -288.931008) (xy 98.559602 -288.952106) (xy 98.512331 -288.965798) (xy 98.463476 -288.97173)
			(xy 98.414301 -288.969749) (xy 98.366082 -288.959905) (xy 98.320066 -288.942453) (xy 98.277445 -288.917846)
			(xy 98.239324 -288.886721) (xy 98.206689 -288.849884) (xy 98.180386 -288.808288) (xy 98.161095 -288.763012)
			(xy 98.149318 -288.715228) (xy 98.145358 -288.666174) (xy 97.816416 -288.666174) (xy 97.815921 -288.690781)
			(xy 97.808026 -288.739358) (xy 97.792442 -288.786039) (xy 97.769571 -288.829616) (xy 97.740006 -288.86896)
			(xy 97.704513 -288.903052) (xy 97.66401 -288.931008) (xy 97.619548 -288.952106) (xy 97.572277 -288.965798)
			(xy 97.523422 -288.97173) (xy 97.474247 -288.969749) (xy 97.426028 -288.959905) (xy 97.380012 -288.942453)
			(xy 97.337391 -288.917846) (xy 97.29927 -288.886721) (xy 97.266635 -288.849884) (xy 97.240332 -288.808288)
			(xy 97.221041 -288.763012) (xy 97.209264 -288.715228) (xy 97.205304 -288.666174) (xy 96.875955 -288.666174)
			(xy 96.875956 -288.691023) (xy 96.867923 -288.74002) (xy 96.852068 -288.787072) (xy 96.82881 -288.830939)
			(xy 96.798761 -288.870464) (xy 96.762712 -288.904607) (xy 96.721614 -288.932468) (xy 96.67655 -288.953312)
			(xy 96.628707 -288.966591) (xy 96.604074 -288.969704) (xy 96.60001 -288.970212) (xy 96.595374 -288.971188)
			(xy 96.586552 -288.974641) (xy 96.582484 -288.97707) (xy 96.572832 -288.985198) (xy 96.552258 -289.007042)
			(xy 96.546775 -289.01327) (xy 96.539767 -289.0283) (xy 96.538542 -289.036506) (xy 96.538288 -289.042094)
			(xy 96.538288 -289.121088) (xy 96.538542 -289.125406) (xy 96.539221 -289.131608) (xy 96.5432 -289.143429)
			(xy 96.546416 -289.148774) (xy 96.54794 -289.150806) (xy 96.560715 -289.168656) (xy 96.583729 -289.206038)
			(xy 96.593914 -289.225482) (xy 96.600036 -289.237682) (xy 96.611218 -289.262584) (xy 96.616266 -289.275266)
			(xy 96.616266 -289.27552) (xy 96.618895 -289.281708) (xy 96.62687 -289.292527) (xy 96.632014 -289.296856)
			(xy 96.637602 -289.301174) (xy 96.650302 -289.306254) (xy 96.712024 -289.314128) (xy 96.745552 -289.318446)
			(xy 96.755087 -289.319244) (xy 96.773622 -289.314552) (xy 96.78162 -289.309302) (xy 96.793304 -289.297618)
			(xy 96.795336 -289.29457) (xy 96.809867 -289.27574) (xy 96.843774 -289.242387) (xy 96.882432 -289.214682)
			(xy 96.924911 -289.193291) (xy 96.970189 -289.17873) (xy 97.017174 -289.171349) (xy 97.040954 -289.170872)
			(xy 97.066216 -289.171361) (xy 97.116051 -289.17967) (xy 97.16384 -289.19607) (xy 97.208276 -289.220112)
			(xy 97.248149 -289.25114) (xy 97.28237 -289.288309) (xy 97.310007 -289.330604) (xy 97.330303 -289.376872)
			(xy 97.342707 -289.425849) (xy 97.34688 -289.4762) (xy 97.67512 -289.4762) (xy 97.679292 -289.425853)
			(xy 97.691694 -289.376879) (xy 97.711988 -289.330615) (xy 97.73962 -289.288322) (xy 97.773836 -289.251154)
			(xy 97.813704 -289.220125) (xy 97.858135 -289.196081) (xy 97.905917 -289.179678) (xy 97.955748 -289.171364)
			(xy 97.981008 -289.170872) (xy 98.921062 -289.170872) (xy 98.94632 -289.171402) (xy 98.996148 -289.179711)
			(xy 99.043929 -289.196109) (xy 99.088359 -289.220148) (xy 99.128225 -289.251173) (xy 99.162441 -289.288337)
			(xy 99.190073 -289.330626) (xy 99.210366 -289.376886) (xy 99.222768 -289.425856) (xy 99.226938 -289.47618)
			(xy 99.555312 -289.47618) (xy 99.559272 -289.427126) (xy 99.571049 -289.379342) (xy 99.59034 -289.334066)
			(xy 99.616643 -289.29247) (xy 99.649278 -289.255633) (xy 99.687399 -289.224508) (xy 99.73002 -289.199901)
			(xy 99.776036 -289.182449) (xy 99.824255 -289.172605) (xy 99.87343 -289.170624) (xy 99.922285 -289.176556)
			(xy 99.969556 -289.190248) (xy 100.014018 -289.211346) (xy 100.054521 -289.239302) (xy 100.090014 -289.273394)
			(xy 100.119579 -289.312738) (xy 100.14245 -289.356315) (xy 100.158034 -289.402996) (xy 100.165929 -289.451573)
			(xy 100.166424 -289.47618) (xy 100.166424 -289.4762) (xy 100.495349 -289.4762) (xy 100.49952 -289.425862)
			(xy 100.511919 -289.376896) (xy 100.532208 -289.330639) (xy 100.559833 -289.288352) (xy 100.594041 -289.251189)
			(xy 100.633899 -289.220162) (xy 100.678321 -289.196119) (xy 100.726093 -289.179714) (xy 100.775915 -289.171396)
			(xy 100.80117 -289.170872) (xy 101.741224 -289.170872) (xy 101.766476 -289.171435) (xy 101.816292 -289.179752)
			(xy 101.864059 -289.196154) (xy 101.908475 -289.220194) (xy 101.948329 -289.251216) (xy 101.982534 -289.288375)
			(xy 102.010156 -289.330657) (xy 102.030443 -289.376908) (xy 102.042841 -289.425868) (xy 102.047009 -289.47618)
			(xy 102.37522 -289.47618) (xy 102.37918 -289.427126) (xy 102.390957 -289.379342) (xy 102.410248 -289.334066)
			(xy 102.436551 -289.29247) (xy 102.469186 -289.255633) (xy 102.507307 -289.224508) (xy 102.549928 -289.199901)
			(xy 102.595944 -289.182449) (xy 102.644163 -289.172605) (xy 102.693338 -289.170624) (xy 102.742193 -289.176556)
			(xy 102.789464 -289.190248) (xy 102.833926 -289.211346) (xy 102.874429 -289.239302) (xy 102.909922 -289.273394)
			(xy 102.939487 -289.312738) (xy 102.962358 -289.356315) (xy 102.977942 -289.402996) (xy 102.985837 -289.451573)
			(xy 102.986332 -289.47618) (xy 102.986332 -289.4762) (xy 103.315249 -289.4762) (xy 103.31942 -289.425861)
			(xy 103.331819 -289.376895) (xy 103.352109 -289.330637) (xy 103.379735 -289.28835) (xy 103.413944 -289.251186)
			(xy 103.453804 -289.220159) (xy 103.498226 -289.196116) (xy 103.546 -289.179713) (xy 103.595822 -289.171395)
			(xy 103.621078 -289.170872) (xy 104.561132 -289.170872) (xy 104.586384 -289.171436) (xy 104.636198 -289.179753)
			(xy 104.683965 -289.196156) (xy 104.72838 -289.220196) (xy 104.768233 -289.251219) (xy 104.802436 -289.288378)
			(xy 104.830058 -289.330659) (xy 104.850344 -289.37691) (xy 104.862741 -289.425868) (xy 104.866909 -289.47618)
			(xy 105.195128 -289.47618) (xy 105.199088 -289.427126) (xy 105.210865 -289.379342) (xy 105.230156 -289.334066)
			(xy 105.256459 -289.29247) (xy 105.289094 -289.255633) (xy 105.327215 -289.224508) (xy 105.369836 -289.199901)
			(xy 105.415852 -289.182449) (xy 105.464071 -289.172605) (xy 105.513246 -289.170624) (xy 105.562101 -289.176556)
			(xy 105.609372 -289.190248) (xy 105.653834 -289.211346) (xy 105.694337 -289.239302) (xy 105.72983 -289.273394)
			(xy 105.759395 -289.312738) (xy 105.782266 -289.356315) (xy 105.79785 -289.402996) (xy 105.805745 -289.451573)
			(xy 105.80624 -289.47618) (xy 105.80624 -289.4762) (xy 106.135149 -289.4762) (xy 106.13932 -289.42586)
			(xy 106.15172 -289.376893) (xy 106.17201 -289.330635) (xy 106.199637 -289.288347) (xy 106.233847 -289.251183)
			(xy 106.273708 -289.220157) (xy 106.318132 -289.196114) (xy 106.365907 -289.179711) (xy 106.41573 -289.171395)
			(xy 106.440986 -289.170872) (xy 107.38104 -289.170872) (xy 107.406291 -289.171437) (xy 107.456105 -289.179755)
			(xy 107.50387 -289.196158) (xy 107.548284 -289.220199) (xy 107.588136 -289.251222) (xy 107.622338 -289.28838)
			(xy 107.649959 -289.330661) (xy 107.670244 -289.376911) (xy 107.682641 -289.425869) (xy 107.686809 -289.47618)
			(xy 108.01529 -289.47618) (xy 108.01925 -289.427126) (xy 108.031027 -289.379342) (xy 108.050318 -289.334066)
			(xy 108.076621 -289.29247) (xy 108.109256 -289.255633) (xy 108.147377 -289.224508) (xy 108.189998 -289.199901)
			(xy 108.236014 -289.182449) (xy 108.284233 -289.172605) (xy 108.333408 -289.170624) (xy 108.382263 -289.176556)
			(xy 108.429534 -289.190248) (xy 108.473996 -289.211346) (xy 108.514499 -289.239302) (xy 108.549992 -289.273394)
			(xy 108.579557 -289.312738) (xy 108.602428 -289.356315) (xy 108.618012 -289.402996) (xy 108.625907 -289.451573)
			(xy 108.626402 -289.47618) (xy 115.528864 -289.47618) (xy 115.532824 -289.427126) (xy 115.544601 -289.379342)
			(xy 115.563892 -289.334066) (xy 115.590195 -289.29247) (xy 115.62283 -289.255633) (xy 115.660951 -289.224508)
			(xy 115.703572 -289.199901) (xy 115.749588 -289.182449) (xy 115.797807 -289.172605) (xy 115.846982 -289.170624)
			(xy 115.895837 -289.176556) (xy 115.943108 -289.190248) (xy 115.98757 -289.211346) (xy 116.028073 -289.239302)
			(xy 116.063566 -289.273394) (xy 116.093131 -289.312738) (xy 116.116002 -289.356315) (xy 116.131586 -289.402996)
			(xy 116.139481 -289.451573) (xy 116.139976 -289.47618) (xy 116.139976 -289.4762) (xy 116.46882 -289.4762)
			(xy 116.472992 -289.425852) (xy 116.485395 -289.376877) (xy 116.50569 -289.330611) (xy 116.533323 -289.288317)
			(xy 116.567542 -289.251149) (xy 116.607411 -289.22012) (xy 116.651844 -289.196077) (xy 116.699629 -289.179675)
			(xy 116.749461 -289.171363) (xy 116.774722 -289.170872) (xy 117.714776 -289.170872) (xy 117.740033 -289.171403)
			(xy 117.78986 -289.179714) (xy 117.837638 -289.196113) (xy 117.882066 -289.220153) (xy 117.92193 -289.251178)
			(xy 117.956145 -289.288341) (xy 117.983775 -289.33063) (xy 118.004067 -289.376889) (xy 118.016468 -289.425858)
			(xy 118.020638 -289.47618) (xy 118.349026 -289.47618) (xy 118.352986 -289.427126) (xy 118.364763 -289.379342)
			(xy 118.384054 -289.334066) (xy 118.410357 -289.29247) (xy 118.442992 -289.255633) (xy 118.481113 -289.224508)
			(xy 118.523734 -289.199901) (xy 118.56975 -289.182449) (xy 118.617969 -289.172605) (xy 118.667144 -289.170624)
			(xy 118.715999 -289.176556) (xy 118.76327 -289.190248) (xy 118.807732 -289.211346) (xy 118.848235 -289.239302)
			(xy 118.883728 -289.273394) (xy 118.913293 -289.312738) (xy 118.936164 -289.356315) (xy 118.951748 -289.402996)
			(xy 118.959643 -289.451573) (xy 118.960138 -289.47618) (xy 118.960138 -289.4762) (xy 119.28872 -289.4762)
			(xy 119.292892 -289.425851) (xy 119.305295 -289.376875) (xy 119.325591 -289.330609) (xy 119.353225 -289.288315)
			(xy 119.387445 -289.251146) (xy 119.427315 -289.220117) (xy 119.47175 -289.196074) (xy 119.519535 -289.179674)
			(xy 119.569369 -289.171362) (xy 119.59463 -289.170872) (xy 120.534684 -289.170872) (xy 120.559941 -289.171403)
			(xy 120.609766 -289.179715) (xy 120.657544 -289.196115) (xy 120.70197 -289.220155) (xy 120.741834 -289.25118)
			(xy 120.776047 -289.288344) (xy 120.803676 -289.330632) (xy 120.823968 -289.376891) (xy 120.836368 -289.425859)
			(xy 120.840538 -289.47618) (xy 121.168934 -289.47618) (xy 121.172894 -289.427126) (xy 121.184671 -289.379342)
			(xy 121.203962 -289.334066) (xy 121.230265 -289.29247) (xy 121.2629 -289.255633) (xy 121.301021 -289.224508)
			(xy 121.343642 -289.199901) (xy 121.389658 -289.182449) (xy 121.437877 -289.172605) (xy 121.487052 -289.170624)
			(xy 121.535907 -289.176556) (xy 121.583178 -289.190248) (xy 121.62764 -289.211346) (xy 121.668143 -289.239302)
			(xy 121.703636 -289.273394) (xy 121.733201 -289.312738) (xy 121.756072 -289.356315) (xy 121.771656 -289.402996)
			(xy 121.779551 -289.451573) (xy 121.780046 -289.47618) (xy 121.780046 -289.4762) (xy 122.108949 -289.4762)
			(xy 122.11312 -289.425859) (xy 122.12552 -289.376892) (xy 122.145811 -289.330633) (xy 122.173439 -289.288345)
			(xy 122.20765 -289.251181) (xy 122.247511 -289.220155) (xy 122.291936 -289.196112) (xy 122.339711 -289.17971)
			(xy 122.389535 -289.171394) (xy 122.414792 -289.170872) (xy 123.354846 -289.170872) (xy 123.380097 -289.171437)
			(xy 123.42991 -289.179756) (xy 123.477674 -289.19616) (xy 123.522087 -289.220201) (xy 123.561938 -289.251224)
			(xy 123.59614 -289.288382) (xy 123.62376 -289.330663) (xy 123.644044 -289.376913) (xy 123.656441 -289.42587)
			(xy 123.660609 -289.47618) (xy 123.988842 -289.47618) (xy 123.992802 -289.427126) (xy 124.004579 -289.379342)
			(xy 124.02387 -289.334066) (xy 124.050173 -289.29247) (xy 124.082808 -289.255633) (xy 124.120929 -289.224508)
			(xy 124.16355 -289.199901) (xy 124.209566 -289.182449) (xy 124.257785 -289.172605) (xy 124.30696 -289.170624)
			(xy 124.355815 -289.176556) (xy 124.403086 -289.190248) (xy 124.447548 -289.211346) (xy 124.488051 -289.239302)
			(xy 124.523544 -289.273394) (xy 124.553109 -289.312738) (xy 124.57598 -289.356315) (xy 124.591564 -289.402996)
			(xy 124.599459 -289.451573) (xy 124.599954 -289.47618) (xy 124.599954 -289.4762) (xy 124.928849 -289.4762)
			(xy 124.93302 -289.425859) (xy 124.945421 -289.37689) (xy 124.965712 -289.330631) (xy 124.993341 -289.288342)
			(xy 125.027553 -289.251178) (xy 125.067415 -289.220152) (xy 125.111841 -289.19611) (xy 125.159618 -289.179708)
			(xy 125.209443 -289.171394) (xy 125.2347 -289.170872) (xy 126.174754 -289.170872) (xy 126.200013 -289.171401)
			(xy 126.249842 -289.179709) (xy 126.297623 -289.196106) (xy 126.342054 -289.220145) (xy 126.381922 -289.25117)
			(xy 126.416139 -289.288334) (xy 126.443771 -289.330623) (xy 126.464066 -289.376885) (xy 126.476468 -289.425856)
			(xy 126.48064 -289.4762) (xy 126.476468 -289.526544) (xy 126.464066 -289.575515) (xy 126.443771 -289.621777)
			(xy 126.416139 -289.664066) (xy 126.381922 -289.70123) (xy 126.342054 -289.732255) (xy 126.297623 -289.756294)
			(xy 126.249842 -289.772691) (xy 126.200013 -289.780999) (xy 126.174754 -289.781488) (xy 125.2347 -289.781488)
			(xy 125.209443 -289.781006) (xy 125.159618 -289.772692) (xy 125.111841 -289.75629) (xy 125.067415 -289.732248)
			(xy 125.027553 -289.701222) (xy 124.993341 -289.664058) (xy 124.965712 -289.621769) (xy 124.945421 -289.57551)
			(xy 124.93302 -289.526541) (xy 124.928849 -289.4762) (xy 124.599954 -289.4762) (xy 124.599459 -289.500787)
			(xy 124.591564 -289.549364) (xy 124.57598 -289.596045) (xy 124.553109 -289.639622) (xy 124.523544 -289.678966)
			(xy 124.488051 -289.713058) (xy 124.447548 -289.741014) (xy 124.403086 -289.762112) (xy 124.355815 -289.775804)
			(xy 124.30696 -289.781736) (xy 124.257785 -289.779755) (xy 124.209566 -289.769911) (xy 124.16355 -289.752459)
			(xy 124.120929 -289.727852) (xy 124.082808 -289.696727) (xy 124.050173 -289.65989) (xy 124.02387 -289.618294)
			(xy 124.004579 -289.573018) (xy 123.992802 -289.525234) (xy 123.988842 -289.47618) (xy 123.660609 -289.47618)
			(xy 123.660611 -289.4762) (xy 123.656441 -289.52653) (xy 123.644044 -289.575487) (xy 123.62376 -289.621737)
			(xy 123.59614 -289.664018) (xy 123.561938 -289.701176) (xy 123.522087 -289.732199) (xy 123.477674 -289.75624)
			(xy 123.42991 -289.772644) (xy 123.380097 -289.780963) (xy 123.354846 -289.781488) (xy 122.414792 -289.781488)
			(xy 122.389535 -289.781006) (xy 122.339711 -289.77269) (xy 122.291936 -289.756288) (xy 122.247511 -289.732245)
			(xy 122.20765 -289.701219) (xy 122.173439 -289.664055) (xy 122.145811 -289.621767) (xy 122.12552 -289.575508)
			(xy 122.11312 -289.526541) (xy 122.108949 -289.4762) (xy 121.780046 -289.4762) (xy 121.779551 -289.500787)
			(xy 121.771656 -289.549364) (xy 121.756072 -289.596045) (xy 121.733201 -289.639622) (xy 121.703636 -289.678966)
			(xy 121.668143 -289.713058) (xy 121.62764 -289.741014) (xy 121.583178 -289.762112) (xy 121.535907 -289.775804)
			(xy 121.487052 -289.781736) (xy 121.437877 -289.779755) (xy 121.389658 -289.769911) (xy 121.343642 -289.752459)
			(xy 121.301021 -289.727852) (xy 121.2629 -289.696727) (xy 121.230265 -289.65989) (xy 121.203962 -289.618294)
			(xy 121.184671 -289.573018) (xy 121.172894 -289.525234) (xy 121.168934 -289.47618) (xy 120.840538 -289.47618)
			(xy 120.84054 -289.4762) (xy 120.836368 -289.526541) (xy 120.823968 -289.575509) (xy 120.803676 -289.621768)
			(xy 120.776047 -289.664056) (xy 120.741834 -289.70122) (xy 120.70197 -289.732245) (xy 120.657544 -289.756285)
			(xy 120.609766 -289.772685) (xy 120.559941 -289.780997) (xy 120.534684 -289.781488) (xy 119.59463 -289.781488)
			(xy 119.569369 -289.781038) (xy 119.519535 -289.772726) (xy 119.47175 -289.756326) (xy 119.427315 -289.732283)
			(xy 119.387445 -289.701254) (xy 119.353225 -289.664085) (xy 119.325591 -289.621791) (xy 119.305295 -289.575525)
			(xy 119.292892 -289.526549) (xy 119.28872 -289.4762) (xy 118.960138 -289.4762) (xy 118.959643 -289.500787)
			(xy 118.951748 -289.549364) (xy 118.936164 -289.596045) (xy 118.913293 -289.639622) (xy 118.883728 -289.678966)
			(xy 118.848235 -289.713058) (xy 118.807732 -289.741014) (xy 118.76327 -289.762112) (xy 118.715999 -289.775804)
			(xy 118.667144 -289.781736) (xy 118.617969 -289.779755) (xy 118.56975 -289.769911) (xy 118.523734 -289.752459)
			(xy 118.481113 -289.727852) (xy 118.442992 -289.696727) (xy 118.410357 -289.65989) (xy 118.384054 -289.618294)
			(xy 118.364763 -289.573018) (xy 118.352986 -289.525234) (xy 118.349026 -289.47618) (xy 118.020638 -289.47618)
			(xy 118.02064 -289.4762) (xy 118.016468 -289.526542) (xy 118.004067 -289.575511) (xy 117.983775 -289.62177)
			(xy 117.956145 -289.664059) (xy 117.92193 -289.701222) (xy 117.882066 -289.732247) (xy 117.837638 -289.756287)
			(xy 117.78986 -289.772686) (xy 117.740033 -289.780997) (xy 117.714776 -289.781488) (xy 116.774722 -289.781488)
			(xy 116.749461 -289.781037) (xy 116.699629 -289.772725) (xy 116.651844 -289.756323) (xy 116.607411 -289.73228)
			(xy 116.567542 -289.701251) (xy 116.533323 -289.664083) (xy 116.50569 -289.621789) (xy 116.485395 -289.575523)
			(xy 116.472992 -289.526548) (xy 116.46882 -289.4762) (xy 116.139976 -289.4762) (xy 116.139481 -289.500787)
			(xy 116.131586 -289.549364) (xy 116.116002 -289.596045) (xy 116.093131 -289.639622) (xy 116.063566 -289.678966)
			(xy 116.028073 -289.713058) (xy 115.98757 -289.741014) (xy 115.943108 -289.762112) (xy 115.895837 -289.775804)
			(xy 115.846982 -289.781736) (xy 115.797807 -289.779755) (xy 115.749588 -289.769911) (xy 115.703572 -289.752459)
			(xy 115.660951 -289.727852) (xy 115.62283 -289.696727) (xy 115.590195 -289.65989) (xy 115.563892 -289.618294)
			(xy 115.544601 -289.573018) (xy 115.532824 -289.525234) (xy 115.528864 -289.47618) (xy 108.626402 -289.47618)
			(xy 108.625907 -289.500787) (xy 108.618012 -289.549364) (xy 108.602428 -289.596045) (xy 108.579557 -289.639622)
			(xy 108.549992 -289.678966) (xy 108.514499 -289.713058) (xy 108.473996 -289.741014) (xy 108.429534 -289.762112)
			(xy 108.382263 -289.775804) (xy 108.333408 -289.781736) (xy 108.284233 -289.779755) (xy 108.236014 -289.769911)
			(xy 108.189998 -289.752459) (xy 108.147377 -289.727852) (xy 108.109256 -289.696727) (xy 108.076621 -289.65989)
			(xy 108.050318 -289.618294) (xy 108.031027 -289.573018) (xy 108.01925 -289.525234) (xy 108.01529 -289.47618)
			(xy 107.686809 -289.47618) (xy 107.686811 -289.4762) (xy 107.682641 -289.526531) (xy 107.670244 -289.575489)
			(xy 107.649959 -289.621739) (xy 107.622338 -289.66402) (xy 107.588136 -289.701178) (xy 107.548284 -289.732201)
			(xy 107.50387 -289.756242) (xy 107.456105 -289.772645) (xy 107.406292 -289.780963) (xy 107.38104 -289.781488)
			(xy 106.440986 -289.781488) (xy 106.41573 -289.781005) (xy 106.365907 -289.772689) (xy 106.318132 -289.756286)
			(xy 106.273708 -289.732243) (xy 106.233847 -289.701217) (xy 106.199637 -289.664053) (xy 106.17201 -289.621765)
			(xy 106.15172 -289.575507) (xy 106.13932 -289.52654) (xy 106.135149 -289.4762) (xy 105.80624 -289.4762)
			(xy 105.805745 -289.500787) (xy 105.79785 -289.549364) (xy 105.782266 -289.596045) (xy 105.759395 -289.639622)
			(xy 105.72983 -289.678966) (xy 105.694337 -289.713058) (xy 105.653834 -289.741014) (xy 105.609372 -289.762112)
			(xy 105.562101 -289.775804) (xy 105.513246 -289.781736) (xy 105.464071 -289.779755) (xy 105.415852 -289.769911)
			(xy 105.369836 -289.752459) (xy 105.327215 -289.727852) (xy 105.289094 -289.696727) (xy 105.256459 -289.65989)
			(xy 105.230156 -289.618294) (xy 105.210865 -289.573018) (xy 105.199088 -289.525234) (xy 105.195128 -289.47618)
			(xy 104.866909 -289.47618) (xy 104.866911 -289.4762) (xy 104.862741 -289.526532) (xy 104.850344 -289.57549)
			(xy 104.830058 -289.621741) (xy 104.802436 -289.664022) (xy 104.768233 -289.701181) (xy 104.72838 -289.732204)
			(xy 104.683965 -289.756244) (xy 104.636198 -289.772647) (xy 104.586384 -289.780964) (xy 104.561132 -289.781488)
			(xy 103.621078 -289.781488) (xy 103.595822 -289.781005) (xy 103.546 -289.772687) (xy 103.498226 -289.756284)
			(xy 103.453804 -289.732241) (xy 103.413944 -289.701214) (xy 103.379735 -289.66405) (xy 103.352109 -289.621763)
			(xy 103.331819 -289.575505) (xy 103.31942 -289.526539) (xy 103.315249 -289.4762) (xy 102.986332 -289.4762)
			(xy 102.985837 -289.500787) (xy 102.977942 -289.549364) (xy 102.962358 -289.596045) (xy 102.939487 -289.639622)
			(xy 102.909922 -289.678966) (xy 102.874429 -289.713058) (xy 102.833926 -289.741014) (xy 102.789464 -289.762112)
			(xy 102.742193 -289.775804) (xy 102.693338 -289.781736) (xy 102.644163 -289.779755) (xy 102.595944 -289.769911)
			(xy 102.549928 -289.752459) (xy 102.507307 -289.727852) (xy 102.469186 -289.696727) (xy 102.436551 -289.65989)
			(xy 102.410248 -289.618294) (xy 102.390957 -289.573018) (xy 102.37918 -289.525234) (xy 102.37522 -289.47618)
			(xy 102.047009 -289.47618) (xy 102.047011 -289.4762) (xy 102.042841 -289.526532) (xy 102.030443 -289.575492)
			(xy 102.010156 -289.621743) (xy 101.982534 -289.664025) (xy 101.948329 -289.701184) (xy 101.908475 -289.732206)
			(xy 101.864059 -289.756246) (xy 101.816292 -289.772648) (xy 101.766476 -289.780965) (xy 101.741224 -289.781488)
			(xy 100.80117 -289.781488) (xy 100.775915 -289.781004) (xy 100.726093 -289.772686) (xy 100.678321 -289.756281)
			(xy 100.633899 -289.732238) (xy 100.594041 -289.701211) (xy 100.559833 -289.664048) (xy 100.532208 -289.621761)
			(xy 100.511919 -289.575504) (xy 100.49952 -289.526538) (xy 100.495349 -289.4762) (xy 100.166424 -289.4762)
			(xy 100.165929 -289.500787) (xy 100.158034 -289.549364) (xy 100.14245 -289.596045) (xy 100.119579 -289.639622)
			(xy 100.090014 -289.678966) (xy 100.054521 -289.713058) (xy 100.014018 -289.741014) (xy 99.969556 -289.762112)
			(xy 99.922285 -289.775804) (xy 99.87343 -289.781736) (xy 99.824255 -289.779755) (xy 99.776036 -289.769911)
			(xy 99.73002 -289.752459) (xy 99.687399 -289.727852) (xy 99.649278 -289.696727) (xy 99.616643 -289.65989)
			(xy 99.59034 -289.618294) (xy 99.571049 -289.573018) (xy 99.559272 -289.525234) (xy 99.555312 -289.47618)
			(xy 99.226938 -289.47618) (xy 99.22694 -289.4762) (xy 99.222768 -289.526544) (xy 99.210366 -289.575514)
			(xy 99.190073 -289.621774) (xy 99.162441 -289.664063) (xy 99.128225 -289.701227) (xy 99.088358 -289.732252)
			(xy 99.043929 -289.756291) (xy 98.996148 -289.772689) (xy 98.94632 -289.780998) (xy 98.921062 -289.781488)
			(xy 97.981008 -289.781488) (xy 97.955748 -289.781036) (xy 97.905917 -289.772722) (xy 97.858135 -289.756319)
			(xy 97.813704 -289.732275) (xy 97.773836 -289.701246) (xy 97.73962 -289.664078) (xy 97.711988 -289.621785)
			(xy 97.691694 -289.575521) (xy 97.679292 -289.526547) (xy 97.67512 -289.4762) (xy 97.34688 -289.4762)
			(xy 97.342707 -289.526551) (xy 97.330303 -289.575528) (xy 97.310007 -289.621796) (xy 97.28237 -289.664091)
			(xy 97.248149 -289.70126) (xy 97.208276 -289.732288) (xy 97.163839 -289.75633) (xy 97.116051 -289.77273)
			(xy 97.066216 -289.781039) (xy 97.040954 -289.781488) (xy 97.01717 -289.781039) (xy 96.970176 -289.773677)
			(xy 96.92489 -289.759122) (xy 96.882407 -289.737726) (xy 96.843752 -289.710006) (xy 96.809858 -289.676631)
			(xy 96.795336 -289.65779) (xy 96.793304 -289.654742) (xy 96.78162 -289.643058) (xy 96.773631 -289.637783)
			(xy 96.755089 -289.633083) (xy 96.745552 -289.633914) (xy 96.712024 -289.638232) (xy 96.65716 -289.64509)
			(xy 96.650329 -289.646231) (xy 96.637588 -289.651646) (xy 96.632014 -289.655758) (xy 96.62668 -289.659822)
			(xy 96.618806 -289.67049) (xy 96.616266 -289.677094) (xy 96.610799 -289.690832) (xy 96.598599 -289.71777)
			(xy 96.591882 -289.730942) (xy 96.579182 -289.753802) (xy 96.543876 -289.814508) (xy 96.541507 -289.819405)
			(xy 96.538697 -289.829911) (xy 96.538288 -289.835336) (xy 96.538288 -289.910266) (xy 96.538542 -289.915854)
			(xy 96.539773 -289.92406) (xy 96.546769 -289.939095) (xy 96.552258 -289.945318) (xy 96.572832 -289.967162)
			(xy 96.582484 -289.97529) (xy 96.586561 -289.977702) (xy 96.595378 -289.981159) (xy 96.60001 -289.982148)
			(xy 96.604074 -289.982656) (xy 96.628701 -289.98582) (xy 96.676542 -289.999097) (xy 96.721605 -290.01994)
			(xy 96.762701 -290.047799) (xy 96.798749 -290.08194) (xy 96.828798 -290.121464) (xy 96.852056 -290.165329)
			(xy 96.86791 -290.212379) (xy 96.875943 -290.261374) (xy 96.875943 -290.286186) (xy 99.085158 -290.286186)
			(xy 99.089118 -290.237132) (xy 99.100895 -290.189348) (xy 99.120186 -290.144072) (xy 99.146489 -290.102476)
			(xy 99.179124 -290.065639) (xy 99.217245 -290.034514) (xy 99.259866 -290.009907) (xy 99.305882 -289.992455)
			(xy 99.354101 -289.982611) (xy 99.403276 -289.98063) (xy 99.452131 -289.986562) (xy 99.499402 -290.000254)
			(xy 99.543864 -290.021352) (xy 99.584367 -290.049308) (xy 99.61986 -290.0834) (xy 99.649425 -290.122744)
			(xy 99.672296 -290.166321) (xy 99.68788 -290.213002) (xy 99.695775 -290.261579) (xy 99.69627 -290.286186)
			(xy 101.90532 -290.286186) (xy 101.90928 -290.237132) (xy 101.921057 -290.189348) (xy 101.940348 -290.144072)
			(xy 101.966651 -290.102476) (xy 101.999286 -290.065639) (xy 102.037407 -290.034514) (xy 102.080028 -290.009907)
			(xy 102.126044 -289.992455) (xy 102.174263 -289.982611) (xy 102.223438 -289.98063) (xy 102.272293 -289.986562)
			(xy 102.319564 -290.000254) (xy 102.364026 -290.021352) (xy 102.404529 -290.049308) (xy 102.440022 -290.0834)
			(xy 102.469587 -290.122744) (xy 102.492458 -290.166321) (xy 102.508042 -290.213002) (xy 102.515937 -290.261579)
			(xy 102.516432 -290.286186) (xy 104.725228 -290.286186) (xy 104.729188 -290.237132) (xy 104.740965 -290.189348)
			(xy 104.760256 -290.144072) (xy 104.786559 -290.102476) (xy 104.819194 -290.065639) (xy 104.857315 -290.034514)
			(xy 104.899936 -290.009907) (xy 104.945952 -289.992455) (xy 104.994171 -289.982611) (xy 105.043346 -289.98063)
			(xy 105.092201 -289.986562) (xy 105.139472 -290.000254) (xy 105.183934 -290.021352) (xy 105.224437 -290.049308)
			(xy 105.25993 -290.0834) (xy 105.289495 -290.122744) (xy 105.312366 -290.166321) (xy 105.32795 -290.213002)
			(xy 105.335845 -290.261579) (xy 105.33634 -290.286186) (xy 107.545136 -290.286186) (xy 107.549096 -290.237132)
			(xy 107.560873 -290.189348) (xy 107.580164 -290.144072) (xy 107.606467 -290.102476) (xy 107.639102 -290.065639)
			(xy 107.677223 -290.034514) (xy 107.719844 -290.009907) (xy 107.76586 -289.992455) (xy 107.814079 -289.982611)
			(xy 107.863254 -289.98063) (xy 107.912109 -289.986562) (xy 107.95938 -290.000254) (xy 108.003842 -290.021352)
			(xy 108.044345 -290.049308) (xy 108.079838 -290.0834) (xy 108.109403 -290.122744) (xy 108.132274 -290.166321)
			(xy 108.147858 -290.213002) (xy 108.155753 -290.261579) (xy 108.156248 -290.286186) (xy 108.156248 -290.2862)
			(xy 108.4849 -290.2862) (xy 108.489075 -290.235818) (xy 108.501485 -290.186811) (xy 108.521793 -290.140514)
			(xy 108.549443 -290.098192) (xy 108.583682 -290.060997) (xy 108.623576 -290.029946) (xy 108.668037 -290.005884)
			(xy 108.715852 -289.989468) (xy 108.765717 -289.981146) (xy 108.790994 -289.980624) (xy 109.731048 -289.980624)
			(xy 109.756321 -289.981178) (xy 109.806175 -289.989504) (xy 109.85398 -290.005922) (xy 109.898431 -290.029984)
			(xy 109.938315 -290.061033) (xy 109.972546 -290.098223) (xy 110.000189 -290.140539) (xy 110.020491 -290.186828)
			(xy 110.032898 -290.235827) (xy 110.037071 -290.286186) (xy 110.365298 -290.286186) (xy 110.369258 -290.237132)
			(xy 110.381035 -290.189348) (xy 110.400326 -290.144072) (xy 110.426629 -290.102476) (xy 110.459264 -290.065639)
			(xy 110.497385 -290.034514) (xy 110.540006 -290.009907) (xy 110.586022 -289.992455) (xy 110.634241 -289.982611)
			(xy 110.683416 -289.98063) (xy 110.732271 -289.986562) (xy 110.779542 -290.000254) (xy 110.824004 -290.021352)
			(xy 110.864507 -290.049308) (xy 110.9 -290.0834) (xy 110.929565 -290.122744) (xy 110.952436 -290.166321)
			(xy 110.96802 -290.213002) (xy 110.975915 -290.261579) (xy 110.97641 -290.286186) (xy 113.178856 -290.286186)
			(xy 113.182816 -290.237132) (xy 113.194593 -290.189348) (xy 113.213884 -290.144072) (xy 113.240187 -290.102476)
			(xy 113.272822 -290.065639) (xy 113.310943 -290.034514) (xy 113.353564 -290.009907) (xy 113.39958 -289.992455)
			(xy 113.447799 -289.982611) (xy 113.496974 -289.98063) (xy 113.545829 -289.986562) (xy 113.5931 -290.000254)
			(xy 113.637562 -290.021352) (xy 113.678065 -290.049308) (xy 113.713558 -290.0834) (xy 113.743123 -290.122744)
			(xy 113.765994 -290.166321) (xy 113.781578 -290.213002) (xy 113.789473 -290.261579) (xy 113.789968 -290.286186)
			(xy 113.789968 -290.2862) (xy 114.118571 -290.2862) (xy 114.122747 -290.235811) (xy 114.135159 -290.186797)
			(xy 114.15547 -290.140495) (xy 114.183125 -290.098167) (xy 114.21737 -290.060969) (xy 114.257271 -290.029915)
			(xy 114.301739 -290.005852) (xy 114.349561 -289.989436) (xy 114.399433 -289.981116) (xy 114.424714 -289.980624)
			(xy 115.364768 -289.980624) (xy 115.390047 -289.981142) (xy 115.439917 -289.989459) (xy 115.487738 -290.005872)
			(xy 115.532204 -290.029932) (xy 115.572104 -290.060983) (xy 115.606348 -290.098179) (xy 115.634003 -290.140503)
			(xy 115.654313 -290.186803) (xy 115.666725 -290.235814) (xy 115.6709 -290.286186) (xy 115.999018 -290.286186)
			(xy 116.002978 -290.237132) (xy 116.014755 -290.189348) (xy 116.034046 -290.144072) (xy 116.060349 -290.102476)
			(xy 116.092984 -290.065639) (xy 116.131105 -290.034514) (xy 116.173726 -290.009907) (xy 116.219742 -289.992455)
			(xy 116.267961 -289.982611) (xy 116.317136 -289.98063) (xy 116.365991 -289.986562) (xy 116.413262 -290.000254)
			(xy 116.457724 -290.021352) (xy 116.498227 -290.049308) (xy 116.53372 -290.0834) (xy 116.563285 -290.122744)
			(xy 116.586156 -290.166321) (xy 116.60174 -290.213002) (xy 116.609635 -290.261579) (xy 116.61013 -290.286186)
			(xy 118.818926 -290.286186) (xy 118.822886 -290.237132) (xy 118.834663 -290.189348) (xy 118.853954 -290.144072)
			(xy 118.880257 -290.102476) (xy 118.912892 -290.065639) (xy 118.951013 -290.034514) (xy 118.993634 -290.009907)
			(xy 119.03965 -289.992455) (xy 119.087869 -289.982611) (xy 119.137044 -289.98063) (xy 119.185899 -289.986562)
			(xy 119.23317 -290.000254) (xy 119.277632 -290.021352) (xy 119.318135 -290.049308) (xy 119.353628 -290.0834)
			(xy 119.383193 -290.122744) (xy 119.406064 -290.166321) (xy 119.421648 -290.213002) (xy 119.429543 -290.261579)
			(xy 119.430038 -290.286186) (xy 121.638834 -290.286186) (xy 121.642794 -290.237132) (xy 121.654571 -290.189348)
			(xy 121.673862 -290.144072) (xy 121.700165 -290.102476) (xy 121.7328 -290.065639) (xy 121.770921 -290.034514)
			(xy 121.813542 -290.009907) (xy 121.859558 -289.992455) (xy 121.907777 -289.982611) (xy 121.956952 -289.98063)
			(xy 122.005807 -289.986562) (xy 122.053078 -290.000254) (xy 122.09754 -290.021352) (xy 122.138043 -290.049308)
			(xy 122.173536 -290.0834) (xy 122.203101 -290.122744) (xy 122.225972 -290.166321) (xy 122.241556 -290.213002)
			(xy 122.249451 -290.261579) (xy 122.249946 -290.286186) (xy 124.458996 -290.286186) (xy 124.462956 -290.237132)
			(xy 124.474733 -290.189348) (xy 124.494024 -290.144072) (xy 124.520327 -290.102476) (xy 124.552962 -290.065639)
			(xy 124.591083 -290.034514) (xy 124.633704 -290.009907) (xy 124.67972 -289.992455) (xy 124.727939 -289.982611)
			(xy 124.777114 -289.98063) (xy 124.825969 -289.986562) (xy 124.87324 -290.000254) (xy 124.917702 -290.021352)
			(xy 124.958205 -290.049308) (xy 124.993698 -290.0834) (xy 125.023263 -290.122744) (xy 125.046134 -290.166321)
			(xy 125.061718 -290.213002) (xy 125.069613 -290.261579) (xy 125.070108 -290.286186) (xy 125.069613 -290.310793)
			(xy 125.061718 -290.35937) (xy 125.046134 -290.406051) (xy 125.023263 -290.449628) (xy 124.993698 -290.488972)
			(xy 124.958205 -290.523064) (xy 124.917702 -290.55102) (xy 124.87324 -290.572118) (xy 124.825969 -290.58581)
			(xy 124.777114 -290.591742) (xy 124.727939 -290.589761) (xy 124.67972 -290.579917) (xy 124.633704 -290.562465)
			(xy 124.591083 -290.537858) (xy 124.552962 -290.506733) (xy 124.520327 -290.469896) (xy 124.494024 -290.4283)
			(xy 124.474733 -290.383024) (xy 124.462956 -290.33524) (xy 124.458996 -290.286186) (xy 122.249946 -290.286186)
			(xy 122.249451 -290.310793) (xy 122.241556 -290.35937) (xy 122.225972 -290.406051) (xy 122.203101 -290.449628)
			(xy 122.173536 -290.488972) (xy 122.138043 -290.523064) (xy 122.09754 -290.55102) (xy 122.053078 -290.572118)
			(xy 122.005807 -290.58581) (xy 121.956952 -290.591742) (xy 121.907777 -290.589761) (xy 121.859558 -290.579917)
			(xy 121.813542 -290.562465) (xy 121.770921 -290.537858) (xy 121.7328 -290.506733) (xy 121.700165 -290.469896)
			(xy 121.673862 -290.4283) (xy 121.654571 -290.383024) (xy 121.642794 -290.33524) (xy 121.638834 -290.286186)
			(xy 119.430038 -290.286186) (xy 119.429543 -290.310793) (xy 119.421648 -290.35937) (xy 119.406064 -290.406051)
			(xy 119.383193 -290.449628) (xy 119.353628 -290.488972) (xy 119.318135 -290.523064) (xy 119.277632 -290.55102)
			(xy 119.23317 -290.572118) (xy 119.185899 -290.58581) (xy 119.137044 -290.591742) (xy 119.087869 -290.589761)
			(xy 119.03965 -290.579917) (xy 118.993634 -290.562465) (xy 118.951013 -290.537858) (xy 118.912892 -290.506733)
			(xy 118.880257 -290.469896) (xy 118.853954 -290.4283) (xy 118.834663 -290.383024) (xy 118.822886 -290.33524)
			(xy 118.818926 -290.286186) (xy 116.61013 -290.286186) (xy 116.609635 -290.310793) (xy 116.60174 -290.35937)
			(xy 116.586156 -290.406051) (xy 116.563285 -290.449628) (xy 116.53372 -290.488972) (xy 116.498227 -290.523064)
			(xy 116.457724 -290.55102) (xy 116.413262 -290.572118) (xy 116.365991 -290.58581) (xy 116.317136 -290.591742)
			(xy 116.267961 -290.589761) (xy 116.219742 -290.579917) (xy 116.173726 -290.562465) (xy 116.131105 -290.537858)
			(xy 116.092984 -290.506733) (xy 116.060349 -290.469896) (xy 116.034046 -290.4283) (xy 116.014755 -290.383024)
			(xy 116.002978 -290.33524) (xy 115.999018 -290.286186) (xy 115.6709 -290.286186) (xy 115.670901 -290.2862)
			(xy 115.666725 -290.336586) (xy 115.654313 -290.385597) (xy 115.634003 -290.431897) (xy 115.606348 -290.474221)
			(xy 115.572104 -290.511417) (xy 115.532204 -290.542468) (xy 115.487738 -290.566528) (xy 115.439917 -290.582941)
			(xy 115.390047 -290.591258) (xy 115.364768 -290.591748) (xy 114.424714 -290.591748) (xy 114.399433 -290.591284)
			(xy 114.349561 -290.582964) (xy 114.301739 -290.566548) (xy 114.257271 -290.542485) (xy 114.21737 -290.511431)
			(xy 114.183125 -290.474233) (xy 114.15547 -290.431905) (xy 114.135159 -290.385603) (xy 114.122747 -290.336589)
			(xy 114.118571 -290.2862) (xy 113.789968 -290.2862) (xy 113.789473 -290.310793) (xy 113.781578 -290.35937)
			(xy 113.765994 -290.406051) (xy 113.743123 -290.449628) (xy 113.713558 -290.488972) (xy 113.678065 -290.523064)
			(xy 113.637562 -290.55102) (xy 113.5931 -290.572118) (xy 113.545829 -290.58581) (xy 113.496974 -290.591742)
			(xy 113.447799 -290.589761) (xy 113.39958 -290.579917) (xy 113.353564 -290.562465) (xy 113.310943 -290.537858)
			(xy 113.272822 -290.506733) (xy 113.240187 -290.469896) (xy 113.213884 -290.4283) (xy 113.194593 -290.383024)
			(xy 113.182816 -290.33524) (xy 113.178856 -290.286186) (xy 110.97641 -290.286186) (xy 110.975915 -290.310793)
			(xy 110.96802 -290.35937) (xy 110.952436 -290.406051) (xy 110.929565 -290.449628) (xy 110.9 -290.488972)
			(xy 110.864507 -290.523064) (xy 110.824004 -290.55102) (xy 110.779542 -290.572118) (xy 110.732271 -290.58581)
			(xy 110.683416 -290.591742) (xy 110.634241 -290.589761) (xy 110.586022 -290.579917) (xy 110.540006 -290.562465)
			(xy 110.497385 -290.537858) (xy 110.459264 -290.506733) (xy 110.426629 -290.469896) (xy 110.400326 -290.4283)
			(xy 110.381035 -290.383024) (xy 110.369258 -290.33524) (xy 110.365298 -290.286186) (xy 110.037071 -290.286186)
			(xy 110.037072 -290.2862) (xy 110.032898 -290.336573) (xy 110.020491 -290.385572) (xy 110.000189 -290.431861)
			(xy 109.972546 -290.474177) (xy 109.938315 -290.511367) (xy 109.898431 -290.542416) (xy 109.85398 -290.566478)
			(xy 109.806175 -290.582896) (xy 109.756321 -290.591222) (xy 109.731048 -290.591748) (xy 108.790994 -290.591748)
			(xy 108.765717 -290.591254) (xy 108.715852 -290.582932) (xy 108.668037 -290.566516) (xy 108.623576 -290.542454)
			(xy 108.583682 -290.511403) (xy 108.549443 -290.474208) (xy 108.521793 -290.431886) (xy 108.501485 -290.385589)
			(xy 108.489075 -290.336582) (xy 108.4849 -290.2862) (xy 108.156248 -290.2862) (xy 108.155753 -290.310793)
			(xy 108.147858 -290.35937) (xy 108.132274 -290.406051) (xy 108.109403 -290.449628) (xy 108.079838 -290.488972)
			(xy 108.044345 -290.523064) (xy 108.003842 -290.55102) (xy 107.95938 -290.572118) (xy 107.912109 -290.58581)
			(xy 107.863254 -290.591742) (xy 107.814079 -290.589761) (xy 107.76586 -290.579917) (xy 107.719844 -290.562465)
			(xy 107.677223 -290.537858) (xy 107.639102 -290.506733) (xy 107.606467 -290.469896) (xy 107.580164 -290.4283)
			(xy 107.560873 -290.383024) (xy 107.549096 -290.33524) (xy 107.545136 -290.286186) (xy 105.33634 -290.286186)
			(xy 105.335845 -290.310793) (xy 105.32795 -290.35937) (xy 105.312366 -290.406051) (xy 105.289495 -290.449628)
			(xy 105.25993 -290.488972) (xy 105.224437 -290.523064) (xy 105.183934 -290.55102) (xy 105.139472 -290.572118)
			(xy 105.092201 -290.58581) (xy 105.043346 -290.591742) (xy 104.994171 -290.589761) (xy 104.945952 -290.579917)
			(xy 104.899936 -290.562465) (xy 104.857315 -290.537858) (xy 104.819194 -290.506733) (xy 104.786559 -290.469896)
			(xy 104.760256 -290.4283) (xy 104.740965 -290.383024) (xy 104.729188 -290.33524) (xy 104.725228 -290.286186)
			(xy 102.516432 -290.286186) (xy 102.515937 -290.310793) (xy 102.508042 -290.35937) (xy 102.492458 -290.406051)
			(xy 102.469587 -290.449628) (xy 102.440022 -290.488972) (xy 102.404529 -290.523064) (xy 102.364026 -290.55102)
			(xy 102.319564 -290.572118) (xy 102.272293 -290.58581) (xy 102.223438 -290.591742) (xy 102.174263 -290.589761)
			(xy 102.126044 -290.579917) (xy 102.080028 -290.562465) (xy 102.037407 -290.537858) (xy 101.999286 -290.506733)
			(xy 101.966651 -290.469896) (xy 101.940348 -290.4283) (xy 101.921057 -290.383024) (xy 101.90928 -290.33524)
			(xy 101.90532 -290.286186) (xy 99.69627 -290.286186) (xy 99.695775 -290.310793) (xy 99.68788 -290.35937)
			(xy 99.672296 -290.406051) (xy 99.649425 -290.449628) (xy 99.61986 -290.488972) (xy 99.584367 -290.523064)
			(xy 99.543864 -290.55102) (xy 99.499402 -290.572118) (xy 99.452131 -290.58581) (xy 99.403276 -290.591742)
			(xy 99.354101 -290.589761) (xy 99.305882 -290.579917) (xy 99.259866 -290.562465) (xy 99.217245 -290.537858)
			(xy 99.179124 -290.506733) (xy 99.146489 -290.469896) (xy 99.120186 -290.4283) (xy 99.100895 -290.383024)
			(xy 99.089118 -290.33524) (xy 99.085158 -290.286186) (xy 96.875943 -290.286186) (xy 96.875944 -290.311023)
			(xy 96.867911 -290.360018) (xy 96.852057 -290.407068) (xy 96.828799 -290.450933) (xy 96.798751 -290.490457)
			(xy 96.762703 -290.524599) (xy 96.721607 -290.552458) (xy 96.676545 -290.573301) (xy 96.628704 -290.586579)
			(xy 96.604074 -290.589716) (xy 96.60001 -290.590224) (xy 96.595374 -290.5912) (xy 96.586553 -290.594654)
			(xy 96.582484 -290.597082) (xy 96.572832 -290.60521) (xy 96.552258 -290.627054) (xy 96.546776 -290.633282)
			(xy 96.539772 -290.648313) (xy 96.538542 -290.656518) (xy 96.538288 -290.662106) (xy 96.538288 -290.735766)
			(xy 96.538655 -290.743801) (xy 96.543707 -290.759061) (xy 96.548194 -290.765738) (xy 96.56189 -290.784556)
			(xy 96.586436 -290.824105) (xy 96.597216 -290.844732) (xy 96.603817 -290.858034) (xy 96.61576 -290.885228)
			(xy 96.621092 -290.899088) (xy 96.623632 -290.905438) (xy 96.6343 -290.91382) (xy 96.639822 -290.917859)
			(xy 96.652438 -290.92314) (xy 96.659192 -290.924234) (xy 96.74733 -290.935664) (xy 96.756063 -290.936437)
			(xy 96.773188 -290.932733) (xy 96.788078 -290.9235) (xy 96.793812 -290.916868) (xy 96.808276 -290.897699)
			(xy 96.842217 -290.863731) (xy 96.881059 -290.835498) (xy 96.923843 -290.813697) (xy 96.969514 -290.798865)
			(xy 97.016944 -290.791368) (xy 97.040954 -290.790884) (xy 97.065491 -290.791378) (xy 97.113933 -290.799236)
			(xy 97.160493 -290.814742) (xy 97.203974 -290.837495) (xy 97.243256 -290.866911) (xy 97.277326 -290.902231)
			(xy 97.305308 -290.942546) (xy 97.326482 -290.986818) (xy 97.340301 -291.033907) (xy 97.34641 -291.0826)
			(xy 97.345922 -291.0962) (xy 97.675132 -291.0962) (xy 97.679304 -291.045855) (xy 97.691705 -290.996883)
			(xy 97.711998 -290.950621) (xy 97.739629 -290.908329) (xy 97.773844 -290.871163) (xy 97.81371 -290.840135)
			(xy 97.85814 -290.816092) (xy 97.90592 -290.79969) (xy 97.955749 -290.791376) (xy 97.981008 -290.790884)
			(xy 98.921062 -290.790884) (xy 98.946321 -290.79139) (xy 98.996151 -290.799699) (xy 99.043934 -290.816098)
			(xy 99.088365 -290.840138) (xy 99.128233 -290.871164) (xy 99.16245 -290.908329) (xy 99.190083 -290.95062)
			(xy 99.210377 -290.996882) (xy 99.22278 -291.045854) (xy 99.226951 -291.096192) (xy 99.555312 -291.096192)
			(xy 99.559272 -291.047138) (xy 99.571049 -290.999354) (xy 99.59034 -290.954078) (xy 99.616643 -290.912482)
			(xy 99.649278 -290.875645) (xy 99.687399 -290.84452) (xy 99.73002 -290.819913) (xy 99.776036 -290.802461)
			(xy 99.824255 -290.792617) (xy 99.87343 -290.790636) (xy 99.922285 -290.796568) (xy 99.969556 -290.81026)
			(xy 100.014018 -290.831358) (xy 100.054521 -290.859314) (xy 100.090014 -290.893406) (xy 100.119579 -290.93275)
			(xy 100.14245 -290.976327) (xy 100.158034 -291.023008) (xy 100.165929 -291.071585) (xy 100.166424 -291.096192)
			(xy 100.166424 -291.0962) (xy 100.495361 -291.0962) (xy 100.499532 -291.045864) (xy 100.51193 -290.9969)
			(xy 100.532218 -290.950645) (xy 100.559842 -290.90836) (xy 100.594049 -290.871198) (xy 100.633906 -290.840172)
			(xy 100.678326 -290.81613) (xy 100.726096 -290.799726) (xy 100.775916 -290.791408) (xy 100.80117 -290.790884)
			(xy 101.741224 -290.790884) (xy 101.766477 -290.791423) (xy 101.816295 -290.79974) (xy 101.864064 -290.816143)
			(xy 101.908482 -290.840184) (xy 101.948338 -290.871207) (xy 101.982544 -290.908368) (xy 102.010167 -290.950651)
			(xy 102.030454 -290.996904) (xy 102.042852 -291.045866) (xy 102.047022 -291.096192) (xy 102.37522 -291.096192)
			(xy 102.37918 -291.047138) (xy 102.390957 -290.999354) (xy 102.410248 -290.954078) (xy 102.436551 -290.912482)
			(xy 102.469186 -290.875645) (xy 102.507307 -290.84452) (xy 102.549928 -290.819913) (xy 102.595944 -290.802461)
			(xy 102.644163 -290.792617) (xy 102.693338 -290.790636) (xy 102.742193 -290.796568) (xy 102.789464 -290.81026)
			(xy 102.833926 -290.831358) (xy 102.874429 -290.859314) (xy 102.909922 -290.893406) (xy 102.939487 -290.93275)
			(xy 102.962358 -290.976327) (xy 102.977942 -291.023008) (xy 102.985837 -291.071585) (xy 102.986332 -291.096192)
			(xy 102.986332 -291.0962) (xy 103.315261 -291.0962) (xy 103.319432 -291.045863) (xy 103.331831 -290.996899)
			(xy 103.352119 -290.950643) (xy 103.379744 -290.908357) (xy 103.413952 -290.871195) (xy 103.45381 -290.840169)
			(xy 103.498231 -290.816127) (xy 103.546003 -290.799724) (xy 103.595823 -290.791407) (xy 103.621078 -290.790884)
			(xy 104.561132 -290.790884) (xy 104.586385 -290.791424) (xy 104.636201 -290.799742) (xy 104.683969 -290.816145)
			(xy 104.728386 -290.840186) (xy 104.768241 -290.87121) (xy 104.802446 -290.90837) (xy 104.830068 -290.950653)
			(xy 104.850355 -290.996906) (xy 104.862753 -291.045867) (xy 104.866922 -291.096192) (xy 105.195128 -291.096192)
			(xy 105.199088 -291.047138) (xy 105.210865 -290.999354) (xy 105.230156 -290.954078) (xy 105.256459 -290.912482)
			(xy 105.289094 -290.875645) (xy 105.327215 -290.84452) (xy 105.369836 -290.819913) (xy 105.415852 -290.802461)
			(xy 105.464071 -290.792617) (xy 105.513246 -290.790636) (xy 105.562101 -290.796568) (xy 105.609372 -290.81026)
			(xy 105.653834 -290.831358) (xy 105.694337 -290.859314) (xy 105.72983 -290.893406) (xy 105.759395 -290.93275)
			(xy 105.782266 -290.976327) (xy 105.79785 -291.023008) (xy 105.805745 -291.071585) (xy 105.80624 -291.096192)
			(xy 105.80624 -291.0962) (xy 106.135161 -291.0962) (xy 106.139332 -291.045862) (xy 106.151731 -290.996897)
			(xy 106.172021 -290.950641) (xy 106.199646 -290.908354) (xy 106.233855 -290.871192) (xy 106.273715 -290.840167)
			(xy 106.318136 -290.816125) (xy 106.36591 -290.799722) (xy 106.415731 -290.791407) (xy 106.440986 -290.790884)
			(xy 107.38104 -290.790884) (xy 107.406292 -290.791425) (xy 107.456108 -290.799743) (xy 107.503875 -290.816147)
			(xy 107.548291 -290.840189) (xy 107.588144 -290.871213) (xy 107.622348 -290.908373) (xy 107.649969 -290.950655)
			(xy 107.670255 -290.996907) (xy 107.682653 -291.045867) (xy 107.686822 -291.096192) (xy 108.01529 -291.096192)
			(xy 108.01925 -291.047138) (xy 108.031027 -290.999354) (xy 108.050318 -290.954078) (xy 108.076621 -290.912482)
			(xy 108.109256 -290.875645) (xy 108.147377 -290.84452) (xy 108.189998 -290.819913) (xy 108.236014 -290.802461)
			(xy 108.284233 -290.792617) (xy 108.333408 -290.790636) (xy 108.382263 -290.796568) (xy 108.429534 -290.81026)
			(xy 108.473996 -290.831358) (xy 108.514499 -290.859314) (xy 108.549992 -290.893406) (xy 108.579557 -290.93275)
			(xy 108.602428 -290.976327) (xy 108.618012 -291.023008) (xy 108.625907 -291.071585) (xy 108.626402 -291.096192)
			(xy 115.528864 -291.096192) (xy 115.532824 -291.047138) (xy 115.544601 -290.999354) (xy 115.563892 -290.954078)
			(xy 115.590195 -290.912482) (xy 115.62283 -290.875645) (xy 115.660951 -290.84452) (xy 115.703572 -290.819913)
			(xy 115.749588 -290.802461) (xy 115.797807 -290.792617) (xy 115.846982 -290.790636) (xy 115.895837 -290.796568)
			(xy 115.943108 -290.81026) (xy 115.98757 -290.831358) (xy 116.028073 -290.859314) (xy 116.063566 -290.893406)
			(xy 116.093131 -290.93275) (xy 116.116002 -290.976327) (xy 116.131586 -291.023008) (xy 116.139481 -291.071585)
			(xy 116.139976 -291.096192) (xy 116.139976 -291.0962) (xy 116.468832 -291.0962) (xy 116.473004 -291.045853)
			(xy 116.485406 -290.99688) (xy 116.5057 -290.950617) (xy 116.533333 -290.908325) (xy 116.56755 -290.871158)
			(xy 116.607418 -290.84013) (xy 116.651849 -290.816088) (xy 116.699632 -290.799687) (xy 116.749462 -290.791375)
			(xy 116.774722 -290.790884) (xy 117.714776 -290.790884) (xy 117.740034 -290.791391) (xy 117.789863 -290.799702)
			(xy 117.837643 -290.816102) (xy 117.882072 -290.840143) (xy 117.921939 -290.871169) (xy 117.956154 -290.908334)
			(xy 117.983785 -290.950624) (xy 118.004078 -290.996885) (xy 118.01648 -291.045856) (xy 118.020651 -291.096192)
			(xy 118.349026 -291.096192) (xy 118.352986 -291.047138) (xy 118.364763 -290.999354) (xy 118.384054 -290.954078)
			(xy 118.410357 -290.912482) (xy 118.442992 -290.875645) (xy 118.481113 -290.84452) (xy 118.523734 -290.819913)
			(xy 118.56975 -290.802461) (xy 118.617969 -290.792617) (xy 118.667144 -290.790636) (xy 118.715999 -290.796568)
			(xy 118.76327 -290.81026) (xy 118.807732 -290.831358) (xy 118.848235 -290.859314) (xy 118.883728 -290.893406)
			(xy 118.913293 -290.93275) (xy 118.936164 -290.976327) (xy 118.951748 -291.023008) (xy 118.959643 -291.071585)
			(xy 118.960138 -291.096192) (xy 118.960138 -291.0962) (xy 119.288732 -291.0962) (xy 119.292904 -291.045853)
			(xy 119.305307 -290.996879) (xy 119.325602 -290.950615) (xy 119.353235 -290.908322) (xy 119.387453 -290.871155)
			(xy 119.427322 -290.840127) (xy 119.471755 -290.816085) (xy 119.519538 -290.799685) (xy 119.56937 -290.791374)
			(xy 119.59463 -290.790884) (xy 120.534684 -290.790884) (xy 120.559942 -290.791391) (xy 120.609769 -290.799704)
			(xy 120.657549 -290.816104) (xy 120.701977 -290.840145) (xy 120.741842 -290.871172) (xy 120.776056 -290.908336)
			(xy 120.803686 -290.950626) (xy 120.823979 -290.996887) (xy 120.83638 -291.045857) (xy 120.840551 -291.096192)
			(xy 121.168934 -291.096192) (xy 121.172894 -291.047138) (xy 121.184671 -290.999354) (xy 121.203962 -290.954078)
			(xy 121.230265 -290.912482) (xy 121.2629 -290.875645) (xy 121.301021 -290.84452) (xy 121.343642 -290.819913)
			(xy 121.389658 -290.802461) (xy 121.437877 -290.792617) (xy 121.487052 -290.790636) (xy 121.535907 -290.796568)
			(xy 121.583178 -290.81026) (xy 121.62764 -290.831358) (xy 121.668143 -290.859314) (xy 121.703636 -290.893406)
			(xy 121.733201 -290.93275) (xy 121.756072 -290.976327) (xy 121.771656 -291.023008) (xy 121.779551 -291.071585)
			(xy 121.780046 -291.096192) (xy 121.780046 -291.0962) (xy 122.108961 -291.0962) (xy 122.113132 -291.045861)
			(xy 122.125532 -290.996896) (xy 122.145821 -290.950639) (xy 122.173448 -290.908352) (xy 122.207658 -290.87119)
			(xy 122.247518 -290.840165) (xy 122.29194 -290.816123) (xy 122.339714 -290.799721) (xy 122.389536 -290.791406)
			(xy 122.414792 -290.790884) (xy 123.354846 -290.790884) (xy 123.380098 -290.791425) (xy 123.429913 -290.799745)
			(xy 123.477679 -290.816149) (xy 123.522094 -290.840191) (xy 123.561946 -290.871215) (xy 123.596149 -290.908375)
			(xy 123.62377 -290.950657) (xy 123.644056 -290.996909) (xy 123.656453 -291.045868) (xy 123.660622 -291.096192)
			(xy 123.988842 -291.096192) (xy 123.992802 -291.047138) (xy 124.004579 -290.999354) (xy 124.02387 -290.954078)
			(xy 124.050173 -290.912482) (xy 124.082808 -290.875645) (xy 124.120929 -290.84452) (xy 124.16355 -290.819913)
			(xy 124.209566 -290.802461) (xy 124.257785 -290.792617) (xy 124.30696 -290.790636) (xy 124.355815 -290.796568)
			(xy 124.403086 -290.81026) (xy 124.447548 -290.831358) (xy 124.488051 -290.859314) (xy 124.523544 -290.893406)
			(xy 124.553109 -290.93275) (xy 124.57598 -290.976327) (xy 124.591564 -291.023008) (xy 124.599459 -291.071585)
			(xy 124.599954 -291.096192) (xy 124.599954 -291.0962) (xy 124.928861 -291.0962) (xy 124.933032 -291.045861)
			(xy 124.945432 -290.996894) (xy 124.965723 -290.950637) (xy 124.99335 -290.90835) (xy 125.027561 -290.871187)
			(xy 125.067422 -290.840162) (xy 125.111846 -290.816121) (xy 125.159621 -290.79972) (xy 125.209444 -290.791406)
			(xy 125.2347 -290.790884) (xy 126.174754 -290.790884) (xy 126.200014 -290.791389) (xy 126.249845 -290.799697)
			(xy 126.297628 -290.816095) (xy 126.342061 -290.840135) (xy 126.38193 -290.871161) (xy 126.416148 -290.908327)
			(xy 126.443782 -290.950618) (xy 126.464077 -290.996881) (xy 126.47648 -291.045854) (xy 126.480652 -291.0962)
			(xy 126.47648 -291.146546) (xy 126.464077 -291.195519) (xy 126.443782 -291.241782) (xy 126.416148 -291.284074)
			(xy 126.38193 -291.321239) (xy 126.342061 -291.352265) (xy 126.297628 -291.376305) (xy 126.249845 -291.392703)
			(xy 126.200014 -291.401011) (xy 126.174754 -291.4015) (xy 125.2347 -291.4015) (xy 125.209444 -291.400994)
			(xy 125.159621 -291.39268) (xy 125.111846 -291.376279) (xy 125.067422 -291.352238) (xy 125.027561 -291.321213)
			(xy 124.99335 -291.28405) (xy 124.965723 -291.241763) (xy 124.945432 -291.195506) (xy 124.933032 -291.146539)
			(xy 124.928861 -291.0962) (xy 124.599954 -291.0962) (xy 124.599459 -291.120799) (xy 124.591564 -291.169376)
			(xy 124.57598 -291.216057) (xy 124.553109 -291.259634) (xy 124.523544 -291.298978) (xy 124.488051 -291.33307)
			(xy 124.447548 -291.361026) (xy 124.403086 -291.382124) (xy 124.355815 -291.395816) (xy 124.30696 -291.401748)
			(xy 124.257785 -291.399767) (xy 124.209566 -291.389923) (xy 124.16355 -291.372471) (xy 124.120929 -291.347864)
			(xy 124.082808 -291.316739) (xy 124.050173 -291.279902) (xy 124.02387 -291.238306) (xy 124.004579 -291.19303)
			(xy 123.992802 -291.145246) (xy 123.988842 -291.096192) (xy 123.660622 -291.096192) (xy 123.660623 -291.0962)
			(xy 123.656453 -291.146532) (xy 123.644056 -291.195491) (xy 123.62377 -291.241743) (xy 123.596149 -291.284025)
			(xy 123.561946 -291.321185) (xy 123.522094 -291.352209) (xy 123.477679 -291.376251) (xy 123.429913 -291.392655)
			(xy 123.380098 -291.400975) (xy 123.354846 -291.4015) (xy 122.414792 -291.4015) (xy 122.389536 -291.400994)
			(xy 122.339714 -291.392679) (xy 122.29194 -291.376277) (xy 122.247518 -291.352235) (xy 122.207658 -291.32121)
			(xy 122.173448 -291.284048) (xy 122.145821 -291.241761) (xy 122.125532 -291.195504) (xy 122.113132 -291.146539)
			(xy 122.108961 -291.0962) (xy 121.780046 -291.0962) (xy 121.779551 -291.120799) (xy 121.771656 -291.169376)
			(xy 121.756072 -291.216057) (xy 121.733201 -291.259634) (xy 121.703636 -291.298978) (xy 121.668143 -291.33307)
			(xy 121.62764 -291.361026) (xy 121.583178 -291.382124) (xy 121.535907 -291.395816) (xy 121.487052 -291.401748)
			(xy 121.437877 -291.399767) (xy 121.389658 -291.389923) (xy 121.343642 -291.372471) (xy 121.301021 -291.347864)
			(xy 121.2629 -291.316739) (xy 121.230265 -291.279902) (xy 121.203962 -291.238306) (xy 121.184671 -291.19303)
			(xy 121.172894 -291.145246) (xy 121.168934 -291.096192) (xy 120.840551 -291.096192) (xy 120.840552 -291.0962)
			(xy 120.83638 -291.146543) (xy 120.823979 -291.195513) (xy 120.803686 -291.241774) (xy 120.776056 -291.284064)
			(xy 120.741842 -291.321228) (xy 120.701977 -291.352255) (xy 120.657549 -291.376296) (xy 120.609769 -291.392696)
			(xy 120.559942 -291.401009) (xy 120.534684 -291.4015) (xy 119.59463 -291.4015) (xy 119.56937 -291.401026)
			(xy 119.519538 -291.392715) (xy 119.471755 -291.376315) (xy 119.427322 -291.352273) (xy 119.387453 -291.321245)
			(xy 119.353235 -291.284078) (xy 119.325602 -291.241785) (xy 119.305307 -291.195521) (xy 119.292904 -291.146547)
			(xy 119.288732 -291.0962) (xy 118.960138 -291.0962) (xy 118.959643 -291.120799) (xy 118.951748 -291.169376)
			(xy 118.936164 -291.216057) (xy 118.913293 -291.259634) (xy 118.883728 -291.298978) (xy 118.848235 -291.33307)
			(xy 118.807732 -291.361026) (xy 118.76327 -291.382124) (xy 118.715999 -291.395816) (xy 118.667144 -291.401748)
			(xy 118.617969 -291.399767) (xy 118.56975 -291.389923) (xy 118.523734 -291.372471) (xy 118.481113 -291.347864)
			(xy 118.442992 -291.316739) (xy 118.410357 -291.279902) (xy 118.384054 -291.238306) (xy 118.364763 -291.19303)
			(xy 118.352986 -291.145246) (xy 118.349026 -291.096192) (xy 118.020651 -291.096192) (xy 118.020652 -291.0962)
			(xy 118.01648 -291.146544) (xy 118.004078 -291.195515) (xy 117.983785 -291.241776) (xy 117.956154 -291.284066)
			(xy 117.921939 -291.321231) (xy 117.882072 -291.352257) (xy 117.837643 -291.376298) (xy 117.789863 -291.392698)
			(xy 117.740034 -291.401009) (xy 117.714776 -291.4015) (xy 116.774722 -291.4015) (xy 116.749462 -291.401025)
			(xy 116.699632 -291.392713) (xy 116.651849 -291.376312) (xy 116.607418 -291.35227) (xy 116.56755 -291.321242)
			(xy 116.533333 -291.284075) (xy 116.5057 -291.241783) (xy 116.485406 -291.19552) (xy 116.473004 -291.146547)
			(xy 116.468832 -291.0962) (xy 116.139976 -291.0962) (xy 116.139481 -291.120799) (xy 116.131586 -291.169376)
			(xy 116.116002 -291.216057) (xy 116.093131 -291.259634) (xy 116.063566 -291.298978) (xy 116.028073 -291.33307)
			(xy 115.98757 -291.361026) (xy 115.943108 -291.382124) (xy 115.895837 -291.395816) (xy 115.846982 -291.401748)
			(xy 115.797807 -291.399767) (xy 115.749588 -291.389923) (xy 115.703572 -291.372471) (xy 115.660951 -291.347864)
			(xy 115.62283 -291.316739) (xy 115.590195 -291.279902) (xy 115.563892 -291.238306) (xy 115.544601 -291.19303)
			(xy 115.532824 -291.145246) (xy 115.528864 -291.096192) (xy 108.626402 -291.096192) (xy 108.625907 -291.120799)
			(xy 108.618012 -291.169376) (xy 108.602428 -291.216057) (xy 108.579557 -291.259634) (xy 108.549992 -291.298978)
			(xy 108.514499 -291.33307) (xy 108.473996 -291.361026) (xy 108.429534 -291.382124) (xy 108.382263 -291.395816)
			(xy 108.333408 -291.401748) (xy 108.284233 -291.399767) (xy 108.236014 -291.389923) (xy 108.189998 -291.372471)
			(xy 108.147377 -291.347864) (xy 108.109256 -291.316739) (xy 108.076621 -291.279902) (xy 108.050318 -291.238306)
			(xy 108.031027 -291.19303) (xy 108.01925 -291.145246) (xy 108.01529 -291.096192) (xy 107.686822 -291.096192)
			(xy 107.686823 -291.0962) (xy 107.682653 -291.146533) (xy 107.670255 -291.195493) (xy 107.649969 -291.241745)
			(xy 107.622348 -291.284027) (xy 107.588144 -291.321187) (xy 107.548291 -291.352211) (xy 107.503875 -291.376253)
			(xy 107.456108 -291.392657) (xy 107.406292 -291.400975) (xy 107.38104 -291.4015) (xy 106.440986 -291.4015)
			(xy 106.415731 -291.400993) (xy 106.36591 -291.392678) (xy 106.318136 -291.376275) (xy 106.273715 -291.352233)
			(xy 106.233855 -291.321208) (xy 106.199646 -291.284046) (xy 106.172021 -291.241759) (xy 106.151731 -291.195503)
			(xy 106.139332 -291.146538) (xy 106.135161 -291.0962) (xy 105.80624 -291.0962) (xy 105.805745 -291.120799)
			(xy 105.79785 -291.169376) (xy 105.782266 -291.216057) (xy 105.759395 -291.259634) (xy 105.72983 -291.298978)
			(xy 105.694337 -291.33307) (xy 105.653834 -291.361026) (xy 105.609372 -291.382124) (xy 105.562101 -291.395816)
			(xy 105.513246 -291.401748) (xy 105.464071 -291.399767) (xy 105.415852 -291.389923) (xy 105.369836 -291.372471)
			(xy 105.327215 -291.347864) (xy 105.289094 -291.316739) (xy 105.256459 -291.279902) (xy 105.230156 -291.238306)
			(xy 105.210865 -291.19303) (xy 105.199088 -291.145246) (xy 105.195128 -291.096192) (xy 104.866922 -291.096192)
			(xy 104.866923 -291.0962) (xy 104.862753 -291.146533) (xy 104.850355 -291.195494) (xy 104.830068 -291.241747)
			(xy 104.802446 -291.28403) (xy 104.768241 -291.32119) (xy 104.728386 -291.352214) (xy 104.683969 -291.376255)
			(xy 104.636201 -291.392658) (xy 104.586385 -291.400976) (xy 104.561132 -291.4015) (xy 103.621078 -291.4015)
			(xy 103.595823 -291.400993) (xy 103.546003 -291.392676) (xy 103.498231 -291.376273) (xy 103.45381 -291.352231)
			(xy 103.413952 -291.321205) (xy 103.379744 -291.284043) (xy 103.352119 -291.241757) (xy 103.331831 -291.195501)
			(xy 103.319432 -291.146537) (xy 103.315261 -291.0962) (xy 102.986332 -291.0962) (xy 102.985837 -291.120799)
			(xy 102.977942 -291.169376) (xy 102.962358 -291.216057) (xy 102.939487 -291.259634) (xy 102.909922 -291.298978)
			(xy 102.874429 -291.33307) (xy 102.833926 -291.361026) (xy 102.789464 -291.382124) (xy 102.742193 -291.395816)
			(xy 102.693338 -291.401748) (xy 102.644163 -291.399767) (xy 102.595944 -291.389923) (xy 102.549928 -291.372471)
			(xy 102.507307 -291.347864) (xy 102.469186 -291.316739) (xy 102.436551 -291.279902) (xy 102.410248 -291.238306)
			(xy 102.390957 -291.19303) (xy 102.37918 -291.145246) (xy 102.37522 -291.096192) (xy 102.047022 -291.096192)
			(xy 102.047023 -291.0962) (xy 102.042852 -291.146534) (xy 102.030454 -291.195496) (xy 102.010167 -291.241749)
			(xy 101.982544 -291.284032) (xy 101.948338 -291.321193) (xy 101.908482 -291.352216) (xy 101.864064 -291.376257)
			(xy 101.816295 -291.39266) (xy 101.766477 -291.400977) (xy 101.741224 -291.4015) (xy 100.80117 -291.4015)
			(xy 100.775916 -291.400992) (xy 100.726096 -291.392674) (xy 100.678326 -291.37627) (xy 100.633906 -291.352228)
			(xy 100.594049 -291.321202) (xy 100.559842 -291.28404) (xy 100.532218 -291.241755) (xy 100.51193 -291.1955)
			(xy 100.499532 -291.146536) (xy 100.495361 -291.0962) (xy 100.166424 -291.0962) (xy 100.165929 -291.120799)
			(xy 100.158034 -291.169376) (xy 100.14245 -291.216057) (xy 100.119579 -291.259634) (xy 100.090014 -291.298978)
			(xy 100.054521 -291.33307) (xy 100.014018 -291.361026) (xy 99.969556 -291.382124) (xy 99.922285 -291.395816)
			(xy 99.87343 -291.401748) (xy 99.824255 -291.399767) (xy 99.776036 -291.389923) (xy 99.73002 -291.372471)
			(xy 99.687399 -291.347864) (xy 99.649278 -291.316739) (xy 99.616643 -291.279902) (xy 99.59034 -291.238306)
			(xy 99.571049 -291.19303) (xy 99.559272 -291.145246) (xy 99.555312 -291.096192) (xy 99.226951 -291.096192)
			(xy 99.226952 -291.0962) (xy 99.22278 -291.146546) (xy 99.210377 -291.195518) (xy 99.190083 -291.24178)
			(xy 99.16245 -291.284071) (xy 99.128233 -291.321236) (xy 99.088365 -291.352262) (xy 99.043934 -291.376302)
			(xy 98.996151 -291.392701) (xy 98.946321 -291.40101) (xy 98.921062 -291.4015) (xy 97.981008 -291.4015)
			(xy 97.955749 -291.401024) (xy 97.90592 -291.39271) (xy 97.85814 -291.376308) (xy 97.81371 -291.352265)
			(xy 97.773844 -291.321237) (xy 97.739629 -291.284071) (xy 97.711998 -291.241779) (xy 97.691705 -291.195517)
			(xy 97.679304 -291.146545) (xy 97.675132 -291.0962) (xy 97.345922 -291.0962) (xy 97.344652 -291.131643)
			(xy 97.335071 -291.179773) (xy 97.317916 -291.225752) (xy 97.293626 -291.268394) (xy 97.262829 -291.306601)
			(xy 97.226317 -291.339391) (xy 97.18503 -291.365918) (xy 97.140031 -291.3855) (xy 97.116392 -291.392102)
			(xy 97.115884 -291.392102) (xy 97.110296 -291.393626) (xy 97.098866 -291.40023) (xy 96.834452 -291.664644)
			(xy 96.831404 -291.701474) (xy 96.842072 -291.71646) (xy 96.856123 -291.737388) (xy 96.878398 -291.782603)
			(xy 96.893558 -291.830674) (xy 96.90125 -291.880488) (xy 96.901762 -291.90569) (xy 96.901762 -291.906198)
			(xy 96.901295 -291.931641) (xy 96.893502 -291.981927) (xy 96.878099 -292.030427) (xy 96.85545 -292.075995)
			(xy 96.826089 -292.117556) (xy 96.79071 -292.154131) (xy 96.770698 -292.16985) (xy 96.761046 -292.177216)
			(xy 96.750632 -292.198298) (xy 96.750632 -292.231318) (xy 96.751059 -292.241386) (xy 96.758782 -292.259983)
			(xy 96.765618 -292.267386) (xy 96.820228 -292.321996) (xy 96.827628 -292.328838) (xy 96.846226 -292.336563)
			(xy 96.856296 -292.336982) (xy 97.539556 -292.336982) (xy 97.54971 -292.33653) (xy 97.568435 -292.328665)
			(xy 97.575878 -292.321742) (xy 97.59569 -292.302184) (xy 97.599381 -292.298615) (xy 97.605392 -292.290295)
			(xy 97.607628 -292.285674) (xy 97.620074 -292.25748) (xy 97.61965 -292.247463) (xy 97.611976 -292.228958)
			(xy 97.597804 -292.214798) (xy 97.579291 -292.207141) (xy 97.569274 -292.20668) (xy 97.561146 -292.207442)
			(xy 97.548913 -292.209325) (xy 97.524246 -292.211362) (xy 97.51187 -292.211506) (xy 97.511108 -292.211506)
			(xy 97.486287 -292.211021) (xy 97.437299 -292.202991) (xy 97.390256 -292.187141) (xy 97.346396 -292.16389)
			(xy 97.306876 -292.133849) (xy 97.272737 -292.09781) (xy 97.244878 -292.056723) (xy 97.224033 -292.01167)
			(xy 97.210752 -291.963838) (xy 97.205383 -291.914488) (xy 97.20807 -291.864919) (xy 97.21874 -291.816438)
			(xy 97.237114 -291.770321) (xy 97.262706 -291.727785) (xy 97.294843 -291.68995) (xy 97.332677 -291.657812)
			(xy 97.375212 -291.632218) (xy 97.421328 -291.613843) (xy 97.469809 -291.603171) (xy 97.519378 -291.600483)
			(xy 97.568728 -291.60585) (xy 97.616561 -291.61913) (xy 97.661614 -291.639973) (xy 97.702702 -291.667831)
			(xy 97.738742 -291.701969) (xy 97.768785 -291.741488) (xy 97.792037 -291.785347) (xy 97.807888 -291.83239)
			(xy 97.81592 -291.881377) (xy 97.816416 -291.906198) (xy 97.815763 -291.934897) (xy 97.805021 -291.991281)
			(xy 97.79508 -292.018212) (xy 97.79 -292.030658) (xy 97.794064 -292.057328) (xy 97.865184 -292.147752)
			(xy 97.890076 -292.157658) (xy 97.903538 -292.15588) (xy 97.922812 -292.153442) (xy 97.961581 -292.150898)
			(xy 97.981008 -292.1508) (xy 98.070162 -292.1508) (xy 98.082556 -292.150257) (xy 98.104533 -292.138808)
			(xy 98.112072 -292.128956) (xy 98.15957 -292.059868) (xy 98.16588 -292.049441) (xy 98.168955 -292.025299)
			(xy 98.165412 -292.01364) (xy 98.165412 -292.013386) (xy 98.156342 -291.987519) (xy 98.146501 -291.933601)
			(xy 98.145854 -291.906198) (xy 98.146376 -291.880943) (xy 98.154689 -291.831121) (xy 98.17109 -291.783347)
			(xy 98.195131 -291.738924) (xy 98.226155 -291.699064) (xy 98.263317 -291.664854) (xy 98.305603 -291.637228)
			(xy 98.351859 -291.616938) (xy 98.400824 -291.604538) (xy 98.451162 -291.600367) (xy 98.5015 -291.604538)
			(xy 98.550465 -291.616938) (xy 98.596721 -291.637228) (xy 98.639007 -291.664854) (xy 98.676169 -291.699064)
			(xy 98.707193 -291.738924) (xy 98.731234 -291.783347) (xy 98.747635 -291.831121) (xy 98.755948 -291.880943)
			(xy 98.75647 -291.906198) (xy 98.755822 -291.93354) (xy 98.745989 -291.987333) (xy 98.736912 -292.013132)
			(xy 98.736912 -292.01364) (xy 98.732594 -292.025324) (xy 98.735642 -292.049454) (xy 98.790252 -292.128956)
			(xy 98.797911 -292.13867) (xy 98.819812 -292.150087) (xy 98.832162 -292.1508) (xy 98.92157 -292.1508)
			(xy 98.9538 -292.151289) (xy 99.017837 -292.158681) (xy 99.080618 -292.173304) (xy 99.14133 -292.194969)
			(xy 99.199186 -292.223395) (xy 99.253435 -292.258214) (xy 99.303375 -292.298973) (xy 99.326192 -292.321742)
			(xy 99.333673 -292.328721) (xy 99.352544 -292.336576) (xy 99.362768 -292.336982) (xy 100.359718 -292.336982)
			(xy 100.369875 -292.336537) (xy 100.38861 -292.328682) (xy 100.39604 -292.321742) (xy 100.415852 -292.302184)
			(xy 100.419545 -292.298617) (xy 100.42556 -292.290299) (xy 100.42779 -292.285674) (xy 100.440236 -292.25748)
			(xy 100.439751 -292.247504) (xy 100.432137 -292.229061) (xy 100.418065 -292.214915) (xy 100.399664 -292.207202)
			(xy 100.38969 -292.20668) (xy 100.381308 -292.207442) (xy 100.368826 -292.209377) (xy 100.343647 -292.211411)
			(xy 100.331016 -292.211506) (xy 100.306195 -292.211021) (xy 100.257207 -292.202993) (xy 100.210163 -292.187144)
			(xy 100.166302 -292.163894) (xy 100.126781 -292.133854) (xy 100.092641 -292.097815) (xy 100.064781 -292.056729)
			(xy 100.043935 -292.011676) (xy 100.030653 -291.963844) (xy 100.025283 -291.914493) (xy 100.027969 -291.864924)
			(xy 100.038639 -291.816442) (xy 100.057012 -291.770326) (xy 100.082604 -291.727789) (xy 100.11474 -291.689953)
			(xy 100.152574 -291.657814) (xy 100.195109 -291.63222) (xy 100.241225 -291.613844) (xy 100.289706 -291.603172)
			(xy 100.339275 -291.600483) (xy 100.388626 -291.605849) (xy 100.436459 -291.619129) (xy 100.481513 -291.639972)
			(xy 100.522601 -291.66783) (xy 100.558642 -291.701968) (xy 100.588684 -291.741487) (xy 100.611937 -291.785346)
			(xy 100.627788 -291.832389) (xy 100.63582 -291.881377) (xy 100.636324 -291.906198) (xy 100.635671 -291.934897)
			(xy 100.62493 -291.991282) (xy 100.614988 -292.018212) (xy 100.609908 -292.030912) (xy 100.613972 -292.057582)
			(xy 100.67671 -292.137338) (xy 100.682459 -292.144029) (xy 100.697426 -292.153342) (xy 100.714669 -292.157007)
			(xy 100.723446 -292.156134) (xy 100.742653 -292.153641) (xy 100.781295 -292.150968) (xy 100.800662 -292.1508)
			(xy 100.89007 -292.1508) (xy 100.902463 -292.150256) (xy 100.924437 -292.138804) (xy 100.93198 -292.128956)
			(xy 100.979478 -292.059868) (xy 100.985788 -292.049441) (xy 100.988862 -292.025299) (xy 100.98532 -292.01364)
			(xy 100.98532 -292.013386) (xy 100.97625 -291.987519) (xy 100.966409 -291.933601) (xy 100.965762 -291.906198)
			(xy 100.966284 -291.880943) (xy 100.974597 -291.831121) (xy 100.990998 -291.783347) (xy 101.015039 -291.738924)
			(xy 101.046063 -291.699064) (xy 101.083225 -291.664854) (xy 101.125511 -291.637228) (xy 101.171767 -291.616938)
			(xy 101.220732 -291.604538) (xy 101.27107 -291.600367) (xy 101.321408 -291.604538) (xy 101.370373 -291.616938)
			(xy 101.416629 -291.637228) (xy 101.458915 -291.664854) (xy 101.496077 -291.699064) (xy 101.527101 -291.738924)
			(xy 101.551142 -291.783347) (xy 101.567543 -291.831121) (xy 101.575856 -291.880943) (xy 101.576378 -291.906198)
			(xy 101.57573 -291.93354) (xy 101.565897 -291.987333) (xy 101.55682 -292.013132) (xy 101.55682 -292.01364)
			(xy 101.552502 -292.025324) (xy 101.55555 -292.049454) (xy 101.61016 -292.128956) (xy 101.61782 -292.138669)
			(xy 101.639721 -292.150082) (xy 101.65207 -292.1508) (xy 101.741478 -292.1508) (xy 101.773708 -292.151289)
			(xy 101.837744 -292.158682) (xy 101.900525 -292.173306) (xy 101.961236 -292.194972) (xy 102.019091 -292.223398)
			(xy 102.07334 -292.258217) (xy 102.12328 -292.298977) (xy 102.1461 -292.321742) (xy 102.153581 -292.32872)
			(xy 102.172453 -292.336572) (xy 102.182676 -292.336982) (xy 103.179626 -292.336982) (xy 103.189783 -292.336536)
			(xy 103.208516 -292.328678) (xy 103.215948 -292.321742) (xy 103.23576 -292.302184) (xy 103.239452 -292.298617)
			(xy 103.245467 -292.290298) (xy 103.247698 -292.285674) (xy 103.260144 -292.25748) (xy 103.259653 -292.247472)
			(xy 103.251992 -292.228979) (xy 103.237841 -292.214822) (xy 103.219352 -292.207152) (xy 103.209344 -292.20668)
			(xy 103.201216 -292.207442) (xy 103.188983 -292.209323) (xy 103.164316 -292.211359) (xy 103.15194 -292.211506)
			(xy 103.151178 -292.211506) (xy 103.126358 -292.211018) (xy 103.077372 -292.202984) (xy 103.030331 -292.187131)
			(xy 102.986474 -292.163876) (xy 102.946958 -292.133832) (xy 102.912822 -292.097791) (xy 102.884966 -292.056703)
			(xy 102.864125 -292.011649) (xy 102.850848 -291.963817) (xy 102.845483 -291.914468) (xy 102.848172 -291.8649)
			(xy 102.858846 -291.81642) (xy 102.877221 -291.770306) (xy 102.902815 -291.727772) (xy 102.934953 -291.689939)
			(xy 102.972788 -291.657804) (xy 103.015324 -291.632213) (xy 103.061439 -291.61384) (xy 103.10992 -291.60317)
			(xy 103.159488 -291.600483) (xy 103.208837 -291.605851) (xy 103.256668 -291.619132) (xy 103.30172 -291.639976)
			(xy 103.342807 -291.667834) (xy 103.378846 -291.701972) (xy 103.408887 -291.741491) (xy 103.432139 -291.785349)
			(xy 103.447989 -291.832391) (xy 103.45602 -291.881378) (xy 103.456486 -291.906198) (xy 103.455833 -291.934897)
			(xy 103.44509 -291.991281) (xy 103.43515 -292.018212) (xy 103.43007 -292.030658) (xy 103.434134 -292.057328)
			(xy 103.505254 -292.147752) (xy 103.530146 -292.157658) (xy 103.543608 -292.15588) (xy 103.562882 -292.153444)
			(xy 103.601651 -292.150905) (xy 103.621078 -292.1508) (xy 103.709978 -292.1508) (xy 103.72237 -292.150254)
			(xy 103.744341 -292.138801) (xy 103.751888 -292.128956) (xy 103.799386 -292.059868) (xy 103.805695 -292.049441)
			(xy 103.808769 -292.025299) (xy 103.805228 -292.01364) (xy 103.805228 -292.013386) (xy 103.796158 -291.987519)
			(xy 103.786316 -291.933601) (xy 103.78567 -291.906198) (xy 103.786192 -291.880943) (xy 103.794505 -291.831121)
			(xy 103.810906 -291.783347) (xy 103.834947 -291.738924) (xy 103.865971 -291.699064) (xy 103.903133 -291.664854)
			(xy 103.945419 -291.637228) (xy 103.991675 -291.616938) (xy 104.04064 -291.604538) (xy 104.090978 -291.600367)
			(xy 104.141316 -291.604538) (xy 104.190281 -291.616938) (xy 104.236537 -291.637228) (xy 104.278823 -291.664854)
			(xy 104.315985 -291.699064) (xy 104.347009 -291.738924) (xy 104.37105 -291.783347) (xy 104.387451 -291.831121)
			(xy 104.395764 -291.880943) (xy 104.396286 -291.906198) (xy 104.395638 -291.93354) (xy 104.385806 -291.987333)
			(xy 104.376728 -292.013132) (xy 104.376728 -292.01364) (xy 104.37241 -292.025324) (xy 104.375458 -292.049454)
			(xy 104.430068 -292.128956) (xy 104.437728 -292.138668) (xy 104.459629 -292.150077) (xy 104.471978 -292.1508)
			(xy 104.56164 -292.1508) (xy 104.593871 -292.151287) (xy 104.657909 -292.158676) (xy 104.720692 -292.173297)
			(xy 104.781407 -292.194959) (xy 104.839265 -292.223383) (xy 104.893517 -292.2582) (xy 104.943459 -292.298958)
			(xy 104.966262 -292.321742) (xy 104.973741 -292.328726) (xy 104.992613 -292.336592) (xy 105.002838 -292.336982)
			(xy 105.999534 -292.336982) (xy 106.00969 -292.336534) (xy 106.028421 -292.328675) (xy 106.035856 -292.321742)
			(xy 106.055668 -292.302184) (xy 106.05936 -292.298616) (xy 106.065373 -292.290297) (xy 106.067606 -292.285674)
			(xy 106.080052 -292.25748) (xy 106.079628 -292.247465) (xy 106.071953 -292.228963) (xy 106.05778 -292.214809)
			(xy 106.039268 -292.207158) (xy 106.029252 -292.20668) (xy 106.021124 -292.207442) (xy 106.008891 -292.209324)
			(xy 105.984224 -292.21136) (xy 105.971848 -292.211506) (xy 105.971086 -292.211506) (xy 105.946266 -292.211019)
			(xy 105.897279 -292.202986) (xy 105.850237 -292.187133) (xy 105.80638 -292.16388) (xy 105.766863 -292.133837)
			(xy 105.732726 -292.097796) (xy 105.70487 -292.056708) (xy 105.684027 -292.011655) (xy 105.670749 -291.963823)
			(xy 105.665383 -291.914473) (xy 105.668072 -291.864905) (xy 105.678744 -291.816425) (xy 105.697119 -291.77031)
			(xy 105.722713 -291.727776) (xy 105.75485 -291.689942) (xy 105.792685 -291.657806) (xy 105.835221 -291.632214)
			(xy 105.881336 -291.613841) (xy 105.929817 -291.60317) (xy 105.979385 -291.600483) (xy 106.028735 -291.605851)
			(xy 106.076566 -291.619132) (xy 106.121619 -291.639975) (xy 106.162706 -291.667833) (xy 106.198745 -291.701971)
			(xy 106.228786 -291.74149) (xy 106.252038 -291.785348) (xy 106.267889 -291.832391) (xy 106.27592 -291.881378)
			(xy 106.276394 -291.906198) (xy 106.275741 -291.934897) (xy 106.264998 -291.991281) (xy 106.255058 -292.018212)
			(xy 106.249978 -292.030658) (xy 106.254042 -292.057328) (xy 106.325162 -292.147752) (xy 106.350054 -292.157658)
			(xy 106.363516 -292.15588) (xy 106.382789 -292.153441) (xy 106.421559 -292.150896) (xy 106.440986 -292.1508)
			(xy 106.53014 -292.1508) (xy 106.542537 -292.150262) (xy 106.564522 -292.138818) (xy 106.57205 -292.128956)
			(xy 106.619548 -292.059868) (xy 106.625851 -292.049439) (xy 106.628921 -292.0253) (xy 106.62539 -292.01364)
			(xy 106.62539 -292.013386) (xy 106.61632 -291.987519) (xy 106.60648 -291.933601) (xy 106.605832 -291.906198)
			(xy 106.606354 -291.880943) (xy 106.614667 -291.831121) (xy 106.631068 -291.783347) (xy 106.655109 -291.738924)
			(xy 106.686133 -291.699064) (xy 106.723295 -291.664854) (xy 106.765581 -291.637228) (xy 106.811837 -291.616938)
			(xy 106.860802 -291.604538) (xy 106.91114 -291.600367) (xy 106.961478 -291.604538) (xy 107.010443 -291.616938)
			(xy 107.056699 -291.637228) (xy 107.098985 -291.664854) (xy 107.136147 -291.699064) (xy 107.167171 -291.738924)
			(xy 107.191212 -291.783347) (xy 107.207613 -291.831121) (xy 107.215926 -291.880943) (xy 107.216448 -291.906198)
			(xy 108.48519 -291.906198) (xy 108.48915 -291.857144) (xy 108.500927 -291.80936) (xy 108.520218 -291.764084)
			(xy 108.546521 -291.722488) (xy 108.579156 -291.685651) (xy 108.617277 -291.654526) (xy 108.659898 -291.629919)
			(xy 108.705914 -291.612467) (xy 108.754133 -291.602623) (xy 108.803308 -291.600642) (xy 108.852163 -291.606574)
			(xy 108.899434 -291.620266) (xy 108.943896 -291.641364) (xy 108.984399 -291.66932) (xy 109.019892 -291.703412)
			(xy 109.049457 -291.742756) (xy 109.072328 -291.786333) (xy 109.087912 -291.833014) (xy 109.095807 -291.881591)
			(xy 109.096302 -291.906198) (xy 109.425244 -291.906198) (xy 109.429204 -291.857144) (xy 109.440981 -291.80936)
			(xy 109.460272 -291.764084) (xy 109.486575 -291.722488) (xy 109.51921 -291.685651) (xy 109.557331 -291.654526)
			(xy 109.599952 -291.629919) (xy 109.645968 -291.612467) (xy 109.694187 -291.602623) (xy 109.743362 -291.600642)
			(xy 109.792217 -291.606574) (xy 109.839488 -291.620266) (xy 109.88395 -291.641364) (xy 109.924453 -291.66932)
			(xy 109.959946 -291.703412) (xy 109.989511 -291.742756) (xy 110.012382 -291.786333) (xy 110.027966 -291.833014)
			(xy 110.035861 -291.881591) (xy 110.036356 -291.906198) (xy 110.365298 -291.906198) (xy 110.369258 -291.857144)
			(xy 110.381035 -291.80936) (xy 110.400326 -291.764084) (xy 110.426629 -291.722488) (xy 110.459264 -291.685651)
			(xy 110.497385 -291.654526) (xy 110.540006 -291.629919) (xy 110.586022 -291.612467) (xy 110.634241 -291.602623)
			(xy 110.683416 -291.600642) (xy 110.732271 -291.606574) (xy 110.779542 -291.620266) (xy 110.824004 -291.641364)
			(xy 110.864507 -291.66932) (xy 110.9 -291.703412) (xy 110.929565 -291.742756) (xy 110.952436 -291.786333)
			(xy 110.96802 -291.833014) (xy 110.975915 -291.881591) (xy 110.97641 -291.906198) (xy 113.178856 -291.906198)
			(xy 113.182816 -291.857144) (xy 113.194593 -291.80936) (xy 113.213884 -291.764084) (xy 113.240187 -291.722488)
			(xy 113.272822 -291.685651) (xy 113.310943 -291.654526) (xy 113.353564 -291.629919) (xy 113.39958 -291.612467)
			(xy 113.447799 -291.602623) (xy 113.496974 -291.600642) (xy 113.545829 -291.606574) (xy 113.5931 -291.620266)
			(xy 113.637562 -291.641364) (xy 113.678065 -291.66932) (xy 113.713558 -291.703412) (xy 113.743123 -291.742756)
			(xy 113.765994 -291.786333) (xy 113.781578 -291.833014) (xy 113.789473 -291.881591) (xy 113.789968 -291.906198)
			(xy 114.11891 -291.906198) (xy 114.12287 -291.857144) (xy 114.134647 -291.80936) (xy 114.153938 -291.764084)
			(xy 114.180241 -291.722488) (xy 114.212876 -291.685651) (xy 114.250997 -291.654526) (xy 114.293618 -291.629919)
			(xy 114.339634 -291.612467) (xy 114.387853 -291.602623) (xy 114.437028 -291.600642) (xy 114.485883 -291.606574)
			(xy 114.533154 -291.620266) (xy 114.577616 -291.641364) (xy 114.618119 -291.66932) (xy 114.653612 -291.703412)
			(xy 114.683177 -291.742756) (xy 114.706048 -291.786333) (xy 114.721632 -291.833014) (xy 114.729527 -291.881591)
			(xy 114.730022 -291.906198) (xy 115.058964 -291.906198) (xy 115.062924 -291.857144) (xy 115.074701 -291.80936)
			(xy 115.093992 -291.764084) (xy 115.120295 -291.722488) (xy 115.15293 -291.685651) (xy 115.191051 -291.654526)
			(xy 115.233672 -291.629919) (xy 115.279688 -291.612467) (xy 115.327907 -291.602623) (xy 115.377082 -291.600642)
			(xy 115.425937 -291.606574) (xy 115.473208 -291.620266) (xy 115.51767 -291.641364) (xy 115.558173 -291.66932)
			(xy 115.593666 -291.703412) (xy 115.623231 -291.742756) (xy 115.646102 -291.786333) (xy 115.661686 -291.833014)
			(xy 115.669581 -291.881591) (xy 115.670076 -291.906198) (xy 116.938818 -291.906198) (xy 116.942778 -291.857144)
			(xy 116.954555 -291.80936) (xy 116.973846 -291.764084) (xy 117.000149 -291.722488) (xy 117.032784 -291.685651)
			(xy 117.070905 -291.654526) (xy 117.113526 -291.629919) (xy 117.159542 -291.612467) (xy 117.207761 -291.602623)
			(xy 117.256936 -291.600642) (xy 117.305791 -291.606574) (xy 117.353062 -291.620266) (xy 117.397524 -291.641364)
			(xy 117.438027 -291.66932) (xy 117.47352 -291.703412) (xy 117.503085 -291.742756) (xy 117.525956 -291.786333)
			(xy 117.54154 -291.833014) (xy 117.549435 -291.881591) (xy 117.54993 -291.906198) (xy 117.878872 -291.906198)
			(xy 117.882832 -291.857144) (xy 117.894609 -291.80936) (xy 117.9139 -291.764084) (xy 117.940203 -291.722488)
			(xy 117.972838 -291.685651) (xy 118.010959 -291.654526) (xy 118.05358 -291.629919) (xy 118.099596 -291.612467)
			(xy 118.147815 -291.602623) (xy 118.19699 -291.600642) (xy 118.245845 -291.606574) (xy 118.293116 -291.620266)
			(xy 118.337578 -291.641364) (xy 118.378081 -291.66932) (xy 118.413574 -291.703412) (xy 118.443139 -291.742756)
			(xy 118.46601 -291.786333) (xy 118.481594 -291.833014) (xy 118.489489 -291.881591) (xy 118.489984 -291.906198)
			(xy 119.75898 -291.906198) (xy 119.76294 -291.857144) (xy 119.774717 -291.80936) (xy 119.794008 -291.764084)
			(xy 119.820311 -291.722488) (xy 119.852946 -291.685651) (xy 119.891067 -291.654526) (xy 119.933688 -291.629919)
			(xy 119.979704 -291.612467) (xy 120.027923 -291.602623) (xy 120.077098 -291.600642) (xy 120.125953 -291.606574)
			(xy 120.173224 -291.620266) (xy 120.217686 -291.641364) (xy 120.258189 -291.66932) (xy 120.293682 -291.703412)
			(xy 120.323247 -291.742756) (xy 120.346118 -291.786333) (xy 120.361702 -291.833014) (xy 120.369597 -291.881591)
			(xy 120.370092 -291.906198) (xy 120.699034 -291.906198) (xy 120.702994 -291.857144) (xy 120.714771 -291.80936)
			(xy 120.734062 -291.764084) (xy 120.760365 -291.722488) (xy 120.793 -291.685651) (xy 120.831121 -291.654526)
			(xy 120.873742 -291.629919) (xy 120.919758 -291.612467) (xy 120.967977 -291.602623) (xy 121.017152 -291.600642)
			(xy 121.066007 -291.606574) (xy 121.113278 -291.620266) (xy 121.15774 -291.641364) (xy 121.198243 -291.66932)
			(xy 121.233736 -291.703412) (xy 121.263301 -291.742756) (xy 121.286172 -291.786333) (xy 121.301756 -291.833014)
			(xy 121.309651 -291.881591) (xy 121.310146 -291.906198) (xy 122.578888 -291.906198) (xy 122.582848 -291.857144)
			(xy 122.594625 -291.80936) (xy 122.613916 -291.764084) (xy 122.640219 -291.722488) (xy 122.672854 -291.685651)
			(xy 122.710975 -291.654526) (xy 122.753596 -291.629919) (xy 122.799612 -291.612467) (xy 122.847831 -291.602623)
			(xy 122.897006 -291.600642) (xy 122.945861 -291.606574) (xy 122.993132 -291.620266) (xy 123.037594 -291.641364)
			(xy 123.078097 -291.66932) (xy 123.11359 -291.703412) (xy 123.143155 -291.742756) (xy 123.166026 -291.786333)
			(xy 123.18161 -291.833014) (xy 123.189505 -291.881591) (xy 123.19 -291.906198) (xy 123.518942 -291.906198)
			(xy 123.522902 -291.857144) (xy 123.534679 -291.80936) (xy 123.55397 -291.764084) (xy 123.580273 -291.722488)
			(xy 123.612908 -291.685651) (xy 123.651029 -291.654526) (xy 123.69365 -291.629919) (xy 123.739666 -291.612467)
			(xy 123.787885 -291.602623) (xy 123.83706 -291.600642) (xy 123.885915 -291.606574) (xy 123.933186 -291.620266)
			(xy 123.977648 -291.641364) (xy 124.018151 -291.66932) (xy 124.053644 -291.703412) (xy 124.083209 -291.742756)
			(xy 124.10608 -291.786333) (xy 124.121664 -291.833014) (xy 124.129559 -291.881591) (xy 124.130054 -291.906198)
			(xy 125.39905 -291.906198) (xy 125.40301 -291.857144) (xy 125.414787 -291.80936) (xy 125.434078 -291.764084)
			(xy 125.460381 -291.722488) (xy 125.493016 -291.685651) (xy 125.531137 -291.654526) (xy 125.573758 -291.629919)
			(xy 125.619774 -291.612467) (xy 125.667993 -291.602623) (xy 125.717168 -291.600642) (xy 125.766023 -291.606574)
			(xy 125.813294 -291.620266) (xy 125.857756 -291.641364) (xy 125.898259 -291.66932) (xy 125.933752 -291.703412)
			(xy 125.963317 -291.742756) (xy 125.986188 -291.786333) (xy 126.001772 -291.833014) (xy 126.009667 -291.881591)
			(xy 126.010162 -291.906198) (xy 126.33885 -291.906198) (xy 126.34281 -291.857144) (xy 126.354587 -291.80936)
			(xy 126.373878 -291.764084) (xy 126.400181 -291.722488) (xy 126.432816 -291.685651) (xy 126.470937 -291.654526)
			(xy 126.513558 -291.629919) (xy 126.559574 -291.612467) (xy 126.607793 -291.602623) (xy 126.656968 -291.600642)
			(xy 126.705823 -291.606574) (xy 126.753094 -291.620266) (xy 126.797556 -291.641364) (xy 126.838059 -291.66932)
			(xy 126.873552 -291.703412) (xy 126.903117 -291.742756) (xy 126.925988 -291.786333) (xy 126.941572 -291.833014)
			(xy 126.949467 -291.881591) (xy 126.949962 -291.906198) (xy 126.949467 -291.930805) (xy 126.941572 -291.979382)
			(xy 126.925988 -292.026063) (xy 126.903117 -292.06964) (xy 126.873552 -292.108984) (xy 126.838059 -292.143076)
			(xy 126.797556 -292.171032) (xy 126.753094 -292.19213) (xy 126.705823 -292.205822) (xy 126.656968 -292.211754)
			(xy 126.607793 -292.209773) (xy 126.559574 -292.199929) (xy 126.513558 -292.182477) (xy 126.470937 -292.15787)
			(xy 126.432816 -292.126745) (xy 126.400181 -292.089908) (xy 126.373878 -292.048312) (xy 126.354587 -292.003036)
			(xy 126.34281 -291.955252) (xy 126.33885 -291.906198) (xy 126.010162 -291.906198) (xy 126.009667 -291.930805)
			(xy 126.001772 -291.979382) (xy 125.986188 -292.026063) (xy 125.963317 -292.06964) (xy 125.933752 -292.108984)
			(xy 125.898259 -292.143076) (xy 125.857756 -292.171032) (xy 125.813294 -292.19213) (xy 125.766023 -292.205822)
			(xy 125.717168 -292.211754) (xy 125.667993 -292.209773) (xy 125.619774 -292.199929) (xy 125.573758 -292.182477)
			(xy 125.531137 -292.15787) (xy 125.493016 -292.126745) (xy 125.460381 -292.089908) (xy 125.434078 -292.048312)
			(xy 125.414787 -292.003036) (xy 125.40301 -291.955252) (xy 125.39905 -291.906198) (xy 124.130054 -291.906198)
			(xy 124.129559 -291.930805) (xy 124.121664 -291.979382) (xy 124.10608 -292.026063) (xy 124.083209 -292.06964)
			(xy 124.053644 -292.108984) (xy 124.018151 -292.143076) (xy 123.977648 -292.171032) (xy 123.933186 -292.19213)
			(xy 123.885915 -292.205822) (xy 123.83706 -292.211754) (xy 123.787885 -292.209773) (xy 123.739666 -292.199929)
			(xy 123.69365 -292.182477) (xy 123.651029 -292.15787) (xy 123.612908 -292.126745) (xy 123.580273 -292.089908)
			(xy 123.55397 -292.048312) (xy 123.534679 -292.003036) (xy 123.522902 -291.955252) (xy 123.518942 -291.906198)
			(xy 123.19 -291.906198) (xy 123.189505 -291.930805) (xy 123.18161 -291.979382) (xy 123.166026 -292.026063)
			(xy 123.143155 -292.06964) (xy 123.11359 -292.108984) (xy 123.078097 -292.143076) (xy 123.037594 -292.171032)
			(xy 122.993132 -292.19213) (xy 122.945861 -292.205822) (xy 122.897006 -292.211754) (xy 122.847831 -292.209773)
			(xy 122.799612 -292.199929) (xy 122.753596 -292.182477) (xy 122.710975 -292.15787) (xy 122.672854 -292.126745)
			(xy 122.640219 -292.089908) (xy 122.613916 -292.048312) (xy 122.594625 -292.003036) (xy 122.582848 -291.955252)
			(xy 122.578888 -291.906198) (xy 121.310146 -291.906198) (xy 121.309651 -291.930805) (xy 121.301756 -291.979382)
			(xy 121.286172 -292.026063) (xy 121.263301 -292.06964) (xy 121.233736 -292.108984) (xy 121.198243 -292.143076)
			(xy 121.15774 -292.171032) (xy 121.113278 -292.19213) (xy 121.066007 -292.205822) (xy 121.017152 -292.211754)
			(xy 120.967977 -292.209773) (xy 120.919758 -292.199929) (xy 120.873742 -292.182477) (xy 120.831121 -292.15787)
			(xy 120.793 -292.126745) (xy 120.760365 -292.089908) (xy 120.734062 -292.048312) (xy 120.714771 -292.003036)
			(xy 120.702994 -291.955252) (xy 120.699034 -291.906198) (xy 120.370092 -291.906198) (xy 120.369597 -291.930805)
			(xy 120.361702 -291.979382) (xy 120.346118 -292.026063) (xy 120.323247 -292.06964) (xy 120.293682 -292.108984)
			(xy 120.258189 -292.143076) (xy 120.217686 -292.171032) (xy 120.173224 -292.19213) (xy 120.125953 -292.205822)
			(xy 120.077098 -292.211754) (xy 120.027923 -292.209773) (xy 119.979704 -292.199929) (xy 119.933688 -292.182477)
			(xy 119.891067 -292.15787) (xy 119.852946 -292.126745) (xy 119.820311 -292.089908) (xy 119.794008 -292.048312)
			(xy 119.774717 -292.003036) (xy 119.76294 -291.955252) (xy 119.75898 -291.906198) (xy 118.489984 -291.906198)
			(xy 118.489489 -291.930805) (xy 118.481594 -291.979382) (xy 118.46601 -292.026063) (xy 118.443139 -292.06964)
			(xy 118.413574 -292.108984) (xy 118.378081 -292.143076) (xy 118.337578 -292.171032) (xy 118.293116 -292.19213)
			(xy 118.245845 -292.205822) (xy 118.19699 -292.211754) (xy 118.147815 -292.209773) (xy 118.099596 -292.199929)
			(xy 118.05358 -292.182477) (xy 118.010959 -292.15787) (xy 117.972838 -292.126745) (xy 117.940203 -292.089908)
			(xy 117.9139 -292.048312) (xy 117.894609 -292.003036) (xy 117.882832 -291.955252) (xy 117.878872 -291.906198)
			(xy 117.54993 -291.906198) (xy 117.549435 -291.930805) (xy 117.54154 -291.979382) (xy 117.525956 -292.026063)
			(xy 117.503085 -292.06964) (xy 117.47352 -292.108984) (xy 117.438027 -292.143076) (xy 117.397524 -292.171032)
			(xy 117.353062 -292.19213) (xy 117.305791 -292.205822) (xy 117.256936 -292.211754) (xy 117.207761 -292.209773)
			(xy 117.159542 -292.199929) (xy 117.113526 -292.182477) (xy 117.070905 -292.15787) (xy 117.032784 -292.126745)
			(xy 117.000149 -292.089908) (xy 116.973846 -292.048312) (xy 116.954555 -292.003036) (xy 116.942778 -291.955252)
			(xy 116.938818 -291.906198) (xy 115.670076 -291.906198) (xy 115.669581 -291.930805) (xy 115.661686 -291.979382)
			(xy 115.646102 -292.026063) (xy 115.623231 -292.06964) (xy 115.593666 -292.108984) (xy 115.558173 -292.143076)
			(xy 115.51767 -292.171032) (xy 115.473208 -292.19213) (xy 115.425937 -292.205822) (xy 115.377082 -292.211754)
			(xy 115.327907 -292.209773) (xy 115.279688 -292.199929) (xy 115.233672 -292.182477) (xy 115.191051 -292.15787)
			(xy 115.15293 -292.126745) (xy 115.120295 -292.089908) (xy 115.093992 -292.048312) (xy 115.074701 -292.003036)
			(xy 115.062924 -291.955252) (xy 115.058964 -291.906198) (xy 114.730022 -291.906198) (xy 114.729527 -291.930805)
			(xy 114.721632 -291.979382) (xy 114.706048 -292.026063) (xy 114.683177 -292.06964) (xy 114.653612 -292.108984)
			(xy 114.618119 -292.143076) (xy 114.577616 -292.171032) (xy 114.533154 -292.19213) (xy 114.485883 -292.205822)
			(xy 114.437028 -292.211754) (xy 114.387853 -292.209773) (xy 114.339634 -292.199929) (xy 114.293618 -292.182477)
			(xy 114.250997 -292.15787) (xy 114.212876 -292.126745) (xy 114.180241 -292.089908) (xy 114.153938 -292.048312)
			(xy 114.134647 -292.003036) (xy 114.12287 -291.955252) (xy 114.11891 -291.906198) (xy 113.789968 -291.906198)
			(xy 113.789473 -291.930805) (xy 113.781578 -291.979382) (xy 113.765994 -292.026063) (xy 113.743123 -292.06964)
			(xy 113.713558 -292.108984) (xy 113.678065 -292.143076) (xy 113.637562 -292.171032) (xy 113.5931 -292.19213)
			(xy 113.545829 -292.205822) (xy 113.496974 -292.211754) (xy 113.447799 -292.209773) (xy 113.39958 -292.199929)
			(xy 113.353564 -292.182477) (xy 113.310943 -292.15787) (xy 113.272822 -292.126745) (xy 113.240187 -292.089908)
			(xy 113.213884 -292.048312) (xy 113.194593 -292.003036) (xy 113.182816 -291.955252) (xy 113.178856 -291.906198)
			(xy 110.97641 -291.906198) (xy 110.975915 -291.930805) (xy 110.96802 -291.979382) (xy 110.952436 -292.026063)
			(xy 110.929565 -292.06964) (xy 110.9 -292.108984) (xy 110.864507 -292.143076) (xy 110.824004 -292.171032)
			(xy 110.779542 -292.19213) (xy 110.732271 -292.205822) (xy 110.683416 -292.211754) (xy 110.634241 -292.209773)
			(xy 110.586022 -292.199929) (xy 110.540006 -292.182477) (xy 110.497385 -292.15787) (xy 110.459264 -292.126745)
			(xy 110.426629 -292.089908) (xy 110.400326 -292.048312) (xy 110.381035 -292.003036) (xy 110.369258 -291.955252)
			(xy 110.365298 -291.906198) (xy 110.036356 -291.906198) (xy 110.035861 -291.930805) (xy 110.027966 -291.979382)
			(xy 110.012382 -292.026063) (xy 109.989511 -292.06964) (xy 109.959946 -292.108984) (xy 109.924453 -292.143076)
			(xy 109.88395 -292.171032) (xy 109.839488 -292.19213) (xy 109.792217 -292.205822) (xy 109.743362 -292.211754)
			(xy 109.694187 -292.209773) (xy 109.645968 -292.199929) (xy 109.599952 -292.182477) (xy 109.557331 -292.15787)
			(xy 109.51921 -292.126745) (xy 109.486575 -292.089908) (xy 109.460272 -292.048312) (xy 109.440981 -292.003036)
			(xy 109.429204 -291.955252) (xy 109.425244 -291.906198) (xy 109.096302 -291.906198) (xy 109.095807 -291.930805)
			(xy 109.087912 -291.979382) (xy 109.072328 -292.026063) (xy 109.049457 -292.06964) (xy 109.019892 -292.108984)
			(xy 108.984399 -292.143076) (xy 108.943896 -292.171032) (xy 108.899434 -292.19213) (xy 108.852163 -292.205822)
			(xy 108.803308 -292.211754) (xy 108.754133 -292.209773) (xy 108.705914 -292.199929) (xy 108.659898 -292.182477)
			(xy 108.617277 -292.15787) (xy 108.579156 -292.126745) (xy 108.546521 -292.089908) (xy 108.520218 -292.048312)
			(xy 108.500927 -292.003036) (xy 108.48915 -291.955252) (xy 108.48519 -291.906198) (xy 107.216448 -291.906198)
			(xy 107.2158 -291.93354) (xy 107.205966 -291.987333) (xy 107.19689 -292.013132) (xy 107.19689 -292.01364)
			(xy 107.192572 -292.025324) (xy 107.19562 -292.049454) (xy 107.25023 -292.128956) (xy 107.257888 -292.138674)
			(xy 107.279788 -292.1501) (xy 107.29214 -292.1508) (xy 107.38104 -292.1508) (xy 107.414768 -292.151291)
			(xy 107.481744 -292.159319) (xy 107.54729 -292.175257) (xy 107.610475 -292.198878) (xy 107.670402 -292.229846)
			(xy 107.72622 -292.267723) (xy 107.777137 -292.31197) (xy 107.822429 -292.361959) (xy 107.861454 -292.41698)
			(xy 107.893657 -292.476252) (xy 107.906566 -292.507416) (xy 107.910376 -292.517068) (xy 108.025692 -292.632384)
			(xy 108.032526 -292.639787) (xy 108.040231 -292.658385) (xy 108.040678 -292.668452) (xy 108.040678 -292.716204)
			(xy 109.895144 -292.716204) (xy 109.899104 -292.66715) (xy 109.910881 -292.619366) (xy 109.930172 -292.57409)
			(xy 109.956475 -292.532494) (xy 109.98911 -292.495657) (xy 110.027231 -292.464532) (xy 110.069852 -292.439925)
			(xy 110.115868 -292.422473) (xy 110.164087 -292.412629) (xy 110.213262 -292.410648) (xy 110.262117 -292.41658)
			(xy 110.309388 -292.430272) (xy 110.35385 -292.45137) (xy 110.394353 -292.479326) (xy 110.429846 -292.513418)
			(xy 110.459411 -292.552762) (xy 110.482282 -292.596339) (xy 110.497866 -292.64302) (xy 110.505761 -292.691597)
			(xy 110.506256 -292.716204) (xy 116.468918 -292.716204) (xy 116.472878 -292.66715) (xy 116.484655 -292.619366)
			(xy 116.503946 -292.57409) (xy 116.530249 -292.532494) (xy 116.562884 -292.495657) (xy 116.601005 -292.464532)
			(xy 116.643626 -292.439925) (xy 116.689642 -292.422473) (xy 116.737861 -292.412629) (xy 116.787036 -292.410648)
			(xy 116.835891 -292.41658) (xy 116.883162 -292.430272) (xy 116.927624 -292.45137) (xy 116.968127 -292.479326)
			(xy 117.00362 -292.513418) (xy 117.033185 -292.552762) (xy 117.056056 -292.596339) (xy 117.07164 -292.64302)
			(xy 117.079535 -292.691597) (xy 117.08003 -292.716204) (xy 117.408972 -292.716204) (xy 117.412932 -292.66715)
			(xy 117.424709 -292.619366) (xy 117.444 -292.57409) (xy 117.470303 -292.532494) (xy 117.502938 -292.495657)
			(xy 117.541059 -292.464532) (xy 117.58368 -292.439925) (xy 117.629696 -292.422473) (xy 117.677915 -292.412629)
			(xy 117.72709 -292.410648) (xy 117.775945 -292.41658) (xy 117.823216 -292.430272) (xy 117.867678 -292.45137)
			(xy 117.908181 -292.479326) (xy 117.943674 -292.513418) (xy 117.973239 -292.552762) (xy 117.99611 -292.596339)
			(xy 118.011694 -292.64302) (xy 118.019589 -292.691597) (xy 118.020084 -292.716204) (xy 119.288826 -292.716204)
			(xy 119.292786 -292.66715) (xy 119.304563 -292.619366) (xy 119.323854 -292.57409) (xy 119.350157 -292.532494)
			(xy 119.382792 -292.495657) (xy 119.420913 -292.464532) (xy 119.463534 -292.439925) (xy 119.50955 -292.422473)
			(xy 119.557769 -292.412629) (xy 119.606944 -292.410648) (xy 119.655799 -292.41658) (xy 119.70307 -292.430272)
			(xy 119.747532 -292.45137) (xy 119.788035 -292.479326) (xy 119.823528 -292.513418) (xy 119.853093 -292.552762)
			(xy 119.875964 -292.596339) (xy 119.891548 -292.64302) (xy 119.899443 -292.691597) (xy 119.899938 -292.716204)
			(xy 120.22888 -292.716204) (xy 120.23284 -292.66715) (xy 120.244617 -292.619366) (xy 120.263908 -292.57409)
			(xy 120.290211 -292.532494) (xy 120.322846 -292.495657) (xy 120.360967 -292.464532) (xy 120.403588 -292.439925)
			(xy 120.449604 -292.422473) (xy 120.497823 -292.412629) (xy 120.546998 -292.410648) (xy 120.595853 -292.41658)
			(xy 120.643124 -292.430272) (xy 120.687586 -292.45137) (xy 120.728089 -292.479326) (xy 120.763582 -292.513418)
			(xy 120.793147 -292.552762) (xy 120.816018 -292.596339) (xy 120.831602 -292.64302) (xy 120.839497 -292.691597)
			(xy 120.839992 -292.716204) (xy 122.108988 -292.716204) (xy 122.112948 -292.66715) (xy 122.124725 -292.619366)
			(xy 122.144016 -292.57409) (xy 122.170319 -292.532494) (xy 122.202954 -292.495657) (xy 122.241075 -292.464532)
			(xy 122.283696 -292.439925) (xy 122.329712 -292.422473) (xy 122.377931 -292.412629) (xy 122.427106 -292.410648)
			(xy 122.475961 -292.41658) (xy 122.523232 -292.430272) (xy 122.567694 -292.45137) (xy 122.608197 -292.479326)
			(xy 122.64369 -292.513418) (xy 122.673255 -292.552762) (xy 122.696126 -292.596339) (xy 122.71171 -292.64302)
			(xy 122.719605 -292.691597) (xy 122.7201 -292.716204) (xy 123.049042 -292.716204) (xy 123.053002 -292.66715)
			(xy 123.064779 -292.619366) (xy 123.08407 -292.57409) (xy 123.110373 -292.532494) (xy 123.143008 -292.495657)
			(xy 123.181129 -292.464532) (xy 123.22375 -292.439925) (xy 123.269766 -292.422473) (xy 123.317985 -292.412629)
			(xy 123.36716 -292.410648) (xy 123.416015 -292.41658) (xy 123.463286 -292.430272) (xy 123.507748 -292.45137)
			(xy 123.548251 -292.479326) (xy 123.583744 -292.513418) (xy 123.613309 -292.552762) (xy 123.63618 -292.596339)
			(xy 123.651764 -292.64302) (xy 123.659659 -292.691597) (xy 123.660154 -292.716204) (xy 124.928896 -292.716204)
			(xy 124.932856 -292.66715) (xy 124.944633 -292.619366) (xy 124.963924 -292.57409) (xy 124.990227 -292.532494)
			(xy 125.022862 -292.495657) (xy 125.060983 -292.464532) (xy 125.103604 -292.439925) (xy 125.14962 -292.422473)
			(xy 125.197839 -292.412629) (xy 125.247014 -292.410648) (xy 125.295869 -292.41658) (xy 125.34314 -292.430272)
			(xy 125.387602 -292.45137) (xy 125.428105 -292.479326) (xy 125.463598 -292.513418) (xy 125.493163 -292.552762)
			(xy 125.516034 -292.596339) (xy 125.531618 -292.64302) (xy 125.539513 -292.691597) (xy 125.540008 -292.716204)
			(xy 125.86895 -292.716204) (xy 125.87291 -292.66715) (xy 125.884687 -292.619366) (xy 125.903978 -292.57409)
			(xy 125.930281 -292.532494) (xy 125.962916 -292.495657) (xy 126.001037 -292.464532) (xy 126.043658 -292.439925)
			(xy 126.089674 -292.422473) (xy 126.137893 -292.412629) (xy 126.187068 -292.410648) (xy 126.235923 -292.41658)
			(xy 126.283194 -292.430272) (xy 126.327656 -292.45137) (xy 126.368159 -292.479326) (xy 126.403652 -292.513418)
			(xy 126.433217 -292.552762) (xy 126.456088 -292.596339) (xy 126.471672 -292.64302) (xy 126.479567 -292.691597)
			(xy 126.480062 -292.716204) (xy 126.479567 -292.740811) (xy 126.471672 -292.789388) (xy 126.456088 -292.836069)
			(xy 126.433217 -292.879646) (xy 126.403652 -292.91899) (xy 126.368159 -292.953082) (xy 126.327656 -292.981038)
			(xy 126.283194 -293.002136) (xy 126.235923 -293.015828) (xy 126.187068 -293.02176) (xy 126.137893 -293.019779)
			(xy 126.089674 -293.009935) (xy 126.043658 -292.992483) (xy 126.001037 -292.967876) (xy 125.962916 -292.936751)
			(xy 125.930281 -292.899914) (xy 125.903978 -292.858318) (xy 125.884687 -292.813042) (xy 125.87291 -292.765258)
			(xy 125.86895 -292.716204) (xy 125.540008 -292.716204) (xy 125.539513 -292.740811) (xy 125.531618 -292.789388)
			(xy 125.516034 -292.836069) (xy 125.493163 -292.879646) (xy 125.463598 -292.91899) (xy 125.428105 -292.953082)
			(xy 125.387602 -292.981038) (xy 125.34314 -293.002136) (xy 125.295869 -293.015828) (xy 125.247014 -293.02176)
			(xy 125.197839 -293.019779) (xy 125.14962 -293.009935) (xy 125.103604 -292.992483) (xy 125.060983 -292.967876)
			(xy 125.022862 -292.936751) (xy 124.990227 -292.899914) (xy 124.963924 -292.858318) (xy 124.944633 -292.813042)
			(xy 124.932856 -292.765258) (xy 124.928896 -292.716204) (xy 123.660154 -292.716204) (xy 123.659659 -292.740811)
			(xy 123.651764 -292.789388) (xy 123.63618 -292.836069) (xy 123.613309 -292.879646) (xy 123.583744 -292.91899)
			(xy 123.548251 -292.953082) (xy 123.507748 -292.981038) (xy 123.463286 -293.002136) (xy 123.416015 -293.015828)
			(xy 123.36716 -293.02176) (xy 123.317985 -293.019779) (xy 123.269766 -293.009935) (xy 123.22375 -292.992483)
			(xy 123.181129 -292.967876) (xy 123.143008 -292.936751) (xy 123.110373 -292.899914) (xy 123.08407 -292.858318)
			(xy 123.064779 -292.813042) (xy 123.053002 -292.765258) (xy 123.049042 -292.716204) (xy 122.7201 -292.716204)
			(xy 122.719605 -292.740811) (xy 122.71171 -292.789388) (xy 122.696126 -292.836069) (xy 122.673255 -292.879646)
			(xy 122.64369 -292.91899) (xy 122.608197 -292.953082) (xy 122.567694 -292.981038) (xy 122.523232 -293.002136)
			(xy 122.475961 -293.015828) (xy 122.427106 -293.02176) (xy 122.377931 -293.019779) (xy 122.329712 -293.009935)
			(xy 122.283696 -292.992483) (xy 122.241075 -292.967876) (xy 122.202954 -292.936751) (xy 122.170319 -292.899914)
			(xy 122.144016 -292.858318) (xy 122.124725 -292.813042) (xy 122.112948 -292.765258) (xy 122.108988 -292.716204)
			(xy 120.839992 -292.716204) (xy 120.839497 -292.740811) (xy 120.831602 -292.789388) (xy 120.816018 -292.836069)
			(xy 120.793147 -292.879646) (xy 120.763582 -292.91899) (xy 120.728089 -292.953082) (xy 120.687586 -292.981038)
			(xy 120.643124 -293.002136) (xy 120.595853 -293.015828) (xy 120.546998 -293.02176) (xy 120.497823 -293.019779)
			(xy 120.449604 -293.009935) (xy 120.403588 -292.992483) (xy 120.360967 -292.967876) (xy 120.322846 -292.936751)
			(xy 120.290211 -292.899914) (xy 120.263908 -292.858318) (xy 120.244617 -292.813042) (xy 120.23284 -292.765258)
			(xy 120.22888 -292.716204) (xy 119.899938 -292.716204) (xy 119.899443 -292.740811) (xy 119.891548 -292.789388)
			(xy 119.875964 -292.836069) (xy 119.853093 -292.879646) (xy 119.823528 -292.91899) (xy 119.788035 -292.953082)
			(xy 119.747532 -292.981038) (xy 119.70307 -293.002136) (xy 119.655799 -293.015828) (xy 119.606944 -293.02176)
			(xy 119.557769 -293.019779) (xy 119.50955 -293.009935) (xy 119.463534 -292.992483) (xy 119.420913 -292.967876)
			(xy 119.382792 -292.936751) (xy 119.350157 -292.899914) (xy 119.323854 -292.858318) (xy 119.304563 -292.813042)
			(xy 119.292786 -292.765258) (xy 119.288826 -292.716204) (xy 118.020084 -292.716204) (xy 118.019589 -292.740811)
			(xy 118.011694 -292.789388) (xy 117.99611 -292.836069) (xy 117.973239 -292.879646) (xy 117.943674 -292.91899)
			(xy 117.908181 -292.953082) (xy 117.867678 -292.981038) (xy 117.823216 -293.002136) (xy 117.775945 -293.015828)
			(xy 117.72709 -293.02176) (xy 117.677915 -293.019779) (xy 117.629696 -293.009935) (xy 117.58368 -292.992483)
			(xy 117.541059 -292.967876) (xy 117.502938 -292.936751) (xy 117.470303 -292.899914) (xy 117.444 -292.858318)
			(xy 117.424709 -292.813042) (xy 117.412932 -292.765258) (xy 117.408972 -292.716204) (xy 117.08003 -292.716204)
			(xy 117.079535 -292.740811) (xy 117.07164 -292.789388) (xy 117.056056 -292.836069) (xy 117.033185 -292.879646)
			(xy 117.00362 -292.91899) (xy 116.968127 -292.953082) (xy 116.927624 -292.981038) (xy 116.883162 -293.002136)
			(xy 116.835891 -293.015828) (xy 116.787036 -293.02176) (xy 116.737861 -293.019779) (xy 116.689642 -293.009935)
			(xy 116.643626 -292.992483) (xy 116.601005 -292.967876) (xy 116.562884 -292.936751) (xy 116.530249 -292.899914)
			(xy 116.503946 -292.858318) (xy 116.484655 -292.813042) (xy 116.472878 -292.765258) (xy 116.468918 -292.716204)
			(xy 110.506256 -292.716204) (xy 110.505761 -292.740811) (xy 110.497866 -292.789388) (xy 110.482282 -292.836069)
			(xy 110.459411 -292.879646) (xy 110.429846 -292.91899) (xy 110.394353 -292.953082) (xy 110.35385 -292.981038)
			(xy 110.309388 -293.002136) (xy 110.262117 -293.015828) (xy 110.213262 -293.02176) (xy 110.164087 -293.019779)
			(xy 110.115868 -293.009935) (xy 110.069852 -292.992483) (xy 110.027231 -292.967876) (xy 109.98911 -292.936751)
			(xy 109.956475 -292.899914) (xy 109.930172 -292.858318) (xy 109.910881 -292.813042) (xy 109.899104 -292.765258)
			(xy 109.895144 -292.716204) (xy 108.040678 -292.716204) (xy 108.040678 -293.027608) (xy 108.041102 -293.037678)
			(xy 108.048816 -293.056283) (xy 108.055664 -293.063676) (xy 108.334302 -293.342314) (xy 108.341146 -293.349714)
			(xy 108.348875 -293.368311) (xy 108.349288 -293.378382) (xy 108.349288 -293.52621) (xy 108.48519 -293.52621)
			(xy 108.48915 -293.477156) (xy 108.500927 -293.429372) (xy 108.520218 -293.384096) (xy 108.546521 -293.3425)
			(xy 108.579156 -293.305663) (xy 108.617277 -293.274538) (xy 108.659898 -293.249931) (xy 108.705914 -293.232479)
			(xy 108.754133 -293.222635) (xy 108.803308 -293.220654) (xy 108.852163 -293.226586) (xy 108.899434 -293.240278)
			(xy 108.943896 -293.261376) (xy 108.984399 -293.289332) (xy 109.019892 -293.323424) (xy 109.049457 -293.362768)
			(xy 109.072328 -293.406345) (xy 109.087912 -293.453026) (xy 109.095807 -293.501603) (xy 109.096302 -293.52621)
			(xy 109.425244 -293.52621) (xy 109.429204 -293.477156) (xy 109.440981 -293.429372) (xy 109.460272 -293.384096)
			(xy 109.486575 -293.3425) (xy 109.51921 -293.305663) (xy 109.557331 -293.274538) (xy 109.599952 -293.249931)
			(xy 109.645968 -293.232479) (xy 109.694187 -293.222635) (xy 109.743362 -293.220654) (xy 109.792217 -293.226586)
			(xy 109.839488 -293.240278) (xy 109.88395 -293.261376) (xy 109.924453 -293.289332) (xy 109.959946 -293.323424)
			(xy 109.989511 -293.362768) (xy 110.012382 -293.406345) (xy 110.027966 -293.453026) (xy 110.035861 -293.501603)
			(xy 110.036356 -293.52621) (xy 110.365298 -293.52621) (xy 110.369258 -293.477156) (xy 110.381035 -293.429372)
			(xy 110.400326 -293.384096) (xy 110.426629 -293.3425) (xy 110.459264 -293.305663) (xy 110.497385 -293.274538)
			(xy 110.540006 -293.249931) (xy 110.586022 -293.232479) (xy 110.634241 -293.222635) (xy 110.683416 -293.220654)
			(xy 110.732271 -293.226586) (xy 110.779542 -293.240278) (xy 110.824004 -293.261376) (xy 110.864507 -293.289332)
			(xy 110.9 -293.323424) (xy 110.929565 -293.362768) (xy 110.952436 -293.406345) (xy 110.96802 -293.453026)
			(xy 110.975915 -293.501603) (xy 110.97641 -293.52621) (xy 113.178856 -293.52621) (xy 113.182816 -293.477156)
			(xy 113.194593 -293.429372) (xy 113.213884 -293.384096) (xy 113.240187 -293.3425) (xy 113.272822 -293.305663)
			(xy 113.310943 -293.274538) (xy 113.353564 -293.249931) (xy 113.39958 -293.232479) (xy 113.447799 -293.222635)
			(xy 113.496974 -293.220654) (xy 113.545829 -293.226586) (xy 113.5931 -293.240278) (xy 113.637562 -293.261376)
			(xy 113.678065 -293.289332) (xy 113.713558 -293.323424) (xy 113.743123 -293.362768) (xy 113.765994 -293.406345)
			(xy 113.781578 -293.453026) (xy 113.789473 -293.501603) (xy 113.789968 -293.52621) (xy 114.11891 -293.52621)
			(xy 114.12287 -293.477156) (xy 114.134647 -293.429372) (xy 114.153938 -293.384096) (xy 114.180241 -293.3425)
			(xy 114.212876 -293.305663) (xy 114.250997 -293.274538) (xy 114.293618 -293.249931) (xy 114.339634 -293.232479)
			(xy 114.387853 -293.222635) (xy 114.437028 -293.220654) (xy 114.485883 -293.226586) (xy 114.533154 -293.240278)
			(xy 114.577616 -293.261376) (xy 114.618119 -293.289332) (xy 114.653612 -293.323424) (xy 114.683177 -293.362768)
			(xy 114.706048 -293.406345) (xy 114.721632 -293.453026) (xy 114.729527 -293.501603) (xy 114.730022 -293.52621)
			(xy 115.058964 -293.52621) (xy 115.062924 -293.477156) (xy 115.074701 -293.429372) (xy 115.093992 -293.384096)
			(xy 115.120295 -293.3425) (xy 115.15293 -293.305663) (xy 115.191051 -293.274538) (xy 115.233672 -293.249931)
			(xy 115.279688 -293.232479) (xy 115.327907 -293.222635) (xy 115.377082 -293.220654) (xy 115.425937 -293.226586)
			(xy 115.473208 -293.240278) (xy 115.51767 -293.261376) (xy 115.558173 -293.289332) (xy 115.593666 -293.323424)
			(xy 115.623231 -293.362768) (xy 115.646102 -293.406345) (xy 115.661686 -293.453026) (xy 115.669581 -293.501603)
			(xy 115.670076 -293.52621) (xy 115.999018 -293.52621) (xy 116.002978 -293.477156) (xy 116.014755 -293.429372)
			(xy 116.034046 -293.384096) (xy 116.060349 -293.3425) (xy 116.092984 -293.305663) (xy 116.131105 -293.274538)
			(xy 116.173726 -293.249931) (xy 116.219742 -293.232479) (xy 116.267961 -293.222635) (xy 116.317136 -293.220654)
			(xy 116.365991 -293.226586) (xy 116.413262 -293.240278) (xy 116.457724 -293.261376) (xy 116.498227 -293.289332)
			(xy 116.53372 -293.323424) (xy 116.563285 -293.362768) (xy 116.586156 -293.406345) (xy 116.60174 -293.453026)
			(xy 116.609635 -293.501603) (xy 116.61013 -293.52621) (xy 116.938818 -293.52621) (xy 116.942778 -293.477156)
			(xy 116.954555 -293.429372) (xy 116.973846 -293.384096) (xy 117.000149 -293.3425) (xy 117.032784 -293.305663)
			(xy 117.070905 -293.274538) (xy 117.113526 -293.249931) (xy 117.159542 -293.232479) (xy 117.207761 -293.222635)
			(xy 117.256936 -293.220654) (xy 117.305791 -293.226586) (xy 117.353062 -293.240278) (xy 117.397524 -293.261376)
			(xy 117.438027 -293.289332) (xy 117.47352 -293.323424) (xy 117.503085 -293.362768) (xy 117.525956 -293.406345)
			(xy 117.54154 -293.453026) (xy 117.549435 -293.501603) (xy 117.54993 -293.52621) (xy 117.878872 -293.52621)
			(xy 117.882832 -293.477156) (xy 117.894609 -293.429372) (xy 117.9139 -293.384096) (xy 117.940203 -293.3425)
			(xy 117.972838 -293.305663) (xy 118.010959 -293.274538) (xy 118.05358 -293.249931) (xy 118.099596 -293.232479)
			(xy 118.147815 -293.222635) (xy 118.19699 -293.220654) (xy 118.245845 -293.226586) (xy 118.293116 -293.240278)
			(xy 118.337578 -293.261376) (xy 118.378081 -293.289332) (xy 118.413574 -293.323424) (xy 118.443139 -293.362768)
			(xy 118.46601 -293.406345) (xy 118.481594 -293.453026) (xy 118.489489 -293.501603) (xy 118.489984 -293.52621)
			(xy 118.818926 -293.52621) (xy 118.822886 -293.477156) (xy 118.834663 -293.429372) (xy 118.853954 -293.384096)
			(xy 118.880257 -293.3425) (xy 118.912892 -293.305663) (xy 118.951013 -293.274538) (xy 118.993634 -293.249931)
			(xy 119.03965 -293.232479) (xy 119.087869 -293.222635) (xy 119.137044 -293.220654) (xy 119.185899 -293.226586)
			(xy 119.23317 -293.240278) (xy 119.277632 -293.261376) (xy 119.318135 -293.289332) (xy 119.353628 -293.323424)
			(xy 119.383193 -293.362768) (xy 119.406064 -293.406345) (xy 119.421648 -293.453026) (xy 119.429543 -293.501603)
			(xy 119.430038 -293.52621) (xy 119.75898 -293.52621) (xy 119.76294 -293.477156) (xy 119.774717 -293.429372)
			(xy 119.794008 -293.384096) (xy 119.820311 -293.3425) (xy 119.852946 -293.305663) (xy 119.891067 -293.274538)
			(xy 119.933688 -293.249931) (xy 119.979704 -293.232479) (xy 120.027923 -293.222635) (xy 120.077098 -293.220654)
			(xy 120.125953 -293.226586) (xy 120.173224 -293.240278) (xy 120.217686 -293.261376) (xy 120.258189 -293.289332)
			(xy 120.293682 -293.323424) (xy 120.323247 -293.362768) (xy 120.346118 -293.406345) (xy 120.361702 -293.453026)
			(xy 120.369597 -293.501603) (xy 120.370092 -293.52621) (xy 120.699034 -293.52621) (xy 120.702994 -293.477156)
			(xy 120.714771 -293.429372) (xy 120.734062 -293.384096) (xy 120.760365 -293.3425) (xy 120.793 -293.305663)
			(xy 120.831121 -293.274538) (xy 120.873742 -293.249931) (xy 120.919758 -293.232479) (xy 120.967977 -293.222635)
			(xy 121.017152 -293.220654) (xy 121.066007 -293.226586) (xy 121.113278 -293.240278) (xy 121.15774 -293.261376)
			(xy 121.198243 -293.289332) (xy 121.233736 -293.323424) (xy 121.263301 -293.362768) (xy 121.286172 -293.406345)
			(xy 121.301756 -293.453026) (xy 121.309651 -293.501603) (xy 121.310146 -293.52621) (xy 121.638834 -293.52621)
			(xy 121.642794 -293.477156) (xy 121.654571 -293.429372) (xy 121.673862 -293.384096) (xy 121.700165 -293.3425)
			(xy 121.7328 -293.305663) (xy 121.770921 -293.274538) (xy 121.813542 -293.249931) (xy 121.859558 -293.232479)
			(xy 121.907777 -293.222635) (xy 121.956952 -293.220654) (xy 122.005807 -293.226586) (xy 122.053078 -293.240278)
			(xy 122.09754 -293.261376) (xy 122.138043 -293.289332) (xy 122.173536 -293.323424) (xy 122.203101 -293.362768)
			(xy 122.225972 -293.406345) (xy 122.241556 -293.453026) (xy 122.249451 -293.501603) (xy 122.249946 -293.52621)
			(xy 122.578888 -293.52621) (xy 122.582848 -293.477156) (xy 122.594625 -293.429372) (xy 122.613916 -293.384096)
			(xy 122.640219 -293.3425) (xy 122.672854 -293.305663) (xy 122.710975 -293.274538) (xy 122.753596 -293.249931)
			(xy 122.799612 -293.232479) (xy 122.847831 -293.222635) (xy 122.897006 -293.220654) (xy 122.945861 -293.226586)
			(xy 122.993132 -293.240278) (xy 123.037594 -293.261376) (xy 123.078097 -293.289332) (xy 123.11359 -293.323424)
			(xy 123.143155 -293.362768) (xy 123.166026 -293.406345) (xy 123.18161 -293.453026) (xy 123.189505 -293.501603)
			(xy 123.19 -293.52621) (xy 123.518942 -293.52621) (xy 123.522902 -293.477156) (xy 123.534679 -293.429372)
			(xy 123.55397 -293.384096) (xy 123.580273 -293.3425) (xy 123.612908 -293.305663) (xy 123.651029 -293.274538)
			(xy 123.69365 -293.249931) (xy 123.739666 -293.232479) (xy 123.787885 -293.222635) (xy 123.83706 -293.220654)
			(xy 123.885915 -293.226586) (xy 123.933186 -293.240278) (xy 123.977648 -293.261376) (xy 124.018151 -293.289332)
			(xy 124.053644 -293.323424) (xy 124.083209 -293.362768) (xy 124.10608 -293.406345) (xy 124.121664 -293.453026)
			(xy 124.129559 -293.501603) (xy 124.130054 -293.52621) (xy 124.458996 -293.52621) (xy 124.462956 -293.477156)
			(xy 124.474733 -293.429372) (xy 124.494024 -293.384096) (xy 124.520327 -293.3425) (xy 124.552962 -293.305663)
			(xy 124.591083 -293.274538) (xy 124.633704 -293.249931) (xy 124.67972 -293.232479) (xy 124.727939 -293.222635)
			(xy 124.777114 -293.220654) (xy 124.825969 -293.226586) (xy 124.87324 -293.240278) (xy 124.917702 -293.261376)
			(xy 124.958205 -293.289332) (xy 124.993698 -293.323424) (xy 125.023263 -293.362768) (xy 125.046134 -293.406345)
			(xy 125.061718 -293.453026) (xy 125.069613 -293.501603) (xy 125.070108 -293.52621) (xy 125.39905 -293.52621)
			(xy 125.40301 -293.477156) (xy 125.414787 -293.429372) (xy 125.434078 -293.384096) (xy 125.460381 -293.3425)
			(xy 125.493016 -293.305663) (xy 125.531137 -293.274538) (xy 125.573758 -293.249931) (xy 125.619774 -293.232479)
			(xy 125.667993 -293.222635) (xy 125.717168 -293.220654) (xy 125.766023 -293.226586) (xy 125.813294 -293.240278)
			(xy 125.857756 -293.261376) (xy 125.898259 -293.289332) (xy 125.933752 -293.323424) (xy 125.963317 -293.362768)
			(xy 125.986188 -293.406345) (xy 126.001772 -293.453026) (xy 126.009667 -293.501603) (xy 126.010162 -293.52621)
			(xy 126.33885 -293.52621) (xy 126.34281 -293.477156) (xy 126.354587 -293.429372) (xy 126.373878 -293.384096)
			(xy 126.400181 -293.3425) (xy 126.432816 -293.305663) (xy 126.470937 -293.274538) (xy 126.513558 -293.249931)
			(xy 126.559574 -293.232479) (xy 126.607793 -293.222635) (xy 126.656968 -293.220654) (xy 126.705823 -293.226586)
			(xy 126.753094 -293.240278) (xy 126.797556 -293.261376) (xy 126.838059 -293.289332) (xy 126.873552 -293.323424)
			(xy 126.903117 -293.362768) (xy 126.925988 -293.406345) (xy 126.941572 -293.453026) (xy 126.949467 -293.501603)
			(xy 126.949962 -293.52621) (xy 126.949467 -293.550817) (xy 126.941572 -293.599394) (xy 126.925988 -293.646075)
			(xy 126.903117 -293.689652) (xy 126.873552 -293.728996) (xy 126.838059 -293.763088) (xy 126.797556 -293.791044)
			(xy 126.753094 -293.812142) (xy 126.705823 -293.825834) (xy 126.656968 -293.831766) (xy 126.607793 -293.829785)
			(xy 126.559574 -293.819941) (xy 126.513558 -293.802489) (xy 126.470937 -293.777882) (xy 126.432816 -293.746757)
			(xy 126.400181 -293.70992) (xy 126.373878 -293.668324) (xy 126.354587 -293.623048) (xy 126.34281 -293.575264)
			(xy 126.33885 -293.52621) (xy 126.010162 -293.52621) (xy 126.009667 -293.550817) (xy 126.001772 -293.599394)
			(xy 125.986188 -293.646075) (xy 125.963317 -293.689652) (xy 125.933752 -293.728996) (xy 125.898259 -293.763088)
			(xy 125.857756 -293.791044) (xy 125.813294 -293.812142) (xy 125.766023 -293.825834) (xy 125.717168 -293.831766)
			(xy 125.667993 -293.829785) (xy 125.619774 -293.819941) (xy 125.573758 -293.802489) (xy 125.531137 -293.777882)
			(xy 125.493016 -293.746757) (xy 125.460381 -293.70992) (xy 125.434078 -293.668324) (xy 125.414787 -293.623048)
			(xy 125.40301 -293.575264) (xy 125.39905 -293.52621) (xy 125.070108 -293.52621) (xy 125.069613 -293.550817)
			(xy 125.061718 -293.599394) (xy 125.046134 -293.646075) (xy 125.023263 -293.689652) (xy 124.993698 -293.728996)
			(xy 124.958205 -293.763088) (xy 124.917702 -293.791044) (xy 124.87324 -293.812142) (xy 124.825969 -293.825834)
			(xy 124.777114 -293.831766) (xy 124.727939 -293.829785) (xy 124.67972 -293.819941) (xy 124.633704 -293.802489)
			(xy 124.591083 -293.777882) (xy 124.552962 -293.746757) (xy 124.520327 -293.70992) (xy 124.494024 -293.668324)
			(xy 124.474733 -293.623048) (xy 124.462956 -293.575264) (xy 124.458996 -293.52621) (xy 124.130054 -293.52621)
			(xy 124.129559 -293.550817) (xy 124.121664 -293.599394) (xy 124.10608 -293.646075) (xy 124.083209 -293.689652)
			(xy 124.053644 -293.728996) (xy 124.018151 -293.763088) (xy 123.977648 -293.791044) (xy 123.933186 -293.812142)
			(xy 123.885915 -293.825834) (xy 123.83706 -293.831766) (xy 123.787885 -293.829785) (xy 123.739666 -293.819941)
			(xy 123.69365 -293.802489) (xy 123.651029 -293.777882) (xy 123.612908 -293.746757) (xy 123.580273 -293.70992)
			(xy 123.55397 -293.668324) (xy 123.534679 -293.623048) (xy 123.522902 -293.575264) (xy 123.518942 -293.52621)
			(xy 123.19 -293.52621) (xy 123.189505 -293.550817) (xy 123.18161 -293.599394) (xy 123.166026 -293.646075)
			(xy 123.143155 -293.689652) (xy 123.11359 -293.728996) (xy 123.078097 -293.763088) (xy 123.037594 -293.791044)
			(xy 122.993132 -293.812142) (xy 122.945861 -293.825834) (xy 122.897006 -293.831766) (xy 122.847831 -293.829785)
			(xy 122.799612 -293.819941) (xy 122.753596 -293.802489) (xy 122.710975 -293.777882) (xy 122.672854 -293.746757)
			(xy 122.640219 -293.70992) (xy 122.613916 -293.668324) (xy 122.594625 -293.623048) (xy 122.582848 -293.575264)
			(xy 122.578888 -293.52621) (xy 122.249946 -293.52621) (xy 122.249451 -293.550817) (xy 122.241556 -293.599394)
			(xy 122.225972 -293.646075) (xy 122.203101 -293.689652) (xy 122.173536 -293.728996) (xy 122.138043 -293.763088)
			(xy 122.09754 -293.791044) (xy 122.053078 -293.812142) (xy 122.005807 -293.825834) (xy 121.956952 -293.831766)
			(xy 121.907777 -293.829785) (xy 121.859558 -293.819941) (xy 121.813542 -293.802489) (xy 121.770921 -293.777882)
			(xy 121.7328 -293.746757) (xy 121.700165 -293.70992) (xy 121.673862 -293.668324) (xy 121.654571 -293.623048)
			(xy 121.642794 -293.575264) (xy 121.638834 -293.52621) (xy 121.310146 -293.52621) (xy 121.309651 -293.550817)
			(xy 121.301756 -293.599394) (xy 121.286172 -293.646075) (xy 121.263301 -293.689652) (xy 121.233736 -293.728996)
			(xy 121.198243 -293.763088) (xy 121.15774 -293.791044) (xy 121.113278 -293.812142) (xy 121.066007 -293.825834)
			(xy 121.017152 -293.831766) (xy 120.967977 -293.829785) (xy 120.919758 -293.819941) (xy 120.873742 -293.802489)
			(xy 120.831121 -293.777882) (xy 120.793 -293.746757) (xy 120.760365 -293.70992) (xy 120.734062 -293.668324)
			(xy 120.714771 -293.623048) (xy 120.702994 -293.575264) (xy 120.699034 -293.52621) (xy 120.370092 -293.52621)
			(xy 120.369597 -293.550817) (xy 120.361702 -293.599394) (xy 120.346118 -293.646075) (xy 120.323247 -293.689652)
			(xy 120.293682 -293.728996) (xy 120.258189 -293.763088) (xy 120.217686 -293.791044) (xy 120.173224 -293.812142)
			(xy 120.125953 -293.825834) (xy 120.077098 -293.831766) (xy 120.027923 -293.829785) (xy 119.979704 -293.819941)
			(xy 119.933688 -293.802489) (xy 119.891067 -293.777882) (xy 119.852946 -293.746757) (xy 119.820311 -293.70992)
			(xy 119.794008 -293.668324) (xy 119.774717 -293.623048) (xy 119.76294 -293.575264) (xy 119.75898 -293.52621)
			(xy 119.430038 -293.52621) (xy 119.429543 -293.550817) (xy 119.421648 -293.599394) (xy 119.406064 -293.646075)
			(xy 119.383193 -293.689652) (xy 119.353628 -293.728996) (xy 119.318135 -293.763088) (xy 119.277632 -293.791044)
			(xy 119.23317 -293.812142) (xy 119.185899 -293.825834) (xy 119.137044 -293.831766) (xy 119.087869 -293.829785)
			(xy 119.03965 -293.819941) (xy 118.993634 -293.802489) (xy 118.951013 -293.777882) (xy 118.912892 -293.746757)
			(xy 118.880257 -293.70992) (xy 118.853954 -293.668324) (xy 118.834663 -293.623048) (xy 118.822886 -293.575264)
			(xy 118.818926 -293.52621) (xy 118.489984 -293.52621) (xy 118.489489 -293.550817) (xy 118.481594 -293.599394)
			(xy 118.46601 -293.646075) (xy 118.443139 -293.689652) (xy 118.413574 -293.728996) (xy 118.378081 -293.763088)
			(xy 118.337578 -293.791044) (xy 118.293116 -293.812142) (xy 118.245845 -293.825834) (xy 118.19699 -293.831766)
			(xy 118.147815 -293.829785) (xy 118.099596 -293.819941) (xy 118.05358 -293.802489) (xy 118.010959 -293.777882)
			(xy 117.972838 -293.746757) (xy 117.940203 -293.70992) (xy 117.9139 -293.668324) (xy 117.894609 -293.623048)
			(xy 117.882832 -293.575264) (xy 117.878872 -293.52621) (xy 117.54993 -293.52621) (xy 117.549435 -293.550817)
			(xy 117.54154 -293.599394) (xy 117.525956 -293.646075) (xy 117.503085 -293.689652) (xy 117.47352 -293.728996)
			(xy 117.438027 -293.763088) (xy 117.397524 -293.791044) (xy 117.353062 -293.812142) (xy 117.305791 -293.825834)
			(xy 117.256936 -293.831766) (xy 117.207761 -293.829785) (xy 117.159542 -293.819941) (xy 117.113526 -293.802489)
			(xy 117.070905 -293.777882) (xy 117.032784 -293.746757) (xy 117.000149 -293.70992) (xy 116.973846 -293.668324)
			(xy 116.954555 -293.623048) (xy 116.942778 -293.575264) (xy 116.938818 -293.52621) (xy 116.61013 -293.52621)
			(xy 116.609635 -293.550817) (xy 116.60174 -293.599394) (xy 116.586156 -293.646075) (xy 116.563285 -293.689652)
			(xy 116.53372 -293.728996) (xy 116.498227 -293.763088) (xy 116.457724 -293.791044) (xy 116.413262 -293.812142)
			(xy 116.365991 -293.825834) (xy 116.317136 -293.831766) (xy 116.267961 -293.829785) (xy 116.219742 -293.819941)
			(xy 116.173726 -293.802489) (xy 116.131105 -293.777882) (xy 116.092984 -293.746757) (xy 116.060349 -293.70992)
			(xy 116.034046 -293.668324) (xy 116.014755 -293.623048) (xy 116.002978 -293.575264) (xy 115.999018 -293.52621)
			(xy 115.670076 -293.52621) (xy 115.669581 -293.550817) (xy 115.661686 -293.599394) (xy 115.646102 -293.646075)
			(xy 115.623231 -293.689652) (xy 115.593666 -293.728996) (xy 115.558173 -293.763088) (xy 115.51767 -293.791044)
			(xy 115.473208 -293.812142) (xy 115.425937 -293.825834) (xy 115.377082 -293.831766) (xy 115.327907 -293.829785)
			(xy 115.279688 -293.819941) (xy 115.233672 -293.802489) (xy 115.191051 -293.777882) (xy 115.15293 -293.746757)
			(xy 115.120295 -293.70992) (xy 115.093992 -293.668324) (xy 115.074701 -293.623048) (xy 115.062924 -293.575264)
			(xy 115.058964 -293.52621) (xy 114.730022 -293.52621) (xy 114.729527 -293.550817) (xy 114.721632 -293.599394)
			(xy 114.706048 -293.646075) (xy 114.683177 -293.689652) (xy 114.653612 -293.728996) (xy 114.618119 -293.763088)
			(xy 114.577616 -293.791044) (xy 114.533154 -293.812142) (xy 114.485883 -293.825834) (xy 114.437028 -293.831766)
			(xy 114.387853 -293.829785) (xy 114.339634 -293.819941) (xy 114.293618 -293.802489) (xy 114.250997 -293.777882)
			(xy 114.212876 -293.746757) (xy 114.180241 -293.70992) (xy 114.153938 -293.668324) (xy 114.134647 -293.623048)
			(xy 114.12287 -293.575264) (xy 114.11891 -293.52621) (xy 113.789968 -293.52621) (xy 113.789473 -293.550817)
			(xy 113.781578 -293.599394) (xy 113.765994 -293.646075) (xy 113.743123 -293.689652) (xy 113.713558 -293.728996)
			(xy 113.678065 -293.763088) (xy 113.637562 -293.791044) (xy 113.5931 -293.812142) (xy 113.545829 -293.825834)
			(xy 113.496974 -293.831766) (xy 113.447799 -293.829785) (xy 113.39958 -293.819941) (xy 113.353564 -293.802489)
			(xy 113.310943 -293.777882) (xy 113.272822 -293.746757) (xy 113.240187 -293.70992) (xy 113.213884 -293.668324)
			(xy 113.194593 -293.623048) (xy 113.182816 -293.575264) (xy 113.178856 -293.52621) (xy 110.97641 -293.52621)
			(xy 110.975915 -293.550817) (xy 110.96802 -293.599394) (xy 110.952436 -293.646075) (xy 110.929565 -293.689652)
			(xy 110.9 -293.728996) (xy 110.864507 -293.763088) (xy 110.824004 -293.791044) (xy 110.779542 -293.812142)
			(xy 110.732271 -293.825834) (xy 110.683416 -293.831766) (xy 110.634241 -293.829785) (xy 110.586022 -293.819941)
			(xy 110.540006 -293.802489) (xy 110.497385 -293.777882) (xy 110.459264 -293.746757) (xy 110.426629 -293.70992)
			(xy 110.400326 -293.668324) (xy 110.381035 -293.623048) (xy 110.369258 -293.575264) (xy 110.365298 -293.52621)
			(xy 110.036356 -293.52621) (xy 110.035861 -293.550817) (xy 110.027966 -293.599394) (xy 110.012382 -293.646075)
			(xy 109.989511 -293.689652) (xy 109.959946 -293.728996) (xy 109.924453 -293.763088) (xy 109.88395 -293.791044)
			(xy 109.839488 -293.812142) (xy 109.792217 -293.825834) (xy 109.743362 -293.831766) (xy 109.694187 -293.829785)
			(xy 109.645968 -293.819941) (xy 109.599952 -293.802489) (xy 109.557331 -293.777882) (xy 109.51921 -293.746757)
			(xy 109.486575 -293.70992) (xy 109.460272 -293.668324) (xy 109.440981 -293.623048) (xy 109.429204 -293.575264)
			(xy 109.425244 -293.52621) (xy 109.096302 -293.52621) (xy 109.095807 -293.550817) (xy 109.087912 -293.599394)
			(xy 109.072328 -293.646075) (xy 109.049457 -293.689652) (xy 109.019892 -293.728996) (xy 108.984399 -293.763088)
			(xy 108.943896 -293.791044) (xy 108.899434 -293.812142) (xy 108.852163 -293.825834) (xy 108.803308 -293.831766)
			(xy 108.754133 -293.829785) (xy 108.705914 -293.819941) (xy 108.659898 -293.802489) (xy 108.617277 -293.777882)
			(xy 108.579156 -293.746757) (xy 108.546521 -293.70992) (xy 108.520218 -293.668324) (xy 108.500927 -293.623048)
			(xy 108.48915 -293.575264) (xy 108.48519 -293.52621) (xy 108.349288 -293.52621) (xy 108.349288 -293.603934)
			(xy 108.348858 -293.614001) (xy 108.341134 -293.632596) (xy 108.334302 -293.640002) (xy 107.89285 -294.081454)
			(xy 107.889548 -294.087296) (xy 107.874649 -294.113169) (xy 107.842503 -294.163488) (xy 107.825286 -294.18788)
			(xy 107.820952 -294.194463) (xy 107.816153 -294.209467) (xy 107.815888 -294.217344) (xy 107.815888 -294.336216)
			(xy 108.01529 -294.336216) (xy 108.01925 -294.287162) (xy 108.031027 -294.239378) (xy 108.050318 -294.194102)
			(xy 108.076621 -294.152506) (xy 108.109256 -294.115669) (xy 108.147377 -294.084544) (xy 108.189998 -294.059937)
			(xy 108.236014 -294.042485) (xy 108.284233 -294.032641) (xy 108.333408 -294.03066) (xy 108.382263 -294.036592)
			(xy 108.429534 -294.050284) (xy 108.473996 -294.071382) (xy 108.514499 -294.099338) (xy 108.549992 -294.13343)
			(xy 108.579557 -294.172774) (xy 108.602428 -294.216351) (xy 108.618012 -294.263032) (xy 108.625907 -294.311609)
			(xy 108.626402 -294.336216) (xy 108.955344 -294.336216) (xy 108.959304 -294.287162) (xy 108.971081 -294.239378)
			(xy 108.990372 -294.194102) (xy 109.016675 -294.152506) (xy 109.04931 -294.115669) (xy 109.087431 -294.084544)
			(xy 109.130052 -294.059937) (xy 109.176068 -294.042485) (xy 109.224287 -294.032641) (xy 109.273462 -294.03066)
			(xy 109.322317 -294.036592) (xy 109.369588 -294.050284) (xy 109.41405 -294.071382) (xy 109.454553 -294.099338)
			(xy 109.490046 -294.13343) (xy 109.519611 -294.172774) (xy 109.542482 -294.216351) (xy 109.558066 -294.263032)
			(xy 109.565961 -294.311609) (xy 109.566456 -294.336216) (xy 109.895144 -294.336216) (xy 109.899104 -294.287162)
			(xy 109.910881 -294.239378) (xy 109.930172 -294.194102) (xy 109.956475 -294.152506) (xy 109.98911 -294.115669)
			(xy 110.027231 -294.084544) (xy 110.069852 -294.059937) (xy 110.115868 -294.042485) (xy 110.164087 -294.032641)
			(xy 110.213262 -294.03066) (xy 110.262117 -294.036592) (xy 110.309388 -294.050284) (xy 110.35385 -294.071382)
			(xy 110.394353 -294.099338) (xy 110.429846 -294.13343) (xy 110.459411 -294.172774) (xy 110.482282 -294.216351)
			(xy 110.497866 -294.263032) (xy 110.505761 -294.311609) (xy 110.506256 -294.336216) (xy 113.64901 -294.336216)
			(xy 113.65297 -294.287162) (xy 113.664747 -294.239378) (xy 113.684038 -294.194102) (xy 113.710341 -294.152506)
			(xy 113.742976 -294.115669) (xy 113.781097 -294.084544) (xy 113.823718 -294.059937) (xy 113.869734 -294.042485)
			(xy 113.917953 -294.032641) (xy 113.967128 -294.03066) (xy 114.015983 -294.036592) (xy 114.063254 -294.050284)
			(xy 114.107716 -294.071382) (xy 114.148219 -294.099338) (xy 114.183712 -294.13343) (xy 114.213277 -294.172774)
			(xy 114.236148 -294.216351) (xy 114.251732 -294.263032) (xy 114.259627 -294.311609) (xy 114.260122 -294.336216)
			(xy 114.58881 -294.336216) (xy 114.59277 -294.287162) (xy 114.604547 -294.239378) (xy 114.623838 -294.194102)
			(xy 114.650141 -294.152506) (xy 114.682776 -294.115669) (xy 114.720897 -294.084544) (xy 114.763518 -294.059937)
			(xy 114.809534 -294.042485) (xy 114.857753 -294.032641) (xy 114.906928 -294.03066) (xy 114.955783 -294.036592)
			(xy 115.003054 -294.050284) (xy 115.047516 -294.071382) (xy 115.088019 -294.099338) (xy 115.123512 -294.13343)
			(xy 115.153077 -294.172774) (xy 115.175948 -294.216351) (xy 115.191532 -294.263032) (xy 115.199427 -294.311609)
			(xy 115.199922 -294.336216) (xy 115.528864 -294.336216) (xy 115.532824 -294.287162) (xy 115.544601 -294.239378)
			(xy 115.563892 -294.194102) (xy 115.590195 -294.152506) (xy 115.62283 -294.115669) (xy 115.660951 -294.084544)
			(xy 115.703572 -294.059937) (xy 115.749588 -294.042485) (xy 115.797807 -294.032641) (xy 115.846982 -294.03066)
			(xy 115.895837 -294.036592) (xy 115.943108 -294.050284) (xy 115.98757 -294.071382) (xy 116.028073 -294.099338)
			(xy 116.063566 -294.13343) (xy 116.093131 -294.172774) (xy 116.116002 -294.216351) (xy 116.131586 -294.263032)
			(xy 116.139481 -294.311609) (xy 116.139976 -294.336216) (xy 116.468918 -294.336216) (xy 116.472878 -294.287162)
			(xy 116.484655 -294.239378) (xy 116.503946 -294.194102) (xy 116.530249 -294.152506) (xy 116.562884 -294.115669)
			(xy 116.601005 -294.084544) (xy 116.643626 -294.059937) (xy 116.689642 -294.042485) (xy 116.737861 -294.032641)
			(xy 116.787036 -294.03066) (xy 116.835891 -294.036592) (xy 116.883162 -294.050284) (xy 116.927624 -294.071382)
			(xy 116.968127 -294.099338) (xy 117.00362 -294.13343) (xy 117.033185 -294.172774) (xy 117.056056 -294.216351)
			(xy 117.07164 -294.263032) (xy 117.079535 -294.311609) (xy 117.08003 -294.336216) (xy 117.408972 -294.336216)
			(xy 117.412932 -294.287162) (xy 117.424709 -294.239378) (xy 117.444 -294.194102) (xy 117.470303 -294.152506)
			(xy 117.502938 -294.115669) (xy 117.541059 -294.084544) (xy 117.58368 -294.059937) (xy 117.629696 -294.042485)
			(xy 117.677915 -294.032641) (xy 117.72709 -294.03066) (xy 117.775945 -294.036592) (xy 117.823216 -294.050284)
			(xy 117.867678 -294.071382) (xy 117.908181 -294.099338) (xy 117.943674 -294.13343) (xy 117.973239 -294.172774)
			(xy 117.99611 -294.216351) (xy 118.011694 -294.263032) (xy 118.019589 -294.311609) (xy 118.020084 -294.336216)
			(xy 118.349026 -294.336216) (xy 118.352986 -294.287162) (xy 118.364763 -294.239378) (xy 118.384054 -294.194102)
			(xy 118.410357 -294.152506) (xy 118.442992 -294.115669) (xy 118.481113 -294.084544) (xy 118.523734 -294.059937)
			(xy 118.56975 -294.042485) (xy 118.617969 -294.032641) (xy 118.667144 -294.03066) (xy 118.715999 -294.036592)
			(xy 118.76327 -294.050284) (xy 118.807732 -294.071382) (xy 118.848235 -294.099338) (xy 118.883728 -294.13343)
			(xy 118.913293 -294.172774) (xy 118.936164 -294.216351) (xy 118.951748 -294.263032) (xy 118.959643 -294.311609)
			(xy 118.960138 -294.336216) (xy 119.288826 -294.336216) (xy 119.292786 -294.287162) (xy 119.304563 -294.239378)
			(xy 119.323854 -294.194102) (xy 119.350157 -294.152506) (xy 119.382792 -294.115669) (xy 119.420913 -294.084544)
			(xy 119.463534 -294.059937) (xy 119.50955 -294.042485) (xy 119.557769 -294.032641) (xy 119.606944 -294.03066)
			(xy 119.655799 -294.036592) (xy 119.70307 -294.050284) (xy 119.747532 -294.071382) (xy 119.788035 -294.099338)
			(xy 119.823528 -294.13343) (xy 119.853093 -294.172774) (xy 119.875964 -294.216351) (xy 119.891548 -294.263032)
			(xy 119.899443 -294.311609) (xy 119.899938 -294.336216) (xy 120.22888 -294.336216) (xy 120.23284 -294.287162)
			(xy 120.244617 -294.239378) (xy 120.263908 -294.194102) (xy 120.290211 -294.152506) (xy 120.322846 -294.115669)
			(xy 120.360967 -294.084544) (xy 120.403588 -294.059937) (xy 120.449604 -294.042485) (xy 120.497823 -294.032641)
			(xy 120.546998 -294.03066) (xy 120.595853 -294.036592) (xy 120.643124 -294.050284) (xy 120.687586 -294.071382)
			(xy 120.728089 -294.099338) (xy 120.763582 -294.13343) (xy 120.793147 -294.172774) (xy 120.816018 -294.216351)
			(xy 120.831602 -294.263032) (xy 120.839497 -294.311609) (xy 120.839992 -294.336216) (xy 121.168934 -294.336216)
			(xy 121.172894 -294.287162) (xy 121.184671 -294.239378) (xy 121.203962 -294.194102) (xy 121.230265 -294.152506)
			(xy 121.2629 -294.115669) (xy 121.301021 -294.084544) (xy 121.343642 -294.059937) (xy 121.389658 -294.042485)
			(xy 121.437877 -294.032641) (xy 121.487052 -294.03066) (xy 121.535907 -294.036592) (xy 121.583178 -294.050284)
			(xy 121.62764 -294.071382) (xy 121.668143 -294.099338) (xy 121.703636 -294.13343) (xy 121.733201 -294.172774)
			(xy 121.756072 -294.216351) (xy 121.771656 -294.263032) (xy 121.779551 -294.311609) (xy 121.780046 -294.336216)
			(xy 122.108988 -294.336216) (xy 122.112948 -294.287162) (xy 122.124725 -294.239378) (xy 122.144016 -294.194102)
			(xy 122.170319 -294.152506) (xy 122.202954 -294.115669) (xy 122.241075 -294.084544) (xy 122.283696 -294.059937)
			(xy 122.329712 -294.042485) (xy 122.377931 -294.032641) (xy 122.427106 -294.03066) (xy 122.475961 -294.036592)
			(xy 122.523232 -294.050284) (xy 122.567694 -294.071382) (xy 122.608197 -294.099338) (xy 122.64369 -294.13343)
			(xy 122.673255 -294.172774) (xy 122.696126 -294.216351) (xy 122.71171 -294.263032) (xy 122.719605 -294.311609)
			(xy 122.7201 -294.336216) (xy 123.049042 -294.336216) (xy 123.053002 -294.287162) (xy 123.064779 -294.239378)
			(xy 123.08407 -294.194102) (xy 123.110373 -294.152506) (xy 123.143008 -294.115669) (xy 123.181129 -294.084544)
			(xy 123.22375 -294.059937) (xy 123.269766 -294.042485) (xy 123.317985 -294.032641) (xy 123.36716 -294.03066)
			(xy 123.416015 -294.036592) (xy 123.463286 -294.050284) (xy 123.507748 -294.071382) (xy 123.548251 -294.099338)
			(xy 123.583744 -294.13343) (xy 123.613309 -294.172774) (xy 123.63618 -294.216351) (xy 123.651764 -294.263032)
			(xy 123.659659 -294.311609) (xy 123.660154 -294.336216) (xy 123.988842 -294.336216) (xy 123.992802 -294.287162)
			(xy 124.004579 -294.239378) (xy 124.02387 -294.194102) (xy 124.050173 -294.152506) (xy 124.082808 -294.115669)
			(xy 124.120929 -294.084544) (xy 124.16355 -294.059937) (xy 124.209566 -294.042485) (xy 124.257785 -294.032641)
			(xy 124.30696 -294.03066) (xy 124.355815 -294.036592) (xy 124.403086 -294.050284) (xy 124.447548 -294.071382)
			(xy 124.488051 -294.099338) (xy 124.523544 -294.13343) (xy 124.553109 -294.172774) (xy 124.57598 -294.216351)
			(xy 124.591564 -294.263032) (xy 124.599459 -294.311609) (xy 124.599954 -294.336216) (xy 124.928896 -294.336216)
			(xy 124.932856 -294.287162) (xy 124.944633 -294.239378) (xy 124.963924 -294.194102) (xy 124.990227 -294.152506)
			(xy 125.022862 -294.115669) (xy 125.060983 -294.084544) (xy 125.103604 -294.059937) (xy 125.14962 -294.042485)
			(xy 125.197839 -294.032641) (xy 125.247014 -294.03066) (xy 125.295869 -294.036592) (xy 125.34314 -294.050284)
			(xy 125.387602 -294.071382) (xy 125.428105 -294.099338) (xy 125.463598 -294.13343) (xy 125.493163 -294.172774)
			(xy 125.516034 -294.216351) (xy 125.531618 -294.263032) (xy 125.539513 -294.311609) (xy 125.540008 -294.336216)
			(xy 125.86895 -294.336216) (xy 125.87291 -294.287162) (xy 125.884687 -294.239378) (xy 125.903978 -294.194102)
			(xy 125.930281 -294.152506) (xy 125.962916 -294.115669) (xy 126.001037 -294.084544) (xy 126.043658 -294.059937)
			(xy 126.089674 -294.042485) (xy 126.137893 -294.032641) (xy 126.187068 -294.03066) (xy 126.235923 -294.036592)
			(xy 126.283194 -294.050284) (xy 126.327656 -294.071382) (xy 126.368159 -294.099338) (xy 126.403652 -294.13343)
			(xy 126.433217 -294.172774) (xy 126.456088 -294.216351) (xy 126.471672 -294.263032) (xy 126.479567 -294.311609)
			(xy 126.480062 -294.336216) (xy 126.809004 -294.336216) (xy 126.812964 -294.287162) (xy 126.824741 -294.239378)
			(xy 126.844032 -294.194102) (xy 126.870335 -294.152506) (xy 126.90297 -294.115669) (xy 126.941091 -294.084544)
			(xy 126.983712 -294.059937) (xy 127.029728 -294.042485) (xy 127.077947 -294.032641) (xy 127.127122 -294.03066)
			(xy 127.175977 -294.036592) (xy 127.223248 -294.050284) (xy 127.26771 -294.071382) (xy 127.308213 -294.099338)
			(xy 127.343706 -294.13343) (xy 127.373271 -294.172774) (xy 127.396142 -294.216351) (xy 127.411726 -294.263032)
			(xy 127.419621 -294.311609) (xy 127.420116 -294.336216) (xy 127.419621 -294.360823) (xy 127.411726 -294.4094)
			(xy 127.396142 -294.456081) (xy 127.373271 -294.499658) (xy 127.343706 -294.539002) (xy 127.308213 -294.573094)
			(xy 127.26771 -294.60105) (xy 127.223248 -294.622148) (xy 127.175977 -294.63584) (xy 127.127122 -294.641772)
			(xy 127.077947 -294.639791) (xy 127.029728 -294.629947) (xy 126.983712 -294.612495) (xy 126.941091 -294.587888)
			(xy 126.90297 -294.556763) (xy 126.870335 -294.519926) (xy 126.844032 -294.47833) (xy 126.824741 -294.433054)
			(xy 126.812964 -294.38527) (xy 126.809004 -294.336216) (xy 126.480062 -294.336216) (xy 126.479567 -294.360823)
			(xy 126.471672 -294.4094) (xy 126.456088 -294.456081) (xy 126.433217 -294.499658) (xy 126.403652 -294.539002)
			(xy 126.368159 -294.573094) (xy 126.327656 -294.60105) (xy 126.283194 -294.622148) (xy 126.235923 -294.63584)
			(xy 126.187068 -294.641772) (xy 126.137893 -294.639791) (xy 126.089674 -294.629947) (xy 126.043658 -294.612495)
			(xy 126.001037 -294.587888) (xy 125.962916 -294.556763) (xy 125.930281 -294.519926) (xy 125.903978 -294.47833)
			(xy 125.884687 -294.433054) (xy 125.87291 -294.38527) (xy 125.86895 -294.336216) (xy 125.540008 -294.336216)
			(xy 125.539513 -294.360823) (xy 125.531618 -294.4094) (xy 125.516034 -294.456081) (xy 125.493163 -294.499658)
			(xy 125.463598 -294.539002) (xy 125.428105 -294.573094) (xy 125.387602 -294.60105) (xy 125.34314 -294.622148)
			(xy 125.295869 -294.63584) (xy 125.247014 -294.641772) (xy 125.197839 -294.639791) (xy 125.14962 -294.629947)
			(xy 125.103604 -294.612495) (xy 125.060983 -294.587888) (xy 125.022862 -294.556763) (xy 124.990227 -294.519926)
			(xy 124.963924 -294.47833) (xy 124.944633 -294.433054) (xy 124.932856 -294.38527) (xy 124.928896 -294.336216)
			(xy 124.599954 -294.336216) (xy 124.599459 -294.360823) (xy 124.591564 -294.4094) (xy 124.57598 -294.456081)
			(xy 124.553109 -294.499658) (xy 124.523544 -294.539002) (xy 124.488051 -294.573094) (xy 124.447548 -294.60105)
			(xy 124.403086 -294.622148) (xy 124.355815 -294.63584) (xy 124.30696 -294.641772) (xy 124.257785 -294.639791)
			(xy 124.209566 -294.629947) (xy 124.16355 -294.612495) (xy 124.120929 -294.587888) (xy 124.082808 -294.556763)
			(xy 124.050173 -294.519926) (xy 124.02387 -294.47833) (xy 124.004579 -294.433054) (xy 123.992802 -294.38527)
			(xy 123.988842 -294.336216) (xy 123.660154 -294.336216) (xy 123.659659 -294.360823) (xy 123.651764 -294.4094)
			(xy 123.63618 -294.456081) (xy 123.613309 -294.499658) (xy 123.583744 -294.539002) (xy 123.548251 -294.573094)
			(xy 123.507748 -294.60105) (xy 123.463286 -294.622148) (xy 123.416015 -294.63584) (xy 123.36716 -294.641772)
			(xy 123.317985 -294.639791) (xy 123.269766 -294.629947) (xy 123.22375 -294.612495) (xy 123.181129 -294.587888)
			(xy 123.143008 -294.556763) (xy 123.110373 -294.519926) (xy 123.08407 -294.47833) (xy 123.064779 -294.433054)
			(xy 123.053002 -294.38527) (xy 123.049042 -294.336216) (xy 122.7201 -294.336216) (xy 122.719605 -294.360823)
			(xy 122.71171 -294.4094) (xy 122.696126 -294.456081) (xy 122.673255 -294.499658) (xy 122.64369 -294.539002)
			(xy 122.608197 -294.573094) (xy 122.567694 -294.60105) (xy 122.523232 -294.622148) (xy 122.475961 -294.63584)
			(xy 122.427106 -294.641772) (xy 122.377931 -294.639791) (xy 122.329712 -294.629947) (xy 122.283696 -294.612495)
			(xy 122.241075 -294.587888) (xy 122.202954 -294.556763) (xy 122.170319 -294.519926) (xy 122.144016 -294.47833)
			(xy 122.124725 -294.433054) (xy 122.112948 -294.38527) (xy 122.108988 -294.336216) (xy 121.780046 -294.336216)
			(xy 121.779551 -294.360823) (xy 121.771656 -294.4094) (xy 121.756072 -294.456081) (xy 121.733201 -294.499658)
			(xy 121.703636 -294.539002) (xy 121.668143 -294.573094) (xy 121.62764 -294.60105) (xy 121.583178 -294.622148)
			(xy 121.535907 -294.63584) (xy 121.487052 -294.641772) (xy 121.437877 -294.639791) (xy 121.389658 -294.629947)
			(xy 121.343642 -294.612495) (xy 121.301021 -294.587888) (xy 121.2629 -294.556763) (xy 121.230265 -294.519926)
			(xy 121.203962 -294.47833) (xy 121.184671 -294.433054) (xy 121.172894 -294.38527) (xy 121.168934 -294.336216)
			(xy 120.839992 -294.336216) (xy 120.839497 -294.360823) (xy 120.831602 -294.4094) (xy 120.816018 -294.456081)
			(xy 120.793147 -294.499658) (xy 120.763582 -294.539002) (xy 120.728089 -294.573094) (xy 120.687586 -294.60105)
			(xy 120.643124 -294.622148) (xy 120.595853 -294.63584) (xy 120.546998 -294.641772) (xy 120.497823 -294.639791)
			(xy 120.449604 -294.629947) (xy 120.403588 -294.612495) (xy 120.360967 -294.587888) (xy 120.322846 -294.556763)
			(xy 120.290211 -294.519926) (xy 120.263908 -294.47833) (xy 120.244617 -294.433054) (xy 120.23284 -294.38527)
			(xy 120.22888 -294.336216) (xy 119.899938 -294.336216) (xy 119.899443 -294.360823) (xy 119.891548 -294.4094)
			(xy 119.875964 -294.456081) (xy 119.853093 -294.499658) (xy 119.823528 -294.539002) (xy 119.788035 -294.573094)
			(xy 119.747532 -294.60105) (xy 119.70307 -294.622148) (xy 119.655799 -294.63584) (xy 119.606944 -294.641772)
			(xy 119.557769 -294.639791) (xy 119.50955 -294.629947) (xy 119.463534 -294.612495) (xy 119.420913 -294.587888)
			(xy 119.382792 -294.556763) (xy 119.350157 -294.519926) (xy 119.323854 -294.47833) (xy 119.304563 -294.433054)
			(xy 119.292786 -294.38527) (xy 119.288826 -294.336216) (xy 118.960138 -294.336216) (xy 118.959643 -294.360823)
			(xy 118.951748 -294.4094) (xy 118.936164 -294.456081) (xy 118.913293 -294.499658) (xy 118.883728 -294.539002)
			(xy 118.848235 -294.573094) (xy 118.807732 -294.60105) (xy 118.76327 -294.622148) (xy 118.715999 -294.63584)
			(xy 118.667144 -294.641772) (xy 118.617969 -294.639791) (xy 118.56975 -294.629947) (xy 118.523734 -294.612495)
			(xy 118.481113 -294.587888) (xy 118.442992 -294.556763) (xy 118.410357 -294.519926) (xy 118.384054 -294.47833)
			(xy 118.364763 -294.433054) (xy 118.352986 -294.38527) (xy 118.349026 -294.336216) (xy 118.020084 -294.336216)
			(xy 118.019589 -294.360823) (xy 118.011694 -294.4094) (xy 117.99611 -294.456081) (xy 117.973239 -294.499658)
			(xy 117.943674 -294.539002) (xy 117.908181 -294.573094) (xy 117.867678 -294.60105) (xy 117.823216 -294.622148)
			(xy 117.775945 -294.63584) (xy 117.72709 -294.641772) (xy 117.677915 -294.639791) (xy 117.629696 -294.629947)
			(xy 117.58368 -294.612495) (xy 117.541059 -294.587888) (xy 117.502938 -294.556763) (xy 117.470303 -294.519926)
			(xy 117.444 -294.47833) (xy 117.424709 -294.433054) (xy 117.412932 -294.38527) (xy 117.408972 -294.336216)
			(xy 117.08003 -294.336216) (xy 117.079535 -294.360823) (xy 117.07164 -294.4094) (xy 117.056056 -294.456081)
			(xy 117.033185 -294.499658) (xy 117.00362 -294.539002) (xy 116.968127 -294.573094) (xy 116.927624 -294.60105)
			(xy 116.883162 -294.622148) (xy 116.835891 -294.63584) (xy 116.787036 -294.641772) (xy 116.737861 -294.639791)
			(xy 116.689642 -294.629947) (xy 116.643626 -294.612495) (xy 116.601005 -294.587888) (xy 116.562884 -294.556763)
			(xy 116.530249 -294.519926) (xy 116.503946 -294.47833) (xy 116.484655 -294.433054) (xy 116.472878 -294.38527)
			(xy 116.468918 -294.336216) (xy 116.139976 -294.336216) (xy 116.139481 -294.360823) (xy 116.131586 -294.4094)
			(xy 116.116002 -294.456081) (xy 116.093131 -294.499658) (xy 116.063566 -294.539002) (xy 116.028073 -294.573094)
			(xy 115.98757 -294.60105) (xy 115.943108 -294.622148) (xy 115.895837 -294.63584) (xy 115.846982 -294.641772)
			(xy 115.797807 -294.639791) (xy 115.749588 -294.629947) (xy 115.703572 -294.612495) (xy 115.660951 -294.587888)
			(xy 115.62283 -294.556763) (xy 115.590195 -294.519926) (xy 115.563892 -294.47833) (xy 115.544601 -294.433054)
			(xy 115.532824 -294.38527) (xy 115.528864 -294.336216) (xy 115.199922 -294.336216) (xy 115.199427 -294.360823)
			(xy 115.191532 -294.4094) (xy 115.175948 -294.456081) (xy 115.153077 -294.499658) (xy 115.123512 -294.539002)
			(xy 115.088019 -294.573094) (xy 115.047516 -294.60105) (xy 115.003054 -294.622148) (xy 114.955783 -294.63584)
			(xy 114.906928 -294.641772) (xy 114.857753 -294.639791) (xy 114.809534 -294.629947) (xy 114.763518 -294.612495)
			(xy 114.720897 -294.587888) (xy 114.682776 -294.556763) (xy 114.650141 -294.519926) (xy 114.623838 -294.47833)
			(xy 114.604547 -294.433054) (xy 114.59277 -294.38527) (xy 114.58881 -294.336216) (xy 114.260122 -294.336216)
			(xy 114.259627 -294.360823) (xy 114.251732 -294.4094) (xy 114.236148 -294.456081) (xy 114.213277 -294.499658)
			(xy 114.183712 -294.539002) (xy 114.148219 -294.573094) (xy 114.107716 -294.60105) (xy 114.063254 -294.622148)
			(xy 114.015983 -294.63584) (xy 113.967128 -294.641772) (xy 113.917953 -294.639791) (xy 113.869734 -294.629947)
			(xy 113.823718 -294.612495) (xy 113.781097 -294.587888) (xy 113.742976 -294.556763) (xy 113.710341 -294.519926)
			(xy 113.684038 -294.47833) (xy 113.664747 -294.433054) (xy 113.65297 -294.38527) (xy 113.64901 -294.336216)
			(xy 110.506256 -294.336216) (xy 110.505761 -294.360823) (xy 110.497866 -294.4094) (xy 110.482282 -294.456081)
			(xy 110.459411 -294.499658) (xy 110.429846 -294.539002) (xy 110.394353 -294.573094) (xy 110.35385 -294.60105)
			(xy 110.309388 -294.622148) (xy 110.262117 -294.63584) (xy 110.213262 -294.641772) (xy 110.164087 -294.639791)
			(xy 110.115868 -294.629947) (xy 110.069852 -294.612495) (xy 110.027231 -294.587888) (xy 109.98911 -294.556763)
			(xy 109.956475 -294.519926) (xy 109.930172 -294.47833) (xy 109.910881 -294.433054) (xy 109.899104 -294.38527)
			(xy 109.895144 -294.336216) (xy 109.566456 -294.336216) (xy 109.565961 -294.360823) (xy 109.558066 -294.4094)
			(xy 109.542482 -294.456081) (xy 109.519611 -294.499658) (xy 109.490046 -294.539002) (xy 109.454553 -294.573094)
			(xy 109.41405 -294.60105) (xy 109.369588 -294.622148) (xy 109.322317 -294.63584) (xy 109.273462 -294.641772)
			(xy 109.224287 -294.639791) (xy 109.176068 -294.629947) (xy 109.130052 -294.612495) (xy 109.087431 -294.587888)
			(xy 109.04931 -294.556763) (xy 109.016675 -294.519926) (xy 108.990372 -294.47833) (xy 108.971081 -294.433054)
			(xy 108.959304 -294.38527) (xy 108.955344 -294.336216) (xy 108.626402 -294.336216) (xy 108.625907 -294.360823)
			(xy 108.618012 -294.4094) (xy 108.602428 -294.456081) (xy 108.579557 -294.499658) (xy 108.549992 -294.539002)
			(xy 108.514499 -294.573094) (xy 108.473996 -294.60105) (xy 108.429534 -294.622148) (xy 108.382263 -294.63584)
			(xy 108.333408 -294.641772) (xy 108.284233 -294.639791) (xy 108.236014 -294.629947) (xy 108.189998 -294.612495)
			(xy 108.147377 -294.587888) (xy 108.109256 -294.556763) (xy 108.076621 -294.519926) (xy 108.050318 -294.47833)
			(xy 108.031027 -294.433054) (xy 108.01925 -294.38527) (xy 108.01529 -294.336216) (xy 107.815888 -294.336216)
			(xy 107.815888 -294.720264) (xy 107.815453 -294.730329) (xy 107.807721 -294.748915) (xy 107.800902 -294.756332)
			(xy 107.554268 -295.002966) (xy 107.547424 -295.010365) (xy 107.539703 -295.028964) (xy 107.539282 -295.039034)
			(xy 107.539282 -295.146222) (xy 109.425244 -295.146222) (xy 109.429204 -295.097168) (xy 109.440981 -295.049384)
			(xy 109.460272 -295.004108) (xy 109.486575 -294.962512) (xy 109.51921 -294.925675) (xy 109.557331 -294.89455)
			(xy 109.599952 -294.869943) (xy 109.645968 -294.852491) (xy 109.694187 -294.842647) (xy 109.743362 -294.840666)
			(xy 109.792217 -294.846598) (xy 109.839488 -294.86029) (xy 109.88395 -294.881388) (xy 109.924453 -294.909344)
			(xy 109.959946 -294.943436) (xy 109.989511 -294.98278) (xy 110.012382 -295.026357) (xy 110.027966 -295.073038)
			(xy 110.035861 -295.121615) (xy 110.036356 -295.146222) (xy 110.365298 -295.146222) (xy 110.369258 -295.097168)
			(xy 110.381035 -295.049384) (xy 110.400326 -295.004108) (xy 110.426629 -294.962512) (xy 110.459264 -294.925675)
			(xy 110.497385 -294.89455) (xy 110.540006 -294.869943) (xy 110.586022 -294.852491) (xy 110.634241 -294.842647)
			(xy 110.683416 -294.840666) (xy 110.732271 -294.846598) (xy 110.779542 -294.86029) (xy 110.824004 -294.881388)
			(xy 110.864507 -294.909344) (xy 110.9 -294.943436) (xy 110.929565 -294.98278) (xy 110.952436 -295.026357)
			(xy 110.96802 -295.073038) (xy 110.975915 -295.121615) (xy 110.97641 -295.146222) (xy 113.178856 -295.146222)
			(xy 113.182816 -295.097168) (xy 113.194593 -295.049384) (xy 113.213884 -295.004108) (xy 113.240187 -294.962512)
			(xy 113.272822 -294.925675) (xy 113.310943 -294.89455) (xy 113.353564 -294.869943) (xy 113.39958 -294.852491)
			(xy 113.447799 -294.842647) (xy 113.496974 -294.840666) (xy 113.545829 -294.846598) (xy 113.5931 -294.86029)
			(xy 113.637562 -294.881388) (xy 113.678065 -294.909344) (xy 113.713558 -294.943436) (xy 113.743123 -294.98278)
			(xy 113.765994 -295.026357) (xy 113.781578 -295.073038) (xy 113.789473 -295.121615) (xy 113.789968 -295.146222)
			(xy 114.11891 -295.146222) (xy 114.12287 -295.097168) (xy 114.134647 -295.049384) (xy 114.153938 -295.004108)
			(xy 114.180241 -294.962512) (xy 114.212876 -294.925675) (xy 114.250997 -294.89455) (xy 114.293618 -294.869943)
			(xy 114.339634 -294.852491) (xy 114.387853 -294.842647) (xy 114.437028 -294.840666) (xy 114.485883 -294.846598)
			(xy 114.533154 -294.86029) (xy 114.577616 -294.881388) (xy 114.618119 -294.909344) (xy 114.653612 -294.943436)
			(xy 114.683177 -294.98278) (xy 114.706048 -295.026357) (xy 114.721632 -295.073038) (xy 114.729527 -295.121615)
			(xy 114.730022 -295.146222) (xy 116.938818 -295.146222) (xy 116.942778 -295.097168) (xy 116.954555 -295.049384)
			(xy 116.973846 -295.004108) (xy 117.000149 -294.962512) (xy 117.032784 -294.925675) (xy 117.070905 -294.89455)
			(xy 117.113526 -294.869943) (xy 117.159542 -294.852491) (xy 117.207761 -294.842647) (xy 117.256936 -294.840666)
			(xy 117.305791 -294.846598) (xy 117.353062 -294.86029) (xy 117.397524 -294.881388) (xy 117.438027 -294.909344)
			(xy 117.47352 -294.943436) (xy 117.503085 -294.98278) (xy 117.525956 -295.026357) (xy 117.54154 -295.073038)
			(xy 117.549435 -295.121615) (xy 117.54993 -295.146222) (xy 119.75898 -295.146222) (xy 119.76294 -295.097168)
			(xy 119.774717 -295.049384) (xy 119.794008 -295.004108) (xy 119.820311 -294.962512) (xy 119.852946 -294.925675)
			(xy 119.891067 -294.89455) (xy 119.933688 -294.869943) (xy 119.979704 -294.852491) (xy 120.027923 -294.842647)
			(xy 120.077098 -294.840666) (xy 120.125953 -294.846598) (xy 120.173224 -294.86029) (xy 120.217686 -294.881388)
			(xy 120.258189 -294.909344) (xy 120.293682 -294.943436) (xy 120.323247 -294.98278) (xy 120.346118 -295.026357)
			(xy 120.361702 -295.073038) (xy 120.369597 -295.121615) (xy 120.370092 -295.146222) (xy 122.578888 -295.146222)
			(xy 122.582848 -295.097168) (xy 122.594625 -295.049384) (xy 122.613916 -295.004108) (xy 122.640219 -294.962512)
			(xy 122.672854 -294.925675) (xy 122.710975 -294.89455) (xy 122.753596 -294.869943) (xy 122.799612 -294.852491)
			(xy 122.847831 -294.842647) (xy 122.897006 -294.840666) (xy 122.945861 -294.846598) (xy 122.993132 -294.86029)
			(xy 123.037594 -294.881388) (xy 123.078097 -294.909344) (xy 123.11359 -294.943436) (xy 123.143155 -294.98278)
			(xy 123.166026 -295.026357) (xy 123.18161 -295.073038) (xy 123.189505 -295.121615) (xy 123.19 -295.146222)
			(xy 125.39905 -295.146222) (xy 125.40301 -295.097168) (xy 125.414787 -295.049384) (xy 125.434078 -295.004108)
			(xy 125.460381 -294.962512) (xy 125.493016 -294.925675) (xy 125.531137 -294.89455) (xy 125.573758 -294.869943)
			(xy 125.619774 -294.852491) (xy 125.667993 -294.842647) (xy 125.717168 -294.840666) (xy 125.766023 -294.846598)
			(xy 125.813294 -294.86029) (xy 125.857756 -294.881388) (xy 125.898259 -294.909344) (xy 125.933752 -294.943436)
			(xy 125.963317 -294.98278) (xy 125.986188 -295.026357) (xy 126.001772 -295.073038) (xy 126.009667 -295.121615)
			(xy 126.010162 -295.146222) (xy 126.009667 -295.170829) (xy 126.001772 -295.219406) (xy 125.986188 -295.266087)
			(xy 125.963317 -295.309664) (xy 125.933752 -295.349008) (xy 125.898259 -295.3831) (xy 125.857756 -295.411056)
			(xy 125.813294 -295.432154) (xy 125.766023 -295.445846) (xy 125.717168 -295.451778) (xy 125.667993 -295.449797)
			(xy 125.619774 -295.439953) (xy 125.573758 -295.422501) (xy 125.531137 -295.397894) (xy 125.493016 -295.366769)
			(xy 125.460381 -295.329932) (xy 125.434078 -295.288336) (xy 125.414787 -295.24306) (xy 125.40301 -295.195276)
			(xy 125.39905 -295.146222) (xy 123.19 -295.146222) (xy 123.189505 -295.170829) (xy 123.18161 -295.219406)
			(xy 123.166026 -295.266087) (xy 123.143155 -295.309664) (xy 123.11359 -295.349008) (xy 123.078097 -295.3831)
			(xy 123.037594 -295.411056) (xy 122.993132 -295.432154) (xy 122.945861 -295.445846) (xy 122.897006 -295.451778)
			(xy 122.847831 -295.449797) (xy 122.799612 -295.439953) (xy 122.753596 -295.422501) (xy 122.710975 -295.397894)
			(xy 122.672854 -295.366769) (xy 122.640219 -295.329932) (xy 122.613916 -295.288336) (xy 122.594625 -295.24306)
			(xy 122.582848 -295.195276) (xy 122.578888 -295.146222) (xy 120.370092 -295.146222) (xy 120.369597 -295.170829)
			(xy 120.361702 -295.219406) (xy 120.346118 -295.266087) (xy 120.323247 -295.309664) (xy 120.293682 -295.349008)
			(xy 120.258189 -295.3831) (xy 120.217686 -295.411056) (xy 120.173224 -295.432154) (xy 120.125953 -295.445846)
			(xy 120.077098 -295.451778) (xy 120.027923 -295.449797) (xy 119.979704 -295.439953) (xy 119.933688 -295.422501)
			(xy 119.891067 -295.397894) (xy 119.852946 -295.366769) (xy 119.820311 -295.329932) (xy 119.794008 -295.288336)
			(xy 119.774717 -295.24306) (xy 119.76294 -295.195276) (xy 119.75898 -295.146222) (xy 117.54993 -295.146222)
			(xy 117.549435 -295.170829) (xy 117.54154 -295.219406) (xy 117.525956 -295.266087) (xy 117.503085 -295.309664)
			(xy 117.47352 -295.349008) (xy 117.438027 -295.3831) (xy 117.397524 -295.411056) (xy 117.353062 -295.432154)
			(xy 117.305791 -295.445846) (xy 117.256936 -295.451778) (xy 117.207761 -295.449797) (xy 117.159542 -295.439953)
			(xy 117.113526 -295.422501) (xy 117.070905 -295.397894) (xy 117.032784 -295.366769) (xy 117.000149 -295.329932)
			(xy 116.973846 -295.288336) (xy 116.954555 -295.24306) (xy 116.942778 -295.195276) (xy 116.938818 -295.146222)
			(xy 114.730022 -295.146222) (xy 114.729527 -295.170829) (xy 114.721632 -295.219406) (xy 114.706048 -295.266087)
			(xy 114.683177 -295.309664) (xy 114.653612 -295.349008) (xy 114.618119 -295.3831) (xy 114.577616 -295.411056)
			(xy 114.533154 -295.432154) (xy 114.485883 -295.445846) (xy 114.437028 -295.451778) (xy 114.387853 -295.449797)
			(xy 114.339634 -295.439953) (xy 114.293618 -295.422501) (xy 114.250997 -295.397894) (xy 114.212876 -295.366769)
			(xy 114.180241 -295.329932) (xy 114.153938 -295.288336) (xy 114.134647 -295.24306) (xy 114.12287 -295.195276)
			(xy 114.11891 -295.146222) (xy 113.789968 -295.146222) (xy 113.789473 -295.170829) (xy 113.781578 -295.219406)
			(xy 113.765994 -295.266087) (xy 113.743123 -295.309664) (xy 113.713558 -295.349008) (xy 113.678065 -295.3831)
			(xy 113.637562 -295.411056) (xy 113.5931 -295.432154) (xy 113.545829 -295.445846) (xy 113.496974 -295.451778)
			(xy 113.447799 -295.449797) (xy 113.39958 -295.439953) (xy 113.353564 -295.422501) (xy 113.310943 -295.397894)
			(xy 113.272822 -295.366769) (xy 113.240187 -295.329932) (xy 113.213884 -295.288336) (xy 113.194593 -295.24306)
			(xy 113.182816 -295.195276) (xy 113.178856 -295.146222) (xy 110.97641 -295.146222) (xy 110.975915 -295.170829)
			(xy 110.96802 -295.219406) (xy 110.952436 -295.266087) (xy 110.929565 -295.309664) (xy 110.9 -295.349008)
			(xy 110.864507 -295.3831) (xy 110.824004 -295.411056) (xy 110.779542 -295.432154) (xy 110.732271 -295.445846)
			(xy 110.683416 -295.451778) (xy 110.634241 -295.449797) (xy 110.586022 -295.439953) (xy 110.540006 -295.422501)
			(xy 110.497385 -295.397894) (xy 110.459264 -295.366769) (xy 110.426629 -295.329932) (xy 110.400326 -295.288336)
			(xy 110.381035 -295.24306) (xy 110.369258 -295.195276) (xy 110.365298 -295.146222) (xy 110.036356 -295.146222)
			(xy 110.035861 -295.170829) (xy 110.027966 -295.219406) (xy 110.012382 -295.266087) (xy 109.989511 -295.309664)
			(xy 109.959946 -295.349008) (xy 109.924453 -295.3831) (xy 109.88395 -295.411056) (xy 109.839488 -295.432154)
			(xy 109.792217 -295.445846) (xy 109.743362 -295.451778) (xy 109.694187 -295.449797) (xy 109.645968 -295.439953)
			(xy 109.599952 -295.422501) (xy 109.557331 -295.397894) (xy 109.51921 -295.366769) (xy 109.486575 -295.329932)
			(xy 109.460272 -295.288336) (xy 109.440981 -295.24306) (xy 109.429204 -295.195276) (xy 109.425244 -295.146222)
			(xy 107.539282 -295.146222) (xy 107.539282 -295.655746) (xy 107.539449 -295.661756) (xy 107.542271 -295.673439)
			(xy 107.54487 -295.67886) (xy 107.56011 -295.708578) (xy 107.565698 -295.712896) (xy 107.585779 -295.728794)
			(xy 107.620835 -295.76613) (xy 107.649175 -295.808789) (xy 107.670003 -295.855576) (xy 107.682736 -295.905182)
			(xy 107.687019 -295.956217) (xy 107.687018 -295.956228) (xy 114.58881 -295.956228) (xy 114.59277 -295.907174)
			(xy 114.604547 -295.85939) (xy 114.623838 -295.814114) (xy 114.650141 -295.772518) (xy 114.682776 -295.735681)
			(xy 114.720897 -295.704556) (xy 114.763518 -295.679949) (xy 114.809534 -295.662497) (xy 114.857753 -295.652653)
			(xy 114.906928 -295.650672) (xy 114.955783 -295.656604) (xy 115.003054 -295.670296) (xy 115.047516 -295.691394)
			(xy 115.088019 -295.71935) (xy 115.123512 -295.753442) (xy 115.153077 -295.792786) (xy 115.175948 -295.836363)
			(xy 115.191532 -295.883044) (xy 115.199427 -295.931621) (xy 115.199922 -295.956228) (xy 115.528864 -295.956228)
			(xy 115.532824 -295.907174) (xy 115.544601 -295.85939) (xy 115.563892 -295.814114) (xy 115.590195 -295.772518)
			(xy 115.62283 -295.735681) (xy 115.660951 -295.704556) (xy 115.703572 -295.679949) (xy 115.749588 -295.662497)
			(xy 115.797807 -295.652653) (xy 115.846982 -295.650672) (xy 115.895837 -295.656604) (xy 115.943108 -295.670296)
			(xy 115.98757 -295.691394) (xy 116.028073 -295.71935) (xy 116.063566 -295.753442) (xy 116.093131 -295.792786)
			(xy 116.116002 -295.836363) (xy 116.131586 -295.883044) (xy 116.139481 -295.931621) (xy 116.139976 -295.956228)
			(xy 116.468918 -295.956228) (xy 116.472878 -295.907174) (xy 116.484655 -295.85939) (xy 116.503946 -295.814114)
			(xy 116.530249 -295.772518) (xy 116.562884 -295.735681) (xy 116.601005 -295.704556) (xy 116.643626 -295.679949)
			(xy 116.689642 -295.662497) (xy 116.737861 -295.652653) (xy 116.787036 -295.650672) (xy 116.835891 -295.656604)
			(xy 116.883162 -295.670296) (xy 116.927624 -295.691394) (xy 116.968127 -295.71935) (xy 117.00362 -295.753442)
			(xy 117.033185 -295.792786) (xy 117.056056 -295.836363) (xy 117.07164 -295.883044) (xy 117.079535 -295.931621)
			(xy 117.08003 -295.956228) (xy 117.408972 -295.956228) (xy 117.412932 -295.907174) (xy 117.424709 -295.85939)
			(xy 117.444 -295.814114) (xy 117.470303 -295.772518) (xy 117.502938 -295.735681) (xy 117.541059 -295.704556)
			(xy 117.58368 -295.679949) (xy 117.629696 -295.662497) (xy 117.677915 -295.652653) (xy 117.72709 -295.650672)
			(xy 117.775945 -295.656604) (xy 117.823216 -295.670296) (xy 117.867678 -295.691394) (xy 117.908181 -295.71935)
			(xy 117.943674 -295.753442) (xy 117.973239 -295.792786) (xy 117.99611 -295.836363) (xy 118.011694 -295.883044)
			(xy 118.019589 -295.931621) (xy 118.020084 -295.956228) (xy 118.349026 -295.956228) (xy 118.352986 -295.907174)
			(xy 118.364763 -295.85939) (xy 118.384054 -295.814114) (xy 118.410357 -295.772518) (xy 118.442992 -295.735681)
			(xy 118.481113 -295.704556) (xy 118.523734 -295.679949) (xy 118.56975 -295.662497) (xy 118.617969 -295.652653)
			(xy 118.667144 -295.650672) (xy 118.715999 -295.656604) (xy 118.76327 -295.670296) (xy 118.807732 -295.691394)
			(xy 118.848235 -295.71935) (xy 118.883728 -295.753442) (xy 118.913293 -295.792786) (xy 118.936164 -295.836363)
			(xy 118.951748 -295.883044) (xy 118.959643 -295.931621) (xy 118.960138 -295.956228) (xy 120.22888 -295.956228)
			(xy 120.23284 -295.907174) (xy 120.244617 -295.85939) (xy 120.263908 -295.814114) (xy 120.290211 -295.772518)
			(xy 120.322846 -295.735681) (xy 120.360967 -295.704556) (xy 120.403588 -295.679949) (xy 120.449604 -295.662497)
			(xy 120.497823 -295.652653) (xy 120.546998 -295.650672) (xy 120.595853 -295.656604) (xy 120.643124 -295.670296)
			(xy 120.687586 -295.691394) (xy 120.728089 -295.71935) (xy 120.763582 -295.753442) (xy 120.793147 -295.792786)
			(xy 120.816018 -295.836363) (xy 120.831602 -295.883044) (xy 120.839497 -295.931621) (xy 120.839992 -295.956228)
			(xy 121.168934 -295.956228) (xy 121.172894 -295.907174) (xy 121.184671 -295.85939) (xy 121.203962 -295.814114)
			(xy 121.230265 -295.772518) (xy 121.2629 -295.735681) (xy 121.301021 -295.704556) (xy 121.343642 -295.679949)
			(xy 121.389658 -295.662497) (xy 121.437877 -295.652653) (xy 121.487052 -295.650672) (xy 121.535907 -295.656604)
			(xy 121.583178 -295.670296) (xy 121.62764 -295.691394) (xy 121.668143 -295.71935) (xy 121.703636 -295.753442)
			(xy 121.733201 -295.792786) (xy 121.756072 -295.836363) (xy 121.771656 -295.883044) (xy 121.779551 -295.931621)
			(xy 121.780046 -295.956228) (xy 122.108988 -295.956228) (xy 122.112948 -295.907174) (xy 122.124725 -295.85939)
			(xy 122.144016 -295.814114) (xy 122.170319 -295.772518) (xy 122.202954 -295.735681) (xy 122.241075 -295.704556)
			(xy 122.283696 -295.679949) (xy 122.329712 -295.662497) (xy 122.377931 -295.652653) (xy 122.427106 -295.650672)
			(xy 122.475961 -295.656604) (xy 122.523232 -295.670296) (xy 122.567694 -295.691394) (xy 122.608197 -295.71935)
			(xy 122.64369 -295.753442) (xy 122.673255 -295.792786) (xy 122.696126 -295.836363) (xy 122.71171 -295.883044)
			(xy 122.719605 -295.931621) (xy 122.7201 -295.956228) (xy 123.049042 -295.956228) (xy 123.053002 -295.907174)
			(xy 123.064779 -295.85939) (xy 123.08407 -295.814114) (xy 123.110373 -295.772518) (xy 123.143008 -295.735681)
			(xy 123.181129 -295.704556) (xy 123.22375 -295.679949) (xy 123.269766 -295.662497) (xy 123.317985 -295.652653)
			(xy 123.36716 -295.650672) (xy 123.416015 -295.656604) (xy 123.463286 -295.670296) (xy 123.507748 -295.691394)
			(xy 123.548251 -295.71935) (xy 123.583744 -295.753442) (xy 123.613309 -295.792786) (xy 123.63618 -295.836363)
			(xy 123.651764 -295.883044) (xy 123.659659 -295.931621) (xy 123.660154 -295.956228) (xy 123.988842 -295.956228)
			(xy 123.992802 -295.907174) (xy 124.004579 -295.85939) (xy 124.02387 -295.814114) (xy 124.050173 -295.772518)
			(xy 124.082808 -295.735681) (xy 124.120929 -295.704556) (xy 124.16355 -295.679949) (xy 124.209566 -295.662497)
			(xy 124.257785 -295.652653) (xy 124.30696 -295.650672) (xy 124.355815 -295.656604) (xy 124.403086 -295.670296)
			(xy 124.447548 -295.691394) (xy 124.488051 -295.71935) (xy 124.523544 -295.753442) (xy 124.553109 -295.792786)
			(xy 124.57598 -295.836363) (xy 124.591564 -295.883044) (xy 124.599459 -295.931621) (xy 124.599954 -295.956228)
			(xy 125.86895 -295.956228) (xy 125.87291 -295.907174) (xy 125.884687 -295.85939) (xy 125.903978 -295.814114)
			(xy 125.930281 -295.772518) (xy 125.962916 -295.735681) (xy 126.001037 -295.704556) (xy 126.043658 -295.679949)
			(xy 126.089674 -295.662497) (xy 126.137893 -295.652653) (xy 126.187068 -295.650672) (xy 126.235923 -295.656604)
			(xy 126.283194 -295.670296) (xy 126.327656 -295.691394) (xy 126.368159 -295.71935) (xy 126.403652 -295.753442)
			(xy 126.433217 -295.792786) (xy 126.456088 -295.836363) (xy 126.471672 -295.883044) (xy 126.479567 -295.931621)
			(xy 126.480062 -295.956228) (xy 126.809004 -295.956228) (xy 126.812964 -295.907174) (xy 126.824741 -295.85939)
			(xy 126.844032 -295.814114) (xy 126.870335 -295.772518) (xy 126.90297 -295.735681) (xy 126.941091 -295.704556)
			(xy 126.983712 -295.679949) (xy 127.029728 -295.662497) (xy 127.077947 -295.652653) (xy 127.127122 -295.650672)
			(xy 127.175977 -295.656604) (xy 127.223248 -295.670296) (xy 127.26771 -295.691394) (xy 127.308213 -295.71935)
			(xy 127.343706 -295.753442) (xy 127.373271 -295.792786) (xy 127.396142 -295.836363) (xy 127.411726 -295.883044)
			(xy 127.419621 -295.931621) (xy 127.420116 -295.956228) (xy 127.749058 -295.956228) (xy 127.753018 -295.907174)
			(xy 127.764795 -295.85939) (xy 127.784086 -295.814114) (xy 127.810389 -295.772518) (xy 127.843024 -295.735681)
			(xy 127.881145 -295.704556) (xy 127.923766 -295.679949) (xy 127.969782 -295.662497) (xy 128.018001 -295.652653)
			(xy 128.067176 -295.650672) (xy 128.116031 -295.656604) (xy 128.163302 -295.670296) (xy 128.207764 -295.691394)
			(xy 128.248267 -295.71935) (xy 128.28376 -295.753442) (xy 128.313325 -295.792786) (xy 128.336196 -295.836363)
			(xy 128.35178 -295.883044) (xy 128.359675 -295.931621) (xy 128.36017 -295.956228) (xy 128.688858 -295.956228)
			(xy 128.692818 -295.907174) (xy 128.704595 -295.85939) (xy 128.723886 -295.814114) (xy 128.750189 -295.772518)
			(xy 128.782824 -295.735681) (xy 128.820945 -295.704556) (xy 128.863566 -295.679949) (xy 128.909582 -295.662497)
			(xy 128.957801 -295.652653) (xy 129.006976 -295.650672) (xy 129.055831 -295.656604) (xy 129.103102 -295.670296)
			(xy 129.147564 -295.691394) (xy 129.188067 -295.71935) (xy 129.22356 -295.753442) (xy 129.253125 -295.792786)
			(xy 129.275996 -295.836363) (xy 129.29158 -295.883044) (xy 129.299475 -295.931621) (xy 129.29997 -295.956228)
			(xy 129.299475 -295.980835) (xy 129.29158 -296.029412) (xy 129.275996 -296.076093) (xy 129.253125 -296.11967)
			(xy 129.22356 -296.159014) (xy 129.188067 -296.193106) (xy 129.147564 -296.221062) (xy 129.103102 -296.24216)
			(xy 129.055831 -296.255852) (xy 129.006976 -296.261784) (xy 128.957801 -296.259803) (xy 128.909582 -296.249959)
			(xy 128.863566 -296.232507) (xy 128.820945 -296.2079) (xy 128.782824 -296.176775) (xy 128.750189 -296.139938)
			(xy 128.723886 -296.098342) (xy 128.704595 -296.053066) (xy 128.692818 -296.005282) (xy 128.688858 -295.956228)
			(xy 128.36017 -295.956228) (xy 128.359675 -295.980835) (xy 128.35178 -296.029412) (xy 128.336196 -296.076093)
			(xy 128.313325 -296.11967) (xy 128.28376 -296.159014) (xy 128.248267 -296.193106) (xy 128.207764 -296.221062)
			(xy 128.163302 -296.24216) (xy 128.116031 -296.255852) (xy 128.067176 -296.261784) (xy 128.018001 -296.259803)
			(xy 127.969782 -296.249959) (xy 127.923766 -296.232507) (xy 127.881145 -296.2079) (xy 127.843024 -296.176775)
			(xy 127.810389 -296.139938) (xy 127.784086 -296.098342) (xy 127.764795 -296.053066) (xy 127.753018 -296.005282)
			(xy 127.749058 -295.956228) (xy 127.420116 -295.956228) (xy 127.419621 -295.980835) (xy 127.411726 -296.029412)
			(xy 127.396142 -296.076093) (xy 127.373271 -296.11967) (xy 127.343706 -296.159014) (xy 127.308213 -296.193106)
			(xy 127.26771 -296.221062) (xy 127.223248 -296.24216) (xy 127.175977 -296.255852) (xy 127.127122 -296.261784)
			(xy 127.077947 -296.259803) (xy 127.029728 -296.249959) (xy 126.983712 -296.232507) (xy 126.941091 -296.2079)
			(xy 126.90297 -296.176775) (xy 126.870335 -296.139938) (xy 126.844032 -296.098342) (xy 126.824741 -296.053066)
			(xy 126.812964 -296.005282) (xy 126.809004 -295.956228) (xy 126.480062 -295.956228) (xy 126.479567 -295.980835)
			(xy 126.471672 -296.029412) (xy 126.456088 -296.076093) (xy 126.433217 -296.11967) (xy 126.403652 -296.159014)
			(xy 126.368159 -296.193106) (xy 126.327656 -296.221062) (xy 126.283194 -296.24216) (xy 126.235923 -296.255852)
			(xy 126.187068 -296.261784) (xy 126.137893 -296.259803) (xy 126.089674 -296.249959) (xy 126.043658 -296.232507)
			(xy 126.001037 -296.2079) (xy 125.962916 -296.176775) (xy 125.930281 -296.139938) (xy 125.903978 -296.098342)
			(xy 125.884687 -296.053066) (xy 125.87291 -296.005282) (xy 125.86895 -295.956228) (xy 124.599954 -295.956228)
			(xy 124.599459 -295.980835) (xy 124.591564 -296.029412) (xy 124.57598 -296.076093) (xy 124.553109 -296.11967)
			(xy 124.523544 -296.159014) (xy 124.488051 -296.193106) (xy 124.447548 -296.221062) (xy 124.403086 -296.24216)
			(xy 124.355815 -296.255852) (xy 124.30696 -296.261784) (xy 124.257785 -296.259803) (xy 124.209566 -296.249959)
			(xy 124.16355 -296.232507) (xy 124.120929 -296.2079) (xy 124.082808 -296.176775) (xy 124.050173 -296.139938)
			(xy 124.02387 -296.098342) (xy 124.004579 -296.053066) (xy 123.992802 -296.005282) (xy 123.988842 -295.956228)
			(xy 123.660154 -295.956228) (xy 123.659659 -295.980835) (xy 123.651764 -296.029412) (xy 123.63618 -296.076093)
			(xy 123.613309 -296.11967) (xy 123.583744 -296.159014) (xy 123.548251 -296.193106) (xy 123.507748 -296.221062)
			(xy 123.463286 -296.24216) (xy 123.416015 -296.255852) (xy 123.36716 -296.261784) (xy 123.317985 -296.259803)
			(xy 123.269766 -296.249959) (xy 123.22375 -296.232507) (xy 123.181129 -296.2079) (xy 123.143008 -296.176775)
			(xy 123.110373 -296.139938) (xy 123.08407 -296.098342) (xy 123.064779 -296.053066) (xy 123.053002 -296.005282)
			(xy 123.049042 -295.956228) (xy 122.7201 -295.956228) (xy 122.719605 -295.980835) (xy 122.71171 -296.029412)
			(xy 122.696126 -296.076093) (xy 122.673255 -296.11967) (xy 122.64369 -296.159014) (xy 122.608197 -296.193106)
			(xy 122.567694 -296.221062) (xy 122.523232 -296.24216) (xy 122.475961 -296.255852) (xy 122.427106 -296.261784)
			(xy 122.377931 -296.259803) (xy 122.329712 -296.249959) (xy 122.283696 -296.232507) (xy 122.241075 -296.2079)
			(xy 122.202954 -296.176775) (xy 122.170319 -296.139938) (xy 122.144016 -296.098342) (xy 122.124725 -296.053066)
			(xy 122.112948 -296.005282) (xy 122.108988 -295.956228) (xy 121.780046 -295.956228) (xy 121.779551 -295.980835)
			(xy 121.771656 -296.029412) (xy 121.756072 -296.076093) (xy 121.733201 -296.11967) (xy 121.703636 -296.159014)
			(xy 121.668143 -296.193106) (xy 121.62764 -296.221062) (xy 121.583178 -296.24216) (xy 121.535907 -296.255852)
			(xy 121.487052 -296.261784) (xy 121.437877 -296.259803) (xy 121.389658 -296.249959) (xy 121.343642 -296.232507)
			(xy 121.301021 -296.2079) (xy 121.2629 -296.176775) (xy 121.230265 -296.139938) (xy 121.203962 -296.098342)
			(xy 121.184671 -296.053066) (xy 121.172894 -296.005282) (xy 121.168934 -295.956228) (xy 120.839992 -295.956228)
			(xy 120.839497 -295.980835) (xy 120.831602 -296.029412) (xy 120.816018 -296.076093) (xy 120.793147 -296.11967)
			(xy 120.763582 -296.159014) (xy 120.728089 -296.193106) (xy 120.687586 -296.221062) (xy 120.643124 -296.24216)
			(xy 120.595853 -296.255852) (xy 120.546998 -296.261784) (xy 120.497823 -296.259803) (xy 120.449604 -296.249959)
			(xy 120.403588 -296.232507) (xy 120.360967 -296.2079) (xy 120.322846 -296.176775) (xy 120.290211 -296.139938)
			(xy 120.263908 -296.098342) (xy 120.244617 -296.053066) (xy 120.23284 -296.005282) (xy 120.22888 -295.956228)
			(xy 118.960138 -295.956228) (xy 118.959643 -295.980835) (xy 118.951748 -296.029412) (xy 118.936164 -296.076093)
			(xy 118.913293 -296.11967) (xy 118.883728 -296.159014) (xy 118.848235 -296.193106) (xy 118.807732 -296.221062)
			(xy 118.76327 -296.24216) (xy 118.715999 -296.255852) (xy 118.667144 -296.261784) (xy 118.617969 -296.259803)
			(xy 118.56975 -296.249959) (xy 118.523734 -296.232507) (xy 118.481113 -296.2079) (xy 118.442992 -296.176775)
			(xy 118.410357 -296.139938) (xy 118.384054 -296.098342) (xy 118.364763 -296.053066) (xy 118.352986 -296.005282)
			(xy 118.349026 -295.956228) (xy 118.020084 -295.956228) (xy 118.019589 -295.980835) (xy 118.011694 -296.029412)
			(xy 117.99611 -296.076093) (xy 117.973239 -296.11967) (xy 117.943674 -296.159014) (xy 117.908181 -296.193106)
			(xy 117.867678 -296.221062) (xy 117.823216 -296.24216) (xy 117.775945 -296.255852) (xy 117.72709 -296.261784)
			(xy 117.677915 -296.259803) (xy 117.629696 -296.249959) (xy 117.58368 -296.232507) (xy 117.541059 -296.2079)
			(xy 117.502938 -296.176775) (xy 117.470303 -296.139938) (xy 117.444 -296.098342) (xy 117.424709 -296.053066)
			(xy 117.412932 -296.005282) (xy 117.408972 -295.956228) (xy 117.08003 -295.956228) (xy 117.079535 -295.980835)
			(xy 117.07164 -296.029412) (xy 117.056056 -296.076093) (xy 117.033185 -296.11967) (xy 117.00362 -296.159014)
			(xy 116.968127 -296.193106) (xy 116.927624 -296.221062) (xy 116.883162 -296.24216) (xy 116.835891 -296.255852)
			(xy 116.787036 -296.261784) (xy 116.737861 -296.259803) (xy 116.689642 -296.249959) (xy 116.643626 -296.232507)
			(xy 116.601005 -296.2079) (xy 116.562884 -296.176775) (xy 116.530249 -296.139938) (xy 116.503946 -296.098342)
			(xy 116.484655 -296.053066) (xy 116.472878 -296.005282) (xy 116.468918 -295.956228) (xy 116.139976 -295.956228)
			(xy 116.139481 -295.980835) (xy 116.131586 -296.029412) (xy 116.116002 -296.076093) (xy 116.093131 -296.11967)
			(xy 116.063566 -296.159014) (xy 116.028073 -296.193106) (xy 115.98757 -296.221062) (xy 115.943108 -296.24216)
			(xy 115.895837 -296.255852) (xy 115.846982 -296.261784) (xy 115.797807 -296.259803) (xy 115.749588 -296.249959)
			(xy 115.703572 -296.232507) (xy 115.660951 -296.2079) (xy 115.62283 -296.176775) (xy 115.590195 -296.139938)
			(xy 115.563892 -296.098342) (xy 115.544601 -296.053066) (xy 115.532824 -296.005282) (xy 115.528864 -295.956228)
			(xy 115.199922 -295.956228) (xy 115.199427 -295.980835) (xy 115.191532 -296.029412) (xy 115.175948 -296.076093)
			(xy 115.153077 -296.11967) (xy 115.123512 -296.159014) (xy 115.088019 -296.193106) (xy 115.047516 -296.221062)
			(xy 115.003054 -296.24216) (xy 114.955783 -296.255852) (xy 114.906928 -296.261784) (xy 114.857753 -296.259803)
			(xy 114.809534 -296.249959) (xy 114.763518 -296.232507) (xy 114.720897 -296.2079) (xy 114.682776 -296.176775)
			(xy 114.650141 -296.139938) (xy 114.623838 -296.098342) (xy 114.604547 -296.053066) (xy 114.59277 -296.005282)
			(xy 114.58881 -295.956228) (xy 107.687018 -295.956228) (xy 107.682731 -296.007251) (xy 107.669992 -296.056856)
			(xy 107.649158 -296.103641) (xy 107.620814 -296.146297) (xy 107.585754 -296.183628) (xy 107.565698 -296.19956)
			(xy 107.56011 -296.203878) (xy 107.539282 -296.244518) (xy 107.539282 -296.25798) (xy 107.841288 -296.56024)
			(xy 107.86397 -296.58354) (xy 107.904516 -296.634378) (xy 107.939112 -296.689439) (xy 107.967323 -296.748028)
			(xy 107.988794 -296.809409) (xy 108.003255 -296.872808) (xy 108.010523 -296.937428) (xy 108.01096 -296.969942)
			(xy 108.01096 -297.096434) (xy 108.011391 -297.1065) (xy 108.019121 -297.12509) (xy 108.025946 -297.132502)
			(xy 108.32719 -297.433746) (xy 108.33403 -297.441147) (xy 108.34175 -297.459745) (xy 108.342176 -297.469814)
			(xy 108.342176 -299.598291) (xy 112.20805 -299.598291) (xy 112.20805 -299.534369) (xy 112.216061 -299.470951)
			(xy 112.231958 -299.409037) (xy 112.25549 -299.349604) (xy 112.286284 -299.293589) (xy 112.323857 -299.241874)
			(xy 112.367614 -299.195277) (xy 112.416867 -299.154532) (xy 112.470838 -299.120281) (xy 112.528677 -299.093064)
			(xy 112.58947 -299.073311) (xy 112.65226 -299.061333) (xy 112.716056 -299.05732) (xy 112.779852 -299.061333)
			(xy 112.842642 -299.073311) (xy 112.903435 -299.093064) (xy 112.961274 -299.120281) (xy 113.015245 -299.154532)
			(xy 113.064498 -299.195277) (xy 113.108255 -299.241874) (xy 113.145828 -299.293589) (xy 113.176622 -299.349604)
			(xy 113.200154 -299.409037) (xy 113.216051 -299.470951) (xy 113.224062 -299.534369) (xy 113.224564 -299.56633)
			(xy 113.224062 -299.598291) (xy 113.216051 -299.661709) (xy 113.200154 -299.723623) (xy 113.176622 -299.783056)
			(xy 113.145828 -299.839071) (xy 113.108255 -299.890786) (xy 113.064498 -299.937383) (xy 113.015245 -299.978128)
			(xy 112.961274 -300.012379) (xy 112.903435 -300.039596) (xy 112.842642 -300.059349) (xy 112.779852 -300.071327)
			(xy 112.716056 -300.075341) (xy 112.65226 -300.071327) (xy 112.58947 -300.059349) (xy 112.528677 -300.039596)
			(xy 112.470838 -300.012379) (xy 112.416867 -299.978128) (xy 112.367614 -299.937383) (xy 112.323857 -299.890786)
			(xy 112.286284 -299.839071) (xy 112.25549 -299.783056) (xy 112.231958 -299.723623) (xy 112.216061 -299.661709)
			(xy 112.20805 -299.598291) (xy 108.342176 -299.598291) (xy 108.342176 -309.888636) (xy 108.341746 -309.898703)
			(xy 108.334019 -309.917296) (xy 108.32719 -309.924704) (xy 102.59568 -315.656214) (xy 102.588285 -315.663067)
			(xy 102.569686 -315.670807) (xy 102.559612 -315.6712) (xy 97.353882 -315.6712) (xy 97.343813 -315.670773)
			(xy 97.325214 -315.663054) (xy 97.317814 -315.656214) (xy 96.673924 -315.012324) (xy 96.666523 -315.005487)
			(xy 96.647924 -314.997776) (xy 96.637856 -314.997338) (xy 79.596996 -314.997338) (xy 79.58709 -314.998354)
			(xy 77.24394 -315.46419) (xy 77.239876 -315.465206) (xy 73.809098 -316.444376) (xy 73.795128 -316.446408)
			(xy 72.30872 -316.446408) (xy 72.298814 -316.447424) (xy 71.829168 -316.540642) (xy 71.81977 -316.54369)
			(xy 71.579486 -316.643004) (xy 71.460106 -316.69228) (xy 71.456275 -316.694241) (xy 71.449255 -316.69922)
			(xy 71.446136 -316.702186) (xy 65.501266 -322.647056) (xy 65.493868 -322.653902) (xy 65.475269 -322.661631)
			(xy 65.465198 -322.662042) (xy 65.084706 -322.662042) (xy 65.079688 -322.662138) (xy 65.069838 -322.664064)
			(xy 65.065148 -322.665852) (xy 64.183514 -323.031104) (xy 64.178954 -323.033116) (xy 64.170648 -323.038624)
			(xy 64.167004 -323.042026) (xy 63.813436 -323.395594) (xy 63.806034 -323.402431) (xy 63.787436 -323.410143)
			(xy 63.777368 -323.41058) (xy 63.277496 -323.41058) (xy 63.272476 -323.410668) (xy 63.26262 -323.412579)
			(xy 63.257938 -323.41439) (xy 62.588648 -323.691758) (xy 62.553474 -323.705628) (xy 62.480433 -323.725174)
			(xy 62.405473 -323.735067) (xy 62.367668 -323.7357) (xy 60.995814 -323.7357) (xy 60.98762 -323.736007)
			(xy 60.972071 -323.741186) (xy 60.965334 -323.74586) (xy 60.959746 -323.750686) (xy 60.687712 -324.02272)
			(xy 60.684092 -324.02615) (xy 60.675772 -324.031644) (xy 60.671202 -324.033642) (xy 60.662058 -324.037452)
			(xy 60.65393 -324.040754) (xy 58.195972 -326.498712) (xy 58.193265 -326.501562) (xy 58.18867 -326.50794)
			(xy 58.186828 -326.511412) (xy 58.18424 -326.516838) (xy 58.181408 -326.528517) (xy 58.18124 -326.534526)
			(xy 58.18124 -334.34401) (xy 58.182256 -334.353662) (xy 58.183886 -334.360905) (xy 58.190731 -334.37407)
			(xy 58.195718 -334.37957) (xy 58.916824 -335.100676) (xy 58.951114 -335.134712) (xy 58.95721 -335.139612)
			(xy 58.971563 -335.145806) (xy 58.979308 -335.146904)
		)
		(stroke
			(width 0)
			(type solid)
		)
		(fill yes)
		(layer "In2.Cu")
		(net "PVDDCR_CPU1_P1")
	)
	(gr_arc
		(start 0.508 -77.67193)
		(mid 0.621601 -78.242658)
		(end 0.94488 -78.726538)
		(stroke
			(width 0.2)
			(type default)
		)
		(layer "In2.Cu")
	)
	(gr_line
		(start 0.508 -13.780008)
		(end 0.508 -77.67193)
		(stroke
			(width 0.2)
			(type default)
		)
		(layer "In2.Cu")
	)
	(gr_arc
		(start 0.508 -7.78002)
		(mid 0.944996 -8.83502)
		(end 1.999996 -9.272016)
		(stroke
			(width 0.2)
			(type default)
		)
		(layer "In2.Cu")
	)
	(gr_line
		(start 0.508 10.40003)
		(end 0.508 -7.78002)
		(stroke
			(width 0.2)
			(type default)
		)
		(layer "In2.Cu")
	)
	(gr_line
		(start 0.94488 -78.726538)
		(end 1.773428 -79.555086)
		(stroke
			(width 0.2)
			(type default)
		)
		(layer "In2.Cu")
	)
	(gr_arc
		(start 1.999996 -12.288012)
		(mid 0.944996 -12.725008)
		(end 0.508 -13.780008)
		(stroke
			(width 0.2)
			(type default)
		)
		(layer "In2.Cu")
	)
	(gr_line
		(start 1.999996 -9.272016)
		(end 9.10209 -9.272016)
		(stroke
			(width 0.2)
			(type default)
		)
		(layer "In2.Cu")
	)
	(gr_arc
		(start 1.999996 11.892026)
		(mid 0.944996 11.45503)
		(end 0.508 10.40003)
		(stroke
			(width 0.2)
			(type default)
		)
		(layer "In2.Cu")
	)
	(gr_arc
		(start 2.507996 -403.371812)
		(mid 2.621533 -403.942691)
		(end 2.944876 -404.426674)
		(stroke
			(width 0.2)
			(type default)
		)
		(layer "In2.Cu")
	)
	(gr_arc
		(start 2.507996 -81.32826)
		(mid 2.317045 -80.368624)
		(end 1.773428 -79.555086)
		(stroke
			(width 0.2)
			(type default)
		)
		(layer "In2.Cu")
	)
	(gr_line
		(start 2.507996 -81.32826)
		(end 2.507996 -403.371812)
		(stroke
			(width 0.2)
			(type default)
		)
		(layer "In2.Cu")
	)
	(gr_line
		(start 2.944876 -404.426674)
		(end 6.273292 -407.75509)
		(stroke
			(width 0.2)
			(type default)
		)
		(layer "In2.Cu")
	)
	(gr_arc
		(start 7.008114 -439.989976)
		(mid 7.44511 -441.044976)
		(end 8.50011 -441.481972)
		(stroke
			(width 0.2)
			(type default)
		)
		(layer "In2.Cu")
	)
	(gr_arc
		(start 7.008114 -409.528518)
		(mid 6.817049 -408.568734)
		(end 6.273292 -407.75509)
		(stroke
			(width 0.2)
			(type default)
		)
		(layer "In2.Cu")
	)
	(gr_line
		(start 7.008114 -409.528518)
		(end 7.008114 -439.989976)
		(stroke
			(width 0.2)
			(type default)
		)
		(layer "In2.Cu")
	)
	(gr_line
		(start 8.50011 -441.481972)
		(end 194.496944 -441.481972)
		(stroke
			(width 0.2)
			(type default)
		)
		(layer "In2.Cu")
	)
	(gr_arc
		(start 9.10209 -9.272016)
		(mid 10.15709 -8.83502)
		(end 10.594086 -7.78002)
		(stroke
			(width 0.2)
			(type default)
		)
		(layer "In2.Cu")
	)
	(gr_line
		(start 10.263124 -186.749436)
		(end 10.252202 -186.810904)
		(stroke
			(width 0.07112)
			(type default)
		)
		(layer "In2.Cu")
	)
	(gr_line
		(start 10.298684 -186.698382)
		(end 10.263124 -186.749436)
		(stroke
			(width 0.07112)
			(type default)
		)
		(layer "In2.Cu")
	)
	(gr_line
		(start 10.298938 -186.698382)
		(end 10.298684 -186.698382)
		(stroke
			(width 0.07112)
			(type default)
		)
		(layer "In2.Cu")
	)
	(gr_line
		(start 10.594086 -7.78002)
		(end 10.594086 0.40005)
		(stroke
			(width 0.2)
			(type default)
		)
		(layer "In2.Cu")
	)
	(gr_line
		(start 11.001756 -182.790846)
		(end 11.001756 -182.790592)
		(stroke
			(width 0.07112)
			(type default)
		)
		(layer "In2.Cu")
	)
	(gr_line
		(start 11.102086 -12.288012)
		(end 1.999996 -12.288012)
		(stroke
			(width 0.2)
			(type default)
		)
		(layer "In2.Cu")
	)
	(gr_arc
		(start 11.102086 -12.288012)
		(mid 12.875508 -11.553438)
		(end 13.610082 -9.780016)
		(stroke
			(width 0.2)
			(type default)
		)
		(layer "In2.Cu")
	)
	(gr_line
		(start 11.177524 -187.12815)
		(end 11.166602 -187.189618)
		(stroke
			(width 0.07112)
			(type default)
		)
		(layer "In2.Cu")
	)
	(gr_line
		(start 11.213084 -187.077096)
		(end 11.177524 -187.12815)
		(stroke
			(width 0.07112)
			(type default)
		)
		(layer "In2.Cu")
	)
	(gr_line
		(start 11.213338 -187.077096)
		(end 11.213084 -187.077096)
		(stroke
			(width 0.07112)
			(type default)
		)
		(layer "In2.Cu")
	)
	(gr_line
		(start 11.568938 -117.473222)
		(end 12.065 -117.969284)
		(stroke
			(width 0.07112)
			(type default)
		)
		(layer "In2.Cu")
	)
	(gr_line
		(start 11.636248 -114.706908)
		(end 11.939778 -114.403378)
		(stroke
			(width 0.07112)
			(type default)
		)
		(layer "In2.Cu")
	)
	(gr_line
		(start 11.770106 -117.273832)
		(end 11.962384 -117.273832)
		(stroke
			(width 0.07112)
			(type default)
		)
		(layer "In2.Cu")
	)
	(gr_line
		(start 11.962384 -117.273832)
		(end 12.26439 -117.575838)
		(stroke
			(width 0.07112)
			(type default)
		)
		(layer "In2.Cu")
	)
	(gr_line
		(start 12.065 -117.969284)
		(end 11.568938 -117.473222)
		(stroke
			(width 0.07112)
			(type default)
		)
		(layer "In2.Cu")
	)
	(gr_line
		(start 12.222988 -114.430048)
		(end 12.222988 -114.402108)
		(stroke
			(width 0.07112)
			(type default)
		)
		(layer "In2.Cu")
	)
	(gr_line
		(start 12.222988 -114.430048)
		(end 12.499848 -114.706908)
		(stroke
			(width 0.07112)
			(type default)
		)
		(layer "In2.Cu")
	)
	(gr_line
		(start 12.222988 -114.402108)
		(end 12.222988 -114.430048)
		(stroke
			(width 0.07112)
			(type default)
		)
		(layer "In2.Cu")
	)
	(gr_line
		(start 12.26439 -117.575838)
		(end 12.26439 -117.768116)
		(stroke
			(width 0.07112)
			(type default)
		)
		(layer "In2.Cu")
	)
	(gr_line
		(start 12.430252 -118.334536)
		(end 12.926314 -118.830598)
		(stroke
			(width 0.07112)
			(type default)
		)
		(layer "In2.Cu")
	)
	(gr_line
		(start 12.499848 -114.706908)
		(end 12.222988 -114.430048)
		(stroke
			(width 0.07112)
			(type default)
		)
		(layer "In2.Cu")
	)
	(gr_line
		(start 12.63142 -118.135146)
		(end 12.823698 -118.135146)
		(stroke
			(width 0.07112)
			(type default)
		)
		(layer "In2.Cu")
	)
	(gr_line
		(start 12.823698 -118.135146)
		(end 13.125704 -118.437152)
		(stroke
			(width 0.07112)
			(type default)
		)
		(layer "In2.Cu")
	)
	(gr_line
		(start 12.926314 -118.830598)
		(end 12.430252 -118.334536)
		(stroke
			(width 0.07112)
			(type default)
		)
		(layer "In2.Cu")
	)
	(gr_arc
		(start 13.102082 2.908046)
		(mid 11.32866 2.173472)
		(end 10.594086 0.40005)
		(stroke
			(width 0.2)
			(type default)
		)
		(layer "In2.Cu")
	)
	(gr_line
		(start 13.102082 2.908046)
		(end 81.701894 2.908046)
		(stroke
			(width 0.2)
			(type default)
		)
		(layer "In2.Cu")
	)
	(gr_line
		(start 13.125704 -118.437152)
		(end 13.125704 -118.62943)
		(stroke
			(width 0.07112)
			(type default)
		)
		(layer "In2.Cu")
	)
	(gr_line
		(start 13.21435 -360.125772)
		(end 12.92352 -360.416602)
		(stroke
			(width 0.07112)
			(type default)
		)
		(layer "In2.Cu")
	)
	(gr_line
		(start 13.21435 -359.843832)
		(end 12.92352 -359.553002)
		(stroke
			(width 0.07112)
			(type default)
		)
		(layer "In2.Cu")
	)
	(gr_line
		(start 13.470382 -119.518684)
		(end 13.51026 -119.613934)
		(stroke
			(width 0.07112)
			(type default)
		)
		(layer "In2.Cu")
	)
	(gr_line
		(start 13.51026 -119.613934)
		(end 13.470382 -119.518684)
		(stroke
			(width 0.07112)
			(type default)
		)
		(layer "In2.Cu")
	)
	(gr_line
		(start 13.51026 -119.613934)
		(end 13.780516 -120.261126)
		(stroke
			(width 0.07112)
			(type default)
		)
		(layer "In2.Cu")
	)
	(gr_line
		(start 13.610082 -0.508)
		(end 13.610082 -9.780016)
		(stroke
			(width 0.2)
			(type default)
		)
		(layer "In2.Cu")
	)
	(gr_line
		(start 13.730478 -119.409972)
		(end 13.770356 -119.505222)
		(stroke
			(width 0.07112)
			(type default)
		)
		(layer "In2.Cu")
	)
	(gr_line
		(start 13.772134 -119.505984)
		(end 13.949934 -119.578882)
		(stroke
			(width 0.07112)
			(type default)
		)
		(layer "In2.Cu")
	)
	(gr_line
		(start 13.780516 -120.261126)
		(end 13.51026 -119.613934)
		(stroke
			(width 0.07112)
			(type default)
		)
		(layer "In2.Cu")
	)
	(gr_line
		(start 13.780516 -120.261126)
		(end 13.944854 -120.654572)
		(stroke
			(width 0.07112)
			(type default)
		)
		(layer "In2.Cu")
	)
	(gr_line
		(start 13.944854 -120.654572)
		(end 13.780516 -120.261126)
		(stroke
			(width 0.07112)
			(type default)
		)
		(layer "In2.Cu")
	)
	(gr_line
		(start 13.944854 -120.654572)
		(end 14.21511 -121.301764)
		(stroke
			(width 0.07112)
			(type default)
		)
		(layer "In2.Cu")
	)
	(gr_line
		(start 13.949934 -119.578882)
		(end 14.114526 -119.972836)
		(stroke
			(width 0.07112)
			(type default)
		)
		(layer "In2.Cu")
	)
	(gr_line
		(start 14.040612 -120.152414)
		(end 14.20495 -120.546114)
		(stroke
			(width 0.07112)
			(type default)
		)
		(layer "In2.Cu")
	)
	(gr_line
		(start 14.114526 -119.972836)
		(end 14.041374 -120.150636)
		(stroke
			(width 0.07112)
			(type default)
		)
		(layer "In2.Cu")
	)
	(gr_line
		(start 14.206728 -120.546876)
		(end 14.384528 -120.619774)
		(stroke
			(width 0.07112)
			(type default)
		)
		(layer "In2.Cu")
	)
	(gr_line
		(start 14.21511 -121.301764)
		(end 13.944854 -120.654572)
		(stroke
			(width 0.07112)
			(type default)
		)
		(layer "In2.Cu")
	)
	(gr_line
		(start 14.21511 -121.301764)
		(end 14.379448 -121.695464)
		(stroke
			(width 0.07112)
			(type default)
		)
		(layer "In2.Cu")
	)
	(gr_line
		(start 14.379448 -121.695464)
		(end 14.21511 -121.301764)
		(stroke
			(width 0.07112)
			(type default)
		)
		(layer "In2.Cu")
	)
	(gr_line
		(start 14.379448 -121.695464)
		(end 14.649704 -122.34291)
		(stroke
			(width 0.07112)
			(type default)
		)
		(layer "In2.Cu")
	)
	(gr_line
		(start 14.384528 -120.619774)
		(end 14.54912 -121.013728)
		(stroke
			(width 0.07112)
			(type default)
		)
		(layer "In2.Cu")
	)
	(gr_line
		(start 14.475206 -121.193306)
		(end 14.639544 -121.587006)
		(stroke
			(width 0.07112)
			(type default)
		)
		(layer "In2.Cu")
	)
	(gr_line
		(start 14.504924 -176.415954)
		(end 14.773402 -175.768)
		(stroke
			(width 0.07112)
			(type default)
		)
		(layer "In2.Cu")
	)
	(gr_line
		(start 14.54912 -121.013728)
		(end 14.475968 -121.191528)
		(stroke
			(width 0.07112)
			(type default)
		)
		(layer "In2.Cu")
	)
	(gr_line
		(start 14.641322 -121.587768)
		(end 14.819122 -121.660666)
		(stroke
			(width 0.07112)
			(type default)
		)
		(layer "In2.Cu")
	)
	(gr_line
		(start 14.649704 -122.34291)
		(end 14.379448 -121.695464)
		(stroke
			(width 0.07112)
			(type default)
		)
		(layer "In2.Cu")
	)
	(gr_line
		(start 14.649704 -122.34291)
		(end 15.801848 -125.101604)
		(stroke
			(width 0.07112)
			(type default)
		)
		(layer "In2.Cu")
	)
	(gr_line
		(start 14.767052 -176.523396)
		(end 14.945106 -176.449736)
		(stroke
			(width 0.07112)
			(type default)
		)
		(layer "In2.Cu")
	)
	(gr_line
		(start 14.819122 -121.660666)
		(end 14.983714 -122.05462)
		(stroke
			(width 0.07112)
			(type default)
		)
		(layer "In2.Cu")
	)
	(gr_line
		(start 14.9098 -122.234198)
		(end 16.061944 -124.992892)
		(stroke
			(width 0.07112)
			(type default)
		)
		(layer "In2.Cu")
	)
	(gr_line
		(start 14.936724 -175.373792)
		(end 15.205202 -174.725838)
		(stroke
			(width 0.07112)
			(type default)
		)
		(layer "In2.Cu")
	)
	(gr_line
		(start 14.945106 -176.449736)
		(end 15.108428 -176.055274)
		(stroke
			(width 0.07112)
			(type default)
		)
		(layer "In2.Cu")
	)
	(gr_line
		(start 14.983714 -122.05462)
		(end 14.910562 -122.23242)
		(stroke
			(width 0.07112)
			(type default)
		)
		(layer "In2.Cu")
	)
	(gr_line
		(start 15.108428 -176.055274)
		(end 15.034768 -175.87722)
		(stroke
			(width 0.07112)
			(type default)
		)
		(layer "In2.Cu")
	)
	(gr_line
		(start 15.111476 -357.780844)
		(end 14.820646 -358.071674)
		(stroke
			(width 0.07112)
			(type default)
		)
		(layer "In2.Cu")
	)
	(gr_line
		(start 15.111476 -357.498904)
		(end 14.820646 -357.208074)
		(stroke
			(width 0.07112)
			(type default)
		)
		(layer "In2.Cu")
	)
	(gr_line
		(start 15.198852 -175.481234)
		(end 15.376906 -175.407574)
		(stroke
			(width 0.07112)
			(type default)
		)
		(layer "In2.Cu")
	)
	(gr_line
		(start 15.36827 -174.33163)
		(end 15.636748 -173.683676)
		(stroke
			(width 0.07112)
			(type default)
		)
		(layer "In2.Cu")
	)
	(gr_line
		(start 15.376906 -175.407574)
		(end 15.540228 -175.013112)
		(stroke
			(width 0.07112)
			(type default)
		)
		(layer "In2.Cu")
	)
	(gr_line
		(start 15.540228 -175.013112)
		(end 15.466568 -174.834804)
		(stroke
			(width 0.07112)
			(type default)
		)
		(layer "In2.Cu")
	)
	(gr_line
		(start 15.630398 -174.439072)
		(end 15.808706 -174.365412)
		(stroke
			(width 0.07112)
			(type default)
		)
		(layer "In2.Cu")
	)
	(gr_line
		(start 15.80007 -173.289468)
		(end 16.068548 -172.641514)
		(stroke
			(width 0.07112)
			(type default)
		)
		(layer "In2.Cu")
	)
	(gr_line
		(start 15.801848 -125.101604)
		(end 14.649704 -122.34291)
		(stroke
			(width 0.07112)
			(type default)
		)
		(layer "In2.Cu")
	)
	(gr_line
		(start 15.808706 -174.365412)
		(end 15.972028 -173.97095)
		(stroke
			(width 0.07112)
			(type default)
		)
		(layer "In2.Cu")
	)
	(gr_line
		(start 15.972028 -173.97095)
		(end 15.898114 -173.792388)
		(stroke
			(width 0.07112)
			(type default)
		)
		(layer "In2.Cu")
	)
	(gr_line
		(start 16.061944 -173.39691)
		(end 16.240506 -173.32325)
		(stroke
			(width 0.07112)
			(type default)
		)
		(layer "In2.Cu")
	)
	(gr_line
		(start 16.231616 -172.247306)
		(end 16.500094 -171.599098)
		(stroke
			(width 0.07112)
			(type default)
		)
		(layer "In2.Cu")
	)
	(gr_line
		(start 16.240506 -173.32325)
		(end 16.403828 -172.928788)
		(stroke
			(width 0.07112)
			(type default)
		)
		(layer "In2.Cu")
	)
	(gr_line
		(start 16.403828 -172.928788)
		(end 16.329914 -172.750226)
		(stroke
			(width 0.07112)
			(type default)
		)
		(layer "In2.Cu")
	)
	(gr_line
		(start 16.493744 -172.354748)
		(end 16.672306 -172.281088)
		(stroke
			(width 0.07112)
			(type default)
		)
		(layer "In2.Cu")
	)
	(gr_line
		(start 16.500094 -161.722816)
		(end 16.490696 -161.753296)
		(stroke
			(width 0.07112)
			(type default)
		)
		(layer "In2.Cu")
	)
	(gr_line
		(start 16.50238 -161.691066)
		(end 16.500094 -161.722816)
		(stroke
			(width 0.07112)
			(type default)
		)
		(layer "In2.Cu")
	)
	(gr_line
		(start 16.50238 -161.690812)
		(end 16.50238 -161.691066)
		(stroke
			(width 0.07112)
			(type default)
		)
		(layer "In2.Cu")
	)
	(gr_line
		(start 16.672306 -172.281088)
		(end 16.835628 -171.886626)
		(stroke
			(width 0.07112)
			(type default)
		)
		(layer "In2.Cu")
	)
	(gr_line
		(start 16.835628 -171.886626)
		(end 16.76146 -171.708318)
		(stroke
			(width 0.07112)
			(type default)
		)
		(layer "In2.Cu")
	)
	(gr_line
		(start 20.353274 -418.7952)
		(end 21.054314 -418.7952)
		(stroke
			(width 0.07112)
			(type default)
		)
		(layer "In2.Cu")
	)
	(gr_line
		(start 20.354544 -418.51199)
		(end 20.490434 -418.3761)
		(stroke
			(width 0.07112)
			(type default)
		)
		(layer "In2.Cu")
	)
	(gr_line
		(start 20.490434 -418.3761)
		(end 20.917154 -418.3761)
		(stroke
			(width 0.07112)
			(type default)
		)
		(layer "In2.Cu")
	)
	(gr_line
		(start 20.560792 -133.480302)
		(end 20.915122 -133.125972)
		(stroke
			(width 0.07112)
			(type default)
		)
		(layer "In2.Cu")
	)
	(gr_line
		(start 20.560792 -132.489702)
		(end 20.915122 -132.844032)
		(stroke
			(width 0.07112)
			(type default)
		)
		(layer "In2.Cu")
	)
	(gr_line
		(start 20.917154 -418.3761)
		(end 21.053044 -418.51199)
		(stroke
			(width 0.07112)
			(type default)
		)
		(layer "In2.Cu")
	)
	(gr_line
		(start 21.054314 -418.7952)
		(end 20.353274 -418.7952)
		(stroke
			(width 0.07112)
			(type default)
		)
		(layer "In2.Cu")
	)
	(gr_line
		(start 21.481034 -418.7952)
		(end 22.182074 -418.7952)
		(stroke
			(width 0.07112)
			(type default)
		)
		(layer "In2.Cu")
	)
	(gr_line
		(start 21.482304 -418.51199)
		(end 21.618194 -418.3761)
		(stroke
			(width 0.07112)
			(type default)
		)
		(layer "In2.Cu")
	)
	(gr_line
		(start 21.618194 -418.3761)
		(end 22.044914 -418.3761)
		(stroke
			(width 0.07112)
			(type default)
		)
		(layer "In2.Cu")
	)
	(gr_line
		(start 22.044914 -418.3761)
		(end 22.180804 -418.51199)
		(stroke
			(width 0.07112)
			(type default)
		)
		(layer "In2.Cu")
	)
	(gr_line
		(start 22.182074 -418.7952)
		(end 21.481034 -418.7952)
		(stroke
			(width 0.07112)
			(type default)
		)
		(layer "In2.Cu")
	)
	(gr_line
		(start 23.833328 -418.209984)
		(end 23.833328 -418.017706)
		(stroke
			(width 0.07112)
			(type default)
		)
		(layer "In2.Cu")
	)
	(gr_line
		(start 23.833328 -418.017706)
		(end 24.135334 -417.7157)
		(stroke
			(width 0.07112)
			(type default)
		)
		(layer "In2.Cu")
	)
	(gr_line
		(start 24.032718 -418.411152)
		(end 24.52878 -417.91509)
		(stroke
			(width 0.07112)
			(type default)
		)
		(layer "In2.Cu")
	)
	(gr_line
		(start 24.127968 -427.35246)
		(end 24.127968 -428.0535)
		(stroke
			(width 0.07112)
			(type default)
		)
		(layer "In2.Cu")
	)
	(gr_line
		(start 24.127968 -426.2247)
		(end 24.127968 -426.92574)
		(stroke
			(width 0.07112)
			(type default)
		)
		(layer "In2.Cu")
	)
	(gr_line
		(start 24.127968 -425.09694)
		(end 24.127968 -425.79798)
		(stroke
			(width 0.07112)
			(type default)
		)
		(layer "In2.Cu")
	)
	(gr_line
		(start 24.135334 -417.7157)
		(end 24.327612 -417.7157)
		(stroke
			(width 0.07112)
			(type default)
		)
		(layer "In2.Cu")
	)
	(gr_line
		(start 24.411178 -427.35373)
		(end 24.547068 -427.48962)
		(stroke
			(width 0.07112)
			(type default)
		)
		(layer "In2.Cu")
	)
	(gr_line
		(start 24.411178 -426.22597)
		(end 24.547068 -426.36186)
		(stroke
			(width 0.07112)
			(type default)
		)
		(layer "In2.Cu")
	)
	(gr_line
		(start 24.411178 -425.09821)
		(end 24.547068 -425.2341)
		(stroke
			(width 0.07112)
			(type default)
		)
		(layer "In2.Cu")
	)
	(gr_line
		(start 24.52878 -417.91509)
		(end 24.032718 -418.411152)
		(stroke
			(width 0.07112)
			(type default)
		)
		(layer "In2.Cu")
	)
	(gr_line
		(start 24.547068 -427.91634)
		(end 24.411178 -428.05223)
		(stroke
			(width 0.07112)
			(type default)
		)
		(layer "In2.Cu")
	)
	(gr_line
		(start 24.547068 -427.48962)
		(end 24.547068 -427.91634)
		(stroke
			(width 0.07112)
			(type default)
		)
		(layer "In2.Cu")
	)
	(gr_line
		(start 24.547068 -426.78858)
		(end 24.411178 -426.92447)
		(stroke
			(width 0.07112)
			(type default)
		)
		(layer "In2.Cu")
	)
	(gr_line
		(start 24.547068 -426.36186)
		(end 24.547068 -426.78858)
		(stroke
			(width 0.07112)
			(type default)
		)
		(layer "In2.Cu")
	)
	(gr_line
		(start 24.547068 -425.66082)
		(end 24.411178 -425.79671)
		(stroke
			(width 0.07112)
			(type default)
		)
		(layer "In2.Cu")
	)
	(gr_line
		(start 24.547068 -425.2341)
		(end 24.547068 -425.66082)
		(stroke
			(width 0.07112)
			(type default)
		)
		(layer "In2.Cu")
	)
	(gr_line
		(start 26.276554 -419.350444)
		(end 26.140664 -419.214554)
		(stroke
			(width 0.07112)
			(type default)
		)
		(layer "In2.Cu")
	)
	(gr_line
		(start 26.703274 -419.350444)
		(end 26.276554 -419.350444)
		(stroke
			(width 0.07112)
			(type default)
		)
		(layer "In2.Cu")
	)
	(gr_line
		(start 26.839164 -419.214554)
		(end 26.703274 -419.350444)
		(stroke
			(width 0.07112)
			(type default)
		)
		(layer "In2.Cu")
	)
	(gr_line
		(start 26.840434 -418.931344)
		(end 26.139394 -418.931344)
		(stroke
			(width 0.07112)
			(type default)
		)
		(layer "In2.Cu")
	)
	(gr_line
		(start 27.452828 -419.350444)
		(end 27.316938 -419.214554)
		(stroke
			(width 0.07112)
			(type default)
		)
		(layer "In2.Cu")
	)
	(gr_line
		(start 27.510232 -417.174172)
		(end 28.211272 -417.174172)
		(stroke
			(width 0.07112)
			(type default)
		)
		(layer "In2.Cu")
	)
	(gr_line
		(start 27.511502 -416.890962)
		(end 27.647392 -416.755072)
		(stroke
			(width 0.07112)
			(type default)
		)
		(layer "In2.Cu")
	)
	(gr_line
		(start 27.613356 -428.474632)
		(end 27.322526 -428.183802)
		(stroke
			(width 0.07112)
			(type default)
		)
		(layer "In2.Cu")
	)
	(gr_line
		(start 27.647392 -416.755072)
		(end 28.074112 -416.755072)
		(stroke
			(width 0.07112)
			(type default)
		)
		(layer "In2.Cu")
	)
	(gr_line
		(start 27.704542 -421.69969)
		(end 27.995372 -421.99052)
		(stroke
			(width 0.07112)
			(type default)
		)
		(layer "In2.Cu")
	)
	(gr_line
		(start 27.879548 -419.350444)
		(end 27.452828 -419.350444)
		(stroke
			(width 0.07112)
			(type default)
		)
		(layer "In2.Cu")
	)
	(gr_line
		(start 27.895296 -428.474632)
		(end 28.186126 -428.183802)
		(stroke
			(width 0.07112)
			(type default)
		)
		(layer "In2.Cu")
	)
	(gr_line
		(start 28.015438 -419.214554)
		(end 27.879548 -419.350444)
		(stroke
			(width 0.07112)
			(type default)
		)
		(layer "In2.Cu")
	)
	(gr_line
		(start 28.016708 -418.931344)
		(end 27.315668 -418.931344)
		(stroke
			(width 0.07112)
			(type default)
		)
		(layer "In2.Cu")
	)
	(gr_line
		(start 28.074112 -416.755072)
		(end 28.210002 -416.890962)
		(stroke
			(width 0.07112)
			(type default)
		)
		(layer "In2.Cu")
	)
	(gr_line
		(start 28.211272 -417.174172)
		(end 27.510232 -417.174172)
		(stroke
			(width 0.07112)
			(type default)
		)
		(layer "In2.Cu")
	)
	(gr_line
		(start 28.568142 -421.69969)
		(end 28.277312 -421.99052)
		(stroke
			(width 0.07112)
			(type default)
		)
		(layer "In2.Cu")
	)
	(gr_line
		(start 28.637992 -417.174172)
		(end 29.339032 -417.174172)
		(stroke
			(width 0.07112)
			(type default)
		)
		(layer "In2.Cu")
	)
	(gr_line
		(start 28.639262 -416.890962)
		(end 28.775152 -416.755072)
		(stroke
			(width 0.07112)
			(type default)
		)
		(layer "In2.Cu")
	)
	(gr_line
		(start 28.732734 -145.958814)
		(end 29.305504 -145.558002)
		(stroke
			(width 0.07112)
			(type default)
		)
		(layer "In2.Cu")
	)
	(gr_line
		(start 28.775152 -416.755072)
		(end 29.201872 -416.755072)
		(stroke
			(width 0.07112)
			(type default)
		)
		(layer "In2.Cu")
	)
	(gr_line
		(start 28.894532 -419.350444)
		(end 28.758642 -419.214554)
		(stroke
			(width 0.07112)
			(type default)
		)
		(layer "In2.Cu")
	)
	(gr_line
		(start 28.896056 -146.190462)
		(end 29.086048 -146.223736)
		(stroke
			(width 0.07112)
			(type default)
		)
		(layer "In2.Cu")
	)
	(gr_line
		(start 29.008324 -374.762776)
		(end 29.008578 -374.762776)
		(stroke
			(width 0.07112)
			(type default)
		)
		(layer "In2.Cu")
	)
	(gr_line
		(start 29.086048 -146.223736)
		(end 29.433774 -145.980404)
		(stroke
			(width 0.07112)
			(type default)
		)
		(layer "In2.Cu")
	)
	(gr_line
		(start 29.201872 -416.755072)
		(end 29.337762 -416.890962)
		(stroke
			(width 0.07112)
			(type default)
		)
		(layer "In2.Cu")
	)
	(gr_line
		(start 29.321252 -419.350444)
		(end 28.894532 -419.350444)
		(stroke
			(width 0.07112)
			(type default)
		)
		(layer "In2.Cu")
	)
	(gr_line
		(start 29.339032 -417.174172)
		(end 28.637992 -417.174172)
		(stroke
			(width 0.07112)
			(type default)
		)
		(layer "In2.Cu")
	)
	(gr_line
		(start 29.433774 -145.980404)
		(end 29.467048 -145.790666)
		(stroke
			(width 0.07112)
			(type default)
		)
		(layer "In2.Cu")
	)
	(gr_line
		(start 29.457142 -419.214554)
		(end 29.321252 -419.350444)
		(stroke
			(width 0.07112)
			(type default)
		)
		(layer "In2.Cu")
	)
	(gr_line
		(start 29.458412 -418.931344)
		(end 28.757372 -418.931344)
		(stroke
			(width 0.07112)
			(type default)
		)
		(layer "In2.Cu")
	)
	(gr_line
		(start 29.652722 -145.314924)
		(end 30.225238 -144.913858)
		(stroke
			(width 0.07112)
			(type default)
		)
		(layer "In2.Cu")
	)
	(gr_line
		(start 29.765752 -417.174172)
		(end 30.466792 -417.174172)
		(stroke
			(width 0.07112)
			(type default)
		)
		(layer "In2.Cu")
	)
	(gr_line
		(start 29.767022 -416.890962)
		(end 29.902912 -416.755072)
		(stroke
			(width 0.07112)
			(type default)
		)
		(layer "In2.Cu")
	)
	(gr_line
		(start 29.81579 -145.546318)
		(end 30.005782 -145.579592)
		(stroke
			(width 0.07112)
			(type default)
		)
		(layer "In2.Cu")
	)
	(gr_line
		(start 29.902912 -416.755072)
		(end 30.329632 -416.755072)
		(stroke
			(width 0.07112)
			(type default)
		)
		(layer "In2.Cu")
	)
	(gr_line
		(start 30.005782 -145.579592)
		(end 30.353508 -145.336006)
		(stroke
			(width 0.07112)
			(type default)
		)
		(layer "In2.Cu")
	)
	(gr_line
		(start 30.022292 -419.350444)
		(end 29.886402 -419.214554)
		(stroke
			(width 0.07112)
			(type default)
		)
		(layer "In2.Cu")
	)
	(gr_line
		(start 30.329632 -416.755072)
		(end 30.465522 -416.890962)
		(stroke
			(width 0.07112)
			(type default)
		)
		(layer "In2.Cu")
	)
	(gr_line
		(start 30.353508 -145.336006)
		(end 30.386782 -145.146522)
		(stroke
			(width 0.07112)
			(type default)
		)
		(layer "In2.Cu")
	)
	(gr_line
		(start 30.449012 -419.350444)
		(end 30.022292 -419.350444)
		(stroke
			(width 0.07112)
			(type default)
		)
		(layer "In2.Cu")
	)
	(gr_line
		(start 30.466792 -417.174172)
		(end 29.765752 -417.174172)
		(stroke
			(width 0.07112)
			(type default)
		)
		(layer "In2.Cu")
	)
	(gr_line
		(start 30.572456 -144.67078)
		(end 31.144972 -144.269968)
		(stroke
			(width 0.07112)
			(type default)
		)
		(layer "In2.Cu")
	)
	(gr_line
		(start 30.584902 -419.214554)
		(end 30.449012 -419.350444)
		(stroke
			(width 0.07112)
			(type default)
		)
		(layer "In2.Cu")
	)
	(gr_line
		(start 30.586172 -418.931344)
		(end 29.885132 -418.931344)
		(stroke
			(width 0.07112)
			(type default)
		)
		(layer "In2.Cu")
	)
	(gr_line
		(start 30.735778 -144.902174)
		(end 30.925516 -144.935448)
		(stroke
			(width 0.07112)
			(type default)
		)
		(layer "In2.Cu")
	)
	(gr_line
		(start 30.893512 -417.174172)
		(end 31.594552 -417.174172)
		(stroke
			(width 0.07112)
			(type default)
		)
		(layer "In2.Cu")
	)
	(gr_line
		(start 30.894782 -416.890962)
		(end 31.030672 -416.755072)
		(stroke
			(width 0.07112)
			(type default)
		)
		(layer "In2.Cu")
	)
	(gr_line
		(start 30.925516 -144.935448)
		(end 31.273242 -144.691862)
		(stroke
			(width 0.07112)
			(type default)
		)
		(layer "In2.Cu")
	)
	(gr_line
		(start 31.030672 -416.755072)
		(end 31.457392 -416.755072)
		(stroke
			(width 0.07112)
			(type default)
		)
		(layer "In2.Cu")
	)
	(gr_line
		(start 31.273242 -144.691862)
		(end 31.306516 -144.502632)
		(stroke
			(width 0.07112)
			(type default)
		)
		(layer "In2.Cu")
	)
	(gr_line
		(start 31.457392 -416.755072)
		(end 31.593282 -416.890962)
		(stroke
			(width 0.07112)
			(type default)
		)
		(layer "In2.Cu")
	)
	(gr_line
		(start 31.497016 -380.032768)
		(end 31.497016 -380.033022)
		(stroke
			(width 0.07112)
			(type default)
		)
		(layer "In2.Cu")
	)
	(gr_line
		(start 31.498032 -419.350444)
		(end 31.362142 -419.214554)
		(stroke
			(width 0.07112)
			(type default)
		)
		(layer "In2.Cu")
	)
	(gr_line
		(start 31.594552 -417.174172)
		(end 30.893512 -417.174172)
		(stroke
			(width 0.07112)
			(type default)
		)
		(layer "In2.Cu")
	)
	(gr_line
		(start 31.924752 -419.350444)
		(end 31.498032 -419.350444)
		(stroke
			(width 0.07112)
			(type default)
		)
		(layer "In2.Cu")
	)
	(gr_line
		(start 32.021272 -417.174172)
		(end 32.722312 -417.174172)
		(stroke
			(width 0.07112)
			(type default)
		)
		(layer "In2.Cu")
	)
	(gr_line
		(start 32.022542 -416.890962)
		(end 32.158432 -416.755072)
		(stroke
			(width 0.07112)
			(type default)
		)
		(layer "In2.Cu")
	)
	(gr_line
		(start 32.060642 -419.214554)
		(end 31.924752 -419.350444)
		(stroke
			(width 0.07112)
			(type default)
		)
		(layer "In2.Cu")
	)
	(gr_line
		(start 32.061912 -418.931344)
		(end 31.360872 -418.931344)
		(stroke
			(width 0.07112)
			(type default)
		)
		(layer "In2.Cu")
	)
	(gr_line
		(start 32.158432 -416.755072)
		(end 32.585152 -416.755072)
		(stroke
			(width 0.07112)
			(type default)
		)
		(layer "In2.Cu")
	)
	(gr_line
		(start 32.585152 -416.755072)
		(end 32.721042 -416.890962)
		(stroke
			(width 0.07112)
			(type default)
		)
		(layer "In2.Cu")
	)
	(gr_line
		(start 32.625792 -419.350444)
		(end 32.489902 -419.214554)
		(stroke
			(width 0.07112)
			(type default)
		)
		(layer "In2.Cu")
	)
	(gr_line
		(start 32.722312 -417.174172)
		(end 32.021272 -417.174172)
		(stroke
			(width 0.07112)
			(type default)
		)
		(layer "In2.Cu")
	)
	(gr_line
		(start 33.052512 -419.350444)
		(end 32.625792 -419.350444)
		(stroke
			(width 0.07112)
			(type default)
		)
		(layer "In2.Cu")
	)
	(gr_line
		(start 33.188402 -419.214554)
		(end 33.052512 -419.350444)
		(stroke
			(width 0.07112)
			(type default)
		)
		(layer "In2.Cu")
	)
	(gr_line
		(start 33.189672 -418.931344)
		(end 32.488632 -418.931344)
		(stroke
			(width 0.07112)
			(type default)
		)
		(layer "In2.Cu")
	)
	(gr_line
		(start 33.753552 -419.350444)
		(end 33.617662 -419.214554)
		(stroke
			(width 0.07112)
			(type default)
		)
		(layer "In2.Cu")
	)
	(gr_line
		(start 34.180272 -419.350444)
		(end 33.753552 -419.350444)
		(stroke
			(width 0.07112)
			(type default)
		)
		(layer "In2.Cu")
	)
	(gr_line
		(start 34.316162 -419.214554)
		(end 34.180272 -419.350444)
		(stroke
			(width 0.07112)
			(type default)
		)
		(layer "In2.Cu")
	)
	(gr_line
		(start 34.317432 -418.931344)
		(end 33.616392 -418.931344)
		(stroke
			(width 0.07112)
			(type default)
		)
		(layer "In2.Cu")
	)
	(gr_line
		(start 35.923474 -417.174172)
		(end 36.214304 -417.465002)
		(stroke
			(width 0.07112)
			(type default)
		)
		(layer "In2.Cu")
	)
	(gr_line
		(start 35.923474 -416.892232)
		(end 36.214304 -416.601402)
		(stroke
			(width 0.07112)
			(type default)
		)
		(layer "In2.Cu")
	)
	(gr_line
		(start 36.214304 -417.465002)
		(end 35.923474 -417.174172)
		(stroke
			(width 0.07112)
			(type default)
		)
		(layer "In2.Cu")
	)
	(gr_line
		(start 36.773104 -419.350444)
		(end 36.637214 -419.214554)
		(stroke
			(width 0.07112)
			(type default)
		)
		(layer "In2.Cu")
	)
	(gr_line
		(start 37.199824 -419.350444)
		(end 36.773104 -419.350444)
		(stroke
			(width 0.07112)
			(type default)
		)
		(layer "In2.Cu")
	)
	(gr_line
		(start 37.335714 -419.214554)
		(end 37.199824 -419.350444)
		(stroke
			(width 0.07112)
			(type default)
		)
		(layer "In2.Cu")
	)
	(gr_line
		(start 37.336984 -418.931344)
		(end 36.635944 -418.931344)
		(stroke
			(width 0.07112)
			(type default)
		)
		(layer "In2.Cu")
	)
	(gr_line
		(start 38.477444 -419.350444)
		(end 38.341554 -419.214554)
		(stroke
			(width 0.07112)
			(type default)
		)
		(layer "In2.Cu")
	)
	(gr_line
		(start 38.904164 -419.350444)
		(end 38.477444 -419.350444)
		(stroke
			(width 0.07112)
			(type default)
		)
		(layer "In2.Cu")
	)
	(gr_line
		(start 39.040054 -419.214554)
		(end 38.904164 -419.350444)
		(stroke
			(width 0.07112)
			(type default)
		)
		(layer "In2.Cu")
	)
	(gr_line
		(start 39.041324 -418.931344)
		(end 38.340284 -418.931344)
		(stroke
			(width 0.07112)
			(type default)
		)
		(layer "In2.Cu")
	)
	(gr_line
		(start 40.761158 -418.114226)
		(end 40.56888 -418.114226)
		(stroke
			(width 0.07112)
			(type default)
		)
		(layer "In2.Cu")
	)
	(gr_line
		(start 40.863774 -417.418774)
		(end 40.367712 -417.914836)
		(stroke
			(width 0.07112)
			(type default)
		)
		(layer "In2.Cu")
	)
	(gr_line
		(start 41.063164 -417.81222)
		(end 40.761158 -418.114226)
		(stroke
			(width 0.07112)
			(type default)
		)
		(layer "In2.Cu")
	)
	(gr_line
		(start 41.063164 -417.619942)
		(end 41.063164 -417.81222)
		(stroke
			(width 0.07112)
			(type default)
		)
		(layer "In2.Cu")
	)
	(gr_line
		(start 41.283636 -419.99789)
		(end 41.283636 -419.805866)
		(stroke
			(width 0.07112)
			(type default)
		)
		(layer "In2.Cu")
	)
	(gr_line
		(start 41.283636 -419.805866)
		(end 41.585642 -419.50386)
		(stroke
			(width 0.07112)
			(type default)
		)
		(layer "In2.Cu")
	)
	(gr_line
		(start 41.483026 -420.199058)
		(end 41.978834 -419.70325)
		(stroke
			(width 0.07112)
			(type default)
		)
		(layer "In2.Cu")
	)
	(gr_line
		(start 41.558718 -417.316666)
		(end 41.36644 -417.316666)
		(stroke
			(width 0.07112)
			(type default)
		)
		(layer "In2.Cu")
	)
	(gr_line
		(start 41.585642 -419.50386)
		(end 41.777666 -419.50386)
		(stroke
			(width 0.07112)
			(type default)
		)
		(layer "In2.Cu")
	)
	(gr_line
		(start 41.661334 -416.621214)
		(end 41.165272 -417.117276)
		(stroke
			(width 0.07112)
			(type default)
		)
		(layer "In2.Cu")
	)
	(gr_line
		(start 41.860724 -417.01466)
		(end 41.558718 -417.316666)
		(stroke
			(width 0.07112)
			(type default)
		)
		(layer "In2.Cu")
	)
	(gr_line
		(start 41.860724 -416.822382)
		(end 41.860724 -417.01466)
		(stroke
			(width 0.07112)
			(type default)
		)
		(layer "In2.Cu")
	)
	(gr_line
		(start 42.080942 -419.200584)
		(end 42.080942 -419.008306)
		(stroke
			(width 0.07112)
			(type default)
		)
		(layer "In2.Cu")
	)
	(gr_line
		(start 42.080942 -419.008306)
		(end 42.382948 -418.7063)
		(stroke
			(width 0.07112)
			(type default)
		)
		(layer "In2.Cu")
	)
	(gr_line
		(start 42.280332 -419.401752)
		(end 42.776394 -418.90569)
		(stroke
			(width 0.07112)
			(type default)
		)
		(layer "In2.Cu")
	)
	(gr_line
		(start 42.356278 -416.519106)
		(end 42.164 -416.519106)
		(stroke
			(width 0.07112)
			(type default)
		)
		(layer "In2.Cu")
	)
	(gr_line
		(start 42.382948 -418.7063)
		(end 42.575226 -418.7063)
		(stroke
			(width 0.07112)
			(type default)
		)
		(layer "In2.Cu")
	)
	(gr_line
		(start 42.458894 -415.823654)
		(end 41.962832 -416.319716)
		(stroke
			(width 0.07112)
			(type default)
		)
		(layer "In2.Cu")
	)
	(gr_line
		(start 42.658284 -416.2171)
		(end 42.356278 -416.519106)
		(stroke
			(width 0.07112)
			(type default)
		)
		(layer "In2.Cu")
	)
	(gr_line
		(start 42.658284 -416.024822)
		(end 42.658284 -416.2171)
		(stroke
			(width 0.07112)
			(type default)
		)
		(layer "In2.Cu")
	)
	(gr_line
		(start 43.153838 -415.721546)
		(end 42.96156 -415.721546)
		(stroke
			(width 0.07112)
			(type default)
		)
		(layer "In2.Cu")
	)
	(gr_line
		(start 43.256454 -415.026094)
		(end 42.760392 -415.522156)
		(stroke
			(width 0.07112)
			(type default)
		)
		(layer "In2.Cu")
	)
	(gr_line
		(start 43.455844 -415.41954)
		(end 43.153838 -415.721546)
		(stroke
			(width 0.07112)
			(type default)
		)
		(layer "In2.Cu")
	)
	(gr_line
		(start 43.455844 -415.227262)
		(end 43.455844 -415.41954)
		(stroke
			(width 0.07112)
			(type default)
		)
		(layer "In2.Cu")
	)
	(gr_line
		(start 43.951398 -414.923986)
		(end 43.75912 -414.923986)
		(stroke
			(width 0.07112)
			(type default)
		)
		(layer "In2.Cu")
	)
	(gr_line
		(start 44.054014 -414.228534)
		(end 43.557952 -414.724596)
		(stroke
			(width 0.07112)
			(type default)
		)
		(layer "In2.Cu")
	)
	(gr_line
		(start 44.253404 -414.62198)
		(end 43.951398 -414.923986)
		(stroke
			(width 0.07112)
			(type default)
		)
		(layer "In2.Cu")
	)
	(gr_line
		(start 44.253404 -414.429702)
		(end 44.253404 -414.62198)
		(stroke
			(width 0.07112)
			(type default)
		)
		(layer "In2.Cu")
	)
	(gr_line
		(start 49.194466 -417.436808)
		(end 49.485296 -417.145978)
		(stroke
			(width 0.07112)
			(type default)
		)
		(layer "In2.Cu")
	)
	(gr_line
		(start 49.194466 -416.573208)
		(end 49.485296 -416.864038)
		(stroke
			(width 0.07112)
			(type default)
		)
		(layer "In2.Cu")
	)
	(gr_line
		(start 52.191666 -419.64102)
		(end 52.514246 -419.31844)
		(stroke
			(width 0.07112)
			(type default)
		)
		(layer "In2.Cu")
	)
	(gr_line
		(start 52.191666 -418.77742)
		(end 52.449476 -419.03523)
		(stroke
			(width 0.07112)
			(type default)
		)
		(layer "In2.Cu")
	)
	(gr_line
		(start 52.449476 -419.03523)
		(end 52.515516 -419.03523)
		(stroke
			(width 0.07112)
			(type default)
		)
		(layer "In2.Cu")
	)
	(gr_line
		(start 52.514246 -419.31844)
		(end 52.191666 -419.64102)
		(stroke
			(width 0.07112)
			(type default)
		)
		(layer "In2.Cu")
	)
	(gr_line
		(start 54.37251 -416.864038)
		(end 55.07355 -416.864038)
		(stroke
			(width 0.07112)
			(type default)
		)
		(layer "In2.Cu")
	)
	(gr_line
		(start 54.37378 -417.147248)
		(end 54.50967 -417.283138)
		(stroke
			(width 0.07112)
			(type default)
		)
		(layer "In2.Cu")
	)
	(gr_line
		(start 54.50967 -417.283138)
		(end 54.93639 -417.283138)
		(stroke
			(width 0.07112)
			(type default)
		)
		(layer "In2.Cu")
	)
	(gr_line
		(start 54.93639 -417.283138)
		(end 55.07228 -417.147248)
		(stroke
			(width 0.07112)
			(type default)
		)
		(layer "In2.Cu")
	)
	(gr_line
		(start 55.88127 -419.34892)
		(end 56.58231 -419.34892)
		(stroke
			(width 0.07112)
			(type default)
		)
		(layer "In2.Cu")
	)
	(gr_line
		(start 55.88254 -419.63213)
		(end 56.01843 -419.76802)
		(stroke
			(width 0.07112)
			(type default)
		)
		(layer "In2.Cu")
	)
	(gr_line
		(start 56.01843 -419.76802)
		(end 55.88254 -419.63213)
		(stroke
			(width 0.07112)
			(type default)
		)
		(layer "In2.Cu")
	)
	(gr_line
		(start 56.01843 -419.76802)
		(end 56.44515 -419.76802)
		(stroke
			(width 0.07112)
			(type default)
		)
		(layer "In2.Cu")
	)
	(gr_line
		(start 56.44515 -419.76802)
		(end 56.01843 -419.76802)
		(stroke
			(width 0.07112)
			(type default)
		)
		(layer "In2.Cu")
	)
	(gr_line
		(start 56.44515 -419.76802)
		(end 56.58104 -419.63213)
		(stroke
			(width 0.07112)
			(type default)
		)
		(layer "In2.Cu")
	)
	(gr_line
		(start 56.58104 -419.63213)
		(end 56.44515 -419.76802)
		(stroke
			(width 0.07112)
			(type default)
		)
		(layer "In2.Cu")
	)
	(gr_line
		(start 58.190892 -419.63086)
		(end 58.64987 -420.089838)
		(stroke
			(width 0.07112)
			(type default)
		)
		(layer "In2.Cu")
	)
	(gr_line
		(start 58.190892 -419.34892)
		(end 58.64987 -418.889942)
		(stroke
			(width 0.07112)
			(type default)
		)
		(layer "In2.Cu")
	)
	(gr_line
		(start 58.64987 -420.089838)
		(end 58.190892 -419.63086)
		(stroke
			(width 0.07112)
			(type default)
		)
		(layer "In2.Cu")
	)
	(gr_line
		(start 59.332368 -323.156326)
		(end 59.33313 -323.156326)
		(stroke
			(width 0.07112)
			(type default)
		)
		(layer "In2.Cu")
	)
	(gr_line
		(start 59.33313 -323.156326)
		(end 59.3344 -323.156326)
		(stroke
			(width 0.07112)
			(type default)
		)
		(layer "In2.Cu")
	)
	(gr_line
		(start 59.336178 -322.190364)
		(end 59.33694 -322.190364)
		(stroke
			(width 0.07112)
			(type default)
		)
		(layer "In2.Cu")
	)
	(gr_line
		(start 59.33694 -322.190364)
		(end 59.33821 -322.190364)
		(stroke
			(width 0.07112)
			(type default)
		)
		(layer "In2.Cu")
	)
	(gr_line
		(start 59.340242 -321.200526)
		(end 59.341004 -321.200526)
		(stroke
			(width 0.07112)
			(type default)
		)
		(layer "In2.Cu")
	)
	(gr_line
		(start 59.341004 -321.200526)
		(end 59.342274 -321.200526)
		(stroke
			(width 0.07112)
			(type default)
		)
		(layer "In2.Cu")
	)
	(gr_line
		(start 59.344052 -320.241422)
		(end 59.344814 -320.241422)
		(stroke
			(width 0.07112)
			(type default)
		)
		(layer "In2.Cu")
	)
	(gr_line
		(start 59.344814 -320.241422)
		(end 59.346084 -320.241422)
		(stroke
			(width 0.07112)
			(type default)
		)
		(layer "In2.Cu")
	)
	(gr_line
		(start 60.190888 -420.630858)
		(end 60.649866 -421.089836)
		(stroke
			(width 0.07112)
			(type default)
		)
		(layer "In2.Cu")
	)
	(gr_line
		(start 60.190888 -420.348918)
		(end 60.649866 -419.88994)
		(stroke
			(width 0.07112)
			(type default)
		)
		(layer "In2.Cu")
	)
	(gr_line
		(start 61.821314 -403.08784)
		(end 61.687964 -402.95449)
		(stroke
			(width 0.07112)
			(type default)
		)
		(layer "In2.Cu")
	)
	(gr_line
		(start 62.248034 -403.08784)
		(end 61.821314 -403.08784)
		(stroke
			(width 0.07112)
			(type default)
		)
		(layer "In2.Cu")
	)
	(gr_line
		(start 62.381384 -402.95449)
		(end 62.248034 -403.08784)
		(stroke
			(width 0.07112)
			(type default)
		)
		(layer "In2.Cu")
	)
	(gr_line
		(start 62.382654 -402.67128)
		(end 61.686694 -402.67128)
		(stroke
			(width 0.07112)
			(type default)
		)
		(layer "In2.Cu")
	)
	(gr_line
		(start 64.737742 -403.08784)
		(end 64.604392 -402.95449)
		(stroke
			(width 0.07112)
			(type default)
		)
		(layer "In2.Cu")
	)
	(gr_line
		(start 65.164462 -403.08784)
		(end 64.737742 -403.08784)
		(stroke
			(width 0.07112)
			(type default)
		)
		(layer "In2.Cu")
	)
	(gr_line
		(start 65.297812 -402.95449)
		(end 65.164462 -403.08784)
		(stroke
			(width 0.07112)
			(type default)
		)
		(layer "In2.Cu")
	)
	(gr_line
		(start 65.299082 -402.67128)
		(end 64.603122 -402.67128)
		(stroke
			(width 0.07112)
			(type default)
		)
		(layer "In2.Cu")
	)
	(gr_line
		(start 66.312796 -403.08784)
		(end 66.179446 -402.95449)
		(stroke
			(width 0.07112)
			(type default)
		)
		(layer "In2.Cu")
	)
	(gr_line
		(start 66.739516 -403.08784)
		(end 66.312796 -403.08784)
		(stroke
			(width 0.07112)
			(type default)
		)
		(layer "In2.Cu")
	)
	(gr_line
		(start 66.872866 -402.95449)
		(end 66.739516 -403.08784)
		(stroke
			(width 0.07112)
			(type default)
		)
		(layer "In2.Cu")
	)
	(gr_line
		(start 66.874136 -402.67128)
		(end 66.178176 -402.67128)
		(stroke
			(width 0.07112)
			(type default)
		)
		(layer "In2.Cu")
	)
	(gr_line
		(start 68.128642 -403.08784)
		(end 67.995292 -402.95449)
		(stroke
			(width 0.07112)
			(type default)
		)
		(layer "In2.Cu")
	)
	(gr_line
		(start 68.186554 -420.3446)
		(end 68.19519 -420.3446)
		(stroke
			(width 0.07112)
			(type default)
		)
		(layer "In2.Cu")
	)
	(gr_line
		(start 68.187824 -420.62781)
		(end 68.64985 -421.089836)
		(stroke
			(width 0.07112)
			(type default)
		)
		(layer "In2.Cu")
	)
	(gr_line
		(start 68.19519 -420.3446)
		(end 68.64985 -419.88994)
		(stroke
			(width 0.07112)
			(type default)
		)
		(layer "In2.Cu")
	)
	(gr_line
		(start 68.555362 -403.08784)
		(end 68.128642 -403.08784)
		(stroke
			(width 0.07112)
			(type default)
		)
		(layer "In2.Cu")
	)
	(gr_line
		(start 68.64985 -424.689778)
		(end 69.108828 -424.2308)
		(stroke
			(width 0.07112)
			(type default)
		)
		(layer "In2.Cu")
	)
	(gr_line
		(start 68.64985 -423.489882)
		(end 69.108828 -423.94886)
		(stroke
			(width 0.07112)
			(type default)
		)
		(layer "In2.Cu")
	)
	(gr_line
		(start 68.688712 -402.95449)
		(end 68.555362 -403.08784)
		(stroke
			(width 0.07112)
			(type default)
		)
		(layer "In2.Cu")
	)
	(gr_line
		(start 68.689982 -402.67128)
		(end 67.994022 -402.67128)
		(stroke
			(width 0.07112)
			(type default)
		)
		(layer "In2.Cu")
	)
	(gr_line
		(start 69.58076 -417.13277)
		(end 69.744082 -416.738308)
		(stroke
			(width 0.07112)
			(type default)
		)
		(layer "In2.Cu")
	)
	(gr_line
		(start 69.65442 -417.31057)
		(end 69.58076 -417.13277)
		(stroke
			(width 0.07112)
			(type default)
		)
		(layer "In2.Cu")
	)
	(gr_line
		(start 69.744082 -416.738308)
		(end 69.921882 -416.664648)
		(stroke
			(width 0.07112)
			(type default)
		)
		(layer "In2.Cu")
	)
	(gr_line
		(start 69.915532 -417.41979)
		(end 70.18401 -416.771582)
		(stroke
			(width 0.07112)
			(type default)
		)
		(layer "In2.Cu")
	)
	(gr_line
		(start 69.92366 -416.663886)
		(end 70.02145 -416.427666)
		(stroke
			(width 0.07112)
			(type default)
		)
		(layer "In2.Cu")
	)
	(gr_line
		(start 70.01256 -416.090608)
		(end 70.175882 -415.696146)
		(stroke
			(width 0.07112)
			(type default)
		)
		(layer "In2.Cu")
	)
	(gr_line
		(start 70.085966 -416.268154)
		(end 70.01256 -416.090608)
		(stroke
			(width 0.07112)
			(type default)
		)
		(layer "In2.Cu")
	)
	(gr_line
		(start 70.175882 -415.696146)
		(end 70.353428 -415.622486)
		(stroke
			(width 0.07112)
			(type default)
		)
		(layer "In2.Cu")
	)
	(gr_line
		(start 70.347332 -416.377374)
		(end 70.61581 -415.72942)
		(stroke
			(width 0.07112)
			(type default)
		)
		(layer "In2.Cu")
	)
	(gr_line
		(start 70.355206 -415.621724)
		(end 70.370192 -415.585656)
		(stroke
			(width 0.07112)
			(type default)
		)
		(layer "In2.Cu")
	)
	(gr_line
		(start 70.444106 -415.048446)
		(end 70.607428 -414.653984)
		(stroke
			(width 0.07112)
			(type default)
		)
		(layer "In2.Cu")
	)
	(gr_line
		(start 70.517766 -415.225992)
		(end 70.444106 -415.048446)
		(stroke
			(width 0.07112)
			(type default)
		)
		(layer "In2.Cu")
	)
	(gr_line
		(start 70.607428 -414.653984)
		(end 70.785228 -414.580324)
		(stroke
			(width 0.07112)
			(type default)
		)
		(layer "In2.Cu")
	)
	(gr_line
		(start 70.61581 -415.72942)
		(end 70.630542 -415.693352)
		(stroke
			(width 0.07112)
			(type default)
		)
		(layer "In2.Cu")
	)
	(gr_line
		(start 70.649846 -423.68978)
		(end 71.108824 -423.230802)
		(stroke
			(width 0.07112)
			(type default)
		)
		(layer "In2.Cu")
	)
	(gr_line
		(start 70.649846 -422.489884)
		(end 71.108824 -422.948862)
		(stroke
			(width 0.07112)
			(type default)
		)
		(layer "In2.Cu")
	)
	(gr_line
		(start 70.778878 -415.335466)
		(end 71.047356 -414.687512)
		(stroke
			(width 0.07112)
			(type default)
		)
		(layer "In2.Cu")
	)
	(gr_line
		(start 71.079868 -403.08784)
		(end 70.946518 -402.95449)
		(stroke
			(width 0.07112)
			(type default)
		)
		(layer "In2.Cu")
	)
	(gr_line
		(start 71.149718 -316.084712)
		(end 71.149718 -316.084966)
		(stroke
			(width 0.07112)
			(type default)
		)
		(layer "In2.Cu")
	)
	(gr_line
		(start 71.506588 -403.08784)
		(end 71.079868 -403.08784)
		(stroke
			(width 0.07112)
			(type default)
		)
		(layer "In2.Cu")
	)
	(gr_line
		(start 71.639938 -402.95449)
		(end 71.506588 -403.08784)
		(stroke
			(width 0.07112)
			(type default)
		)
		(layer "In2.Cu")
	)
	(gr_line
		(start 71.641208 -402.67128)
		(end 70.945248 -402.67128)
		(stroke
			(width 0.07112)
			(type default)
		)
		(layer "In2.Cu")
	)
	(gr_line
		(start 72.649842 -424.689778)
		(end 73.10882 -424.2308)
		(stroke
			(width 0.07112)
			(type default)
		)
		(layer "In2.Cu")
	)
	(gr_line
		(start 72.649842 -423.489882)
		(end 73.10882 -423.94886)
		(stroke
			(width 0.07112)
			(type default)
		)
		(layer "In2.Cu")
	)
	(gr_line
		(start 74.197972 -312.620406)
		(end 74.304652 -312.460386)
		(stroke
			(width 0.07112)
			(type default)
		)
		(layer "In2.Cu")
	)
	(gr_line
		(start 74.25182 -312.898536)
		(end 74.939652 -312.76163)
		(stroke
			(width 0.07112)
			(type default)
		)
		(layer "In2.Cu")
	)
	(gr_line
		(start 74.304652 -312.460386)
		(end 74.723498 -312.377074)
		(stroke
			(width 0.07112)
			(type default)
		)
		(layer "In2.Cu")
	)
	(gr_line
		(start 74.690986 -315.09335)
		(end 74.697844 -315.09208)
		(stroke
			(width 0.07112)
			(type default)
		)
		(layer "In2.Cu")
	)
	(gr_line
		(start 74.69886 -315.090556)
		(end 74.80554 -314.930536)
		(stroke
			(width 0.07112)
			(type default)
		)
		(layer "In2.Cu")
	)
	(gr_line
		(start 74.723498 -312.377074)
		(end 74.883772 -312.484008)
		(stroke
			(width 0.07112)
			(type default)
		)
		(layer "In2.Cu")
	)
	(gr_line
		(start 74.746104 -315.369956)
		(end 74.752708 -315.368686)
		(stroke
			(width 0.07112)
			(type default)
		)
		(layer "In2.Cu")
	)
	(gr_line
		(start 74.752708 -315.368686)
		(end 75.44054 -315.23178)
		(stroke
			(width 0.07112)
			(type default)
		)
		(layer "In2.Cu")
	)
	(gr_line
		(start 74.80554 -314.930536)
		(end 75.224386 -314.847224)
		(stroke
			(width 0.07112)
			(type default)
		)
		(layer "In2.Cu")
	)
	(gr_line
		(start 75.224386 -314.847224)
		(end 75.38466 -314.954158)
		(stroke
			(width 0.07112)
			(type default)
		)
		(layer "In2.Cu")
	)
	(gr_line
		(start 75.303888 -312.400442)
		(end 75.410822 -312.240168)
		(stroke
			(width 0.07112)
			(type default)
		)
		(layer "In2.Cu")
	)
	(gr_line
		(start 75.35799 -312.678318)
		(end 76.046076 -312.541666)
		(stroke
			(width 0.07112)
			(type default)
		)
		(layer "In2.Cu")
	)
	(gr_line
		(start 75.410822 -312.240168)
		(end 75.829668 -312.156856)
		(stroke
			(width 0.07112)
			(type default)
		)
		(layer "In2.Cu")
	)
	(gr_line
		(start 75.804776 -314.870592)
		(end 75.911964 -314.710318)
		(stroke
			(width 0.07112)
			(type default)
		)
		(layer "In2.Cu")
	)
	(gr_line
		(start 75.829668 -312.156856)
		(end 75.989942 -312.264044)
		(stroke
			(width 0.07112)
			(type default)
		)
		(layer "In2.Cu")
	)
	(gr_line
		(start 75.858878 -315.148722)
		(end 76.54671 -315.011816)
		(stroke
			(width 0.07112)
			(type default)
		)
		(layer "In2.Cu")
	)
	(gr_line
		(start 75.911964 -314.710318)
		(end 76.330556 -314.62726)
		(stroke
			(width 0.07112)
			(type default)
		)
		(layer "In2.Cu")
	)
	(gr_line
		(start 76.330556 -314.62726)
		(end 76.49083 -314.734194)
		(stroke
			(width 0.07112)
			(type default)
		)
		(layer "In2.Cu")
	)
	(gr_line
		(start 76.410058 -312.180478)
		(end 76.516992 -312.01995)
		(stroke
			(width 0.07112)
			(type default)
		)
		(layer "In2.Cu")
	)
	(gr_line
		(start 76.46416 -312.458354)
		(end 77.152246 -312.321448)
		(stroke
			(width 0.07112)
			(type default)
		)
		(layer "In2.Cu")
	)
	(gr_line
		(start 76.516992 -312.01995)
		(end 76.935838 -311.936638)
		(stroke
			(width 0.07112)
			(type default)
		)
		(layer "In2.Cu")
	)
	(gr_line
		(start 76.910946 -314.650882)
		(end 77.018134 -314.490354)
		(stroke
			(width 0.07112)
			(type default)
		)
		(layer "In2.Cu")
	)
	(gr_line
		(start 76.935838 -311.936638)
		(end 77.096366 -312.043826)
		(stroke
			(width 0.07112)
			(type default)
		)
		(layer "In2.Cu")
	)
	(gr_line
		(start 76.965048 -314.928758)
		(end 77.65288 -314.792106)
		(stroke
			(width 0.07112)
			(type default)
		)
		(layer "In2.Cu")
	)
	(gr_line
		(start 77.018134 -314.490354)
		(end 77.436726 -314.407296)
		(stroke
			(width 0.07112)
			(type default)
		)
		(layer "In2.Cu")
	)
	(gr_line
		(start 77.436726 -314.407296)
		(end 77.597 -314.514484)
		(stroke
			(width 0.07112)
			(type default)
		)
		(layer "In2.Cu")
	)
	(gr_line
		(start 77.540104 -311.955434)
		(end 77.647546 -311.794906)
		(stroke
			(width 0.07112)
			(type default)
		)
		(layer "In2.Cu")
	)
	(gr_line
		(start 77.594714 -312.233564)
		(end 78.282546 -312.096658)
		(stroke
			(width 0.07112)
			(type default)
		)
		(layer "In2.Cu")
	)
	(gr_line
		(start 77.647546 -311.794906)
		(end 78.066138 -311.711594)
		(stroke
			(width 0.07112)
			(type default)
		)
		(layer "In2.Cu")
	)
	(gr_line
		(start 78.062328 -314.421774)
		(end 78.169516 -314.2615)
		(stroke
			(width 0.07112)
			(type default)
		)
		(layer "In2.Cu")
	)
	(gr_line
		(start 78.066138 -311.711594)
		(end 78.22692 -311.819036)
		(stroke
			(width 0.07112)
			(type default)
		)
		(layer "In2.Cu")
	)
	(gr_line
		(start 78.11643 -314.699904)
		(end 78.804516 -314.562998)
		(stroke
			(width 0.07112)
			(type default)
		)
		(layer "In2.Cu")
	)
	(gr_line
		(start 78.169516 -314.2615)
		(end 78.588108 -314.178188)
		(stroke
			(width 0.07112)
			(type default)
		)
		(layer "In2.Cu")
	)
	(gr_line
		(start 78.588108 -314.178188)
		(end 78.748382 -314.285376)
		(stroke
			(width 0.07112)
			(type default)
		)
		(layer "In2.Cu")
	)
	(gr_line
		(start 78.760574 -311.712864)
		(end 78.867762 -311.551828)
		(stroke
			(width 0.07112)
			(type default)
		)
		(layer "In2.Cu")
	)
	(gr_line
		(start 78.815184 -311.99074)
		(end 79.503016 -311.853834)
		(stroke
			(width 0.07112)
			(type default)
		)
		(layer "In2.Cu")
	)
	(gr_line
		(start 78.867762 -311.551828)
		(end 79.286608 -311.46877)
		(stroke
			(width 0.07112)
			(type default)
		)
		(layer "In2.Cu")
	)
	(gr_line
		(start 79.286608 -311.46877)
		(end 79.44739 -311.576212)
		(stroke
			(width 0.07112)
			(type default)
		)
		(layer "In2.Cu")
	)
	(gr_line
		(start 79.864966 -309.213758)
		(end 79.574136 -309.504588)
		(stroke
			(width 0.07112)
			(type default)
		)
		(layer "In2.Cu")
	)
	(gr_line
		(start 79.864966 -308.931818)
		(end 79.574136 -308.640988)
		(stroke
			(width 0.07112)
			(type default)
		)
		(layer "In2.Cu")
	)
	(gr_line
		(start 79.866744 -311.492646)
		(end 79.974186 -311.331864)
		(stroke
			(width 0.07112)
			(type default)
		)
		(layer "In2.Cu")
	)
	(gr_line
		(start 79.921354 -311.770522)
		(end 80.609186 -311.633616)
		(stroke
			(width 0.07112)
			(type default)
		)
		(layer "In2.Cu")
	)
	(gr_line
		(start 79.974186 -311.331864)
		(end 80.392778 -311.248552)
		(stroke
			(width 0.07112)
			(type default)
		)
		(layer "In2.Cu")
	)
	(gr_line
		(start 80.392778 -311.248552)
		(end 80.553306 -311.355994)
		(stroke
			(width 0.07112)
			(type default)
		)
		(layer "In2.Cu")
	)
	(gr_line
		(start 80.972914 -311.272682)
		(end 81.080356 -311.1119)
		(stroke
			(width 0.07112)
			(type default)
		)
		(layer "In2.Cu")
	)
	(gr_line
		(start 81.027524 -311.550558)
		(end 81.715356 -311.413652)
		(stroke
			(width 0.07112)
			(type default)
		)
		(layer "In2.Cu")
	)
	(gr_line
		(start 81.080356 -311.1119)
		(end 81.498948 -311.028588)
		(stroke
			(width 0.07112)
			(type default)
		)
		(layer "In2.Cu")
	)
	(gr_line
		(start 81.193894 -9.780016)
		(end 81.193894 -0.508)
		(stroke
			(width 0.2)
			(type default)
		)
		(layer "In2.Cu")
	)
	(gr_arc
		(start 81.193894 -9.780016)
		(mid 81.928474 -11.55343)
		(end 83.70189 -12.288012)
		(stroke
			(width 0.2)
			(type default)
		)
		(layer "In2.Cu")
	)
	(gr_line
		(start 81.193894 -0.508)
		(end 13.610082 -0.508)
		(stroke
			(width 0.2)
			(type default)
		)
		(layer "In2.Cu")
	)
	(gr_line
		(start 81.498948 -311.028588)
		(end 81.659476 -311.13603)
		(stroke
			(width 0.07112)
			(type default)
		)
		(layer "In2.Cu")
	)
	(gr_line
		(start 81.660238 -311.136538)
		(end 81.660492 -311.136538)
		(stroke
			(width 0.07112)
			(type default)
		)
		(layer "In2.Cu")
	)
	(gr_line
		(start 81.715356 -311.413652)
		(end 81.715356 -311.413144)
		(stroke
			(width 0.07112)
			(type default)
		)
		(layer "In2.Cu")
	)
	(gr_line
		(start 82.443574 -313.646566)
		(end 82.666332 -313.624722)
		(stroke
			(width 0.07112)
			(type default)
		)
		(layer "In2.Cu")
	)
	(gr_line
		(start 82.471006 -313.927236)
		(end 82.694018 -313.905392)
		(stroke
			(width 0.07112)
			(type default)
		)
		(layer "In2.Cu")
	)
	(gr_line
		(start 82.667602 -313.623198)
		(end 82.789522 -313.474354)
		(stroke
			(width 0.07112)
			(type default)
		)
		(layer "In2.Cu")
	)
	(gr_line
		(start 82.694018 -313.905392)
		(end 83.39201 -313.836558)
		(stroke
			(width 0.07112)
			(type default)
		)
		(layer "In2.Cu")
	)
	(gr_line
		(start 82.789522 -313.474354)
		(end 83.214464 -313.432698)
		(stroke
			(width 0.07112)
			(type default)
		)
		(layer "In2.Cu")
	)
	(gr_line
		(start 83.214464 -313.432698)
		(end 83.363308 -313.554872)
		(stroke
			(width 0.07112)
			(type default)
		)
		(layer "In2.Cu")
	)
	(gr_arc
		(start 84.20989 -7.78002)
		(mid 84.646886 -8.83502)
		(end 85.701886 -9.272016)
		(stroke
			(width 0.2)
			(type default)
		)
		(layer "In2.Cu")
	)
	(gr_arc
		(start 84.20989 0.40005)
		(mid 83.475332 2.173501)
		(end 81.701894 2.908046)
		(stroke
			(width 0.2)
			(type default)
		)
		(layer "In2.Cu")
	)
	(gr_line
		(start 84.20989 0.40005)
		(end 84.20989 -7.78002)
		(stroke
			(width 0.2)
			(type default)
		)
		(layer "In2.Cu")
	)
	(gr_line
		(start 85.136736 -307.125624)
		(end 85.192108 -307.310028)
		(stroke
			(width 0.07112)
			(type default)
		)
		(layer "In2.Cu")
	)
	(gr_line
		(start 85.31733 -400.572986)
		(end 85.18144 -400.437096)
		(stroke
			(width 0.07112)
			(type default)
		)
		(layer "In2.Cu")
	)
	(gr_line
		(start 85.33892 -306.749704)
		(end 85.136736 -307.125624)
		(stroke
			(width 0.07112)
			(type default)
		)
		(layer "In2.Cu")
	)
	(gr_line
		(start 85.523324 -306.694332)
		(end 85.33892 -306.749704)
		(stroke
			(width 0.07112)
			(type default)
		)
		(layer "In2.Cu")
	)
	(gr_line
		(start 85.670898 -306.13223)
		(end 85.72627 -306.316634)
		(stroke
			(width 0.07112)
			(type default)
		)
		(layer "In2.Cu")
	)
	(gr_line
		(start 85.701886 -9.272016)
		(end 122.102118 -9.272016)
		(stroke
			(width 0.2)
			(type default)
		)
		(layer "In2.Cu")
	)
	(gr_line
		(start 85.74405 -400.572986)
		(end 85.31733 -400.572986)
		(stroke
			(width 0.07112)
			(type default)
		)
		(layer "In2.Cu")
	)
	(gr_line
		(start 85.77326 -306.827428)
		(end 85.441028 -307.445156)
		(stroke
			(width 0.07112)
			(type default)
		)
		(layer "In2.Cu")
	)
	(gr_line
		(start 85.873082 -305.75631)
		(end 85.670898 -306.13223)
		(stroke
			(width 0.07112)
			(type default)
		)
		(layer "In2.Cu")
	)
	(gr_line
		(start 85.87994 -400.437096)
		(end 85.74405 -400.572986)
		(stroke
			(width 0.07112)
			(type default)
		)
		(layer "In2.Cu")
	)
	(gr_line
		(start 85.88121 -400.153886)
		(end 85.18017 -400.153886)
		(stroke
			(width 0.07112)
			(type default)
		)
		(layer "In2.Cu")
	)
	(gr_line
		(start 85.981794 -313.296808)
		(end 86.103968 -313.147964)
		(stroke
			(width 0.07112)
			(type default)
		)
		(layer "In2.Cu")
	)
	(gr_line
		(start 86.008464 -313.578748)
		(end 86.706456 -313.509914)
		(stroke
			(width 0.07112)
			(type default)
		)
		(layer "In2.Cu")
	)
	(gr_line
		(start 86.057486 -305.700938)
		(end 85.873082 -305.75631)
		(stroke
			(width 0.07112)
			(type default)
		)
		(layer "In2.Cu")
	)
	(gr_line
		(start 86.103968 -313.147964)
		(end 86.528656 -313.106054)
		(stroke
			(width 0.07112)
			(type default)
		)
		(layer "In2.Cu")
	)
	(gr_line
		(start 86.20506 -305.138836)
		(end 86.260432 -305.32324)
		(stroke
			(width 0.07112)
			(type default)
		)
		(layer "In2.Cu")
	)
	(gr_line
		(start 86.300818 -403.09038)
		(end 86.164928 -402.95449)
		(stroke
			(width 0.07112)
			(type default)
		)
		(layer "In2.Cu")
	)
	(gr_line
		(start 86.307422 -305.834034)
		(end 85.97519 -306.451762)
		(stroke
			(width 0.07112)
			(type default)
		)
		(layer "In2.Cu")
	)
	(gr_line
		(start 86.407244 -304.762916)
		(end 86.20506 -305.138836)
		(stroke
			(width 0.07112)
			(type default)
		)
		(layer "In2.Cu")
	)
	(gr_line
		(start 86.44509 -400.572986)
		(end 86.3092 -400.437096)
		(stroke
			(width 0.07112)
			(type default)
		)
		(layer "In2.Cu")
	)
	(gr_line
		(start 86.528656 -313.106054)
		(end 86.677754 -313.228228)
		(stroke
			(width 0.07112)
			(type default)
		)
		(layer "In2.Cu")
	)
	(gr_line
		(start 86.591648 -304.707544)
		(end 86.407244 -304.762916)
		(stroke
			(width 0.07112)
			(type default)
		)
		(layer "In2.Cu")
	)
	(gr_line
		(start 86.727538 -403.09038)
		(end 86.300818 -403.09038)
		(stroke
			(width 0.07112)
			(type default)
		)
		(layer "In2.Cu")
	)
	(gr_line
		(start 86.841584 -304.84064)
		(end 86.509352 -305.458368)
		(stroke
			(width 0.07112)
			(type default)
		)
		(layer "In2.Cu")
	)
	(gr_line
		(start 86.841584 -304.840386)
		(end 86.841584 -304.84064)
		(stroke
			(width 0.07112)
			(type default)
		)
		(layer "In2.Cu")
	)
	(gr_line
		(start 86.863428 -402.95449)
		(end 86.727538 -403.09038)
		(stroke
			(width 0.07112)
			(type default)
		)
		(layer "In2.Cu")
	)
	(gr_line
		(start 86.864698 -402.67128)
		(end 86.163658 -402.67128)
		(stroke
			(width 0.07112)
			(type default)
		)
		(layer "In2.Cu")
	)
	(gr_line
		(start 86.87181 -400.572986)
		(end 86.44509 -400.572986)
		(stroke
			(width 0.07112)
			(type default)
		)
		(layer "In2.Cu")
	)
	(gr_line
		(start 87.0077 -400.437096)
		(end 86.87181 -400.572986)
		(stroke
			(width 0.07112)
			(type default)
		)
		(layer "In2.Cu")
	)
	(gr_line
		(start 87.00897 -400.153886)
		(end 86.30793 -400.153886)
		(stroke
			(width 0.07112)
			(type default)
		)
		(layer "In2.Cu")
	)
	(gr_line
		(start 87.57285 -400.572986)
		(end 87.43696 -400.437096)
		(stroke
			(width 0.07112)
			(type default)
		)
		(layer "In2.Cu")
	)
	(gr_line
		(start 87.99957 -400.572986)
		(end 87.57285 -400.572986)
		(stroke
			(width 0.07112)
			(type default)
		)
		(layer "In2.Cu")
	)
	(gr_line
		(start 88.039956 -300.65853)
		(end 88.039956 -300.658784)
		(stroke
			(width 0.07112)
			(type default)
		)
		(layer "In2.Cu")
	)
	(gr_line
		(start 88.040718 -300.65726)
		(end 88.12276 -300.48327)
		(stroke
			(width 0.07112)
			(type default)
		)
		(layer "In2.Cu")
	)
	(gr_line
		(start 88.12276 -300.48327)
		(end 88.524842 -300.339506)
		(stroke
			(width 0.07112)
			(type default)
		)
		(layer "In2.Cu")
	)
	(gr_line
		(start 88.134952 -300.924214)
		(end 88.795098 -300.687994)
		(stroke
			(width 0.07112)
			(type default)
		)
		(layer "In2.Cu")
	)
	(gr_line
		(start 88.13546 -400.437096)
		(end 87.99957 -400.572986)
		(stroke
			(width 0.07112)
			(type default)
		)
		(layer "In2.Cu")
	)
	(gr_line
		(start 88.13673 -400.153886)
		(end 87.43569 -400.153886)
		(stroke
			(width 0.07112)
			(type default)
		)
		(layer "In2.Cu")
	)
	(gr_line
		(start 88.156034 -303.223168)
		(end 88.118188 -303.41189)
		(stroke
			(width 0.07112)
			(type default)
		)
		(layer "In2.Cu")
	)
	(gr_line
		(start 88.387428 -311.584594)
		(end 88.501728 -311.429908)
		(stroke
			(width 0.07112)
			(type default)
		)
		(layer "In2.Cu")
	)
	(gr_line
		(start 88.427814 -311.864756)
		(end 89.121488 -311.761886)
		(stroke
			(width 0.07112)
			(type default)
		)
		(layer "In2.Cu")
	)
	(gr_line
		(start 88.501728 -311.429908)
		(end 88.92413 -311.36717)
		(stroke
			(width 0.07112)
			(type default)
		)
		(layer "In2.Cu")
	)
	(gr_line
		(start 88.511126 -302.986186)
		(end 88.156034 -303.223168)
		(stroke
			(width 0.07112)
			(type default)
		)
		(layer "In2.Cu")
	)
	(gr_line
		(start 88.524842 -300.339506)
		(end 88.698578 -300.421802)
		(stroke
			(width 0.07112)
			(type default)
		)
		(layer "In2.Cu")
	)
	(gr_line
		(start 88.699848 -303.024032)
		(end 88.511126 -302.986186)
		(stroke
			(width 0.07112)
			(type default)
		)
		(layer "In2.Cu")
	)
	(gr_line
		(start 88.70061 -400.572986)
		(end 88.56472 -400.437096)
		(stroke
			(width 0.07112)
			(type default)
		)
		(layer "In2.Cu")
	)
	(gr_line
		(start 88.857836 -303.258982)
		(end 88.274398 -303.64811)
		(stroke
			(width 0.07112)
			(type default)
		)
		(layer "In2.Cu")
	)
	(gr_line
		(start 88.92413 -311.36717)
		(end 89.07907 -311.481978)
		(stroke
			(width 0.07112)
			(type default)
		)
		(layer "In2.Cu")
	)
	(gr_line
		(start 89.126822 -300.26864)
		(end 89.208864 -300.094396)
		(stroke
			(width 0.07112)
			(type default)
		)
		(layer "In2.Cu")
	)
	(gr_line
		(start 89.12733 -400.572986)
		(end 88.70061 -400.572986)
		(stroke
			(width 0.07112)
			(type default)
		)
		(layer "In2.Cu")
	)
	(gr_line
		(start 89.208864 -300.094396)
		(end 89.610946 -299.950632)
		(stroke
			(width 0.07112)
			(type default)
		)
		(layer "In2.Cu")
	)
	(gr_line
		(start 89.221056 -300.535594)
		(end 89.881202 -300.299374)
		(stroke
			(width 0.07112)
			(type default)
		)
		(layer "In2.Cu")
	)
	(gr_line
		(start 89.26322 -400.437096)
		(end 89.12733 -400.572986)
		(stroke
			(width 0.07112)
			(type default)
		)
		(layer "In2.Cu")
	)
	(gr_line
		(start 89.26449 -400.153886)
		(end 88.56345 -400.153886)
		(stroke
			(width 0.07112)
			(type default)
		)
		(layer "In2.Cu")
	)
	(gr_line
		(start 89.486486 -403.09038)
		(end 89.350596 -402.95449)
		(stroke
			(width 0.07112)
			(type default)
		)
		(layer "In2.Cu")
	)
	(gr_line
		(start 89.502996 -311.418986)
		(end 89.61755 -311.2643)
		(stroke
			(width 0.07112)
			(type default)
		)
		(layer "In2.Cu")
	)
	(gr_line
		(start 89.543382 -311.699402)
		(end 90.237056 -311.596532)
		(stroke
			(width 0.07112)
			(type default)
		)
		(layer "In2.Cu")
	)
	(gr_line
		(start 89.610946 -299.950632)
		(end 89.784936 -300.033182)
		(stroke
			(width 0.07112)
			(type default)
		)
		(layer "In2.Cu")
	)
	(gr_line
		(start 89.61755 -311.2643)
		(end 90.039698 -311.201562)
		(stroke
			(width 0.07112)
			(type default)
		)
		(layer "In2.Cu")
	)
	(gr_line
		(start 89.913206 -403.09038)
		(end 89.486486 -403.09038)
		(stroke
			(width 0.07112)
			(type default)
		)
		(layer "In2.Cu")
	)
	(gr_line
		(start 90.039698 -311.201562)
		(end 90.194638 -311.31637)
		(stroke
			(width 0.07112)
			(type default)
		)
		(layer "In2.Cu")
	)
	(gr_line
		(start 90.049096 -402.95449)
		(end 89.913206 -403.09038)
		(stroke
			(width 0.07112)
			(type default)
		)
		(layer "In2.Cu")
	)
	(gr_line
		(start 90.050366 -402.67128)
		(end 89.349326 -402.67128)
		(stroke
			(width 0.07112)
			(type default)
		)
		(layer "In2.Cu")
	)
	(gr_line
		(start 90.096848 -400.572986)
		(end 89.960958 -400.437096)
		(stroke
			(width 0.07112)
			(type default)
		)
		(layer "In2.Cu")
	)
	(gr_line
		(start 90.21445 -299.879512)
		(end 90.296746 -299.705268)
		(stroke
			(width 0.07112)
			(type default)
		)
		(layer "In2.Cu")
	)
	(gr_line
		(start 90.296746 -299.705268)
		(end 90.698574 -299.561504)
		(stroke
			(width 0.07112)
			(type default)
		)
		(layer "In2.Cu")
	)
	(gr_line
		(start 90.308684 -300.146466)
		(end 90.969084 -299.910246)
		(stroke
			(width 0.07112)
			(type default)
		)
		(layer "In2.Cu")
	)
	(gr_line
		(start 90.523568 -400.572986)
		(end 90.096848 -400.572986)
		(stroke
			(width 0.07112)
			(type default)
		)
		(layer "In2.Cu")
	)
	(gr_line
		(start 90.659458 -400.437096)
		(end 90.523568 -400.572986)
		(stroke
			(width 0.07112)
			(type default)
		)
		(layer "In2.Cu")
	)
	(gr_line
		(start 90.660728 -400.153886)
		(end 89.959688 -400.153886)
		(stroke
			(width 0.07112)
			(type default)
		)
		(layer "In2.Cu")
	)
	(gr_line
		(start 90.698574 -299.561504)
		(end 90.872564 -299.6438)
		(stroke
			(width 0.07112)
			(type default)
		)
		(layer "In2.Cu")
	)
	(gr_line
		(start 91.224608 -400.572986)
		(end 91.088718 -400.437096)
		(stroke
			(width 0.07112)
			(type default)
		)
		(layer "In2.Cu")
	)
	(gr_line
		(start 91.276424 -299.499528)
		(end 91.358466 -299.325284)
		(stroke
			(width 0.07112)
			(type default)
		)
		(layer "In2.Cu")
	)
	(gr_line
		(start 91.358466 -299.325284)
		(end 91.760548 -299.18152)
		(stroke
			(width 0.07112)
			(type default)
		)
		(layer "In2.Cu")
	)
	(gr_line
		(start 91.370658 -299.766482)
		(end 92.030804 -299.530262)
		(stroke
			(width 0.07112)
			(type default)
		)
		(layer "In2.Cu")
	)
	(gr_line
		(start 91.651328 -400.572986)
		(end 91.224608 -400.572986)
		(stroke
			(width 0.07112)
			(type default)
		)
		(layer "In2.Cu")
	)
	(gr_line
		(start 91.760548 -299.18152)
		(end 91.934538 -299.263816)
		(stroke
			(width 0.07112)
			(type default)
		)
		(layer "In2.Cu")
	)
	(gr_line
		(start 91.787218 -400.437096)
		(end 91.651328 -400.572986)
		(stroke
			(width 0.07112)
			(type default)
		)
		(layer "In2.Cu")
	)
	(gr_line
		(start 91.788488 -400.153886)
		(end 91.087448 -400.153886)
		(stroke
			(width 0.07112)
			(type default)
		)
		(layer "In2.Cu")
	)
	(gr_line
		(start 92.352368 -400.572986)
		(end 92.216478 -400.437096)
		(stroke
			(width 0.07112)
			(type default)
		)
		(layer "In2.Cu")
	)
	(gr_line
		(start 92.533216 -299.049694)
		(end 92.615766 -298.87545)
		(stroke
			(width 0.07112)
			(type default)
		)
		(layer "In2.Cu")
	)
	(gr_line
		(start 92.615766 -298.87545)
		(end 93.017594 -298.731686)
		(stroke
			(width 0.07112)
			(type default)
		)
		(layer "In2.Cu")
	)
	(gr_line
		(start 92.627704 -299.316648)
		(end 93.288104 -299.080428)
		(stroke
			(width 0.07112)
			(type default)
		)
		(layer "In2.Cu")
	)
	(gr_line
		(start 92.779088 -400.572986)
		(end 92.352368 -400.572986)
		(stroke
			(width 0.07112)
			(type default)
		)
		(layer "In2.Cu")
	)
	(gr_line
		(start 92.914978 -400.437096)
		(end 92.779088 -400.572986)
		(stroke
			(width 0.07112)
			(type default)
		)
		(layer "In2.Cu")
	)
	(gr_line
		(start 92.916248 -400.153886)
		(end 92.215208 -400.153886)
		(stroke
			(width 0.07112)
			(type default)
		)
		(layer "In2.Cu")
	)
	(gr_line
		(start 93.017594 -298.731686)
		(end 93.191838 -298.813982)
		(stroke
			(width 0.07112)
			(type default)
		)
		(layer "In2.Cu")
	)
	(gr_line
		(start 93.480128 -400.572986)
		(end 93.344238 -400.437096)
		(stroke
			(width 0.07112)
			(type default)
		)
		(layer "In2.Cu")
	)
	(gr_line
		(start 93.59519 -298.66971)
		(end 93.67774 -298.495466)
		(stroke
			(width 0.07112)
			(type default)
		)
		(layer "In2.Cu")
	)
	(gr_line
		(start 93.67774 -298.495466)
		(end 94.079568 -298.351702)
		(stroke
			(width 0.07112)
			(type default)
		)
		(layer "In2.Cu")
	)
	(gr_line
		(start 93.689678 -298.936664)
		(end 94.350078 -298.700444)
		(stroke
			(width 0.07112)
			(type default)
		)
		(layer "In2.Cu")
	)
	(gr_line
		(start 93.906848 -400.572986)
		(end 93.480128 -400.572986)
		(stroke
			(width 0.07112)
			(type default)
		)
		(layer "In2.Cu")
	)
	(gr_line
		(start 93.947234 -308.18074)
		(end 93.656404 -308.47157)
		(stroke
			(width 0.07112)
			(type default)
		)
		(layer "In2.Cu")
	)
	(gr_line
		(start 94.042738 -400.437096)
		(end 93.906848 -400.572986)
		(stroke
			(width 0.07112)
			(type default)
		)
		(layer "In2.Cu")
	)
	(gr_line
		(start 94.044008 -400.153886)
		(end 93.342968 -400.153886)
		(stroke
			(width 0.07112)
			(type default)
		)
		(layer "In2.Cu")
	)
	(gr_line
		(start 94.079568 -298.351702)
		(end 94.253558 -298.433998)
		(stroke
			(width 0.07112)
			(type default)
		)
		(layer "In2.Cu")
	)
	(gr_line
		(start 94.15526 -307.03774)
		(end 94.144338 -307.064156)
		(stroke
			(width 0.07112)
			(type default)
		)
		(layer "In2.Cu")
	)
	(gr_line
		(start 94.171262 -307.013864)
		(end 94.15526 -307.03774)
		(stroke
			(width 0.07112)
			(type default)
		)
		(layer "In2.Cu")
	)
	(gr_line
		(start 94.229174 -308.18074)
		(end 94.520004 -308.47157)
		(stroke
			(width 0.07112)
			(type default)
		)
		(layer "In2.Cu")
	)
	(gr_line
		(start 94.657164 -298.289726)
		(end 94.739714 -298.115482)
		(stroke
			(width 0.07112)
			(type default)
		)
		(layer "In2.Cu")
	)
	(gr_line
		(start 94.739714 -298.115482)
		(end 95.141796 -297.971718)
		(stroke
			(width 0.07112)
			(type default)
		)
		(layer "In2.Cu")
	)
	(gr_line
		(start 94.751652 -298.55668)
		(end 95.412052 -298.32046)
		(stroke
			(width 0.07112)
			(type default)
		)
		(layer "In2.Cu")
	)
	(gr_line
		(start 95.141796 -297.971718)
		(end 95.31604 -298.054014)
		(stroke
			(width 0.07112)
			(type default)
		)
		(layer "In2.Cu")
	)
	(gr_line
		(start 95.82531 -308.305708)
		(end 96.079818 -307.962808)
		(stroke
			(width 0.07112)
			(type default)
		)
		(layer "In2.Cu")
	)
	(gr_line
		(start 95.853504 -308.496208)
		(end 95.82531 -308.305708)
		(stroke
			(width 0.07112)
			(type default)
		)
		(layer "In2.Cu")
	)
	(gr_line
		(start 96.079818 -307.962808)
		(end 96.270064 -307.934614)
		(stroke
			(width 0.07112)
			(type default)
		)
		(layer "In2.Cu")
	)
	(gr_line
		(start 96.080326 -308.665626)
		(end 96.498156 -308.102508)
		(stroke
			(width 0.07112)
			(type default)
		)
		(layer "In2.Cu")
	)
	(gr_line
		(start 96.656906 -296.612564)
		(end 96.656906 -296.584116)
		(stroke
			(width 0.05715)
			(type default)
		)
		(layer "In2.Cu")
	)
	(gr_line
		(start 96.656906 -296.584116)
		(end 96.702626 -296.538396)
		(stroke
			(width 0.05715)
			(type default)
		)
		(layer "In2.Cu")
	)
	(gr_line
		(start 96.795844 -306.997354)
		(end 97.050352 -306.654454)
		(stroke
			(width 0.07112)
			(type default)
		)
		(layer "In2.Cu")
	)
	(gr_line
		(start 96.824038 -307.1876)
		(end 96.795844 -306.997354)
		(stroke
			(width 0.07112)
			(type default)
		)
		(layer "In2.Cu")
	)
	(gr_line
		(start 96.938846 -296.612564)
		(end 96.938846 -296.584116)
		(stroke
			(width 0.05715)
			(type default)
		)
		(layer "In2.Cu")
	)
	(gr_line
		(start 96.938846 -296.584116)
		(end 96.893126 -296.538396)
		(stroke
			(width 0.05715)
			(type default)
		)
		(layer "In2.Cu")
	)
	(gr_line
		(start 97.050352 -306.654454)
		(end 97.240344 -306.62626)
		(stroke
			(width 0.07112)
			(type default)
		)
		(layer "In2.Cu")
	)
	(gr_line
		(start 97.050606 -307.357272)
		(end 97.46869 -306.7939)
		(stroke
			(width 0.07112)
			(type default)
		)
		(layer "In2.Cu")
	)
	(gr_line
		(start 97.338896 -294.336216)
		(end 97.040954 -294.336216)
		(stroke
			(width 0.05715)
			(type default)
		)
		(layer "In2.Cu")
	)
	(gr_line
		(start 97.408238 -294.405558)
		(end 97.338896 -294.336216)
		(stroke
			(width 0.05715)
			(type default)
		)
		(layer "In2.Cu")
	)
	(gr_line
		(start 97.467674 -306.09159)
		(end 97.722182 -305.748436)
		(stroke
			(width 0.07112)
			(type default)
		)
		(layer "In2.Cu")
	)
	(gr_line
		(start 97.495868 -306.281836)
		(end 97.467674 -306.09159)
		(stroke
			(width 0.07112)
			(type default)
		)
		(layer "In2.Cu")
	)
	(gr_arc
		(start 97.596452 -294.44188)
		(mid 97.598475 -294.43047)
		(end 97.600262 -294.41902)
		(stroke
			(width 0.05715)
			(type default)
		)
		(layer "In2.Cu")
	)
	(gr_line
		(start 97.600262 -294.41902)
		(end 97.683066 -294.336216)
		(stroke
			(width 0.05715)
			(type default)
		)
		(layer "In2.Cu")
	)
	(gr_line
		(start 97.683066 -294.336216)
		(end 97.981008 -294.336216)
		(stroke
			(width 0.05715)
			(type default)
		)
		(layer "In2.Cu")
	)
	(gr_line
		(start 97.722182 -305.748436)
		(end 97.912428 -305.720242)
		(stroke
			(width 0.07112)
			(type default)
		)
		(layer "In2.Cu")
	)
	(gr_line
		(start 97.72269 -306.451254)
		(end 98.140774 -305.887882)
		(stroke
			(width 0.07112)
			(type default)
		)
		(layer "In2.Cu")
	)
	(gr_line
		(start 97.914206 -305.719988)
		(end 97.982278 -305.628294)
		(stroke
			(width 0.07112)
			(type default)
		)
		(layer "In2.Cu")
	)
	(gr_line
		(start 97.981008 -292.716204)
		(end 98.27895 -292.716204)
		(stroke
			(width 0.05715)
			(type default)
		)
		(layer "In2.Cu")
	)
	(gr_line
		(start 98.062796 -297.261788)
		(end 98.062796 -297.290236)
		(stroke
			(width 0.05715)
			(type default)
		)
		(layer "In2.Cu")
	)
	(gr_line
		(start 98.108516 -297.216068)
		(end 98.062796 -297.261788)
		(stroke
			(width 0.05715)
			(type default)
		)
		(layer "In2.Cu")
	)
	(gr_line
		(start 98.139758 -305.185572)
		(end 98.394266 -304.842418)
		(stroke
			(width 0.07112)
			(type default)
		)
		(layer "In2.Cu")
	)
	(gr_line
		(start 98.140774 -305.887882)
		(end 98.208592 -305.796188)
		(stroke
			(width 0.07112)
			(type default)
		)
		(layer "In2.Cu")
	)
	(gr_line
		(start 98.167952 -305.375564)
		(end 98.139758 -305.185572)
		(stroke
			(width 0.07112)
			(type default)
		)
		(layer "In2.Cu")
	)
	(gr_line
		(start 98.27895 -292.716204)
		(end 98.361754 -292.799008)
		(stroke
			(width 0.05715)
			(type default)
		)
		(layer "In2.Cu")
	)
	(gr_line
		(start 98.299016 -297.216068)
		(end 98.344736 -297.261788)
		(stroke
			(width 0.05715)
			(type default)
		)
		(layer "In2.Cu")
	)
	(gr_line
		(start 98.344736 -297.261788)
		(end 98.344736 -297.290236)
		(stroke
			(width 0.05715)
			(type default)
		)
		(layer "In2.Cu")
	)
	(gr_arc
		(start 98.361754 -292.799008)
		(mid 98.363547 -292.81033)
		(end 98.365564 -292.821614)
		(stroke
			(width 0.05715)
			(type default)
		)
		(layer "In2.Cu")
	)
	(gr_line
		(start 98.394266 -304.842418)
		(end 98.584258 -304.814224)
		(stroke
			(width 0.07112)
			(type default)
		)
		(layer "In2.Cu")
	)
	(gr_line
		(start 98.394774 -305.545236)
		(end 98.812604 -304.981864)
		(stroke
			(width 0.07112)
			(type default)
		)
		(layer "In2.Cu")
	)
	(gr_line
		(start 98.551238 -404.701502)
		(end 98.551238 -404.701756)
		(stroke
			(width 0.07112)
			(type default)
		)
		(layer "In2.Cu")
	)
	(gr_line
		(start 98.58629 -304.81397)
		(end 98.793046 -304.535078)
		(stroke
			(width 0.07112)
			(type default)
		)
		(layer "In2.Cu")
	)
	(gr_line
		(start 98.62312 -292.716204)
		(end 98.553778 -292.785546)
		(stroke
			(width 0.05715)
			(type default)
		)
		(layer "In2.Cu")
	)
	(gr_line
		(start 98.631502 -293.852346)
		(end 98.630486 -293.852854)
		(stroke
			(width 0.05715)
			(type default)
		)
		(layer "In2.Cu")
	)
	(gr_line
		(start 98.634296 -293.850822)
		(end 98.631502 -293.852346)
		(stroke
			(width 0.05715)
			(type default)
		)
		(layer "In2.Cu")
	)
	(gr_line
		(start 98.635312 -293.850314)
		(end 98.634296 -293.850822)
		(stroke
			(width 0.05715)
			(type default)
		)
		(layer "In2.Cu")
	)
	(gr_line
		(start 98.63709 -293.849298)
		(end 98.635312 -293.850314)
		(stroke
			(width 0.05715)
			(type default)
		)
		(layer "In2.Cu")
	)
	(gr_line
		(start 98.63836 -293.203884)
		(end 98.638868 -293.204138)
		(stroke
			(width 0.05715)
			(type default)
		)
		(layer "In2.Cu")
	)
	(gr_line
		(start 98.638868 -293.204138)
		(end 98.641916 -293.205916)
		(stroke
			(width 0.05715)
			(type default)
		)
		(layer "In2.Cu")
	)
	(gr_line
		(start 98.726752 -294.0177)
		(end 98.725736 -294.018208)
		(stroke
			(width 0.05715)
			(type default)
		)
		(layer "In2.Cu")
	)
	(gr_line
		(start 98.727514 -294.017192)
		(end 98.726752 -294.0177)
		(stroke
			(width 0.05715)
			(type default)
		)
		(layer "In2.Cu")
	)
	(gr_line
		(start 98.730054 -294.015922)
		(end 98.727514 -294.017192)
		(stroke
			(width 0.05715)
			(type default)
		)
		(layer "In2.Cu")
	)
	(gr_line
		(start 98.732594 -294.014398)
		(end 98.731832 -294.014906)
		(stroke
			(width 0.05715)
			(type default)
		)
		(layer "In2.Cu")
	)
	(gr_line
		(start 98.733864 -294.013636)
		(end 98.732594 -294.014398)
		(stroke
			(width 0.05715)
			(type default)
		)
		(layer "In2.Cu")
	)
	(gr_line
		(start 98.765106 -294.67683)
		(end 98.77044 -294.679878)
		(stroke
			(width 0.05715)
			(type default)
		)
		(layer "In2.Cu")
	)
	(gr_line
		(start 98.77044 -294.679878)
		(end 98.771456 -294.680386)
		(stroke
			(width 0.05715)
			(type default)
		)
		(layer "In2.Cu")
	)
	(gr_line
		(start 98.771456 -294.680386)
		(end 98.772472 -294.681148)
		(stroke
			(width 0.05715)
			(type default)
		)
		(layer "In2.Cu")
	)
	(gr_arc
		(start 98.780346 -294.686736)
		(mid 98.77642 -294.683926)
		(end 98.772472 -294.681148)
		(stroke
			(width 0.05715)
			(type default)
		)
		(layer "In2.Cu")
	)
	(gr_line
		(start 98.811842 -304.279554)
		(end 99.06635 -303.9364)
		(stroke
			(width 0.07112)
			(type default)
		)
		(layer "In2.Cu")
	)
	(gr_line
		(start 98.840036 -304.469546)
		(end 98.811842 -304.279554)
		(stroke
			(width 0.07112)
			(type default)
		)
		(layer "In2.Cu")
	)
	(gr_line
		(start 98.921062 -292.716204)
		(end 98.62312 -292.716204)
		(stroke
			(width 0.05715)
			(type default)
		)
		(layer "In2.Cu")
	)
	(gr_line
		(start 98.991928 -314.71743)
		(end 98.71202 -314.997338)
		(stroke
			(width 0.07112)
			(type default)
		)
		(layer "In2.Cu")
	)
	(gr_line
		(start 99.012502 -314.43422)
		(end 98.71202 -314.133738)
		(stroke
			(width 0.07112)
			(type default)
		)
		(layer "In2.Cu")
	)
	(gr_line
		(start 99.013772 -314.71743)
		(end 98.991928 -314.71743)
		(stroke
			(width 0.07112)
			(type default)
		)
		(layer "In2.Cu")
	)
	(gr_line
		(start 99.06635 -303.9364)
		(end 99.256342 -303.908206)
		(stroke
			(width 0.07112)
			(type default)
		)
		(layer "In2.Cu")
	)
	(gr_line
		(start 99.066858 -304.639218)
		(end 99.484688 -304.075846)
		(stroke
			(width 0.07112)
			(type default)
		)
		(layer "In2.Cu")
	)
	(gr_line
		(start 99.482656 -297.989244)
		(end 99.482656 -297.960796)
		(stroke
			(width 0.05715)
			(type default)
		)
		(layer "In2.Cu")
	)
	(gr_line
		(start 99.482656 -297.960796)
		(end 99.528376 -297.915076)
		(stroke
			(width 0.05715)
			(type default)
		)
		(layer "In2.Cu")
	)
	(gr_line
		(start 99.564444 5.922264)
		(end 99.273614 5.631434)
		(stroke
			(width 0.07112)
			(type default)
		)
		(layer "In2.Cu")
	)
	(gr_line
		(start 99.564444 6.204204)
		(end 99.273614 6.495034)
		(stroke
			(width 0.07112)
			(type default)
		)
		(layer "In2.Cu")
	)
	(gr_line
		(start 99.598226 -310.312816)
		(end 99.307396 -310.603646)
		(stroke
			(width 0.07112)
			(type default)
		)
		(layer "In2.Cu")
	)
	(gr_line
		(start 99.598226 -310.030876)
		(end 99.307396 -309.740046)
		(stroke
			(width 0.07112)
			(type default)
		)
		(layer "In2.Cu")
	)
	(gr_line
		(start 99.718876 -295.917112)
		(end 99.71913 -295.917366)
		(stroke
			(width 0.05715)
			(type default)
		)
		(layer "In2.Cu")
	)
	(gr_line
		(start 99.764596 -297.989244)
		(end 99.764596 -297.960796)
		(stroke
			(width 0.05715)
			(type default)
		)
		(layer "In2.Cu")
	)
	(gr_line
		(start 99.764596 -297.960796)
		(end 99.718876 -297.915076)
		(stroke
			(width 0.05715)
			(type default)
		)
		(layer "In2.Cu")
	)
	(gr_line
		(start 99.837494 -295.532556)
		(end 99.837748 -295.532556)
		(stroke
			(width 0.05715)
			(type default)
		)
		(layer "In2.Cu")
	)
	(gr_line
		(start 100.04552 -294.66032)
		(end 100.047044 -294.659304)
		(stroke
			(width 0.05715)
			(type default)
		)
		(layer "In2.Cu")
	)
	(gr_line
		(start 100.04806 -294.658796)
		(end 100.048822 -294.658288)
		(stroke
			(width 0.05715)
			(type default)
		)
		(layer "In2.Cu")
	)
	(gr_line
		(start 100.05187 -294.65651)
		(end 100.052886 -294.656002)
		(stroke
			(width 0.05715)
			(type default)
		)
		(layer "In2.Cu")
	)
	(gr_line
		(start 100.12553 -294.83431)
		(end 100.126038 -294.834056)
		(stroke
			(width 0.05715)
			(type default)
		)
		(layer "In2.Cu")
	)
	(gr_line
		(start 100.1395 -294.826182)
		(end 100.140516 -294.825674)
		(stroke
			(width 0.05715)
			(type default)
		)
		(layer "In2.Cu")
	)
	(gr_line
		(start 100.140516 -294.825674)
		(end 100.14331 -294.82415)
		(stroke
			(width 0.05715)
			(type default)
		)
		(layer "In2.Cu")
	)
	(gr_line
		(start 100.14331 -294.82415)
		(end 100.144072 -294.823642)
		(stroke
			(width 0.05715)
			(type default)
		)
		(layer "In2.Cu")
	)
	(gr_line
		(start 100.144072 -294.823642)
		(end 100.145088 -294.823134)
		(stroke
			(width 0.05715)
			(type default)
		)
		(layer "In2.Cu")
	)
	(gr_line
		(start 100.145088 -294.823134)
		(end 100.146358 -294.822372)
		(stroke
			(width 0.05715)
			(type default)
		)
		(layer "In2.Cu")
	)
	(gr_line
		(start 100.146358 -294.822372)
		(end 100.146866 -294.822118)
		(stroke
			(width 0.05715)
			(type default)
		)
		(layer "In2.Cu")
	)
	(gr_line
		(start 100.159058 -294.336216)
		(end 99.861116 -294.336216)
		(stroke
			(width 0.05715)
			(type default)
		)
		(layer "In2.Cu")
	)
	(gr_line
		(start 100.2284 -294.405558)
		(end 100.159058 -294.336216)
		(stroke
			(width 0.05715)
			(type default)
		)
		(layer "In2.Cu")
	)
	(gr_line
		(start 100.32492 -309.344314)
		(end 100.402898 -309.52059)
		(stroke
			(width 0.07112)
			(type default)
		)
		(layer "In2.Cu")
	)
	(gr_arc
		(start 100.416614 -294.44188)
		(mid 100.418637 -294.43047)
		(end 100.420424 -294.41902)
		(stroke
			(width 0.05715)
			(type default)
		)
		(layer "In2.Cu")
	)
	(gr_line
		(start 100.420424 -294.41902)
		(end 100.503228 -294.336216)
		(stroke
			(width 0.05715)
			(type default)
		)
		(layer "In2.Cu")
	)
	(gr_line
		(start 100.478336 -308.946042)
		(end 100.32492 -309.344314)
		(stroke
			(width 0.07112)
			(type default)
		)
		(layer "In2.Cu")
	)
	(gr_line
		(start 100.503228 -294.336216)
		(end 100.80117 -294.336216)
		(stroke
			(width 0.05715)
			(type default)
		)
		(layer "In2.Cu")
	)
	(gr_line
		(start 100.654612 -308.868064)
		(end 100.478336 -308.946042)
		(stroke
			(width 0.07112)
			(type default)
		)
		(layer "In2.Cu")
	)
	(gr_line
		(start 100.731066 -308.291992)
		(end 100.809044 -308.468014)
		(stroke
			(width 0.07112)
			(type default)
		)
		(layer "In2.Cu")
	)
	(gr_line
		(start 100.80117 -292.716204)
		(end 101.099112 -292.716204)
		(stroke
			(width 0.05715)
			(type default)
		)
		(layer "In2.Cu")
	)
	(gr_line
		(start 100.869496 -313.63285)
		(end 100.869496 -313.825128)
		(stroke
			(width 0.07112)
			(type default)
		)
		(layer "In2.Cu")
	)
	(gr_line
		(start 100.874576 -298.680378)
		(end 100.874576 -298.708826)
		(stroke
			(width 0.05715)
			(type default)
		)
		(layer "In2.Cu")
	)
	(gr_line
		(start 100.884482 -307.89372)
		(end 100.731066 -308.291992)
		(stroke
			(width 0.07112)
			(type default)
		)
		(layer "In2.Cu")
	)
	(gr_line
		(start 100.91928 -308.968648)
		(end 100.666804 -309.623206)
		(stroke
			(width 0.07112)
			(type default)
		)
		(layer "In2.Cu")
	)
	(gr_line
		(start 100.920296 -298.634658)
		(end 100.874576 -298.680378)
		(stroke
			(width 0.05715)
			(type default)
		)
		(layer "In2.Cu")
	)
	(gr_line
		(start 101.060504 -307.815742)
		(end 100.884482 -307.89372)
		(stroke
			(width 0.07112)
			(type default)
		)
		(layer "In2.Cu")
	)
	(gr_line
		(start 101.099112 -292.716204)
		(end 101.18217 -292.801548)
		(stroke
			(width 0.05715)
			(type default)
		)
		(layer "In2.Cu")
	)
	(gr_line
		(start 101.110796 -298.634658)
		(end 101.156516 -298.680378)
		(stroke
			(width 0.05715)
			(type default)
		)
		(layer "In2.Cu")
	)
	(gr_line
		(start 101.137212 -307.23967)
		(end 101.214936 -307.415438)
		(stroke
			(width 0.07112)
			(type default)
		)
		(layer "In2.Cu")
	)
	(gr_line
		(start 101.156516 -298.680378)
		(end 101.156516 -298.708826)
		(stroke
			(width 0.05715)
			(type default)
		)
		(layer "In2.Cu")
	)
	(gr_line
		(start 101.16185 -307.556662)
		(end 101.062282 -307.81498)
		(stroke
			(width 0.07112)
			(type default)
		)
		(layer "In2.Cu")
	)
	(gr_line
		(start 101.171502 -313.330844)
		(end 100.869496 -313.63285)
		(stroke
			(width 0.07112)
			(type default)
		)
		(layer "In2.Cu")
	)
	(gr_arc
		(start 101.18217 -292.801548)
		(mid 101.183876 -292.811721)
		(end 101.185726 -292.821868)
		(stroke
			(width 0.05715)
			(type default)
		)
		(layer "In2.Cu")
	)
	(gr_line
		(start 101.22789 -23.167086)
		(end 101.628956 -22.594316)
		(stroke
			(width 0.07112)
			(type default)
		)
		(layer "In2.Cu")
	)
	(gr_line
		(start 101.290628 -306.841144)
		(end 101.137212 -307.23967)
		(stroke
			(width 0.07112)
			(type default)
		)
		(layer "In2.Cu")
	)
	(gr_line
		(start 101.325172 -307.916326)
		(end 101.07295 -308.570884)
		(stroke
			(width 0.07112)
			(type default)
		)
		(layer "In2.Cu")
	)
	(gr_line
		(start 101.36378 -313.330844)
		(end 101.171502 -313.330844)
		(stroke
			(width 0.07112)
			(type default)
		)
		(layer "In2.Cu")
	)
	(gr_line
		(start 101.443028 -292.716204)
		(end 101.37394 -292.785292)
		(stroke
			(width 0.05715)
			(type default)
		)
		(layer "In2.Cu")
	)
	(gr_arc
		(start 101.451156 -293.19982)
		(mid 101.452932 -293.200839)
		(end 101.454712 -293.201852)
		(stroke
			(width 0.05715)
			(type default)
		)
		(layer "In2.Cu")
	)
	(gr_line
		(start 101.458776 -23.328884)
		(end 101.458776 -23.32863)
		(stroke
			(width 0.07112)
			(type default)
		)
		(layer "In2.Cu")
	)
	(gr_line
		(start 101.460554 -23.328376)
		(end 101.649784 -23.294848)
		(stroke
			(width 0.07112)
			(type default)
		)
		(layer "In2.Cu")
	)
	(gr_line
		(start 101.466396 -306.76342)
		(end 101.290628 -306.841144)
		(stroke
			(width 0.07112)
			(type default)
		)
		(layer "In2.Cu")
	)
	(gr_line
		(start 101.48951 -294.84193)
		(end 101.489764 -294.84193)
		(stroke
			(width 0.05715)
			(type default)
		)
		(layer "In2.Cu")
	)
	(gr_line
		(start 101.50221 -306.67452)
		(end 101.468174 -306.762658)
		(stroke
			(width 0.07112)
			(type default)
		)
		(layer "In2.Cu")
	)
	(gr_line
		(start 101.543104 -306.187348)
		(end 101.620828 -306.363116)
		(stroke
			(width 0.07112)
			(type default)
		)
		(layer "In2.Cu")
	)
	(gr_line
		(start 101.550978 -293.037006)
		(end 101.553772 -293.03853)
		(stroke
			(width 0.05715)
			(type default)
		)
		(layer "In2.Cu")
	)
	(gr_line
		(start 101.564948 -313.530234)
		(end 101.068886 -314.026296)
		(stroke
			(width 0.07112)
			(type default)
		)
		(layer "In2.Cu")
	)
	(gr_line
		(start 101.584506 -293.056564)
		(end 101.59238 -293.061136)
		(stroke
			(width 0.05715)
			(type default)
		)
		(layer "In2.Cu")
	)
	(gr_arc
		(start 101.59238 -293.061136)
		(mid 101.592761 -293.06139)
		(end 101.593142 -293.061644)
		(stroke
			(width 0.05715)
			(type default)
		)
		(layer "In2.Cu")
	)
	(gr_arc
		(start 101.601016 -293.067232)
		(mid 101.597091 -293.064421)
		(end 101.593142 -293.061644)
		(stroke
			(width 0.05715)
			(type default)
		)
		(layer "In2.Cu")
	)
	(gr_line
		(start 101.649784 -23.294848)
		(end 101.89337 -22.947376)
		(stroke
			(width 0.07112)
			(type default)
		)
		(layer "In2.Cu")
	)
	(gr_line
		(start 101.69652 -305.788822)
		(end 101.543104 -306.187348)
		(stroke
			(width 0.07112)
			(type default)
		)
		(layer "In2.Cu")
	)
	(gr_line
		(start 101.710998 -22.476968)
		(end 101.872034 -22.247352)
		(stroke
			(width 0.07112)
			(type default)
		)
		(layer "In2.Cu")
	)
	(gr_line
		(start 101.731318 -306.864004)
		(end 101.478842 -307.518308)
		(stroke
			(width 0.07112)
			(type default)
		)
		(layer "In2.Cu")
	)
	(gr_line
		(start 101.74097 -292.716204)
		(end 101.443028 -292.716204)
		(stroke
			(width 0.05715)
			(type default)
		)
		(layer "In2.Cu")
	)
	(gr_line
		(start 101.849428 -312.653172)
		(end 101.849428 -312.84545)
		(stroke
			(width 0.07112)
			(type default)
		)
		(layer "In2.Cu")
	)
	(gr_line
		(start 101.872034 -22.247352)
		(end 102.272846 -21.674582)
		(stroke
			(width 0.07112)
			(type default)
		)
		(layer "In2.Cu")
	)
	(gr_line
		(start 101.872542 -305.711098)
		(end 101.69652 -305.788822)
		(stroke
			(width 0.07112)
			(type default)
		)
		(layer "In2.Cu")
	)
	(gr_line
		(start 101.89337 -22.947376)
		(end 101.860096 -22.757892)
		(stroke
			(width 0.07112)
			(type default)
		)
		(layer "In2.Cu")
	)
	(gr_line
		(start 101.942138 -22.638766)
		(end 102.10292 -22.408896)
		(stroke
			(width 0.07112)
			(type default)
		)
		(layer "In2.Cu")
	)
	(gr_line
		(start 102.104698 -22.408642)
		(end 102.293928 -22.375114)
		(stroke
			(width 0.07112)
			(type default)
		)
		(layer "In2.Cu")
	)
	(gr_line
		(start 102.13721 -305.811936)
		(end 101.884734 -306.465986)
		(stroke
			(width 0.07112)
			(type default)
		)
		(layer "In2.Cu")
	)
	(gr_line
		(start 102.151434 -312.351166)
		(end 101.849428 -312.653172)
		(stroke
			(width 0.07112)
			(type default)
		)
		(layer "In2.Cu")
	)
	(gr_line
		(start 102.265988 -298.023788)
		(end 102.265988 -297.99534)
		(stroke
			(width 0.05715)
			(type default)
		)
		(layer "In2.Cu")
	)
	(gr_line
		(start 102.265988 -297.99534)
		(end 102.311708 -297.94962)
		(stroke
			(width 0.05715)
			(type default)
		)
		(layer "In2.Cu")
	)
	(gr_line
		(start 102.293928 -22.375114)
		(end 102.537514 -22.027642)
		(stroke
			(width 0.07112)
			(type default)
		)
		(layer "In2.Cu")
	)
	(gr_line
		(start 102.343712 -312.351166)
		(end 102.151434 -312.351166)
		(stroke
			(width 0.07112)
			(type default)
		)
		(layer "In2.Cu")
	)
	(gr_line
		(start 102.537514 -22.027642)
		(end 102.50424 -21.838158)
		(stroke
			(width 0.07112)
			(type default)
		)
		(layer "In2.Cu")
	)
	(gr_line
		(start 102.544626 -312.550556)
		(end 102.048818 -313.046364)
		(stroke
			(width 0.07112)
			(type default)
		)
		(layer "In2.Cu")
	)
	(gr_line
		(start 102.547928 -298.023788)
		(end 102.547928 -297.99534)
		(stroke
			(width 0.05715)
			(type default)
		)
		(layer "In2.Cu")
	)
	(gr_line
		(start 102.547928 -297.99534)
		(end 102.502208 -297.94962)
		(stroke
			(width 0.05715)
			(type default)
		)
		(layer "In2.Cu")
	)
	(gr_line
		(start 102.642162 -21.218398)
		(end 102.932484 -21.014944)
		(stroke
			(width 0.07112)
			(type default)
		)
		(layer "In2.Cu")
	)
	(gr_line
		(start 102.80396 -21.449284)
		(end 103.094282 -21.24583)
		(stroke
			(width 0.07112)
			(type default)
		)
		(layer "In2.Cu")
	)
	(gr_line
		(start 102.932484 -21.014944)
		(end 103.505 -20.614132)
		(stroke
			(width 0.07112)
			(type default)
		)
		(layer "In2.Cu")
	)
	(gr_line
		(start 102.978966 -294.336216)
		(end 102.681024 -294.336216)
		(stroke
			(width 0.05715)
			(type default)
		)
		(layer "In2.Cu")
	)
	(gr_line
		(start 103.048308 -294.405558)
		(end 102.978966 -294.336216)
		(stroke
			(width 0.05715)
			(type default)
		)
		(layer "In2.Cu")
	)
	(gr_line
		(start 103.09606 -21.246084)
		(end 103.28529 -21.279612)
		(stroke
			(width 0.07112)
			(type default)
		)
		(layer "In2.Cu")
	)
	(gr_line
		(start 103.203502 -310.850534)
		(end 103.281226 -311.026302)
		(stroke
			(width 0.07112)
			(type default)
		)
		(layer "In2.Cu")
	)
	(gr_arc
		(start 103.236522 -294.44188)
		(mid 103.238545 -294.43047)
		(end 103.240332 -294.41902)
		(stroke
			(width 0.05715)
			(type default)
		)
		(layer "In2.Cu")
	)
	(gr_line
		(start 103.240332 -294.41902)
		(end 103.323136 -294.336216)
		(stroke
			(width 0.05715)
			(type default)
		)
		(layer "In2.Cu")
	)
	(gr_line
		(start 103.28529 -21.279612)
		(end 103.633016 -21.036026)
		(stroke
			(width 0.07112)
			(type default)
		)
		(layer "In2.Cu")
	)
	(gr_line
		(start 103.323136 -294.336216)
		(end 103.621078 -294.336216)
		(stroke
			(width 0.05715)
			(type default)
		)
		(layer "In2.Cu")
	)
	(gr_line
		(start 103.356918 -310.452262)
		(end 103.203502 -310.850534)
		(stroke
			(width 0.07112)
			(type default)
		)
		(layer "In2.Cu")
	)
	(gr_line
		(start 103.53294 -310.374284)
		(end 103.356918 -310.452262)
		(stroke
			(width 0.07112)
			(type default)
		)
		(layer "In2.Cu")
	)
	(gr_line
		(start 103.610664 -309.801514)
		(end 103.687118 -309.97398)
		(stroke
			(width 0.07112)
			(type default)
		)
		(layer "In2.Cu")
	)
	(gr_line
		(start 103.621078 -292.716204)
		(end 103.91902 -292.716204)
		(stroke
			(width 0.05715)
			(type default)
		)
		(layer "In2.Cu")
	)
	(gr_line
		(start 103.633016 -21.036026)
		(end 103.666544 -20.846542)
		(stroke
			(width 0.07112)
			(type default)
		)
		(layer "In2.Cu")
	)
	(gr_line
		(start 103.67518 -296.700702)
		(end 103.67518 -296.72915)
		(stroke
			(width 0.05715)
			(type default)
		)
		(layer "In2.Cu")
	)
	(gr_line
		(start 103.7209 -296.654982)
		(end 103.67518 -296.700702)
		(stroke
			(width 0.05715)
			(type default)
		)
		(layer "In2.Cu")
	)
	(gr_line
		(start 103.764334 -309.402988)
		(end 103.610664 -309.801514)
		(stroke
			(width 0.07112)
			(type default)
		)
		(layer "In2.Cu")
	)
	(gr_line
		(start 103.797608 -310.474868)
		(end 103.545132 -311.129172)
		(stroke
			(width 0.07112)
			(type default)
		)
		(layer "In2.Cu")
	)
	(gr_line
		(start 103.852218 -20.3708)
		(end 104.281732 -20.06981)
		(stroke
			(width 0.07112)
			(type default)
		)
		(layer "In2.Cu")
	)
	(gr_line
		(start 103.9114 -296.654982)
		(end 103.95712 -296.700702)
		(stroke
			(width 0.05715)
			(type default)
		)
		(layer "In2.Cu")
	)
	(gr_line
		(start 103.91902 -292.716204)
		(end 104.001824 -292.799008)
		(stroke
			(width 0.05715)
			(type default)
		)
		(layer "In2.Cu")
	)
	(gr_line
		(start 103.9368 -309.326788)
		(end 103.764334 -309.402988)
		(stroke
			(width 0.07112)
			(type default)
		)
		(layer "In2.Cu")
	)
	(gr_line
		(start 103.95712 -296.700702)
		(end 103.95712 -296.72915)
		(stroke
			(width 0.05715)
			(type default)
		)
		(layer "In2.Cu")
	)
	(gr_arc
		(start 104.001824 -292.799008)
		(mid 104.003617 -292.81033)
		(end 104.005634 -292.821614)
		(stroke
			(width 0.05715)
			(type default)
		)
		(layer "In2.Cu")
	)
	(gr_line
		(start 104.015794 -20.60194)
		(end 104.205024 -20.635468)
		(stroke
			(width 0.07112)
			(type default)
		)
		(layer "In2.Cu")
	)
	(gr_line
		(start 104.201468 -309.427372)
		(end 103.951024 -310.07685)
		(stroke
			(width 0.07112)
			(type default)
		)
		(layer "In2.Cu")
	)
	(gr_line
		(start 104.205024 -20.635468)
		(end 104.55275 -20.391882)
		(stroke
			(width 0.07112)
			(type default)
		)
		(layer "In2.Cu")
	)
	(gr_arc
		(start 104.230932 -293.175182)
		(mid 104.234984 -293.177994)
		(end 104.23906 -293.18077)
		(stroke
			(width 0.05715)
			(type default)
		)
		(layer "In2.Cu")
	)
	(gr_line
		(start 104.23906 -293.18077)
		(end 104.241854 -293.182802)
		(stroke
			(width 0.05715)
			(type default)
		)
		(layer "In2.Cu")
	)
	(gr_line
		(start 104.241854 -293.182802)
		(end 104.248204 -293.186358)
		(stroke
			(width 0.05715)
			(type default)
		)
		(layer "In2.Cu")
	)
	(gr_line
		(start 104.26319 -292.716204)
		(end 104.193848 -292.785546)
		(stroke
			(width 0.05715)
			(type default)
		)
		(layer "In2.Cu")
	)
	(gr_line
		(start 104.277668 -293.203376)
		(end 104.27843 -293.203884)
		(stroke
			(width 0.05715)
			(type default)
		)
		(layer "In2.Cu")
	)
	(gr_line
		(start 104.277922 -293.849044)
		(end 104.275382 -293.850568)
		(stroke
			(width 0.05715)
			(type default)
		)
		(layer "In2.Cu")
	)
	(gr_line
		(start 104.278176 -293.84879)
		(end 104.277922 -293.849044)
		(stroke
			(width 0.05715)
			(type default)
		)
		(layer "In2.Cu")
	)
	(gr_line
		(start 104.279446 -293.848028)
		(end 104.278176 -293.84879)
		(stroke
			(width 0.05715)
			(type default)
		)
		(layer "In2.Cu")
	)
	(gr_line
		(start 104.280208 -293.84752)
		(end 104.279446 -293.848028)
		(stroke
			(width 0.05715)
			(type default)
		)
		(layer "In2.Cu")
	)
	(gr_line
		(start 104.281732 -20.06981)
		(end 104.424734 -19.969734)
		(stroke
			(width 0.07112)
			(type default)
		)
		(layer "In2.Cu")
	)
	(gr_line
		(start 104.283764 -293.845488)
		(end 104.280208 -293.84752)
		(stroke
			(width 0.05715)
			(type default)
		)
		(layer "In2.Cu")
	)
	(gr_line
		(start 104.32923 -293.235634)
		(end 104.329738 -293.236142)
		(stroke
			(width 0.05715)
			(type default)
		)
		(layer "In2.Cu")
	)
	(gr_line
		(start 104.372918 -293.038276)
		(end 104.373426 -293.03853)
		(stroke
			(width 0.05715)
			(type default)
		)
		(layer "In2.Cu")
	)
	(gr_line
		(start 104.37495 -294.013128)
		(end 104.373934 -294.013636)
		(stroke
			(width 0.05715)
			(type default)
		)
		(layer "In2.Cu")
	)
	(gr_line
		(start 104.55275 -20.391882)
		(end 104.586278 -20.202144)
		(stroke
			(width 0.07112)
			(type default)
		)
		(layer "In2.Cu")
	)
	(gr_line
		(start 104.561132 -292.716204)
		(end 104.26319 -292.716204)
		(stroke
			(width 0.05715)
			(type default)
		)
		(layer "In2.Cu")
	)
	(gr_line
		(start 105.116884 -296.612564)
		(end 105.116884 -296.584116)
		(stroke
			(width 0.05715)
			(type default)
		)
		(layer "In2.Cu")
	)
	(gr_line
		(start 105.116884 -296.584116)
		(end 105.162604 -296.538396)
		(stroke
			(width 0.05715)
			(type default)
		)
		(layer "In2.Cu")
	)
	(gr_line
		(start 105.398824 -296.612564)
		(end 105.398824 -296.584116)
		(stroke
			(width 0.05715)
			(type default)
		)
		(layer "In2.Cu")
	)
	(gr_line
		(start 105.398824 -296.584116)
		(end 105.353104 -296.538396)
		(stroke
			(width 0.05715)
			(type default)
		)
		(layer "In2.Cu")
	)
	(gr_line
		(start 105.685336 -294.66032)
		(end 105.68686 -294.659304)
		(stroke
			(width 0.05715)
			(type default)
		)
		(layer "In2.Cu")
	)
	(gr_line
		(start 105.687876 -294.658796)
		(end 105.688638 -294.658288)
		(stroke
			(width 0.05715)
			(type default)
		)
		(layer "In2.Cu")
	)
	(gr_line
		(start 105.691686 -294.65651)
		(end 105.692702 -294.656002)
		(stroke
			(width 0.05715)
			(type default)
		)
		(layer "In2.Cu")
	)
	(gr_line
		(start 105.779316 -294.826182)
		(end 105.780332 -294.825674)
		(stroke
			(width 0.05715)
			(type default)
		)
		(layer "In2.Cu")
	)
	(gr_line
		(start 105.780332 -294.825674)
		(end 105.783126 -294.82415)
		(stroke
			(width 0.05715)
			(type default)
		)
		(layer "In2.Cu")
	)
	(gr_line
		(start 105.783126 -294.82415)
		(end 105.783888 -294.823642)
		(stroke
			(width 0.05715)
			(type default)
		)
		(layer "In2.Cu")
	)
	(gr_line
		(start 105.783888 -294.823642)
		(end 105.784904 -294.823134)
		(stroke
			(width 0.05715)
			(type default)
		)
		(layer "In2.Cu")
	)
	(gr_line
		(start 105.784904 -294.823134)
		(end 105.786174 -294.822372)
		(stroke
			(width 0.05715)
			(type default)
		)
		(layer "In2.Cu")
	)
	(gr_line
		(start 105.786174 -294.822372)
		(end 105.786682 -294.822118)
		(stroke
			(width 0.05715)
			(type default)
		)
		(layer "In2.Cu")
	)
	(gr_line
		(start 105.798874 -294.336216)
		(end 105.500932 -294.336216)
		(stroke
			(width 0.05715)
			(type default)
		)
		(layer "In2.Cu")
	)
	(gr_line
		(start 105.868216 -294.405558)
		(end 105.798874 -294.336216)
		(stroke
			(width 0.05715)
			(type default)
		)
		(layer "In2.Cu")
	)
	(gr_arc
		(start 106.05643 -294.44188)
		(mid 106.058453 -294.43047)
		(end 106.06024 -294.41902)
		(stroke
			(width 0.05715)
			(type default)
		)
		(layer "In2.Cu")
	)
	(gr_line
		(start 106.06024 -294.41902)
		(end 106.143044 -294.336216)
		(stroke
			(width 0.05715)
			(type default)
		)
		(layer "In2.Cu")
	)
	(gr_line
		(start 106.143044 -294.336216)
		(end 106.440986 -294.336216)
		(stroke
			(width 0.05715)
			(type default)
		)
		(layer "In2.Cu")
	)
	(gr_line
		(start 106.30027 -295.502076)
		(end 106.30027 -295.530524)
		(stroke
			(width 0.05715)
			(type default)
		)
		(layer "In2.Cu")
	)
	(gr_line
		(start 106.34599 -295.456356)
		(end 106.30027 -295.502076)
		(stroke
			(width 0.05715)
			(type default)
		)
		(layer "In2.Cu")
	)
	(gr_line
		(start 106.440986 -292.716204)
		(end 106.738928 -292.716204)
		(stroke
			(width 0.05715)
			(type default)
		)
		(layer "In2.Cu")
	)
	(gr_line
		(start 106.499914 -302.683672)
		(end 103.938578 -309.326026)
		(stroke
			(width 0.07112)
			(type default)
		)
		(layer "In2.Cu")
	)
	(gr_line
		(start 106.53649 -295.456356)
		(end 106.58221 -295.502076)
		(stroke
			(width 0.05715)
			(type default)
		)
		(layer "In2.Cu")
	)
	(gr_line
		(start 106.58221 -295.502076)
		(end 106.58221 -295.530524)
		(stroke
			(width 0.05715)
			(type default)
		)
		(layer "In2.Cu")
	)
	(gr_line
		(start 106.660188 -294.638476)
		(end 106.659934 -294.638476)
		(stroke
			(width 0.05715)
			(type default)
		)
		(layer "In2.Cu")
	)
	(gr_line
		(start 106.738928 -292.716204)
		(end 106.821732 -292.799008)
		(stroke
			(width 0.05715)
			(type default)
		)
		(layer "In2.Cu")
	)
	(gr_line
		(start 106.763058 -302.785272)
		(end 104.201468 -309.427372)
		(stroke
			(width 0.07112)
			(type default)
		)
		(layer "In2.Cu")
	)
	(gr_arc
		(start 106.821732 -292.799008)
		(mid 106.823525 -292.81033)
		(end 106.825542 -292.821614)
		(stroke
			(width 0.05715)
			(type default)
		)
		(layer "In2.Cu")
	)
	(gr_arc
		(start 107.05084 -293.175182)
		(mid 107.054892 -293.177994)
		(end 107.058968 -293.18077)
		(stroke
			(width 0.05715)
			(type default)
		)
		(layer "In2.Cu")
	)
	(gr_line
		(start 107.058968 -293.18077)
		(end 107.066588 -293.185342)
		(stroke
			(width 0.05715)
			(type default)
		)
		(layer "In2.Cu")
	)
	(gr_line
		(start 107.066588 -293.185342)
		(end 107.067096 -293.185596)
		(stroke
			(width 0.05715)
			(type default)
		)
		(layer "In2.Cu")
	)
	(gr_line
		(start 107.083098 -292.716204)
		(end 107.013756 -292.785546)
		(stroke
			(width 0.05715)
			(type default)
		)
		(layer "In2.Cu")
	)
	(gr_line
		(start 107.098084 -293.20363)
		(end 107.099608 -293.204646)
		(stroke
			(width 0.05715)
			(type default)
		)
		(layer "In2.Cu")
	)
	(gr_line
		(start 107.098338 -293.848536)
		(end 107.09148 -293.8526)
		(stroke
			(width 0.05715)
			(type default)
		)
		(layer "In2.Cu")
	)
	(gr_line
		(start 107.1118 -293.211758)
		(end 107.11561 -293.21379)
		(stroke
			(width 0.05715)
			(type default)
		)
		(layer "In2.Cu")
	)
	(gr_line
		(start 107.118404 -293.215568)
		(end 107.119166 -293.215822)
		(stroke
			(width 0.05715)
			(type default)
		)
		(layer "In2.Cu")
	)
	(gr_line
		(start 107.119166 -293.215822)
		(end 107.119928 -293.21633)
		(stroke
			(width 0.05715)
			(type default)
		)
		(layer "In2.Cu")
	)
	(gr_line
		(start 107.119928 -293.21633)
		(end 107.12069 -293.216838)
		(stroke
			(width 0.05715)
			(type default)
		)
		(layer "In2.Cu")
	)
	(gr_line
		(start 107.193842 -293.038784)
		(end 107.19435 -293.039038)
		(stroke
			(width 0.05715)
			(type default)
		)
		(layer "In2.Cu")
	)
	(gr_line
		(start 107.195874 -293.0398)
		(end 107.197398 -293.040562)
		(stroke
			(width 0.05715)
			(type default)
		)
		(layer "In2.Cu")
	)
	(gr_line
		(start 107.19943 -293.041832)
		(end 107.200192 -293.042086)
		(stroke
			(width 0.05715)
			(type default)
		)
		(layer "In2.Cu")
	)
	(gr_line
		(start 107.208828 -293.04742)
		(end 107.211114 -293.04869)
		(stroke
			(width 0.05715)
			(type default)
		)
		(layer "In2.Cu")
	)
	(gr_line
		(start 107.211114 -293.04869)
		(end 107.21213 -293.049198)
		(stroke
			(width 0.05715)
			(type default)
		)
		(layer "In2.Cu")
	)
	(gr_line
		(start 107.21213 -293.049198)
		(end 107.212892 -293.049706)
		(stroke
			(width 0.05715)
			(type default)
		)
		(layer "In2.Cu")
	)
	(gr_line
		(start 107.212892 -293.049706)
		(end 107.2134 -293.04996)
		(stroke
			(width 0.05715)
			(type default)
		)
		(layer "In2.Cu")
	)
	(gr_line
		(start 107.221274 -293.054532)
		(end 107.223306 -293.055802)
		(stroke
			(width 0.05715)
			(type default)
		)
		(layer "In2.Cu")
	)
	(gr_line
		(start 107.224322 -293.05631)
		(end 107.225084 -293.056818)
		(stroke
			(width 0.05715)
			(type default)
		)
		(layer "In2.Cu")
	)
	(gr_line
		(start 107.225846 -293.057326)
		(end 107.230418 -293.059866)
		(stroke
			(width 0.05715)
			(type default)
		)
		(layer "In2.Cu")
	)
	(gr_arc
		(start 107.244642 -293.069772)
		(mid 107.237567 -293.064766)
		(end 107.230418 -293.059866)
		(stroke
			(width 0.05715)
			(type default)
		)
		(layer "In2.Cu")
	)
	(gr_line
		(start 107.38104 -292.716204)
		(end 107.083098 -292.716204)
		(stroke
			(width 0.05715)
			(type default)
		)
		(layer "In2.Cu")
	)
	(gr_line
		(start 114.833908 -22.532594)
		(end 115.124738 -22.823424)
		(stroke
			(width 0.07112)
			(type default)
		)
		(layer "In2.Cu")
	)
	(gr_line
		(start 115.124738 -22.823424)
		(end 114.833908 -22.532594)
		(stroke
			(width 0.07112)
			(type default)
		)
		(layer "In2.Cu")
	)
	(gr_line
		(start 115.406678 -22.823424)
		(end 115.697508 -22.532594)
		(stroke
			(width 0.07112)
			(type default)
		)
		(layer "In2.Cu")
	)
	(gr_line
		(start 120.11533 -33.02508)
		(end 120.40616 -32.73425)
		(stroke
			(width 0.07112)
			(type default)
		)
		(layer "In2.Cu")
	)
	(gr_line
		(start 120.40616 -32.73425)
		(end 120.11533 -33.02508)
		(stroke
			(width 0.07112)
			(type default)
		)
		(layer "In2.Cu")
	)
	(gr_line
		(start 120.97893 -33.02508)
		(end 120.6881 -32.73425)
		(stroke
			(width 0.07112)
			(type default)
		)
		(layer "In2.Cu")
	)
	(gr_arc
		(start 122.102118 -9.272016)
		(mid 123.157118 -8.83502)
		(end 123.594114 -7.78002)
		(stroke
			(width 0.2)
			(type default)
		)
		(layer "In2.Cu")
	)
	(gr_line
		(start 123.594114 -7.78002)
		(end 123.594114 -4.879848)
		(stroke
			(width 0.2)
			(type default)
		)
		(layer "In2.Cu")
	)
	(gr_line
		(start 124.102114 -12.288012)
		(end 83.70189 -12.288012)
		(stroke
			(width 0.2)
			(type default)
		)
		(layer "In2.Cu")
	)
	(gr_arc
		(start 124.102114 -12.288012)
		(mid 125.875532 -11.553433)
		(end 126.61011 -9.780016)
		(stroke
			(width 0.2)
			(type default)
		)
		(layer "In2.Cu")
	)
	(gr_arc
		(start 126.10211 -2.371852)
		(mid 124.3287 -3.106426)
		(end 123.594114 -4.879848)
		(stroke
			(width 0.2)
			(type default)
		)
		(layer "In2.Cu")
	)
	(gr_line
		(start 126.10211 -2.371852)
		(end 194.701922 -2.371852)
		(stroke
			(width 0.2)
			(type default)
		)
		(layer "In2.Cu")
	)
	(gr_line
		(start 126.61011 -5.787898)
		(end 126.61011 -9.780016)
		(stroke
			(width 0.2)
			(type default)
		)
		(layer "In2.Cu")
	)
	(gr_line
		(start 130.505962 -11.548872)
		(end 130.215132 -11.839702)
		(stroke
			(width 0.07112)
			(type default)
		)
		(layer "In2.Cu")
	)
	(gr_line
		(start 130.787902 -11.548872)
		(end 131.078732 -11.839702)
		(stroke
			(width 0.07112)
			(type default)
		)
		(layer "In2.Cu")
	)
	(gr_line
		(start 141.954504 -370.40947)
		(end 141.663674 -370.11864)
		(stroke
			(width 0.07112)
			(type default)
		)
		(layer "In2.Cu")
	)
	(gr_line
		(start 141.954504 -369.54587)
		(end 141.663674 -369.8367)
		(stroke
			(width 0.07112)
			(type default)
		)
		(layer "In2.Cu")
	)
	(gr_line
		(start 174.09414 -57.809892)
		(end 174.093886 -57.809892)
		(stroke
			(width 0.07112)
			(type default)
		)
		(layer "In2.Cu")
	)
	(gr_line
		(start 174.094394 -57.8104)
		(end 174.09414 -57.809892)
		(stroke
			(width 0.07112)
			(type default)
		)
		(layer "In2.Cu")
	)
	(gr_line
		(start 174.094648 -57.809638)
		(end 174.094394 -57.8104)
		(stroke
			(width 0.07112)
			(type default)
		)
		(layer "In2.Cu")
	)
	(gr_line
		(start 174.168562 -57.630822)
		(end 174.09541 -57.80786)
		(stroke
			(width 0.07112)
			(type default)
		)
		(layer "In2.Cu")
	)
	(gr_line
		(start 174.560738 -57.468516)
		(end 174.168562 -57.630822)
		(stroke
			(width 0.07112)
			(type default)
		)
		(layer "In2.Cu")
	)
	(gr_line
		(start 174.737776 -57.541668)
		(end 174.560738 -57.468516)
		(stroke
			(width 0.07112)
			(type default)
		)
		(layer "In2.Cu")
	)
	(gr_line
		(start 174.739808 -57.542176)
		(end 174.740062 -57.542684)
		(stroke
			(width 0.07112)
			(type default)
		)
		(layer "In2.Cu")
	)
	(gr_line
		(start 174.740062 -57.542684)
		(end 174.739554 -57.54243)
		(stroke
			(width 0.07112)
			(type default)
		)
		(layer "In2.Cu")
	)
	(gr_line
		(start 174.847758 -57.80278)
		(end 174.201836 -58.070496)
		(stroke
			(width 0.07112)
			(type default)
		)
		(layer "In2.Cu")
	)
	(gr_line
		(start 175.13173 -57.380632)
		(end 175.131476 -57.37987)
		(stroke
			(width 0.07112)
			(type default)
		)
		(layer "In2.Cu")
	)
	(gr_line
		(start 175.132238 -57.379616)
		(end 175.13173 -57.380632)
		(stroke
			(width 0.07112)
			(type default)
		)
		(layer "In2.Cu")
	)
	(gr_line
		(start 175.205898 -57.201054)
		(end 175.132746 -57.378092)
		(stroke
			(width 0.07112)
			(type default)
		)
		(layer "In2.Cu")
	)
	(gr_line
		(start 175.598074 -57.038748)
		(end 175.205898 -57.201054)
		(stroke
			(width 0.07112)
			(type default)
		)
		(layer "In2.Cu")
	)
	(gr_line
		(start 175.774604 -57.112154)
		(end 175.598074 -57.038748)
		(stroke
			(width 0.07112)
			(type default)
		)
		(layer "In2.Cu")
	)
	(gr_line
		(start 175.77689 -57.112662)
		(end 175.777398 -57.11317)
		(stroke
			(width 0.07112)
			(type default)
		)
		(layer "In2.Cu")
	)
	(gr_line
		(start 175.77689 -57.112408)
		(end 175.77689 -57.112662)
		(stroke
			(width 0.07112)
			(type default)
		)
		(layer "In2.Cu")
	)
	(gr_line
		(start 175.777398 -57.11317)
		(end 175.776382 -57.112662)
		(stroke
			(width 0.07112)
			(type default)
		)
		(layer "In2.Cu")
	)
	(gr_line
		(start 175.88484 -57.373012)
		(end 175.239426 -57.640474)
		(stroke
			(width 0.07112)
			(type default)
		)
		(layer "In2.Cu")
	)
	(gr_line
		(start 176.185322 -56.943244)
		(end 176.078134 -56.987694)
		(stroke
			(width 0.07112)
			(type default)
		)
		(layer "In2.Cu")
	)
	(gr_line
		(start 176.25949 -56.763666)
		(end 176.186084 -56.941466)
		(stroke
			(width 0.07112)
			(type default)
		)
		(layer "In2.Cu")
	)
	(gr_line
		(start 176.293272 -57.203594)
		(end 176.186084 -57.248044)
		(stroke
			(width 0.07112)
			(type default)
		)
		(layer "In2.Cu")
	)
	(gr_line
		(start 176.651412 -56.60136)
		(end 176.25949 -56.763666)
		(stroke
			(width 0.07112)
			(type default)
		)
		(layer "In2.Cu")
	)
	(gr_line
		(start 176.829212 -56.67502)
		(end 176.651412 -56.60136)
		(stroke
			(width 0.07112)
			(type default)
		)
		(layer "In2.Cu")
	)
	(gr_line
		(start 176.938686 -56.936132)
		(end 176.293272 -57.203594)
		(stroke
			(width 0.07112)
			(type default)
		)
		(layer "In2.Cu")
	)
	(gr_line
		(start 178.721004 -43.190922)
		(end 179.011834 -43.481752)
		(stroke
			(width 0.07112)
			(type default)
		)
		(layer "In2.Cu")
	)
	(gr_line
		(start 178.721004 -42.908982)
		(end 179.011834 -42.618152)
		(stroke
			(width 0.07112)
			(type default)
		)
		(layer "In2.Cu")
	)
	(gr_line
		(start 179.011834 -55.481728)
		(end 179.302664 -55.190898)
		(stroke
			(width 0.07112)
			(type default)
		)
		(layer "In2.Cu")
	)
	(gr_line
		(start 179.011834 -54.618128)
		(end 179.302664 -54.908958)
		(stroke
			(width 0.07112)
			(type default)
		)
		(layer "In2.Cu")
	)
	(gr_line
		(start 179.011834 -52.481734)
		(end 179.302664 -52.190904)
		(stroke
			(width 0.07112)
			(type default)
		)
		(layer "In2.Cu")
	)
	(gr_line
		(start 179.011834 -51.618134)
		(end 179.302664 -51.908964)
		(stroke
			(width 0.07112)
			(type default)
		)
		(layer "In2.Cu")
	)
	(gr_line
		(start 179.011834 -49.48174)
		(end 179.302664 -49.19091)
		(stroke
			(width 0.07112)
			(type default)
		)
		(layer "In2.Cu")
	)
	(gr_line
		(start 179.011834 -48.61814)
		(end 179.302664 -48.90897)
		(stroke
			(width 0.07112)
			(type default)
		)
		(layer "In2.Cu")
	)
	(gr_line
		(start 179.011834 -46.481746)
		(end 179.302664 -46.190916)
		(stroke
			(width 0.07112)
			(type default)
		)
		(layer "In2.Cu")
	)
	(gr_line
		(start 179.011834 -45.618146)
		(end 179.302664 -45.908976)
		(stroke
			(width 0.07112)
			(type default)
		)
		(layer "In2.Cu")
	)
	(gr_line
		(start 183.150002 -56.329326)
		(end 183.150002 -56.52135)
		(stroke
			(width 0.07112)
			(type default)
		)
		(layer "In2.Cu")
	)
	(gr_line
		(start 183.45023 -56.029098)
		(end 183.150002 -56.329326)
		(stroke
			(width 0.07112)
			(type default)
		)
		(layer "In2.Cu")
	)
	(gr_line
		(start 183.570118 -49.898046)
		(end 183.870346 -50.198274)
		(stroke
			(width 0.07112)
			(type default)
		)
		(layer "In2.Cu")
	)
	(gr_line
		(start 183.570118 -49.705768)
		(end 183.570118 -49.898046)
		(stroke
			(width 0.07112)
			(type default)
		)
		(layer "In2.Cu")
	)
	(gr_line
		(start 183.642254 -56.029098)
		(end 183.45023 -56.029098)
		(stroke
			(width 0.07112)
			(type default)
		)
		(layer "In2.Cu")
	)
	(gr_line
		(start 183.711088 -46.684692)
		(end 184.011316 -46.98492)
		(stroke
			(width 0.07112)
			(type default)
		)
		(layer "In2.Cu")
	)
	(gr_line
		(start 183.711088 -46.492414)
		(end 183.711088 -46.684692)
		(stroke
			(width 0.07112)
			(type default)
		)
		(layer "In2.Cu")
	)
	(gr_line
		(start 183.769508 -49.5046)
		(end 184.263792 -49.998884)
		(stroke
			(width 0.07112)
			(type default)
		)
		(layer "In2.Cu")
	)
	(gr_line
		(start 183.814466 -55.063898)
		(end 183.950356 -55.199788)
		(stroke
			(width 0.07112)
			(type default)
		)
		(layer "In2.Cu")
	)
	(gr_line
		(start 183.814466 -54.639718)
		(end 183.814466 -55.063898)
		(stroke
			(width 0.07112)
			(type default)
		)
		(layer "In2.Cu")
	)
	(gr_line
		(start 183.814466 -53.941218)
		(end 183.950356 -54.077108)
		(stroke
			(width 0.07112)
			(type default)
		)
		(layer "In2.Cu")
	)
	(gr_line
		(start 183.814466 -53.517038)
		(end 183.814466 -53.941218)
		(stroke
			(width 0.07112)
			(type default)
		)
		(layer "In2.Cu")
	)
	(gr_line
		(start 183.843422 -56.228488)
		(end 183.349392 -56.722518)
		(stroke
			(width 0.07112)
			(type default)
		)
		(layer "In2.Cu")
	)
	(gr_line
		(start 183.870346 -50.198274)
		(end 184.062624 -50.198274)
		(stroke
			(width 0.07112)
			(type default)
		)
		(layer "In2.Cu")
	)
	(gr_line
		(start 183.910478 -46.291246)
		(end 184.404762 -46.78553)
		(stroke
			(width 0.07112)
			(type default)
		)
		(layer "In2.Cu")
	)
	(gr_line
		(start 183.950356 -54.503828)
		(end 183.814466 -54.639718)
		(stroke
			(width 0.07112)
			(type default)
		)
		(layer "In2.Cu")
	)
	(gr_line
		(start 183.950356 -53.381148)
		(end 183.814466 -53.517038)
		(stroke
			(width 0.07112)
			(type default)
		)
		(layer "In2.Cu")
	)
	(gr_line
		(start 184.011316 -46.98492)
		(end 184.203594 -46.98492)
		(stroke
			(width 0.07112)
			(type default)
		)
		(layer "In2.Cu")
	)
	(gr_line
		(start 184.233566 -54.502558)
		(end 184.233566 -55.201058)
		(stroke
			(width 0.07112)
			(type default)
		)
		(layer "In2.Cu")
	)
	(gr_line
		(start 184.233566 -53.379878)
		(end 184.233566 -54.078378)
		(stroke
			(width 0.07112)
			(type default)
		)
		(layer "In2.Cu")
	)
	(gr_line
		(start 184.364122 -50.69205)
		(end 184.66435 -50.992278)
		(stroke
			(width 0.07112)
			(type default)
		)
		(layer "In2.Cu")
	)
	(gr_line
		(start 184.364122 -50.499772)
		(end 184.364122 -50.69205)
		(stroke
			(width 0.07112)
			(type default)
		)
		(layer "In2.Cu")
	)
	(gr_line
		(start 184.38495 5.631434)
		(end 184.09412 5.922264)
		(stroke
			(width 0.07112)
			(type default)
		)
		(layer "In2.Cu")
	)
	(gr_line
		(start 184.38495 6.495034)
		(end 184.09412 6.204204)
		(stroke
			(width 0.07112)
			(type default)
		)
		(layer "In2.Cu")
	)
	(gr_line
		(start 184.505092 -47.478696)
		(end 184.80532 -47.778924)
		(stroke
			(width 0.07112)
			(type default)
		)
		(layer "In2.Cu")
	)
	(gr_line
		(start 184.505092 -47.286418)
		(end 184.505092 -47.478696)
		(stroke
			(width 0.07112)
			(type default)
		)
		(layer "In2.Cu")
	)
	(gr_line
		(start 184.563512 -50.298604)
		(end 185.057796 -50.792888)
		(stroke
			(width 0.07112)
			(type default)
		)
		(layer "In2.Cu")
	)
	(gr_line
		(start 184.66435 -50.992278)
		(end 184.856628 -50.992278)
		(stroke
			(width 0.07112)
			(type default)
		)
		(layer "In2.Cu")
	)
	(gr_line
		(start 184.704482 -47.08525)
		(end 185.198766 -47.579534)
		(stroke
			(width 0.07112)
			(type default)
		)
		(layer "In2.Cu")
	)
	(gr_line
		(start 184.80532 -47.778924)
		(end 184.997598 -47.778924)
		(stroke
			(width 0.07112)
			(type default)
		)
		(layer "In2.Cu")
	)
	(gr_line
		(start 185.036206 -52.582826)
		(end 185.172096 -52.718716)
		(stroke
			(width 0.07112)
			(type default)
		)
		(layer "In2.Cu")
	)
	(gr_line
		(start 185.036206 -52.158646)
		(end 185.036206 -52.582826)
		(stroke
			(width 0.07112)
			(type default)
		)
		(layer "In2.Cu")
	)
	(gr_line
		(start 185.172096 -52.022756)
		(end 185.036206 -52.158646)
		(stroke
			(width 0.07112)
			(type default)
		)
		(layer "In2.Cu")
	)
	(gr_line
		(start 185.455306 -52.021486)
		(end 185.455306 -52.719986)
		(stroke
			(width 0.07112)
			(type default)
		)
		(layer "In2.Cu")
	)
	(gr_line
		(start 185.99658 -50.708814)
		(end 186.13247 -50.844704)
		(stroke
			(width 0.07112)
			(type default)
		)
		(layer "In2.Cu")
	)
	(gr_line
		(start 185.99658 -50.284634)
		(end 185.99658 -50.708814)
		(stroke
			(width 0.07112)
			(type default)
		)
		(layer "In2.Cu")
	)
	(gr_line
		(start 186.13247 -50.148744)
		(end 185.99658 -50.284634)
		(stroke
			(width 0.07112)
			(type default)
		)
		(layer "In2.Cu")
	)
	(gr_line
		(start 186.41568 -50.147474)
		(end 186.41568 -50.845974)
		(stroke
			(width 0.07112)
			(type default)
		)
		(layer "In2.Cu")
	)
	(gr_line
		(start 194.193922 -9.780016)
		(end 194.193922 -5.787898)
		(stroke
			(width 0.2)
			(type default)
		)
		(layer "In2.Cu")
	)
	(gr_arc
		(start 194.193922 -9.780016)
		(mid 194.928504 -11.55342)
		(end 196.701918 -12.288012)
		(stroke
			(width 0.2)
			(type default)
		)
		(layer "In2.Cu")
	)
	(gr_line
		(start 194.193922 -5.787898)
		(end 126.61011 -5.787898)
		(stroke
			(width 0.2)
			(type default)
		)
		(layer "In2.Cu")
	)
	(gr_line
		(start 194.496944 -441.481972)
		(end 194.496944 -441.17006)
		(stroke
			(width 0.2)
			(type default)
		)
		(layer "In2.Cu")
	)
	(gr_arc
		(start 195.50507 -440.161934)
		(mid 194.792223 -440.457215)
		(end 194.496944 -441.17006)
		(stroke
			(width 0.2)
			(type default)
		)
		(layer "In2.Cu")
	)
	(gr_line
		(start 195.50507 -440.161934)
		(end 276.314916 -440.161934)
		(stroke
			(width 0.2)
			(type default)
		)
		(layer "In2.Cu")
	)
	(gr_arc
		(start 197.209918 -7.78002)
		(mid 197.646914 -8.83502)
		(end 198.701914 -9.272016)
		(stroke
			(width 0.2)
			(type default)
		)
		(layer "In2.Cu")
	)
	(gr_arc
		(start 197.209918 -4.879848)
		(mid 196.475361 -3.106388)
		(end 194.701922 -2.371852)
		(stroke
			(width 0.2)
			(type default)
		)
		(layer "In2.Cu")
	)
	(gr_line
		(start 197.209918 -4.879848)
		(end 197.209918 -7.78002)
		(stroke
			(width 0.2)
			(type default)
		)
		(layer "In2.Cu")
	)
	(gr_line
		(start 198.701914 -9.272016)
		(end 223.300036 -9.272016)
		(stroke
			(width 0.2)
			(type default)
		)
		(layer "In2.Cu")
	)
	(gr_line
		(start 221.30004 -12.288012)
		(end 196.701918 -12.288012)
		(stroke
			(width 0.2)
			(type default)
		)
		(layer "In2.Cu")
	)
	(gr_line
		(start 222.792036 -34.120074)
		(end 222.792036 -13.780008)
		(stroke
			(width 0.2)
			(type default)
		)
		(layer "In2.Cu")
	)
	(gr_arc
		(start 222.792036 -34.120074)
		(mid 223.526604 -35.8935)
		(end 225.300032 -36.62807)
		(stroke
			(width 0.2)
			(type default)
		)
		(layer "In2.Cu")
	)
	(gr_arc
		(start 222.792036 -13.780008)
		(mid 222.35504 -12.725008)
		(end 221.30004 -12.288012)
		(stroke
			(width 0.2)
			(type default)
		)
		(layer "In2.Cu")
	)
	(gr_arc
		(start 225.808032 -33.120076)
		(mid 225.952135 -33.467971)
		(end 226.30003 -33.612074)
		(stroke
			(width 0.2)
			(type default)
		)
		(layer "In2.Cu")
	)
	(gr_arc
		(start 225.808032 -11.780012)
		(mid 225.073463 -10.006571)
		(end 223.300036 -9.272016)
		(stroke
			(width 0.2)
			(type default)
		)
		(layer "In2.Cu")
	)
	(gr_line
		(start 225.808032 -11.780012)
		(end 225.808032 -33.120076)
		(stroke
			(width 0.2)
			(type default)
		)
		(layer "In2.Cu")
	)
	(gr_line
		(start 226.30003 -33.612074)
		(end 255.800098 -33.612074)
		(stroke
			(width 0.2)
			(type default)
		)
		(layer "In2.Cu")
	)
	(gr_line
		(start 249.964194 -216.660476)
		(end 249.964194 -217.361516)
		(stroke
			(width 0.07112)
			(type default)
		)
		(layer "In2.Cu")
	)
	(gr_line
		(start 249.964194 -215.532716)
		(end 249.964194 -216.233756)
		(stroke
			(width 0.07112)
			(type default)
		)
		(layer "In2.Cu")
	)
	(gr_line
		(start 249.964194 -214.404956)
		(end 249.964194 -215.105996)
		(stroke
			(width 0.07112)
			(type default)
		)
		(layer "In2.Cu")
	)
	(gr_line
		(start 249.964194 -213.277196)
		(end 249.964194 -213.978236)
		(stroke
			(width 0.07112)
			(type default)
		)
		(layer "In2.Cu")
	)
	(gr_line
		(start 250.247404 -216.661746)
		(end 250.383294 -216.797636)
		(stroke
			(width 0.07112)
			(type default)
		)
		(layer "In2.Cu")
	)
	(gr_line
		(start 250.247404 -215.533986)
		(end 250.383294 -215.669876)
		(stroke
			(width 0.07112)
			(type default)
		)
		(layer "In2.Cu")
	)
	(gr_line
		(start 250.247404 -214.406226)
		(end 250.383294 -214.542116)
		(stroke
			(width 0.07112)
			(type default)
		)
		(layer "In2.Cu")
	)
	(gr_line
		(start 250.247404 -213.278466)
		(end 250.383294 -213.414356)
		(stroke
			(width 0.07112)
			(type default)
		)
		(layer "In2.Cu")
	)
	(gr_line
		(start 250.383294 -217.224356)
		(end 250.247404 -217.360246)
		(stroke
			(width 0.07112)
			(type default)
		)
		(layer "In2.Cu")
	)
	(gr_line
		(start 250.383294 -216.797636)
		(end 250.383294 -217.224356)
		(stroke
			(width 0.07112)
			(type default)
		)
		(layer "In2.Cu")
	)
	(gr_line
		(start 250.383294 -216.096596)
		(end 250.247404 -216.232486)
		(stroke
			(width 0.07112)
			(type default)
		)
		(layer "In2.Cu")
	)
	(gr_line
		(start 250.383294 -215.669876)
		(end 250.383294 -216.096596)
		(stroke
			(width 0.07112)
			(type default)
		)
		(layer "In2.Cu")
	)
	(gr_line
		(start 250.383294 -214.968836)
		(end 250.247404 -215.104726)
		(stroke
			(width 0.07112)
			(type default)
		)
		(layer "In2.Cu")
	)
	(gr_line
		(start 250.383294 -214.542116)
		(end 250.383294 -214.968836)
		(stroke
			(width 0.07112)
			(type default)
		)
		(layer "In2.Cu")
	)
	(gr_line
		(start 250.383294 -213.841076)
		(end 250.247404 -213.976966)
		(stroke
			(width 0.07112)
			(type default)
		)
		(layer "In2.Cu")
	)
	(gr_line
		(start 250.383294 -213.414356)
		(end 250.383294 -213.841076)
		(stroke
			(width 0.07112)
			(type default)
		)
		(layer "In2.Cu")
	)
	(gr_line
		(start 251.455936 -218.656662)
		(end 251.455936 -219.357702)
		(stroke
			(width 0.07112)
			(type default)
		)
		(layer "In2.Cu")
	)
	(gr_line
		(start 251.455936 -217.528902)
		(end 251.455936 -218.229942)
		(stroke
			(width 0.07112)
			(type default)
		)
		(layer "In2.Cu")
	)
	(gr_line
		(start 251.455936 -216.401142)
		(end 251.455936 -217.102182)
		(stroke
			(width 0.07112)
			(type default)
		)
		(layer "In2.Cu")
	)
	(gr_line
		(start 251.455936 -215.273382)
		(end 251.455936 -215.974422)
		(stroke
			(width 0.07112)
			(type default)
		)
		(layer "In2.Cu")
	)
	(gr_line
		(start 251.739146 -218.657932)
		(end 251.875036 -218.793822)
		(stroke
			(width 0.07112)
			(type default)
		)
		(layer "In2.Cu")
	)
	(gr_line
		(start 251.739146 -217.530172)
		(end 251.875036 -217.666062)
		(stroke
			(width 0.07112)
			(type default)
		)
		(layer "In2.Cu")
	)
	(gr_line
		(start 251.739146 -216.402412)
		(end 251.875036 -216.538302)
		(stroke
			(width 0.07112)
			(type default)
		)
		(layer "In2.Cu")
	)
	(gr_line
		(start 251.739146 -215.274652)
		(end 251.875036 -215.410542)
		(stroke
			(width 0.07112)
			(type default)
		)
		(layer "In2.Cu")
	)
	(gr_line
		(start 251.875036 -219.220542)
		(end 251.739146 -219.356432)
		(stroke
			(width 0.07112)
			(type default)
		)
		(layer "In2.Cu")
	)
	(gr_line
		(start 251.875036 -218.793822)
		(end 251.875036 -219.220542)
		(stroke
			(width 0.07112)
			(type default)
		)
		(layer "In2.Cu")
	)
	(gr_line
		(start 251.875036 -218.092782)
		(end 251.739146 -218.228672)
		(stroke
			(width 0.07112)
			(type default)
		)
		(layer "In2.Cu")
	)
	(gr_line
		(start 251.875036 -217.666062)
		(end 251.875036 -218.092782)
		(stroke
			(width 0.07112)
			(type default)
		)
		(layer "In2.Cu")
	)
	(gr_line
		(start 251.875036 -216.965022)
		(end 251.739146 -217.100912)
		(stroke
			(width 0.07112)
			(type default)
		)
		(layer "In2.Cu")
	)
	(gr_line
		(start 251.875036 -216.538302)
		(end 251.875036 -216.965022)
		(stroke
			(width 0.07112)
			(type default)
		)
		(layer "In2.Cu")
	)
	(gr_line
		(start 251.875036 -215.837262)
		(end 251.739146 -215.973152)
		(stroke
			(width 0.07112)
			(type default)
		)
		(layer "In2.Cu")
	)
	(gr_line
		(start 251.875036 -215.410542)
		(end 251.875036 -215.837262)
		(stroke
			(width 0.07112)
			(type default)
		)
		(layer "In2.Cu")
	)
	(gr_line
		(start 253.119636 -218.241626)
		(end 253.119636 -218.942666)
		(stroke
			(width 0.07112)
			(type default)
		)
		(layer "In2.Cu")
	)
	(gr_line
		(start 253.119636 -217.113866)
		(end 253.119636 -217.814906)
		(stroke
			(width 0.07112)
			(type default)
		)
		(layer "In2.Cu")
	)
	(gr_line
		(start 253.119636 -215.986106)
		(end 253.119636 -216.687146)
		(stroke
			(width 0.07112)
			(type default)
		)
		(layer "In2.Cu")
	)
	(gr_line
		(start 253.119636 -214.858346)
		(end 253.119636 -215.559386)
		(stroke
			(width 0.07112)
			(type default)
		)
		(layer "In2.Cu")
	)
	(gr_line
		(start 253.402846 -218.242896)
		(end 253.538736 -218.378786)
		(stroke
			(width 0.07112)
			(type default)
		)
		(layer "In2.Cu")
	)
	(gr_line
		(start 253.402846 -217.115136)
		(end 253.538736 -217.251026)
		(stroke
			(width 0.07112)
			(type default)
		)
		(layer "In2.Cu")
	)
	(gr_line
		(start 253.402846 -215.987376)
		(end 253.538736 -216.123266)
		(stroke
			(width 0.07112)
			(type default)
		)
		(layer "In2.Cu")
	)
	(gr_line
		(start 253.402846 -214.859616)
		(end 253.538736 -214.995506)
		(stroke
			(width 0.07112)
			(type default)
		)
		(layer "In2.Cu")
	)
	(gr_line
		(start 253.538736 -218.805506)
		(end 253.402846 -218.941396)
		(stroke
			(width 0.07112)
			(type default)
		)
		(layer "In2.Cu")
	)
	(gr_line
		(start 253.538736 -218.378786)
		(end 253.538736 -218.805506)
		(stroke
			(width 0.07112)
			(type default)
		)
		(layer "In2.Cu")
	)
	(gr_line
		(start 253.538736 -217.677746)
		(end 253.402846 -217.813636)
		(stroke
			(width 0.07112)
			(type default)
		)
		(layer "In2.Cu")
	)
	(gr_line
		(start 253.538736 -217.251026)
		(end 253.538736 -217.677746)
		(stroke
			(width 0.07112)
			(type default)
		)
		(layer "In2.Cu")
	)
	(gr_line
		(start 253.538736 -216.549986)
		(end 253.402846 -216.685876)
		(stroke
			(width 0.07112)
			(type default)
		)
		(layer "In2.Cu")
	)
	(gr_line
		(start 253.538736 -216.123266)
		(end 253.538736 -216.549986)
		(stroke
			(width 0.07112)
			(type default)
		)
		(layer "In2.Cu")
	)
	(gr_line
		(start 253.538736 -215.422226)
		(end 253.402846 -215.558116)
		(stroke
			(width 0.07112)
			(type default)
		)
		(layer "In2.Cu")
	)
	(gr_line
		(start 253.538736 -214.995506)
		(end 253.538736 -215.422226)
		(stroke
			(width 0.07112)
			(type default)
		)
		(layer "In2.Cu")
	)
	(gr_line
		(start 254.267462 -218.948254)
		(end 254.267462 -219.649294)
		(stroke
			(width 0.07112)
			(type default)
		)
		(layer "In2.Cu")
	)
	(gr_line
		(start 254.267462 -217.820494)
		(end 254.267462 -218.521534)
		(stroke
			(width 0.07112)
			(type default)
		)
		(layer "In2.Cu")
	)
	(gr_line
		(start 254.267462 -216.692734)
		(end 254.267462 -217.393774)
		(stroke
			(width 0.07112)
			(type default)
		)
		(layer "In2.Cu")
	)
	(gr_line
		(start 254.267462 -215.564974)
		(end 254.267462 -216.266014)
		(stroke
			(width 0.07112)
			(type default)
		)
		(layer "In2.Cu")
	)
	(gr_line
		(start 254.550672 -218.949524)
		(end 254.686562 -219.085414)
		(stroke
			(width 0.07112)
			(type default)
		)
		(layer "In2.Cu")
	)
	(gr_line
		(start 254.550672 -217.821764)
		(end 254.686562 -217.957654)
		(stroke
			(width 0.07112)
			(type default)
		)
		(layer "In2.Cu")
	)
	(gr_line
		(start 254.550672 -216.694004)
		(end 254.686562 -216.829894)
		(stroke
			(width 0.07112)
			(type default)
		)
		(layer "In2.Cu")
	)
	(gr_line
		(start 254.550672 -215.566244)
		(end 254.686562 -215.702134)
		(stroke
			(width 0.07112)
			(type default)
		)
		(layer "In2.Cu")
	)
	(gr_line
		(start 254.686562 -219.512134)
		(end 254.550672 -219.648024)
		(stroke
			(width 0.07112)
			(type default)
		)
		(layer "In2.Cu")
	)
	(gr_line
		(start 254.686562 -219.085414)
		(end 254.686562 -219.512134)
		(stroke
			(width 0.07112)
			(type default)
		)
		(layer "In2.Cu")
	)
	(gr_line
		(start 254.686562 -218.384374)
		(end 254.550672 -218.520264)
		(stroke
			(width 0.07112)
			(type default)
		)
		(layer "In2.Cu")
	)
	(gr_line
		(start 254.686562 -217.957654)
		(end 254.686562 -218.384374)
		(stroke
			(width 0.07112)
			(type default)
		)
		(layer "In2.Cu")
	)
	(gr_line
		(start 254.686562 -217.256614)
		(end 254.550672 -217.392504)
		(stroke
			(width 0.07112)
			(type default)
		)
		(layer "In2.Cu")
	)
	(gr_line
		(start 254.686562 -216.829894)
		(end 254.686562 -217.256614)
		(stroke
			(width 0.07112)
			(type default)
		)
		(layer "In2.Cu")
	)
	(gr_line
		(start 254.686562 -216.128854)
		(end 254.550672 -216.264744)
		(stroke
			(width 0.07112)
			(type default)
		)
		(layer "In2.Cu")
	)
	(gr_line
		(start 254.686562 -215.702134)
		(end 254.686562 -216.128854)
		(stroke
			(width 0.07112)
			(type default)
		)
		(layer "In2.Cu")
	)
	(gr_arc
		(start 255.800098 -33.612074)
		(mid 256.147993 -33.467971)
		(end 256.292096 -33.120076)
		(stroke
			(width 0.2)
			(type default)
		)
		(layer "In2.Cu")
	)
	(gr_line
		(start 255.927098 -213.806024)
		(end 255.636268 -213.515194)
		(stroke
			(width 0.07112)
			(type default)
		)
		(layer "In2.Cu")
	)
	(gr_line
		(start 255.927098 -212.942424)
		(end 255.636268 -213.233254)
		(stroke
			(width 0.07112)
			(type default)
		)
		(layer "In2.Cu")
	)
	(gr_line
		(start 255.927098 -211.011516)
		(end 255.636268 -210.720686)
		(stroke
			(width 0.07112)
			(type default)
		)
		(layer "In2.Cu")
	)
	(gr_line
		(start 255.927098 -210.147916)
		(end 255.636268 -210.438746)
		(stroke
			(width 0.07112)
			(type default)
		)
		(layer "In2.Cu")
	)
	(gr_line
		(start 255.927098 -208.217008)
		(end 255.636268 -207.926178)
		(stroke
			(width 0.07112)
			(type default)
		)
		(layer "In2.Cu")
	)
	(gr_line
		(start 255.927098 -207.353408)
		(end 255.636268 -207.644238)
		(stroke
			(width 0.07112)
			(type default)
		)
		(layer "In2.Cu")
	)
	(gr_line
		(start 255.927098 -205.439772)
		(end 255.636268 -205.148942)
		(stroke
			(width 0.07112)
			(type default)
		)
		(layer "In2.Cu")
	)
	(gr_line
		(start 255.927098 -204.576172)
		(end 255.636268 -204.867002)
		(stroke
			(width 0.07112)
			(type default)
		)
		(layer "In2.Cu")
	)
	(gr_line
		(start 256.292096 -33.120076)
		(end 256.292096 -11.780012)
		(stroke
			(width 0.2)
			(type default)
		)
		(layer "In2.Cu")
	)
	(gr_line
		(start 256.800096 -36.62807)
		(end 225.300032 -36.62807)
		(stroke
			(width 0.2)
			(type default)
		)
		(layer "In2.Cu")
	)
	(gr_arc
		(start 256.800096 -36.62807)
		(mid 258.57351 -35.893495)
		(end 259.308092 -34.120074)
		(stroke
			(width 0.2)
			(type default)
		)
		(layer "In2.Cu")
	)
	(gr_arc
		(start 258.800092 -9.272016)
		(mid 257.02668 -10.006595)
		(end 256.292096 -11.780012)
		(stroke
			(width 0.2)
			(type default)
		)
		(layer "In2.Cu")
	)
	(gr_line
		(start 258.800092 -9.272016)
		(end 383.601976 -9.272016)
		(stroke
			(width 0.2)
			(type default)
		)
		(layer "In2.Cu")
	)
	(gr_line
		(start 259.308092 -13.780008)
		(end 259.308092 -34.120074)
		(stroke
			(width 0.2)
			(type default)
		)
		(layer "In2.Cu")
	)
	(gr_arc
		(start 260.800088 -12.288012)
		(mid 259.745088 -12.725008)
		(end 259.308092 -13.780008)
		(stroke
			(width 0.2)
			(type default)
		)
		(layer "In2.Cu")
	)
	(gr_line
		(start 261.02564 -322.285868)
		(end 261.02564 -322.285614)
		(stroke
			(width 0.07112)
			(type default)
		)
		(layer "In2.Cu")
	)
	(gr_line
		(start 262.001508 -322.805298)
		(end 262.001254 -322.805298)
		(stroke
			(width 0.07112)
			(type default)
		)
		(layer "In2.Cu")
	)
	(gr_line
		(start 262.001508 -322.805298)
		(end 262.05307 -322.826888)
		(stroke
			(width 0.07112)
			(type default)
		)
		(layer "In2.Cu")
	)
	(gr_line
		(start 262.05307 -322.826888)
		(end 262.108696 -322.827142)
		(stroke
			(width 0.07112)
			(type default)
		)
		(layer "In2.Cu")
	)
	(gr_line
		(start 262.108696 -322.827142)
		(end 262.10895 -322.827142)
		(stroke
			(width 0.07112)
			(type default)
		)
		(layer "In2.Cu")
	)
	(gr_line
		(start 262.110474 -322.545202)
		(end 262.110728 -322.545202)
		(stroke
			(width 0.07112)
			(type default)
		)
		(layer "In2.Cu")
	)
	(gr_line
		(start 262.642858 -320.403728)
		(end 262.651748 -320.52768)
		(stroke
			(width 0.07112)
			(type default)
		)
		(layer "In2.Cu")
	)
	(gr_line
		(start 262.651748 -320.52768)
		(end 262.734044 -320.609976)
		(stroke
			(width 0.07112)
			(type default)
		)
		(layer "In2.Cu")
	)
	(gr_line
		(start 262.734044 -320.609976)
		(end 262.815324 -320.644012)
		(stroke
			(width 0.07112)
			(type default)
		)
		(layer "In2.Cu")
	)
	(gr_line
		(start 263.052814 -321.586098)
		(end 263.053068 -321.586098)
		(stroke
			(width 0.07112)
			(type default)
		)
		(layer "In2.Cu")
	)
	(gr_line
		(start 264.082022 -316.608714)
		(end 264.082022 -316.608968)
		(stroke
			(width 0.07112)
			(type default)
		)
		(layer "In2.Cu")
	)
	(gr_line
		(start 277.323042 -441.481972)
		(end 463.300064 -441.481972)
		(stroke
			(width 0.2)
			(type default)
		)
		(layer "In2.Cu")
	)
	(gr_arc
		(start 277.323042 -441.17006)
		(mid 277.027756 -440.457227)
		(end 276.314916 -440.161934)
		(stroke
			(width 0.2)
			(type default)
		)
		(layer "In2.Cu")
	)
	(gr_line
		(start 277.323042 -441.17006)
		(end 277.323042 -441.481972)
		(stroke
			(width 0.2)
			(type default)
		)
		(layer "In2.Cu")
	)
	(gr_line
		(start 280.90368 -407.9367)
		(end 280.90368 -407.23566)
		(stroke
			(width 0.07112)
			(type default)
		)
		(layer "In2.Cu")
	)
	(gr_line
		(start 280.90368 -406.80894)
		(end 280.90368 -406.1079)
		(stroke
			(width 0.07112)
			(type default)
		)
		(layer "In2.Cu")
	)
	(gr_line
		(start 280.90368 -405.68118)
		(end 280.90368 -404.98014)
		(stroke
			(width 0.07112)
			(type default)
		)
		(layer "In2.Cu")
	)
	(gr_line
		(start 280.90368 -404.55342)
		(end 280.90368 -403.85238)
		(stroke
			(width 0.07112)
			(type default)
		)
		(layer "In2.Cu")
	)
	(gr_line
		(start 280.90368 -403.42566)
		(end 280.90368 -402.72462)
		(stroke
			(width 0.07112)
			(type default)
		)
		(layer "In2.Cu")
	)
	(gr_line
		(start 281.18689 -407.93543)
		(end 281.32278 -407.79954)
		(stroke
			(width 0.07112)
			(type default)
		)
		(layer "In2.Cu")
	)
	(gr_line
		(start 281.18689 -406.80767)
		(end 281.32278 -406.67178)
		(stroke
			(width 0.07112)
			(type default)
		)
		(layer "In2.Cu")
	)
	(gr_line
		(start 281.18689 -405.67991)
		(end 281.32278 -405.54402)
		(stroke
			(width 0.07112)
			(type default)
		)
		(layer "In2.Cu")
	)
	(gr_line
		(start 281.18689 -404.55215)
		(end 281.32278 -404.41626)
		(stroke
			(width 0.07112)
			(type default)
		)
		(layer "In2.Cu")
	)
	(gr_line
		(start 281.18689 -403.42439)
		(end 281.32278 -403.2885)
		(stroke
			(width 0.07112)
			(type default)
		)
		(layer "In2.Cu")
	)
	(gr_line
		(start 281.287728 -401.714716)
		(end 281.78379 -401.218654)
		(stroke
			(width 0.07112)
			(type default)
		)
		(layer "In2.Cu")
	)
	(gr_line
		(start 281.32278 -407.79954)
		(end 281.32278 -407.37282)
		(stroke
			(width 0.07112)
			(type default)
		)
		(layer "In2.Cu")
	)
	(gr_line
		(start 281.32278 -407.37282)
		(end 281.18689 -407.23693)
		(stroke
			(width 0.07112)
			(type default)
		)
		(layer "In2.Cu")
	)
	(gr_line
		(start 281.32278 -406.67178)
		(end 281.32278 -406.24506)
		(stroke
			(width 0.07112)
			(type default)
		)
		(layer "In2.Cu")
	)
	(gr_line
		(start 281.32278 -406.24506)
		(end 281.18689 -406.10917)
		(stroke
			(width 0.07112)
			(type default)
		)
		(layer "In2.Cu")
	)
	(gr_line
		(start 281.32278 -405.54402)
		(end 281.32278 -405.1173)
		(stroke
			(width 0.07112)
			(type default)
		)
		(layer "In2.Cu")
	)
	(gr_line
		(start 281.32278 -405.1173)
		(end 281.18689 -404.98141)
		(stroke
			(width 0.07112)
			(type default)
		)
		(layer "In2.Cu")
	)
	(gr_line
		(start 281.32278 -404.41626)
		(end 281.32278 -403.98954)
		(stroke
			(width 0.07112)
			(type default)
		)
		(layer "In2.Cu")
	)
	(gr_line
		(start 281.32278 -403.98954)
		(end 281.18689 -403.85365)
		(stroke
			(width 0.07112)
			(type default)
		)
		(layer "In2.Cu")
	)
	(gr_line
		(start 281.32278 -403.2885)
		(end 281.32278 -402.86178)
		(stroke
			(width 0.07112)
			(type default)
		)
		(layer "In2.Cu")
	)
	(gr_line
		(start 281.32278 -402.86178)
		(end 281.18689 -402.72589)
		(stroke
			(width 0.07112)
			(type default)
		)
		(layer "In2.Cu")
	)
	(gr_line
		(start 281.488896 -401.914106)
		(end 281.681174 -401.914106)
		(stroke
			(width 0.07112)
			(type default)
		)
		(layer "In2.Cu")
	)
	(gr_line
		(start 281.681174 -401.914106)
		(end 281.98318 -401.6121)
		(stroke
			(width 0.07112)
			(type default)
		)
		(layer "In2.Cu")
	)
	(gr_line
		(start 281.88031 -408.35326)
		(end 281.74442 -408.48915)
		(stroke
			(width 0.07112)
			(type default)
		)
		(layer "In2.Cu")
	)
	(gr_line
		(start 281.98318 -401.6121)
		(end 281.98318 -401.419822)
		(stroke
			(width 0.07112)
			(type default)
		)
		(layer "In2.Cu")
	)
	(gr_line
		(start 282.085288 -400.917156)
		(end 282.58135 -400.421094)
		(stroke
			(width 0.07112)
			(type default)
		)
		(layer "In2.Cu")
	)
	(gr_line
		(start 282.286456 -401.116546)
		(end 282.478734 -401.116546)
		(stroke
			(width 0.07112)
			(type default)
		)
		(layer "In2.Cu")
	)
	(gr_line
		(start 282.30703 -408.35326)
		(end 281.88031 -408.35326)
		(stroke
			(width 0.07112)
			(type default)
		)
		(layer "In2.Cu")
	)
	(gr_line
		(start 282.44292 -408.48915)
		(end 282.30703 -408.35326)
		(stroke
			(width 0.07112)
			(type default)
		)
		(layer "In2.Cu")
	)
	(gr_line
		(start 282.44419 -408.77236)
		(end 281.74315 -408.77236)
		(stroke
			(width 0.07112)
			(type default)
		)
		(layer "In2.Cu")
	)
	(gr_line
		(start 282.478734 -401.116546)
		(end 282.78074 -400.81454)
		(stroke
			(width 0.07112)
			(type default)
		)
		(layer "In2.Cu")
	)
	(gr_line
		(start 282.78074 -400.81454)
		(end 282.78074 -400.622262)
		(stroke
			(width 0.07112)
			(type default)
		)
		(layer "In2.Cu")
	)
	(gr_line
		(start 282.882848 -400.119596)
		(end 283.37891 -399.623534)
		(stroke
			(width 0.07112)
			(type default)
		)
		(layer "In2.Cu")
	)
	(gr_line
		(start 282.917138 -407.556716)
		(end 283.207968 -407.847546)
		(stroke
			(width 0.07112)
			(type default)
		)
		(layer "In2.Cu")
	)
	(gr_line
		(start 283.084016 -400.318986)
		(end 283.276294 -400.318986)
		(stroke
			(width 0.07112)
			(type default)
		)
		(layer "In2.Cu")
	)
	(gr_line
		(start 283.276294 -400.318986)
		(end 283.5783 -400.01698)
		(stroke
			(width 0.07112)
			(type default)
		)
		(layer "In2.Cu")
	)
	(gr_line
		(start 283.5783 -400.01698)
		(end 283.5783 -399.824702)
		(stroke
			(width 0.07112)
			(type default)
		)
		(layer "In2.Cu")
	)
	(gr_line
		(start 283.680408 -399.322036)
		(end 284.17647 -398.825974)
		(stroke
			(width 0.07112)
			(type default)
		)
		(layer "In2.Cu")
	)
	(gr_line
		(start 283.780738 -407.556716)
		(end 283.489908 -407.847546)
		(stroke
			(width 0.07112)
			(type default)
		)
		(layer "In2.Cu")
	)
	(gr_line
		(start 283.881576 -399.521426)
		(end 284.073854 -399.521426)
		(stroke
			(width 0.07112)
			(type default)
		)
		(layer "In2.Cu")
	)
	(gr_line
		(start 284.005782 -404.215092)
		(end 284.296612 -403.924262)
		(stroke
			(width 0.07112)
			(type default)
		)
		(layer "In2.Cu")
	)
	(gr_line
		(start 284.005782 -403.351492)
		(end 284.296612 -403.642322)
		(stroke
			(width 0.07112)
			(type default)
		)
		(layer "In2.Cu")
	)
	(gr_line
		(start 284.073854 -399.521426)
		(end 284.37586 -399.21942)
		(stroke
			(width 0.07112)
			(type default)
		)
		(layer "In2.Cu")
	)
	(gr_line
		(start 284.37586 -399.21942)
		(end 284.37586 -399.027142)
		(stroke
			(width 0.07112)
			(type default)
		)
		(layer "In2.Cu")
	)
	(gr_line
		(start 284.477968 -398.524476)
		(end 284.97403 -398.028414)
		(stroke
			(width 0.07112)
			(type default)
		)
		(layer "In2.Cu")
	)
	(gr_line
		(start 284.679136 -398.723866)
		(end 284.871414 -398.723866)
		(stroke
			(width 0.07112)
			(type default)
		)
		(layer "In2.Cu")
	)
	(gr_line
		(start 284.871414 -398.723866)
		(end 285.17342 -398.42186)
		(stroke
			(width 0.07112)
			(type default)
		)
		(layer "In2.Cu")
	)
	(gr_line
		(start 285.17342 -398.42186)
		(end 285.17342 -398.229582)
		(stroke
			(width 0.07112)
			(type default)
		)
		(layer "In2.Cu")
	)
	(gr_line
		(start 285.79699 -397.601948)
		(end 286.49803 -397.601948)
		(stroke
			(width 0.07112)
			(type default)
		)
		(layer "In2.Cu")
	)
	(gr_line
		(start 285.79826 -397.885158)
		(end 285.93415 -398.021048)
		(stroke
			(width 0.07112)
			(type default)
		)
		(layer "In2.Cu")
	)
	(gr_line
		(start 285.93415 -398.021048)
		(end 286.36087 -398.021048)
		(stroke
			(width 0.07112)
			(type default)
		)
		(layer "In2.Cu")
	)
	(gr_line
		(start 286.36087 -398.021048)
		(end 286.49676 -397.885158)
		(stroke
			(width 0.07112)
			(type default)
		)
		(layer "In2.Cu")
	)
	(gr_line
		(start 286.796734 -404.22322)
		(end 287.497774 -404.22322)
		(stroke
			(width 0.07112)
			(type default)
		)
		(layer "In2.Cu")
	)
	(gr_line
		(start 286.798004 -404.50643)
		(end 286.933894 -404.64232)
		(stroke
			(width 0.07112)
			(type default)
		)
		(layer "In2.Cu")
	)
	(gr_line
		(start 286.92475 -397.601948)
		(end 287.62579 -397.601948)
		(stroke
			(width 0.07112)
			(type default)
		)
		(layer "In2.Cu")
	)
	(gr_line
		(start 286.92602 -397.885158)
		(end 287.06191 -398.021048)
		(stroke
			(width 0.07112)
			(type default)
		)
		(layer "In2.Cu")
	)
	(gr_line
		(start 286.933894 -404.64232)
		(end 287.360614 -404.64232)
		(stroke
			(width 0.07112)
			(type default)
		)
		(layer "In2.Cu")
	)
	(gr_line
		(start 287.06191 -398.021048)
		(end 287.48863 -398.021048)
		(stroke
			(width 0.07112)
			(type default)
		)
		(layer "In2.Cu")
	)
	(gr_line
		(start 287.360614 -404.64232)
		(end 287.496504 -404.50643)
		(stroke
			(width 0.07112)
			(type default)
		)
		(layer "In2.Cu")
	)
	(gr_line
		(start 287.483296 -407.414222)
		(end 287.774126 -407.123392)
		(stroke
			(width 0.07112)
			(type default)
		)
		(layer "In2.Cu")
	)
	(gr_line
		(start 287.483296 -406.550622)
		(end 287.774126 -406.841452)
		(stroke
			(width 0.07112)
			(type default)
		)
		(layer "In2.Cu")
	)
	(gr_line
		(start 287.48863 -398.021048)
		(end 287.62452 -397.885158)
		(stroke
			(width 0.07112)
			(type default)
		)
		(layer "In2.Cu")
	)
	(gr_line
		(start 288.107374 -404.22322)
		(end 288.808414 -404.22322)
		(stroke
			(width 0.07112)
			(type default)
		)
		(layer "In2.Cu")
	)
	(gr_line
		(start 288.108644 -404.50643)
		(end 288.244534 -404.64232)
		(stroke
			(width 0.07112)
			(type default)
		)
		(layer "In2.Cu")
	)
	(gr_line
		(start 288.244534 -404.64232)
		(end 288.671254 -404.64232)
		(stroke
			(width 0.07112)
			(type default)
		)
		(layer "In2.Cu")
	)
	(gr_line
		(start 288.613342 -406.841452)
		(end 289.314382 -406.841452)
		(stroke
			(width 0.07112)
			(type default)
		)
		(layer "In2.Cu")
	)
	(gr_line
		(start 288.614612 -407.124662)
		(end 288.750502 -407.260552)
		(stroke
			(width 0.07112)
			(type default)
		)
		(layer "In2.Cu")
	)
	(gr_line
		(start 288.671254 -404.64232)
		(end 288.807144 -404.50643)
		(stroke
			(width 0.07112)
			(type default)
		)
		(layer "In2.Cu")
	)
	(gr_line
		(start 288.750502 -407.260552)
		(end 289.177222 -407.260552)
		(stroke
			(width 0.07112)
			(type default)
		)
		(layer "In2.Cu")
	)
	(gr_line
		(start 289.177222 -407.260552)
		(end 289.313112 -407.124662)
		(stroke
			(width 0.07112)
			(type default)
		)
		(layer "In2.Cu")
	)
	(gr_line
		(start 290.300918 -403.025356)
		(end 290.591748 -402.734526)
		(stroke
			(width 0.07112)
			(type default)
		)
		(layer "In2.Cu")
	)
	(gr_line
		(start 290.300918 -402.161756)
		(end 290.591748 -402.452586)
		(stroke
			(width 0.07112)
			(type default)
		)
		(layer "In2.Cu")
	)
	(gr_line
		(start 290.451032 -397.601948)
		(end 291.152072 -397.601948)
		(stroke
			(width 0.07112)
			(type default)
		)
		(layer "In2.Cu")
	)
	(gr_line
		(start 290.452302 -397.885158)
		(end 290.588192 -398.021048)
		(stroke
			(width 0.07112)
			(type default)
		)
		(layer "In2.Cu")
	)
	(gr_line
		(start 290.588192 -398.021048)
		(end 291.014912 -398.021048)
		(stroke
			(width 0.07112)
			(type default)
		)
		(layer "In2.Cu")
	)
	(gr_line
		(start 291.014912 -398.021048)
		(end 291.150802 -397.885158)
		(stroke
			(width 0.07112)
			(type default)
		)
		(layer "In2.Cu")
	)
	(gr_line
		(start 291.05225 -406.329642)
		(end 291.548058 -405.833834)
		(stroke
			(width 0.07112)
			(type default)
		)
		(layer "In2.Cu")
	)
	(gr_line
		(start 291.253418 -406.529032)
		(end 291.445442 -406.529032)
		(stroke
			(width 0.07112)
			(type default)
		)
		(layer "In2.Cu")
	)
	(gr_line
		(start 291.445442 -406.529032)
		(end 291.747448 -406.227026)
		(stroke
			(width 0.07112)
			(type default)
		)
		(layer "In2.Cu")
	)
	(gr_line
		(start 291.747448 -406.227026)
		(end 291.747448 -406.035002)
		(stroke
			(width 0.07112)
			(type default)
		)
		(layer "In2.Cu")
	)
	(gr_line
		(start 292.18382 -402.233638)
		(end 292.679882 -401.737576)
		(stroke
			(width 0.07112)
			(type default)
		)
		(layer "In2.Cu")
	)
	(gr_line
		(start 292.384988 -402.433028)
		(end 292.577266 -402.433028)
		(stroke
			(width 0.07112)
			(type default)
		)
		(layer "In2.Cu")
	)
	(gr_line
		(start 292.577266 -402.433028)
		(end 292.879272 -402.131022)
		(stroke
			(width 0.07112)
			(type default)
		)
		(layer "In2.Cu")
	)
	(gr_line
		(start 292.754812 -397.601948)
		(end 293.455852 -397.601948)
		(stroke
			(width 0.07112)
			(type default)
		)
		(layer "In2.Cu")
	)
	(gr_line
		(start 292.756082 -397.885158)
		(end 292.891972 -398.021048)
		(stroke
			(width 0.07112)
			(type default)
		)
		(layer "In2.Cu")
	)
	(gr_line
		(start 292.879272 -402.131022)
		(end 292.879272 -401.938744)
		(stroke
			(width 0.07112)
			(type default)
		)
		(layer "In2.Cu")
	)
	(gr_line
		(start 292.891972 -398.021048)
		(end 293.318692 -398.021048)
		(stroke
			(width 0.07112)
			(type default)
		)
		(layer "In2.Cu")
	)
	(gr_line
		(start 292.98138 -401.436078)
		(end 293.477442 -400.940016)
		(stroke
			(width 0.07112)
			(type default)
		)
		(layer "In2.Cu")
	)
	(gr_line
		(start 293.182548 -401.635468)
		(end 293.374826 -401.635468)
		(stroke
			(width 0.07112)
			(type default)
		)
		(layer "In2.Cu")
	)
	(gr_line
		(start 293.318692 -398.021048)
		(end 293.454582 -397.885158)
		(stroke
			(width 0.07112)
			(type default)
		)
		(layer "In2.Cu")
	)
	(gr_line
		(start 293.374826 -401.635468)
		(end 293.676832 -401.333462)
		(stroke
			(width 0.07112)
			(type default)
		)
		(layer "In2.Cu")
	)
	(gr_line
		(start 293.676832 -401.333462)
		(end 293.676832 -401.141184)
		(stroke
			(width 0.07112)
			(type default)
		)
		(layer "In2.Cu")
	)
	(gr_line
		(start 293.98468 -397.383)
		(end 294.480742 -396.886938)
		(stroke
			(width 0.07112)
			(type default)
		)
		(layer "In2.Cu")
	)
	(gr_line
		(start 294.185848 -397.58239)
		(end 294.378126 -397.58239)
		(stroke
			(width 0.07112)
			(type default)
		)
		(layer "In2.Cu")
	)
	(gr_line
		(start 294.378126 -397.58239)
		(end 294.680132 -397.280384)
		(stroke
			(width 0.07112)
			(type default)
		)
		(layer "In2.Cu")
	)
	(gr_line
		(start 294.680132 -397.280384)
		(end 294.680132 -397.088106)
		(stroke
			(width 0.07112)
			(type default)
		)
		(layer "In2.Cu")
	)
	(gr_line
		(start 294.78224 -396.58544)
		(end 295.278302 -396.089378)
		(stroke
			(width 0.07112)
			(type default)
		)
		(layer "In2.Cu")
	)
	(gr_line
		(start 294.983408 -396.78483)
		(end 295.175686 -396.78483)
		(stroke
			(width 0.07112)
			(type default)
		)
		(layer "In2.Cu")
	)
	(gr_line
		(start 295.175686 -396.78483)
		(end 295.477692 -396.482824)
		(stroke
			(width 0.07112)
			(type default)
		)
		(layer "In2.Cu")
	)
	(gr_line
		(start 295.477692 -396.482824)
		(end 295.477692 -396.290546)
		(stroke
			(width 0.07112)
			(type default)
		)
		(layer "In2.Cu")
	)
	(gr_line
		(start 296.991786 -395.880844)
		(end 297.282616 -396.171674)
		(stroke
			(width 0.07112)
			(type default)
		)
		(layer "In2.Cu")
	)
	(gr_line
		(start 296.991786 -395.598904)
		(end 297.282616 -395.308074)
		(stroke
			(width 0.07112)
			(type default)
		)
		(layer "In2.Cu")
	)
	(gr_line
		(start 303.786794 -402.804122)
		(end 304.487834 -402.804122)
		(stroke
			(width 0.07112)
			(type default)
		)
		(layer "In2.Cu")
	)
	(gr_line
		(start 303.788064 -403.087332)
		(end 303.923954 -403.223222)
		(stroke
			(width 0.07112)
			(type default)
		)
		(layer "In2.Cu")
	)
	(gr_line
		(start 303.923954 -403.223222)
		(end 304.350674 -403.223222)
		(stroke
			(width 0.07112)
			(type default)
		)
		(layer "In2.Cu")
	)
	(gr_line
		(start 304.350674 -403.223222)
		(end 304.486564 -403.087332)
		(stroke
			(width 0.07112)
			(type default)
		)
		(layer "In2.Cu")
	)
	(gr_line
		(start 304.914554 -402.804122)
		(end 305.615594 -402.804122)
		(stroke
			(width 0.07112)
			(type default)
		)
		(layer "In2.Cu")
	)
	(gr_line
		(start 304.915824 -403.087332)
		(end 305.051714 -403.223222)
		(stroke
			(width 0.07112)
			(type default)
		)
		(layer "In2.Cu")
	)
	(gr_line
		(start 305.034442 -153.958036)
		(end 305.402742 -153.589736)
		(stroke
			(width 0.127)
			(type default)
		)
		(layer "In2.Cu")
	)
	(gr_line
		(start 305.034442 -152.840436)
		(end 305.402742 -153.208736)
		(stroke
			(width 0.127)
			(type default)
		)
		(layer "In2.Cu")
	)
	(gr_line
		(start 305.051714 -403.223222)
		(end 305.478434 -403.223222)
		(stroke
			(width 0.07112)
			(type default)
		)
		(layer "In2.Cu")
	)
	(gr_line
		(start 305.478434 -403.223222)
		(end 305.614324 -403.087332)
		(stroke
			(width 0.07112)
			(type default)
		)
		(layer "In2.Cu")
	)
	(gr_line
		(start 316.73419 4.941824)
		(end 316.44336 4.650994)
		(stroke
			(width 0.07112)
			(type default)
		)
		(layer "In2.Cu")
	)
	(gr_line
		(start 316.73419 5.223764)
		(end 316.44336 5.514594)
		(stroke
			(width 0.07112)
			(type default)
		)
		(layer "In2.Cu")
	)
	(gr_line
		(start 324.75805 -310.335168)
		(end 324.83171 -310.157114)
		(stroke
			(width 0.07112)
			(type default)
		)
		(layer "In2.Cu")
	)
	(gr_line
		(start 324.821296 -398.92097)
		(end 325.317358 -398.424908)
		(stroke
			(width 0.07112)
			(type default)
		)
		(layer "In2.Cu")
	)
	(gr_line
		(start 324.83171 -310.157114)
		(end 325.226172 -309.993792)
		(stroke
			(width 0.07112)
			(type default)
		)
		(layer "In2.Cu")
	)
	(gr_line
		(start 324.865492 -310.597296)
		(end 324.973442 -310.552592)
		(stroke
			(width 0.07112)
			(type default)
		)
		(layer "In2.Cu")
	)
	(gr_line
		(start 324.973442 -310.552592)
		(end 324.97395 -310.55183)
		(stroke
			(width 0.07112)
			(type default)
		)
		(layer "In2.Cu")
	)
	(gr_line
		(start 324.97395 -310.55183)
		(end 325.513192 -310.32831)
		(stroke
			(width 0.07112)
			(type default)
		)
		(layer "In2.Cu")
	)
	(gr_line
		(start 325.022464 -399.12036)
		(end 325.214742 -399.12036)
		(stroke
			(width 0.07112)
			(type default)
		)
		(layer "In2.Cu")
	)
	(gr_line
		(start 325.08698 -312.966608)
		(end 325.087488 -312.966608)
		(stroke
			(width 0.07112)
			(type default)
		)
		(layer "In2.Cu")
	)
	(gr_line
		(start 325.088504 -312.96483)
		(end 325.178928 -312.795158)
		(stroke
			(width 0.07112)
			(type default)
		)
		(layer "In2.Cu")
	)
	(gr_line
		(start 325.168768 -313.236356)
		(end 325.840344 -313.032648)
		(stroke
			(width 0.07112)
			(type default)
		)
		(layer "In2.Cu")
	)
	(gr_line
		(start 325.178928 -312.795158)
		(end 325.587614 -312.671206)
		(stroke
			(width 0.07112)
			(type default)
		)
		(layer "In2.Cu")
	)
	(gr_line
		(start 325.214742 -399.12036)
		(end 325.516748 -398.818354)
		(stroke
			(width 0.07112)
			(type default)
		)
		(layer "In2.Cu")
	)
	(gr_line
		(start 325.226172 -309.993792)
		(end 325.403464 -310.067452)
		(stroke
			(width 0.07112)
			(type default)
		)
		(layer "In2.Cu")
	)
	(gr_line
		(start 325.405496 -310.068214)
		(end 326.055482 -309.798974)
		(stroke
			(width 0.07112)
			(type default)
		)
		(layer "In2.Cu")
	)
	(gr_line
		(start 325.513192 -310.32831)
		(end 326.163178 -310.059324)
		(stroke
			(width 0.07112)
			(type default)
		)
		(layer "In2.Cu")
	)
	(gr_line
		(start 325.516748 -398.818354)
		(end 325.516748 -398.626076)
		(stroke
			(width 0.07112)
			(type default)
		)
		(layer "In2.Cu")
	)
	(gr_line
		(start 325.587614 -312.671206)
		(end 325.757286 -312.761884)
		(stroke
			(width 0.07112)
			(type default)
		)
		(layer "In2.Cu")
	)
	(gr_line
		(start 326.056244 -309.796942)
		(end 326.12965 -309.619396)
		(stroke
			(width 0.07112)
			(type default)
		)
		(layer "In2.Cu")
	)
	(gr_line
		(start 326.12965 -309.619396)
		(end 326.524112 -309.456074)
		(stroke
			(width 0.07112)
			(type default)
		)
		(layer "In2.Cu")
	)
	(gr_line
		(start 326.163178 -310.059324)
		(end 326.811386 -309.790846)
		(stroke
			(width 0.07112)
			(type default)
		)
		(layer "In2.Cu")
	)
	(gr_line
		(start 326.524112 -309.456074)
		(end 326.701912 -309.52948)
		(stroke
			(width 0.07112)
			(type default)
		)
		(layer "In2.Cu")
	)
	(gr_line
		(start 326.96531 -309.727092)
		(end 327.36536 -309.56123)
		(stroke
			(width 0.07112)
			(type default)
		)
		(layer "In2.Cu")
	)
	(gr_line
		(start 327.258426 -309.299102)
		(end 327.332086 -309.121302)
		(stroke
			(width 0.07112)
			(type default)
		)
		(layer "In2.Cu")
	)
	(gr_line
		(start 327.332086 -309.121302)
		(end 327.726548 -308.95798)
		(stroke
			(width 0.07112)
			(type default)
		)
		(layer "In2.Cu")
	)
	(gr_line
		(start 327.36536 -309.56123)
		(end 328.013568 -309.292752)
		(stroke
			(width 0.07112)
			(type default)
		)
		(layer "In2.Cu")
	)
	(gr_line
		(start 327.726548 -308.95798)
		(end 327.904094 -309.03164)
		(stroke
			(width 0.07112)
			(type default)
		)
		(layer "In2.Cu")
	)
	(gr_line
		(start 327.949814 -395.480032)
		(end 328.032618 -395.397482)
		(stroke
			(width 0.07112)
			(type default)
		)
		(layer "In2.Cu")
	)
	(gr_line
		(start 327.950068 -395.480032)
		(end 327.949814 -395.480032)
		(stroke
			(width 0.07112)
			(type default)
		)
		(layer "In2.Cu")
	)
	(gr_line
		(start 328.032618 -395.397482)
		(end 328.149458 -395.397482)
		(stroke
			(width 0.07112)
			(type default)
		)
		(layer "In2.Cu")
	)
	(gr_line
		(start 328.271378 -308.880764)
		(end 328.299826 -308.86908)
		(stroke
			(width 0.07112)
			(type default)
		)
		(layer "In2.Cu")
	)
	(gr_line
		(start 328.300588 -308.867302)
		(end 328.373994 -308.689502)
		(stroke
			(width 0.07112)
			(type default)
		)
		(layer "In2.Cu")
	)
	(gr_line
		(start 328.373994 -308.689502)
		(end 328.76871 -308.526434)
		(stroke
			(width 0.07112)
			(type default)
		)
		(layer "In2.Cu")
	)
	(gr_line
		(start 328.407522 -309.129684)
		(end 329.05573 -308.861206)
		(stroke
			(width 0.07112)
			(type default)
		)
		(layer "In2.Cu")
	)
	(gr_line
		(start 328.569574 -139.949174)
		(end 328.569574 -137.849864)
		(stroke
			(width 0.127)
			(type default)
		)
		(layer "In2.Cu")
	)
	(gr_line
		(start 328.76871 -308.526434)
		(end 328.946256 -308.59984)
		(stroke
			(width 0.07112)
			(type default)
		)
		(layer "In2.Cu")
	)
	(gr_line
		(start 328.914252 -141.10335)
		(end 328.914252 -142.578074)
		(stroke
			(width 0.127)
			(type default)
		)
		(layer "In2.Cu")
	)
	(gr_line
		(start 328.979276 -312.254138)
		(end 328.979276 -312.254646)
		(stroke
			(width 0.07112)
			(type default)
		)
		(layer "In2.Cu")
	)
	(gr_line
		(start 328.9808 -312.252868)
		(end 329.102212 -312.104532)
		(stroke
			(width 0.07112)
			(type default)
		)
		(layer "In2.Cu")
	)
	(gr_line
		(start 329.006962 -312.534808)
		(end 329.704954 -312.466228)
		(stroke
			(width 0.07112)
			(type default)
		)
		(layer "In2.Cu")
	)
	(gr_line
		(start 329.029568 -140.409168)
		(end 328.569574 -139.949174)
		(stroke
			(width 0.127)
			(type default)
		)
		(layer "In2.Cu")
	)
	(gr_line
		(start 329.03922 -140.399516)
		(end 329.029568 -140.409168)
		(stroke
			(width 0.127)
			(type default)
		)
		(layer "In2.Cu")
	)
	(gr_line
		(start 329.102212 -312.104532)
		(end 329.527154 -312.062622)
		(stroke
			(width 0.07112)
			(type default)
		)
		(layer "In2.Cu")
	)
	(gr_line
		(start 329.114658 -140.781786)
		(end 328.914252 -141.10335)
		(stroke
			(width 0.127)
			(type default)
		)
		(layer "In2.Cu")
	)
	(gr_line
		(start 329.11542 -140.399516)
		(end 329.03922 -140.399516)
		(stroke
			(width 0.127)
			(type default)
		)
		(layer "In2.Cu")
	)
	(gr_line
		(start 329.519534 -395.880844)
		(end 329.810364 -396.171674)
		(stroke
			(width 0.07112)
			(type default)
		)
		(layer "In2.Cu")
	)
	(gr_line
		(start 329.519534 -395.598904)
		(end 329.810364 -395.308074)
		(stroke
			(width 0.07112)
			(type default)
		)
		(layer "In2.Cu")
	)
	(gr_line
		(start 329.527154 -312.062622)
		(end 329.675744 -312.184542)
		(stroke
			(width 0.07112)
			(type default)
		)
		(layer "In2.Cu")
	)
	(gr_line
		(start 329.677268 -312.185812)
		(end 329.677268 -312.185304)
		(stroke
			(width 0.07112)
			(type default)
		)
		(layer "In2.Cu")
	)
	(gr_line
		(start 329.960986 -140.751814)
		(end 329.96124 -140.751814)
		(stroke
			(width 0.127)
			(type default)
		)
		(layer "In2.Cu")
	)
	(gr_line
		(start 330.072746 -141.021562)
		(end 330.072746 -140.863574)
		(stroke
			(width 0.127)
			(type default)
		)
		(layer "In2.Cu")
	)
	(gr_line
		(start 330.072746 -140.863574)
		(end 329.96124 -140.751814)
		(stroke
			(width 0.127)
			(type default)
		)
		(layer "In2.Cu")
	)
	(gr_line
		(start 330.101702 -312.144156)
		(end 330.101956 -312.143648)
		(stroke
			(width 0.07112)
			(type default)
		)
		(layer "In2.Cu")
	)
	(gr_line
		(start 330.101702 -312.143648)
		(end 330.101702 -312.144156)
		(stroke
			(width 0.07112)
			(type default)
		)
		(layer "In2.Cu")
	)
	(gr_line
		(start 330.103226 -312.142378)
		(end 330.224892 -311.994042)
		(stroke
			(width 0.07112)
			(type default)
		)
		(layer "In2.Cu")
	)
	(gr_line
		(start 330.129134 -312.424318)
		(end 330.82738 -312.355484)
		(stroke
			(width 0.07112)
			(type default)
		)
		(layer "In2.Cu")
	)
	(gr_line
		(start 330.224892 -311.994042)
		(end 330.649834 -311.952132)
		(stroke
			(width 0.07112)
			(type default)
		)
		(layer "In2.Cu")
	)
	(gr_line
		(start 330.649834 -311.952132)
		(end 330.797916 -312.073798)
		(stroke
			(width 0.07112)
			(type default)
		)
		(layer "In2.Cu")
	)
	(gr_line
		(start 330.799694 -312.075322)
		(end 330.799694 -312.074814)
		(stroke
			(width 0.07112)
			(type default)
		)
		(layer "In2.Cu")
	)
	(gr_line
		(start 331.49667 -312.006742)
		(end 331.496924 -312.006234)
		(stroke
			(width 0.07112)
			(type default)
		)
		(layer "In2.Cu")
	)
	(gr_line
		(start 331.49667 -312.006234)
		(end 331.49667 -312.006742)
		(stroke
			(width 0.07112)
			(type default)
		)
		(layer "In2.Cu")
	)
	(gr_line
		(start 331.498194 -312.004964)
		(end 331.619606 -311.856628)
		(stroke
			(width 0.07112)
			(type default)
		)
		(layer "In2.Cu")
	)
	(gr_line
		(start 331.524356 -312.286904)
		(end 332.222348 -312.21807)
		(stroke
			(width 0.07112)
			(type default)
		)
		(layer "In2.Cu")
	)
	(gr_line
		(start 331.577188 -313.605164)
		(end 331.577696 -313.604656)
		(stroke
			(width 0.07112)
			(type default)
		)
		(layer "In2.Cu")
	)
	(gr_line
		(start 331.577188 -313.604656)
		(end 331.577188 -313.605164)
		(stroke
			(width 0.07112)
			(type default)
		)
		(layer "In2.Cu")
	)
	(gr_line
		(start 331.578712 -313.603132)
		(end 331.700124 -313.45505)
		(stroke
			(width 0.07112)
			(type default)
		)
		(layer "In2.Cu")
	)
	(gr_line
		(start 331.604874 -313.885326)
		(end 332.302612 -313.816492)
		(stroke
			(width 0.07112)
			(type default)
		)
		(layer "In2.Cu")
	)
	(gr_line
		(start 331.619606 -311.856628)
		(end 332.044548 -311.814718)
		(stroke
			(width 0.07112)
			(type default)
		)
		(layer "In2.Cu")
	)
	(gr_line
		(start 331.700124 -313.45505)
		(end 332.125066 -313.413394)
		(stroke
			(width 0.07112)
			(type default)
		)
		(layer "In2.Cu")
	)
	(gr_line
		(start 332.044548 -311.814718)
		(end 332.193138 -311.936384)
		(stroke
			(width 0.07112)
			(type default)
		)
		(layer "In2.Cu")
	)
	(gr_line
		(start 332.125066 -313.413394)
		(end 332.273402 -313.534806)
		(stroke
			(width 0.07112)
			(type default)
		)
		(layer "In2.Cu")
	)
	(gr_line
		(start 332.194662 -311.937654)
		(end 332.194662 -311.9374)
		(stroke
			(width 0.07112)
			(type default)
		)
		(layer "In2.Cu")
	)
	(gr_line
		(start 332.274672 -313.535822)
		(end 332.27518 -313.53633)
		(stroke
			(width 0.07112)
			(type default)
		)
		(layer "In2.Cu")
	)
	(gr_line
		(start 332.27518 -313.53633)
		(end 332.699614 -313.494674)
		(stroke
			(width 0.07112)
			(type default)
		)
		(layer "In2.Cu")
	)
	(gr_line
		(start 332.302612 -313.816492)
		(end 332.727046 -313.774582)
		(stroke
			(width 0.07112)
			(type default)
		)
		(layer "In2.Cu")
	)
	(gr_line
		(start 332.699614 -313.494674)
		(end 332.700122 -313.493912)
		(stroke
			(width 0.07112)
			(type default)
		)
		(layer "In2.Cu")
	)
	(gr_line
		(start 332.701392 -313.492642)
		(end 332.82255 -313.344306)
		(stroke
			(width 0.07112)
			(type default)
		)
		(layer "In2.Cu")
	)
	(gr_line
		(start 332.727046 -313.774582)
		(end 333.425038 -313.706002)
		(stroke
			(width 0.07112)
			(type default)
		)
		(layer "In2.Cu")
	)
	(gr_line
		(start 332.82255 -313.344306)
		(end 333.247492 -313.30265)
		(stroke
			(width 0.07112)
			(type default)
		)
		(layer "In2.Cu")
	)
	(gr_line
		(start 332.949042 -308.009544)
		(end 332.982062 -307.82006)
		(stroke
			(width 0.07112)
			(type default)
		)
		(layer "In2.Cu")
	)
	(gr_line
		(start 332.982062 -307.82006)
		(end 333.331312 -307.574442)
		(stroke
			(width 0.07112)
			(type default)
		)
		(layer "In2.Cu")
	)
	(gr_line
		(start 333.087726 -302.413416)
		(end 333.251048 -302.018954)
		(stroke
			(width 0.07112)
			(type default)
		)
		(layer "In2.Cu")
	)
	(gr_line
		(start 333.111094 -308.241954)
		(end 333.684626 -307.838348)
		(stroke
			(width 0.07112)
			(type default)
		)
		(layer "In2.Cu")
	)
	(gr_line
		(start 333.161386 -302.590962)
		(end 333.087726 -302.413416)
		(stroke
			(width 0.07112)
			(type default)
		)
		(layer "In2.Cu")
	)
	(gr_line
		(start 333.247492 -313.30265)
		(end 333.395828 -313.424062)
		(stroke
			(width 0.07112)
			(type default)
		)
		(layer "In2.Cu")
	)
	(gr_line
		(start 333.251048 -302.018954)
		(end 333.428848 -301.945294)
		(stroke
			(width 0.07112)
			(type default)
		)
		(layer "In2.Cu")
	)
	(gr_line
		(start 333.331312 -307.574442)
		(end 333.520796 -307.607462)
		(stroke
			(width 0.07112)
			(type default)
		)
		(layer "In2.Cu")
	)
	(gr_line
		(start 333.3369 -311.824878)
		(end 333.3369 -311.825386)
		(stroke
			(width 0.07112)
			(type default)
		)
		(layer "In2.Cu")
	)
	(gr_line
		(start 333.338424 -311.823608)
		(end 333.459836 -311.675018)
		(stroke
			(width 0.07112)
			(type default)
		)
		(layer "In2.Cu")
	)
	(gr_line
		(start 333.364586 -312.105548)
		(end 334.062578 -312.036968)
		(stroke
			(width 0.07112)
			(type default)
		)
		(layer "In2.Cu")
	)
	(gr_line
		(start 333.397606 -313.425586)
		(end 333.82204 -313.38393)
		(stroke
			(width 0.07112)
			(type default)
		)
		(layer "In2.Cu")
	)
	(gr_line
		(start 333.39913 -302.62322)
		(end 333.667608 -301.975266)
		(stroke
			(width 0.07112)
			(type default)
		)
		(layer "In2.Cu")
	)
	(gr_line
		(start 333.425038 -313.706002)
		(end 333.849472 -313.664092)
		(stroke
			(width 0.07112)
			(type default)
		)
		(layer "In2.Cu")
	)
	(gr_line
		(start 333.459836 -311.675018)
		(end 333.884778 -311.633362)
		(stroke
			(width 0.07112)
			(type default)
		)
		(layer "In2.Cu")
	)
	(gr_line
		(start 333.82204 -313.38393)
		(end 333.822548 -313.383422)
		(stroke
			(width 0.07112)
			(type default)
		)
		(layer "In2.Cu")
	)
	(gr_line
		(start 333.823564 -313.382152)
		(end 333.944976 -313.233816)
		(stroke
			(width 0.07112)
			(type default)
		)
		(layer "In2.Cu")
	)
	(gr_line
		(start 333.849472 -313.664092)
		(end 334.54721 -313.595258)
		(stroke
			(width 0.07112)
			(type default)
		)
		(layer "In2.Cu")
	)
	(gr_line
		(start 333.884778 -311.633362)
		(end 334.033368 -311.755028)
		(stroke
			(width 0.07112)
			(type default)
		)
		(layer "In2.Cu")
	)
	(gr_line
		(start 333.944976 -313.233816)
		(end 334.369918 -313.191906)
		(stroke
			(width 0.07112)
			(type default)
		)
		(layer "In2.Cu")
	)
	(gr_line
		(start 334.034892 -311.756298)
		(end 334.034892 -311.756044)
		(stroke
			(width 0.07112)
			(type default)
		)
		(layer "In2.Cu")
	)
	(gr_line
		(start 334.152748 -307.162708)
		(end 334.185006 -306.97678)
		(stroke
			(width 0.07112)
			(type default)
		)
		(layer "In2.Cu")
	)
	(gr_line
		(start 334.185006 -306.97678)
		(end 334.534256 -306.730908)
		(stroke
			(width 0.07112)
			(type default)
		)
		(layer "In2.Cu")
	)
	(gr_line
		(start 334.3148 -307.394864)
		(end 334.884268 -306.994306)
		(stroke
			(width 0.07112)
			(type default)
		)
		(layer "In2.Cu")
	)
	(gr_line
		(start 334.369918 -313.191906)
		(end 334.518254 -313.313572)
		(stroke
			(width 0.07112)
			(type default)
		)
		(layer "In2.Cu")
	)
	(gr_line
		(start 334.459326 -311.714388)
		(end 334.459326 -311.714642)
		(stroke
			(width 0.07112)
			(type default)
		)
		(layer "In2.Cu")
	)
	(gr_line
		(start 334.460596 -311.713118)
		(end 334.582516 -311.564528)
		(stroke
			(width 0.07112)
			(type default)
		)
		(layer "In2.Cu")
	)
	(gr_line
		(start 334.467708 -304.390298)
		(end 334.176878 -304.681128)
		(stroke
			(width 0.07112)
			(type default)
		)
		(layer "In2.Cu")
	)
	(gr_line
		(start 334.467708 -304.108358)
		(end 334.176878 -303.817528)
		(stroke
			(width 0.07112)
			(type default)
		)
		(layer "In2.Cu")
	)
	(gr_line
		(start 334.486758 -311.995058)
		(end 335.185004 -311.926224)
		(stroke
			(width 0.07112)
			(type default)
		)
		(layer "In2.Cu")
	)
	(gr_line
		(start 334.519778 -313.314842)
		(end 335.381092 -313.23026)
		(stroke
			(width 0.07112)
			(type default)
		)
		(layer "In2.Cu")
	)
	(gr_line
		(start 334.534256 -306.730908)
		(end 334.720692 -306.763166)
		(stroke
			(width 0.07112)
			(type default)
		)
		(layer "In2.Cu")
	)
	(gr_line
		(start 334.54721 -313.595258)
		(end 335.408524 -313.510422)
		(stroke
			(width 0.07112)
			(type default)
		)
		(layer "In2.Cu")
	)
	(gr_line
		(start 334.582516 -311.564528)
		(end 335.007204 -311.522618)
		(stroke
			(width 0.07112)
			(type default)
		)
		(layer "In2.Cu")
	)
	(gr_line
		(start 335.007204 -311.522618)
		(end 335.156048 -311.644538)
		(stroke
			(width 0.07112)
			(type default)
		)
		(layer "In2.Cu")
	)
	(gr_line
		(start 335.381092 -313.23026)
		(end 335.381346 -313.229752)
		(stroke
			(width 0.07112)
			(type default)
		)
		(layer "In2.Cu")
	)
	(gr_line
		(start 335.382616 -313.228482)
		(end 335.504028 -313.080146)
		(stroke
			(width 0.07112)
			(type default)
		)
		(layer "In2.Cu")
	)
	(gr_line
		(start 335.408524 -313.510422)
		(end 336.10677 -313.441842)
		(stroke
			(width 0.07112)
			(type default)
		)
		(layer "In2.Cu")
	)
	(gr_line
		(start 335.47431 -303.691036)
		(end 335.426304 -303.873662)
		(stroke
			(width 0.07112)
			(type default)
		)
		(layer "In2.Cu")
	)
	(gr_line
		(start 335.504028 -313.080146)
		(end 335.92897 -313.038236)
		(stroke
			(width 0.07112)
			(type default)
		)
		(layer "In2.Cu")
	)
	(gr_line
		(start 335.672684 -311.594754)
		(end 335.672684 -311.595008)
		(stroke
			(width 0.07112)
			(type default)
		)
		(layer "In2.Cu")
	)
	(gr_line
		(start 335.673954 -311.593484)
		(end 335.79562 -311.44464)
		(stroke
			(width 0.07112)
			(type default)
		)
		(layer "In2.Cu")
	)
	(gr_line
		(start 335.70037 -311.875424)
		(end 336.398362 -311.806844)
		(stroke
			(width 0.07112)
			(type default)
		)
		(layer "In2.Cu")
	)
	(gr_line
		(start 335.788508 -299.930566)
		(end 335.788762 -299.930312)
		(stroke
			(width 0.07112)
			(type default)
		)
		(layer "In2.Cu")
	)
	(gr_line
		(start 335.788762 -299.930312)
		(end 335.788762 -299.930566)
		(stroke
			(width 0.07112)
			(type default)
		)
		(layer "In2.Cu")
	)
	(gr_line
		(start 335.79562 -311.44464)
		(end 336.220562 -311.402984)
		(stroke
			(width 0.07112)
			(type default)
		)
		(layer "In2.Cu")
	)
	(gr_line
		(start 335.843118 -303.476152)
		(end 335.47431 -303.691036)
		(stroke
			(width 0.07112)
			(type default)
		)
		(layer "In2.Cu")
	)
	(gr_line
		(start 335.92897 -313.038236)
		(end 336.077306 -313.159902)
		(stroke
			(width 0.07112)
			(type default)
		)
		(layer "In2.Cu")
	)
	(gr_line
		(start 336.025744 -303.524158)
		(end 335.843118 -303.476152)
		(stroke
			(width 0.07112)
			(type default)
		)
		(layer "In2.Cu")
	)
	(gr_line
		(start 336.079084 -313.161426)
		(end 336.768694 -313.093608)
		(stroke
			(width 0.07112)
			(type default)
		)
		(layer "In2.Cu")
	)
	(gr_line
		(start 336.10677 -313.441842)
		(end 336.796126 -313.37377)
		(stroke
			(width 0.07112)
			(type default)
		)
		(layer "In2.Cu")
	)
	(gr_line
		(start 336.169254 -303.768252)
		(end 335.567782 -304.119026)
		(stroke
			(width 0.07112)
			(type default)
		)
		(layer "In2.Cu")
	)
	(gr_line
		(start 336.220562 -311.402984)
		(end 336.36966 -311.524904)
		(stroke
			(width 0.07112)
			(type default)
		)
		(layer "In2.Cu")
	)
	(gr_line
		(start 336.444336 -303.125632)
		(end 336.39633 -303.308258)
		(stroke
			(width 0.07112)
			(type default)
		)
		(layer "In2.Cu")
	)
	(gr_line
		(start 336.758788 -305.408838)
		(end 336.813906 -305.227736)
		(stroke
			(width 0.07112)
			(type default)
		)
		(layer "In2.Cu")
	)
	(gr_line
		(start 336.768694 -313.093608)
		(end 336.768948 -313.0931)
		(stroke
			(width 0.07112)
			(type default)
		)
		(layer "In2.Cu")
	)
	(gr_line
		(start 336.770218 -313.09183)
		(end 336.891884 -312.943494)
		(stroke
			(width 0.07112)
			(type default)
		)
		(layer "In2.Cu")
	)
	(gr_line
		(start 336.796126 -313.37377)
		(end 337.494372 -313.304936)
		(stroke
			(width 0.07112)
			(type default)
		)
		(layer "In2.Cu")
	)
	(gr_line
		(start 336.796126 -311.482994)
		(end 336.918046 -311.33415)
		(stroke
			(width 0.07112)
			(type default)
		)
		(layer "In2.Cu")
	)
	(gr_line
		(start 336.813144 -302.910494)
		(end 336.444336 -303.125632)
		(stroke
			(width 0.07112)
			(type default)
		)
		(layer "In2.Cu")
	)
	(gr_line
		(start 336.813906 -305.227736)
		(end 337.190588 -305.026568)
		(stroke
			(width 0.07112)
			(type default)
		)
		(layer "In2.Cu")
	)
	(gr_line
		(start 336.822542 -311.764934)
		(end 337.521042 -311.6961)
		(stroke
			(width 0.07112)
			(type default)
		)
		(layer "In2.Cu")
	)
	(gr_line
		(start 336.89163 -305.659028)
		(end 337.505548 -305.33086)
		(stroke
			(width 0.07112)
			(type default)
		)
		(layer "In2.Cu")
	)
	(gr_line
		(start 336.891884 -312.943494)
		(end 337.316572 -312.901584)
		(stroke
			(width 0.07112)
			(type default)
		)
		(layer "In2.Cu")
	)
	(gr_line
		(start 336.918046 -311.33415)
		(end 337.342988 -311.29224)
		(stroke
			(width 0.07112)
			(type default)
		)
		(layer "In2.Cu")
	)
	(gr_line
		(start 336.996024 -302.958754)
		(end 336.813144 -302.910494)
		(stroke
			(width 0.07112)
			(type default)
		)
		(layer "In2.Cu")
	)
	(gr_line
		(start 337.116166 -299.379386)
		(end 337.189572 -299.201586)
		(stroke
			(width 0.07112)
			(type default)
		)
		(layer "In2.Cu")
	)
	(gr_line
		(start 337.139534 -303.202848)
		(end 336.537808 -303.553622)
		(stroke
			(width 0.07112)
			(type default)
		)
		(layer "In2.Cu")
	)
	(gr_line
		(start 337.189572 -299.201586)
		(end 337.584034 -299.038518)
		(stroke
			(width 0.07112)
			(type default)
		)
		(layer "In2.Cu")
	)
	(gr_line
		(start 337.190588 -305.026568)
		(end 337.371436 -305.081432)
		(stroke
			(width 0.07112)
			(type default)
		)
		(layer "In2.Cu")
	)
	(gr_line
		(start 337.223354 -299.641768)
		(end 337.871308 -299.37329)
		(stroke
			(width 0.07112)
			(type default)
		)
		(layer "In2.Cu")
	)
	(gr_line
		(start 337.316572 -312.901584)
		(end 337.464908 -313.02325)
		(stroke
			(width 0.07112)
			(type default)
		)
		(layer "In2.Cu")
	)
	(gr_line
		(start 337.342988 -311.29224)
		(end 337.491832 -311.414414)
		(stroke
			(width 0.07112)
			(type default)
		)
		(layer "In2.Cu")
	)
	(gr_line
		(start 337.414362 -302.559974)
		(end 337.366102 -302.742854)
		(stroke
			(width 0.07112)
			(type default)
		)
		(layer "In2.Cu")
	)
	(gr_line
		(start 337.466686 -313.024774)
		(end 338.060284 -312.966354)
		(stroke
			(width 0.07112)
			(type default)
		)
		(layer "In2.Cu")
	)
	(gr_line
		(start 337.493102 -311.41543)
		(end 337.493356 -311.41543)
		(stroke
			(width 0.07112)
			(type default)
		)
		(layer "In2.Cu")
	)
	(gr_line
		(start 337.494372 -313.304936)
		(end 338.08797 -313.246516)
		(stroke
			(width 0.07112)
			(type default)
		)
		(layer "In2.Cu")
	)
	(gr_line
		(start 337.584034 -299.038518)
		(end 337.761834 -299.112178)
		(stroke
			(width 0.07112)
			(type default)
		)
		(layer "In2.Cu")
	)
	(gr_line
		(start 337.749388 -304.879502)
		(end 337.804252 -304.6984)
		(stroke
			(width 0.07112)
			(type default)
		)
		(layer "In2.Cu")
	)
	(gr_line
		(start 337.78317 -302.34509)
		(end 337.414362 -302.559974)
		(stroke
			(width 0.07112)
			(type default)
		)
		(layer "In2.Cu")
	)
	(gr_line
		(start 337.804252 -304.6984)
		(end 338.18068 -304.497486)
		(stroke
			(width 0.07112)
			(type default)
		)
		(layer "In2.Cu")
	)
	(gr_line
		(start 337.881722 -305.129946)
		(end 338.496148 -304.801524)
		(stroke
			(width 0.07112)
			(type default)
		)
		(layer "In2.Cu")
	)
	(gr_line
		(start 337.966304 -302.393096)
		(end 337.78317 -302.34509)
		(stroke
			(width 0.07112)
			(type default)
		)
		(layer "In2.Cu")
	)
	(gr_line
		(start 338.060284 -312.966354)
		(end 338.060538 -312.965846)
		(stroke
			(width 0.07112)
			(type default)
		)
		(layer "In2.Cu")
	)
	(gr_line
		(start 338.061808 -312.964576)
		(end 338.183474 -312.81624)
		(stroke
			(width 0.07112)
			(type default)
		)
		(layer "In2.Cu")
	)
	(gr_line
		(start 338.08797 -313.246516)
		(end 338.785708 -313.177682)
		(stroke
			(width 0.07112)
			(type default)
		)
		(layer "In2.Cu")
	)
	(gr_line
		(start 338.10956 -302.637444)
		(end 337.508088 -302.987964)
		(stroke
			(width 0.07112)
			(type default)
		)
		(layer "In2.Cu")
	)
	(gr_line
		(start 338.18068 -304.497486)
		(end 338.361782 -304.55235)
		(stroke
			(width 0.07112)
			(type default)
		)
		(layer "In2.Cu")
	)
	(gr_line
		(start 338.183474 -312.81624)
		(end 338.608416 -312.77433)
		(stroke
			(width 0.07112)
			(type default)
		)
		(layer "In2.Cu")
	)
	(gr_line
		(start 338.384388 -301.994316)
		(end 338.336128 -302.17745)
		(stroke
			(width 0.07112)
			(type default)
		)
		(layer "In2.Cu")
	)
	(gr_line
		(start 338.608416 -312.77433)
		(end 338.756752 -312.895996)
		(stroke
			(width 0.07112)
			(type default)
		)
		(layer "In2.Cu")
	)
	(gr_line
		(start 338.739734 -304.35042)
		(end 338.794598 -304.169064)
		(stroke
			(width 0.07112)
			(type default)
		)
		(layer "In2.Cu")
	)
	(gr_line
		(start 338.753196 -301.779432)
		(end 338.384388 -301.994316)
		(stroke
			(width 0.07112)
			(type default)
		)
		(layer "In2.Cu")
	)
	(gr_line
		(start 338.758276 -312.897266)
		(end 339.250274 -312.849006)
		(stroke
			(width 0.07112)
			(type default)
		)
		(layer "In2.Cu")
	)
	(gr_line
		(start 338.785708 -313.177682)
		(end 339.277706 -313.129422)
		(stroke
			(width 0.07112)
			(type default)
		)
		(layer "In2.Cu")
	)
	(gr_line
		(start 338.794598 -304.169064)
		(end 339.17128 -303.96815)
		(stroke
			(width 0.07112)
			(type default)
		)
		(layer "In2.Cu")
	)
	(gr_line
		(start 338.872068 -304.60061)
		(end 339.486494 -304.272188)
		(stroke
			(width 0.07112)
			(type default)
		)
		(layer "In2.Cu")
	)
	(gr_line
		(start 338.936076 -301.827692)
		(end 338.753196 -301.779432)
		(stroke
			(width 0.07112)
			(type default)
		)
		(layer "In2.Cu")
	)
	(gr_line
		(start 339.079586 -302.071786)
		(end 338.478114 -302.42256)
		(stroke
			(width 0.07112)
			(type default)
		)
		(layer "In2.Cu")
	)
	(gr_line
		(start 339.17128 -303.96815)
		(end 339.352128 -304.023014)
		(stroke
			(width 0.07112)
			(type default)
		)
		(layer "In2.Cu")
	)
	(gr_line
		(start 339.251544 -312.847228)
		(end 339.37321 -312.698892)
		(stroke
			(width 0.07112)
			(type default)
		)
		(layer "In2.Cu")
	)
	(gr_line
		(start 339.277706 -313.129422)
		(end 339.975698 -313.060588)
		(stroke
			(width 0.07112)
			(type default)
		)
		(layer "In2.Cu")
	)
	(gr_line
		(start 339.37321 -312.698892)
		(end 339.798152 -312.656982)
		(stroke
			(width 0.07112)
			(type default)
		)
		(layer "In2.Cu")
	)
	(gr_line
		(start 339.739478 -303.816004)
		(end 339.794596 -303.634648)
		(stroke
			(width 0.07112)
			(type default)
		)
		(layer "In2.Cu")
	)
	(gr_line
		(start 339.794596 -303.634648)
		(end 340.171024 -303.43348)
		(stroke
			(width 0.07112)
			(type default)
		)
		(layer "In2.Cu")
	)
	(gr_line
		(start 339.798152 -312.656982)
		(end 339.946996 -312.778902)
		(stroke
			(width 0.07112)
			(type default)
		)
		(layer "In2.Cu")
	)
	(gr_line
		(start 339.87232 -304.06594)
		(end 340.486492 -303.737772)
		(stroke
			(width 0.07112)
			(type default)
		)
		(layer "In2.Cu")
	)
	(gr_line
		(start 340.068154 -298.298108)
		(end 340.175088 -298.138088)
		(stroke
			(width 0.07112)
			(type default)
		)
		(layer "In2.Cu")
	)
	(gr_line
		(start 340.103714 -312.764678)
		(end 340.581996 -312.717688)
		(stroke
			(width 0.07112)
			(type default)
		)
		(layer "In2.Cu")
	)
	(gr_line
		(start 340.122002 -298.576238)
		(end 340.810088 -298.439332)
		(stroke
			(width 0.07112)
			(type default)
		)
		(layer "In2.Cu")
	)
	(gr_line
		(start 340.1314 -313.045348)
		(end 340.609428 -312.998104)
		(stroke
			(width 0.07112)
			(type default)
		)
		(layer "In2.Cu")
	)
	(gr_line
		(start 340.171024 -303.43348)
		(end 340.352126 -303.488598)
		(stroke
			(width 0.07112)
			(type default)
		)
		(layer "In2.Cu")
	)
	(gr_line
		(start 340.175088 -298.138088)
		(end 340.59368 -298.054776)
		(stroke
			(width 0.07112)
			(type default)
		)
		(layer "In2.Cu")
	)
	(gr_line
		(start 340.583266 -312.716164)
		(end 340.704932 -312.56732)
		(stroke
			(width 0.07112)
			(type default)
		)
		(layer "In2.Cu")
	)
	(gr_line
		(start 340.59368 -298.054776)
		(end 340.753954 -298.16171)
		(stroke
			(width 0.07112)
			(type default)
		)
		(layer "In2.Cu")
	)
	(gr_line
		(start 340.609428 -312.998104)
		(end 341.30742 -312.92927)
		(stroke
			(width 0.07112)
			(type default)
		)
		(layer "In2.Cu")
	)
	(gr_line
		(start 340.704932 -312.56732)
		(end 341.129874 -312.525664)
		(stroke
			(width 0.07112)
			(type default)
		)
		(layer "In2.Cu")
	)
	(gr_line
		(start 341.129874 -312.525664)
		(end 341.278464 -312.647584)
		(stroke
			(width 0.07112)
			(type default)
		)
		(layer "In2.Cu")
	)
	(gr_line
		(start 341.153496 -305.845718)
		(end 340.877144 -305.569366)
		(stroke
			(width 0.07112)
			(type default)
		)
		(layer "In2.Cu")
	)
	(gr_line
		(start 341.181182 -306.128928)
		(end 340.877144 -306.432966)
		(stroke
			(width 0.07112)
			(type default)
		)
		(layer "In2.Cu")
	)
	(gr_line
		(start 341.182452 -305.845718)
		(end 341.153496 -305.845718)
		(stroke
			(width 0.07112)
			(type default)
		)
		(layer "In2.Cu")
	)
	(gr_line
		(start 341.778844 -305.35372)
		(end 341.778844 -305.542442)
		(stroke
			(width 0.07112)
			(type default)
		)
		(layer "In2.Cu")
	)
	(gr_line
		(start 342.010746 -297.911774)
		(end 342.11768 -297.7515)
		(stroke
			(width 0.07112)
			(type default)
		)
		(layer "In2.Cu")
	)
	(gr_line
		(start 342.065102 -298.189904)
		(end 342.752934 -298.052998)
		(stroke
			(width 0.07112)
			(type default)
		)
		(layer "In2.Cu")
	)
	(gr_line
		(start 342.08085 -305.051714)
		(end 341.778844 -305.35372)
		(stroke
			(width 0.07112)
			(type default)
		)
		(layer "In2.Cu")
	)
	(gr_line
		(start 342.11768 -297.7515)
		(end 342.536526 -297.668442)
		(stroke
			(width 0.07112)
			(type default)
		)
		(layer "In2.Cu")
	)
	(gr_line
		(start 342.190832 -309.012336)
		(end 341.900002 -309.303166)
		(stroke
			(width 0.07112)
			(type default)
		)
		(layer "In2.Cu")
	)
	(gr_line
		(start 342.190832 -308.730396)
		(end 341.900002 -308.439566)
		(stroke
			(width 0.07112)
			(type default)
		)
		(layer "In2.Cu")
	)
	(gr_line
		(start 342.269572 -305.051714)
		(end 342.08085 -305.051714)
		(stroke
			(width 0.07112)
			(type default)
		)
		(layer "In2.Cu")
	)
	(gr_line
		(start 342.47074 -305.251104)
		(end 341.978234 -305.74361)
		(stroke
			(width 0.07112)
			(type default)
		)
		(layer "In2.Cu")
	)
	(gr_line
		(start 342.536526 -297.668442)
		(end 342.6968 -297.775376)
		(stroke
			(width 0.07112)
			(type default)
		)
		(layer "In2.Cu")
	)
	(gr_line
		(start 342.548718 -302.31461)
		(end 342.603582 -302.133508)
		(stroke
			(width 0.07112)
			(type default)
		)
		(layer "In2.Cu")
	)
	(gr_line
		(start 342.603582 -302.133508)
		(end 342.98001 -301.93234)
		(stroke
			(width 0.07112)
			(type default)
		)
		(layer "In2.Cu")
	)
	(gr_line
		(start 342.681052 -302.565054)
		(end 343.295224 -302.236632)
		(stroke
			(width 0.07112)
			(type default)
		)
		(layer "In2.Cu")
	)
	(gr_line
		(start 342.98001 -301.93234)
		(end 343.161112 -301.987458)
		(stroke
			(width 0.07112)
			(type default)
		)
		(layer "In2.Cu")
	)
	(gr_line
		(start 343.27338 -304.014886)
		(end 343.235788 -304.203354)
		(stroke
			(width 0.07112)
			(type default)
		)
		(layer "In2.Cu")
	)
	(gr_line
		(start 343.628472 -303.77765)
		(end 343.27338 -304.014886)
		(stroke
			(width 0.07112)
			(type default)
		)
		(layer "In2.Cu")
	)
	(gr_line
		(start 343.750392 -301.672244)
		(end 343.80551 -301.491142)
		(stroke
			(width 0.07112)
			(type default)
		)
		(layer "In2.Cu")
	)
	(gr_line
		(start 343.80551 -301.491142)
		(end 344.182192 -301.289974)
		(stroke
			(width 0.07112)
			(type default)
		)
		(layer "In2.Cu")
	)
	(gr_line
		(start 343.817194 -303.814988)
		(end 343.628472 -303.77765)
		(stroke
			(width 0.07112)
			(type default)
		)
		(layer "In2.Cu")
	)
	(gr_line
		(start 343.883234 -301.922434)
		(end 344.497406 -301.594266)
		(stroke
			(width 0.07112)
			(type default)
		)
		(layer "In2.Cu")
	)
	(gr_line
		(start 343.975436 -304.049684)
		(end 343.392252 -304.439574)
		(stroke
			(width 0.07112)
			(type default)
		)
		(layer "In2.Cu")
	)
	(gr_line
		(start 344.182192 -301.289974)
		(end 344.36304 -301.344838)
		(stroke
			(width 0.07112)
			(type default)
		)
		(layer "In2.Cu")
	)
	(gr_line
		(start 344.211148 -303.388014)
		(end 344.173556 -303.576736)
		(stroke
			(width 0.07112)
			(type default)
		)
		(layer "In2.Cu")
	)
	(gr_line
		(start 344.47226 -296.61231)
		(end 344.47226 -296.583862)
		(stroke
			(width 0.05715)
			(type default)
		)
		(layer "In2.Cu")
	)
	(gr_line
		(start 344.47226 -296.583862)
		(end 344.51798 -296.538142)
		(stroke
			(width 0.05715)
			(type default)
		)
		(layer "In2.Cu")
	)
	(gr_line
		(start 344.56624 -303.150778)
		(end 344.211148 -303.388014)
		(stroke
			(width 0.07112)
			(type default)
		)
		(layer "In2.Cu")
	)
	(gr_line
		(start 344.7542 -296.61231)
		(end 344.7542 -296.583862)
		(stroke
			(width 0.05715)
			(type default)
		)
		(layer "In2.Cu")
	)
	(gr_line
		(start 344.7542 -296.583862)
		(end 344.70848 -296.538142)
		(stroke
			(width 0.05715)
			(type default)
		)
		(layer "In2.Cu")
	)
	(gr_line
		(start 344.754962 -303.18837)
		(end 344.56624 -303.150778)
		(stroke
			(width 0.07112)
			(type default)
		)
		(layer "In2.Cu")
	)
	(gr_line
		(start 344.913204 -303.423066)
		(end 344.33002 -303.812702)
		(stroke
			(width 0.07112)
			(type default)
		)
		(layer "In2.Cu")
	)
	(gr_line
		(start 344.972132 -308.595776)
		(end 344.838782 -308.729126)
		(stroke
			(width 0.07112)
			(type default)
		)
		(layer "In2.Cu")
	)
	(gr_line
		(start 345.278964 -294.335962)
		(end 344.981022 -294.335962)
		(stroke
			(width 0.05715)
			(type default)
		)
		(layer "In2.Cu")
	)
	(gr_line
		(start 345.348306 -294.405304)
		(end 345.278964 -294.335962)
		(stroke
			(width 0.05715)
			(type default)
		)
		(layer "In2.Cu")
	)
	(gr_line
		(start 345.398852 -308.595776)
		(end 344.972132 -308.595776)
		(stroke
			(width 0.07112)
			(type default)
		)
		(layer "In2.Cu")
	)
	(gr_line
		(start 345.532202 -308.729126)
		(end 345.398852 -308.595776)
		(stroke
			(width 0.07112)
			(type default)
		)
		(layer "In2.Cu")
	)
	(gr_line
		(start 345.533472 -309.012336)
		(end 344.837512 -309.012336)
		(stroke
			(width 0.07112)
			(type default)
		)
		(layer "In2.Cu")
	)
	(gr_arc
		(start 345.53652 -294.441626)
		(mid 345.538542 -294.430215)
		(end 345.54033 -294.418766)
		(stroke
			(width 0.05715)
			(type default)
		)
		(layer "In2.Cu")
	)
	(gr_line
		(start 345.54033 -294.418766)
		(end 345.623134 -294.335962)
		(stroke
			(width 0.05715)
			(type default)
		)
		(layer "In2.Cu")
	)
	(gr_line
		(start 345.623134 -294.335962)
		(end 345.921076 -294.335962)
		(stroke
			(width 0.05715)
			(type default)
		)
		(layer "In2.Cu")
	)
	(gr_line
		(start 345.859354 -297.951906)
		(end 345.859354 -297.980354)
		(stroke
			(width 0.05715)
			(type default)
		)
		(layer "In2.Cu")
	)
	(gr_line
		(start 345.905074 -297.906186)
		(end 345.859354 -297.951906)
		(stroke
			(width 0.05715)
			(type default)
		)
		(layer "In2.Cu")
	)
	(gr_line
		(start 345.921076 -292.71595)
		(end 346.219018 -292.71595)
		(stroke
			(width 0.05715)
			(type default)
		)
		(layer "In2.Cu")
	)
	(gr_line
		(start 346.095574 -297.906186)
		(end 346.141294 -297.951906)
		(stroke
			(width 0.05715)
			(type default)
		)
		(layer "In2.Cu")
	)
	(gr_line
		(start 346.141294 -297.951906)
		(end 346.141294 -297.980354)
		(stroke
			(width 0.05715)
			(type default)
		)
		(layer "In2.Cu")
	)
	(gr_line
		(start 346.219018 -292.71595)
		(end 346.301822 -292.798754)
		(stroke
			(width 0.05715)
			(type default)
		)
		(layer "In2.Cu")
	)
	(gr_line
		(start 346.301822 -292.817042)
		(end 346.30614 -292.82136)
		(stroke
			(width 0.05715)
			(type default)
		)
		(layer "In2.Cu")
	)
	(gr_arc
		(start 346.301822 -292.798754)
		(mid 346.301747 -292.807898)
		(end 346.301822 -292.817042)
		(stroke
			(width 0.05715)
			(type default)
		)
		(layer "In2.Cu")
	)
	(gr_line
		(start 346.547694 -293.866316)
		(end 346.531184 -293.876984)
		(stroke
			(width 0.05715)
			(type default)
		)
		(layer "In2.Cu")
	)
	(gr_line
		(start 346.563188 -294.814752)
		(end 346.562934 -294.814752)
		(stroke
			(width 0.05715)
			(type default)
		)
		(layer "In2.Cu")
	)
	(gr_line
		(start 346.563188 -292.71595)
		(end 346.493338 -292.7858)
		(stroke
			(width 0.05715)
			(type default)
		)
		(layer "In2.Cu")
	)
	(gr_line
		(start 346.658184 -293.029132)
		(end 346.659454 -293.029894)
		(stroke
			(width 0.05715)
			(type default)
		)
		(layer "In2.Cu")
	)
	(gr_line
		(start 346.658438 -294.649398)
		(end 346.6592 -294.649906)
		(stroke
			(width 0.05715)
			(type default)
		)
		(layer "In2.Cu")
	)
	(gr_line
		(start 346.86113 -292.71595)
		(end 346.563188 -292.71595)
		(stroke
			(width 0.05715)
			(type default)
		)
		(layer "In2.Cu")
	)
	(gr_line
		(start 347.308932 -296.871644)
		(end 347.308932 -296.843196)
		(stroke
			(width 0.05715)
			(type default)
		)
		(layer "In2.Cu")
	)
	(gr_line
		(start 347.308932 -296.843196)
		(end 347.354652 -296.797476)
		(stroke
			(width 0.05715)
			(type default)
		)
		(layer "In2.Cu")
	)
	(gr_line
		(start 347.326458 -307.067966)
		(end 347.354144 -307.254656)
		(stroke
			(width 0.07112)
			(type default)
		)
		(layer "In2.Cu")
	)
	(gr_line
		(start 347.354652 -296.081958)
		(end 347.354652 -296.069766)
		(stroke
			(width 0.05715)
			(type default)
		)
		(layer "In2.Cu")
	)
	(gr_arc
		(start 347.401896 -295.95572)
		(mid 347.366904 -296.008035)
		(end 347.354652 -296.069766)
		(stroke
			(width 0.05715)
			(type default)
		)
		(layer "In2.Cu")
	)
	(gr_arc
		(start 347.401896 -295.95572)
		(mid 347.404071 -295.953577)
		(end 347.406214 -295.951402)
		(stroke
			(width 0.05715)
			(type default)
		)
		(layer "In2.Cu")
	)
	(gr_arc
		(start 347.46311 -295.698672)
		(mid 347.46311 -295.698164)
		(end 347.46311 -295.697656)
		(stroke
			(width 0.05715)
			(type default)
		)
		(layer "In2.Cu")
	)
	(gr_line
		(start 347.580966 -306.724812)
		(end 347.326458 -307.067966)
		(stroke
			(width 0.07112)
			(type default)
		)
		(layer "In2.Cu")
	)
	(gr_line
		(start 347.590872 -296.871644)
		(end 347.590872 -296.843196)
		(stroke
			(width 0.05715)
			(type default)
		)
		(layer "In2.Cu")
	)
	(gr_line
		(start 347.590872 -296.843196)
		(end 347.545152 -296.797476)
		(stroke
			(width 0.05715)
			(type default)
		)
		(layer "In2.Cu")
	)
	(gr_arc
		(start 347.65361 -295.698418)
		(mid 347.65361 -295.698164)
		(end 347.65361 -295.69791)
		(stroke
			(width 0.05715)
			(type default)
		)
		(layer "In2.Cu")
	)
	(gr_line
		(start 347.7133 -295.562528)
		(end 347.7133 -295.562782)
		(stroke
			(width 0.05715)
			(type default)
		)
		(layer "In2.Cu")
	)
	(gr_line
		(start 347.767656 -306.697126)
		(end 347.580966 -306.724812)
		(stroke
			(width 0.07112)
			(type default)
		)
		(layer "In2.Cu")
	)
	(gr_line
		(start 347.996002 -306.864766)
		(end 347.580966 -307.424074)
		(stroke
			(width 0.07112)
			(type default)
		)
		(layer "In2.Cu")
	)
	(gr_line
		(start 348.004638 -306.153566)
		(end 348.032324 -306.34051)
		(stroke
			(width 0.07112)
			(type default)
		)
		(layer "In2.Cu")
	)
	(gr_line
		(start 348.099126 -294.335962)
		(end 347.801184 -294.335962)
		(stroke
			(width 0.05715)
			(type default)
		)
		(layer "In2.Cu")
	)
	(gr_line
		(start 348.168468 -294.405304)
		(end 348.099126 -294.335962)
		(stroke
			(width 0.05715)
			(type default)
		)
		(layer "In2.Cu")
	)
	(gr_line
		(start 348.259146 -305.810666)
		(end 348.004638 -306.153566)
		(stroke
			(width 0.07112)
			(type default)
		)
		(layer "In2.Cu")
	)
	(gr_arc
		(start 348.356682 -294.441626)
		(mid 348.358704 -294.430215)
		(end 348.360492 -294.418766)
		(stroke
			(width 0.05715)
			(type default)
		)
		(layer "In2.Cu")
	)
	(gr_line
		(start 348.360492 -294.418766)
		(end 348.443296 -294.335962)
		(stroke
			(width 0.05715)
			(type default)
		)
		(layer "In2.Cu")
	)
	(gr_line
		(start 348.443296 -294.335962)
		(end 348.741238 -294.335962)
		(stroke
			(width 0.05715)
			(type default)
		)
		(layer "In2.Cu")
	)
	(gr_line
		(start 348.443804 -310.939942)
		(end 348.15399 -310.650128)
		(stroke
			(width 0.07112)
			(type default)
		)
		(layer "In2.Cu")
	)
	(gr_line
		(start 348.444566 -311.223152)
		(end 348.15399 -311.513728)
		(stroke
			(width 0.07112)
			(type default)
		)
		(layer "In2.Cu")
	)
	(gr_line
		(start 348.445836 -310.939942)
		(end 348.443804 -310.939942)
		(stroke
			(width 0.07112)
			(type default)
		)
		(layer "In2.Cu")
	)
	(gr_line
		(start 348.445836 -305.78298)
		(end 348.259146 -305.810666)
		(stroke
			(width 0.07112)
			(type default)
		)
		(layer "In2.Cu")
	)
	(gr_line
		(start 348.44736 -305.782726)
		(end 348.447614 -305.782726)
		(stroke
			(width 0.07112)
			(type default)
		)
		(layer "In2.Cu")
	)
	(gr_line
		(start 348.673928 -305.950874)
		(end 348.259146 -306.509928)
		(stroke
			(width 0.07112)
			(type default)
		)
		(layer "In2.Cu")
	)
	(gr_line
		(start 348.694248 -305.22418)
		(end 348.721934 -305.41087)
		(stroke
			(width 0.07112)
			(type default)
		)
		(layer "In2.Cu")
	)
	(gr_line
		(start 348.722188 -305.412648)
		(end 348.721934 -305.412902)
		(stroke
			(width 0.07112)
			(type default)
		)
		(layer "In2.Cu")
	)
	(gr_line
		(start 348.741238 -292.71595)
		(end 349.038926 -292.71595)
		(stroke
			(width 0.05715)
			(type default)
		)
		(layer "In2.Cu")
	)
	(gr_line
		(start 348.753176 -297.607228)
		(end 348.753176 -297.635676)
		(stroke
			(width 0.05715)
			(type default)
		)
		(layer "In2.Cu")
	)
	(gr_line
		(start 348.798896 -297.561508)
		(end 348.753176 -297.607228)
		(stroke
			(width 0.05715)
			(type default)
		)
		(layer "In2.Cu")
	)
	(gr_line
		(start 348.948756 -304.88128)
		(end 348.694248 -305.22418)
		(stroke
			(width 0.07112)
			(type default)
		)
		(layer "In2.Cu")
	)
	(gr_line
		(start 348.989396 -297.561508)
		(end 349.035116 -297.607228)
		(stroke
			(width 0.05715)
			(type default)
		)
		(layer "In2.Cu")
	)
	(gr_line
		(start 349.035116 -297.607228)
		(end 349.035116 -297.635676)
		(stroke
			(width 0.05715)
			(type default)
		)
		(layer "In2.Cu")
	)
	(gr_line
		(start 349.038926 -292.71595)
		(end 349.12173 -292.798754)
		(stroke
			(width 0.05715)
			(type default)
		)
		(layer "In2.Cu")
	)
	(gr_line
		(start 349.12173 -292.817042)
		(end 349.126048 -292.82136)
		(stroke
			(width 0.05715)
			(type default)
		)
		(layer "In2.Cu")
	)
	(gr_arc
		(start 349.12173 -292.798754)
		(mid 349.121655 -292.807898)
		(end 349.12173 -292.817042)
		(stroke
			(width 0.05715)
			(type default)
		)
		(layer "In2.Cu")
	)
	(gr_line
		(start 349.135192 -304.853594)
		(end 348.948756 -304.88128)
		(stroke
			(width 0.07112)
			(type default)
		)
		(layer "In2.Cu")
	)
	(gr_line
		(start 349.350838 -293.87673)
		(end 349.351092 -293.876984)
		(stroke
			(width 0.05715)
			(type default)
		)
		(layer "In2.Cu")
	)
	(gr_arc
		(start 349.359728 -293.870634)
		(mid 349.355269 -293.873661)
		(end 349.350838 -293.87673)
		(stroke
			(width 0.05715)
			(type default)
		)
		(layer "In2.Cu")
	)
	(gr_line
		(start 349.363538 -305.021234)
		(end 348.948248 -305.58105)
		(stroke
			(width 0.07112)
			(type default)
		)
		(layer "In2.Cu")
	)
	(gr_line
		(start 349.367348 -293.866316)
		(end 349.359728 -293.870634)
		(stroke
			(width 0.05715)
			(type default)
		)
		(layer "In2.Cu")
	)
	(gr_line
		(start 349.383096 -294.814752)
		(end 349.382842 -294.814752)
		(stroke
			(width 0.05715)
			(type default)
		)
		(layer "In2.Cu")
	)
	(gr_line
		(start 349.383096 -292.71595)
		(end 349.313246 -292.7858)
		(stroke
			(width 0.05715)
			(type default)
		)
		(layer "In2.Cu")
	)
	(gr_line
		(start 349.383604 -294.81526)
		(end 349.384366 -294.815514)
		(stroke
			(width 0.05715)
			(type default)
		)
		(layer "In2.Cu")
	)
	(gr_line
		(start 349.384366 -294.815514)
		(end 349.385128 -294.816022)
		(stroke
			(width 0.05715)
			(type default)
		)
		(layer "In2.Cu")
	)
	(gr_line
		(start 349.385128 -294.816022)
		(end 349.386906 -294.817038)
		(stroke
			(width 0.05715)
			(type default)
		)
		(layer "In2.Cu")
	)
	(gr_line
		(start 349.478092 -293.029132)
		(end 349.479362 -293.029894)
		(stroke
			(width 0.05715)
			(type default)
		)
		(layer "In2.Cu")
	)
	(gr_line
		(start 349.478346 -294.649398)
		(end 349.479108 -294.649906)
		(stroke
			(width 0.05715)
			(type default)
		)
		(layer "In2.Cu")
	)
	(gr_line
		(start 349.479108 -294.649906)
		(end 349.47987 -294.650414)
		(stroke
			(width 0.05715)
			(type default)
		)
		(layer "In2.Cu")
	)
	(gr_line
		(start 349.525082 -295.606724)
		(end 349.52432 -295.607232)
		(stroke
			(width 0.05715)
			(type default)
		)
		(layer "In2.Cu")
	)
	(gr_line
		(start 349.525336 -294.677592)
		(end 349.526098 -294.6781)
		(stroke
			(width 0.05715)
			(type default)
		)
		(layer "In2.Cu")
	)
	(gr_line
		(start 349.681038 -292.71595)
		(end 349.383096 -292.71595)
		(stroke
			(width 0.05715)
			(type default)
		)
		(layer "In2.Cu")
	)
	(gr_line
		(start 349.692468 -309.790338)
		(end 349.729298 -309.976012)
		(stroke
			(width 0.07112)
			(type default)
		)
		(layer "In2.Cu")
	)
	(gr_line
		(start 349.929704 -309.4355)
		(end 349.692468 -309.790338)
		(stroke
			(width 0.07112)
			(type default)
		)
		(layer "In2.Cu")
	)
	(gr_line
		(start 350.115124 -309.398416)
		(end 349.929704 -309.4355)
		(stroke
			(width 0.07112)
			(type default)
		)
		(layer "In2.Cu")
	)
	(gr_line
		(start 350.237044 -298.22394)
		(end 350.237044 -298.195492)
		(stroke
			(width 0.05715)
			(type default)
		)
		(layer "In2.Cu")
	)
	(gr_line
		(start 350.237044 -298.195492)
		(end 350.282764 -298.149772)
		(stroke
			(width 0.05715)
			(type default)
		)
		(layer "In2.Cu")
	)
	(gr_line
		(start 350.316292 -308.856888)
		(end 350.353122 -309.042308)
		(stroke
			(width 0.07112)
			(type default)
		)
		(layer "In2.Cu")
	)
	(gr_line
		(start 350.35109 -309.555134)
		(end 349.964248 -310.134)
		(stroke
			(width 0.07112)
			(type default)
		)
		(layer "In2.Cu")
	)
	(gr_line
		(start 350.518984 -298.22394)
		(end 350.518984 -298.195492)
		(stroke
			(width 0.05715)
			(type default)
		)
		(layer "In2.Cu")
	)
	(gr_line
		(start 350.518984 -298.195492)
		(end 350.473264 -298.149772)
		(stroke
			(width 0.05715)
			(type default)
		)
		(layer "In2.Cu")
	)
	(gr_line
		(start 350.553528 -308.501796)
		(end 350.316292 -308.856888)
		(stroke
			(width 0.07112)
			(type default)
		)
		(layer "In2.Cu")
	)
	(gr_line
		(start 350.738948 -308.464966)
		(end 350.553528 -308.501796)
		(stroke
			(width 0.07112)
			(type default)
		)
		(layer "In2.Cu")
	)
	(gr_line
		(start 350.919034 -294.335962)
		(end 350.621092 -294.335962)
		(stroke
			(width 0.05715)
			(type default)
		)
		(layer "In2.Cu")
	)
	(gr_line
		(start 350.940116 -307.923438)
		(end 350.976946 -308.108858)
		(stroke
			(width 0.07112)
			(type default)
		)
		(layer "In2.Cu")
	)
	(gr_line
		(start 350.974914 -308.621684)
		(end 350.588072 -309.20055)
		(stroke
			(width 0.07112)
			(type default)
		)
		(layer "In2.Cu")
	)
	(gr_line
		(start 350.988376 -294.405304)
		(end 350.919034 -294.335962)
		(stroke
			(width 0.05715)
			(type default)
		)
		(layer "In2.Cu")
	)
	(gr_arc
		(start 351.17659 -294.441626)
		(mid 351.178612 -294.430215)
		(end 351.1804 -294.418766)
		(stroke
			(width 0.05715)
			(type default)
		)
		(layer "In2.Cu")
	)
	(gr_line
		(start 351.177352 -307.568346)
		(end 350.940116 -307.923438)
		(stroke
			(width 0.07112)
			(type default)
		)
		(layer "In2.Cu")
	)
	(gr_line
		(start 351.1804 -294.418766)
		(end 351.263204 -294.335962)
		(stroke
			(width 0.05715)
			(type default)
		)
		(layer "In2.Cu")
	)
	(gr_line
		(start 351.263204 -294.335962)
		(end 351.561146 -294.335962)
		(stroke
			(width 0.05715)
			(type default)
		)
		(layer "In2.Cu")
	)
	(gr_line
		(start 351.362772 -307.531516)
		(end 351.177352 -307.568346)
		(stroke
			(width 0.07112)
			(type default)
		)
		(layer "In2.Cu")
	)
	(gr_line
		(start 351.561146 -292.71595)
		(end 351.859088 -292.71595)
		(stroke
			(width 0.05715)
			(type default)
		)
		(layer "In2.Cu")
	)
	(gr_line
		(start 351.56394 -306.989988)
		(end 351.60077 -307.175408)
		(stroke
			(width 0.07112)
			(type default)
		)
		(layer "In2.Cu")
	)
	(gr_line
		(start 351.598738 -307.688234)
		(end 351.211896 -308.2671)
		(stroke
			(width 0.07112)
			(type default)
		)
		(layer "In2.Cu")
	)
	(gr_line
		(start 351.633536 -297.399202)
		(end 351.633536 -297.42765)
		(stroke
			(width 0.05715)
			(type default)
		)
		(layer "In2.Cu")
	)
	(gr_line
		(start 351.679256 -297.353482)
		(end 351.633536 -297.399202)
		(stroke
			(width 0.05715)
			(type default)
		)
		(layer "In2.Cu")
	)
	(gr_line
		(start 351.801176 -306.634896)
		(end 351.56394 -306.989988)
		(stroke
			(width 0.07112)
			(type default)
		)
		(layer "In2.Cu")
	)
	(gr_line
		(start 351.859088 -292.71595)
		(end 351.941892 -292.798754)
		(stroke
			(width 0.05715)
			(type default)
		)
		(layer "In2.Cu")
	)
	(gr_line
		(start 351.869756 -297.353482)
		(end 351.915476 -297.399202)
		(stroke
			(width 0.05715)
			(type default)
		)
		(layer "In2.Cu")
	)
	(gr_line
		(start 351.915476 -297.399202)
		(end 351.915476 -297.42765)
		(stroke
			(width 0.05715)
			(type default)
		)
		(layer "In2.Cu")
	)
	(gr_arc
		(start 351.941892 -292.798754)
		(mid 351.943684 -292.810076)
		(end 351.945702 -292.82136)
		(stroke
			(width 0.05715)
			(type default)
		)
		(layer "In2.Cu")
	)
	(gr_line
		(start 351.986596 -306.597812)
		(end 351.801176 -306.634896)
		(stroke
			(width 0.07112)
			(type default)
		)
		(layer "In2.Cu")
	)
	(gr_arc
		(start 352.171 -293.174928)
		(mid 352.175052 -293.17774)
		(end 352.179128 -293.180516)
		(stroke
			(width 0.05715)
			(type default)
		)
		(layer "In2.Cu")
	)
	(gr_arc
		(start 352.171254 -294.79494)
		(mid 352.175179 -294.797751)
		(end 352.179128 -294.800528)
		(stroke
			(width 0.05715)
			(type default)
		)
		(layer "In2.Cu")
	)
	(gr_line
		(start 352.179128 -294.800528)
		(end 352.185986 -294.804592)
		(stroke
			(width 0.05715)
			(type default)
		)
		(layer "In2.Cu")
	)
	(gr_line
		(start 352.179128 -293.180516)
		(end 352.185986 -293.18458)
		(stroke
			(width 0.05715)
			(type default)
		)
		(layer "In2.Cu")
	)
	(gr_line
		(start 352.185986 -294.804592)
		(end 352.186748 -294.8051)
		(stroke
			(width 0.05715)
			(type default)
		)
		(layer "In2.Cu")
	)
	(gr_line
		(start 352.185986 -293.18458)
		(end 352.186748 -293.185088)
		(stroke
			(width 0.05715)
			(type default)
		)
		(layer "In2.Cu")
	)
	(gr_line
		(start 352.186748 -294.8051)
		(end 352.18751 -294.805608)
		(stroke
			(width 0.05715)
			(type default)
		)
		(layer "In2.Cu")
	)
	(gr_line
		(start 352.186748 -293.185088)
		(end 352.18751 -293.185596)
		(stroke
			(width 0.05715)
			(type default)
		)
		(layer "In2.Cu")
	)
	(gr_line
		(start 352.203258 -292.71595)
		(end 352.133916 -292.785292)
		(stroke
			(width 0.05715)
			(type default)
		)
		(layer "In2.Cu")
	)
	(gr_line
		(start 352.21164 -293.852092)
		(end 352.210624 -293.8526)
		(stroke
			(width 0.05715)
			(type default)
		)
		(layer "In2.Cu")
	)
	(gr_line
		(start 352.214434 -293.850568)
		(end 352.21164 -293.852092)
		(stroke
			(width 0.05715)
			(type default)
		)
		(layer "In2.Cu")
	)
	(gr_line
		(start 352.21545 -293.85006)
		(end 352.214434 -293.850568)
		(stroke
			(width 0.05715)
			(type default)
		)
		(layer "In2.Cu")
	)
	(gr_line
		(start 352.217228 -293.849044)
		(end 352.21545 -293.85006)
		(stroke
			(width 0.05715)
			(type default)
		)
		(layer "In2.Cu")
	)
	(gr_line
		(start 352.218498 -293.20363)
		(end 352.219006 -293.203884)
		(stroke
			(width 0.05715)
			(type default)
		)
		(layer "In2.Cu")
	)
	(gr_line
		(start 352.219006 -293.203884)
		(end 352.2218 -293.205408)
		(stroke
			(width 0.05715)
			(type default)
		)
		(layer "In2.Cu")
	)
	(gr_line
		(start 352.222308 -306.754276)
		(end 352.222562 -306.75453)
		(stroke
			(width 0.07112)
			(type default)
		)
		(layer "In2.Cu")
	)
	(gr_line
		(start 352.222562 -306.75453)
		(end 351.83572 -307.333396)
		(stroke
			(width 0.07112)
			(type default)
		)
		(layer "In2.Cu")
	)
	(gr_line
		(start 352.22434 -294.826944)
		(end 352.224594 -294.826944)
		(stroke
			(width 0.05715)
			(type default)
		)
		(layer "In2.Cu")
	)
	(gr_line
		(start 352.30689 -294.017446)
		(end 352.305874 -294.017954)
		(stroke
			(width 0.05715)
			(type default)
		)
		(layer "In2.Cu")
	)
	(gr_line
		(start 352.307652 -294.016938)
		(end 352.30689 -294.017446)
		(stroke
			(width 0.05715)
			(type default)
		)
		(layer "In2.Cu")
	)
	(gr_line
		(start 352.310192 -294.015668)
		(end 352.307652 -294.016938)
		(stroke
			(width 0.05715)
			(type default)
		)
		(layer "In2.Cu")
	)
	(gr_line
		(start 352.312732 -294.014144)
		(end 352.31197 -294.014652)
		(stroke
			(width 0.05715)
			(type default)
		)
		(layer "In2.Cu")
	)
	(gr_line
		(start 352.314002 -294.013382)
		(end 352.312732 -294.014144)
		(stroke
			(width 0.05715)
			(type default)
		)
		(layer "In2.Cu")
	)
	(gr_line
		(start 352.314256 -294.658542)
		(end 352.320352 -294.662098)
		(stroke
			(width 0.05715)
			(type default)
		)
		(layer "In2.Cu")
	)
	(gr_line
		(start 352.405696 -295.141904)
		(end 352.40595 -295.14165)
		(stroke
			(width 0.05715)
			(type default)
		)
		(layer "In2.Cu")
	)
	(gr_line
		(start 352.5012 -292.71595)
		(end 352.203258 -292.71595)
		(stroke
			(width 0.05715)
			(type default)
		)
		(layer "In2.Cu")
	)
	(gr_line
		(start 353.027996 -296.276014)
		(end 353.027996 -296.247566)
		(stroke
			(width 0.05715)
			(type default)
		)
		(layer "In2.Cu")
	)
	(gr_line
		(start 353.027996 -296.247566)
		(end 353.073716 -296.201846)
		(stroke
			(width 0.05715)
			(type default)
		)
		(layer "In2.Cu")
	)
	(gr_line
		(start 353.309936 -296.276014)
		(end 353.309936 -296.247566)
		(stroke
			(width 0.05715)
			(type default)
		)
		(layer "In2.Cu")
	)
	(gr_line
		(start 353.309936 -296.247566)
		(end 353.264216 -296.201846)
		(stroke
			(width 0.05715)
			(type default)
		)
		(layer "In2.Cu")
	)
	(gr_arc
		(start 353.353624 -295.562274)
		(mid 353.35337 -295.562528)
		(end 353.353116 -295.562782)
		(stroke
			(width 0.05715)
			(type default)
		)
		(layer "In2.Cu")
	)
	(gr_line
		(start 353.738942 -294.335962)
		(end 353.441 -294.335962)
		(stroke
			(width 0.05715)
			(type default)
		)
		(layer "In2.Cu")
	)
	(gr_line
		(start 353.808284 -294.405304)
		(end 353.738942 -294.335962)
		(stroke
			(width 0.05715)
			(type default)
		)
		(layer "In2.Cu")
	)
	(gr_arc
		(start 353.996498 -294.441626)
		(mid 353.99852 -294.430215)
		(end 354.000308 -294.418766)
		(stroke
			(width 0.05715)
			(type default)
		)
		(layer "In2.Cu")
	)
	(gr_line
		(start 354.000308 -294.418766)
		(end 354.083112 -294.335962)
		(stroke
			(width 0.05715)
			(type default)
		)
		(layer "In2.Cu")
	)
	(gr_line
		(start 354.083112 -294.335962)
		(end 354.381054 -294.335962)
		(stroke
			(width 0.05715)
			(type default)
		)
		(layer "In2.Cu")
	)
	(gr_line
		(start 354.381054 -292.71595)
		(end 354.678996 -292.71595)
		(stroke
			(width 0.05715)
			(type default)
		)
		(layer "In2.Cu")
	)
	(gr_line
		(start 354.665026 -296.396664)
		(end 354.665026 -296.425112)
		(stroke
			(width 0.05715)
			(type default)
		)
		(layer "In2.Cu")
	)
	(gr_line
		(start 354.678996 -292.71595)
		(end 354.7618 -292.798754)
		(stroke
			(width 0.05715)
			(type default)
		)
		(layer "In2.Cu")
	)
	(gr_line
		(start 354.710746 -296.350944)
		(end 354.665026 -296.396664)
		(stroke
			(width 0.05715)
			(type default)
		)
		(layer "In2.Cu")
	)
	(gr_arc
		(start 354.7618 -292.798754)
		(mid 354.763591 -292.810076)
		(end 354.76561 -292.82136)
		(stroke
			(width 0.05715)
			(type default)
		)
		(layer "In2.Cu")
	)
	(gr_line
		(start 354.901246 -296.350944)
		(end 354.946966 -296.396664)
		(stroke
			(width 0.05715)
			(type default)
		)
		(layer "In2.Cu")
	)
	(gr_line
		(start 354.946966 -296.396664)
		(end 354.946966 -296.425112)
		(stroke
			(width 0.05715)
			(type default)
		)
		(layer "In2.Cu")
	)
	(gr_line
		(start 354.953316 -292.7858)
		(end 354.953062 -292.7858)
		(stroke
			(width 0.05715)
			(type default)
		)
		(layer "In2.Cu")
	)
	(gr_arc
		(start 354.991416 -293.175182)
		(mid 354.995215 -293.177864)
		(end 354.999036 -293.180516)
		(stroke
			(width 0.05715)
			(type default)
		)
		(layer "In2.Cu")
	)
	(gr_line
		(start 354.999036 -293.180516)
		(end 355.005894 -293.18458)
		(stroke
			(width 0.05715)
			(type default)
		)
		(layer "In2.Cu")
	)
	(gr_line
		(start 355.005894 -293.18458)
		(end 355.006656 -293.185088)
		(stroke
			(width 0.05715)
			(type default)
		)
		(layer "In2.Cu")
	)
	(gr_line
		(start 355.023166 -293.19474)
		(end 355.026722 -293.196772)
		(stroke
			(width 0.05715)
			(type default)
		)
		(layer "In2.Cu")
	)
	(gr_line
		(start 355.023166 -292.71595)
		(end 354.953824 -292.785292)
		(stroke
			(width 0.05715)
			(type default)
		)
		(layer "In2.Cu")
	)
	(gr_line
		(start 355.026722 -293.196772)
		(end 355.031802 -293.199566)
		(stroke
			(width 0.05715)
			(type default)
		)
		(layer "In2.Cu")
	)
	(gr_line
		(start 355.030024 -293.853362)
		(end 355.029516 -293.853616)
		(stroke
			(width 0.05715)
			(type default)
		)
		(layer "In2.Cu")
	)
	(gr_line
		(start 355.031802 -293.199566)
		(end 355.038152 -293.203376)
		(stroke
			(width 0.05715)
			(type default)
		)
		(layer "In2.Cu")
	)
	(gr_line
		(start 355.04374 -293.845234)
		(end 355.039676 -293.84752)
		(stroke
			(width 0.05715)
			(type default)
		)
		(layer "In2.Cu")
	)
	(gr_line
		(start 355.120448 -293.03091)
		(end 355.125528 -293.033958)
		(stroke
			(width 0.05715)
			(type default)
		)
		(layer "In2.Cu")
	)
	(gr_line
		(start 355.125528 -293.033958)
		(end 355.13391 -293.03853)
		(stroke
			(width 0.05715)
			(type default)
		)
		(layer "In2.Cu")
	)
	(gr_line
		(start 355.135434 -293.039546)
		(end 355.136958 -293.040562)
		(stroke
			(width 0.05715)
			(type default)
		)
		(layer "In2.Cu")
	)
	(gr_line
		(start 355.321108 -292.71595)
		(end 355.023166 -292.71595)
		(stroke
			(width 0.05715)
			(type default)
		)
		(layer "In2.Cu")
	)
	(gr_line
		(start 357.94188 -401.968208)
		(end 358.437942 -401.472146)
		(stroke
			(width 0.07112)
			(type default)
		)
		(layer "In2.Cu")
	)
	(gr_line
		(start 358.143048 -402.167598)
		(end 358.335326 -402.167598)
		(stroke
			(width 0.07112)
			(type default)
		)
		(layer "In2.Cu")
	)
	(gr_line
		(start 358.335326 -402.167598)
		(end 358.637332 -401.865592)
		(stroke
			(width 0.07112)
			(type default)
		)
		(layer "In2.Cu")
	)
	(gr_line
		(start 358.637332 -401.865592)
		(end 358.637332 -401.673314)
		(stroke
			(width 0.07112)
			(type default)
		)
		(layer "In2.Cu")
	)
	(gr_line
		(start 358.907842 -400.294094)
		(end 358.907842 -399.593054)
		(stroke
			(width 0.07112)
			(type default)
		)
		(layer "In2.Cu")
	)
	(gr_line
		(start 359.191052 -400.292824)
		(end 359.326942 -400.156934)
		(stroke
			(width 0.07112)
			(type default)
		)
		(layer "In2.Cu")
	)
	(gr_line
		(start 359.326942 -400.156934)
		(end 359.326942 -399.730214)
		(stroke
			(width 0.07112)
			(type default)
		)
		(layer "In2.Cu")
	)
	(gr_line
		(start 359.326942 -399.730214)
		(end 359.191052 -399.594324)
		(stroke
			(width 0.07112)
			(type default)
		)
		(layer "In2.Cu")
	)
	(gr_line
		(start 359.678478 -403.639274)
		(end 359.730294 -403.617684)
		(stroke
			(width 0.07112)
			(type default)
		)
		(layer "In2.Cu")
	)
	(gr_line
		(start 359.730294 -403.617684)
		(end 359.786682 -403.617684)
		(stroke
			(width 0.07112)
			(type default)
		)
		(layer "In2.Cu")
	)
	(gr_line
		(start 359.786428 -403.899878)
		(end 359.786682 -403.899624)
		(stroke
			(width 0.07112)
			(type default)
		)
		(layer "In2.Cu")
	)
	(gr_line
		(start 364.091982 -395.880844)
		(end 364.382812 -396.171674)
		(stroke
			(width 0.07112)
			(type default)
		)
		(layer "In2.Cu")
	)
	(gr_line
		(start 364.091982 -395.598904)
		(end 364.382812 -395.308074)
		(stroke
			(width 0.07112)
			(type default)
		)
		(layer "In2.Cu")
	)
	(gr_line
		(start 364.810802 4.650994)
		(end 364.519972 4.941824)
		(stroke
			(width 0.07112)
			(type default)
		)
		(layer "In2.Cu")
	)
	(gr_line
		(start 364.810802 5.514594)
		(end 364.519972 5.223764)
		(stroke
			(width 0.07112)
			(type default)
		)
		(layer "In2.Cu")
	)
	(gr_arc
		(start 383.601976 -9.272016)
		(mid 384.656976 -8.83502)
		(end 385.093972 -7.78002)
		(stroke
			(width 0.2)
			(type default)
		)
		(layer "In2.Cu")
	)
	(gr_line
		(start 385.093972 -7.78002)
		(end 385.093972 0.40005)
		(stroke
			(width 0.2)
			(type default)
		)
		(layer "In2.Cu")
	)
	(gr_line
		(start 385.601972 -12.288012)
		(end 260.800088 -12.288012)
		(stroke
			(width 0.2)
			(type default)
		)
		(layer "In2.Cu")
	)
	(gr_arc
		(start 385.601972 -12.288012)
		(mid 387.375417 -11.553448)
		(end 388.109968 -9.780016)
		(stroke
			(width 0.2)
			(type default)
		)
		(layer "In2.Cu")
	)
	(gr_arc
		(start 387.601968 2.908046)
		(mid 385.828585 2.173457)
		(end 385.093972 0.40005)
		(stroke
			(width 0.2)
			(type default)
		)
		(layer "In2.Cu")
	)
	(gr_line
		(start 387.601968 2.908046)
		(end 456.202034 2.908046)
		(stroke
			(width 0.2)
			(type default)
		)
		(layer "In2.Cu")
	)
	(gr_line
		(start 388.109968 -0.508)
		(end 388.109968 -9.780016)
		(stroke
			(width 0.2)
			(type default)
		)
		(layer "In2.Cu")
	)
	(gr_line
		(start 391.216388 -399.851626)
		(end 391.712196 -399.355818)
		(stroke
			(width 0.07112)
			(type default)
		)
		(layer "In2.Cu")
	)
	(gr_line
		(start 391.417556 -400.051016)
		(end 391.60958 -400.051016)
		(stroke
			(width 0.07112)
			(type default)
		)
		(layer "In2.Cu")
	)
	(gr_line
		(start 391.60958 -400.051016)
		(end 391.911586 -399.74901)
		(stroke
			(width 0.07112)
			(type default)
		)
		(layer "In2.Cu")
	)
	(gr_line
		(start 391.911586 -399.74901)
		(end 391.911586 -399.556986)
		(stroke
			(width 0.07112)
			(type default)
		)
		(layer "In2.Cu")
	)
	(gr_line
		(start 392.013694 -399.05432)
		(end 392.509756 -398.558258)
		(stroke
			(width 0.07112)
			(type default)
		)
		(layer "In2.Cu")
	)
	(gr_line
		(start 392.214862 -399.25371)
		(end 392.40714 -399.25371)
		(stroke
			(width 0.07112)
			(type default)
		)
		(layer "In2.Cu")
	)
	(gr_line
		(start 392.40714 -399.25371)
		(end 392.709146 -398.951704)
		(stroke
			(width 0.07112)
			(type default)
		)
		(layer "In2.Cu")
	)
	(gr_line
		(start 392.709146 -398.951704)
		(end 392.709146 -398.759426)
		(stroke
			(width 0.07112)
			(type default)
		)
		(layer "In2.Cu")
	)
	(gr_line
		(start 396.61973 -395.880844)
		(end 396.91056 -396.171674)
		(stroke
			(width 0.07112)
			(type default)
		)
		(layer "In2.Cu")
	)
	(gr_line
		(start 396.61973 -395.598904)
		(end 396.91056 -395.308074)
		(stroke
			(width 0.07112)
			(type default)
		)
		(layer "In2.Cu")
	)
	(gr_line
		(start 455.694034 -9.780016)
		(end 455.694034 -0.508)
		(stroke
			(width 0.2)
			(type default)
		)
		(layer "In2.Cu")
	)
	(gr_arc
		(start 455.694034 -9.780016)
		(mid 456.428616 -11.553416)
		(end 458.20203 -12.288012)
		(stroke
			(width 0.2)
			(type default)
		)
		(layer "In2.Cu")
	)
	(gr_line
		(start 455.694034 -0.508)
		(end 388.109968 -0.508)
		(stroke
			(width 0.2)
			(type default)
		)
		(layer "In2.Cu")
	)
	(gr_arc
		(start 458.71003 -7.78002)
		(mid 459.147026 -8.83502)
		(end 460.202026 -9.272016)
		(stroke
			(width 0.2)
			(type default)
		)
		(layer "In2.Cu")
	)
	(gr_arc
		(start 458.71003 0.40005)
		(mid 457.975475 2.173515)
		(end 456.202034 2.908046)
		(stroke
			(width 0.2)
			(type default)
		)
		(layer "In2.Cu")
	)
	(gr_line
		(start 458.71003 0.40005)
		(end 458.71003 -7.78002)
		(stroke
			(width 0.2)
			(type default)
		)
		(layer "In2.Cu")
	)
	(gr_line
		(start 460.202026 -9.272016)
		(end 464.439 -9.272016)
		(stroke
			(width 0.2)
			(type default)
		)
		(layer "In2.Cu")
	)
	(gr_arc
		(start 463.300064 -441.481972)
		(mid 464.355064 -441.044976)
		(end 464.79206 -439.989976)
		(stroke
			(width 0.2)
			(type default)
		)
		(layer "In2.Cu")
	)
	(gr_line
		(start 464.439 -12.288012)
		(end 458.20203 -12.288012)
		(stroke
			(width 0.2)
			(type default)
		)
		(layer "In2.Cu")
	)
	(gr_line
		(start 464.439 -9.272016)
		(end 464.439 -12.288012)
		(stroke
			(width 0.2)
			(type default)
		)
		(layer "In2.Cu")
	)
	(gr_line
		(start 464.447636 -12.288012)
		(end 464.447636 -9.272016)
		(stroke
			(width 0.2)
			(type default)
		)
		(layer "In2.Cu")
	)
	(gr_line
		(start 464.447636 -9.272016)
		(end 469.799924 -9.272016)
		(stroke
			(width 0.2)
			(type default)
		)
		(layer "In2.Cu")
	)
	(gr_line
		(start 464.79206 -439.989976)
		(end 464.79206 -418.46881)
		(stroke
			(width 0.2)
			(type default)
		)
		(layer "In2.Cu")
	)
	(gr_line
		(start 464.79206 -418.46881)
		(end 467.808056 -418.46881)
		(stroke
			(width 0.2)
			(type default)
		)
		(layer "In2.Cu")
	)
	(gr_line
		(start 464.79206 -418.45738)
		(end 464.79206 -409.528264)
		(stroke
			(width 0.2)
			(type default)
		)
		(layer "In2.Cu")
	)
	(gr_arc
		(start 465.526628 -407.75509)
		(mid 464.983024 -408.568632)
		(end 464.79206 -409.528264)
		(stroke
			(width 0.2)
			(type default)
		)
		(layer "In2.Cu")
	)
	(gr_line
		(start 465.526628 -407.75509)
		(end 467.355174 -405.926544)
		(stroke
			(width 0.2)
			(type default)
		)
		(layer "In2.Cu")
	)
	(gr_arc
		(start 467.355174 -405.926544)
		(mid 467.678507 -405.442687)
		(end 467.792054 -404.871936)
		(stroke
			(width 0.2)
			(type default)
		)
		(layer "In2.Cu")
	)
	(gr_line
		(start 467.792054 -404.871936)
		(end 467.792054 -82.82813)
		(stroke
			(width 0.2)
			(type default)
		)
		(layer "In2.Cu")
	)
	(gr_arc
		(start 467.808056 -439.989976)
		(mid 468.245052 -441.044976)
		(end 469.300052 -441.481972)
		(stroke
			(width 0.2)
			(type default)
		)
		(layer "In2.Cu")
	)
	(gr_line
		(start 467.808056 -418.46881)
		(end 467.808056 -439.989976)
		(stroke
			(width 0.2)
			(type default)
		)
		(layer "In2.Cu")
	)
	(gr_line
		(start 467.808056 -418.45738)
		(end 464.79206 -418.45738)
		(stroke
			(width 0.2)
			(type default)
		)
		(layer "In2.Cu")
	)
	(gr_line
		(start 467.808056 -410.356812)
		(end 467.808056 -418.45738)
		(stroke
			(width 0.2)
			(type default)
		)
		(layer "In2.Cu")
	)
	(gr_arc
		(start 468.244936 -409.30195)
		(mid 467.921608 -409.785939)
		(end 467.808056 -410.356812)
		(stroke
			(width 0.2)
			(type default)
		)
		(layer "In2.Cu")
	)
	(gr_arc
		(start 468.526622 -81.054956)
		(mid 467.983009 -81.868496)
		(end 467.792054 -82.82813)
		(stroke
			(width 0.2)
			(type default)
		)
		(layer "In2.Cu")
	)
	(gr_line
		(start 468.526622 -81.054956)
		(end 470.85504 -78.726538)
		(stroke
			(width 0.2)
			(type default)
		)
		(layer "In2.Cu")
	)
	(gr_line
		(start 469.300052 -441.481972)
		(end 471.79992 -441.481972)
		(stroke
			(width 0.2)
			(type default)
		)
		(layer "In2.Cu")
	)
	(gr_line
		(start 469.487758 -408.059128)
		(end 468.244936 -409.30195)
		(stroke
			(width 0.2)
			(type default)
		)
		(layer "In2.Cu")
	)
	(gr_arc
		(start 469.487758 -408.059128)
		(mid 470.464844 -406.596826)
		(end 470.80805 -404.871936)
		(stroke
			(width 0.2)
			(type default)
		)
		(layer "In2.Cu")
	)
	(gr_line
		(start 469.799924 -12.288012)
		(end 464.447636 -12.288012)
		(stroke
			(width 0.2)
			(type default)
		)
		(layer "In2.Cu")
	)
	(gr_arc
		(start 469.799924 -9.272016)
		(mid 470.854924 -8.83502)
		(end 471.29192 -7.78002)
		(stroke
			(width 0.2)
			(type default)
		)
		(layer "In2.Cu")
	)
	(gr_line
		(start 469.799924 11.892026)
		(end 1.999996 11.892026)
		(stroke
			(width 0.2)
			(type default)
		)
		(layer "In2.Cu")
	)
	(gr_line
		(start 470.80805 -83.656678)
		(end 470.80805 -404.871936)
		(stroke
			(width 0.2)
			(type default)
		)
		(layer "In2.Cu")
	)
	(gr_arc
		(start 470.85504 -78.726538)
		(mid 471.178373 -78.242681)
		(end 471.29192 -77.67193)
		(stroke
			(width 0.2)
			(type default)
		)
		(layer "In2.Cu")
	)
	(gr_arc
		(start 471.245184 -82.601562)
		(mid 470.921671 -83.085639)
		(end 470.80805 -83.656678)
		(stroke
			(width 0.2)
			(type default)
		)
		(layer "In2.Cu")
	)
	(gr_line
		(start 471.29192 -77.67193)
		(end 471.29192 -13.780008)
		(stroke
			(width 0.2)
			(type default)
		)
		(layer "In2.Cu")
	)
	(gr_arc
		(start 471.29192 -13.780008)
		(mid 470.854924 -12.725008)
		(end 469.799924 -12.288012)
		(stroke
			(width 0.2)
			(type default)
		)
		(layer "In2.Cu")
	)
	(gr_line
		(start 471.29192 -7.78002)
		(end 471.29192 10.40003)
		(stroke
			(width 0.2)
			(type default)
		)
		(layer "In2.Cu")
	)
	(gr_arc
		(start 471.29192 10.40003)
		(mid 470.854924 11.45503)
		(end 469.799924 11.892026)
		(stroke
			(width 0.2)
			(type default)
		)
		(layer "In2.Cu")
	)
	(gr_line
		(start 472.987624 -80.859122)
		(end 471.245184 -82.601562)
		(stroke
			(width 0.2)
			(type default)
		)
		(layer "In2.Cu")
	)
	(gr_arc
		(start 472.987624 -80.859122)
		(mid 473.964715 -79.396821)
		(end 474.307916 -77.67193)
		(stroke
			(width 0.2)
			(type default)
		)
		(layer "In2.Cu")
	)
	(gr_arc
		(start 474.307916 -461.028288)
		(mid 474.744912 -462.083288)
		(end 475.799912 -462.520284)
		(stroke
			(width 0.2)
			(type default)
		)
		(layer "In2.Cu")
	)
	(gr_arc
		(start 474.307916 -443.989968)
		(mid 473.573331 -442.216561)
		(end 471.79992 -441.481972)
		(stroke
			(width 0.2)
			(type default)
		)
		(layer "In2.Cu")
	)
	(gr_line
		(start 474.307916 -443.989968)
		(end 474.307916 -461.028288)
		(stroke
			(width 0.2)
			(type default)
		)
		(layer "In2.Cu")
	)
	(gr_line
		(start 474.307916 10.40003)
		(end 474.307916 -77.67193)
		(stroke
			(width 0.2)
			(type default)
		)
		(layer "In2.Cu")
	)
	(gr_line
		(start 475.799912 -462.520284)
		(end 531.7998 -462.520284)
		(stroke
			(width 0.2)
			(type default)
		)
		(layer "In2.Cu")
	)
	(gr_arc
		(start 475.799912 11.892026)
		(mid 474.744912 11.45503)
		(end 474.307916 10.40003)
		(stroke
			(width 0.2)
			(type default)
		)
		(layer "In2.Cu")
	)
	(gr_line
		(start 513.5118 -451.028308)
		(end 513.5118 -312.408316)
		(stroke
			(width 0.2)
			(type default)
		)
		(layer "In2.Cu")
	)
	(gr_arc
		(start 513.5118 -451.028308)
		(mid 514.246378 -452.801725)
		(end 516.019796 -453.536304)
		(stroke
			(width 0.2)
			(type default)
		)
		(layer "In2.Cu")
	)
	(gr_arc
		(start 516.019796 -309.90032)
		(mid 514.246383 -310.634897)
		(end 513.5118 -312.408316)
		(stroke
			(width 0.2)
			(type default)
		)
		(layer "In2.Cu")
	)
	(gr_line
		(start 516.019796 -309.90032)
		(end 531.7998 -309.90032)
		(stroke
			(width 0.2)
			(type default)
		)
		(layer "In2.Cu")
	)
	(gr_arc
		(start 531.7998 -462.520284)
		(mid 532.8548 -462.083288)
		(end 533.291796 -461.028288)
		(stroke
			(width 0.2)
			(type default)
		)
		(layer "In2.Cu")
	)
	(gr_line
		(start 531.7998 -453.536304)
		(end 516.019796 -453.536304)
		(stroke
			(width 0.2)
			(type default)
		)
		(layer "In2.Cu")
	)
	(gr_arc
		(start 531.7998 -309.90032)
		(mid 532.8548 -309.463324)
		(end 533.291796 -308.408324)
		(stroke
			(width 0.2)
			(type default)
		)
		(layer "In2.Cu")
	)
	(gr_line
		(start 531.7998 11.892026)
		(end 475.799912 11.892026)
		(stroke
			(width 0.2)
			(type default)
		)
		(layer "In2.Cu")
	)
	(gr_line
		(start 533.291796 -461.028288)
		(end 533.291796 -455.0283)
		(stroke
			(width 0.2)
			(type default)
		)
		(layer "In2.Cu")
	)
	(gr_arc
		(start 533.291796 -455.0283)
		(mid 532.8548 -453.9733)
		(end 531.7998 -453.536304)
		(stroke
			(width 0.2)
			(type default)
		)
		(layer "In2.Cu")
	)
	(gr_line
		(start 533.291796 -308.408324)
		(end 533.291796 10.40003)
		(stroke
			(width 0.2)
			(type default)
		)
		(layer "In2.Cu")
	)
	(gr_arc
		(start 533.291796 10.40003)
		(mid 532.8548 11.45503)
		(end 531.7998 11.892026)
		(stroke
			(width 0.2)
			(type default)
		)
		(layer "In2.Cu")
	)
	(gr_line
		(start 0 -77.671676)
		(end 0 -13.780008)
		(stroke
			(width 1.016)
			(type default)
		)
		(layer "In3.Cu")
	)
	(gr_arc
		(start 0 -77.671676)
		(mid 0.152237 -78.436936)
		(end 0.585724 -79.085694)
		(stroke
			(width 1.016)
			(type default)
		)
		(layer "In3.Cu")
	)
	(gr_poly
		(pts
			(arc
				(start 228.921818 -436.47868)
				(mid 228.941341 -436.474779)
				(end 228.957886 -436.463694)
			)
			(arc
				(start 229.664514 -435.757066)
				(mid 229.675625 -435.740532)
				(end 229.6795 -435.720998)
			)
			(arc
				(start 229.6795 -422.180766)
				(mid 229.703653 -422.05925)
				(end 229.772464 -421.95623)
			)
			(arc
				(start 234.67314 -417.055554)
				(mid 234.776172 -416.986773)
				(end 234.897676 -416.96259)
			)
			(arc
				(start 272.037556 -416.96259)
				(mid 272.057079 -416.958689)
				(end 272.073624 -416.947604)
			)
			(arc
				(start 280.035254 -408.985974)
				(mid 280.046365 -408.96944)
				(end 280.05024 -408.949906)
			)
			(arc
				(start 280.05024 -398.565878)
				(mid 280.046339 -398.546355)
				(end 280.035254 -398.52981)
			)
			(arc
				(start 279.299162 -397.793718)
				(mid 279.282628 -397.782607)
				(end 279.263094 -397.778732)
			)
			(arc
				(start 239.55375 -397.778732)
				(mid 239.534227 -397.782633)
				(end 239.517682 -397.793718)
			)
			(arc
				(start 239.215168 -398.096232)
				(mid 239.204057 -398.112766)
				(end 239.200182 -398.1323)
			)
			(arc
				(start 239.200182 -406.145746)
				(mid 239.176029 -406.267262)
				(end 239.107218 -406.370282)
			)
			(arc
				(start 234.940348 -410.537152)
				(mid 234.837316 -410.605933)
				(end 234.715812 -410.630116)
			)
			(arc
				(start 229.698296 -410.630116)
				(mid 229.678773 -410.634017)
				(end 229.662228 -410.645102)
			)
			(arc
				(start 227.156264 -413.151066)
				(mid 227.053232 -413.219847)
				(end 226.931728 -413.24403)
			)
			(arc
				(start 195.949062 -413.24403)
				(mid 195.929539 -413.247931)
				(end 195.912994 -413.259016)
			)
			(arc
				(start 195.239386 -413.932624)
				(mid 195.228275 -413.949158)
				(end 195.2244 -413.968692)
			)
			(arc
				(start 195.2244 -420.7002)
				(mid 195.228301 -420.719723)
				(end 195.239386 -420.736268)
			)
			(xy 195.23964 -420.736522)
			(arc
				(start 205.961996 -431.458878)
				(mid 206.030777 -431.56191)
				(end 206.05496 -431.683414)
			)
			(arc
				(start 206.05496 -435.078378)
				(mid 206.058861 -435.097901)
				(end 206.069946 -435.114446)
			)
			(arc
				(start 207.419194 -436.463694)
				(mid 207.435728 -436.474805)
				(end 207.455262 -436.47868)
			)
		)
		(stroke
			(width 0)
			(type solid)
		)
		(fill yes)
		(layer "In3.Cu")
		(net "P12V_PSU")
	)
	(gr_poly
		(pts
			(xy 531.7998 -462.519268) (xy 531.855569 -462.518759) (xy 531.966796 -462.510424) (xy 532.077089 -462.4938)
			(xy 532.185831 -462.46898) (xy 532.292414 -462.436103) (xy 532.396243 -462.395354) (xy 532.496736 -462.346959)
			(xy 532.593331 -462.291189) (xy 532.685488 -462.228357) (xy 532.772692 -462.158813) (xy 532.854456 -462.082947)
			(xy 532.930321 -462.001183) (xy 532.999864 -461.913979) (xy 533.062695 -461.821821) (xy 533.118464 -461.725225)
			(xy 533.166858 -461.624732) (xy 533.207607 -461.520903) (xy 533.240483 -461.41432) (xy 533.265302 -461.305577)
			(xy 533.281925 -461.195284) (xy 533.29026 -461.084057) (xy 533.29078 -461.028288) (xy 533.29078 -455.0283)
			(xy 533.290259 -454.972531) (xy 533.281923 -454.861305) (xy 533.265299 -454.751013) (xy 533.24048 -454.642271)
			(xy 533.207603 -454.535688) (xy 533.166854 -454.43186) (xy 533.118459 -454.331368) (xy 533.06269 -454.234773)
			(xy 532.999859 -454.142616) (xy 532.930316 -454.055412) (xy 532.854451 -453.973649) (xy 532.772688 -453.897784)
			(xy 532.685484 -453.828241) (xy 532.593327 -453.76541) (xy 532.496732 -453.709641) (xy 532.39624 -453.661246)
			(xy 532.292412 -453.620497) (xy 532.185829 -453.58762) (xy 532.077087 -453.562801) (xy 531.966795 -453.546177)
			(xy 531.855569 -453.537841) (xy 531.7998 -453.53732) (xy 516.019796 -453.53732) (xy 515.949414 -453.536826)
			(xy 515.808871 -453.528933) (xy 515.668991 -453.513172) (xy 515.530216 -453.489593) (xy 515.392981 -453.45827)
			(xy 515.257718 -453.419302) (xy 515.124852 -453.37281) (xy 514.994803 -453.318942) (xy 514.867978 -453.257866)
			(xy 514.744778 -453.189776) (xy 514.625589 -453.114884) (xy 514.510787 -453.033428) (xy 514.400733 -452.945663)
			(xy 514.295773 -452.851865) (xy 514.196238 -452.75233) (xy 514.10244 -452.64737) (xy 514.014674 -452.537316)
			(xy 513.933218 -452.422514) (xy 513.858326 -452.303325) (xy 513.790236 -452.180125) (xy 513.72916 -452.053301)
			(xy 513.675292 -451.923251) (xy 513.6288 -451.790386) (xy 513.589831 -451.655123) (xy 513.558507 -451.517888)
			(xy 513.534928 -451.379113) (xy 513.519167 -451.239233) (xy 513.511274 -451.09869) (xy 513.510784 -451.028308)
			(xy 513.510784 -312.408316) (xy 513.511268 -312.337933) (xy 513.51916 -312.197389) (xy 513.53492 -312.057508)
			(xy 513.558498 -311.918731) (xy 513.589821 -311.781495) (xy 513.628789 -311.646231) (xy 513.67528 -311.513364)
			(xy 513.729148 -311.383313) (xy 513.790224 -311.256488) (xy 513.858314 -311.133286) (xy 513.933205 -311.014096)
			(xy 514.014662 -310.899292) (xy 514.102427 -310.789237) (xy 514.196225 -310.684276) (xy 514.295761 -310.584739)
			(xy 514.400722 -310.49094) (xy 514.510776 -310.403174) (xy 514.625579 -310.321716) (xy 514.744769 -310.246824)
			(xy 514.86797 -310.178733) (xy 514.994795 -310.117656) (xy 515.124845 -310.063787) (xy 515.257712 -310.017295)
			(xy 515.392976 -309.978326) (xy 515.530212 -309.947002) (xy 515.668989 -309.923423) (xy 515.808869 -309.907662)
			(xy 515.949413 -309.899769) (xy 516.019796 -309.899304) (xy 531.7998 -309.899304) (xy 531.855569 -309.898783)
			(xy 531.966796 -309.890447) (xy 532.077089 -309.873823) (xy 532.185831 -309.849004) (xy 532.292415 -309.816128)
			(xy 532.396243 -309.775378) (xy 532.496737 -309.726984) (xy 532.593332 -309.671215) (xy 532.68549 -309.608384)
			(xy 532.772695 -309.538841) (xy 532.854459 -309.462976) (xy 532.930326 -309.381213) (xy 532.99987 -309.294009)
			(xy 533.062703 -309.201852) (xy 533.118473 -309.105258) (xy 533.166869 -309.004765) (xy 533.20762 -308.900937)
			(xy 533.240498 -308.794355) (xy 533.265319 -308.685613) (xy 533.281945 -308.57532) (xy 533.290282 -308.464093)
			(xy 533.29078 -308.408324) (xy 533.29078 10.40003) (xy 533.290257 10.455798) (xy 533.28192 10.567023)
			(xy 533.265294 10.677313) (xy 533.240473 10.786053) (xy 533.207596 10.892634) (xy 533.166845 10.99646)
			(xy 533.11845 11.09695) (xy 533.06268 11.193543) (xy 532.999848 11.285698) (xy 532.930305 11.3729)
			(xy 532.85444 11.454661) (xy 532.772677 11.530525) (xy 532.685474 11.600066) (xy 532.593318 11.662896)
			(xy 532.496724 11.718664) (xy 532.396232 11.767057) (xy 532.292406 11.807806) (xy 532.185824 11.840681)
			(xy 532.077084 11.8655) (xy 531.966793 11.882123) (xy 531.855568 11.890459) (xy 531.7998 11.89101)
			(xy 475.799912 11.89101) (xy 475.744142 11.890489) (xy 475.632915 11.882155) (xy 475.522621 11.865531)
			(xy 475.413878 11.840713) (xy 475.307293 11.807837) (xy 475.203464 11.767088) (xy 475.10297 11.718694)
			(xy 475.006373 11.662926) (xy 474.914214 11.600094) (xy 474.827008 11.530552) (xy 474.745243 11.454687)
			(xy 474.669376 11.372924) (xy 474.599831 11.28572) (xy 474.536997 11.193563) (xy 474.481225 11.096967)
			(xy 474.432829 10.996475) (xy 474.392077 10.892646) (xy 474.359198 10.786063) (xy 474.334376 10.67732)
			(xy 474.31775 10.567027) (xy 474.309413 10.4558) (xy 474.308932 10.40003) (xy 474.308932 7.335466)
			(xy 526.704041 7.335466) (xy 526.704041 7.464606) (xy 526.711991 7.593501) (xy 526.727861 7.721661)
			(xy 526.75159 7.848602) (xy 526.783089 7.973841) (xy 526.822238 8.096904) (xy 526.868889 8.217323)
			(xy 526.922864 8.334642) (xy 526.983959 8.448416) (xy 527.051942 8.558213) (xy 527.126556 8.663616)
			(xy 527.207517 8.764226) (xy 527.294517 8.859661) (xy 527.387228 8.94956) (xy 527.485298 9.033581)
			(xy 527.588353 9.111405) (xy 527.696004 9.182737) (xy 527.807843 9.247307) (xy 527.923444 9.304869)
			(xy 528.042369 9.355206) (xy 528.164168 9.398126) (xy 528.288378 9.433467) (xy 528.414527 9.461094)
			(xy 528.542139 9.480903) (xy 528.670728 9.492819) (xy 528.799806 9.496796) (xy 528.928884 9.492819)
			(xy 529.057473 9.480903) (xy 529.185085 9.461094) (xy 529.311234 9.433467) (xy 529.435444 9.398126)
			(xy 529.557243 9.355206) (xy 529.676168 9.304869) (xy 529.791769 9.247307) (xy 529.903608 9.182737)
			(xy 530.011259 9.111405) (xy 530.114314 9.033581) (xy 530.212384 8.94956) (xy 530.305095 8.859661)
			(xy 530.392095 8.764226) (xy 530.473056 8.663616) (xy 530.54767 8.558213) (xy 530.615653 8.448416)
			(xy 530.676748 8.334642) (xy 530.730723 8.217323) (xy 530.777374 8.096904) (xy 530.816523 7.973841)
			(xy 530.848022 7.848602) (xy 530.871751 7.721661) (xy 530.887621 7.593501) (xy 530.895571 7.464606)
			(xy 530.896068 7.400036) (xy 530.895571 7.335466) (xy 530.887621 7.206571) (xy 530.871751 7.078411)
			(xy 530.848022 6.95147) (xy 530.816523 6.826231) (xy 530.777374 6.703168) (xy 530.730723 6.582749)
			(xy 530.676748 6.46543) (xy 530.615653 6.351656) (xy 530.54767 6.241859) (xy 530.473056 6.136456)
			(xy 530.392095 6.035846) (xy 530.305095 5.940411) (xy 530.212384 5.850512) (xy 530.114314 5.766491)
			(xy 530.011259 5.688667) (xy 529.903608 5.617335) (xy 529.791769 5.552765) (xy 529.676168 5.495203)
			(xy 529.557243 5.444866) (xy 529.435444 5.401946) (xy 529.311234 5.366605) (xy 529.185085 5.338978)
			(xy 529.057473 5.319169) (xy 528.928884 5.307253) (xy 528.799806 5.303277) (xy 528.670728 5.307253)
			(xy 528.542139 5.319169) (xy 528.414527 5.338978) (xy 528.288378 5.366605) (xy 528.164168 5.401946)
			(xy 528.042369 5.444866) (xy 527.923444 5.495203) (xy 527.807843 5.552765) (xy 527.696004 5.617335)
			(xy 527.588353 5.688667) (xy 527.485298 5.766491) (xy 527.387228 5.850512) (xy 527.294517 5.940411)
			(xy 527.207517 6.035846) (xy 527.126556 6.136456) (xy 527.051942 6.241859) (xy 526.983959 6.351656)
			(xy 526.922864 6.46543) (xy 526.868889 6.582749) (xy 526.822238 6.703168) (xy 526.783089 6.826231)
			(xy 526.75159 6.95147) (xy 526.727861 7.078411) (xy 526.711991 7.206571) (xy 526.704041 7.335466)
			(xy 474.308932 7.335466) (xy 474.308932 -12.515904) (xy 476.704141 -12.515904) (xy 476.704141 -12.386764)
			(xy 476.712091 -12.257869) (xy 476.727961 -12.129709) (xy 476.75169 -12.002768) (xy 476.783189 -11.877529)
			(xy 476.822338 -11.754466) (xy 476.868989 -11.634047) (xy 476.922964 -11.516728) (xy 476.984059 -11.402954)
			(xy 477.052042 -11.293157) (xy 477.126656 -11.187754) (xy 477.207617 -11.087144) (xy 477.294617 -10.991709)
			(xy 477.387328 -10.90181) (xy 477.485398 -10.817789) (xy 477.588453 -10.739965) (xy 477.696104 -10.668633)
			(xy 477.807943 -10.604063) (xy 477.923544 -10.546501) (xy 478.042469 -10.496164) (xy 478.164268 -10.453244)
			(xy 478.288478 -10.417903) (xy 478.414627 -10.390276) (xy 478.542239 -10.370467) (xy 478.670828 -10.358551)
			(xy 478.799906 -10.354575) (xy 478.928984 -10.358551) (xy 479.057573 -10.370467) (xy 479.185185 -10.390276)
			(xy 479.311334 -10.417903) (xy 479.435544 -10.453244) (xy 479.557343 -10.496164) (xy 479.676268 -10.546501)
			(xy 479.791869 -10.604063) (xy 479.903708 -10.668633) (xy 480.011359 -10.739965) (xy 480.114414 -10.817789)
			(xy 480.212484 -10.90181) (xy 480.305195 -10.991709) (xy 480.392195 -11.087144) (xy 480.473156 -11.187754)
			(xy 480.54777 -11.293157) (xy 480.615753 -11.402954) (xy 480.676848 -11.516728) (xy 480.730823 -11.634047)
			(xy 480.777474 -11.754466) (xy 480.816623 -11.877529) (xy 480.848122 -12.002768) (xy 480.871851 -12.129709)
			(xy 480.887721 -12.257869) (xy 480.895671 -12.386764) (xy 480.896168 -12.451334) (xy 480.895671 -12.515904)
			(xy 480.887721 -12.644799) (xy 480.871851 -12.772959) (xy 480.848122 -12.8999) (xy 480.816623 -13.025139)
			(xy 480.777474 -13.148202) (xy 480.730823 -13.268621) (xy 480.676848 -13.38594) (xy 480.615753 -13.499714)
			(xy 480.54777 -13.609511) (xy 480.473156 -13.714914) (xy 480.392195 -13.815524) (xy 480.305195 -13.910959)
			(xy 480.212484 -14.000858) (xy 480.114414 -14.084879) (xy 480.011359 -14.162703) (xy 479.903708 -14.234035)
			(xy 479.791869 -14.298605) (xy 479.676268 -14.356167) (xy 479.557343 -14.406504) (xy 479.435544 -14.449424)
			(xy 479.311334 -14.484765) (xy 479.185185 -14.512392) (xy 479.057573 -14.532201) (xy 478.928984 -14.544117)
			(xy 478.799906 -14.548094) (xy 478.670828 -14.544117) (xy 478.542239 -14.532201) (xy 478.414627 -14.512392)
			(xy 478.288478 -14.484765) (xy 478.164268 -14.449424) (xy 478.042469 -14.406504) (xy 477.923544 -14.356167)
			(xy 477.807943 -14.298605) (xy 477.696104 -14.234035) (xy 477.588453 -14.162703) (xy 477.485398 -14.084879)
			(xy 477.387328 -14.000858) (xy 477.294617 -13.910959) (xy 477.207617 -13.815524) (xy 477.126656 -13.714914)
			(xy 477.052042 -13.609511) (xy 476.984059 -13.499714) (xy 476.922964 -13.38594) (xy 476.868989 -13.268621)
			(xy 476.822338 -13.148202) (xy 476.783189 -13.025139) (xy 476.75169 -12.8999) (xy 476.727961 -12.772959)
			(xy 476.712091 -12.644799) (xy 476.704141 -12.515904) (xy 474.308932 -12.515904) (xy 474.308932 -77.67193)
			(xy 474.308458 -77.765117) (xy 474.300759 -77.951331) (xy 474.28537 -78.137067) (xy 474.262318 -78.32201)
			(xy 474.231642 -78.505841) (xy 474.193396 -78.688247) (xy 474.147643 -78.868917) (xy 474.094463 -79.047542)
			(xy 474.033945 -79.223817) (xy 473.966195 -79.397439) (xy 473.891327 -79.568113) (xy 473.809469 -79.735548)
			(xy 473.720761 -79.899456) (xy 473.625355 -80.059558) (xy 473.523414 -80.21558) (xy 473.415112 -80.367256)
			(xy 473.300633 -80.514327) (xy 473.180175 -80.65654) (xy 473.053942 -80.793654) (xy 472.988386 -80.859884)
			(xy 471.245946 -82.602324) (xy 471.208633 -82.640304) (xy 471.138899 -82.72077) (xy 471.07508 -82.806006)
			(xy 471.017504 -82.895576) (xy 470.966464 -82.989025) (xy 470.922218 -83.085876) (xy 470.884993 -83.185636)
			(xy 470.854978 -83.287798) (xy 470.832326 -83.391839) (xy 470.817153 -83.497232) (xy 470.809535 -83.603438)
			(xy 470.809066 -83.656678) (xy 470.809066 -328.137828) (xy 473.204275 -328.137828) (xy 473.204275 -328.008688)
			(xy 473.212225 -327.879793) (xy 473.228095 -327.751633) (xy 473.251824 -327.624692) (xy 473.283323 -327.499453)
			(xy 473.322472 -327.37639) (xy 473.369123 -327.255971) (xy 473.423098 -327.138652) (xy 473.484193 -327.024878)
			(xy 473.552176 -326.915081) (xy 473.62679 -326.809678) (xy 473.707751 -326.709068) (xy 473.794751 -326.613633)
			(xy 473.887462 -326.523734) (xy 473.985532 -326.439713) (xy 474.088587 -326.361889) (xy 474.196238 -326.290557)
			(xy 474.308077 -326.225987) (xy 474.423678 -326.168425) (xy 474.542603 -326.118088) (xy 474.664402 -326.075168)
			(xy 474.788612 -326.039827) (xy 474.914761 -326.0122) (xy 475.042373 -325.992391) (xy 475.170962 -325.980475)
			(xy 475.30004 -325.976499) (xy 475.429118 -325.980475) (xy 475.557707 -325.992391) (xy 475.685319 -326.0122)
			(xy 475.811468 -326.039827) (xy 475.935678 -326.075168) (xy 476.057477 -326.118088) (xy 476.176402 -326.168425)
			(xy 476.292003 -326.225987) (xy 476.403842 -326.290557) (xy 476.511493 -326.361889) (xy 476.614548 -326.439713)
			(xy 476.712618 -326.523734) (xy 476.805329 -326.613633) (xy 476.892329 -326.709068) (xy 476.97329 -326.809678)
			(xy 477.047904 -326.915081) (xy 477.115887 -327.024878) (xy 477.176982 -327.138652) (xy 477.230957 -327.255971)
			(xy 477.277608 -327.37639) (xy 477.316757 -327.499453) (xy 477.348256 -327.624692) (xy 477.371985 -327.751633)
			(xy 477.387855 -327.879793) (xy 477.395805 -328.008688) (xy 477.396302 -328.073258) (xy 477.395805 -328.137828)
			(xy 477.387855 -328.266723) (xy 477.371985 -328.394883) (xy 477.348256 -328.521824) (xy 477.316757 -328.647063)
			(xy 477.277608 -328.770126) (xy 477.230957 -328.890545) (xy 477.176982 -329.007864) (xy 477.115887 -329.121638)
			(xy 477.047904 -329.231435) (xy 476.97329 -329.336838) (xy 476.892329 -329.437448) (xy 476.805329 -329.532883)
			(xy 476.712618 -329.622782) (xy 476.614548 -329.706803) (xy 476.511493 -329.784627) (xy 476.403842 -329.855959)
			(xy 476.292003 -329.920529) (xy 476.176402 -329.978091) (xy 476.057477 -330.028428) (xy 475.935678 -330.071348)
			(xy 475.811468 -330.106689) (xy 475.685319 -330.134316) (xy 475.557707 -330.154125) (xy 475.429118 -330.166041)
			(xy 475.30004 -330.170018) (xy 475.170962 -330.166041) (xy 475.042373 -330.154125) (xy 474.914761 -330.134316)
			(xy 474.788612 -330.106689) (xy 474.664402 -330.071348) (xy 474.542603 -330.028428) (xy 474.423678 -329.978091)
			(xy 474.308077 -329.920529) (xy 474.196238 -329.855959) (xy 474.088587 -329.784627) (xy 473.985532 -329.706803)
			(xy 473.887462 -329.622782) (xy 473.794751 -329.532883) (xy 473.707751 -329.437448) (xy 473.62679 -329.336838)
			(xy 473.552176 -329.231435) (xy 473.484193 -329.121638) (xy 473.423098 -329.007864) (xy 473.369123 -328.890545)
			(xy 473.322472 -328.770126) (xy 473.283323 -328.647063) (xy 473.251824 -328.521824) (xy 473.228095 -328.394883)
			(xy 473.212225 -328.266723) (xy 473.204275 -328.137828) (xy 470.809066 -328.137828) (xy 470.809066 -404.871936)
			(xy 470.808592 -404.965123) (xy 470.800892 -405.151337) (xy 470.785503 -405.337074) (xy 470.762451 -405.522016)
			(xy 470.731776 -405.705847) (xy 470.693529 -405.888254) (xy 470.647776 -406.068924) (xy 470.594596 -406.247549)
			(xy 470.534079 -406.423823) (xy 470.466329 -406.597446) (xy 470.391461 -406.76812) (xy 470.309603 -406.935555)
			(xy 470.220896 -407.099463) (xy 470.12549 -407.259566) (xy 470.02355 -407.415588) (xy 469.915248 -407.567265)
			(xy 469.80077 -407.714335) (xy 469.680312 -407.856549) (xy 469.554079 -407.993664) (xy 469.48852 -408.05989)
			(xy 468.245698 -409.302712) (xy 468.208406 -409.340689) (xy 468.138712 -409.421147) (xy 468.074932 -409.506369)
			(xy 468.017391 -409.595922) (xy 467.966382 -409.68935) (xy 467.922165 -409.786178) (xy 467.884964 -409.885911)
			(xy 467.85497 -409.988044) (xy 467.832334 -410.092055) (xy 467.817172 -410.197416) (xy 467.809562 -410.303589)
			(xy 467.809072 -410.356812) (xy 467.809072 -439.989976) (xy 467.809593 -440.045746) (xy 467.817926 -440.156975)
			(xy 467.834548 -440.26727) (xy 467.859367 -440.376014) (xy 467.892242 -440.4826) (xy 467.93299 -440.586431)
			(xy 467.981383 -440.686926) (xy 468.037152 -440.783525) (xy 468.099983 -440.875685) (xy 468.169525 -440.962893)
			(xy 468.24539 -441.044659) (xy 468.327153 -441.120528) (xy 468.414357 -441.190075) (xy 468.506514 -441.25291)
			(xy 468.60311 -441.308683) (xy 468.703603 -441.357081) (xy 468.807432 -441.397835) (xy 468.914016 -441.430715)
			(xy 469.022759 -441.455538) (xy 469.133053 -441.472166) (xy 469.244282 -441.480505) (xy 469.300052 -441.480956)
			(xy 471.79992 -441.480956) (xy 471.870302 -441.48145) (xy 472.010845 -441.489344) (xy 472.150724 -441.505105)
			(xy 472.2895 -441.528685) (xy 472.426735 -441.560009) (xy 472.561998 -441.598978) (xy 472.694863 -441.64547)
			(xy 472.824912 -441.699339) (xy 472.951736 -441.760414) (xy 473.074936 -441.828505) (xy 473.194125 -441.903396)
			(xy 473.308927 -441.984852) (xy 473.418981 -442.072617) (xy 473.523941 -442.166415) (xy 473.623477 -442.26595)
			(xy 473.717275 -442.37091) (xy 473.80504 -442.480964) (xy 473.886497 -442.595765) (xy 473.961389 -442.714953)
			(xy 474.02948 -442.838153) (xy 474.090556 -442.964977) (xy 474.144426 -443.095026) (xy 474.190918 -443.227891)
			(xy 474.229888 -443.363154) (xy 474.261212 -443.500389) (xy 474.284793 -443.639164) (xy 474.300555 -443.779043)
			(xy 474.308449 -443.919586) (xy 474.308932 -443.989968) (xy 474.308932 -458.092864) (xy 526.704041 -458.092864)
			(xy 526.704041 -457.963724) (xy 526.711991 -457.834829) (xy 526.727861 -457.706669) (xy 526.75159 -457.579728)
			(xy 526.783089 -457.454489) (xy 526.822238 -457.331426) (xy 526.868889 -457.211007) (xy 526.922864 -457.093688)
			(xy 526.983959 -456.979914) (xy 527.051942 -456.870117) (xy 527.126556 -456.764714) (xy 527.207517 -456.664104)
			(xy 527.294517 -456.568669) (xy 527.387228 -456.47877) (xy 527.485298 -456.394749) (xy 527.588353 -456.316925)
			(xy 527.696004 -456.245593) (xy 527.807843 -456.181023) (xy 527.923444 -456.123461) (xy 528.042369 -456.073124)
			(xy 528.164168 -456.030204) (xy 528.288378 -455.994863) (xy 528.414527 -455.967236) (xy 528.542139 -455.947427)
			(xy 528.670728 -455.935511) (xy 528.799806 -455.931535) (xy 528.928884 -455.935511) (xy 529.057473 -455.947427)
			(xy 529.185085 -455.967236) (xy 529.311234 -455.994863) (xy 529.435444 -456.030204) (xy 529.557243 -456.073124)
			(xy 529.676168 -456.123461) (xy 529.791769 -456.181023) (xy 529.903608 -456.245593) (xy 530.011259 -456.316925)
			(xy 530.114314 -456.394749) (xy 530.212384 -456.47877) (xy 530.305095 -456.568669) (xy 530.392095 -456.664104)
			(xy 530.473056 -456.764714) (xy 530.54767 -456.870117) (xy 530.615653 -456.979914) (xy 530.676748 -457.093688)
			(xy 530.730723 -457.211007) (xy 530.777374 -457.331426) (xy 530.816523 -457.454489) (xy 530.848022 -457.579728)
			(xy 530.871751 -457.706669) (xy 530.887621 -457.834829) (xy 530.895571 -457.963724) (xy 530.896068 -458.028294)
			(xy 530.895571 -458.092864) (xy 530.887621 -458.221759) (xy 530.871751 -458.349919) (xy 530.848022 -458.47686)
			(xy 530.816523 -458.602099) (xy 530.777374 -458.725162) (xy 530.730723 -458.845581) (xy 530.676748 -458.9629)
			(xy 530.615653 -459.076674) (xy 530.54767 -459.186471) (xy 530.473056 -459.291874) (xy 530.392095 -459.392484)
			(xy 530.305095 -459.487919) (xy 530.212384 -459.577818) (xy 530.114314 -459.661839) (xy 530.011259 -459.739663)
			(xy 529.903608 -459.810995) (xy 529.791769 -459.875565) (xy 529.676168 -459.933127) (xy 529.557243 -459.983464)
			(xy 529.435444 -460.026384) (xy 529.311234 -460.061725) (xy 529.185085 -460.089352) (xy 529.057473 -460.109161)
			(xy 528.928884 -460.121077) (xy 528.799806 -460.125054) (xy 528.670728 -460.121077) (xy 528.542139 -460.109161)
			(xy 528.414527 -460.089352) (xy 528.288378 -460.061725) (xy 528.164168 -460.026384) (xy 528.042369 -459.983464)
			(xy 527.923444 -459.933127) (xy 527.807843 -459.875565) (xy 527.696004 -459.810995) (xy 527.588353 -459.739663)
			(xy 527.485298 -459.661839) (xy 527.387228 -459.577818) (xy 527.294517 -459.487919) (xy 527.207517 -459.392484)
			(xy 527.126556 -459.291874) (xy 527.051942 -459.186471) (xy 526.983959 -459.076674) (xy 526.922864 -458.9629)
			(xy 526.868889 -458.845581) (xy 526.822238 -458.725162) (xy 526.783089 -458.602099) (xy 526.75159 -458.47686)
			(xy 526.727861 -458.349919) (xy 526.711991 -458.221759) (xy 526.704041 -458.092864) (xy 474.308932 -458.092864)
			(xy 474.308932 -461.028288) (xy 474.30944 -461.084058) (xy 474.317775 -461.195285) (xy 474.334398 -461.305579)
			(xy 474.359217 -461.414322) (xy 474.392093 -461.520906) (xy 474.432843 -461.624735) (xy 474.481238 -461.725228)
			(xy 474.537007 -461.821824) (xy 474.599839 -461.913982) (xy 474.669383 -462.001187) (xy 474.745248 -462.082952)
			(xy 474.827013 -462.158817) (xy 474.914218 -462.228361) (xy 475.006376 -462.291193) (xy 475.102972 -462.346962)
			(xy 475.203465 -462.395357) (xy 475.307294 -462.436107) (xy 475.413878 -462.468983) (xy 475.522621 -462.493802)
			(xy 475.632915 -462.510425) (xy 475.744142 -462.51876) (xy 475.799912 -462.519268)
		)
		(stroke
			(width 0)
			(type solid)
		)
		(fill yes)
		(layer "In3.Cu")
		(net "T1_GND")
	)
	(gr_poly
		(pts
			(xy 255.800098 -33.611058) (xy 255.832245 -33.610555) (xy 255.89599 -33.602163) (xy 255.958093 -33.585522)
			(xy 256.017493 -33.560917) (xy 256.073173 -33.528769) (xy 256.124181 -33.489628) (xy 256.169643 -33.444164)
			(xy 256.208781 -33.393155) (xy 256.240927 -33.337473) (xy 256.265529 -33.278072) (xy 256.282167 -33.215968)
			(xy 256.290557 -33.152223) (xy 256.29108 -33.120076) (xy 256.29108 -11.780012) (xy 256.291564 -11.709629)
			(xy 256.299456 -11.569085) (xy 256.315217 -11.429205) (xy 256.338795 -11.290428) (xy 256.370118 -11.153191)
			(xy 256.409086 -11.017927) (xy 256.455577 -10.885061) (xy 256.509445 -10.75501) (xy 256.570521 -10.628184)
			(xy 256.638611 -10.504983) (xy 256.713502 -10.385793) (xy 256.794959 -10.27099) (xy 256.882724 -10.160934)
			(xy 256.976523 -10.055973) (xy 257.076059 -9.956436) (xy 257.181019 -9.862637) (xy 257.291074 -9.774871)
			(xy 257.405876 -9.693414) (xy 257.525065 -9.618521) (xy 257.648266 -9.55043) (xy 257.775092 -9.489354)
			(xy 257.905142 -9.435484) (xy 258.038008 -9.388992) (xy 258.173272 -9.350023) (xy 258.310508 -9.318699)
			(xy 258.449285 -9.295119) (xy 258.589165 -9.279358) (xy 258.729709 -9.271465) (xy 258.800092 -9.271)
			(xy 383.601976 -9.271) (xy 383.657746 -9.270492) (xy 383.768975 -9.262159) (xy 383.87927 -9.245536)
			(xy 383.988015 -9.220718) (xy 384.094601 -9.187842) (xy 384.198432 -9.147093) (xy 384.298927 -9.098699)
			(xy 384.395525 -9.04293) (xy 384.487685 -8.980099) (xy 384.574892 -8.910555) (xy 384.656659 -8.83469)
			(xy 384.732527 -8.752926) (xy 384.802073 -8.665721) (xy 384.864907 -8.573562) (xy 384.920679 -8.476966)
			(xy 384.969076 -8.376472) (xy 385.009828 -8.272642) (xy 385.042706 -8.166058) (xy 385.067528 -8.057314)
			(xy 385.084154 -7.947019) (xy 385.092491 -7.83579) (xy 385.092956 -7.78002) (xy 385.092956 0.40005)
			(xy 385.093451 0.470432) (xy 385.101346 0.610973) (xy 385.117109 0.750851) (xy 385.14069 0.889625)
			(xy 385.172015 1.026859) (xy 385.210985 1.16212) (xy 385.257478 1.294984) (xy 385.311348 1.425032)
			(xy 385.372424 1.551855) (xy 385.440515 1.675053) (xy 385.515407 1.79424) (xy 385.596863 1.909041)
			(xy 385.684628 2.019094) (xy 385.778426 2.124052) (xy 385.877961 2.223587) (xy 385.98292 2.317383)
			(xy 386.092974 2.405148) (xy 386.207775 2.486603) (xy 386.326962 2.561494) (xy 386.450161 2.629584)
			(xy 386.576985 2.69066) (xy 386.707033 2.744528) (xy 386.839897 2.79102) (xy 386.975158 2.829989)
			(xy 387.112392 2.861313) (xy 387.251166 2.884893) (xy 387.391045 2.900655) (xy 387.531586 2.908549)
			(xy 387.601968 2.909062) (xy 456.202034 2.909062) (xy 456.272416 2.908567) (xy 456.412959 2.900673)
			(xy 456.552838 2.884911) (xy 456.691613 2.861331) (xy 456.828848 2.830006) (xy 456.96411 2.791037)
			(xy 457.096975 2.744544) (xy 457.227024 2.690676) (xy 457.353848 2.6296) (xy 457.477048 2.561509)
			(xy 457.596236 2.486618) (xy 457.711038 2.405161) (xy 457.821092 2.317396) (xy 457.926052 2.223599)
			(xy 458.025588 2.124064) (xy 458.119386 2.019104) (xy 458.207152 1.909051) (xy 458.288609 1.79425)
			(xy 458.363501 1.675062) (xy 458.431592 1.551862) (xy 458.492669 1.425039) (xy 458.546539 1.29499)
			(xy 458.593032 1.162126) (xy 458.632002 1.026863) (xy 458.663327 0.889629) (xy 458.686909 0.750854)
			(xy 458.702672 0.610975) (xy 458.710567 0.470432) (xy 458.711046 0.40005) (xy 458.711046 -4.844596)
			(xy 464.704165 -4.844596) (xy 464.704165 -4.715456) (xy 464.712115 -4.586561) (xy 464.727985 -4.458401)
			(xy 464.751714 -4.33146) (xy 464.783213 -4.206221) (xy 464.822362 -4.083158) (xy 464.869013 -3.962739)
			(xy 464.922988 -3.84542) (xy 464.984083 -3.731646) (xy 465.052066 -3.621849) (xy 465.12668 -3.516446)
			(xy 465.207641 -3.415836) (xy 465.294641 -3.320401) (xy 465.387352 -3.230502) (xy 465.485422 -3.146481)
			(xy 465.588477 -3.068657) (xy 465.696128 -2.997325) (xy 465.807967 -2.932755) (xy 465.923568 -2.875193)
			(xy 466.042493 -2.824856) (xy 466.164292 -2.781936) (xy 466.288502 -2.746595) (xy 466.414651 -2.718968)
			(xy 466.542263 -2.699159) (xy 466.670852 -2.687243) (xy 466.79993 -2.683267) (xy 466.929008 -2.687243)
			(xy 467.057597 -2.699159) (xy 467.185209 -2.718968) (xy 467.311358 -2.746595) (xy 467.435568 -2.781936)
			(xy 467.557367 -2.824856) (xy 467.676292 -2.875193) (xy 467.791893 -2.932755) (xy 467.903732 -2.997325)
			(xy 468.011383 -3.068657) (xy 468.114438 -3.146481) (xy 468.212508 -3.230502) (xy 468.305219 -3.320401)
			(xy 468.392219 -3.415836) (xy 468.47318 -3.516446) (xy 468.547794 -3.621849) (xy 468.615777 -3.731646)
			(xy 468.676872 -3.84542) (xy 468.730847 -3.962739) (xy 468.777498 -4.083158) (xy 468.816647 -4.206221)
			(xy 468.848146 -4.33146) (xy 468.871875 -4.458401) (xy 468.887745 -4.586561) (xy 468.895695 -4.715456)
			(xy 468.896192 -4.780026) (xy 468.895695 -4.844596) (xy 468.887745 -4.973491) (xy 468.871875 -5.101651)
			(xy 468.848146 -5.228592) (xy 468.816647 -5.353831) (xy 468.777498 -5.476894) (xy 468.730847 -5.597313)
			(xy 468.676872 -5.714632) (xy 468.615777 -5.828406) (xy 468.547794 -5.938203) (xy 468.47318 -6.043606)
			(xy 468.392219 -6.144216) (xy 468.305219 -6.239651) (xy 468.212508 -6.32955) (xy 468.114438 -6.413571)
			(xy 468.011383 -6.491395) (xy 467.903732 -6.562727) (xy 467.791893 -6.627297) (xy 467.676292 -6.684859)
			(xy 467.557367 -6.735196) (xy 467.435568 -6.778116) (xy 467.311358 -6.813457) (xy 467.185209 -6.841084)
			(xy 467.057597 -6.860893) (xy 466.929008 -6.872809) (xy 466.79993 -6.876786) (xy 466.670852 -6.872809)
			(xy 466.542263 -6.860893) (xy 466.414651 -6.841084) (xy 466.288502 -6.813457) (xy 466.164292 -6.778116)
			(xy 466.042493 -6.735196) (xy 465.923568 -6.684859) (xy 465.807967 -6.627297) (xy 465.696128 -6.562727)
			(xy 465.588477 -6.491395) (xy 465.485422 -6.413571) (xy 465.387352 -6.32955) (xy 465.294641 -6.239651)
			(xy 465.207641 -6.144216) (xy 465.12668 -6.043606) (xy 465.052066 -5.938203) (xy 464.984083 -5.828406)
			(xy 464.922988 -5.714632) (xy 464.869013 -5.597313) (xy 464.822362 -5.476894) (xy 464.783213 -5.353831)
			(xy 464.751714 -5.228592) (xy 464.727985 -5.101651) (xy 464.712115 -4.973491) (xy 464.704165 -4.844596)
			(xy 458.711046 -4.844596) (xy 458.711046 -7.78002) (xy 458.711555 -7.835789) (xy 458.719892 -7.947014)
			(xy 458.736517 -8.057305) (xy 458.761338 -8.166046) (xy 458.794216 -8.272628) (xy 458.834967 -8.376454)
			(xy 458.883362 -8.476945) (xy 458.939132 -8.573538) (xy 459.001965 -8.665694) (xy 459.071509 -8.752896)
			(xy 459.147375 -8.834658) (xy 459.229138 -8.910521) (xy 459.316343 -8.980062) (xy 459.4085 -9.042892)
			(xy 459.505096 -9.098659) (xy 459.605588 -9.147052) (xy 459.709416 -9.187799) (xy 459.815999 -9.220674)
			(xy 459.92474 -9.245491) (xy 460.035032 -9.262113) (xy 460.146257 -9.270446) (xy 460.202026 -9.271)
			(xy 469.799924 -9.271) (xy 469.855693 -9.270478) (xy 469.966918 -9.262141) (xy 470.07721 -9.245516)
			(xy 470.18595 -9.220695) (xy 470.292532 -9.187817) (xy 470.396359 -9.147067) (xy 470.49685 -9.098672)
			(xy 470.593444 -9.042903) (xy 470.685601 -8.980071) (xy 470.772804 -8.910528) (xy 470.854566 -8.834664)
			(xy 470.930431 -8.752901) (xy 470.999974 -8.665697) (xy 471.062805 -8.573541) (xy 471.118574 -8.476947)
			(xy 471.166969 -8.376455) (xy 471.207719 -8.272628) (xy 471.240596 -8.166046) (xy 471.265416 -8.057306)
			(xy 471.282041 -7.947014) (xy 471.290378 -7.835789) (xy 471.290904 -7.78002) (xy 471.290904 10.40003)
			(xy 471.290381 10.455799) (xy 471.282044 10.567024) (xy 471.265419 10.677315) (xy 471.240598 10.786055)
			(xy 471.20772 10.892637) (xy 471.16697 10.996464) (xy 471.118574 11.096955) (xy 471.062805 11.193548)
			(xy 470.999973 11.285705) (xy 470.930431 11.372908) (xy 470.854566 11.45467) (xy 470.772803 11.530534)
			(xy 470.6856 11.600077) (xy 470.593443 11.662908) (xy 470.49685 11.718677) (xy 470.396358 11.767072)
			(xy 470.292531 11.807822) (xy 470.18595 11.840699) (xy 470.077209 11.86552) (xy 469.966918 11.882145)
			(xy 469.855693 11.890482) (xy 469.799924 11.89101) (xy 1.999996 11.89101) (xy 1.944227 11.890488)
			(xy 1.833001 11.882153) (xy 1.722709 11.865529) (xy 1.613968 11.840709) (xy 1.507385 11.807832) (xy 1.403558 11.767083)
			(xy 1.303066 11.718688) (xy 1.206471 11.662919) (xy 1.114314 11.600087) (xy 1.027111 11.530545) (xy 0.945348 11.454679)
			(xy 0.869483 11.372916) (xy 0.79994 11.285712) (xy 0.737109 11.193555) (xy 0.68134 11.096961) (xy 0.632946 10.996469)
			(xy 0.592196 10.892641) (xy 0.55932 10.786058) (xy 0.534501 10.677317) (xy 0.517877 10.567025) (xy 0.509541 10.455799)
			(xy 0.509016 10.40003) (xy 0.509016 9.916973) (xy 385.651997 9.916973) (xy 385.651997 10.002723)
			(xy 385.659909 10.088106) (xy 385.675665 10.172396) (xy 385.699132 10.254872) (xy 385.730108 10.334831)
			(xy 385.76833 10.411591) (xy 385.813471 10.484497) (xy 385.865147 10.552926) (xy 385.922916 10.616296)
			(xy 385.986286 10.674065) (xy 386.054715 10.725741) (xy 386.127621 10.770882) (xy 386.204381 10.809104)
			(xy 386.28434 10.84008) (xy 386.366816 10.863547) (xy 386.451106 10.879303) (xy 386.536489 10.887215)
			(xy 386.622239 10.887215) (xy 386.707622 10.879303) (xy 386.791912 10.863547) (xy 386.874388 10.84008)
			(xy 386.954347 10.809104) (xy 387.031107 10.770882) (xy 387.104013 10.725741) (xy 387.172442 10.674065)
			(xy 387.235812 10.616296) (xy 387.293581 10.552926) (xy 387.345257 10.484497) (xy 387.390398 10.411591)
			(xy 387.42862 10.334831) (xy 387.459596 10.254872) (xy 387.483063 10.172396) (xy 387.498819 10.088106)
			(xy 387.506731 10.002723) (xy 387.507226 9.959848) (xy 387.506731 9.916973) (xy 392.001997 9.916973)
			(xy 392.001997 10.002723) (xy 392.009909 10.088106) (xy 392.025665 10.172396) (xy 392.049132 10.254872)
			(xy 392.080108 10.334831) (xy 392.11833 10.411591) (xy 392.163471 10.484497) (xy 392.215147 10.552926)
			(xy 392.272916 10.616296) (xy 392.336286 10.674065) (xy 392.404715 10.725741) (xy 392.477621 10.770882)
			(xy 392.554381 10.809104) (xy 392.63434 10.84008) (xy 392.716816 10.863547) (xy 392.801106 10.879303)
			(xy 392.886489 10.887215) (xy 392.972239 10.887215) (xy 393.057622 10.879303) (xy 393.141912 10.863547)
			(xy 393.224388 10.84008) (xy 393.304347 10.809104) (xy 393.381107 10.770882) (xy 393.454013 10.725741)
			(xy 393.522442 10.674065) (xy 393.585812 10.616296) (xy 393.643581 10.552926) (xy 393.695257 10.484497)
			(xy 393.740398 10.411591) (xy 393.77862 10.334831) (xy 393.809596 10.254872) (xy 393.833063 10.172396)
			(xy 393.848819 10.088106) (xy 393.856731 10.002723) (xy 393.857226 9.959848) (xy 393.856731 9.916973)
			(xy 436.390783 9.916973) (xy 436.390783 10.002723) (xy 436.398695 10.088106) (xy 436.414451 10.172396)
			(xy 436.437918 10.254872) (xy 436.468894 10.334831) (xy 436.507116 10.411591) (xy 436.552257 10.484497)
			(xy 436.603933 10.552926) (xy 436.661702 10.616296) (xy 436.725072 10.674065) (xy 436.793501 10.725741)
			(xy 436.866407 10.770882) (xy 436.943167 10.809104) (xy 437.023126 10.84008) (xy 437.105602 10.863547)
			(xy 437.189892 10.879303) (xy 437.275275 10.887215) (xy 437.361025 10.887215) (xy 437.446408 10.879303)
			(xy 437.530698 10.863547) (xy 437.613174 10.84008) (xy 437.693133 10.809104) (xy 437.769893 10.770882)
			(xy 437.842799 10.725741) (xy 437.911228 10.674065) (xy 437.974598 10.616296) (xy 438.032367 10.552926)
			(xy 438.084043 10.484497) (xy 438.129184 10.411591) (xy 438.167406 10.334831) (xy 438.198382 10.254872)
			(xy 438.221849 10.172396) (xy 438.237605 10.088106) (xy 438.245517 10.002723) (xy 438.246012 9.959848)
			(xy 438.245517 9.916973) (xy 442.740783 9.916973) (xy 442.740783 10.002723) (xy 442.748695 10.088106)
			(xy 442.764451 10.172396) (xy 442.787918 10.254872) (xy 442.818894 10.334831) (xy 442.857116 10.411591)
			(xy 442.902257 10.484497) (xy 442.953933 10.552926) (xy 443.011702 10.616296) (xy 443.075072 10.674065)
			(xy 443.143501 10.725741) (xy 443.216407 10.770882) (xy 443.293167 10.809104) (xy 443.373126 10.84008)
			(xy 443.455602 10.863547) (xy 443.539892 10.879303) (xy 443.625275 10.887215) (xy 443.711025 10.887215)
			(xy 443.796408 10.879303) (xy 443.880698 10.863547) (xy 443.963174 10.84008) (xy 444.043133 10.809104)
			(xy 444.119893 10.770882) (xy 444.192799 10.725741) (xy 444.261228 10.674065) (xy 444.324598 10.616296)
			(xy 444.382367 10.552926) (xy 444.434043 10.484497) (xy 444.479184 10.411591) (xy 444.517406 10.334831)
			(xy 444.548382 10.254872) (xy 444.571849 10.172396) (xy 444.587605 10.088106) (xy 444.595517 10.002723)
			(xy 444.596012 9.959848) (xy 444.595517 9.916973) (xy 444.587605 9.83159) (xy 444.571849 9.7473)
			(xy 444.548382 9.664824) (xy 444.517406 9.584865) (xy 444.479184 9.508105) (xy 444.434043 9.435199)
			(xy 444.382367 9.36677) (xy 444.324598 9.3034) (xy 444.261228 9.245631) (xy 444.192799 9.193955)
			(xy 444.119893 9.148814) (xy 444.043133 9.110592) (xy 443.963174 9.079616) (xy 443.880698 9.056149)
			(xy 443.796408 9.040393) (xy 443.711025 9.032481) (xy 443.625275 9.032481) (xy 443.539892 9.040393)
			(xy 443.455602 9.056149) (xy 443.373126 9.079616) (xy 443.293167 9.110592) (xy 443.216407 9.148814)
			(xy 443.143501 9.193955) (xy 443.075072 9.245631) (xy 443.011702 9.3034) (xy 442.953933 9.36677)
			(xy 442.902257 9.435199) (xy 442.857116 9.508105) (xy 442.818894 9.584865) (xy 442.787918 9.664824)
			(xy 442.764451 9.7473) (xy 442.748695 9.83159) (xy 442.740783 9.916973) (xy 438.245517 9.916973)
			(xy 438.237605 9.83159) (xy 438.221849 9.7473) (xy 438.198382 9.664824) (xy 438.167406 9.584865)
			(xy 438.129184 9.508105) (xy 438.084043 9.435199) (xy 438.032367 9.36677) (xy 437.974598 9.3034)
			(xy 437.911228 9.245631) (xy 437.842799 9.193955) (xy 437.769893 9.148814) (xy 437.693133 9.110592)
			(xy 437.613174 9.079616) (xy 437.530698 9.056149) (xy 437.446408 9.040393) (xy 437.361025 9.032481)
			(xy 437.275275 9.032481) (xy 437.189892 9.040393) (xy 437.105602 9.056149) (xy 437.023126 9.079616)
			(xy 436.943167 9.110592) (xy 436.866407 9.148814) (xy 436.793501 9.193955) (xy 436.725072 9.245631)
			(xy 436.661702 9.3034) (xy 436.603933 9.36677) (xy 436.552257 9.435199) (xy 436.507116 9.508105)
			(xy 436.468894 9.584865) (xy 436.437918 9.664824) (xy 436.414451 9.7473) (xy 436.398695 9.83159)
			(xy 436.390783 9.916973) (xy 393.856731 9.916973) (xy 393.848819 9.83159) (xy 393.833063 9.7473)
			(xy 393.809596 9.664824) (xy 393.77862 9.584865) (xy 393.740398 9.508105) (xy 393.695257 9.435199)
			(xy 393.643581 9.36677) (xy 393.585812 9.3034) (xy 393.522442 9.245631) (xy 393.454013 9.193955)
			(xy 393.381107 9.148814) (xy 393.304347 9.110592) (xy 393.224388 9.079616) (xy 393.141912 9.056149)
			(xy 393.057622 9.040393) (xy 392.972239 9.032481) (xy 392.886489 9.032481) (xy 392.801106 9.040393)
			(xy 392.716816 9.056149) (xy 392.63434 9.079616) (xy 392.554381 9.110592) (xy 392.477621 9.148814)
			(xy 392.404715 9.193955) (xy 392.336286 9.245631) (xy 392.272916 9.3034) (xy 392.215147 9.36677)
			(xy 392.163471 9.435199) (xy 392.11833 9.508105) (xy 392.080108 9.584865) (xy 392.049132 9.664824)
			(xy 392.025665 9.7473) (xy 392.009909 9.83159) (xy 392.001997 9.916973) (xy 387.506731 9.916973)
			(xy 387.498819 9.83159) (xy 387.483063 9.7473) (xy 387.459596 9.664824) (xy 387.42862 9.584865) (xy 387.390398 9.508105)
			(xy 387.345257 9.435199) (xy 387.293581 9.36677) (xy 387.235812 9.3034) (xy 387.172442 9.245631)
			(xy 387.104013 9.193955) (xy 387.031107 9.148814) (xy 386.954347 9.110592) (xy 386.874388 9.079616)
			(xy 386.791912 9.056149) (xy 386.707622 9.040393) (xy 386.622239 9.032481) (xy 386.536489 9.032481)
			(xy 386.451106 9.040393) (xy 386.366816 9.056149) (xy 386.28434 9.079616) (xy 386.204381 9.110592)
			(xy 386.127621 9.148814) (xy 386.054715 9.193955) (xy 385.986286 9.245631) (xy 385.922916 9.3034)
			(xy 385.865147 9.36677) (xy 385.813471 9.435199) (xy 385.76833 9.508105) (xy 385.730108 9.584865)
			(xy 385.699132 9.664824) (xy 385.675665 9.7473) (xy 385.659909 9.83159) (xy 385.651997 9.916973)
			(xy 0.509016 9.916973) (xy 0.509016 7.335466) (xy 2.904225 7.335466) (xy 2.904225 7.464606) (xy 2.912175 7.593501)
			(xy 2.928045 7.721661) (xy 2.951774 7.848602) (xy 2.983273 7.973841) (xy 3.022422 8.096904) (xy 3.069073 8.217323)
			(xy 3.123048 8.334642) (xy 3.184143 8.448416) (xy 3.252126 8.558213) (xy 3.32674 8.663616) (xy 3.407701 8.764226)
			(xy 3.494701 8.859661) (xy 3.587412 8.94956) (xy 3.685482 9.033581) (xy 3.788537 9.111405) (xy 3.896188 9.182737)
			(xy 4.008027 9.247307) (xy 4.123628 9.304869) (xy 4.242553 9.355206) (xy 4.364352 9.398126) (xy 4.488562 9.433467)
			(xy 4.614711 9.461094) (xy 4.742323 9.480903) (xy 4.870912 9.492819) (xy 4.99999 9.496796) (xy 5.129068 9.492819)
			(xy 5.257657 9.480903) (xy 5.385269 9.461094) (xy 5.511418 9.433467) (xy 5.635628 9.398126) (xy 5.757427 9.355206)
			(xy 5.876352 9.304869) (xy 5.991953 9.247307) (xy 6.103792 9.182737) (xy 6.211443 9.111405) (xy 6.314498 9.033581)
			(xy 6.412568 8.94956) (xy 6.505279 8.859661) (xy 6.51416 8.849919) (xy 208.661241 8.849919) (xy 208.661241 8.935669)
			(xy 208.669153 9.021052) (xy 208.684909 9.105342) (xy 208.708376 9.187818) (xy 208.739352 9.267777)
			(xy 208.777574 9.344537) (xy 208.822715 9.417443) (xy 208.874391 9.485872) (xy 208.93216 9.549242)
			(xy 208.99553 9.607011) (xy 209.063959 9.658687) (xy 209.136865 9.703828) (xy 209.213625 9.74205)
			(xy 209.293584 9.773026) (xy 209.37606 9.796493) (xy 209.46035 9.812249) (xy 209.545733 9.820161)
			(xy 209.631483 9.820161) (xy 209.716866 9.812249) (xy 209.801156 9.796493) (xy 209.883632 9.773026)
			(xy 209.963591 9.74205) (xy 210.040351 9.703828) (xy 210.113257 9.658687) (xy 210.181686 9.607011)
			(xy 210.245056 9.549242) (xy 210.302825 9.485872) (xy 210.354501 9.417443) (xy 210.399642 9.344537)
			(xy 210.437864 9.267777) (xy 210.46884 9.187818) (xy 210.492307 9.105342) (xy 210.508063 9.021052)
			(xy 210.515975 8.935669) (xy 210.51647 8.892794) (xy 210.515975 8.849919) (xy 215.011241 8.849919)
			(xy 215.011241 8.935669) (xy 215.019153 9.021052) (xy 215.034909 9.105342) (xy 215.058376 9.187818)
			(xy 215.089352 9.267777) (xy 215.127574 9.344537) (xy 215.172715 9.417443) (xy 215.224391 9.485872)
			(xy 215.28216 9.549242) (xy 215.34553 9.607011) (xy 215.413959 9.658687) (xy 215.486865 9.703828)
			(xy 215.563625 9.74205) (xy 215.643584 9.773026) (xy 215.72606 9.796493) (xy 215.81035 9.812249)
			(xy 215.895733 9.820161) (xy 215.981483 9.820161) (xy 216.066866 9.812249) (xy 216.151156 9.796493)
			(xy 216.233632 9.773026) (xy 216.313591 9.74205) (xy 216.390351 9.703828) (xy 216.463257 9.658687)
			(xy 216.531686 9.607011) (xy 216.595056 9.549242) (xy 216.652825 9.485872) (xy 216.704501 9.417443)
			(xy 216.749642 9.344537) (xy 216.787864 9.267777) (xy 216.81884 9.187818) (xy 216.842307 9.105342)
			(xy 216.858063 9.021052) (xy 216.865975 8.935669) (xy 216.86647 8.892794) (xy 216.865975 8.849919)
			(xy 296.143921 8.849919) (xy 296.143921 8.935669) (xy 296.151833 9.021052) (xy 296.167589 9.105342)
			(xy 296.191056 9.187818) (xy 296.222032 9.267777) (xy 296.260254 9.344537) (xy 296.305395 9.417443)
			(xy 296.357071 9.485872) (xy 296.41484 9.549242) (xy 296.47821 9.607011) (xy 296.546639 9.658687)
			(xy 296.619545 9.703828) (xy 296.696305 9.74205) (xy 296.776264 9.773026) (xy 296.85874 9.796493)
			(xy 296.94303 9.812249) (xy 297.028413 9.820161) (xy 297.114163 9.820161) (xy 297.199546 9.812249)
			(xy 297.283836 9.796493) (xy 297.366312 9.773026) (xy 297.446271 9.74205) (xy 297.523031 9.703828)
			(xy 297.595937 9.658687) (xy 297.664366 9.607011) (xy 297.727736 9.549242) (xy 297.785505 9.485872)
			(xy 297.837181 9.417443) (xy 297.882322 9.344537) (xy 297.920544 9.267777) (xy 297.95152 9.187818)
			(xy 297.974987 9.105342) (xy 297.990743 9.021052) (xy 297.998655 8.935669) (xy 297.99915 8.892794)
			(xy 297.998655 8.849919) (xy 302.493921 8.849919) (xy 302.493921 8.935669) (xy 302.501833 9.021052)
			(xy 302.517589 9.105342) (xy 302.541056 9.187818) (xy 302.572032 9.267777) (xy 302.610254 9.344537)
			(xy 302.655395 9.417443) (xy 302.707071 9.485872) (xy 302.76484 9.549242) (xy 302.82821 9.607011)
			(xy 302.896639 9.658687) (xy 302.969545 9.703828) (xy 303.046305 9.74205) (xy 303.126264 9.773026)
			(xy 303.20874 9.796493) (xy 303.29303 9.812249) (xy 303.378413 9.820161) (xy 303.464163 9.820161)
			(xy 303.549546 9.812249) (xy 303.633836 9.796493) (xy 303.716312 9.773026) (xy 303.796271 9.74205)
			(xy 303.873031 9.703828) (xy 303.945937 9.658687) (xy 304.014366 9.607011) (xy 304.077736 9.549242)
			(xy 304.135505 9.485872) (xy 304.187181 9.417443) (xy 304.232322 9.344537) (xy 304.270544 9.267777)
			(xy 304.30152 9.187818) (xy 304.324987 9.105342) (xy 304.340743 9.021052) (xy 304.348655 8.935669)
			(xy 304.34915 8.892794) (xy 304.348655 8.849919) (xy 311.155321 8.849919) (xy 311.155321 8.935669)
			(xy 311.163233 9.021052) (xy 311.178989 9.105342) (xy 311.202456 9.187818) (xy 311.233432 9.267777)
			(xy 311.271654 9.344537) (xy 311.316795 9.417443) (xy 311.368471 9.485872) (xy 311.42624 9.549242)
			(xy 311.48961 9.607011) (xy 311.558039 9.658687) (xy 311.630945 9.703828) (xy 311.707705 9.74205)
			(xy 311.787664 9.773026) (xy 311.87014 9.796493) (xy 311.95443 9.812249) (xy 312.039813 9.820161)
			(xy 312.125563 9.820161) (xy 312.210946 9.812249) (xy 312.295236 9.796493) (xy 312.377712 9.773026)
			(xy 312.457671 9.74205) (xy 312.534431 9.703828) (xy 312.607337 9.658687) (xy 312.675766 9.607011)
			(xy 312.739136 9.549242) (xy 312.796905 9.485872) (xy 312.848581 9.417443) (xy 312.893722 9.344537)
			(xy 312.931944 9.267777) (xy 312.96292 9.187818) (xy 312.986387 9.105342) (xy 313.002143 9.021052)
			(xy 313.010055 8.935669) (xy 313.01055 8.892794) (xy 313.010055 8.849919) (xy 317.505321 8.849919)
			(xy 317.505321 8.935669) (xy 317.513233 9.021052) (xy 317.528989 9.105342) (xy 317.552456 9.187818)
			(xy 317.583432 9.267777) (xy 317.621654 9.344537) (xy 317.666795 9.417443) (xy 317.718471 9.485872)
			(xy 317.77624 9.549242) (xy 317.83961 9.607011) (xy 317.908039 9.658687) (xy 317.980945 9.703828)
			(xy 318.057705 9.74205) (xy 318.137664 9.773026) (xy 318.22014 9.796493) (xy 318.30443 9.812249)
			(xy 318.389813 9.820161) (xy 318.475563 9.820161) (xy 318.560946 9.812249) (xy 318.645236 9.796493)
			(xy 318.727712 9.773026) (xy 318.807671 9.74205) (xy 318.884431 9.703828) (xy 318.957337 9.658687)
			(xy 319.025766 9.607011) (xy 319.089136 9.549242) (xy 319.146905 9.485872) (xy 319.198581 9.417443)
			(xy 319.243722 9.344537) (xy 319.281944 9.267777) (xy 319.31292 9.187818) (xy 319.336387 9.105342)
			(xy 319.352143 9.021052) (xy 319.360055 8.935669) (xy 319.36055 8.892794) (xy 319.360055 8.849919)
			(xy 361.894107 8.849919) (xy 361.894107 8.935669) (xy 361.902019 9.021052) (xy 361.917775 9.105342)
			(xy 361.941242 9.187818) (xy 361.972218 9.267777) (xy 362.01044 9.344537) (xy 362.055581 9.417443)
			(xy 362.107257 9.485872) (xy 362.165026 9.549242) (xy 362.228396 9.607011) (xy 362.296825 9.658687)
			(xy 362.369731 9.703828) (xy 362.446491 9.74205) (xy 362.52645 9.773026) (xy 362.608926 9.796493)
			(xy 362.693216 9.812249) (xy 362.778599 9.820161) (xy 362.864349 9.820161) (xy 362.949732 9.812249)
			(xy 363.034022 9.796493) (xy 363.116498 9.773026) (xy 363.196457 9.74205) (xy 363.273217 9.703828)
			(xy 363.346123 9.658687) (xy 363.414552 9.607011) (xy 363.477922 9.549242) (xy 363.535691 9.485872)
			(xy 363.587367 9.417443) (xy 363.632508 9.344537) (xy 363.67073 9.267777) (xy 363.701706 9.187818)
			(xy 363.725173 9.105342) (xy 363.740929 9.021052) (xy 363.748841 8.935669) (xy 363.749336 8.892794)
			(xy 363.748841 8.849919) (xy 368.244107 8.849919) (xy 368.244107 8.935669) (xy 368.252019 9.021052)
			(xy 368.267775 9.105342) (xy 368.291242 9.187818) (xy 368.322218 9.267777) (xy 368.36044 9.344537)
			(xy 368.405581 9.417443) (xy 368.457257 9.485872) (xy 368.515026 9.549242) (xy 368.578396 9.607011)
			(xy 368.646825 9.658687) (xy 368.719731 9.703828) (xy 368.796491 9.74205) (xy 368.87645 9.773026)
			(xy 368.958926 9.796493) (xy 369.043216 9.812249) (xy 369.128599 9.820161) (xy 369.214349 9.820161)
			(xy 369.299732 9.812249) (xy 369.384022 9.796493) (xy 369.466498 9.773026) (xy 369.546457 9.74205)
			(xy 369.623217 9.703828) (xy 369.696123 9.658687) (xy 369.764552 9.607011) (xy 369.827922 9.549242)
			(xy 369.885691 9.485872) (xy 369.937367 9.417443) (xy 369.982508 9.344537) (xy 370.02073 9.267777)
			(xy 370.051706 9.187818) (xy 370.075173 9.105342) (xy 370.090929 9.021052) (xy 370.098841 8.935669)
			(xy 370.099336 8.892794) (xy 370.098841 8.849919) (xy 370.090929 8.764536) (xy 370.075173 8.680246)
			(xy 370.051706 8.59777) (xy 370.02073 8.517811) (xy 369.982508 8.441051) (xy 369.937367 8.368145)
			(xy 369.885691 8.299716) (xy 369.827922 8.236346) (xy 369.764552 8.178577) (xy 369.696123 8.126901)
			(xy 369.623217 8.08176) (xy 369.546457 8.043538) (xy 369.466498 8.012562) (xy 369.384022 7.989095)
			(xy 369.299732 7.973339) (xy 369.214349 7.965427) (xy 369.128599 7.965427) (xy 369.043216 7.973339)
			(xy 368.958926 7.989095) (xy 368.87645 8.012562) (xy 368.796491 8.043538) (xy 368.719731 8.08176)
			(xy 368.646825 8.126901) (xy 368.578396 8.178577) (xy 368.515026 8.236346) (xy 368.457257 8.299716)
			(xy 368.405581 8.368145) (xy 368.36044 8.441051) (xy 368.322218 8.517811) (xy 368.291242 8.59777)
			(xy 368.267775 8.680246) (xy 368.252019 8.764536) (xy 368.244107 8.849919) (xy 363.748841 8.849919)
			(xy 363.740929 8.764536) (xy 363.725173 8.680246) (xy 363.701706 8.59777) (xy 363.67073 8.517811)
			(xy 363.632508 8.441051) (xy 363.587367 8.368145) (xy 363.535691 8.299716) (xy 363.477922 8.236346)
			(xy 363.414552 8.178577) (xy 363.346123 8.126901) (xy 363.273217 8.08176) (xy 363.196457 8.043538)
			(xy 363.116498 8.012562) (xy 363.034022 7.989095) (xy 362.949732 7.973339) (xy 362.864349 7.965427)
			(xy 362.778599 7.965427) (xy 362.693216 7.973339) (xy 362.608926 7.989095) (xy 362.52645 8.012562)
			(xy 362.446491 8.043538) (xy 362.369731 8.08176) (xy 362.296825 8.126901) (xy 362.228396 8.178577)
			(xy 362.165026 8.236346) (xy 362.107257 8.299716) (xy 362.055581 8.368145) (xy 362.01044 8.441051)
			(xy 361.972218 8.517811) (xy 361.941242 8.59777) (xy 361.917775 8.680246) (xy 361.902019 8.764536)
			(xy 361.894107 8.849919) (xy 319.360055 8.849919) (xy 319.352143 8.764536) (xy 319.336387 8.680246)
			(xy 319.31292 8.59777) (xy 319.281944 8.517811) (xy 319.243722 8.441051) (xy 319.198581 8.368145)
			(xy 319.146905 8.299716) (xy 319.089136 8.236346) (xy 319.025766 8.178577) (xy 318.957337 8.126901)
			(xy 318.884431 8.08176) (xy 318.807671 8.043538) (xy 318.727712 8.012562) (xy 318.645236 7.989095)
			(xy 318.560946 7.973339) (xy 318.475563 7.965427) (xy 318.389813 7.965427) (xy 318.30443 7.973339)
			(xy 318.22014 7.989095) (xy 318.137664 8.012562) (xy 318.057705 8.043538) (xy 317.980945 8.08176)
			(xy 317.908039 8.126901) (xy 317.83961 8.178577) (xy 317.77624 8.236346) (xy 317.718471 8.299716)
			(xy 317.666795 8.368145) (xy 317.621654 8.441051) (xy 317.583432 8.517811) (xy 317.552456 8.59777)
			(xy 317.528989 8.680246) (xy 317.513233 8.764536) (xy 317.505321 8.849919) (xy 313.010055 8.849919)
			(xy 313.002143 8.764536) (xy 312.986387 8.680246) (xy 312.96292 8.59777) (xy 312.931944 8.517811)
			(xy 312.893722 8.441051) (xy 312.848581 8.368145) (xy 312.796905 8.299716) (xy 312.739136 8.236346)
			(xy 312.675766 8.178577) (xy 312.607337 8.126901) (xy 312.534431 8.08176) (xy 312.457671 8.043538)
			(xy 312.377712 8.012562) (xy 312.295236 7.989095) (xy 312.210946 7.973339) (xy 312.125563 7.965427)
			(xy 312.039813 7.965427) (xy 311.95443 7.973339) (xy 311.87014 7.989095) (xy 311.787664 8.012562)
			(xy 311.707705 8.043538) (xy 311.630945 8.08176) (xy 311.558039 8.126901) (xy 311.48961 8.178577)
			(xy 311.42624 8.236346) (xy 311.368471 8.299716) (xy 311.316795 8.368145) (xy 311.271654 8.441051)
			(xy 311.233432 8.517811) (xy 311.202456 8.59777) (xy 311.178989 8.680246) (xy 311.163233 8.764536)
			(xy 311.155321 8.849919) (xy 304.348655 8.849919) (xy 304.340743 8.764536) (xy 304.324987 8.680246)
			(xy 304.30152 8.59777) (xy 304.270544 8.517811) (xy 304.232322 8.441051) (xy 304.187181 8.368145)
			(xy 304.135505 8.299716) (xy 304.077736 8.236346) (xy 304.014366 8.178577) (xy 303.945937 8.126901)
			(xy 303.873031 8.08176) (xy 303.796271 8.043538) (xy 303.716312 8.012562) (xy 303.633836 7.989095)
			(xy 303.549546 7.973339) (xy 303.464163 7.965427) (xy 303.378413 7.965427) (xy 303.29303 7.973339)
			(xy 303.20874 7.989095) (xy 303.126264 8.012562) (xy 303.046305 8.043538) (xy 302.969545 8.08176)
			(xy 302.896639 8.126901) (xy 302.82821 8.178577) (xy 302.76484 8.236346) (xy 302.707071 8.299716)
			(xy 302.655395 8.368145) (xy 302.610254 8.441051) (xy 302.572032 8.517811) (xy 302.541056 8.59777)
			(xy 302.517589 8.680246) (xy 302.501833 8.764536) (xy 302.493921 8.849919) (xy 297.998655 8.849919)
			(xy 297.990743 8.764536) (xy 297.974987 8.680246) (xy 297.95152 8.59777) (xy 297.920544 8.517811)
			(xy 297.882322 8.441051) (xy 297.837181 8.368145) (xy 297.785505 8.299716) (xy 297.727736 8.236346)
			(xy 297.664366 8.178577) (xy 297.595937 8.126901) (xy 297.523031 8.08176) (xy 297.446271 8.043538)
			(xy 297.366312 8.012562) (xy 297.283836 7.989095) (xy 297.199546 7.973339) (xy 297.114163 7.965427)
			(xy 297.028413 7.965427) (xy 296.94303 7.973339) (xy 296.85874 7.989095) (xy 296.776264 8.012562)
			(xy 296.696305 8.043538) (xy 296.619545 8.08176) (xy 296.546639 8.126901) (xy 296.47821 8.178577)
			(xy 296.41484 8.236346) (xy 296.357071 8.299716) (xy 296.305395 8.368145) (xy 296.260254 8.441051)
			(xy 296.222032 8.517811) (xy 296.191056 8.59777) (xy 296.167589 8.680246) (xy 296.151833 8.764536)
			(xy 296.143921 8.849919) (xy 216.865975 8.849919) (xy 216.858063 8.764536) (xy 216.842307 8.680246)
			(xy 216.81884 8.59777) (xy 216.787864 8.517811) (xy 216.749642 8.441051) (xy 216.704501 8.368145)
			(xy 216.652825 8.299716) (xy 216.595056 8.236346) (xy 216.531686 8.178577) (xy 216.463257 8.126901)
			(xy 216.390351 8.08176) (xy 216.313591 8.043538) (xy 216.233632 8.012562) (xy 216.151156 7.989095)
			(xy 216.066866 7.973339) (xy 215.981483 7.965427) (xy 215.895733 7.965427) (xy 215.81035 7.973339)
			(xy 215.72606 7.989095) (xy 215.643584 8.012562) (xy 215.563625 8.043538) (xy 215.486865 8.08176)
			(xy 215.413959 8.126901) (xy 215.34553 8.178577) (xy 215.28216 8.236346) (xy 215.224391 8.299716)
			(xy 215.172715 8.368145) (xy 215.127574 8.441051) (xy 215.089352 8.517811) (xy 215.058376 8.59777)
			(xy 215.034909 8.680246) (xy 215.019153 8.764536) (xy 215.011241 8.849919) (xy 210.515975 8.849919)
			(xy 210.508063 8.764536) (xy 210.492307 8.680246) (xy 210.46884 8.59777) (xy 210.437864 8.517811)
			(xy 210.399642 8.441051) (xy 210.354501 8.368145) (xy 210.302825 8.299716) (xy 210.245056 8.236346)
			(xy 210.181686 8.178577) (xy 210.113257 8.126901) (xy 210.040351 8.08176) (xy 209.963591 8.043538)
			(xy 209.883632 8.012562) (xy 209.801156 7.989095) (xy 209.716866 7.973339) (xy 209.631483 7.965427)
			(xy 209.545733 7.965427) (xy 209.46035 7.973339) (xy 209.37606 7.989095) (xy 209.293584 8.012562)
			(xy 209.213625 8.043538) (xy 209.136865 8.08176) (xy 209.063959 8.126901) (xy 208.99553 8.178577)
			(xy 208.93216 8.236346) (xy 208.874391 8.299716) (xy 208.822715 8.368145) (xy 208.777574 8.441051)
			(xy 208.739352 8.517811) (xy 208.708376 8.59777) (xy 208.684909 8.680246) (xy 208.669153 8.764536)
			(xy 208.661241 8.849919) (xy 6.51416 8.849919) (xy 6.592279 8.764226) (xy 6.67324 8.663616) (xy 6.747854 8.558213)
			(xy 6.815837 8.448416) (xy 6.876932 8.334642) (xy 6.930907 8.217323) (xy 6.977558 8.096904) (xy 7.016707 7.973841)
			(xy 7.048206 7.848602) (xy 7.071935 7.721661) (xy 7.087805 7.593501) (xy 7.095755 7.464606) (xy 7.096252 7.400036)
			(xy 7.095755 7.335466) (xy 7.092973 7.290359) (xy 93.985575 7.290359) (xy 93.985575 7.376109) (xy 93.993487 7.461492)
			(xy 94.009243 7.545782) (xy 94.03271 7.628258) (xy 94.063686 7.708217) (xy 94.101908 7.784977) (xy 94.147049 7.857883)
			(xy 94.198725 7.926312) (xy 94.256494 7.989682) (xy 94.319864 8.047451) (xy 94.388293 8.099127) (xy 94.461199 8.144268)
			(xy 94.537959 8.18249) (xy 94.617918 8.213466) (xy 94.700394 8.236933) (xy 94.784684 8.252689) (xy 94.870067 8.260601)
			(xy 94.955817 8.260601) (xy 95.0412 8.252689) (xy 95.12549 8.236933) (xy 95.207966 8.213466) (xy 95.287925 8.18249)
			(xy 95.364685 8.144268) (xy 95.437591 8.099127) (xy 95.50602 8.047451) (xy 95.56939 7.989682) (xy 95.627159 7.926312)
			(xy 95.678835 7.857883) (xy 95.723976 7.784977) (xy 95.762198 7.708217) (xy 95.793174 7.628258) (xy 95.816641 7.545782)
			(xy 95.832397 7.461492) (xy 95.840309 7.376109) (xy 95.840804 7.333234) (xy 95.840309 7.290359) (xy 100.335575 7.290359)
			(xy 100.335575 7.376109) (xy 100.343487 7.461492) (xy 100.359243 7.545782) (xy 100.38271 7.628258)
			(xy 100.413686 7.708217) (xy 100.451908 7.784977) (xy 100.497049 7.857883) (xy 100.548725 7.926312)
			(xy 100.606494 7.989682) (xy 100.669864 8.047451) (xy 100.738293 8.099127) (xy 100.811199 8.144268)
			(xy 100.887959 8.18249) (xy 100.967918 8.213466) (xy 101.050394 8.236933) (xy 101.134684 8.252689)
			(xy 101.220067 8.260601) (xy 101.305817 8.260601) (xy 101.3912 8.252689) (xy 101.47549 8.236933)
			(xy 101.557966 8.213466) (xy 101.637925 8.18249) (xy 101.714685 8.144268) (xy 101.787591 8.099127)
			(xy 101.85602 8.047451) (xy 101.91939 7.989682) (xy 101.977159 7.926312) (xy 102.028835 7.857883)
			(xy 102.073976 7.784977) (xy 102.112198 7.708217) (xy 102.143174 7.628258) (xy 102.166641 7.545782)
			(xy 102.182397 7.461492) (xy 102.190309 7.376109) (xy 102.190804 7.333234) (xy 102.190309 7.290359)
			(xy 181.468255 7.290359) (xy 181.468255 7.376109) (xy 181.476167 7.461492) (xy 181.491923 7.545782)
			(xy 181.51539 7.628258) (xy 181.546366 7.708217) (xy 181.584588 7.784977) (xy 181.629729 7.857883)
			(xy 181.681405 7.926312) (xy 181.739174 7.989682) (xy 181.802544 8.047451) (xy 181.870973 8.099127)
			(xy 181.943879 8.144268) (xy 182.020639 8.18249) (xy 182.100598 8.213466) (xy 182.183074 8.236933)
			(xy 182.267364 8.252689) (xy 182.352747 8.260601) (xy 182.438497 8.260601) (xy 182.52388 8.252689)
			(xy 182.60817 8.236933) (xy 182.690646 8.213466) (xy 182.770605 8.18249) (xy 182.847365 8.144268)
			(xy 182.920271 8.099127) (xy 182.9887 8.047451) (xy 183.05207 7.989682) (xy 183.109839 7.926312)
			(xy 183.161515 7.857883) (xy 183.206656 7.784977) (xy 183.244878 7.708217) (xy 183.275854 7.628258)
			(xy 183.299321 7.545782) (xy 183.315077 7.461492) (xy 183.322989 7.376109) (xy 183.323484 7.333234)
			(xy 183.322989 7.290359) (xy 187.818255 7.290359) (xy 187.818255 7.376109) (xy 187.826167 7.461492)
			(xy 187.841923 7.545782) (xy 187.86539 7.628258) (xy 187.896366 7.708217) (xy 187.934588 7.784977)
			(xy 187.979729 7.857883) (xy 188.031405 7.926312) (xy 188.089174 7.989682) (xy 188.152544 8.047451)
			(xy 188.220973 8.099127) (xy 188.293879 8.144268) (xy 188.370639 8.18249) (xy 188.450598 8.213466)
			(xy 188.533074 8.236933) (xy 188.617364 8.252689) (xy 188.702747 8.260601) (xy 188.788497 8.260601)
			(xy 188.87388 8.252689) (xy 188.95817 8.236933) (xy 189.040646 8.213466) (xy 189.120605 8.18249)
			(xy 189.197365 8.144268) (xy 189.270271 8.099127) (xy 189.3387 8.047451) (xy 189.40207 7.989682)
			(xy 189.459839 7.926312) (xy 189.511515 7.857883) (xy 189.556656 7.784977) (xy 189.594878 7.708217)
			(xy 189.625854 7.628258) (xy 189.649321 7.545782) (xy 189.665077 7.461492) (xy 189.672989 7.376109)
			(xy 189.673484 7.333234) (xy 189.672989 7.290359) (xy 189.665077 7.204976) (xy 189.649321 7.120686)
			(xy 189.625854 7.03821) (xy 189.594878 6.958251) (xy 189.556656 6.881491) (xy 189.511515 6.808585)
			(xy 189.459839 6.740156) (xy 189.40207 6.676786) (xy 189.3387 6.619017) (xy 189.270271 6.567341)
			(xy 189.197365 6.5222) (xy 189.120605 6.483978) (xy 189.040646 6.453002) (xy 188.95817 6.429535)
			(xy 188.87388 6.413779) (xy 188.788497 6.405867) (xy 188.702747 6.405867) (xy 188.617364 6.413779)
			(xy 188.533074 6.429535) (xy 188.450598 6.453002) (xy 188.370639 6.483978) (xy 188.293879 6.5222)
			(xy 188.220973 6.567341) (xy 188.152544 6.619017) (xy 188.089174 6.676786) (xy 188.031405 6.740156)
			(xy 187.979729 6.808585) (xy 187.934588 6.881491) (xy 187.896366 6.958251) (xy 187.86539 7.03821)
			(xy 187.841923 7.120686) (xy 187.826167 7.204976) (xy 187.818255 7.290359) (xy 183.322989 7.290359)
			(xy 183.315077 7.204976) (xy 183.299321 7.120686) (xy 183.275854 7.03821) (xy 183.244878 6.958251)
			(xy 183.206656 6.881491) (xy 183.161515 6.808585) (xy 183.109839 6.740156) (xy 183.05207 6.676786)
			(xy 182.9887 6.619017) (xy 182.920271 6.567341) (xy 182.847365 6.5222) (xy 182.770605 6.483978) (xy 182.690646 6.453002)
			(xy 182.60817 6.429535) (xy 182.52388 6.413779) (xy 182.438497 6.405867) (xy 182.352747 6.405867)
			(xy 182.267364 6.413779) (xy 182.183074 6.429535) (xy 182.100598 6.453002) (xy 182.020639 6.483978)
			(xy 181.943879 6.5222) (xy 181.870973 6.567341) (xy 181.802544 6.619017) (xy 181.739174 6.676786)
			(xy 181.681405 6.740156) (xy 181.629729 6.808585) (xy 181.584588 6.881491) (xy 181.546366 6.958251)
			(xy 181.51539 7.03821) (xy 181.491923 7.120686) (xy 181.476167 7.204976) (xy 181.468255 7.290359)
			(xy 102.190309 7.290359) (xy 102.182397 7.204976) (xy 102.166641 7.120686) (xy 102.143174 7.03821)
			(xy 102.112198 6.958251) (xy 102.073976 6.881491) (xy 102.028835 6.808585) (xy 101.977159 6.740156)
			(xy 101.91939 6.676786) (xy 101.85602 6.619017) (xy 101.787591 6.567341) (xy 101.714685 6.5222) (xy 101.637925 6.483978)
			(xy 101.557966 6.453002) (xy 101.47549 6.429535) (xy 101.3912 6.413779) (xy 101.305817 6.405867)
			(xy 101.220067 6.405867) (xy 101.134684 6.413779) (xy 101.050394 6.429535) (xy 100.967918 6.453002)
			(xy 100.887959 6.483978) (xy 100.811199 6.5222) (xy 100.738293 6.567341) (xy 100.669864 6.619017)
			(xy 100.606494 6.676786) (xy 100.548725 6.740156) (xy 100.497049 6.808585) (xy 100.451908 6.881491)
			(xy 100.413686 6.958251) (xy 100.38271 7.03821) (xy 100.359243 7.120686) (xy 100.343487 7.204976)
			(xy 100.335575 7.290359) (xy 95.840309 7.290359) (xy 95.832397 7.204976) (xy 95.816641 7.120686)
			(xy 95.793174 7.03821) (xy 95.762198 6.958251) (xy 95.723976 6.881491) (xy 95.678835 6.808585) (xy 95.627159 6.740156)
			(xy 95.56939 6.676786) (xy 95.50602 6.619017) (xy 95.437591 6.567341) (xy 95.364685 6.5222) (xy 95.287925 6.483978)
			(xy 95.207966 6.453002) (xy 95.12549 6.429535) (xy 95.0412 6.413779) (xy 94.955817 6.405867) (xy 94.870067 6.405867)
			(xy 94.784684 6.413779) (xy 94.700394 6.429535) (xy 94.617918 6.453002) (xy 94.537959 6.483978) (xy 94.461199 6.5222)
			(xy 94.388293 6.567341) (xy 94.319864 6.619017) (xy 94.256494 6.676786) (xy 94.198725 6.740156) (xy 94.147049 6.808585)
			(xy 94.101908 6.881491) (xy 94.063686 6.958251) (xy 94.03271 7.03821) (xy 94.009243 7.120686) (xy 93.993487 7.204976)
			(xy 93.985575 7.290359) (xy 7.092973 7.290359) (xy 7.087805 7.206571) (xy 7.071935 7.078411) (xy 7.048206 6.95147)
			(xy 7.016707 6.826231) (xy 6.977558 6.703168) (xy 6.930907 6.582749) (xy 6.876932 6.46543) (xy 6.815837 6.351656)
			(xy 6.747854 6.241859) (xy 6.67324 6.136456) (xy 6.592279 6.035846) (xy 6.505279 5.940411) (xy 6.412568 5.850512)
			(xy 6.314498 5.766491) (xy 6.211443 5.688667) (xy 6.103792 5.617335) (xy 5.991953 5.552765) (xy 5.876352 5.495203)
			(xy 5.757427 5.444866) (xy 5.635628 5.401946) (xy 5.511418 5.366605) (xy 5.385269 5.338978) (xy 5.257657 5.319169)
			(xy 5.129068 5.307253) (xy 4.99999 5.303277) (xy 4.870912 5.307253) (xy 4.742323 5.319169) (xy 4.614711 5.338978)
			(xy 4.488562 5.366605) (xy 4.364352 5.401946) (xy 4.242553 5.444866) (xy 4.123628 5.495203) (xy 4.008027 5.552765)
			(xy 3.896188 5.617335) (xy 3.788537 5.688667) (xy 3.685482 5.766491) (xy 3.587412 5.850512) (xy 3.494701 5.940411)
			(xy 3.407701 6.035846) (xy 3.32674 6.136456) (xy 3.252126 6.241859) (xy 3.184143 6.351656) (xy 3.123048 6.46543)
			(xy 3.069073 6.582749) (xy 3.022422 6.703168) (xy 2.983273 6.826231) (xy 2.951774 6.95147) (xy 2.928045 7.078411)
			(xy 2.912175 7.206571) (xy 2.904225 7.335466) (xy 0.509016 7.335466) (xy 0.509016 4.750359) (xy 93.985575 4.750359)
			(xy 93.985575 4.836109) (xy 93.993487 4.921492) (xy 94.009243 5.005782) (xy 94.03271 5.088258) (xy 94.063686 5.168217)
			(xy 94.101908 5.244977) (xy 94.147049 5.317883) (xy 94.198725 5.386312) (xy 94.256494 5.449682) (xy 94.319864 5.507451)
			(xy 94.388293 5.559127) (xy 94.461199 5.604268) (xy 94.537959 5.64249) (xy 94.617918 5.673466) (xy 94.700394 5.696933)
			(xy 94.784684 5.712689) (xy 94.870067 5.720601) (xy 94.955817 5.720601) (xy 95.0412 5.712689) (xy 95.12549 5.696933)
			(xy 95.207966 5.673466) (xy 95.287925 5.64249) (xy 95.308598 5.632196) (xy 98.842576 5.632196) (xy 98.842576 6.495796)
			(xy 98.84308 6.525332) (xy 98.851124 6.583854) (xy 98.867061 6.640736) (xy 98.890596 6.694918) (xy 98.921289 6.745391)
			(xy 98.958569 6.791214) (xy 99.001741 6.831534) (xy 99.050001 6.8656) (xy 99.102451 6.892777) (xy 99.158112 6.912559)
			(xy 99.215949 6.924578) (xy 99.274884 6.928609) (xy 99.333819 6.924578) (xy 99.391656 6.912559) (xy 99.447317 6.892777)
			(xy 99.499767 6.8656) (xy 99.548027 6.831534) (xy 99.591199 6.791214) (xy 99.628479 6.745391) (xy 99.659172 6.694918)
			(xy 99.682707 6.640736) (xy 99.698644 6.583854) (xy 99.706688 6.525332) (xy 99.707192 6.495796) (xy 99.707192 5.632196)
			(xy 99.706688 5.60266) (xy 99.698644 5.544138) (xy 99.682707 5.487256) (xy 99.659172 5.433074) (xy 99.628479 5.382601)
			(xy 99.591199 5.336778) (xy 99.548027 5.296458) (xy 99.499767 5.262392) (xy 99.447317 5.235215) (xy 99.391656 5.215433)
			(xy 99.333819 5.203414) (xy 99.274884 5.199383) (xy 99.215949 5.203414) (xy 99.158112 5.215433) (xy 99.102451 5.235215)
			(xy 99.050001 5.262392) (xy 99.001741 5.296458) (xy 98.958569 5.336778) (xy 98.921289 5.382601) (xy 98.890596 5.433074)
			(xy 98.867061 5.487256) (xy 98.851124 5.544138) (xy 98.84308 5.60266) (xy 98.842576 5.632196) (xy 95.308598 5.632196)
			(xy 95.364685 5.604268) (xy 95.437591 5.559127) (xy 95.50602 5.507451) (xy 95.56939 5.449682) (xy 95.627159 5.386312)
			(xy 95.678835 5.317883) (xy 95.723976 5.244977) (xy 95.762198 5.168217) (xy 95.793174 5.088258) (xy 95.816641 5.005782)
			(xy 95.832397 4.921492) (xy 95.840309 4.836109) (xy 95.840804 4.793234) (xy 95.840309 4.750359) (xy 100.335575 4.750359)
			(xy 100.335575 4.836109) (xy 100.343487 4.921492) (xy 100.359243 5.005782) (xy 100.38271 5.088258)
			(xy 100.413686 5.168217) (xy 100.451908 5.244977) (xy 100.497049 5.317883) (xy 100.548725 5.386312)
			(xy 100.606494 5.449682) (xy 100.669864 5.507451) (xy 100.738293 5.559127) (xy 100.811199 5.604268)
			(xy 100.887959 5.64249) (xy 100.967918 5.673466) (xy 101.050394 5.696933) (xy 101.134684 5.712689)
			(xy 101.220067 5.720601) (xy 101.305817 5.720601) (xy 101.3912 5.712689) (xy 101.47549 5.696933)
			(xy 101.557966 5.673466) (xy 101.637925 5.64249) (xy 101.714685 5.604268) (xy 101.787591 5.559127)
			(xy 101.85602 5.507451) (xy 101.91939 5.449682) (xy 101.977159 5.386312) (xy 102.028835 5.317883)
			(xy 102.073976 5.244977) (xy 102.112198 5.168217) (xy 102.143174 5.088258) (xy 102.166641 5.005782)
			(xy 102.182397 4.921492) (xy 102.190309 4.836109) (xy 102.190804 4.793234) (xy 102.190309 4.750359)
			(xy 181.468255 4.750359) (xy 181.468255 4.836109) (xy 181.476167 4.921492) (xy 181.491923 5.005782)
			(xy 181.51539 5.088258) (xy 181.546366 5.168217) (xy 181.584588 5.244977) (xy 181.629729 5.317883)
			(xy 181.681405 5.386312) (xy 181.739174 5.449682) (xy 181.802544 5.507451) (xy 181.870973 5.559127)
			(xy 181.943879 5.604268) (xy 182.020639 5.64249) (xy 182.100598 5.673466) (xy 182.183074 5.696933)
			(xy 182.267364 5.712689) (xy 182.352747 5.720601) (xy 182.438497 5.720601) (xy 182.52388 5.712689)
			(xy 182.60817 5.696933) (xy 182.690646 5.673466) (xy 182.770605 5.64249) (xy 182.791278 5.632196)
			(xy 183.953912 5.632196) (xy 183.953912 6.495796) (xy 183.954416 6.525332) (xy 183.96246 6.583854)
			(xy 183.978397 6.640736) (xy 184.001932 6.694918) (xy 184.032625 6.745391) (xy 184.069905 6.791214)
			(xy 184.113077 6.831534) (xy 184.161337 6.8656) (xy 184.213787 6.892777) (xy 184.269448 6.912559)
			(xy 184.327285 6.924578) (xy 184.38622 6.928609) (xy 184.445155 6.924578) (xy 184.502992 6.912559)
			(xy 184.558653 6.892777) (xy 184.611103 6.8656) (xy 184.659363 6.831534) (xy 184.702535 6.791214)
			(xy 184.739815 6.745391) (xy 184.770508 6.694918) (xy 184.794043 6.640736) (xy 184.80998 6.583854)
			(xy 184.818024 6.525332) (xy 184.818528 6.495796) (xy 184.818528 6.309919) (xy 208.661241 6.309919)
			(xy 208.661241 6.395669) (xy 208.669153 6.481052) (xy 208.684909 6.565342) (xy 208.708376 6.647818)
			(xy 208.739352 6.727777) (xy 208.777574 6.804537) (xy 208.822715 6.877443) (xy 208.874391 6.945872)
			(xy 208.93216 7.009242) (xy 208.99553 7.067011) (xy 209.063959 7.118687) (xy 209.136865 7.163828)
			(xy 209.213625 7.20205) (xy 209.293584 7.233026) (xy 209.37606 7.256493) (xy 209.46035 7.272249)
			(xy 209.545733 7.280161) (xy 209.631483 7.280161) (xy 209.716866 7.272249) (xy 209.801156 7.256493)
			(xy 209.883632 7.233026) (xy 209.963591 7.20205) (xy 210.040351 7.163828) (xy 210.113257 7.118687)
			(xy 210.181686 7.067011) (xy 210.245056 7.009242) (xy 210.302825 6.945872) (xy 210.354501 6.877443)
			(xy 210.399642 6.804537) (xy 210.437864 6.727777) (xy 210.46884 6.647818) (xy 210.492307 6.565342)
			(xy 210.508063 6.481052) (xy 210.515975 6.395669) (xy 210.51647 6.352794) (xy 210.515975 6.309919)
			(xy 215.011241 6.309919) (xy 215.011241 6.395669) (xy 215.019153 6.481052) (xy 215.034909 6.565342)
			(xy 215.058376 6.647818) (xy 215.089352 6.727777) (xy 215.127574 6.804537) (xy 215.172715 6.877443)
			(xy 215.224391 6.945872) (xy 215.28216 7.009242) (xy 215.34553 7.067011) (xy 215.413959 7.118687)
			(xy 215.486865 7.163828) (xy 215.563625 7.20205) (xy 215.643584 7.233026) (xy 215.72606 7.256493)
			(xy 215.81035 7.272249) (xy 215.895733 7.280161) (xy 215.981483 7.280161) (xy 216.066866 7.272249)
			(xy 216.151156 7.256493) (xy 216.233632 7.233026) (xy 216.313591 7.20205) (xy 216.390351 7.163828)
			(xy 216.463257 7.118687) (xy 216.531686 7.067011) (xy 216.595056 7.009242) (xy 216.652825 6.945872)
			(xy 216.704501 6.877443) (xy 216.749642 6.804537) (xy 216.787864 6.727777) (xy 216.81884 6.647818)
			(xy 216.842307 6.565342) (xy 216.858063 6.481052) (xy 216.865975 6.395669) (xy 216.86647 6.352794)
			(xy 216.865975 6.309919) (xy 296.143921 6.309919) (xy 296.143921 6.395669) (xy 296.151833 6.481052)
			(xy 296.167589 6.565342) (xy 296.191056 6.647818) (xy 296.222032 6.727777) (xy 296.260254 6.804537)
			(xy 296.305395 6.877443) (xy 296.357071 6.945872) (xy 296.41484 7.009242) (xy 296.47821 7.067011)
			(xy 296.546639 7.118687) (xy 296.619545 7.163828) (xy 296.696305 7.20205) (xy 296.776264 7.233026)
			(xy 296.85874 7.256493) (xy 296.94303 7.272249) (xy 297.028413 7.280161) (xy 297.114163 7.280161)
			(xy 297.199546 7.272249) (xy 297.283836 7.256493) (xy 297.366312 7.233026) (xy 297.446271 7.20205)
			(xy 297.523031 7.163828) (xy 297.595937 7.118687) (xy 297.664366 7.067011) (xy 297.727736 7.009242)
			(xy 297.785505 6.945872) (xy 297.837181 6.877443) (xy 297.882322 6.804537) (xy 297.920544 6.727777)
			(xy 297.95152 6.647818) (xy 297.974987 6.565342) (xy 297.990743 6.481052) (xy 297.998655 6.395669)
			(xy 297.99915 6.352794) (xy 297.998655 6.309919) (xy 302.493921 6.309919) (xy 302.493921 6.395669)
			(xy 302.501833 6.481052) (xy 302.517589 6.565342) (xy 302.541056 6.647818) (xy 302.572032 6.727777)
			(xy 302.610254 6.804537) (xy 302.655395 6.877443) (xy 302.707071 6.945872) (xy 302.76484 7.009242)
			(xy 302.82821 7.067011) (xy 302.896639 7.118687) (xy 302.969545 7.163828) (xy 303.046305 7.20205)
			(xy 303.126264 7.233026) (xy 303.20874 7.256493) (xy 303.29303 7.272249) (xy 303.378413 7.280161)
			(xy 303.464163 7.280161) (xy 303.549546 7.272249) (xy 303.633836 7.256493) (xy 303.716312 7.233026)
			(xy 303.796271 7.20205) (xy 303.873031 7.163828) (xy 303.945937 7.118687) (xy 304.014366 7.067011)
			(xy 304.077736 7.009242) (xy 304.135505 6.945872) (xy 304.187181 6.877443) (xy 304.232322 6.804537)
			(xy 304.270544 6.727777) (xy 304.30152 6.647818) (xy 304.324987 6.565342) (xy 304.340743 6.481052)
			(xy 304.348655 6.395669) (xy 304.34915 6.352794) (xy 304.348655 6.309919) (xy 311.155321 6.309919)
			(xy 311.155321 6.395669) (xy 311.163233 6.481052) (xy 311.178989 6.565342) (xy 311.202456 6.647818)
			(xy 311.233432 6.727777) (xy 311.271654 6.804537) (xy 311.316795 6.877443) (xy 311.368471 6.945872)
			(xy 311.42624 7.009242) (xy 311.48961 7.067011) (xy 311.558039 7.118687) (xy 311.630945 7.163828)
			(xy 311.707705 7.20205) (xy 311.787664 7.233026) (xy 311.87014 7.256493) (xy 311.95443 7.272249)
			(xy 312.039813 7.280161) (xy 312.125563 7.280161) (xy 312.210946 7.272249) (xy 312.295236 7.256493)
			(xy 312.377712 7.233026) (xy 312.457671 7.20205) (xy 312.478344 7.191756) (xy 316.012068 7.191756)
			(xy 316.012068 8.055356) (xy 316.012572 8.08491) (xy 316.020621 8.143466) (xy 316.036567 8.200381)
			(xy 316.060116 8.254595) (xy 316.090827 8.305098) (xy 316.128129 8.350948) (xy 316.171326 8.391291)
			(xy 316.219615 8.425377) (xy 316.272095 8.45257) (xy 316.32779 8.472364) (xy 316.385661 8.48439)
			(xy 316.44463 8.488424) (xy 316.503599 8.48439) (xy 316.56147 8.472364) (xy 316.617165 8.45257) (xy 316.669645 8.425377)
			(xy 316.717934 8.391291) (xy 316.761131 8.350948) (xy 316.798433 8.305098) (xy 316.829144 8.254595)
			(xy 316.852693 8.200381) (xy 316.868639 8.143466) (xy 316.876688 8.08491) (xy 316.877192 8.055356)
			(xy 316.877192 7.191756) (xy 316.876688 7.162202) (xy 316.868639 7.103646) (xy 316.852693 7.046731)
			(xy 316.829144 6.992517) (xy 316.798433 6.942014) (xy 316.761131 6.896164) (xy 316.717934 6.855821)
			(xy 316.669645 6.821735) (xy 316.617165 6.794542) (xy 316.56147 6.774748) (xy 316.503599 6.762722)
			(xy 316.44463 6.758689) (xy 316.385661 6.762722) (xy 316.32779 6.774748) (xy 316.272095 6.794542)
			(xy 316.219615 6.821735) (xy 316.171326 6.855821) (xy 316.128129 6.896164) (xy 316.090827 6.942014)
			(xy 316.060116 6.992517) (xy 316.036567 7.046731) (xy 316.020621 7.103646) (xy 316.012572 7.162202)
			(xy 316.012068 7.191756) (xy 312.478344 7.191756) (xy 312.534431 7.163828) (xy 312.607337 7.118687)
			(xy 312.675766 7.067011) (xy 312.739136 7.009242) (xy 312.796905 6.945872) (xy 312.848581 6.877443)
			(xy 312.893722 6.804537) (xy 312.931944 6.727777) (xy 312.96292 6.647818) (xy 312.986387 6.565342)
			(xy 313.002143 6.481052) (xy 313.010055 6.395669) (xy 313.01055 6.352794) (xy 313.010055 6.309919)
			(xy 317.505321 6.309919) (xy 317.505321 6.395669) (xy 317.513233 6.481052) (xy 317.528989 6.565342)
			(xy 317.552456 6.647818) (xy 317.583432 6.727777) (xy 317.621654 6.804537) (xy 317.666795 6.877443)
			(xy 317.718471 6.945872) (xy 317.77624 7.009242) (xy 317.83961 7.067011) (xy 317.908039 7.118687)
			(xy 317.980945 7.163828) (xy 318.057705 7.20205) (xy 318.137664 7.233026) (xy 318.22014 7.256493)
			(xy 318.30443 7.272249) (xy 318.389813 7.280161) (xy 318.475563 7.280161) (xy 318.560946 7.272249)
			(xy 318.645236 7.256493) (xy 318.727712 7.233026) (xy 318.807671 7.20205) (xy 318.884431 7.163828)
			(xy 318.957337 7.118687) (xy 319.025766 7.067011) (xy 319.089136 7.009242) (xy 319.146905 6.945872)
			(xy 319.198581 6.877443) (xy 319.243722 6.804537) (xy 319.281944 6.727777) (xy 319.31292 6.647818)
			(xy 319.336387 6.565342) (xy 319.352143 6.481052) (xy 319.360055 6.395669) (xy 319.36055 6.352794)
			(xy 319.360055 6.309919) (xy 361.894107 6.309919) (xy 361.894107 6.395669) (xy 361.902019 6.481052)
			(xy 361.917775 6.565342) (xy 361.941242 6.647818) (xy 361.972218 6.727777) (xy 362.01044 6.804537)
			(xy 362.055581 6.877443) (xy 362.107257 6.945872) (xy 362.165026 7.009242) (xy 362.228396 7.067011)
			(xy 362.296825 7.118687) (xy 362.369731 7.163828) (xy 362.446491 7.20205) (xy 362.52645 7.233026)
			(xy 362.608926 7.256493) (xy 362.693216 7.272249) (xy 362.778599 7.280161) (xy 362.864349 7.280161)
			(xy 362.949732 7.272249) (xy 363.034022 7.256493) (xy 363.116498 7.233026) (xy 363.196457 7.20205)
			(xy 363.21713 7.191756) (xy 364.379764 7.191756) (xy 364.379764 8.055356) (xy 364.380268 8.084892)
			(xy 364.388312 8.143414) (xy 364.404249 8.200296) (xy 364.427784 8.254478) (xy 364.458477 8.304951)
			(xy 364.495757 8.350774) (xy 364.538929 8.391094) (xy 364.587189 8.42516) (xy 364.639639 8.452337)
			(xy 364.6953 8.472119) (xy 364.753137 8.484138) (xy 364.812072 8.488169) (xy 364.871007 8.484138)
			(xy 364.928844 8.472119) (xy 364.984505 8.452337) (xy 365.036955 8.42516) (xy 365.085215 8.391094)
			(xy 365.128387 8.350774) (xy 365.165667 8.304951) (xy 365.19636 8.254478) (xy 365.219895 8.200296)
			(xy 365.235832 8.143414) (xy 365.243876 8.084892) (xy 365.24438 8.055356) (xy 365.24438 7.376973)
			(xy 385.651997 7.376973) (xy 385.651997 7.462723) (xy 385.659909 7.548106) (xy 385.675665 7.632396)
			(xy 385.699132 7.714872) (xy 385.730108 7.794831) (xy 385.76833 7.871591) (xy 385.813471 7.944497)
			(xy 385.865147 8.012926) (xy 385.922916 8.076296) (xy 385.986286 8.134065) (xy 386.054715 8.185741)
			(xy 386.127621 8.230882) (xy 386.204381 8.269104) (xy 386.28434 8.30008) (xy 386.366816 8.323547)
			(xy 386.451106 8.339303) (xy 386.536489 8.347215) (xy 386.622239 8.347215) (xy 386.707622 8.339303)
			(xy 386.791912 8.323547) (xy 386.874388 8.30008) (xy 386.954347 8.269104) (xy 386.97502 8.25881)
			(xy 390.508744 8.25881) (xy 390.508744 9.12241) (xy 390.509248 9.151964) (xy 390.517297 9.21052)
			(xy 390.533243 9.267435) (xy 390.556792 9.321649) (xy 390.587503 9.372152) (xy 390.624805 9.418002)
			(xy 390.668002 9.458345) (xy 390.716291 9.492431) (xy 390.768771 9.519624) (xy 390.824466 9.539418)
			(xy 390.882337 9.551444) (xy 390.941306 9.555478) (xy 391.000275 9.551444) (xy 391.058146 9.539418)
			(xy 391.113841 9.519624) (xy 391.166321 9.492431) (xy 391.21461 9.458345) (xy 391.257807 9.418002)
			(xy 391.295109 9.372152) (xy 391.32582 9.321649) (xy 391.349369 9.267435) (xy 391.365315 9.21052)
			(xy 391.373364 9.151964) (xy 391.373868 9.12241) (xy 391.373868 8.25881) (xy 391.373364 8.229256)
			(xy 391.365315 8.1707) (xy 391.349369 8.113785) (xy 391.32582 8.059571) (xy 391.295109 8.009068)
			(xy 391.257807 7.963218) (xy 391.21461 7.922875) (xy 391.166321 7.888789) (xy 391.113841 7.861596)
			(xy 391.058146 7.841802) (xy 391.000275 7.829776) (xy 390.941306 7.825743) (xy 390.882337 7.829776)
			(xy 390.824466 7.841802) (xy 390.768771 7.861596) (xy 390.716291 7.888789) (xy 390.668002 7.922875)
			(xy 390.624805 7.963218) (xy 390.587503 8.009068) (xy 390.556792 8.059571) (xy 390.533243 8.113785)
			(xy 390.517297 8.1707) (xy 390.509248 8.229256) (xy 390.508744 8.25881) (xy 386.97502 8.25881) (xy 387.031107 8.230882)
			(xy 387.104013 8.185741) (xy 387.172442 8.134065) (xy 387.235812 8.076296) (xy 387.293581 8.012926)
			(xy 387.345257 7.944497) (xy 387.390398 7.871591) (xy 387.42862 7.794831) (xy 387.459596 7.714872)
			(xy 387.483063 7.632396) (xy 387.498819 7.548106) (xy 387.506731 7.462723) (xy 387.507226 7.419848)
			(xy 387.506731 7.376973) (xy 392.001997 7.376973) (xy 392.001997 7.462723) (xy 392.009909 7.548106)
			(xy 392.025665 7.632396) (xy 392.049132 7.714872) (xy 392.080108 7.794831) (xy 392.11833 7.871591)
			(xy 392.163471 7.944497) (xy 392.215147 8.012926) (xy 392.272916 8.076296) (xy 392.336286 8.134065)
			(xy 392.404715 8.185741) (xy 392.477621 8.230882) (xy 392.554381 8.269104) (xy 392.63434 8.30008)
			(xy 392.716816 8.323547) (xy 392.801106 8.339303) (xy 392.886489 8.347215) (xy 392.972239 8.347215)
			(xy 393.057622 8.339303) (xy 393.141912 8.323547) (xy 393.224388 8.30008) (xy 393.304347 8.269104)
			(xy 393.381107 8.230882) (xy 393.454013 8.185741) (xy 393.522442 8.134065) (xy 393.585812 8.076296)
			(xy 393.643581 8.012926) (xy 393.695257 7.944497) (xy 393.740398 7.871591) (xy 393.77862 7.794831)
			(xy 393.809596 7.714872) (xy 393.833063 7.632396) (xy 393.848819 7.548106) (xy 393.856731 7.462723)
			(xy 393.857226 7.419848) (xy 393.856731 7.376973) (xy 436.390783 7.376973) (xy 436.390783 7.462723)
			(xy 436.398695 7.548106) (xy 436.414451 7.632396) (xy 436.437918 7.714872) (xy 436.468894 7.794831)
			(xy 436.507116 7.871591) (xy 436.552257 7.944497) (xy 436.603933 8.012926) (xy 436.661702 8.076296)
			(xy 436.725072 8.134065) (xy 436.793501 8.185741) (xy 436.866407 8.230882) (xy 436.943167 8.269104)
			(xy 437.023126 8.30008) (xy 437.105602 8.323547) (xy 437.189892 8.339303) (xy 437.275275 8.347215)
			(xy 437.361025 8.347215) (xy 437.446408 8.339303) (xy 437.530698 8.323547) (xy 437.613174 8.30008)
			(xy 437.693133 8.269104) (xy 437.713806 8.25881) (xy 438.87644 8.25881) (xy 438.87644 9.12241) (xy 438.876944 9.151946)
			(xy 438.884988 9.210468) (xy 438.900925 9.26735) (xy 438.92446 9.321532) (xy 438.955153 9.372005)
			(xy 438.992433 9.417828) (xy 439.035605 9.458148) (xy 439.083865 9.492214) (xy 439.136315 9.519391)
			(xy 439.191976 9.539173) (xy 439.249813 9.551192) (xy 439.308748 9.555223) (xy 439.367683 9.551192)
			(xy 439.42552 9.539173) (xy 439.481181 9.519391) (xy 439.533631 9.492214) (xy 439.581891 9.458148)
			(xy 439.625063 9.417828) (xy 439.662343 9.372005) (xy 439.693036 9.321532) (xy 439.716571 9.26735)
			(xy 439.732508 9.210468) (xy 439.740552 9.151946) (xy 439.741056 9.12241) (xy 439.741056 8.25881)
			(xy 439.740552 8.229274) (xy 439.732508 8.170752) (xy 439.716571 8.11387) (xy 439.693036 8.059688)
			(xy 439.662343 8.009215) (xy 439.625063 7.963392) (xy 439.581891 7.923072) (xy 439.533631 7.889006)
			(xy 439.481181 7.861829) (xy 439.42552 7.842047) (xy 439.367683 7.830028) (xy 439.308748 7.825997)
			(xy 439.249813 7.830028) (xy 439.191976 7.842047) (xy 439.136315 7.861829) (xy 439.083865 7.889006)
			(xy 439.035605 7.923072) (xy 438.992433 7.963392) (xy 438.955153 8.009215) (xy 438.92446 8.059688)
			(xy 438.900925 8.11387) (xy 438.884988 8.170752) (xy 438.876944 8.229274) (xy 438.87644 8.25881)
			(xy 437.713806 8.25881) (xy 437.769893 8.230882) (xy 437.842799 8.185741) (xy 437.911228 8.134065)
			(xy 437.974598 8.076296) (xy 438.032367 8.012926) (xy 438.084043 7.944497) (xy 438.129184 7.871591)
			(xy 438.167406 7.794831) (xy 438.198382 7.714872) (xy 438.221849 7.632396) (xy 438.237605 7.548106)
			(xy 438.245517 7.462723) (xy 438.246012 7.419848) (xy 438.245517 7.376973) (xy 442.740783 7.376973)
			(xy 442.740783 7.462723) (xy 442.748695 7.548106) (xy 442.764451 7.632396) (xy 442.787918 7.714872)
			(xy 442.818894 7.794831) (xy 442.857116 7.871591) (xy 442.902257 7.944497) (xy 442.953933 8.012926)
			(xy 443.011702 8.076296) (xy 443.075072 8.134065) (xy 443.143501 8.185741) (xy 443.216407 8.230882)
			(xy 443.293167 8.269104) (xy 443.373126 8.30008) (xy 443.455602 8.323547) (xy 443.539892 8.339303)
			(xy 443.625275 8.347215) (xy 443.711025 8.347215) (xy 443.796408 8.339303) (xy 443.880698 8.323547)
			(xy 443.963174 8.30008) (xy 444.043133 8.269104) (xy 444.119893 8.230882) (xy 444.192799 8.185741)
			(xy 444.261228 8.134065) (xy 444.324598 8.076296) (xy 444.382367 8.012926) (xy 444.434043 7.944497)
			(xy 444.479184 7.871591) (xy 444.517406 7.794831) (xy 444.548382 7.714872) (xy 444.571849 7.632396)
			(xy 444.587605 7.548106) (xy 444.595517 7.462723) (xy 444.596012 7.419848) (xy 444.595517 7.376973)
			(xy 444.587605 7.29159) (xy 444.571849 7.2073) (xy 444.548382 7.124824) (xy 444.517406 7.044865)
			(xy 444.479184 6.968105) (xy 444.434043 6.895199) (xy 444.382367 6.82677) (xy 444.324598 6.7634)
			(xy 444.261228 6.705631) (xy 444.192799 6.653955) (xy 444.119893 6.608814) (xy 444.043133 6.570592)
			(xy 443.963174 6.539616) (xy 443.880698 6.516149) (xy 443.796408 6.500393) (xy 443.711025 6.492481)
			(xy 443.625275 6.492481) (xy 443.539892 6.500393) (xy 443.455602 6.516149) (xy 443.373126 6.539616)
			(xy 443.293167 6.570592) (xy 443.216407 6.608814) (xy 443.143501 6.653955) (xy 443.075072 6.705631)
			(xy 443.011702 6.7634) (xy 442.953933 6.82677) (xy 442.902257 6.895199) (xy 442.857116 6.968105)
			(xy 442.818894 7.044865) (xy 442.787918 7.124824) (xy 442.764451 7.2073) (xy 442.748695 7.29159)
			(xy 442.740783 7.376973) (xy 438.245517 7.376973) (xy 438.237605 7.29159) (xy 438.221849 7.2073)
			(xy 438.198382 7.124824) (xy 438.167406 7.044865) (xy 438.129184 6.968105) (xy 438.084043 6.895199)
			(xy 438.032367 6.82677) (xy 437.974598 6.7634) (xy 437.911228 6.705631) (xy 437.842799 6.653955)
			(xy 437.769893 6.608814) (xy 437.693133 6.570592) (xy 437.613174 6.539616) (xy 437.530698 6.516149)
			(xy 437.446408 6.500393) (xy 437.361025 6.492481) (xy 437.275275 6.492481) (xy 437.189892 6.500393)
			(xy 437.105602 6.516149) (xy 437.023126 6.539616) (xy 436.943167 6.570592) (xy 436.866407 6.608814)
			(xy 436.793501 6.653955) (xy 436.725072 6.705631) (xy 436.661702 6.7634) (xy 436.603933 6.82677)
			(xy 436.552257 6.895199) (xy 436.507116 6.968105) (xy 436.468894 7.044865) (xy 436.437918 7.124824)
			(xy 436.414451 7.2073) (xy 436.398695 7.29159) (xy 436.390783 7.376973) (xy 393.856731 7.376973)
			(xy 393.848819 7.29159) (xy 393.833063 7.2073) (xy 393.809596 7.124824) (xy 393.77862 7.044865) (xy 393.740398 6.968105)
			(xy 393.695257 6.895199) (xy 393.643581 6.82677) (xy 393.585812 6.7634) (xy 393.522442 6.705631)
			(xy 393.454013 6.653955) (xy 393.381107 6.608814) (xy 393.304347 6.570592) (xy 393.224388 6.539616)
			(xy 393.141912 6.516149) (xy 393.057622 6.500393) (xy 392.972239 6.492481) (xy 392.886489 6.492481)
			(xy 392.801106 6.500393) (xy 392.716816 6.516149) (xy 392.63434 6.539616) (xy 392.554381 6.570592)
			(xy 392.477621 6.608814) (xy 392.404715 6.653955) (xy 392.336286 6.705631) (xy 392.272916 6.7634)
			(xy 392.215147 6.82677) (xy 392.163471 6.895199) (xy 392.11833 6.968105) (xy 392.080108 7.044865)
			(xy 392.049132 7.124824) (xy 392.025665 7.2073) (xy 392.009909 7.29159) (xy 392.001997 7.376973)
			(xy 387.506731 7.376973) (xy 387.498819 7.29159) (xy 387.483063 7.2073) (xy 387.459596 7.124824)
			(xy 387.42862 7.044865) (xy 387.390398 6.968105) (xy 387.345257 6.895199) (xy 387.293581 6.82677)
			(xy 387.235812 6.7634) (xy 387.172442 6.705631) (xy 387.104013 6.653955) (xy 387.031107 6.608814)
			(xy 386.954347 6.570592) (xy 386.874388 6.539616) (xy 386.791912 6.516149) (xy 386.707622 6.500393)
			(xy 386.622239 6.492481) (xy 386.536489 6.492481) (xy 386.451106 6.500393) (xy 386.366816 6.516149)
			(xy 386.28434 6.539616) (xy 386.204381 6.570592) (xy 386.127621 6.608814) (xy 386.054715 6.653955)
			(xy 385.986286 6.705631) (xy 385.922916 6.7634) (xy 385.865147 6.82677) (xy 385.813471 6.895199)
			(xy 385.76833 6.968105) (xy 385.730108 7.044865) (xy 385.699132 7.124824) (xy 385.675665 7.2073)
			(xy 385.659909 7.29159) (xy 385.651997 7.376973) (xy 365.24438 7.376973) (xy 365.24438 7.191756)
			(xy 365.243876 7.16222) (xy 365.235832 7.103698) (xy 365.219895 7.046816) (xy 365.19636 6.992634)
			(xy 365.165667 6.942161) (xy 365.128387 6.896338) (xy 365.085215 6.856018) (xy 365.036955 6.821952)
			(xy 364.984505 6.794775) (xy 364.928844 6.774993) (xy 364.871007 6.762974) (xy 364.812072 6.758943)
			(xy 364.753137 6.762974) (xy 364.6953 6.774993) (xy 364.639639 6.794775) (xy 364.587189 6.821952)
			(xy 364.538929 6.856018) (xy 364.495757 6.896338) (xy 364.458477 6.942161) (xy 364.427784 6.992634)
			(xy 364.404249 7.046816) (xy 364.388312 7.103698) (xy 364.380268 7.16222) (xy 364.379764 7.191756)
			(xy 363.21713 7.191756) (xy 363.273217 7.163828) (xy 363.346123 7.118687) (xy 363.414552 7.067011)
			(xy 363.477922 7.009242) (xy 363.535691 6.945872) (xy 363.587367 6.877443) (xy 363.632508 6.804537)
			(xy 363.67073 6.727777) (xy 363.701706 6.647818) (xy 363.725173 6.565342) (xy 363.740929 6.481052)
			(xy 363.748841 6.395669) (xy 363.749336 6.352794) (xy 363.748841 6.309919) (xy 368.244107 6.309919)
			(xy 368.244107 6.395669) (xy 368.252019 6.481052) (xy 368.267775 6.565342) (xy 368.291242 6.647818)
			(xy 368.322218 6.727777) (xy 368.36044 6.804537) (xy 368.405581 6.877443) (xy 368.457257 6.945872)
			(xy 368.515026 7.009242) (xy 368.578396 7.067011) (xy 368.646825 7.118687) (xy 368.719731 7.163828)
			(xy 368.796491 7.20205) (xy 368.87645 7.233026) (xy 368.958926 7.256493) (xy 369.043216 7.272249)
			(xy 369.128599 7.280161) (xy 369.214349 7.280161) (xy 369.299732 7.272249) (xy 369.384022 7.256493)
			(xy 369.466498 7.233026) (xy 369.546457 7.20205) (xy 369.623217 7.163828) (xy 369.696123 7.118687)
			(xy 369.764552 7.067011) (xy 369.827922 7.009242) (xy 369.885691 6.945872) (xy 369.937367 6.877443)
			(xy 369.982508 6.804537) (xy 370.02073 6.727777) (xy 370.051706 6.647818) (xy 370.075173 6.565342)
			(xy 370.090929 6.481052) (xy 370.098841 6.395669) (xy 370.099336 6.352794) (xy 370.098841 6.309919)
			(xy 370.090929 6.224536) (xy 370.075173 6.140246) (xy 370.051706 6.05777) (xy 370.02073 5.977811)
			(xy 369.982508 5.901051) (xy 369.937367 5.828145) (xy 369.885691 5.759716) (xy 369.827922 5.696346)
			(xy 369.764552 5.638577) (xy 369.696123 5.586901) (xy 369.623217 5.54176) (xy 369.546457 5.503538)
			(xy 369.466498 5.472562) (xy 369.384022 5.449095) (xy 369.299732 5.433339) (xy 369.214349 5.425427)
			(xy 369.128599 5.425427) (xy 369.043216 5.433339) (xy 368.958926 5.449095) (xy 368.87645 5.472562)
			(xy 368.796491 5.503538) (xy 368.719731 5.54176) (xy 368.646825 5.586901) (xy 368.578396 5.638577)
			(xy 368.515026 5.696346) (xy 368.457257 5.759716) (xy 368.405581 5.828145) (xy 368.36044 5.901051)
			(xy 368.322218 5.977811) (xy 368.291242 6.05777) (xy 368.267775 6.140246) (xy 368.252019 6.224536)
			(xy 368.244107 6.309919) (xy 363.748841 6.309919) (xy 363.740929 6.224536) (xy 363.725173 6.140246)
			(xy 363.701706 6.05777) (xy 363.67073 5.977811) (xy 363.632508 5.901051) (xy 363.587367 5.828145)
			(xy 363.535691 5.759716) (xy 363.477922 5.696346) (xy 363.414552 5.638577) (xy 363.346123 5.586901)
			(xy 363.273217 5.54176) (xy 363.196457 5.503538) (xy 363.116498 5.472562) (xy 363.034022 5.449095)
			(xy 362.949732 5.433339) (xy 362.864349 5.425427) (xy 362.778599 5.425427) (xy 362.693216 5.433339)
			(xy 362.608926 5.449095) (xy 362.52645 5.472562) (xy 362.446491 5.503538) (xy 362.369731 5.54176)
			(xy 362.296825 5.586901) (xy 362.228396 5.638577) (xy 362.165026 5.696346) (xy 362.107257 5.759716)
			(xy 362.055581 5.828145) (xy 362.01044 5.901051) (xy 361.972218 5.977811) (xy 361.941242 6.05777)
			(xy 361.917775 6.140246) (xy 361.902019 6.224536) (xy 361.894107 6.309919) (xy 319.360055 6.309919)
			(xy 319.352143 6.224536) (xy 319.336387 6.140246) (xy 319.31292 6.05777) (xy 319.281944 5.977811)
			(xy 319.243722 5.901051) (xy 319.198581 5.828145) (xy 319.146905 5.759716) (xy 319.089136 5.696346)
			(xy 319.025766 5.638577) (xy 318.957337 5.586901) (xy 318.884431 5.54176) (xy 318.807671 5.503538)
			(xy 318.727712 5.472562) (xy 318.645236 5.449095) (xy 318.560946 5.433339) (xy 318.475563 5.425427)
			(xy 318.389813 5.425427) (xy 318.30443 5.433339) (xy 318.22014 5.449095) (xy 318.137664 5.472562)
			(xy 318.057705 5.503538) (xy 317.980945 5.54176) (xy 317.908039 5.586901) (xy 317.83961 5.638577)
			(xy 317.77624 5.696346) (xy 317.718471 5.759716) (xy 317.666795 5.828145) (xy 317.621654 5.901051)
			(xy 317.583432 5.977811) (xy 317.552456 6.05777) (xy 317.528989 6.140246) (xy 317.513233 6.224536)
			(xy 317.505321 6.309919) (xy 313.010055 6.309919) (xy 313.002143 6.224536) (xy 312.986387 6.140246)
			(xy 312.96292 6.05777) (xy 312.931944 5.977811) (xy 312.893722 5.901051) (xy 312.848581 5.828145)
			(xy 312.796905 5.759716) (xy 312.739136 5.696346) (xy 312.675766 5.638577) (xy 312.607337 5.586901)
			(xy 312.534431 5.54176) (xy 312.457671 5.503538) (xy 312.377712 5.472562) (xy 312.295236 5.449095)
			(xy 312.210946 5.433339) (xy 312.125563 5.425427) (xy 312.039813 5.425427) (xy 311.95443 5.433339)
			(xy 311.87014 5.449095) (xy 311.787664 5.472562) (xy 311.707705 5.503538) (xy 311.630945 5.54176)
			(xy 311.558039 5.586901) (xy 311.48961 5.638577) (xy 311.42624 5.696346) (xy 311.368471 5.759716)
			(xy 311.316795 5.828145) (xy 311.271654 5.901051) (xy 311.233432 5.977811) (xy 311.202456 6.05777)
			(xy 311.178989 6.140246) (xy 311.163233 6.224536) (xy 311.155321 6.309919) (xy 304.348655 6.309919)
			(xy 304.340743 6.224536) (xy 304.324987 6.140246) (xy 304.30152 6.05777) (xy 304.270544 5.977811)
			(xy 304.232322 5.901051) (xy 304.187181 5.828145) (xy 304.135505 5.759716) (xy 304.077736 5.696346)
			(xy 304.014366 5.638577) (xy 303.945937 5.586901) (xy 303.873031 5.54176) (xy 303.796271 5.503538)
			(xy 303.716312 5.472562) (xy 303.633836 5.449095) (xy 303.549546 5.433339) (xy 303.464163 5.425427)
			(xy 303.378413 5.425427) (xy 303.29303 5.433339) (xy 303.20874 5.449095) (xy 303.126264 5.472562)
			(xy 303.046305 5.503538) (xy 302.969545 5.54176) (xy 302.896639 5.586901) (xy 302.82821 5.638577)
			(xy 302.76484 5.696346) (xy 302.707071 5.759716) (xy 302.655395 5.828145) (xy 302.610254 5.901051)
			(xy 302.572032 5.977811) (xy 302.541056 6.05777) (xy 302.517589 6.140246) (xy 302.501833 6.224536)
			(xy 302.493921 6.309919) (xy 297.998655 6.309919) (xy 297.990743 6.224536) (xy 297.974987 6.140246)
			(xy 297.95152 6.05777) (xy 297.920544 5.977811) (xy 297.882322 5.901051) (xy 297.837181 5.828145)
			(xy 297.785505 5.759716) (xy 297.727736 5.696346) (xy 297.664366 5.638577) (xy 297.595937 5.586901)
			(xy 297.523031 5.54176) (xy 297.446271 5.503538) (xy 297.366312 5.472562) (xy 297.283836 5.449095)
			(xy 297.199546 5.433339) (xy 297.114163 5.425427) (xy 297.028413 5.425427) (xy 296.94303 5.433339)
			(xy 296.85874 5.449095) (xy 296.776264 5.472562) (xy 296.696305 5.503538) (xy 296.619545 5.54176)
			(xy 296.546639 5.586901) (xy 296.47821 5.638577) (xy 296.41484 5.696346) (xy 296.357071 5.759716)
			(xy 296.305395 5.828145) (xy 296.260254 5.901051) (xy 296.222032 5.977811) (xy 296.191056 6.05777)
			(xy 296.167589 6.140246) (xy 296.151833 6.224536) (xy 296.143921 6.309919) (xy 216.865975 6.309919)
			(xy 216.858063 6.224536) (xy 216.842307 6.140246) (xy 216.81884 6.05777) (xy 216.787864 5.977811)
			(xy 216.749642 5.901051) (xy 216.704501 5.828145) (xy 216.652825 5.759716) (xy 216.595056 5.696346)
			(xy 216.531686 5.638577) (xy 216.463257 5.586901) (xy 216.390351 5.54176) (xy 216.313591 5.503538)
			(xy 216.233632 5.472562) (xy 216.151156 5.449095) (xy 216.066866 5.433339) (xy 215.981483 5.425427)
			(xy 215.895733 5.425427) (xy 215.81035 5.433339) (xy 215.72606 5.449095) (xy 215.643584 5.472562)
			(xy 215.563625 5.503538) (xy 215.486865 5.54176) (xy 215.413959 5.586901) (xy 215.34553 5.638577)
			(xy 215.28216 5.696346) (xy 215.224391 5.759716) (xy 215.172715 5.828145) (xy 215.127574 5.901051)
			(xy 215.089352 5.977811) (xy 215.058376 6.05777) (xy 215.034909 6.140246) (xy 215.019153 6.224536)
			(xy 215.011241 6.309919) (xy 210.515975 6.309919) (xy 210.508063 6.224536) (xy 210.492307 6.140246)
			(xy 210.46884 6.05777) (xy 210.437864 5.977811) (xy 210.399642 5.901051) (xy 210.354501 5.828145)
			(xy 210.302825 5.759716) (xy 210.245056 5.696346) (xy 210.181686 5.638577) (xy 210.113257 5.586901)
			(xy 210.040351 5.54176) (xy 209.963591 5.503538) (xy 209.883632 5.472562) (xy 209.801156 5.449095)
			(xy 209.716866 5.433339) (xy 209.631483 5.425427) (xy 209.545733 5.425427) (xy 209.46035 5.433339)
			(xy 209.37606 5.449095) (xy 209.293584 5.472562) (xy 209.213625 5.503538) (xy 209.136865 5.54176)
			(xy 209.063959 5.586901) (xy 208.99553 5.638577) (xy 208.93216 5.696346) (xy 208.874391 5.759716)
			(xy 208.822715 5.828145) (xy 208.777574 5.901051) (xy 208.739352 5.977811) (xy 208.708376 6.05777)
			(xy 208.684909 6.140246) (xy 208.669153 6.224536) (xy 208.661241 6.309919) (xy 184.818528 6.309919)
			(xy 184.818528 5.632196) (xy 184.818024 5.60266) (xy 184.80998 5.544138) (xy 184.794043 5.487256)
			(xy 184.770508 5.433074) (xy 184.739815 5.382601) (xy 184.702535 5.336778) (xy 184.659363 5.296458)
			(xy 184.611103 5.262392) (xy 184.558653 5.235215) (xy 184.502992 5.215433) (xy 184.445155 5.203414)
			(xy 184.38622 5.199383) (xy 184.327285 5.203414) (xy 184.269448 5.215433) (xy 184.213787 5.235215)
			(xy 184.161337 5.262392) (xy 184.113077 5.296458) (xy 184.069905 5.336778) (xy 184.032625 5.382601)
			(xy 184.001932 5.433074) (xy 183.978397 5.487256) (xy 183.96246 5.544138) (xy 183.954416 5.60266)
			(xy 183.953912 5.632196) (xy 182.791278 5.632196) (xy 182.847365 5.604268) (xy 182.920271 5.559127)
			(xy 182.9887 5.507451) (xy 183.05207 5.449682) (xy 183.109839 5.386312) (xy 183.161515 5.317883)
			(xy 183.206656 5.244977) (xy 183.244878 5.168217) (xy 183.275854 5.088258) (xy 183.299321 5.005782)
			(xy 183.315077 4.921492) (xy 183.322989 4.836109) (xy 183.323484 4.793234) (xy 183.322989 4.750359)
			(xy 187.818255 4.750359) (xy 187.818255 4.836109) (xy 187.826167 4.921492) (xy 187.841923 5.005782)
			(xy 187.86539 5.088258) (xy 187.896366 5.168217) (xy 187.934588 5.244977) (xy 187.979729 5.317883)
			(xy 188.031405 5.386312) (xy 188.089174 5.449682) (xy 188.152544 5.507451) (xy 188.220973 5.559127)
			(xy 188.293879 5.604268) (xy 188.370639 5.64249) (xy 188.450598 5.673466) (xy 188.533074 5.696933)
			(xy 188.617364 5.712689) (xy 188.702747 5.720601) (xy 188.788497 5.720601) (xy 188.87388 5.712689)
			(xy 188.95817 5.696933) (xy 189.040646 5.673466) (xy 189.120605 5.64249) (xy 189.197365 5.604268)
			(xy 189.270271 5.559127) (xy 189.3387 5.507451) (xy 189.40207 5.449682) (xy 189.459839 5.386312)
			(xy 189.511515 5.317883) (xy 189.556656 5.244977) (xy 189.594878 5.168217) (xy 189.625854 5.088258)
			(xy 189.649321 5.005782) (xy 189.665077 4.921492) (xy 189.672989 4.836109) (xy 189.673484 4.793234)
			(xy 189.672989 4.750359) (xy 189.665077 4.664976) (xy 189.649321 4.580686) (xy 189.625854 4.49821)
			(xy 189.594878 4.418251) (xy 189.556656 4.341491) (xy 189.511515 4.268585) (xy 189.459839 4.200156)
			(xy 189.40207 4.136786) (xy 189.3387 4.079017) (xy 189.270271 4.027341) (xy 189.197365 3.9822) (xy 189.120605 3.943978)
			(xy 189.040646 3.913002) (xy 188.95817 3.889535) (xy 188.87388 3.873779) (xy 188.788497 3.865867)
			(xy 188.702747 3.865867) (xy 188.617364 3.873779) (xy 188.533074 3.889535) (xy 188.450598 3.913002)
			(xy 188.370639 3.943978) (xy 188.293879 3.9822) (xy 188.220973 4.027341) (xy 188.152544 4.079017)
			(xy 188.089174 4.136786) (xy 188.031405 4.200156) (xy 187.979729 4.268585) (xy 187.934588 4.341491)
			(xy 187.896366 4.418251) (xy 187.86539 4.49821) (xy 187.841923 4.580686) (xy 187.826167 4.664976)
			(xy 187.818255 4.750359) (xy 183.322989 4.750359) (xy 183.315077 4.664976) (xy 183.299321 4.580686)
			(xy 183.275854 4.49821) (xy 183.244878 4.418251) (xy 183.206656 4.341491) (xy 183.161515 4.268585)
			(xy 183.109839 4.200156) (xy 183.05207 4.136786) (xy 182.9887 4.079017) (xy 182.920271 4.027341)
			(xy 182.847365 3.9822) (xy 182.770605 3.943978) (xy 182.690646 3.913002) (xy 182.60817 3.889535)
			(xy 182.52388 3.873779) (xy 182.438497 3.865867) (xy 182.352747 3.865867) (xy 182.267364 3.873779)
			(xy 182.183074 3.889535) (xy 182.100598 3.913002) (xy 182.020639 3.943978) (xy 181.943879 3.9822)
			(xy 181.870973 4.027341) (xy 181.802544 4.079017) (xy 181.739174 4.136786) (xy 181.681405 4.200156)
			(xy 181.629729 4.268585) (xy 181.584588 4.341491) (xy 181.546366 4.418251) (xy 181.51539 4.49821)
			(xy 181.491923 4.580686) (xy 181.476167 4.664976) (xy 181.468255 4.750359) (xy 102.190309 4.750359)
			(xy 102.182397 4.664976) (xy 102.166641 4.580686) (xy 102.143174 4.49821) (xy 102.112198 4.418251)
			(xy 102.073976 4.341491) (xy 102.028835 4.268585) (xy 101.977159 4.200156) (xy 101.91939 4.136786)
			(xy 101.85602 4.079017) (xy 101.787591 4.027341) (xy 101.714685 3.9822) (xy 101.637925 3.943978)
			(xy 101.557966 3.913002) (xy 101.47549 3.889535) (xy 101.3912 3.873779) (xy 101.305817 3.865867)
			(xy 101.220067 3.865867) (xy 101.134684 3.873779) (xy 101.050394 3.889535) (xy 100.967918 3.913002)
			(xy 100.887959 3.943978) (xy 100.811199 3.9822) (xy 100.738293 4.027341) (xy 100.669864 4.079017)
			(xy 100.606494 4.136786) (xy 100.548725 4.200156) (xy 100.497049 4.268585) (xy 100.451908 4.341491)
			(xy 100.413686 4.418251) (xy 100.38271 4.49821) (xy 100.359243 4.580686) (xy 100.343487 4.664976)
			(xy 100.335575 4.750359) (xy 95.840309 4.750359) (xy 95.832397 4.664976) (xy 95.816641 4.580686)
			(xy 95.793174 4.49821) (xy 95.762198 4.418251) (xy 95.723976 4.341491) (xy 95.678835 4.268585) (xy 95.627159 4.200156)
			(xy 95.56939 4.136786) (xy 95.50602 4.079017) (xy 95.437591 4.027341) (xy 95.364685 3.9822) (xy 95.287925 3.943978)
			(xy 95.207966 3.913002) (xy 95.12549 3.889535) (xy 95.0412 3.873779) (xy 94.955817 3.865867) (xy 94.870067 3.865867)
			(xy 94.784684 3.873779) (xy 94.700394 3.889535) (xy 94.617918 3.913002) (xy 94.537959 3.943978) (xy 94.461199 3.9822)
			(xy 94.388293 4.027341) (xy 94.319864 4.079017) (xy 94.256494 4.136786) (xy 94.198725 4.200156) (xy 94.147049 4.268585)
			(xy 94.101908 4.341491) (xy 94.063686 4.418251) (xy 94.03271 4.49821) (xy 94.009243 4.580686) (xy 93.993487 4.664976)
			(xy 93.985575 4.750359) (xy 0.509016 4.750359) (xy 0.509016 -7.78002) (xy 0.509537 -7.835789) (xy 0.517873 -7.947015)
			(xy 0.534497 -8.057308) (xy 0.559316 -8.166049) (xy 0.592193 -8.272632) (xy 0.632942 -8.37646) (xy 0.681336 -8.476953)
			(xy 0.737105 -8.573548) (xy 0.799937 -8.665705) (xy 0.86948 -8.752909) (xy 0.945345 -8.834672) (xy 1.027108 -8.910538)
			(xy 1.114312 -8.980081) (xy 1.206469 -9.042912) (xy 1.303064 -9.098682) (xy 1.403556 -9.147076) (xy 1.507384 -9.187826)
			(xy 1.613967 -9.220703) (xy 1.722708 -9.245523) (xy 1.833001 -9.262147) (xy 1.944227 -9.270482) (xy 1.999996 -9.271)
			(xy 9.10209 -9.271) (xy 9.15786 -9.270479) (xy 9.269087 -9.262144) (xy 9.37938 -9.245521) (xy 9.488123 -9.220702)
			(xy 9.594707 -9.187826) (xy 9.698536 -9.147077) (xy 9.79903 -9.098683) (xy 9.895626 -9.042915) (xy 9.987784 -8.980083)
			(xy 10.07499 -8.910541) (xy 10.156754 -8.834676) (xy 10.232621 -8.752912) (xy 10.302165 -8.665708)
			(xy 10.364999 -8.573551) (xy 10.420769 -8.476956) (xy 10.469165 -8.376463) (xy 10.509916 -8.272635)
			(xy 10.542794 -8.166052) (xy 10.567616 -8.05731) (xy 10.584241 -7.947017) (xy 10.592578 -7.83579)
			(xy 10.59307 -7.78002) (xy 10.59307 0.40005) (xy 10.593555 0.470432) (xy 10.601447 0.610976) (xy 10.617208 0.750856)
			(xy 10.640787 0.889632) (xy 10.67211 1.026868) (xy 10.711079 1.162131) (xy 10.757571 1.294997) (xy 10.811439 1.425046)
			(xy 10.872515 1.551871) (xy 10.940606 1.675072) (xy 11.015497 1.794261) (xy 11.096954 1.909063) (xy 11.184719 2.019118)
			(xy 11.278518 2.124078) (xy 11.378053 2.223614) (xy 11.483014 2.317412) (xy 11.593068 2.405178) (xy 11.707871 2.486634)
			(xy 11.82706 2.561525) (xy 11.950261 2.629616) (xy 12.077085 2.690692) (xy 12.207135 2.74456) (xy 12.340001 2.791052)
			(xy 12.475264 2.83002) (xy 12.6125 2.861343) (xy 12.751276 2.884922) (xy 12.891156 2.900683) (xy 13.0317 2.908575)
			(xy 13.102082 2.909062) (xy 81.701894 2.909062) (xy 81.772277 2.908568) (xy 81.912821 2.900676) (xy 82.052702 2.884916)
			(xy 82.191479 2.861337) (xy 82.328715 2.830015) (xy 82.46398 2.791046) (xy 82.596846 2.744555) (xy 82.726897 2.690688)
			(xy 82.853723 2.629613) (xy 82.976925 2.561522) (xy 83.096116 2.486632) (xy 83.210919 2.405176) (xy 83.320975 2.317411)
			(xy 83.425937 2.223613) (xy 83.439191 2.210359) (xy 93.985575 2.210359) (xy 93.985575 2.296109) (xy 93.993487 2.381492)
			(xy 94.009243 2.465782) (xy 94.03271 2.548258) (xy 94.063686 2.628217) (xy 94.101908 2.704977) (xy 94.147049 2.777883)
			(xy 94.198725 2.846312) (xy 94.256494 2.909682) (xy 94.319864 2.967451) (xy 94.388293 3.019127) (xy 94.461199 3.064268)
			(xy 94.537959 3.10249) (xy 94.617918 3.133466) (xy 94.700394 3.156933) (xy 94.784684 3.172689) (xy 94.870067 3.180601)
			(xy 94.955817 3.180601) (xy 95.0412 3.172689) (xy 95.12549 3.156933) (xy 95.207966 3.133466) (xy 95.287925 3.10249)
			(xy 95.308598 3.092196) (xy 98.842576 3.092196) (xy 98.842576 3.955796) (xy 98.84308 3.985332) (xy 98.851124 4.043854)
			(xy 98.867061 4.100736) (xy 98.890596 4.154918) (xy 98.921289 4.205391) (xy 98.958569 4.251214) (xy 99.001741 4.291534)
			(xy 99.050001 4.3256) (xy 99.102451 4.352777) (xy 99.158112 4.372559) (xy 99.215949 4.384578) (xy 99.274884 4.388609)
			(xy 99.333819 4.384578) (xy 99.391656 4.372559) (xy 99.447317 4.352777) (xy 99.499767 4.3256) (xy 99.548027 4.291534)
			(xy 99.591199 4.251214) (xy 99.628479 4.205391) (xy 99.659172 4.154918) (xy 99.682707 4.100736) (xy 99.698644 4.043854)
			(xy 99.706688 3.985332) (xy 99.707192 3.955796) (xy 99.707192 3.092196) (xy 99.706688 3.06266) (xy 99.698644 3.004138)
			(xy 99.682707 2.947256) (xy 99.659172 2.893074) (xy 99.628479 2.842601) (xy 99.591199 2.796778) (xy 99.548027 2.756458)
			(xy 99.499767 2.722392) (xy 99.447317 2.695215) (xy 99.391656 2.675433) (xy 99.333819 2.663414) (xy 99.274884 2.659383)
			(xy 99.215949 2.663414) (xy 99.158112 2.675433) (xy 99.102451 2.695215) (xy 99.050001 2.722392) (xy 99.001741 2.756458)
			(xy 98.958569 2.796778) (xy 98.921289 2.842601) (xy 98.890596 2.893074) (xy 98.867061 2.947256) (xy 98.851124 3.004138)
			(xy 98.84308 3.06266) (xy 98.842576 3.092196) (xy 95.308598 3.092196) (xy 95.364685 3.064268) (xy 95.437591 3.019127)
			(xy 95.50602 2.967451) (xy 95.56939 2.909682) (xy 95.627159 2.846312) (xy 95.678835 2.777883) (xy 95.723976 2.704977)
			(xy 95.762198 2.628217) (xy 95.793174 2.548258) (xy 95.816641 2.465782) (xy 95.832397 2.381492) (xy 95.840309 2.296109)
			(xy 95.840804 2.253234) (xy 95.840309 2.210359) (xy 100.335575 2.210359) (xy 100.335575 2.296109)
			(xy 100.343487 2.381492) (xy 100.359243 2.465782) (xy 100.38271 2.548258) (xy 100.413686 2.628217)
			(xy 100.451908 2.704977) (xy 100.497049 2.777883) (xy 100.548725 2.846312) (xy 100.606494 2.909682)
			(xy 100.669864 2.967451) (xy 100.738293 3.019127) (xy 100.811199 3.064268) (xy 100.887959 3.10249)
			(xy 100.967918 3.133466) (xy 101.050394 3.156933) (xy 101.134684 3.172689) (xy 101.220067 3.180601)
			(xy 101.305817 3.180601) (xy 101.3912 3.172689) (xy 101.47549 3.156933) (xy 101.557966 3.133466)
			(xy 101.637925 3.10249) (xy 101.714685 3.064268) (xy 101.787591 3.019127) (xy 101.85602 2.967451)
			(xy 101.91939 2.909682) (xy 101.977159 2.846312) (xy 102.028835 2.777883) (xy 102.073976 2.704977)
			(xy 102.112198 2.628217) (xy 102.143174 2.548258) (xy 102.166641 2.465782) (xy 102.182397 2.381492)
			(xy 102.190309 2.296109) (xy 102.190804 2.253234) (xy 102.190309 2.210359) (xy 181.468255 2.210359)
			(xy 181.468255 2.296109) (xy 181.476167 2.381492) (xy 181.491923 2.465782) (xy 181.51539 2.548258)
			(xy 181.546366 2.628217) (xy 181.584588 2.704977) (xy 181.629729 2.777883) (xy 181.681405 2.846312)
			(xy 181.739174 2.909682) (xy 181.802544 2.967451) (xy 181.870973 3.019127) (xy 181.943879 3.064268)
			(xy 182.020639 3.10249) (xy 182.100598 3.133466) (xy 182.183074 3.156933) (xy 182.267364 3.172689)
			(xy 182.352747 3.180601) (xy 182.438497 3.180601) (xy 182.52388 3.172689) (xy 182.60817 3.156933)
			(xy 182.690646 3.133466) (xy 182.770605 3.10249) (xy 182.791278 3.092196) (xy 183.953912 3.092196)
			(xy 183.953912 3.955796) (xy 183.954416 3.985332) (xy 183.96246 4.043854) (xy 183.978397 4.100736)
			(xy 184.001932 4.154918) (xy 184.032625 4.205391) (xy 184.069905 4.251214) (xy 184.113077 4.291534)
			(xy 184.161337 4.3256) (xy 184.213787 4.352777) (xy 184.269448 4.372559) (xy 184.327285 4.384578)
			(xy 184.38622 4.388609) (xy 184.445155 4.384578) (xy 184.502992 4.372559) (xy 184.558653 4.352777)
			(xy 184.611103 4.3256) (xy 184.659363 4.291534) (xy 184.702535 4.251214) (xy 184.739815 4.205391)
			(xy 184.770508 4.154918) (xy 184.794043 4.100736) (xy 184.80998 4.043854) (xy 184.818024 3.985332)
			(xy 184.818528 3.955796) (xy 184.818528 3.769919) (xy 208.661241 3.769919) (xy 208.661241 3.855669)
			(xy 208.669153 3.941052) (xy 208.684909 4.025342) (xy 208.708376 4.107818) (xy 208.739352 4.187777)
			(xy 208.777574 4.264537) (xy 208.822715 4.337443) (xy 208.874391 4.405872) (xy 208.93216 4.469242)
			(xy 208.99553 4.527011) (xy 209.063959 4.578687) (xy 209.136865 4.623828) (xy 209.213625 4.66205)
			(xy 209.293584 4.693026) (xy 209.37606 4.716493) (xy 209.46035 4.732249) (xy 209.545733 4.740161)
			(xy 209.631483 4.740161) (xy 209.716866 4.732249) (xy 209.801156 4.716493) (xy 209.883632 4.693026)
			(xy 209.963591 4.66205) (xy 209.984264 4.651756) (xy 213.517988 4.651756) (xy 213.517988 5.515356)
			(xy 213.518492 5.54491) (xy 213.526541 5.603466) (xy 213.542487 5.660381) (xy 213.566036 5.714595)
			(xy 213.596747 5.765098) (xy 213.634049 5.810948) (xy 213.677246 5.851291) (xy 213.725535 5.885377)
			(xy 213.778015 5.91257) (xy 213.83371 5.932364) (xy 213.891581 5.94439) (xy 213.95055 5.948424) (xy 214.009519 5.94439)
			(xy 214.06739 5.932364) (xy 214.123085 5.91257) (xy 214.175565 5.885377) (xy 214.223854 5.851291)
			(xy 214.267051 5.810948) (xy 214.304353 5.765098) (xy 214.335064 5.714595) (xy 214.358613 5.660381)
			(xy 214.374559 5.603466) (xy 214.382608 5.54491) (xy 214.383112 5.515356) (xy 214.383112 4.651756)
			(xy 214.382608 4.622202) (xy 214.374559 4.563646) (xy 214.358613 4.506731) (xy 214.335064 4.452517)
			(xy 214.304353 4.402014) (xy 214.267051 4.356164) (xy 214.223854 4.315821) (xy 214.175565 4.281735)
			(xy 214.123085 4.254542) (xy 214.06739 4.234748) (xy 214.009519 4.222722) (xy 213.95055 4.218689)
			(xy 213.891581 4.222722) (xy 213.83371 4.234748) (xy 213.778015 4.254542) (xy 213.725535 4.281735)
			(xy 213.677246 4.315821) (xy 213.634049 4.356164) (xy 213.596747 4.402014) (xy 213.566036 4.452517)
			(xy 213.542487 4.506731) (xy 213.526541 4.563646) (xy 213.518492 4.622202) (xy 213.517988 4.651756)
			(xy 209.984264 4.651756) (xy 210.040351 4.623828) (xy 210.113257 4.578687) (xy 210.181686 4.527011)
			(xy 210.245056 4.469242) (xy 210.302825 4.405872) (xy 210.354501 4.337443) (xy 210.399642 4.264537)
			(xy 210.437864 4.187777) (xy 210.46884 4.107818) (xy 210.492307 4.025342) (xy 210.508063 3.941052)
			(xy 210.515975 3.855669) (xy 210.51647 3.812794) (xy 210.515975 3.769919) (xy 215.011241 3.769919)
			(xy 215.011241 3.855669) (xy 215.019153 3.941052) (xy 215.034909 4.025342) (xy 215.058376 4.107818)
			(xy 215.089352 4.187777) (xy 215.127574 4.264537) (xy 215.172715 4.337443) (xy 215.224391 4.405872)
			(xy 215.28216 4.469242) (xy 215.34553 4.527011) (xy 215.413959 4.578687) (xy 215.486865 4.623828)
			(xy 215.563625 4.66205) (xy 215.643584 4.693026) (xy 215.72606 4.716493) (xy 215.81035 4.732249)
			(xy 215.895733 4.740161) (xy 215.981483 4.740161) (xy 216.066866 4.732249) (xy 216.151156 4.716493)
			(xy 216.233632 4.693026) (xy 216.313591 4.66205) (xy 216.390351 4.623828) (xy 216.463257 4.578687)
			(xy 216.531686 4.527011) (xy 216.595056 4.469242) (xy 216.652825 4.405872) (xy 216.704501 4.337443)
			(xy 216.749642 4.264537) (xy 216.787864 4.187777) (xy 216.81884 4.107818) (xy 216.842307 4.025342)
			(xy 216.858063 3.941052) (xy 216.865975 3.855669) (xy 216.86647 3.812794) (xy 216.865975 3.769919)
			(xy 296.143921 3.769919) (xy 296.143921 3.855669) (xy 296.151833 3.941052) (xy 296.167589 4.025342)
			(xy 296.191056 4.107818) (xy 296.222032 4.187777) (xy 296.260254 4.264537) (xy 296.305395 4.337443)
			(xy 296.357071 4.405872) (xy 296.41484 4.469242) (xy 296.47821 4.527011) (xy 296.546639 4.578687)
			(xy 296.619545 4.623828) (xy 296.696305 4.66205) (xy 296.776264 4.693026) (xy 296.85874 4.716493)
			(xy 296.94303 4.732249) (xy 297.028413 4.740161) (xy 297.114163 4.740161) (xy 297.199546 4.732249)
			(xy 297.283836 4.716493) (xy 297.366312 4.693026) (xy 297.446271 4.66205) (xy 297.466944 4.651756)
			(xy 298.629324 4.651756) (xy 298.629324 5.515356) (xy 298.629828 5.54491) (xy 298.637877 5.603466)
			(xy 298.653823 5.660381) (xy 298.677372 5.714595) (xy 298.708083 5.765098) (xy 298.745385 5.810948)
			(xy 298.788582 5.851291) (xy 298.836871 5.885377) (xy 298.889351 5.91257) (xy 298.945046 5.932364)
			(xy 299.002917 5.94439) (xy 299.061886 5.948424) (xy 299.120855 5.94439) (xy 299.178726 5.932364)
			(xy 299.234421 5.91257) (xy 299.286901 5.885377) (xy 299.33519 5.851291) (xy 299.378387 5.810948)
			(xy 299.415689 5.765098) (xy 299.4464 5.714595) (xy 299.469949 5.660381) (xy 299.485895 5.603466)
			(xy 299.493944 5.54491) (xy 299.494448 5.515356) (xy 299.494448 4.651756) (xy 299.493944 4.622202)
			(xy 299.485895 4.563646) (xy 299.469949 4.506731) (xy 299.4464 4.452517) (xy 299.415689 4.402014)
			(xy 299.378387 4.356164) (xy 299.33519 4.315821) (xy 299.286901 4.281735) (xy 299.234421 4.254542)
			(xy 299.178726 4.234748) (xy 299.120855 4.222722) (xy 299.061886 4.218689) (xy 299.002917 4.222722)
			(xy 298.945046 4.234748) (xy 298.889351 4.254542) (xy 298.836871 4.281735) (xy 298.788582 4.315821)
			(xy 298.745385 4.356164) (xy 298.708083 4.402014) (xy 298.677372 4.452517) (xy 298.653823 4.506731)
			(xy 298.637877 4.563646) (xy 298.629828 4.622202) (xy 298.629324 4.651756) (xy 297.466944 4.651756)
			(xy 297.523031 4.623828) (xy 297.595937 4.578687) (xy 297.664366 4.527011) (xy 297.727736 4.469242)
			(xy 297.785505 4.405872) (xy 297.837181 4.337443) (xy 297.882322 4.264537) (xy 297.920544 4.187777)
			(xy 297.95152 4.107818) (xy 297.974987 4.025342) (xy 297.990743 3.941052) (xy 297.998655 3.855669)
			(xy 297.99915 3.812794) (xy 297.998655 3.769919) (xy 302.493921 3.769919) (xy 302.493921 3.855669)
			(xy 302.501833 3.941052) (xy 302.517589 4.025342) (xy 302.541056 4.107818) (xy 302.572032 4.187777)
			(xy 302.610254 4.264537) (xy 302.655395 4.337443) (xy 302.707071 4.405872) (xy 302.76484 4.469242)
			(xy 302.82821 4.527011) (xy 302.896639 4.578687) (xy 302.969545 4.623828) (xy 303.046305 4.66205)
			(xy 303.126264 4.693026) (xy 303.20874 4.716493) (xy 303.29303 4.732249) (xy 303.378413 4.740161)
			(xy 303.464163 4.740161) (xy 303.549546 4.732249) (xy 303.633836 4.716493) (xy 303.716312 4.693026)
			(xy 303.796271 4.66205) (xy 303.873031 4.623828) (xy 303.945937 4.578687) (xy 304.014366 4.527011)
			(xy 304.077736 4.469242) (xy 304.135505 4.405872) (xy 304.187181 4.337443) (xy 304.232322 4.264537)
			(xy 304.270544 4.187777) (xy 304.30152 4.107818) (xy 304.324987 4.025342) (xy 304.340743 3.941052)
			(xy 304.348655 3.855669) (xy 304.34915 3.812794) (xy 304.348655 3.769919) (xy 311.155321 3.769919)
			(xy 311.155321 3.855669) (xy 311.163233 3.941052) (xy 311.178989 4.025342) (xy 311.202456 4.107818)
			(xy 311.233432 4.187777) (xy 311.271654 4.264537) (xy 311.316795 4.337443) (xy 311.368471 4.405872)
			(xy 311.42624 4.469242) (xy 311.48961 4.527011) (xy 311.558039 4.578687) (xy 311.630945 4.623828)
			(xy 311.707705 4.66205) (xy 311.787664 4.693026) (xy 311.87014 4.716493) (xy 311.95443 4.732249)
			(xy 312.039813 4.740161) (xy 312.125563 4.740161) (xy 312.210946 4.732249) (xy 312.295236 4.716493)
			(xy 312.377712 4.693026) (xy 312.457671 4.66205) (xy 312.478344 4.651756) (xy 316.012068 4.651756)
			(xy 316.012068 5.515356) (xy 316.012572 5.54491) (xy 316.020621 5.603466) (xy 316.036567 5.660381)
			(xy 316.060116 5.714595) (xy 316.090827 5.765098) (xy 316.128129 5.810948) (xy 316.171326 5.851291)
			(xy 316.219615 5.885377) (xy 316.272095 5.91257) (xy 316.32779 5.932364) (xy 316.385661 5.94439)
			(xy 316.44463 5.948424) (xy 316.503599 5.94439) (xy 316.56147 5.932364) (xy 316.617165 5.91257) (xy 316.669645 5.885377)
			(xy 316.717934 5.851291) (xy 316.761131 5.810948) (xy 316.798433 5.765098) (xy 316.829144 5.714595)
			(xy 316.852693 5.660381) (xy 316.868639 5.603466) (xy 316.876688 5.54491) (xy 316.877192 5.515356)
			(xy 316.877192 4.651756) (xy 316.876688 4.622202) (xy 316.868639 4.563646) (xy 316.852693 4.506731)
			(xy 316.829144 4.452517) (xy 316.798433 4.402014) (xy 316.761131 4.356164) (xy 316.717934 4.315821)
			(xy 316.669645 4.281735) (xy 316.617165 4.254542) (xy 316.56147 4.234748) (xy 316.503599 4.222722)
			(xy 316.44463 4.218689) (xy 316.385661 4.222722) (xy 316.32779 4.234748) (xy 316.272095 4.254542)
			(xy 316.219615 4.281735) (xy 316.171326 4.315821) (xy 316.128129 4.356164) (xy 316.090827 4.402014)
			(xy 316.060116 4.452517) (xy 316.036567 4.506731) (xy 316.020621 4.563646) (xy 316.012572 4.622202)
			(xy 316.012068 4.651756) (xy 312.478344 4.651756) (xy 312.534431 4.623828) (xy 312.607337 4.578687)
			(xy 312.675766 4.527011) (xy 312.739136 4.469242) (xy 312.796905 4.405872) (xy 312.848581 4.337443)
			(xy 312.893722 4.264537) (xy 312.931944 4.187777) (xy 312.96292 4.107818) (xy 312.986387 4.025342)
			(xy 313.002143 3.941052) (xy 313.010055 3.855669) (xy 313.01055 3.812794) (xy 313.010055 3.769919)
			(xy 317.505321 3.769919) (xy 317.505321 3.855669) (xy 317.513233 3.941052) (xy 317.528989 4.025342)
			(xy 317.552456 4.107818) (xy 317.583432 4.187777) (xy 317.621654 4.264537) (xy 317.666795 4.337443)
			(xy 317.718471 4.405872) (xy 317.77624 4.469242) (xy 317.83961 4.527011) (xy 317.908039 4.578687)
			(xy 317.980945 4.623828) (xy 318.057705 4.66205) (xy 318.137664 4.693026) (xy 318.22014 4.716493)
			(xy 318.30443 4.732249) (xy 318.389813 4.740161) (xy 318.475563 4.740161) (xy 318.560946 4.732249)
			(xy 318.645236 4.716493) (xy 318.727712 4.693026) (xy 318.807671 4.66205) (xy 318.884431 4.623828)
			(xy 318.957337 4.578687) (xy 319.025766 4.527011) (xy 319.089136 4.469242) (xy 319.146905 4.405872)
			(xy 319.198581 4.337443) (xy 319.243722 4.264537) (xy 319.281944 4.187777) (xy 319.31292 4.107818)
			(xy 319.336387 4.025342) (xy 319.352143 3.941052) (xy 319.360055 3.855669) (xy 319.36055 3.812794)
			(xy 319.360055 3.769919) (xy 361.894107 3.769919) (xy 361.894107 3.855669) (xy 361.902019 3.941052)
			(xy 361.917775 4.025342) (xy 361.941242 4.107818) (xy 361.972218 4.187777) (xy 362.01044 4.264537)
			(xy 362.055581 4.337443) (xy 362.107257 4.405872) (xy 362.165026 4.469242) (xy 362.228396 4.527011)
			(xy 362.296825 4.578687) (xy 362.369731 4.623828) (xy 362.446491 4.66205) (xy 362.52645 4.693026)
			(xy 362.608926 4.716493) (xy 362.693216 4.732249) (xy 362.778599 4.740161) (xy 362.864349 4.740161)
			(xy 362.949732 4.732249) (xy 363.034022 4.716493) (xy 363.116498 4.693026) (xy 363.196457 4.66205)
			(xy 363.21713 4.651756) (xy 364.379764 4.651756) (xy 364.379764 5.515356) (xy 364.380268 5.544892)
			(xy 364.388312 5.603414) (xy 364.404249 5.660296) (xy 364.427784 5.714478) (xy 364.458477 5.764951)
			(xy 364.495757 5.810774) (xy 364.538929 5.851094) (xy 364.587189 5.88516) (xy 364.639639 5.912337)
			(xy 364.6953 5.932119) (xy 364.753137 5.944138) (xy 364.812072 5.948169) (xy 364.871007 5.944138)
			(xy 364.928844 5.932119) (xy 364.984505 5.912337) (xy 365.036955 5.88516) (xy 365.085215 5.851094)
			(xy 365.128387 5.810774) (xy 365.165667 5.764951) (xy 365.19636 5.714478) (xy 365.219895 5.660296)
			(xy 365.235832 5.603414) (xy 365.243876 5.544892) (xy 365.24438 5.515356) (xy 365.24438 4.836973)
			(xy 385.651997 4.836973) (xy 385.651997 4.922723) (xy 385.659909 5.008106) (xy 385.675665 5.092396)
			(xy 385.699132 5.174872) (xy 385.730108 5.254831) (xy 385.76833 5.331591) (xy 385.813471 5.404497)
			(xy 385.865147 5.472926) (xy 385.922916 5.536296) (xy 385.986286 5.594065) (xy 386.054715 5.645741)
			(xy 386.127621 5.690882) (xy 386.204381 5.729104) (xy 386.28434 5.76008) (xy 386.366816 5.783547)
			(xy 386.451106 5.799303) (xy 386.536489 5.807215) (xy 386.622239 5.807215) (xy 386.707622 5.799303)
			(xy 386.791912 5.783547) (xy 386.874388 5.76008) (xy 386.954347 5.729104) (xy 386.97502 5.71881)
			(xy 390.508744 5.71881) (xy 390.508744 6.58241) (xy 390.509248 6.611964) (xy 390.517297 6.67052)
			(xy 390.533243 6.727435) (xy 390.556792 6.781649) (xy 390.587503 6.832152) (xy 390.624805 6.878002)
			(xy 390.668002 6.918345) (xy 390.716291 6.952431) (xy 390.768771 6.979624) (xy 390.824466 6.999418)
			(xy 390.882337 7.011444) (xy 390.941306 7.015478) (xy 391.000275 7.011444) (xy 391.058146 6.999418)
			(xy 391.113841 6.979624) (xy 391.166321 6.952431) (xy 391.21461 6.918345) (xy 391.257807 6.878002)
			(xy 391.295109 6.832152) (xy 391.32582 6.781649) (xy 391.349369 6.727435) (xy 391.365315 6.67052)
			(xy 391.373364 6.611964) (xy 391.373868 6.58241) (xy 391.373868 5.71881) (xy 391.373364 5.689256)
			(xy 391.365315 5.6307) (xy 391.349369 5.573785) (xy 391.32582 5.519571) (xy 391.295109 5.469068)
			(xy 391.257807 5.423218) (xy 391.21461 5.382875) (xy 391.166321 5.348789) (xy 391.113841 5.321596)
			(xy 391.058146 5.301802) (xy 391.000275 5.289776) (xy 390.941306 5.285743) (xy 390.882337 5.289776)
			(xy 390.824466 5.301802) (xy 390.768771 5.321596) (xy 390.716291 5.348789) (xy 390.668002 5.382875)
			(xy 390.624805 5.423218) (xy 390.587503 5.469068) (xy 390.556792 5.519571) (xy 390.533243 5.573785)
			(xy 390.517297 5.6307) (xy 390.509248 5.689256) (xy 390.508744 5.71881) (xy 386.97502 5.71881) (xy 387.031107 5.690882)
			(xy 387.104013 5.645741) (xy 387.172442 5.594065) (xy 387.235812 5.536296) (xy 387.293581 5.472926)
			(xy 387.345257 5.404497) (xy 387.390398 5.331591) (xy 387.42862 5.254831) (xy 387.459596 5.174872)
			(xy 387.483063 5.092396) (xy 387.498819 5.008106) (xy 387.506731 4.922723) (xy 387.507226 4.879848)
			(xy 387.506731 4.836973) (xy 392.001997 4.836973) (xy 392.001997 4.922723) (xy 392.009909 5.008106)
			(xy 392.025665 5.092396) (xy 392.049132 5.174872) (xy 392.080108 5.254831) (xy 392.11833 5.331591)
			(xy 392.163471 5.404497) (xy 392.215147 5.472926) (xy 392.272916 5.536296) (xy 392.336286 5.594065)
			(xy 392.404715 5.645741) (xy 392.477621 5.690882) (xy 392.554381 5.729104) (xy 392.63434 5.76008)
			(xy 392.716816 5.783547) (xy 392.801106 5.799303) (xy 392.886489 5.807215) (xy 392.972239 5.807215)
			(xy 393.057622 5.799303) (xy 393.141912 5.783547) (xy 393.224388 5.76008) (xy 393.304347 5.729104)
			(xy 393.381107 5.690882) (xy 393.454013 5.645741) (xy 393.522442 5.594065) (xy 393.585812 5.536296)
			(xy 393.643581 5.472926) (xy 393.695257 5.404497) (xy 393.740398 5.331591) (xy 393.77862 5.254831)
			(xy 393.809596 5.174872) (xy 393.833063 5.092396) (xy 393.848819 5.008106) (xy 393.856731 4.922723)
			(xy 393.857226 4.879848) (xy 393.856731 4.836973) (xy 436.390783 4.836973) (xy 436.390783 4.922723)
			(xy 436.398695 5.008106) (xy 436.414451 5.092396) (xy 436.437918 5.174872) (xy 436.468894 5.254831)
			(xy 436.507116 5.331591) (xy 436.552257 5.404497) (xy 436.603933 5.472926) (xy 436.661702 5.536296)
			(xy 436.725072 5.594065) (xy 436.793501 5.645741) (xy 436.866407 5.690882) (xy 436.943167 5.729104)
			(xy 437.023126 5.76008) (xy 437.105602 5.783547) (xy 437.189892 5.799303) (xy 437.275275 5.807215)
			(xy 437.361025 5.807215) (xy 437.446408 5.799303) (xy 437.530698 5.783547) (xy 437.613174 5.76008)
			(xy 437.693133 5.729104) (xy 437.713806 5.71881) (xy 438.87644 5.71881) (xy 438.87644 6.58241) (xy 438.876944 6.611946)
			(xy 438.884988 6.670468) (xy 438.900925 6.72735) (xy 438.92446 6.781532) (xy 438.955153 6.832005)
			(xy 438.992433 6.877828) (xy 439.035605 6.918148) (xy 439.083865 6.952214) (xy 439.136315 6.979391)
			(xy 439.191976 6.999173) (xy 439.249813 7.011192) (xy 439.308748 7.015223) (xy 439.367683 7.011192)
			(xy 439.42552 6.999173) (xy 439.481181 6.979391) (xy 439.533631 6.952214) (xy 439.581891 6.918148)
			(xy 439.625063 6.877828) (xy 439.662343 6.832005) (xy 439.693036 6.781532) (xy 439.716571 6.72735)
			(xy 439.732508 6.670468) (xy 439.740552 6.611946) (xy 439.741056 6.58241) (xy 439.741056 5.71881)
			(xy 439.740552 5.689274) (xy 439.732508 5.630752) (xy 439.716571 5.57387) (xy 439.693036 5.519688)
			(xy 439.662343 5.469215) (xy 439.625063 5.423392) (xy 439.581891 5.383072) (xy 439.533631 5.349006)
			(xy 439.481181 5.321829) (xy 439.42552 5.302047) (xy 439.367683 5.290028) (xy 439.308748 5.285997)
			(xy 439.249813 5.290028) (xy 439.191976 5.302047) (xy 439.136315 5.321829) (xy 439.083865 5.349006)
			(xy 439.035605 5.383072) (xy 438.992433 5.423392) (xy 438.955153 5.469215) (xy 438.92446 5.519688)
			(xy 438.900925 5.57387) (xy 438.884988 5.630752) (xy 438.876944 5.689274) (xy 438.87644 5.71881)
			(xy 437.713806 5.71881) (xy 437.769893 5.690882) (xy 437.842799 5.645741) (xy 437.911228 5.594065)
			(xy 437.974598 5.536296) (xy 438.032367 5.472926) (xy 438.084043 5.404497) (xy 438.129184 5.331591)
			(xy 438.167406 5.254831) (xy 438.198382 5.174872) (xy 438.221849 5.092396) (xy 438.237605 5.008106)
			(xy 438.245517 4.922723) (xy 438.246012 4.879848) (xy 438.245517 4.836973) (xy 442.740783 4.836973)
			(xy 442.740783 4.922723) (xy 442.748695 5.008106) (xy 442.764451 5.092396) (xy 442.787918 5.174872)
			(xy 442.818894 5.254831) (xy 442.857116 5.331591) (xy 442.902257 5.404497) (xy 442.953933 5.472926)
			(xy 443.011702 5.536296) (xy 443.075072 5.594065) (xy 443.143501 5.645741) (xy 443.216407 5.690882)
			(xy 443.293167 5.729104) (xy 443.373126 5.76008) (xy 443.455602 5.783547) (xy 443.539892 5.799303)
			(xy 443.625275 5.807215) (xy 443.711025 5.807215) (xy 443.796408 5.799303) (xy 443.880698 5.783547)
			(xy 443.963174 5.76008) (xy 444.043133 5.729104) (xy 444.119893 5.690882) (xy 444.192799 5.645741)
			(xy 444.261228 5.594065) (xy 444.324598 5.536296) (xy 444.382367 5.472926) (xy 444.434043 5.404497)
			(xy 444.479184 5.331591) (xy 444.517406 5.254831) (xy 444.548382 5.174872) (xy 444.571849 5.092396)
			(xy 444.587605 5.008106) (xy 444.595517 4.922723) (xy 444.596012 4.879848) (xy 444.595517 4.836973)
			(xy 444.587605 4.75159) (xy 444.571849 4.6673) (xy 444.548382 4.584824) (xy 444.517406 4.504865)
			(xy 444.479184 4.428105) (xy 444.434043 4.355199) (xy 444.382367 4.28677) (xy 444.324598 4.2234)
			(xy 444.261228 4.165631) (xy 444.192799 4.113955) (xy 444.119893 4.068814) (xy 444.043133 4.030592)
			(xy 443.963174 3.999616) (xy 443.880698 3.976149) (xy 443.796408 3.960393) (xy 443.711025 3.952481)
			(xy 443.625275 3.952481) (xy 443.539892 3.960393) (xy 443.455602 3.976149) (xy 443.373126 3.999616)
			(xy 443.293167 4.030592) (xy 443.216407 4.068814) (xy 443.143501 4.113955) (xy 443.075072 4.165631)
			(xy 443.011702 4.2234) (xy 442.953933 4.28677) (xy 442.902257 4.355199) (xy 442.857116 4.428105)
			(xy 442.818894 4.504865) (xy 442.787918 4.584824) (xy 442.764451 4.6673) (xy 442.748695 4.75159)
			(xy 442.740783 4.836973) (xy 438.245517 4.836973) (xy 438.237605 4.75159) (xy 438.221849 4.6673)
			(xy 438.198382 4.584824) (xy 438.167406 4.504865) (xy 438.129184 4.428105) (xy 438.084043 4.355199)
			(xy 438.032367 4.28677) (xy 437.974598 4.2234) (xy 437.911228 4.165631) (xy 437.842799 4.113955)
			(xy 437.769893 4.068814) (xy 437.693133 4.030592) (xy 437.613174 3.999616) (xy 437.530698 3.976149)
			(xy 437.446408 3.960393) (xy 437.361025 3.952481) (xy 437.275275 3.952481) (xy 437.189892 3.960393)
			(xy 437.105602 3.976149) (xy 437.023126 3.999616) (xy 436.943167 4.030592) (xy 436.866407 4.068814)
			(xy 436.793501 4.113955) (xy 436.725072 4.165631) (xy 436.661702 4.2234) (xy 436.603933 4.28677)
			(xy 436.552257 4.355199) (xy 436.507116 4.428105) (xy 436.468894 4.504865) (xy 436.437918 4.584824)
			(xy 436.414451 4.6673) (xy 436.398695 4.75159) (xy 436.390783 4.836973) (xy 393.856731 4.836973)
			(xy 393.848819 4.75159) (xy 393.833063 4.6673) (xy 393.809596 4.584824) (xy 393.77862 4.504865) (xy 393.740398 4.428105)
			(xy 393.695257 4.355199) (xy 393.643581 4.28677) (xy 393.585812 4.2234) (xy 393.522442 4.165631)
			(xy 393.454013 4.113955) (xy 393.381107 4.068814) (xy 393.304347 4.030592) (xy 393.224388 3.999616)
			(xy 393.141912 3.976149) (xy 393.057622 3.960393) (xy 392.972239 3.952481) (xy 392.886489 3.952481)
			(xy 392.801106 3.960393) (xy 392.716816 3.976149) (xy 392.63434 3.999616) (xy 392.554381 4.030592)
			(xy 392.477621 4.068814) (xy 392.404715 4.113955) (xy 392.336286 4.165631) (xy 392.272916 4.2234)
			(xy 392.215147 4.28677) (xy 392.163471 4.355199) (xy 392.11833 4.428105) (xy 392.080108 4.504865)
			(xy 392.049132 4.584824) (xy 392.025665 4.6673) (xy 392.009909 4.75159) (xy 392.001997 4.836973)
			(xy 387.506731 4.836973) (xy 387.498819 4.75159) (xy 387.483063 4.6673) (xy 387.459596 4.584824)
			(xy 387.42862 4.504865) (xy 387.390398 4.428105) (xy 387.345257 4.355199) (xy 387.293581 4.28677)
			(xy 387.235812 4.2234) (xy 387.172442 4.165631) (xy 387.104013 4.113955) (xy 387.031107 4.068814)
			(xy 386.954347 4.030592) (xy 386.874388 3.999616) (xy 386.791912 3.976149) (xy 386.707622 3.960393)
			(xy 386.622239 3.952481) (xy 386.536489 3.952481) (xy 386.451106 3.960393) (xy 386.366816 3.976149)
			(xy 386.28434 3.999616) (xy 386.204381 4.030592) (xy 386.127621 4.068814) (xy 386.054715 4.113955)
			(xy 385.986286 4.165631) (xy 385.922916 4.2234) (xy 385.865147 4.28677) (xy 385.813471 4.355199)
			(xy 385.76833 4.428105) (xy 385.730108 4.504865) (xy 385.699132 4.584824) (xy 385.675665 4.6673)
			(xy 385.659909 4.75159) (xy 385.651997 4.836973) (xy 365.24438 4.836973) (xy 365.24438 4.651756)
			(xy 365.243876 4.62222) (xy 365.235832 4.563698) (xy 365.219895 4.506816) (xy 365.19636 4.452634)
			(xy 365.165667 4.402161) (xy 365.128387 4.356338) (xy 365.085215 4.316018) (xy 365.036955 4.281952)
			(xy 364.984505 4.254775) (xy 364.928844 4.234993) (xy 364.871007 4.222974) (xy 364.812072 4.218943)
			(xy 364.753137 4.222974) (xy 364.6953 4.234993) (xy 364.639639 4.254775) (xy 364.587189 4.281952)
			(xy 364.538929 4.316018) (xy 364.495757 4.356338) (xy 364.458477 4.402161) (xy 364.427784 4.452634)
			(xy 364.404249 4.506816) (xy 364.388312 4.563698) (xy 364.380268 4.62222) (xy 364.379764 4.651756)
			(xy 363.21713 4.651756) (xy 363.273217 4.623828) (xy 363.346123 4.578687) (xy 363.414552 4.527011)
			(xy 363.477922 4.469242) (xy 363.535691 4.405872) (xy 363.587367 4.337443) (xy 363.632508 4.264537)
			(xy 363.67073 4.187777) (xy 363.701706 4.107818) (xy 363.725173 4.025342) (xy 363.740929 3.941052)
			(xy 363.748841 3.855669) (xy 363.749336 3.812794) (xy 363.748841 3.769919) (xy 368.244107 3.769919)
			(xy 368.244107 3.855669) (xy 368.252019 3.941052) (xy 368.267775 4.025342) (xy 368.291242 4.107818)
			(xy 368.322218 4.187777) (xy 368.36044 4.264537) (xy 368.405581 4.337443) (xy 368.457257 4.405872)
			(xy 368.515026 4.469242) (xy 368.578396 4.527011) (xy 368.646825 4.578687) (xy 368.719731 4.623828)
			(xy 368.796491 4.66205) (xy 368.87645 4.693026) (xy 368.958926 4.716493) (xy 369.043216 4.732249)
			(xy 369.128599 4.740161) (xy 369.214349 4.740161) (xy 369.299732 4.732249) (xy 369.384022 4.716493)
			(xy 369.466498 4.693026) (xy 369.546457 4.66205) (xy 369.623217 4.623828) (xy 369.696123 4.578687)
			(xy 369.764552 4.527011) (xy 369.827922 4.469242) (xy 369.885691 4.405872) (xy 369.937367 4.337443)
			(xy 369.982508 4.264537) (xy 370.02073 4.187777) (xy 370.051706 4.107818) (xy 370.075173 4.025342)
			(xy 370.090929 3.941052) (xy 370.098841 3.855669) (xy 370.099336 3.812794) (xy 370.098841 3.769919)
			(xy 370.090929 3.684536) (xy 370.075173 3.600246) (xy 370.051706 3.51777) (xy 370.02073 3.437811)
			(xy 369.982508 3.361051) (xy 369.937367 3.288145) (xy 369.885691 3.219716) (xy 369.827922 3.156346)
			(xy 369.764552 3.098577) (xy 369.696123 3.046901) (xy 369.623217 3.00176) (xy 369.546457 2.963538)
			(xy 369.466498 2.932562) (xy 369.384022 2.909095) (xy 369.299732 2.893339) (xy 369.214349 2.885427)
			(xy 369.128599 2.885427) (xy 369.043216 2.893339) (xy 368.958926 2.909095) (xy 368.87645 2.932562)
			(xy 368.796491 2.963538) (xy 368.719731 3.00176) (xy 368.646825 3.046901) (xy 368.578396 3.098577)
			(xy 368.515026 3.156346) (xy 368.457257 3.219716) (xy 368.405581 3.288145) (xy 368.36044 3.361051)
			(xy 368.322218 3.437811) (xy 368.291242 3.51777) (xy 368.267775 3.600246) (xy 368.252019 3.684536)
			(xy 368.244107 3.769919) (xy 363.748841 3.769919) (xy 363.740929 3.684536) (xy 363.725173 3.600246)
			(xy 363.701706 3.51777) (xy 363.67073 3.437811) (xy 363.632508 3.361051) (xy 363.587367 3.288145)
			(xy 363.535691 3.219716) (xy 363.477922 3.156346) (xy 363.414552 3.098577) (xy 363.346123 3.046901)
			(xy 363.273217 3.00176) (xy 363.196457 2.963538) (xy 363.116498 2.932562) (xy 363.034022 2.909095)
			(xy 362.949732 2.893339) (xy 362.864349 2.885427) (xy 362.778599 2.885427) (xy 362.693216 2.893339)
			(xy 362.608926 2.909095) (xy 362.52645 2.932562) (xy 362.446491 2.963538) (xy 362.369731 3.00176)
			(xy 362.296825 3.046901) (xy 362.228396 3.098577) (xy 362.165026 3.156346) (xy 362.107257 3.219716)
			(xy 362.055581 3.288145) (xy 362.01044 3.361051) (xy 361.972218 3.437811) (xy 361.941242 3.51777)
			(xy 361.917775 3.600246) (xy 361.902019 3.684536) (xy 361.894107 3.769919) (xy 319.360055 3.769919)
			(xy 319.352143 3.684536) (xy 319.336387 3.600246) (xy 319.31292 3.51777) (xy 319.281944 3.437811)
			(xy 319.243722 3.361051) (xy 319.198581 3.288145) (xy 319.146905 3.219716) (xy 319.089136 3.156346)
			(xy 319.025766 3.098577) (xy 318.957337 3.046901) (xy 318.884431 3.00176) (xy 318.807671 2.963538)
			(xy 318.727712 2.932562) (xy 318.645236 2.909095) (xy 318.560946 2.893339) (xy 318.475563 2.885427)
			(xy 318.389813 2.885427) (xy 318.30443 2.893339) (xy 318.22014 2.909095) (xy 318.137664 2.932562)
			(xy 318.057705 2.963538) (xy 317.980945 3.00176) (xy 317.908039 3.046901) (xy 317.83961 3.098577)
			(xy 317.77624 3.156346) (xy 317.718471 3.219716) (xy 317.666795 3.288145) (xy 317.621654 3.361051)
			(xy 317.583432 3.437811) (xy 317.552456 3.51777) (xy 317.528989 3.600246) (xy 317.513233 3.684536)
			(xy 317.505321 3.769919) (xy 313.010055 3.769919) (xy 313.002143 3.684536) (xy 312.986387 3.600246)
			(xy 312.96292 3.51777) (xy 312.931944 3.437811) (xy 312.893722 3.361051) (xy 312.848581 3.288145)
			(xy 312.796905 3.219716) (xy 312.739136 3.156346) (xy 312.675766 3.098577) (xy 312.607337 3.046901)
			(xy 312.534431 3.00176) (xy 312.457671 2.963538) (xy 312.377712 2.932562) (xy 312.295236 2.909095)
			(xy 312.210946 2.893339) (xy 312.125563 2.885427) (xy 312.039813 2.885427) (xy 311.95443 2.893339)
			(xy 311.87014 2.909095) (xy 311.787664 2.932562) (xy 311.707705 2.963538) (xy 311.630945 3.00176)
			(xy 311.558039 3.046901) (xy 311.48961 3.098577) (xy 311.42624 3.156346) (xy 311.368471 3.219716)
			(xy 311.316795 3.288145) (xy 311.271654 3.361051) (xy 311.233432 3.437811) (xy 311.202456 3.51777)
			(xy 311.178989 3.600246) (xy 311.163233 3.684536) (xy 311.155321 3.769919) (xy 304.348655 3.769919)
			(xy 304.340743 3.684536) (xy 304.324987 3.600246) (xy 304.30152 3.51777) (xy 304.270544 3.437811)
			(xy 304.232322 3.361051) (xy 304.187181 3.288145) (xy 304.135505 3.219716) (xy 304.077736 3.156346)
			(xy 304.014366 3.098577) (xy 303.945937 3.046901) (xy 303.873031 3.00176) (xy 303.796271 2.963538)
			(xy 303.716312 2.932562) (xy 303.633836 2.909095) (xy 303.549546 2.893339) (xy 303.464163 2.885427)
			(xy 303.378413 2.885427) (xy 303.29303 2.893339) (xy 303.20874 2.909095) (xy 303.126264 2.932562)
			(xy 303.046305 2.963538) (xy 302.969545 3.00176) (xy 302.896639 3.046901) (xy 302.82821 3.098577)
			(xy 302.76484 3.156346) (xy 302.707071 3.219716) (xy 302.655395 3.288145) (xy 302.610254 3.361051)
			(xy 302.572032 3.437811) (xy 302.541056 3.51777) (xy 302.517589 3.600246) (xy 302.501833 3.684536)
			(xy 302.493921 3.769919) (xy 297.998655 3.769919) (xy 297.990743 3.684536) (xy 297.974987 3.600246)
			(xy 297.95152 3.51777) (xy 297.920544 3.437811) (xy 297.882322 3.361051) (xy 297.837181 3.288145)
			(xy 297.785505 3.219716) (xy 297.727736 3.156346) (xy 297.664366 3.098577) (xy 297.595937 3.046901)
			(xy 297.523031 3.00176) (xy 297.446271 2.963538) (xy 297.366312 2.932562) (xy 297.283836 2.909095)
			(xy 297.199546 2.893339) (xy 297.114163 2.885427) (xy 297.028413 2.885427) (xy 296.94303 2.893339)
			(xy 296.85874 2.909095) (xy 296.776264 2.932562) (xy 296.696305 2.963538) (xy 296.619545 3.00176)
			(xy 296.546639 3.046901) (xy 296.47821 3.098577) (xy 296.41484 3.156346) (xy 296.357071 3.219716)
			(xy 296.305395 3.288145) (xy 296.260254 3.361051) (xy 296.222032 3.437811) (xy 296.191056 3.51777)
			(xy 296.167589 3.600246) (xy 296.151833 3.684536) (xy 296.143921 3.769919) (xy 216.865975 3.769919)
			(xy 216.858063 3.684536) (xy 216.842307 3.600246) (xy 216.81884 3.51777) (xy 216.787864 3.437811)
			(xy 216.749642 3.361051) (xy 216.704501 3.288145) (xy 216.652825 3.219716) (xy 216.595056 3.156346)
			(xy 216.531686 3.098577) (xy 216.463257 3.046901) (xy 216.390351 3.00176) (xy 216.313591 2.963538)
			(xy 216.233632 2.932562) (xy 216.151156 2.909095) (xy 216.066866 2.893339) (xy 215.981483 2.885427)
			(xy 215.895733 2.885427) (xy 215.81035 2.893339) (xy 215.72606 2.909095) (xy 215.643584 2.932562)
			(xy 215.563625 2.963538) (xy 215.486865 3.00176) (xy 215.413959 3.046901) (xy 215.34553 3.098577)
			(xy 215.28216 3.156346) (xy 215.224391 3.219716) (xy 215.172715 3.288145) (xy 215.127574 3.361051)
			(xy 215.089352 3.437811) (xy 215.058376 3.51777) (xy 215.034909 3.600246) (xy 215.019153 3.684536)
			(xy 215.011241 3.769919) (xy 210.515975 3.769919) (xy 210.508063 3.684536) (xy 210.492307 3.600246)
			(xy 210.46884 3.51777) (xy 210.437864 3.437811) (xy 210.399642 3.361051) (xy 210.354501 3.288145)
			(xy 210.302825 3.219716) (xy 210.245056 3.156346) (xy 210.181686 3.098577) (xy 210.113257 3.046901)
			(xy 210.040351 3.00176) (xy 209.963591 2.963538) (xy 209.883632 2.932562) (xy 209.801156 2.909095)
			(xy 209.716866 2.893339) (xy 209.631483 2.885427) (xy 209.545733 2.885427) (xy 209.46035 2.893339)
			(xy 209.37606 2.909095) (xy 209.293584 2.932562) (xy 209.213625 2.963538) (xy 209.136865 3.00176)
			(xy 209.063959 3.046901) (xy 208.99553 3.098577) (xy 208.93216 3.156346) (xy 208.874391 3.219716)
			(xy 208.822715 3.288145) (xy 208.777574 3.361051) (xy 208.739352 3.437811) (xy 208.708376 3.51777)
			(xy 208.684909 3.600246) (xy 208.669153 3.684536) (xy 208.661241 3.769919) (xy 184.818528 3.769919)
			(xy 184.818528 3.092196) (xy 184.818024 3.06266) (xy 184.80998 3.004138) (xy 184.794043 2.947256)
			(xy 184.770508 2.893074) (xy 184.739815 2.842601) (xy 184.702535 2.796778) (xy 184.659363 2.756458)
			(xy 184.611103 2.722392) (xy 184.558653 2.695215) (xy 184.502992 2.675433) (xy 184.445155 2.663414)
			(xy 184.38622 2.659383) (xy 184.327285 2.663414) (xy 184.269448 2.675433) (xy 184.213787 2.695215)
			(xy 184.161337 2.722392) (xy 184.113077 2.756458) (xy 184.069905 2.796778) (xy 184.032625 2.842601)
			(xy 184.001932 2.893074) (xy 183.978397 2.947256) (xy 183.96246 3.004138) (xy 183.954416 3.06266)
			(xy 183.953912 3.092196) (xy 182.791278 3.092196) (xy 182.847365 3.064268) (xy 182.920271 3.019127)
			(xy 182.9887 2.967451) (xy 183.05207 2.909682) (xy 183.109839 2.846312) (xy 183.161515 2.777883)
			(xy 183.206656 2.704977) (xy 183.244878 2.628217) (xy 183.275854 2.548258) (xy 183.299321 2.465782)
			(xy 183.315077 2.381492) (xy 183.322989 2.296109) (xy 183.323484 2.253234) (xy 183.322989 2.210359)
			(xy 187.818255 2.210359) (xy 187.818255 2.296109) (xy 187.826167 2.381492) (xy 187.841923 2.465782)
			(xy 187.86539 2.548258) (xy 187.896366 2.628217) (xy 187.934588 2.704977) (xy 187.979729 2.777883)
			(xy 188.031405 2.846312) (xy 188.089174 2.909682) (xy 188.152544 2.967451) (xy 188.220973 3.019127)
			(xy 188.293879 3.064268) (xy 188.370639 3.10249) (xy 188.450598 3.133466) (xy 188.533074 3.156933)
			(xy 188.617364 3.172689) (xy 188.702747 3.180601) (xy 188.788497 3.180601) (xy 188.87388 3.172689)
			(xy 188.95817 3.156933) (xy 189.040646 3.133466) (xy 189.120605 3.10249) (xy 189.197365 3.064268)
			(xy 189.270271 3.019127) (xy 189.3387 2.967451) (xy 189.40207 2.909682) (xy 189.459839 2.846312)
			(xy 189.511515 2.777883) (xy 189.556656 2.704977) (xy 189.594878 2.628217) (xy 189.625854 2.548258)
			(xy 189.649321 2.465782) (xy 189.665077 2.381492) (xy 189.672989 2.296109) (xy 189.673484 2.253234)
			(xy 189.672989 2.210359) (xy 189.665077 2.124976) (xy 189.649321 2.040686) (xy 189.625854 1.95821)
			(xy 189.594878 1.878251) (xy 189.556656 1.801491) (xy 189.511515 1.728585) (xy 189.459839 1.660156)
			(xy 189.40207 1.596786) (xy 189.3387 1.539017) (xy 189.270271 1.487341) (xy 189.197365 1.4422) (xy 189.120605 1.403978)
			(xy 189.040646 1.373002) (xy 188.95817 1.349535) (xy 188.87388 1.333779) (xy 188.788497 1.325867)
			(xy 188.702747 1.325867) (xy 188.617364 1.333779) (xy 188.533074 1.349535) (xy 188.450598 1.373002)
			(xy 188.370639 1.403978) (xy 188.293879 1.4422) (xy 188.220973 1.487341) (xy 188.152544 1.539017)
			(xy 188.089174 1.596786) (xy 188.031405 1.660156) (xy 187.979729 1.728585) (xy 187.934588 1.801491)
			(xy 187.896366 1.878251) (xy 187.86539 1.95821) (xy 187.841923 2.040686) (xy 187.826167 2.124976)
			(xy 187.818255 2.210359) (xy 183.322989 2.210359) (xy 183.315077 2.124976) (xy 183.299321 2.040686)
			(xy 183.275854 1.95821) (xy 183.244878 1.878251) (xy 183.206656 1.801491) (xy 183.161515 1.728585)
			(xy 183.109839 1.660156) (xy 183.05207 1.596786) (xy 182.9887 1.539017) (xy 182.920271 1.487341)
			(xy 182.847365 1.4422) (xy 182.770605 1.403978) (xy 182.690646 1.373002) (xy 182.60817 1.349535)
			(xy 182.52388 1.333779) (xy 182.438497 1.325867) (xy 182.352747 1.325867) (xy 182.267364 1.333779)
			(xy 182.183074 1.349535) (xy 182.100598 1.373002) (xy 182.020639 1.403978) (xy 181.943879 1.4422)
			(xy 181.870973 1.487341) (xy 181.802544 1.539017) (xy 181.739174 1.596786) (xy 181.681405 1.660156)
			(xy 181.629729 1.728585) (xy 181.584588 1.801491) (xy 181.546366 1.878251) (xy 181.51539 1.95821)
			(xy 181.491923 2.040686) (xy 181.476167 2.124976) (xy 181.468255 2.210359) (xy 102.190309 2.210359)
			(xy 102.182397 2.124976) (xy 102.166641 2.040686) (xy 102.143174 1.95821) (xy 102.112198 1.878251)
			(xy 102.073976 1.801491) (xy 102.028835 1.728585) (xy 101.977159 1.660156) (xy 101.91939 1.596786)
			(xy 101.85602 1.539017) (xy 101.787591 1.487341) (xy 101.714685 1.4422) (xy 101.637925 1.403978)
			(xy 101.557966 1.373002) (xy 101.47549 1.349535) (xy 101.3912 1.333779) (xy 101.305817 1.325867)
			(xy 101.220067 1.325867) (xy 101.134684 1.333779) (xy 101.050394 1.349535) (xy 100.967918 1.373002)
			(xy 100.887959 1.403978) (xy 100.811199 1.4422) (xy 100.738293 1.487341) (xy 100.669864 1.539017)
			(xy 100.606494 1.596786) (xy 100.548725 1.660156) (xy 100.497049 1.728585) (xy 100.451908 1.801491)
			(xy 100.413686 1.878251) (xy 100.38271 1.95821) (xy 100.359243 2.040686) (xy 100.343487 2.124976)
			(xy 100.335575 2.210359) (xy 95.840309 2.210359) (xy 95.832397 2.124976) (xy 95.816641 2.040686)
			(xy 95.793174 1.95821) (xy 95.762198 1.878251) (xy 95.723976 1.801491) (xy 95.678835 1.728585) (xy 95.627159 1.660156)
			(xy 95.56939 1.596786) (xy 95.50602 1.539017) (xy 95.437591 1.487341) (xy 95.364685 1.4422) (xy 95.287925 1.403978)
			(xy 95.207966 1.373002) (xy 95.12549 1.349535) (xy 95.0412 1.333779) (xy 94.955817 1.325867) (xy 94.870067 1.325867)
			(xy 94.784684 1.333779) (xy 94.700394 1.349535) (xy 94.617918 1.373002) (xy 94.537959 1.403978) (xy 94.461199 1.4422)
			(xy 94.388293 1.487341) (xy 94.319864 1.539017) (xy 94.256494 1.596786) (xy 94.198725 1.660156) (xy 94.147049 1.728585)
			(xy 94.101908 1.801491) (xy 94.063686 1.878251) (xy 94.03271 1.95821) (xy 94.009243 2.040686) (xy 93.993487 2.124976)
			(xy 93.985575 2.210359) (xy 83.439191 2.210359) (xy 83.525475 2.124078) (xy 83.619275 2.019118) (xy 83.707042 1.909064)
			(xy 83.788501 1.794262) (xy 83.863394 1.675073) (xy 83.931487 1.551873) (xy 83.992565 1.425048) (xy 84.046435 1.294999)
			(xy 84.069209 1.229919) (xy 208.661241 1.229919) (xy 208.661241 1.315669) (xy 208.669153 1.401052)
			(xy 208.684909 1.485342) (xy 208.708376 1.567818) (xy 208.739352 1.647777) (xy 208.777574 1.724537)
			(xy 208.822715 1.797443) (xy 208.874391 1.865872) (xy 208.93216 1.929242) (xy 208.99553 1.987011)
			(xy 209.063959 2.038687) (xy 209.136865 2.083828) (xy 209.213625 2.12205) (xy 209.293584 2.153026)
			(xy 209.37606 2.176493) (xy 209.46035 2.192249) (xy 209.545733 2.200161) (xy 209.631483 2.200161)
			(xy 209.716866 2.192249) (xy 209.801156 2.176493) (xy 209.883632 2.153026) (xy 209.963591 2.12205)
			(xy 209.984264 2.111756) (xy 213.517988 2.111756) (xy 213.517988 2.975356) (xy 213.518492 3.00491)
			(xy 213.526541 3.063466) (xy 213.542487 3.120381) (xy 213.566036 3.174595) (xy 213.596747 3.225098)
			(xy 213.634049 3.270948) (xy 213.677246 3.311291) (xy 213.725535 3.345377) (xy 213.778015 3.37257)
			(xy 213.83371 3.392364) (xy 213.891581 3.40439) (xy 213.95055 3.408424) (xy 214.009519 3.40439) (xy 214.06739 3.392364)
			(xy 214.123085 3.37257) (xy 214.175565 3.345377) (xy 214.223854 3.311291) (xy 214.267051 3.270948)
			(xy 214.304353 3.225098) (xy 214.335064 3.174595) (xy 214.358613 3.120381) (xy 214.374559 3.063466)
			(xy 214.382608 3.00491) (xy 214.383112 2.975356) (xy 214.383112 2.111756) (xy 214.382608 2.082202)
			(xy 214.374559 2.023646) (xy 214.358613 1.966731) (xy 214.335064 1.912517) (xy 214.304353 1.862014)
			(xy 214.267051 1.816164) (xy 214.223854 1.775821) (xy 214.175565 1.741735) (xy 214.123085 1.714542)
			(xy 214.06739 1.694748) (xy 214.009519 1.682722) (xy 213.95055 1.678689) (xy 213.891581 1.682722)
			(xy 213.83371 1.694748) (xy 213.778015 1.714542) (xy 213.725535 1.741735) (xy 213.677246 1.775821)
			(xy 213.634049 1.816164) (xy 213.596747 1.862014) (xy 213.566036 1.912517) (xy 213.542487 1.966731)
			(xy 213.526541 2.023646) (xy 213.518492 2.082202) (xy 213.517988 2.111756) (xy 209.984264 2.111756)
			(xy 210.040351 2.083828) (xy 210.113257 2.038687) (xy 210.181686 1.987011) (xy 210.245056 1.929242)
			(xy 210.302825 1.865872) (xy 210.354501 1.797443) (xy 210.399642 1.724537) (xy 210.437864 1.647777)
			(xy 210.46884 1.567818) (xy 210.492307 1.485342) (xy 210.508063 1.401052) (xy 210.515975 1.315669)
			(xy 210.51647 1.272794) (xy 210.515975 1.229919) (xy 215.011241 1.229919) (xy 215.011241 1.315669)
			(xy 215.019153 1.401052) (xy 215.034909 1.485342) (xy 215.058376 1.567818) (xy 215.089352 1.647777)
			(xy 215.127574 1.724537) (xy 215.172715 1.797443) (xy 215.224391 1.865872) (xy 215.28216 1.929242)
			(xy 215.34553 1.987011) (xy 215.413959 2.038687) (xy 215.486865 2.083828) (xy 215.563625 2.12205)
			(xy 215.643584 2.153026) (xy 215.72606 2.176493) (xy 215.81035 2.192249) (xy 215.895733 2.200161)
			(xy 215.981483 2.200161) (xy 216.066866 2.192249) (xy 216.151156 2.176493) (xy 216.233632 2.153026)
			(xy 216.313591 2.12205) (xy 216.390351 2.083828) (xy 216.463257 2.038687) (xy 216.531686 1.987011)
			(xy 216.595056 1.929242) (xy 216.652825 1.865872) (xy 216.704501 1.797443) (xy 216.749642 1.724537)
			(xy 216.787864 1.647777) (xy 216.81884 1.567818) (xy 216.842307 1.485342) (xy 216.858063 1.401052)
			(xy 216.865975 1.315669) (xy 216.86647 1.272794) (xy 216.865975 1.229919) (xy 296.143921 1.229919)
			(xy 296.143921 1.315669) (xy 296.151833 1.401052) (xy 296.167589 1.485342) (xy 296.191056 1.567818)
			(xy 296.222032 1.647777) (xy 296.260254 1.724537) (xy 296.305395 1.797443) (xy 296.357071 1.865872)
			(xy 296.41484 1.929242) (xy 296.47821 1.987011) (xy 296.546639 2.038687) (xy 296.619545 2.083828)
			(xy 296.696305 2.12205) (xy 296.776264 2.153026) (xy 296.85874 2.176493) (xy 296.94303 2.192249)
			(xy 297.028413 2.200161) (xy 297.114163 2.200161) (xy 297.199546 2.192249) (xy 297.283836 2.176493)
			(xy 297.366312 2.153026) (xy 297.446271 2.12205) (xy 297.466944 2.111756) (xy 298.629324 2.111756)
			(xy 298.629324 2.975356) (xy 298.629828 3.00491) (xy 298.637877 3.063466) (xy 298.653823 3.120381)
			(xy 298.677372 3.174595) (xy 298.708083 3.225098) (xy 298.745385 3.270948) (xy 298.788582 3.311291)
			(xy 298.836871 3.345377) (xy 298.889351 3.37257) (xy 298.945046 3.392364) (xy 299.002917 3.40439)
			(xy 299.061886 3.408424) (xy 299.120855 3.40439) (xy 299.178726 3.392364) (xy 299.234421 3.37257)
			(xy 299.286901 3.345377) (xy 299.33519 3.311291) (xy 299.378387 3.270948) (xy 299.415689 3.225098)
			(xy 299.4464 3.174595) (xy 299.469949 3.120381) (xy 299.485895 3.063466) (xy 299.493944 3.00491)
			(xy 299.494448 2.975356) (xy 299.494448 2.111756) (xy 299.493944 2.082202) (xy 299.485895 2.023646)
			(xy 299.469949 1.966731) (xy 299.4464 1.912517) (xy 299.415689 1.862014) (xy 299.378387 1.816164)
			(xy 299.33519 1.775821) (xy 299.286901 1.741735) (xy 299.234421 1.714542) (xy 299.178726 1.694748)
			(xy 299.120855 1.682722) (xy 299.061886 1.678689) (xy 299.002917 1.682722) (xy 298.945046 1.694748)
			(xy 298.889351 1.714542) (xy 298.836871 1.741735) (xy 298.788582 1.775821) (xy 298.745385 1.816164)
			(xy 298.708083 1.862014) (xy 298.677372 1.912517) (xy 298.653823 1.966731) (xy 298.637877 2.023646)
			(xy 298.629828 2.082202) (xy 298.629324 2.111756) (xy 297.466944 2.111756) (xy 297.523031 2.083828)
			(xy 297.595937 2.038687) (xy 297.664366 1.987011) (xy 297.727736 1.929242) (xy 297.785505 1.865872)
			(xy 297.837181 1.797443) (xy 297.882322 1.724537) (xy 297.920544 1.647777) (xy 297.95152 1.567818)
			(xy 297.974987 1.485342) (xy 297.990743 1.401052) (xy 297.998655 1.315669) (xy 297.99915 1.272794)
			(xy 297.998655 1.229919) (xy 302.493921 1.229919) (xy 302.493921 1.315669) (xy 302.501833 1.401052)
			(xy 302.517589 1.485342) (xy 302.541056 1.567818) (xy 302.572032 1.647777) (xy 302.610254 1.724537)
			(xy 302.655395 1.797443) (xy 302.707071 1.865872) (xy 302.76484 1.929242) (xy 302.82821 1.987011)
			(xy 302.896639 2.038687) (xy 302.969545 2.083828) (xy 303.046305 2.12205) (xy 303.126264 2.153026)
			(xy 303.20874 2.176493) (xy 303.29303 2.192249) (xy 303.378413 2.200161) (xy 303.464163 2.200161)
			(xy 303.549546 2.192249) (xy 303.633836 2.176493) (xy 303.716312 2.153026) (xy 303.796271 2.12205)
			(xy 303.873031 2.083828) (xy 303.945937 2.038687) (xy 304.014366 1.987011) (xy 304.077736 1.929242)
			(xy 304.135505 1.865872) (xy 304.187181 1.797443) (xy 304.232322 1.724537) (xy 304.270544 1.647777)
			(xy 304.30152 1.567818) (xy 304.324987 1.485342) (xy 304.340743 1.401052) (xy 304.348655 1.315669)
			(xy 304.34915 1.272794) (xy 304.348655 1.229919) (xy 311.155321 1.229919) (xy 311.155321 1.315669)
			(xy 311.163233 1.401052) (xy 311.178989 1.485342) (xy 311.202456 1.567818) (xy 311.233432 1.647777)
			(xy 311.271654 1.724537) (xy 311.316795 1.797443) (xy 311.368471 1.865872) (xy 311.42624 1.929242)
			(xy 311.48961 1.987011) (xy 311.558039 2.038687) (xy 311.630945 2.083828) (xy 311.707705 2.12205)
			(xy 311.787664 2.153026) (xy 311.87014 2.176493) (xy 311.95443 2.192249) (xy 312.039813 2.200161)
			(xy 312.125563 2.200161) (xy 312.210946 2.192249) (xy 312.295236 2.176493) (xy 312.377712 2.153026)
			(xy 312.457671 2.12205) (xy 312.534431 2.083828) (xy 312.607337 2.038687) (xy 312.675766 1.987011)
			(xy 312.739136 1.929242) (xy 312.796905 1.865872) (xy 312.848581 1.797443) (xy 312.893722 1.724537)
			(xy 312.931944 1.647777) (xy 312.96292 1.567818) (xy 312.986387 1.485342) (xy 313.002143 1.401052)
			(xy 313.010055 1.315669) (xy 313.01055 1.272794) (xy 313.010055 1.229919) (xy 317.505321 1.229919)
			(xy 317.505321 1.315669) (xy 317.513233 1.401052) (xy 317.528989 1.485342) (xy 317.552456 1.567818)
			(xy 317.583432 1.647777) (xy 317.621654 1.724537) (xy 317.666795 1.797443) (xy 317.718471 1.865872)
			(xy 317.77624 1.929242) (xy 317.83961 1.987011) (xy 317.908039 2.038687) (xy 317.980945 2.083828)
			(xy 318.057705 2.12205) (xy 318.137664 2.153026) (xy 318.22014 2.176493) (xy 318.30443 2.192249)
			(xy 318.389813 2.200161) (xy 318.475563 2.200161) (xy 318.560946 2.192249) (xy 318.645236 2.176493)
			(xy 318.727712 2.153026) (xy 318.807671 2.12205) (xy 318.884431 2.083828) (xy 318.957337 2.038687)
			(xy 319.025766 1.987011) (xy 319.089136 1.929242) (xy 319.146905 1.865872) (xy 319.198581 1.797443)
			(xy 319.243722 1.724537) (xy 319.281944 1.647777) (xy 319.31292 1.567818) (xy 319.336387 1.485342)
			(xy 319.352143 1.401052) (xy 319.360055 1.315669) (xy 319.36055 1.272794) (xy 319.360055 1.229919)
			(xy 361.894107 1.229919) (xy 361.894107 1.315669) (xy 361.902019 1.401052) (xy 361.917775 1.485342)
			(xy 361.941242 1.567818) (xy 361.972218 1.647777) (xy 362.01044 1.724537) (xy 362.055581 1.797443)
			(xy 362.107257 1.865872) (xy 362.165026 1.929242) (xy 362.228396 1.987011) (xy 362.296825 2.038687)
			(xy 362.369731 2.083828) (xy 362.446491 2.12205) (xy 362.52645 2.153026) (xy 362.608926 2.176493)
			(xy 362.693216 2.192249) (xy 362.778599 2.200161) (xy 362.864349 2.200161) (xy 362.949732 2.192249)
			(xy 363.034022 2.176493) (xy 363.116498 2.153026) (xy 363.196457 2.12205) (xy 363.273217 2.083828)
			(xy 363.346123 2.038687) (xy 363.414552 1.987011) (xy 363.477922 1.929242) (xy 363.535691 1.865872)
			(xy 363.587367 1.797443) (xy 363.632508 1.724537) (xy 363.67073 1.647777) (xy 363.701706 1.567818)
			(xy 363.725173 1.485342) (xy 363.740929 1.401052) (xy 363.748841 1.315669) (xy 363.749336 1.272794)
			(xy 363.748841 1.229919) (xy 368.244107 1.229919) (xy 368.244107 1.315669) (xy 368.252019 1.401052)
			(xy 368.267775 1.485342) (xy 368.291242 1.567818) (xy 368.322218 1.647777) (xy 368.36044 1.724537)
			(xy 368.405581 1.797443) (xy 368.457257 1.865872) (xy 368.515026 1.929242) (xy 368.578396 1.987011)
			(xy 368.646825 2.038687) (xy 368.719731 2.083828) (xy 368.796491 2.12205) (xy 368.87645 2.153026)
			(xy 368.958926 2.176493) (xy 369.043216 2.192249) (xy 369.128599 2.200161) (xy 369.214349 2.200161)
			(xy 369.299732 2.192249) (xy 369.384022 2.176493) (xy 369.466498 2.153026) (xy 369.546457 2.12205)
			(xy 369.623217 2.083828) (xy 369.696123 2.038687) (xy 369.764552 1.987011) (xy 369.827922 1.929242)
			(xy 369.885691 1.865872) (xy 369.937367 1.797443) (xy 369.982508 1.724537) (xy 370.02073 1.647777)
			(xy 370.051706 1.567818) (xy 370.075173 1.485342) (xy 370.090929 1.401052) (xy 370.098841 1.315669)
			(xy 370.099336 1.272794) (xy 370.098841 1.229919) (xy 370.090929 1.144536) (xy 370.075173 1.060246)
			(xy 370.051706 0.97777) (xy 370.02073 0.897811) (xy 369.982508 0.821051) (xy 369.937367 0.748145)
			(xy 369.885691 0.679716) (xy 369.827922 0.616346) (xy 369.764552 0.558577) (xy 369.696123 0.506901)
			(xy 369.623217 0.46176) (xy 369.546457 0.423538) (xy 369.466498 0.392562) (xy 369.384022 0.369095)
			(xy 369.299732 0.353339) (xy 369.214349 0.345427) (xy 369.128599 0.345427) (xy 369.043216 0.353339)
			(xy 368.958926 0.369095) (xy 368.87645 0.392562) (xy 368.796491 0.423538) (xy 368.719731 0.46176)
			(xy 368.646825 0.506901) (xy 368.578396 0.558577) (xy 368.515026 0.616346) (xy 368.457257 0.679716)
			(xy 368.405581 0.748145) (xy 368.36044 0.821051) (xy 368.322218 0.897811) (xy 368.291242 0.97777)
			(xy 368.267775 1.060246) (xy 368.252019 1.144536) (xy 368.244107 1.229919) (xy 363.748841 1.229919)
			(xy 363.740929 1.144536) (xy 363.725173 1.060246) (xy 363.701706 0.97777) (xy 363.67073 0.897811)
			(xy 363.632508 0.821051) (xy 363.587367 0.748145) (xy 363.535691 0.679716) (xy 363.477922 0.616346)
			(xy 363.414552 0.558577) (xy 363.346123 0.506901) (xy 363.273217 0.46176) (xy 363.196457 0.423538)
			(xy 363.116498 0.392562) (xy 363.034022 0.369095) (xy 362.949732 0.353339) (xy 362.864349 0.345427)
			(xy 362.778599 0.345427) (xy 362.693216 0.353339) (xy 362.608926 0.369095) (xy 362.52645 0.392562)
			(xy 362.446491 0.423538) (xy 362.369731 0.46176) (xy 362.296825 0.506901) (xy 362.228396 0.558577)
			(xy 362.165026 0.616346) (xy 362.107257 0.679716) (xy 362.055581 0.748145) (xy 362.01044 0.821051)
			(xy 361.972218 0.897811) (xy 361.941242 0.97777) (xy 361.917775 1.060246) (xy 361.902019 1.144536)
			(xy 361.894107 1.229919) (xy 319.360055 1.229919) (xy 319.352143 1.144536) (xy 319.336387 1.060246)
			(xy 319.31292 0.97777) (xy 319.281944 0.897811) (xy 319.243722 0.821051) (xy 319.198581 0.748145)
			(xy 319.146905 0.679716) (xy 319.089136 0.616346) (xy 319.025766 0.558577) (xy 318.957337 0.506901)
			(xy 318.884431 0.46176) (xy 318.807671 0.423538) (xy 318.727712 0.392562) (xy 318.645236 0.369095)
			(xy 318.560946 0.353339) (xy 318.475563 0.345427) (xy 318.389813 0.345427) (xy 318.30443 0.353339)
			(xy 318.22014 0.369095) (xy 318.137664 0.392562) (xy 318.057705 0.423538) (xy 317.980945 0.46176)
			(xy 317.908039 0.506901) (xy 317.83961 0.558577) (xy 317.77624 0.616346) (xy 317.718471 0.679716)
			(xy 317.666795 0.748145) (xy 317.621654 0.821051) (xy 317.583432 0.897811) (xy 317.552456 0.97777)
			(xy 317.528989 1.060246) (xy 317.513233 1.144536) (xy 317.505321 1.229919) (xy 313.010055 1.229919)
			(xy 313.002143 1.144536) (xy 312.986387 1.060246) (xy 312.96292 0.97777) (xy 312.931944 0.897811)
			(xy 312.893722 0.821051) (xy 312.848581 0.748145) (xy 312.796905 0.679716) (xy 312.739136 0.616346)
			(xy 312.675766 0.558577) (xy 312.607337 0.506901) (xy 312.534431 0.46176) (xy 312.457671 0.423538)
			(xy 312.377712 0.392562) (xy 312.295236 0.369095) (xy 312.210946 0.353339) (xy 312.125563 0.345427)
			(xy 312.039813 0.345427) (xy 311.95443 0.353339) (xy 311.87014 0.369095) (xy 311.787664 0.392562)
			(xy 311.707705 0.423538) (xy 311.630945 0.46176) (xy 311.558039 0.506901) (xy 311.48961 0.558577)
			(xy 311.42624 0.616346) (xy 311.368471 0.679716) (xy 311.316795 0.748145) (xy 311.271654 0.821051)
			(xy 311.233432 0.897811) (xy 311.202456 0.97777) (xy 311.178989 1.060246) (xy 311.163233 1.144536)
			(xy 311.155321 1.229919) (xy 304.348655 1.229919) (xy 304.340743 1.144536) (xy 304.324987 1.060246)
			(xy 304.30152 0.97777) (xy 304.270544 0.897811) (xy 304.232322 0.821051) (xy 304.187181 0.748145)
			(xy 304.135505 0.679716) (xy 304.077736 0.616346) (xy 304.014366 0.558577) (xy 303.945937 0.506901)
			(xy 303.873031 0.46176) (xy 303.796271 0.423538) (xy 303.716312 0.392562) (xy 303.633836 0.369095)
			(xy 303.549546 0.353339) (xy 303.464163 0.345427) (xy 303.378413 0.345427) (xy 303.29303 0.353339)
			(xy 303.20874 0.369095) (xy 303.126264 0.392562) (xy 303.046305 0.423538) (xy 302.969545 0.46176)
			(xy 302.896639 0.506901) (xy 302.82821 0.558577) (xy 302.76484 0.616346) (xy 302.707071 0.679716)
			(xy 302.655395 0.748145) (xy 302.610254 0.821051) (xy 302.572032 0.897811) (xy 302.541056 0.97777)
			(xy 302.517589 1.060246) (xy 302.501833 1.144536) (xy 302.493921 1.229919) (xy 297.998655 1.229919)
			(xy 297.990743 1.144536) (xy 297.974987 1.060246) (xy 297.95152 0.97777) (xy 297.920544 0.897811)
			(xy 297.882322 0.821051) (xy 297.837181 0.748145) (xy 297.785505 0.679716) (xy 297.727736 0.616346)
			(xy 297.664366 0.558577) (xy 297.595937 0.506901) (xy 297.523031 0.46176) (xy 297.446271 0.423538)
			(xy 297.366312 0.392562) (xy 297.283836 0.369095) (xy 297.199546 0.353339) (xy 297.114163 0.345427)
			(xy 297.028413 0.345427) (xy 296.94303 0.353339) (xy 296.85874 0.369095) (xy 296.776264 0.392562)
			(xy 296.696305 0.423538) (xy 296.619545 0.46176) (xy 296.546639 0.506901) (xy 296.47821 0.558577)
			(xy 296.41484 0.616346) (xy 296.357071 0.679716) (xy 296.305395 0.748145) (xy 296.260254 0.821051)
			(xy 296.222032 0.897811) (xy 296.191056 0.97777) (xy 296.167589 1.060246) (xy 296.151833 1.144536)
			(xy 296.143921 1.229919) (xy 216.865975 1.229919) (xy 216.858063 1.144536) (xy 216.842307 1.060246)
			(xy 216.81884 0.97777) (xy 216.787864 0.897811) (xy 216.749642 0.821051) (xy 216.704501 0.748145)
			(xy 216.652825 0.679716) (xy 216.595056 0.616346) (xy 216.531686 0.558577) (xy 216.463257 0.506901)
			(xy 216.390351 0.46176) (xy 216.313591 0.423538) (xy 216.233632 0.392562) (xy 216.151156 0.369095)
			(xy 216.066866 0.353339) (xy 215.981483 0.345427) (xy 215.895733 0.345427) (xy 215.81035 0.353339)
			(xy 215.72606 0.369095) (xy 215.643584 0.392562) (xy 215.563625 0.423538) (xy 215.486865 0.46176)
			(xy 215.413959 0.506901) (xy 215.34553 0.558577) (xy 215.28216 0.616346) (xy 215.224391 0.679716)
			(xy 215.172715 0.748145) (xy 215.127574 0.821051) (xy 215.089352 0.897811) (xy 215.058376 0.97777)
			(xy 215.034909 1.060246) (xy 215.019153 1.144536) (xy 215.011241 1.229919) (xy 210.515975 1.229919)
			(xy 210.508063 1.144536) (xy 210.492307 1.060246) (xy 210.46884 0.97777) (xy 210.437864 0.897811)
			(xy 210.399642 0.821051) (xy 210.354501 0.748145) (xy 210.302825 0.679716) (xy 210.245056 0.616346)
			(xy 210.181686 0.558577) (xy 210.113257 0.506901) (xy 210.040351 0.46176) (xy 209.963591 0.423538)
			(xy 209.883632 0.392562) (xy 209.801156 0.369095) (xy 209.716866 0.353339) (xy 209.631483 0.345427)
			(xy 209.545733 0.345427) (xy 209.46035 0.353339) (xy 209.37606 0.369095) (xy 209.293584 0.392562)
			(xy 209.213625 0.423538) (xy 209.136865 0.46176) (xy 209.063959 0.506901) (xy 208.99553 0.558577)
			(xy 208.93216 0.616346) (xy 208.874391 0.679716) (xy 208.822715 0.748145) (xy 208.777574 0.821051)
			(xy 208.739352 0.897811) (xy 208.708376 0.97777) (xy 208.684909 1.060246) (xy 208.669153 1.144536)
			(xy 208.661241 1.229919) (xy 84.069209 1.229919) (xy 84.092929 1.162133) (xy 84.131901 1.02687) (xy 84.163226 0.889634)
			(xy 84.186808 0.750857) (xy 84.202571 0.610977) (xy 84.210467 0.470433) (xy 84.210906 0.40005) (xy 84.210906 -1.310081)
			(xy 208.661241 -1.310081) (xy 208.661241 -1.224331) (xy 208.669153 -1.138948) (xy 208.684909 -1.054658)
			(xy 208.708376 -0.972182) (xy 208.739352 -0.892223) (xy 208.777574 -0.815463) (xy 208.822715 -0.742557)
			(xy 208.874391 -0.674128) (xy 208.93216 -0.610758) (xy 208.99553 -0.552989) (xy 209.063959 -0.501313)
			(xy 209.136865 -0.456172) (xy 209.213625 -0.41795) (xy 209.293584 -0.386974) (xy 209.37606 -0.363507)
			(xy 209.46035 -0.347751) (xy 209.545733 -0.339839) (xy 209.631483 -0.339839) (xy 209.716866 -0.347751)
			(xy 209.801156 -0.363507) (xy 209.883632 -0.386974) (xy 209.963591 -0.41795) (xy 210.040351 -0.456172)
			(xy 210.113257 -0.501313) (xy 210.181686 -0.552989) (xy 210.245056 -0.610758) (xy 210.302825 -0.674128)
			(xy 210.354501 -0.742557) (xy 210.399642 -0.815463) (xy 210.437864 -0.892223) (xy 210.46884 -0.972182)
			(xy 210.492307 -1.054658) (xy 210.508063 -1.138948) (xy 210.515975 -1.224331) (xy 210.51647 -1.267206)
			(xy 210.515975 -1.310081) (xy 215.011241 -1.310081) (xy 215.011241 -1.224331) (xy 215.019153 -1.138948)
			(xy 215.034909 -1.054658) (xy 215.058376 -0.972182) (xy 215.089352 -0.892223) (xy 215.127574 -0.815463)
			(xy 215.172715 -0.742557) (xy 215.224391 -0.674128) (xy 215.28216 -0.610758) (xy 215.34553 -0.552989)
			(xy 215.413959 -0.501313) (xy 215.486865 -0.456172) (xy 215.563625 -0.41795) (xy 215.643584 -0.386974)
			(xy 215.72606 -0.363507) (xy 215.81035 -0.347751) (xy 215.895733 -0.339839) (xy 215.981483 -0.339839)
			(xy 216.066866 -0.347751) (xy 216.151156 -0.363507) (xy 216.233632 -0.386974) (xy 216.313591 -0.41795)
			(xy 216.390351 -0.456172) (xy 216.463257 -0.501313) (xy 216.531686 -0.552989) (xy 216.595056 -0.610758)
			(xy 216.652825 -0.674128) (xy 216.704501 -0.742557) (xy 216.749642 -0.815463) (xy 216.787864 -0.892223)
			(xy 216.81884 -0.972182) (xy 216.842307 -1.054658) (xy 216.858063 -1.138948) (xy 216.865975 -1.224331)
			(xy 216.86647 -1.267206) (xy 216.865975 -1.310081) (xy 296.143921 -1.310081) (xy 296.143921 -1.224331)
			(xy 296.151833 -1.138948) (xy 296.167589 -1.054658) (xy 296.191056 -0.972182) (xy 296.222032 -0.892223)
			(xy 296.260254 -0.815463) (xy 296.305395 -0.742557) (xy 296.357071 -0.674128) (xy 296.41484 -0.610758)
			(xy 296.47821 -0.552989) (xy 296.546639 -0.501313) (xy 296.619545 -0.456172) (xy 296.696305 -0.41795)
			(xy 296.776264 -0.386974) (xy 296.85874 -0.363507) (xy 296.94303 -0.347751) (xy 297.028413 -0.339839)
			(xy 297.114163 -0.339839) (xy 297.199546 -0.347751) (xy 297.283836 -0.363507) (xy 297.366312 -0.386974)
			(xy 297.446271 -0.41795) (xy 297.523031 -0.456172) (xy 297.595937 -0.501313) (xy 297.664366 -0.552989)
			(xy 297.727736 -0.610758) (xy 297.785505 -0.674128) (xy 297.837181 -0.742557) (xy 297.882322 -0.815463)
			(xy 297.920544 -0.892223) (xy 297.95152 -0.972182) (xy 297.974987 -1.054658) (xy 297.990743 -1.138948)
			(xy 297.998655 -1.224331) (xy 297.99915 -1.267206) (xy 297.998655 -1.310081) (xy 302.493921 -1.310081)
			(xy 302.493921 -1.224331) (xy 302.501833 -1.138948) (xy 302.517589 -1.054658) (xy 302.541056 -0.972182)
			(xy 302.572032 -0.892223) (xy 302.610254 -0.815463) (xy 302.655395 -0.742557) (xy 302.707071 -0.674128)
			(xy 302.76484 -0.610758) (xy 302.82821 -0.552989) (xy 302.896639 -0.501313) (xy 302.969545 -0.456172)
			(xy 303.046305 -0.41795) (xy 303.126264 -0.386974) (xy 303.20874 -0.363507) (xy 303.29303 -0.347751)
			(xy 303.378413 -0.339839) (xy 303.464163 -0.339839) (xy 303.549546 -0.347751) (xy 303.633836 -0.363507)
			(xy 303.716312 -0.386974) (xy 303.796271 -0.41795) (xy 303.873031 -0.456172) (xy 303.945937 -0.501313)
			(xy 304.014366 -0.552989) (xy 304.077736 -0.610758) (xy 304.135505 -0.674128) (xy 304.187181 -0.742557)
			(xy 304.232322 -0.815463) (xy 304.270544 -0.892223) (xy 304.30152 -0.972182) (xy 304.324987 -1.054658)
			(xy 304.340743 -1.138948) (xy 304.348655 -1.224331) (xy 304.34915 -1.267206) (xy 304.348655 -1.310081)
			(xy 311.155321 -1.310081) (xy 311.155321 -1.224331) (xy 311.163233 -1.138948) (xy 311.178989 -1.054658)
			(xy 311.202456 -0.972182) (xy 311.233432 -0.892223) (xy 311.271654 -0.815463) (xy 311.316795 -0.742557)
			(xy 311.368471 -0.674128) (xy 311.42624 -0.610758) (xy 311.48961 -0.552989) (xy 311.558039 -0.501313)
			(xy 311.630945 -0.456172) (xy 311.707705 -0.41795) (xy 311.787664 -0.386974) (xy 311.87014 -0.363507)
			(xy 311.95443 -0.347751) (xy 312.039813 -0.339839) (xy 312.125563 -0.339839) (xy 312.210946 -0.347751)
			(xy 312.295236 -0.363507) (xy 312.377712 -0.386974) (xy 312.457671 -0.41795) (xy 312.478344 -0.428244)
			(xy 316.012068 -0.428244) (xy 316.012068 0.435356) (xy 316.012572 0.46491) (xy 316.020621 0.523466)
			(xy 316.036567 0.580381) (xy 316.060116 0.634595) (xy 316.090827 0.685098) (xy 316.128129 0.730948)
			(xy 316.171326 0.771291) (xy 316.219615 0.805377) (xy 316.272095 0.83257) (xy 316.32779 0.852364)
			(xy 316.385661 0.86439) (xy 316.44463 0.868424) (xy 316.503599 0.86439) (xy 316.56147 0.852364) (xy 316.617165 0.83257)
			(xy 316.669645 0.805377) (xy 316.717934 0.771291) (xy 316.761131 0.730948) (xy 316.798433 0.685098)
			(xy 316.829144 0.634595) (xy 316.852693 0.580381) (xy 316.868639 0.523466) (xy 316.876688 0.46491)
			(xy 316.877192 0.435356) (xy 316.877192 -0.428244) (xy 316.876688 -0.457798) (xy 316.868639 -0.516354)
			(xy 316.852693 -0.573269) (xy 316.829144 -0.627483) (xy 316.798433 -0.677986) (xy 316.761131 -0.723836)
			(xy 316.717934 -0.764179) (xy 316.669645 -0.798265) (xy 316.617165 -0.825458) (xy 316.56147 -0.845252)
			(xy 316.503599 -0.857278) (xy 316.44463 -0.861312) (xy 316.385661 -0.857278) (xy 316.32779 -0.845252)
			(xy 316.272095 -0.825458) (xy 316.219615 -0.798265) (xy 316.171326 -0.764179) (xy 316.128129 -0.723836)
			(xy 316.090827 -0.677986) (xy 316.060116 -0.627483) (xy 316.036567 -0.573269) (xy 316.020621 -0.516354)
			(xy 316.012572 -0.457798) (xy 316.012068 -0.428244) (xy 312.478344 -0.428244) (xy 312.534431 -0.456172)
			(xy 312.607337 -0.501313) (xy 312.675766 -0.552989) (xy 312.739136 -0.610758) (xy 312.796905 -0.674128)
			(xy 312.848581 -0.742557) (xy 312.893722 -0.815463) (xy 312.931944 -0.892223) (xy 312.96292 -0.972182)
			(xy 312.986387 -1.054658) (xy 313.002143 -1.138948) (xy 313.010055 -1.224331) (xy 313.01055 -1.267206)
			(xy 313.010055 -1.310081) (xy 317.505321 -1.310081) (xy 317.505321 -1.224331) (xy 317.513233 -1.138948)
			(xy 317.528989 -1.054658) (xy 317.552456 -0.972182) (xy 317.583432 -0.892223) (xy 317.621654 -0.815463)
			(xy 317.666795 -0.742557) (xy 317.718471 -0.674128) (xy 317.77624 -0.610758) (xy 317.83961 -0.552989)
			(xy 317.908039 -0.501313) (xy 317.980945 -0.456172) (xy 318.057705 -0.41795) (xy 318.137664 -0.386974)
			(xy 318.22014 -0.363507) (xy 318.30443 -0.347751) (xy 318.389813 -0.339839) (xy 318.475563 -0.339839)
			(xy 318.560946 -0.347751) (xy 318.645236 -0.363507) (xy 318.727712 -0.386974) (xy 318.807671 -0.41795)
			(xy 318.884431 -0.456172) (xy 318.957337 -0.501313) (xy 319.025766 -0.552989) (xy 319.089136 -0.610758)
			(xy 319.146905 -0.674128) (xy 319.198581 -0.742557) (xy 319.243722 -0.815463) (xy 319.281944 -0.892223)
			(xy 319.31292 -0.972182) (xy 319.336387 -1.054658) (xy 319.352143 -1.138948) (xy 319.360055 -1.224331)
			(xy 319.36055 -1.267206) (xy 319.360055 -1.310081) (xy 361.894107 -1.310081) (xy 361.894107 -1.224331)
			(xy 361.902019 -1.138948) (xy 361.917775 -1.054658) (xy 361.941242 -0.972182) (xy 361.972218 -0.892223)
			(xy 362.01044 -0.815463) (xy 362.055581 -0.742557) (xy 362.107257 -0.674128) (xy 362.165026 -0.610758)
			(xy 362.228396 -0.552989) (xy 362.296825 -0.501313) (xy 362.369731 -0.456172) (xy 362.446491 -0.41795)
			(xy 362.52645 -0.386974) (xy 362.608926 -0.363507) (xy 362.693216 -0.347751) (xy 362.778599 -0.339839)
			(xy 362.864349 -0.339839) (xy 362.949732 -0.347751) (xy 363.034022 -0.363507) (xy 363.116498 -0.386974)
			(xy 363.196457 -0.41795) (xy 363.21713 -0.428244) (xy 364.379764 -0.428244) (xy 364.379764 0.435356)
			(xy 364.380268 0.464892) (xy 364.388312 0.523414) (xy 364.404249 0.580296) (xy 364.427784 0.634478)
			(xy 364.458477 0.684951) (xy 364.495757 0.730774) (xy 364.538929 0.771094) (xy 364.587189 0.80516)
			(xy 364.639639 0.832337) (xy 364.6953 0.852119) (xy 364.753137 0.864138) (xy 364.812072 0.868169)
			(xy 364.871007 0.864138) (xy 364.928844 0.852119) (xy 364.984505 0.832337) (xy 365.036955 0.80516)
			(xy 365.085215 0.771094) (xy 365.128387 0.730774) (xy 365.165667 0.684951) (xy 365.19636 0.634478)
			(xy 365.219895 0.580296) (xy 365.235832 0.523414) (xy 365.243876 0.464892) (xy 365.24438 0.435356)
			(xy 365.24438 -0.428244) (xy 365.243876 -0.45778) (xy 365.235832 -0.516302) (xy 365.219895 -0.573184)
			(xy 365.19636 -0.627366) (xy 365.165667 -0.677839) (xy 365.128387 -0.723662) (xy 365.085215 -0.763982)
			(xy 365.036955 -0.798048) (xy 364.984505 -0.825225) (xy 364.928844 -0.845007) (xy 364.871007 -0.857026)
			(xy 364.812072 -0.861057) (xy 364.753137 -0.857026) (xy 364.6953 -0.845007) (xy 364.639639 -0.825225)
			(xy 364.587189 -0.798048) (xy 364.538929 -0.763982) (xy 364.495757 -0.723662) (xy 364.458477 -0.677839)
			(xy 364.427784 -0.627366) (xy 364.404249 -0.573184) (xy 364.388312 -0.516302) (xy 364.380268 -0.45778)
			(xy 364.379764 -0.428244) (xy 363.21713 -0.428244) (xy 363.273217 -0.456172) (xy 363.346123 -0.501313)
			(xy 363.414552 -0.552989) (xy 363.477922 -0.610758) (xy 363.535691 -0.674128) (xy 363.587367 -0.742557)
			(xy 363.632508 -0.815463) (xy 363.67073 -0.892223) (xy 363.701706 -0.972182) (xy 363.725173 -1.054658)
			(xy 363.740929 -1.138948) (xy 363.748841 -1.224331) (xy 363.749336 -1.267206) (xy 363.748841 -1.310081)
			(xy 368.244107 -1.310081) (xy 368.244107 -1.224331) (xy 368.252019 -1.138948) (xy 368.267775 -1.054658)
			(xy 368.291242 -0.972182) (xy 368.322218 -0.892223) (xy 368.36044 -0.815463) (xy 368.405581 -0.742557)
			(xy 368.457257 -0.674128) (xy 368.515026 -0.610758) (xy 368.578396 -0.552989) (xy 368.646825 -0.501313)
			(xy 368.719731 -0.456172) (xy 368.796491 -0.41795) (xy 368.87645 -0.386974) (xy 368.958926 -0.363507)
			(xy 369.043216 -0.347751) (xy 369.128599 -0.339839) (xy 369.214349 -0.339839) (xy 369.299732 -0.347751)
			(xy 369.384022 -0.363507) (xy 369.466498 -0.386974) (xy 369.546457 -0.41795) (xy 369.623217 -0.456172)
			(xy 369.696123 -0.501313) (xy 369.764552 -0.552989) (xy 369.827922 -0.610758) (xy 369.885691 -0.674128)
			(xy 369.937367 -0.742557) (xy 369.982508 -0.815463) (xy 370.02073 -0.892223) (xy 370.051706 -0.972182)
			(xy 370.075173 -1.054658) (xy 370.090929 -1.138948) (xy 370.098841 -1.224331) (xy 370.099336 -1.267206)
			(xy 370.098841 -1.310081) (xy 370.090929 -1.395464) (xy 370.075173 -1.479754) (xy 370.051706 -1.56223)
			(xy 370.02073 -1.642189) (xy 369.982508 -1.718949) (xy 369.937367 -1.791855) (xy 369.885691 -1.860284)
			(xy 369.827922 -1.923654) (xy 369.764552 -1.981423) (xy 369.696123 -2.033099) (xy 369.623217 -2.07824)
			(xy 369.546457 -2.116462) (xy 369.466498 -2.147438) (xy 369.384022 -2.170905) (xy 369.299732 -2.186661)
			(xy 369.214349 -2.194573) (xy 369.128599 -2.194573) (xy 369.043216 -2.186661) (xy 368.958926 -2.170905)
			(xy 368.87645 -2.147438) (xy 368.796491 -2.116462) (xy 368.719731 -2.07824) (xy 368.646825 -2.033099)
			(xy 368.578396 -1.981423) (xy 368.515026 -1.923654) (xy 368.457257 -1.860284) (xy 368.405581 -1.791855)
			(xy 368.36044 -1.718949) (xy 368.322218 -1.642189) (xy 368.291242 -1.56223) (xy 368.267775 -1.479754)
			(xy 368.252019 -1.395464) (xy 368.244107 -1.310081) (xy 363.748841 -1.310081) (xy 363.740929 -1.395464)
			(xy 363.725173 -1.479754) (xy 363.701706 -1.56223) (xy 363.67073 -1.642189) (xy 363.632508 -1.718949)
			(xy 363.587367 -1.791855) (xy 363.535691 -1.860284) (xy 363.477922 -1.923654) (xy 363.414552 -1.981423)
			(xy 363.346123 -2.033099) (xy 363.273217 -2.07824) (xy 363.196457 -2.116462) (xy 363.116498 -2.147438)
			(xy 363.034022 -2.170905) (xy 362.949732 -2.186661) (xy 362.864349 -2.194573) (xy 362.778599 -2.194573)
			(xy 362.693216 -2.186661) (xy 362.608926 -2.170905) (xy 362.52645 -2.147438) (xy 362.446491 -2.116462)
			(xy 362.369731 -2.07824) (xy 362.296825 -2.033099) (xy 362.228396 -1.981423) (xy 362.165026 -1.923654)
			(xy 362.107257 -1.860284) (xy 362.055581 -1.791855) (xy 362.01044 -1.718949) (xy 361.972218 -1.642189)
			(xy 361.941242 -1.56223) (xy 361.917775 -1.479754) (xy 361.902019 -1.395464) (xy 361.894107 -1.310081)
			(xy 319.360055 -1.310081) (xy 319.352143 -1.395464) (xy 319.336387 -1.479754) (xy 319.31292 -1.56223)
			(xy 319.281944 -1.642189) (xy 319.243722 -1.718949) (xy 319.198581 -1.791855) (xy 319.146905 -1.860284)
			(xy 319.089136 -1.923654) (xy 319.025766 -1.981423) (xy 318.957337 -2.033099) (xy 318.884431 -2.07824)
			(xy 318.807671 -2.116462) (xy 318.727712 -2.147438) (xy 318.645236 -2.170905) (xy 318.560946 -2.186661)
			(xy 318.475563 -2.194573) (xy 318.389813 -2.194573) (xy 318.30443 -2.186661) (xy 318.22014 -2.170905)
			(xy 318.137664 -2.147438) (xy 318.057705 -2.116462) (xy 317.980945 -2.07824) (xy 317.908039 -2.033099)
			(xy 317.83961 -1.981423) (xy 317.77624 -1.923654) (xy 317.718471 -1.860284) (xy 317.666795 -1.791855)
			(xy 317.621654 -1.718949) (xy 317.583432 -1.642189) (xy 317.552456 -1.56223) (xy 317.528989 -1.479754)
			(xy 317.513233 -1.395464) (xy 317.505321 -1.310081) (xy 313.010055 -1.310081) (xy 313.002143 -1.395464)
			(xy 312.986387 -1.479754) (xy 312.96292 -1.56223) (xy 312.931944 -1.642189) (xy 312.893722 -1.718949)
			(xy 312.848581 -1.791855) (xy 312.796905 -1.860284) (xy 312.739136 -1.923654) (xy 312.675766 -1.981423)
			(xy 312.607337 -2.033099) (xy 312.534431 -2.07824) (xy 312.457671 -2.116462) (xy 312.377712 -2.147438)
			(xy 312.295236 -2.170905) (xy 312.210946 -2.186661) (xy 312.125563 -2.194573) (xy 312.039813 -2.194573)
			(xy 311.95443 -2.186661) (xy 311.87014 -2.170905) (xy 311.787664 -2.147438) (xy 311.707705 -2.116462)
			(xy 311.630945 -2.07824) (xy 311.558039 -2.033099) (xy 311.48961 -1.981423) (xy 311.42624 -1.923654)
			(xy 311.368471 -1.860284) (xy 311.316795 -1.791855) (xy 311.271654 -1.718949) (xy 311.233432 -1.642189)
			(xy 311.202456 -1.56223) (xy 311.178989 -1.479754) (xy 311.163233 -1.395464) (xy 311.155321 -1.310081)
			(xy 304.348655 -1.310081) (xy 304.340743 -1.395464) (xy 304.324987 -1.479754) (xy 304.30152 -1.56223)
			(xy 304.270544 -1.642189) (xy 304.232322 -1.718949) (xy 304.187181 -1.791855) (xy 304.135505 -1.860284)
			(xy 304.077736 -1.923654) (xy 304.014366 -1.981423) (xy 303.945937 -2.033099) (xy 303.873031 -2.07824)
			(xy 303.796271 -2.116462) (xy 303.716312 -2.147438) (xy 303.633836 -2.170905) (xy 303.549546 -2.186661)
			(xy 303.464163 -2.194573) (xy 303.378413 -2.194573) (xy 303.29303 -2.186661) (xy 303.20874 -2.170905)
			(xy 303.126264 -2.147438) (xy 303.046305 -2.116462) (xy 302.969545 -2.07824) (xy 302.896639 -2.033099)
			(xy 302.82821 -1.981423) (xy 302.76484 -1.923654) (xy 302.707071 -1.860284) (xy 302.655395 -1.791855)
			(xy 302.610254 -1.718949) (xy 302.572032 -1.642189) (xy 302.541056 -1.56223) (xy 302.517589 -1.479754)
			(xy 302.501833 -1.395464) (xy 302.493921 -1.310081) (xy 297.998655 -1.310081) (xy 297.990743 -1.395464)
			(xy 297.974987 -1.479754) (xy 297.95152 -1.56223) (xy 297.920544 -1.642189) (xy 297.882322 -1.718949)
			(xy 297.837181 -1.791855) (xy 297.785505 -1.860284) (xy 297.727736 -1.923654) (xy 297.664366 -1.981423)
			(xy 297.595937 -2.033099) (xy 297.523031 -2.07824) (xy 297.446271 -2.116462) (xy 297.366312 -2.147438)
			(xy 297.283836 -2.170905) (xy 297.199546 -2.186661) (xy 297.114163 -2.194573) (xy 297.028413 -2.194573)
			(xy 296.94303 -2.186661) (xy 296.85874 -2.170905) (xy 296.776264 -2.147438) (xy 296.696305 -2.116462)
			(xy 296.619545 -2.07824) (xy 296.546639 -2.033099) (xy 296.47821 -1.981423) (xy 296.41484 -1.923654)
			(xy 296.357071 -1.860284) (xy 296.305395 -1.791855) (xy 296.260254 -1.718949) (xy 296.222032 -1.642189)
			(xy 296.191056 -1.56223) (xy 296.167589 -1.479754) (xy 296.151833 -1.395464) (xy 296.143921 -1.310081)
			(xy 216.865975 -1.310081) (xy 216.858063 -1.395464) (xy 216.842307 -1.479754) (xy 216.81884 -1.56223)
			(xy 216.787864 -1.642189) (xy 216.749642 -1.718949) (xy 216.704501 -1.791855) (xy 216.652825 -1.860284)
			(xy 216.595056 -1.923654) (xy 216.531686 -1.981423) (xy 216.463257 -2.033099) (xy 216.390351 -2.07824)
			(xy 216.313591 -2.116462) (xy 216.233632 -2.147438) (xy 216.151156 -2.170905) (xy 216.066866 -2.186661)
			(xy 215.981483 -2.194573) (xy 215.895733 -2.194573) (xy 215.81035 -2.186661) (xy 215.72606 -2.170905)
			(xy 215.643584 -2.147438) (xy 215.563625 -2.116462) (xy 215.486865 -2.07824) (xy 215.413959 -2.033099)
			(xy 215.34553 -1.981423) (xy 215.28216 -1.923654) (xy 215.224391 -1.860284) (xy 215.172715 -1.791855)
			(xy 215.127574 -1.718949) (xy 215.089352 -1.642189) (xy 215.058376 -1.56223) (xy 215.034909 -1.479754)
			(xy 215.019153 -1.395464) (xy 215.011241 -1.310081) (xy 210.515975 -1.310081) (xy 210.508063 -1.395464)
			(xy 210.492307 -1.479754) (xy 210.46884 -1.56223) (xy 210.437864 -1.642189) (xy 210.399642 -1.718949)
			(xy 210.354501 -1.791855) (xy 210.302825 -1.860284) (xy 210.245056 -1.923654) (xy 210.181686 -1.981423)
			(xy 210.113257 -2.033099) (xy 210.040351 -2.07824) (xy 209.963591 -2.116462) (xy 209.883632 -2.147438)
			(xy 209.801156 -2.170905) (xy 209.716866 -2.186661) (xy 209.631483 -2.194573) (xy 209.545733 -2.194573)
			(xy 209.46035 -2.186661) (xy 209.37606 -2.170905) (xy 209.293584 -2.147438) (xy 209.213625 -2.116462)
			(xy 209.136865 -2.07824) (xy 209.063959 -2.033099) (xy 208.99553 -1.981423) (xy 208.93216 -1.923654)
			(xy 208.874391 -1.860284) (xy 208.822715 -1.791855) (xy 208.777574 -1.718949) (xy 208.739352 -1.642189)
			(xy 208.708376 -1.56223) (xy 208.684909 -1.479754) (xy 208.669153 -1.395464) (xy 208.661241 -1.310081)
			(xy 84.210906 -1.310081) (xy 84.210906 -7.78002) (xy 84.211428 -7.835789) (xy 84.219765 -7.947014)
			(xy 84.23639 -8.057306) (xy 84.26121 -8.166046) (xy 84.294088 -8.272628) (xy 84.334838 -8.376455)
			(xy 84.383233 -8.476947) (xy 84.439002 -8.573541) (xy 84.501834 -8.665697) (xy 84.571376 -8.7529)
			(xy 84.647241 -8.834663) (xy 84.729004 -8.910527) (xy 84.816208 -8.98007) (xy 84.908364 -9.042901)
			(xy 85.004959 -9.09867) (xy 85.10545 -9.147065) (xy 85.209277 -9.187814) (xy 85.315859 -9.220691)
			(xy 85.4246 -9.245511) (xy 85.534892 -9.262136) (xy 85.646117 -9.270472) (xy 85.701886 -9.271) (xy 122.102118 -9.271)
			(xy 122.157887 -9.270478) (xy 122.269113 -9.262141) (xy 122.379404 -9.245517) (xy 122.488145 -9.220696)
			(xy 122.594728 -9.187819) (xy 122.698555 -9.147069) (xy 122.799047 -9.098674) (xy 122.895641 -9.042905)
			(xy 122.987798 -8.980073) (xy 123.075001 -8.910531) (xy 123.156764 -8.834666) (xy 123.232629 -8.752903)
			(xy 123.302172 -8.665699) (xy 123.365004 -8.573543) (xy 123.420773 -8.476948) (xy 123.469168 -8.376457)
			(xy 123.509918 -8.27263) (xy 123.542796 -8.166047) (xy 123.567616 -8.057306) (xy 123.584241 -7.947015)
			(xy 123.592578 -7.835789) (xy 123.593098 -7.78002) (xy 123.593098 -4.879848) (xy 123.593581 -4.809465)
			(xy 123.601472 -4.66892) (xy 123.61723 -4.529038) (xy 123.640807 -4.39026) (xy 123.672128 -4.253022)
			(xy 123.711095 -4.117757) (xy 123.757586 -3.984889) (xy 123.811453 -3.854837) (xy 123.872528 -3.72801)
			(xy 123.940618 -3.604807) (xy 124.015509 -3.485616) (xy 124.096965 -3.370811) (xy 124.184731 -3.260755)
			(xy 124.278529 -3.155793) (xy 124.378065 -3.056255) (xy 124.483026 -2.962455) (xy 124.593081 -2.874688)
			(xy 124.707884 -2.79323) (xy 124.827074 -2.718337) (xy 124.950276 -2.650245) (xy 125.077102 -2.589169)
			(xy 125.207153 -2.535299) (xy 125.340021 -2.488807) (xy 125.475285 -2.449838) (xy 125.612523 -2.418514)
			(xy 125.7513 -2.394935) (xy 125.891182 -2.379175) (xy 126.031727 -2.371282) (xy 126.10211 -2.370836)
			(xy 194.701922 -2.370836) (xy 194.772304 -2.371321) (xy 194.912845 -2.379215) (xy 195.052723 -2.394977)
			(xy 195.191497 -2.418557) (xy 195.328731 -2.449881) (xy 195.463992 -2.488851) (xy 195.596856 -2.535344)
			(xy 195.726904 -2.589213) (xy 195.853726 -2.650289) (xy 195.976925 -2.71838) (xy 196.096111 -2.793273)
			(xy 196.210911 -2.87473) (xy 196.320963 -2.962495) (xy 196.425921 -3.056294) (xy 196.525454 -3.15583)
			(xy 196.61925 -3.26079) (xy 196.707012 -3.370845) (xy 196.788466 -3.485647) (xy 196.863355 -3.604836)
			(xy 196.931443 -3.728036) (xy 196.990215 -3.850081) (xy 208.661241 -3.850081) (xy 208.661241 -3.764331)
			(xy 208.669153 -3.678948) (xy 208.684909 -3.594658) (xy 208.708376 -3.512182) (xy 208.739352 -3.432223)
			(xy 208.777574 -3.355463) (xy 208.822715 -3.282557) (xy 208.874391 -3.214128) (xy 208.93216 -3.150758)
			(xy 208.99553 -3.092989) (xy 209.063959 -3.041313) (xy 209.136865 -2.996172) (xy 209.213625 -2.95795)
			(xy 209.293584 -2.926974) (xy 209.37606 -2.903507) (xy 209.46035 -2.887751) (xy 209.545733 -2.879839)
			(xy 209.631483 -2.879839) (xy 209.716866 -2.887751) (xy 209.801156 -2.903507) (xy 209.883632 -2.926974)
			(xy 209.963591 -2.95795) (xy 209.984264 -2.968244) (xy 213.517988 -2.968244) (xy 213.517988 -2.104644)
			(xy 213.518492 -2.07509) (xy 213.526541 -2.016534) (xy 213.542487 -1.959619) (xy 213.566036 -1.905405)
			(xy 213.596747 -1.854902) (xy 213.634049 -1.809052) (xy 213.677246 -1.768709) (xy 213.725535 -1.734623)
			(xy 213.778015 -1.70743) (xy 213.83371 -1.687636) (xy 213.891581 -1.67561) (xy 213.95055 -1.671577)
			(xy 214.009519 -1.67561) (xy 214.06739 -1.687636) (xy 214.123085 -1.70743) (xy 214.175565 -1.734623)
			(xy 214.223854 -1.768709) (xy 214.267051 -1.809052) (xy 214.304353 -1.854902) (xy 214.335064 -1.905405)
			(xy 214.358613 -1.959619) (xy 214.374559 -2.016534) (xy 214.382608 -2.07509) (xy 214.383112 -2.104644)
			(xy 214.383112 -2.968244) (xy 214.382608 -2.997798) (xy 214.374559 -3.056354) (xy 214.358613 -3.113269)
			(xy 214.335064 -3.167483) (xy 214.304353 -3.217986) (xy 214.267051 -3.263836) (xy 214.223854 -3.304179)
			(xy 214.175565 -3.338265) (xy 214.123085 -3.365458) (xy 214.06739 -3.385252) (xy 214.009519 -3.397278)
			(xy 213.95055 -3.401312) (xy 213.891581 -3.397278) (xy 213.83371 -3.385252) (xy 213.778015 -3.365458)
			(xy 213.725535 -3.338265) (xy 213.677246 -3.304179) (xy 213.634049 -3.263836) (xy 213.596747 -3.217986)
			(xy 213.566036 -3.167483) (xy 213.542487 -3.113269) (xy 213.526541 -3.056354) (xy 213.518492 -2.997798)
			(xy 213.517988 -2.968244) (xy 209.984264 -2.968244) (xy 210.040351 -2.996172) (xy 210.113257 -3.041313)
			(xy 210.181686 -3.092989) (xy 210.245056 -3.150758) (xy 210.302825 -3.214128) (xy 210.354501 -3.282557)
			(xy 210.399642 -3.355463) (xy 210.437864 -3.432223) (xy 210.46884 -3.512182) (xy 210.492307 -3.594658)
			(xy 210.508063 -3.678948) (xy 210.515975 -3.764331) (xy 210.51647 -3.807206) (xy 210.515975 -3.850081)
			(xy 215.011241 -3.850081) (xy 215.011241 -3.764331) (xy 215.019153 -3.678948) (xy 215.034909 -3.594658)
			(xy 215.058376 -3.512182) (xy 215.089352 -3.432223) (xy 215.127574 -3.355463) (xy 215.172715 -3.282557)
			(xy 215.224391 -3.214128) (xy 215.28216 -3.150758) (xy 215.34553 -3.092989) (xy 215.413959 -3.041313)
			(xy 215.486865 -2.996172) (xy 215.563625 -2.95795) (xy 215.643584 -2.926974) (xy 215.72606 -2.903507)
			(xy 215.81035 -2.887751) (xy 215.895733 -2.879839) (xy 215.981483 -2.879839) (xy 216.066866 -2.887751)
			(xy 216.151156 -2.903507) (xy 216.233632 -2.926974) (xy 216.313591 -2.95795) (xy 216.390351 -2.996172)
			(xy 216.463257 -3.041313) (xy 216.531686 -3.092989) (xy 216.595056 -3.150758) (xy 216.652825 -3.214128)
			(xy 216.704501 -3.282557) (xy 216.749642 -3.355463) (xy 216.787864 -3.432223) (xy 216.81884 -3.512182)
			(xy 216.842307 -3.594658) (xy 216.858063 -3.678948) (xy 216.865975 -3.764331) (xy 216.86647 -3.807206)
			(xy 216.865975 -3.850081) (xy 296.143921 -3.850081) (xy 296.143921 -3.764331) (xy 296.151833 -3.678948)
			(xy 296.167589 -3.594658) (xy 296.191056 -3.512182) (xy 296.222032 -3.432223) (xy 296.260254 -3.355463)
			(xy 296.305395 -3.282557) (xy 296.357071 -3.214128) (xy 296.41484 -3.150758) (xy 296.47821 -3.092989)
			(xy 296.546639 -3.041313) (xy 296.619545 -2.996172) (xy 296.696305 -2.95795) (xy 296.776264 -2.926974)
			(xy 296.85874 -2.903507) (xy 296.94303 -2.887751) (xy 297.028413 -2.879839) (xy 297.114163 -2.879839)
			(xy 297.199546 -2.887751) (xy 297.283836 -2.903507) (xy 297.366312 -2.926974) (xy 297.446271 -2.95795)
			(xy 297.466944 -2.968244) (xy 298.629324 -2.968244) (xy 298.629324 -2.104644) (xy 298.629828 -2.07509)
			(xy 298.637877 -2.016534) (xy 298.653823 -1.959619) (xy 298.677372 -1.905405) (xy 298.708083 -1.854902)
			(xy 298.745385 -1.809052) (xy 298.788582 -1.768709) (xy 298.836871 -1.734623) (xy 298.889351 -1.70743)
			(xy 298.945046 -1.687636) (xy 299.002917 -1.67561) (xy 299.061886 -1.671577) (xy 299.120855 -1.67561)
			(xy 299.178726 -1.687636) (xy 299.234421 -1.70743) (xy 299.286901 -1.734623) (xy 299.33519 -1.768709)
			(xy 299.378387 -1.809052) (xy 299.415689 -1.854902) (xy 299.4464 -1.905405) (xy 299.469949 -1.959619)
			(xy 299.485895 -2.016534) (xy 299.493944 -2.07509) (xy 299.494448 -2.104644) (xy 299.494448 -2.968244)
			(xy 299.493944 -2.997798) (xy 299.485895 -3.056354) (xy 299.469949 -3.113269) (xy 299.4464 -3.167483)
			(xy 299.415689 -3.217986) (xy 299.378387 -3.263836) (xy 299.33519 -3.304179) (xy 299.286901 -3.338265)
			(xy 299.234421 -3.365458) (xy 299.178726 -3.385252) (xy 299.120855 -3.397278) (xy 299.061886 -3.401312)
			(xy 299.002917 -3.397278) (xy 298.945046 -3.385252) (xy 298.889351 -3.365458) (xy 298.836871 -3.338265)
			(xy 298.788582 -3.304179) (xy 298.745385 -3.263836) (xy 298.708083 -3.217986) (xy 298.677372 -3.167483)
			(xy 298.653823 -3.113269) (xy 298.637877 -3.056354) (xy 298.629828 -2.997798) (xy 298.629324 -2.968244)
			(xy 297.466944 -2.968244) (xy 297.523031 -2.996172) (xy 297.595937 -3.041313) (xy 297.664366 -3.092989)
			(xy 297.727736 -3.150758) (xy 297.785505 -3.214128) (xy 297.837181 -3.282557) (xy 297.882322 -3.355463)
			(xy 297.920544 -3.432223) (xy 297.95152 -3.512182) (xy 297.974987 -3.594658) (xy 297.990743 -3.678948)
			(xy 297.998655 -3.764331) (xy 297.99915 -3.807206) (xy 297.998655 -3.850081) (xy 302.493921 -3.850081)
			(xy 302.493921 -3.764331) (xy 302.501833 -3.678948) (xy 302.517589 -3.594658) (xy 302.541056 -3.512182)
			(xy 302.572032 -3.432223) (xy 302.610254 -3.355463) (xy 302.655395 -3.282557) (xy 302.707071 -3.214128)
			(xy 302.76484 -3.150758) (xy 302.82821 -3.092989) (xy 302.896639 -3.041313) (xy 302.969545 -2.996172)
			(xy 303.046305 -2.95795) (xy 303.126264 -2.926974) (xy 303.20874 -2.903507) (xy 303.29303 -2.887751)
			(xy 303.378413 -2.879839) (xy 303.464163 -2.879839) (xy 303.549546 -2.887751) (xy 303.633836 -2.903507)
			(xy 303.716312 -2.926974) (xy 303.796271 -2.95795) (xy 303.873031 -2.996172) (xy 303.945937 -3.041313)
			(xy 304.014366 -3.092989) (xy 304.077736 -3.150758) (xy 304.135505 -3.214128) (xy 304.187181 -3.282557)
			(xy 304.232322 -3.355463) (xy 304.270544 -3.432223) (xy 304.30152 -3.512182) (xy 304.324987 -3.594658)
			(xy 304.340743 -3.678948) (xy 304.348655 -3.764331) (xy 304.34915 -3.807206) (xy 304.348655 -3.850081)
			(xy 311.155321 -3.850081) (xy 311.155321 -3.764331) (xy 311.163233 -3.678948) (xy 311.178989 -3.594658)
			(xy 311.202456 -3.512182) (xy 311.233432 -3.432223) (xy 311.271654 -3.355463) (xy 311.316795 -3.282557)
			(xy 311.368471 -3.214128) (xy 311.42624 -3.150758) (xy 311.48961 -3.092989) (xy 311.558039 -3.041313)
			(xy 311.630945 -2.996172) (xy 311.707705 -2.95795) (xy 311.787664 -2.926974) (xy 311.87014 -2.903507)
			(xy 311.95443 -2.887751) (xy 312.039813 -2.879839) (xy 312.125563 -2.879839) (xy 312.210946 -2.887751)
			(xy 312.295236 -2.903507) (xy 312.377712 -2.926974) (xy 312.457671 -2.95795) (xy 312.478344 -2.968244)
			(xy 316.012068 -2.968244) (xy 316.012068 -2.104644) (xy 316.012572 -2.07509) (xy 316.020621 -2.016534)
			(xy 316.036567 -1.959619) (xy 316.060116 -1.905405) (xy 316.090827 -1.854902) (xy 316.128129 -1.809052)
			(xy 316.171326 -1.768709) (xy 316.219615 -1.734623) (xy 316.272095 -1.70743) (xy 316.32779 -1.687636)
			(xy 316.385661 -1.67561) (xy 316.44463 -1.671577) (xy 316.503599 -1.67561) (xy 316.56147 -1.687636)
			(xy 316.617165 -1.70743) (xy 316.669645 -1.734623) (xy 316.717934 -1.768709) (xy 316.761131 -1.809052)
			(xy 316.798433 -1.854902) (xy 316.829144 -1.905405) (xy 316.852693 -1.959619) (xy 316.868639 -2.016534)
			(xy 316.876688 -2.07509) (xy 316.877192 -2.104644) (xy 316.877192 -2.968244) (xy 316.876688 -2.997798)
			(xy 316.868639 -3.056354) (xy 316.852693 -3.113269) (xy 316.829144 -3.167483) (xy 316.798433 -3.217986)
			(xy 316.761131 -3.263836) (xy 316.717934 -3.304179) (xy 316.669645 -3.338265) (xy 316.617165 -3.365458)
			(xy 316.56147 -3.385252) (xy 316.503599 -3.397278) (xy 316.44463 -3.401312) (xy 316.385661 -3.397278)
			(xy 316.32779 -3.385252) (xy 316.272095 -3.365458) (xy 316.219615 -3.338265) (xy 316.171326 -3.304179)
			(xy 316.128129 -3.263836) (xy 316.090827 -3.217986) (xy 316.060116 -3.167483) (xy 316.036567 -3.113269)
			(xy 316.020621 -3.056354) (xy 316.012572 -2.997798) (xy 316.012068 -2.968244) (xy 312.478344 -2.968244)
			(xy 312.534431 -2.996172) (xy 312.607337 -3.041313) (xy 312.675766 -3.092989) (xy 312.739136 -3.150758)
			(xy 312.796905 -3.214128) (xy 312.848581 -3.282557) (xy 312.893722 -3.355463) (xy 312.931944 -3.432223)
			(xy 312.96292 -3.512182) (xy 312.986387 -3.594658) (xy 313.002143 -3.678948) (xy 313.010055 -3.764331)
			(xy 313.01055 -3.807206) (xy 313.010055 -3.850081) (xy 317.505321 -3.850081) (xy 317.505321 -3.764331)
			(xy 317.513233 -3.678948) (xy 317.528989 -3.594658) (xy 317.552456 -3.512182) (xy 317.583432 -3.432223)
			(xy 317.621654 -3.355463) (xy 317.666795 -3.282557) (xy 317.718471 -3.214128) (xy 317.77624 -3.150758)
			(xy 317.83961 -3.092989) (xy 317.908039 -3.041313) (xy 317.980945 -2.996172) (xy 318.057705 -2.95795)
			(xy 318.137664 -2.926974) (xy 318.22014 -2.903507) (xy 318.30443 -2.887751) (xy 318.389813 -2.879839)
			(xy 318.475563 -2.879839) (xy 318.560946 -2.887751) (xy 318.645236 -2.903507) (xy 318.727712 -2.926974)
			(xy 318.807671 -2.95795) (xy 318.884431 -2.996172) (xy 318.957337 -3.041313) (xy 319.025766 -3.092989)
			(xy 319.089136 -3.150758) (xy 319.146905 -3.214128) (xy 319.198581 -3.282557) (xy 319.243722 -3.355463)
			(xy 319.281944 -3.432223) (xy 319.31292 -3.512182) (xy 319.336387 -3.594658) (xy 319.352143 -3.678948)
			(xy 319.360055 -3.764331) (xy 319.36055 -3.807206) (xy 319.360055 -3.850081) (xy 361.894107 -3.850081)
			(xy 361.894107 -3.764331) (xy 361.902019 -3.678948) (xy 361.917775 -3.594658) (xy 361.941242 -3.512182)
			(xy 361.972218 -3.432223) (xy 362.01044 -3.355463) (xy 362.055581 -3.282557) (xy 362.107257 -3.214128)
			(xy 362.165026 -3.150758) (xy 362.228396 -3.092989) (xy 362.296825 -3.041313) (xy 362.369731 -2.996172)
			(xy 362.446491 -2.95795) (xy 362.52645 -2.926974) (xy 362.608926 -2.903507) (xy 362.693216 -2.887751)
			(xy 362.778599 -2.879839) (xy 362.864349 -2.879839) (xy 362.949732 -2.887751) (xy 363.034022 -2.903507)
			(xy 363.116498 -2.926974) (xy 363.196457 -2.95795) (xy 363.21713 -2.968244) (xy 364.379764 -2.968244)
			(xy 364.379764 -2.104644) (xy 364.380268 -2.075108) (xy 364.388312 -2.016586) (xy 364.404249 -1.959704)
			(xy 364.427784 -1.905522) (xy 364.458477 -1.855049) (xy 364.495757 -1.809226) (xy 364.538929 -1.768906)
			(xy 364.587189 -1.73484) (xy 364.639639 -1.707663) (xy 364.6953 -1.687881) (xy 364.753137 -1.675862)
			(xy 364.812072 -1.671831) (xy 364.871007 -1.675862) (xy 364.928844 -1.687881) (xy 364.984505 -1.707663)
			(xy 365.036955 -1.73484) (xy 365.085215 -1.768906) (xy 365.128387 -1.809226) (xy 365.165667 -1.855049)
			(xy 365.19636 -1.905522) (xy 365.219895 -1.959704) (xy 365.235832 -2.016586) (xy 365.243876 -2.075108)
			(xy 365.24438 -2.104644) (xy 365.24438 -2.968244) (xy 365.243876 -2.99778) (xy 365.235832 -3.056302)
			(xy 365.219895 -3.113184) (xy 365.19636 -3.167366) (xy 365.165667 -3.217839) (xy 365.128387 -3.263662)
			(xy 365.085215 -3.303982) (xy 365.036955 -3.338048) (xy 364.984505 -3.365225) (xy 364.928844 -3.385007)
			(xy 364.871007 -3.397026) (xy 364.812072 -3.401057) (xy 364.753137 -3.397026) (xy 364.6953 -3.385007)
			(xy 364.639639 -3.365225) (xy 364.587189 -3.338048) (xy 364.538929 -3.303982) (xy 364.495757 -3.263662)
			(xy 364.458477 -3.217839) (xy 364.427784 -3.167366) (xy 364.404249 -3.113184) (xy 364.388312 -3.056302)
			(xy 364.380268 -2.99778) (xy 364.379764 -2.968244) (xy 363.21713 -2.968244) (xy 363.273217 -2.996172)
			(xy 363.346123 -3.041313) (xy 363.414552 -3.092989) (xy 363.477922 -3.150758) (xy 363.535691 -3.214128)
			(xy 363.587367 -3.282557) (xy 363.632508 -3.355463) (xy 363.67073 -3.432223) (xy 363.701706 -3.512182)
			(xy 363.725173 -3.594658) (xy 363.740929 -3.678948) (xy 363.748841 -3.764331) (xy 363.749336 -3.807206)
			(xy 363.748841 -3.850081) (xy 368.244107 -3.850081) (xy 368.244107 -3.764331) (xy 368.252019 -3.678948)
			(xy 368.267775 -3.594658) (xy 368.291242 -3.512182) (xy 368.322218 -3.432223) (xy 368.36044 -3.355463)
			(xy 368.405581 -3.282557) (xy 368.457257 -3.214128) (xy 368.515026 -3.150758) (xy 368.578396 -3.092989)
			(xy 368.646825 -3.041313) (xy 368.719731 -2.996172) (xy 368.796491 -2.95795) (xy 368.87645 -2.926974)
			(xy 368.958926 -2.903507) (xy 369.043216 -2.887751) (xy 369.128599 -2.879839) (xy 369.214349 -2.879839)
			(xy 369.299732 -2.887751) (xy 369.384022 -2.903507) (xy 369.466498 -2.926974) (xy 369.546457 -2.95795)
			(xy 369.623217 -2.996172) (xy 369.696123 -3.041313) (xy 369.764552 -3.092989) (xy 369.827922 -3.150758)
			(xy 369.885691 -3.214128) (xy 369.937367 -3.282557) (xy 369.982508 -3.355463) (xy 370.02073 -3.432223)
			(xy 370.051706 -3.512182) (xy 370.075173 -3.594658) (xy 370.090929 -3.678948) (xy 370.098841 -3.764331)
			(xy 370.099336 -3.807206) (xy 370.098841 -3.850081) (xy 370.090929 -3.935464) (xy 370.075173 -4.019754)
			(xy 370.051706 -4.10223) (xy 370.02073 -4.182189) (xy 369.982508 -4.258949) (xy 369.937367 -4.331855)
			(xy 369.885691 -4.400284) (xy 369.827922 -4.463654) (xy 369.764552 -4.521423) (xy 369.696123 -4.573099)
			(xy 369.623217 -4.61824) (xy 369.546457 -4.656462) (xy 369.466498 -4.687438) (xy 369.384022 -4.710905)
			(xy 369.299732 -4.726661) (xy 369.214349 -4.734573) (xy 369.128599 -4.734573) (xy 369.043216 -4.726661)
			(xy 368.958926 -4.710905) (xy 368.87645 -4.687438) (xy 368.796491 -4.656462) (xy 368.719731 -4.61824)
			(xy 368.646825 -4.573099) (xy 368.578396 -4.521423) (xy 368.515026 -4.463654) (xy 368.457257 -4.400284)
			(xy 368.405581 -4.331855) (xy 368.36044 -4.258949) (xy 368.322218 -4.182189) (xy 368.291242 -4.10223)
			(xy 368.267775 -4.019754) (xy 368.252019 -3.935464) (xy 368.244107 -3.850081) (xy 363.748841 -3.850081)
			(xy 363.740929 -3.935464) (xy 363.725173 -4.019754) (xy 363.701706 -4.10223) (xy 363.67073 -4.182189)
			(xy 363.632508 -4.258949) (xy 363.587367 -4.331855) (xy 363.535691 -4.400284) (xy 363.477922 -4.463654)
			(xy 363.414552 -4.521423) (xy 363.346123 -4.573099) (xy 363.273217 -4.61824) (xy 363.196457 -4.656462)
			(xy 363.116498 -4.687438) (xy 363.034022 -4.710905) (xy 362.949732 -4.726661) (xy 362.864349 -4.734573)
			(xy 362.778599 -4.734573) (xy 362.693216 -4.726661) (xy 362.608926 -4.710905) (xy 362.52645 -4.687438)
			(xy 362.446491 -4.656462) (xy 362.369731 -4.61824) (xy 362.296825 -4.573099) (xy 362.228396 -4.521423)
			(xy 362.165026 -4.463654) (xy 362.107257 -4.400284) (xy 362.055581 -4.331855) (xy 362.01044 -4.258949)
			(xy 361.972218 -4.182189) (xy 361.941242 -4.10223) (xy 361.917775 -4.019754) (xy 361.902019 -3.935464)
			(xy 361.894107 -3.850081) (xy 319.360055 -3.850081) (xy 319.352143 -3.935464) (xy 319.336387 -4.019754)
			(xy 319.31292 -4.10223) (xy 319.281944 -4.182189) (xy 319.243722 -4.258949) (xy 319.198581 -4.331855)
			(xy 319.146905 -4.400284) (xy 319.089136 -4.463654) (xy 319.025766 -4.521423) (xy 318.957337 -4.573099)
			(xy 318.884431 -4.61824) (xy 318.807671 -4.656462) (xy 318.727712 -4.687438) (xy 318.645236 -4.710905)
			(xy 318.560946 -4.726661) (xy 318.475563 -4.734573) (xy 318.389813 -4.734573) (xy 318.30443 -4.726661)
			(xy 318.22014 -4.710905) (xy 318.137664 -4.687438) (xy 318.057705 -4.656462) (xy 317.980945 -4.61824)
			(xy 317.908039 -4.573099) (xy 317.83961 -4.521423) (xy 317.77624 -4.463654) (xy 317.718471 -4.400284)
			(xy 317.666795 -4.331855) (xy 317.621654 -4.258949) (xy 317.583432 -4.182189) (xy 317.552456 -4.10223)
			(xy 317.528989 -4.019754) (xy 317.513233 -3.935464) (xy 317.505321 -3.850081) (xy 313.010055 -3.850081)
			(xy 313.002143 -3.935464) (xy 312.986387 -4.019754) (xy 312.96292 -4.10223) (xy 312.931944 -4.182189)
			(xy 312.893722 -4.258949) (xy 312.848581 -4.331855) (xy 312.796905 -4.400284) (xy 312.739136 -4.463654)
			(xy 312.675766 -4.521423) (xy 312.607337 -4.573099) (xy 312.534431 -4.61824) (xy 312.457671 -4.656462)
			(xy 312.377712 -4.687438) (xy 312.295236 -4.710905) (xy 312.210946 -4.726661) (xy 312.125563 -4.734573)
			(xy 312.039813 -4.734573) (xy 311.95443 -4.726661) (xy 311.87014 -4.710905) (xy 311.787664 -4.687438)
			(xy 311.707705 -4.656462) (xy 311.630945 -4.61824) (xy 311.558039 -4.573099) (xy 311.48961 -4.521423)
			(xy 311.42624 -4.463654) (xy 311.368471 -4.400284) (xy 311.316795 -4.331855) (xy 311.271654 -4.258949)
			(xy 311.233432 -4.182189) (xy 311.202456 -4.10223) (xy 311.178989 -4.019754) (xy 311.163233 -3.935464)
			(xy 311.155321 -3.850081) (xy 304.348655 -3.850081) (xy 304.340743 -3.935464) (xy 304.324987 -4.019754)
			(xy 304.30152 -4.10223) (xy 304.270544 -4.182189) (xy 304.232322 -4.258949) (xy 304.187181 -4.331855)
			(xy 304.135505 -4.400284) (xy 304.077736 -4.463654) (xy 304.014366 -4.521423) (xy 303.945937 -4.573099)
			(xy 303.873031 -4.61824) (xy 303.796271 -4.656462) (xy 303.716312 -4.687438) (xy 303.633836 -4.710905)
			(xy 303.549546 -4.726661) (xy 303.464163 -4.734573) (xy 303.378413 -4.734573) (xy 303.29303 -4.726661)
			(xy 303.20874 -4.710905) (xy 303.126264 -4.687438) (xy 303.046305 -4.656462) (xy 302.969545 -4.61824)
			(xy 302.896639 -4.573099) (xy 302.82821 -4.521423) (xy 302.76484 -4.463654) (xy 302.707071 -4.400284)
			(xy 302.655395 -4.331855) (xy 302.610254 -4.258949) (xy 302.572032 -4.182189) (xy 302.541056 -4.10223)
			(xy 302.517589 -4.019754) (xy 302.501833 -3.935464) (xy 302.493921 -3.850081) (xy 297.998655 -3.850081)
			(xy 297.990743 -3.935464) (xy 297.974987 -4.019754) (xy 297.95152 -4.10223) (xy 297.920544 -4.182189)
			(xy 297.882322 -4.258949) (xy 297.837181 -4.331855) (xy 297.785505 -4.400284) (xy 297.727736 -4.463654)
			(xy 297.664366 -4.521423) (xy 297.595937 -4.573099) (xy 297.523031 -4.61824) (xy 297.446271 -4.656462)
			(xy 297.366312 -4.687438) (xy 297.283836 -4.710905) (xy 297.199546 -4.726661) (xy 297.114163 -4.734573)
			(xy 297.028413 -4.734573) (xy 296.94303 -4.726661) (xy 296.85874 -4.710905) (xy 296.776264 -4.687438)
			(xy 296.696305 -4.656462) (xy 296.619545 -4.61824) (xy 296.546639 -4.573099) (xy 296.47821 -4.521423)
			(xy 296.41484 -4.463654) (xy 296.357071 -4.400284) (xy 296.305395 -4.331855) (xy 296.260254 -4.258949)
			(xy 296.222032 -4.182189) (xy 296.191056 -4.10223) (xy 296.167589 -4.019754) (xy 296.151833 -3.935464)
			(xy 296.143921 -3.850081) (xy 216.865975 -3.850081) (xy 216.858063 -3.935464) (xy 216.842307 -4.019754)
			(xy 216.81884 -4.10223) (xy 216.787864 -4.182189) (xy 216.749642 -4.258949) (xy 216.704501 -4.331855)
			(xy 216.652825 -4.400284) (xy 216.595056 -4.463654) (xy 216.531686 -4.521423) (xy 216.463257 -4.573099)
			(xy 216.390351 -4.61824) (xy 216.313591 -4.656462) (xy 216.233632 -4.687438) (xy 216.151156 -4.710905)
			(xy 216.066866 -4.726661) (xy 215.981483 -4.734573) (xy 215.895733 -4.734573) (xy 215.81035 -4.726661)
			(xy 215.72606 -4.710905) (xy 215.643584 -4.687438) (xy 215.563625 -4.656462) (xy 215.486865 -4.61824)
			(xy 215.413959 -4.573099) (xy 215.34553 -4.521423) (xy 215.28216 -4.463654) (xy 215.224391 -4.400284)
			(xy 215.172715 -4.331855) (xy 215.127574 -4.258949) (xy 215.089352 -4.182189) (xy 215.058376 -4.10223)
			(xy 215.034909 -4.019754) (xy 215.019153 -3.935464) (xy 215.011241 -3.850081) (xy 210.515975 -3.850081)
			(xy 210.508063 -3.935464) (xy 210.492307 -4.019754) (xy 210.46884 -4.10223) (xy 210.437864 -4.182189)
			(xy 210.399642 -4.258949) (xy 210.354501 -4.331855) (xy 210.302825 -4.400284) (xy 210.245056 -4.463654)
			(xy 210.181686 -4.521423) (xy 210.113257 -4.573099) (xy 210.040351 -4.61824) (xy 209.963591 -4.656462)
			(xy 209.883632 -4.687438) (xy 209.801156 -4.710905) (xy 209.716866 -4.726661) (xy 209.631483 -4.734573)
			(xy 209.545733 -4.734573) (xy 209.46035 -4.726661) (xy 209.37606 -4.710905) (xy 209.293584 -4.687438)
			(xy 209.213625 -4.656462) (xy 209.136865 -4.61824) (xy 209.063959 -4.573099) (xy 208.99553 -4.521423)
			(xy 208.93216 -4.463654) (xy 208.874391 -4.400284) (xy 208.822715 -4.331855) (xy 208.777574 -4.258949)
			(xy 208.739352 -4.182189) (xy 208.708376 -4.10223) (xy 208.684909 -4.019754) (xy 208.669153 -3.935464)
			(xy 208.661241 -3.850081) (xy 196.990215 -3.850081) (xy 196.992516 -3.85486) (xy 197.046381 -3.984909)
			(xy 197.09287 -4.117774) (xy 197.131836 -4.253037) (xy 197.163157 -4.390271) (xy 197.186733 -4.529046)
			(xy 197.202491 -4.668924) (xy 197.210381 -4.809466) (xy 197.210934 -4.879848) (xy 197.210934 -6.390081)
			(xy 208.661241 -6.390081) (xy 208.661241 -6.304331) (xy 208.669153 -6.218948) (xy 208.684909 -6.134658)
			(xy 208.708376 -6.052182) (xy 208.739352 -5.972223) (xy 208.777574 -5.895463) (xy 208.822715 -5.822557)
			(xy 208.874391 -5.754128) (xy 208.93216 -5.690758) (xy 208.99553 -5.632989) (xy 209.063959 -5.581313)
			(xy 209.136865 -5.536172) (xy 209.213625 -5.49795) (xy 209.293584 -5.466974) (xy 209.37606 -5.443507)
			(xy 209.46035 -5.427751) (xy 209.545733 -5.419839) (xy 209.631483 -5.419839) (xy 209.716866 -5.427751)
			(xy 209.801156 -5.443507) (xy 209.883632 -5.466974) (xy 209.963591 -5.49795) (xy 209.984264 -5.508244)
			(xy 213.517988 -5.508244) (xy 213.517988 -4.644644) (xy 213.518492 -4.61509) (xy 213.526541 -4.556534)
			(xy 213.542487 -4.499619) (xy 213.566036 -4.445405) (xy 213.596747 -4.394902) (xy 213.634049 -4.349052)
			(xy 213.677246 -4.308709) (xy 213.725535 -4.274623) (xy 213.778015 -4.24743) (xy 213.83371 -4.227636)
			(xy 213.891581 -4.21561) (xy 213.95055 -4.211577) (xy 214.009519 -4.21561) (xy 214.06739 -4.227636)
			(xy 214.123085 -4.24743) (xy 214.175565 -4.274623) (xy 214.223854 -4.308709) (xy 214.267051 -4.349052)
			(xy 214.304353 -4.394902) (xy 214.335064 -4.445405) (xy 214.358613 -4.499619) (xy 214.374559 -4.556534)
			(xy 214.382608 -4.61509) (xy 214.383112 -4.644644) (xy 214.383112 -5.508244) (xy 214.382608 -5.537798)
			(xy 214.374559 -5.596354) (xy 214.358613 -5.653269) (xy 214.335064 -5.707483) (xy 214.304353 -5.757986)
			(xy 214.267051 -5.803836) (xy 214.223854 -5.844179) (xy 214.175565 -5.878265) (xy 214.123085 -5.905458)
			(xy 214.06739 -5.925252) (xy 214.009519 -5.937278) (xy 213.95055 -5.941312) (xy 213.891581 -5.937278)
			(xy 213.83371 -5.925252) (xy 213.778015 -5.905458) (xy 213.725535 -5.878265) (xy 213.677246 -5.844179)
			(xy 213.634049 -5.803836) (xy 213.596747 -5.757986) (xy 213.566036 -5.707483) (xy 213.542487 -5.653269)
			(xy 213.526541 -5.596354) (xy 213.518492 -5.537798) (xy 213.517988 -5.508244) (xy 209.984264 -5.508244)
			(xy 210.040351 -5.536172) (xy 210.113257 -5.581313) (xy 210.181686 -5.632989) (xy 210.245056 -5.690758)
			(xy 210.302825 -5.754128) (xy 210.354501 -5.822557) (xy 210.399642 -5.895463) (xy 210.437864 -5.972223)
			(xy 210.46884 -6.052182) (xy 210.492307 -6.134658) (xy 210.508063 -6.218948) (xy 210.515975 -6.304331)
			(xy 210.51647 -6.347206) (xy 210.515975 -6.390081) (xy 215.011241 -6.390081) (xy 215.011241 -6.304331)
			(xy 215.019153 -6.218948) (xy 215.034909 -6.134658) (xy 215.058376 -6.052182) (xy 215.089352 -5.972223)
			(xy 215.127574 -5.895463) (xy 215.172715 -5.822557) (xy 215.224391 -5.754128) (xy 215.28216 -5.690758)
			(xy 215.34553 -5.632989) (xy 215.413959 -5.581313) (xy 215.486865 -5.536172) (xy 215.563625 -5.49795)
			(xy 215.643584 -5.466974) (xy 215.72606 -5.443507) (xy 215.81035 -5.427751) (xy 215.895733 -5.419839)
			(xy 215.981483 -5.419839) (xy 216.066866 -5.427751) (xy 216.151156 -5.443507) (xy 216.233632 -5.466974)
			(xy 216.313591 -5.49795) (xy 216.390351 -5.536172) (xy 216.463257 -5.581313) (xy 216.531686 -5.632989)
			(xy 216.595056 -5.690758) (xy 216.652825 -5.754128) (xy 216.704501 -5.822557) (xy 216.749642 -5.895463)
			(xy 216.787864 -5.972223) (xy 216.81884 -6.052182) (xy 216.842307 -6.134658) (xy 216.858063 -6.218948)
			(xy 216.865975 -6.304331) (xy 216.86647 -6.347206) (xy 216.865975 -6.390081) (xy 296.143921 -6.390081)
			(xy 296.143921 -6.304331) (xy 296.151833 -6.218948) (xy 296.167589 -6.134658) (xy 296.191056 -6.052182)
			(xy 296.222032 -5.972223) (xy 296.260254 -5.895463) (xy 296.305395 -5.822557) (xy 296.357071 -5.754128)
			(xy 296.41484 -5.690758) (xy 296.47821 -5.632989) (xy 296.546639 -5.581313) (xy 296.619545 -5.536172)
			(xy 296.696305 -5.49795) (xy 296.776264 -5.466974) (xy 296.85874 -5.443507) (xy 296.94303 -5.427751)
			(xy 297.028413 -5.419839) (xy 297.114163 -5.419839) (xy 297.199546 -5.427751) (xy 297.283836 -5.443507)
			(xy 297.366312 -5.466974) (xy 297.446271 -5.49795) (xy 297.466944 -5.508244) (xy 298.629324 -5.508244)
			(xy 298.629324 -4.644644) (xy 298.629828 -4.61509) (xy 298.637877 -4.556534) (xy 298.653823 -4.499619)
			(xy 298.677372 -4.445405) (xy 298.708083 -4.394902) (xy 298.745385 -4.349052) (xy 298.788582 -4.308709)
			(xy 298.836871 -4.274623) (xy 298.889351 -4.24743) (xy 298.945046 -4.227636) (xy 299.002917 -4.21561)
			(xy 299.061886 -4.211577) (xy 299.120855 -4.21561) (xy 299.178726 -4.227636) (xy 299.234421 -4.24743)
			(xy 299.286901 -4.274623) (xy 299.33519 -4.308709) (xy 299.378387 -4.349052) (xy 299.415689 -4.394902)
			(xy 299.4464 -4.445405) (xy 299.469949 -4.499619) (xy 299.485895 -4.556534) (xy 299.493944 -4.61509)
			(xy 299.494448 -4.644644) (xy 299.494448 -5.508244) (xy 299.493944 -5.537798) (xy 299.485895 -5.596354)
			(xy 299.469949 -5.653269) (xy 299.4464 -5.707483) (xy 299.415689 -5.757986) (xy 299.378387 -5.803836)
			(xy 299.33519 -5.844179) (xy 299.286901 -5.878265) (xy 299.234421 -5.905458) (xy 299.178726 -5.925252)
			(xy 299.120855 -5.937278) (xy 299.061886 -5.941312) (xy 299.002917 -5.937278) (xy 298.945046 -5.925252)
			(xy 298.889351 -5.905458) (xy 298.836871 -5.878265) (xy 298.788582 -5.844179) (xy 298.745385 -5.803836)
			(xy 298.708083 -5.757986) (xy 298.677372 -5.707483) (xy 298.653823 -5.653269) (xy 298.637877 -5.596354)
			(xy 298.629828 -5.537798) (xy 298.629324 -5.508244) (xy 297.466944 -5.508244) (xy 297.523031 -5.536172)
			(xy 297.595937 -5.581313) (xy 297.664366 -5.632989) (xy 297.727736 -5.690758) (xy 297.785505 -5.754128)
			(xy 297.837181 -5.822557) (xy 297.882322 -5.895463) (xy 297.920544 -5.972223) (xy 297.95152 -6.052182)
			(xy 297.974987 -6.134658) (xy 297.990743 -6.218948) (xy 297.998655 -6.304331) (xy 297.99915 -6.347206)
			(xy 297.998655 -6.390081) (xy 302.493921 -6.390081) (xy 302.493921 -6.304331) (xy 302.501833 -6.218948)
			(xy 302.517589 -6.134658) (xy 302.541056 -6.052182) (xy 302.572032 -5.972223) (xy 302.610254 -5.895463)
			(xy 302.655395 -5.822557) (xy 302.707071 -5.754128) (xy 302.76484 -5.690758) (xy 302.82821 -5.632989)
			(xy 302.896639 -5.581313) (xy 302.969545 -5.536172) (xy 303.046305 -5.49795) (xy 303.126264 -5.466974)
			(xy 303.20874 -5.443507) (xy 303.29303 -5.427751) (xy 303.378413 -5.419839) (xy 303.464163 -5.419839)
			(xy 303.549546 -5.427751) (xy 303.633836 -5.443507) (xy 303.716312 -5.466974) (xy 303.796271 -5.49795)
			(xy 303.873031 -5.536172) (xy 303.945937 -5.581313) (xy 304.014366 -5.632989) (xy 304.077736 -5.690758)
			(xy 304.135505 -5.754128) (xy 304.187181 -5.822557) (xy 304.232322 -5.895463) (xy 304.270544 -5.972223)
			(xy 304.30152 -6.052182) (xy 304.324987 -6.134658) (xy 304.340743 -6.218948) (xy 304.348655 -6.304331)
			(xy 304.34915 -6.347206) (xy 304.348655 -6.390081) (xy 311.155321 -6.390081) (xy 311.155321 -6.304331)
			(xy 311.163233 -6.218948) (xy 311.178989 -6.134658) (xy 311.202456 -6.052182) (xy 311.233432 -5.972223)
			(xy 311.271654 -5.895463) (xy 311.316795 -5.822557) (xy 311.368471 -5.754128) (xy 311.42624 -5.690758)
			(xy 311.48961 -5.632989) (xy 311.558039 -5.581313) (xy 311.630945 -5.536172) (xy 311.707705 -5.49795)
			(xy 311.787664 -5.466974) (xy 311.87014 -5.443507) (xy 311.95443 -5.427751) (xy 312.039813 -5.419839)
			(xy 312.125563 -5.419839) (xy 312.210946 -5.427751) (xy 312.295236 -5.443507) (xy 312.377712 -5.466974)
			(xy 312.457671 -5.49795) (xy 312.534431 -5.536172) (xy 312.607337 -5.581313) (xy 312.675766 -5.632989)
			(xy 312.739136 -5.690758) (xy 312.796905 -5.754128) (xy 312.848581 -5.822557) (xy 312.893722 -5.895463)
			(xy 312.931944 -5.972223) (xy 312.96292 -6.052182) (xy 312.986387 -6.134658) (xy 313.002143 -6.218948)
			(xy 313.010055 -6.304331) (xy 313.01055 -6.347206) (xy 313.010055 -6.390081) (xy 317.505321 -6.390081)
			(xy 317.505321 -6.304331) (xy 317.513233 -6.218948) (xy 317.528989 -6.134658) (xy 317.552456 -6.052182)
			(xy 317.583432 -5.972223) (xy 317.621654 -5.895463) (xy 317.666795 -5.822557) (xy 317.718471 -5.754128)
			(xy 317.77624 -5.690758) (xy 317.83961 -5.632989) (xy 317.908039 -5.581313) (xy 317.980945 -5.536172)
			(xy 318.057705 -5.49795) (xy 318.137664 -5.466974) (xy 318.22014 -5.443507) (xy 318.30443 -5.427751)
			(xy 318.389813 -5.419839) (xy 318.475563 -5.419839) (xy 318.560946 -5.427751) (xy 318.645236 -5.443507)
			(xy 318.727712 -5.466974) (xy 318.807671 -5.49795) (xy 318.884431 -5.536172) (xy 318.957337 -5.581313)
			(xy 319.025766 -5.632989) (xy 319.089136 -5.690758) (xy 319.146905 -5.754128) (xy 319.198581 -5.822557)
			(xy 319.243722 -5.895463) (xy 319.281944 -5.972223) (xy 319.31292 -6.052182) (xy 319.336387 -6.134658)
			(xy 319.352143 -6.218948) (xy 319.360055 -6.304331) (xy 319.36055 -6.347206) (xy 319.360055 -6.390081)
			(xy 361.894107 -6.390081) (xy 361.894107 -6.304331) (xy 361.902019 -6.218948) (xy 361.917775 -6.134658)
			(xy 361.941242 -6.052182) (xy 361.972218 -5.972223) (xy 362.01044 -5.895463) (xy 362.055581 -5.822557)
			(xy 362.107257 -5.754128) (xy 362.165026 -5.690758) (xy 362.228396 -5.632989) (xy 362.296825 -5.581313)
			(xy 362.369731 -5.536172) (xy 362.446491 -5.49795) (xy 362.52645 -5.466974) (xy 362.608926 -5.443507)
			(xy 362.693216 -5.427751) (xy 362.778599 -5.419839) (xy 362.864349 -5.419839) (xy 362.949732 -5.427751)
			(xy 363.034022 -5.443507) (xy 363.116498 -5.466974) (xy 363.196457 -5.49795) (xy 363.273217 -5.536172)
			(xy 363.346123 -5.581313) (xy 363.414552 -5.632989) (xy 363.477922 -5.690758) (xy 363.535691 -5.754128)
			(xy 363.587367 -5.822557) (xy 363.632508 -5.895463) (xy 363.67073 -5.972223) (xy 363.701706 -6.052182)
			(xy 363.725173 -6.134658) (xy 363.740929 -6.218948) (xy 363.748841 -6.304331) (xy 363.749336 -6.347206)
			(xy 363.748841 -6.390081) (xy 368.244107 -6.390081) (xy 368.244107 -6.304331) (xy 368.252019 -6.218948)
			(xy 368.267775 -6.134658) (xy 368.291242 -6.052182) (xy 368.322218 -5.972223) (xy 368.36044 -5.895463)
			(xy 368.405581 -5.822557) (xy 368.457257 -5.754128) (xy 368.515026 -5.690758) (xy 368.578396 -5.632989)
			(xy 368.646825 -5.581313) (xy 368.719731 -5.536172) (xy 368.796491 -5.49795) (xy 368.87645 -5.466974)
			(xy 368.958926 -5.443507) (xy 369.043216 -5.427751) (xy 369.128599 -5.419839) (xy 369.214349 -5.419839)
			(xy 369.299732 -5.427751) (xy 369.384022 -5.443507) (xy 369.466498 -5.466974) (xy 369.546457 -5.49795)
			(xy 369.623217 -5.536172) (xy 369.696123 -5.581313) (xy 369.764552 -5.632989) (xy 369.827922 -5.690758)
			(xy 369.885691 -5.754128) (xy 369.937367 -5.822557) (xy 369.982508 -5.895463) (xy 370.02073 -5.972223)
			(xy 370.051706 -6.052182) (xy 370.075173 -6.134658) (xy 370.090929 -6.218948) (xy 370.098841 -6.304331)
			(xy 370.099336 -6.347206) (xy 370.098841 -6.390081) (xy 370.090929 -6.475464) (xy 370.075173 -6.559754)
			(xy 370.051706 -6.64223) (xy 370.02073 -6.722189) (xy 369.982508 -6.798949) (xy 369.937367 -6.871855)
			(xy 369.885691 -6.940284) (xy 369.827922 -7.003654) (xy 369.764552 -7.061423) (xy 369.696123 -7.113099)
			(xy 369.623217 -7.15824) (xy 369.546457 -7.196462) (xy 369.466498 -7.227438) (xy 369.384022 -7.250905)
			(xy 369.299732 -7.266661) (xy 369.214349 -7.274573) (xy 369.128599 -7.274573) (xy 369.043216 -7.266661)
			(xy 368.958926 -7.250905) (xy 368.87645 -7.227438) (xy 368.796491 -7.196462) (xy 368.719731 -7.15824)
			(xy 368.646825 -7.113099) (xy 368.578396 -7.061423) (xy 368.515026 -7.003654) (xy 368.457257 -6.940284)
			(xy 368.405581 -6.871855) (xy 368.36044 -6.798949) (xy 368.322218 -6.722189) (xy 368.291242 -6.64223)
			(xy 368.267775 -6.559754) (xy 368.252019 -6.475464) (xy 368.244107 -6.390081) (xy 363.748841 -6.390081)
			(xy 363.740929 -6.475464) (xy 363.725173 -6.559754) (xy 363.701706 -6.64223) (xy 363.67073 -6.722189)
			(xy 363.632508 -6.798949) (xy 363.587367 -6.871855) (xy 363.535691 -6.940284) (xy 363.477922 -7.003654)
			(xy 363.414552 -7.061423) (xy 363.346123 -7.113099) (xy 363.273217 -7.15824) (xy 363.196457 -7.196462)
			(xy 363.116498 -7.227438) (xy 363.034022 -7.250905) (xy 362.949732 -7.266661) (xy 362.864349 -7.274573)
			(xy 362.778599 -7.274573) (xy 362.693216 -7.266661) (xy 362.608926 -7.250905) (xy 362.52645 -7.227438)
			(xy 362.446491 -7.196462) (xy 362.369731 -7.15824) (xy 362.296825 -7.113099) (xy 362.228396 -7.061423)
			(xy 362.165026 -7.003654) (xy 362.107257 -6.940284) (xy 362.055581 -6.871855) (xy 362.01044 -6.798949)
			(xy 361.972218 -6.722189) (xy 361.941242 -6.64223) (xy 361.917775 -6.559754) (xy 361.902019 -6.475464)
			(xy 361.894107 -6.390081) (xy 319.360055 -6.390081) (xy 319.352143 -6.475464) (xy 319.336387 -6.559754)
			(xy 319.31292 -6.64223) (xy 319.281944 -6.722189) (xy 319.243722 -6.798949) (xy 319.198581 -6.871855)
			(xy 319.146905 -6.940284) (xy 319.089136 -7.003654) (xy 319.025766 -7.061423) (xy 318.957337 -7.113099)
			(xy 318.884431 -7.15824) (xy 318.807671 -7.196462) (xy 318.727712 -7.227438) (xy 318.645236 -7.250905)
			(xy 318.560946 -7.266661) (xy 318.475563 -7.274573) (xy 318.389813 -7.274573) (xy 318.30443 -7.266661)
			(xy 318.22014 -7.250905) (xy 318.137664 -7.227438) (xy 318.057705 -7.196462) (xy 317.980945 -7.15824)
			(xy 317.908039 -7.113099) (xy 317.83961 -7.061423) (xy 317.77624 -7.003654) (xy 317.718471 -6.940284)
			(xy 317.666795 -6.871855) (xy 317.621654 -6.798949) (xy 317.583432 -6.722189) (xy 317.552456 -6.64223)
			(xy 317.528989 -6.559754) (xy 317.513233 -6.475464) (xy 317.505321 -6.390081) (xy 313.010055 -6.390081)
			(xy 313.002143 -6.475464) (xy 312.986387 -6.559754) (xy 312.96292 -6.64223) (xy 312.931944 -6.722189)
			(xy 312.893722 -6.798949) (xy 312.848581 -6.871855) (xy 312.796905 -6.940284) (xy 312.739136 -7.003654)
			(xy 312.675766 -7.061423) (xy 312.607337 -7.113099) (xy 312.534431 -7.15824) (xy 312.457671 -7.196462)
			(xy 312.377712 -7.227438) (xy 312.295236 -7.250905) (xy 312.210946 -7.266661) (xy 312.125563 -7.274573)
			(xy 312.039813 -7.274573) (xy 311.95443 -7.266661) (xy 311.87014 -7.250905) (xy 311.787664 -7.227438)
			(xy 311.707705 -7.196462) (xy 311.630945 -7.15824) (xy 311.558039 -7.113099) (xy 311.48961 -7.061423)
			(xy 311.42624 -7.003654) (xy 311.368471 -6.940284) (xy 311.316795 -6.871855) (xy 311.271654 -6.798949)
			(xy 311.233432 -6.722189) (xy 311.202456 -6.64223) (xy 311.178989 -6.559754) (xy 311.163233 -6.475464)
			(xy 311.155321 -6.390081) (xy 304.348655 -6.390081) (xy 304.340743 -6.475464) (xy 304.324987 -6.559754)
			(xy 304.30152 -6.64223) (xy 304.270544 -6.722189) (xy 304.232322 -6.798949) (xy 304.187181 -6.871855)
			(xy 304.135505 -6.940284) (xy 304.077736 -7.003654) (xy 304.014366 -7.061423) (xy 303.945937 -7.113099)
			(xy 303.873031 -7.15824) (xy 303.796271 -7.196462) (xy 303.716312 -7.227438) (xy 303.633836 -7.250905)
			(xy 303.549546 -7.266661) (xy 303.464163 -7.274573) (xy 303.378413 -7.274573) (xy 303.29303 -7.266661)
			(xy 303.20874 -7.250905) (xy 303.126264 -7.227438) (xy 303.046305 -7.196462) (xy 302.969545 -7.15824)
			(xy 302.896639 -7.113099) (xy 302.82821 -7.061423) (xy 302.76484 -7.003654) (xy 302.707071 -6.940284)
			(xy 302.655395 -6.871855) (xy 302.610254 -6.798949) (xy 302.572032 -6.722189) (xy 302.541056 -6.64223)
			(xy 302.517589 -6.559754) (xy 302.501833 -6.475464) (xy 302.493921 -6.390081) (xy 297.998655 -6.390081)
			(xy 297.990743 -6.475464) (xy 297.974987 -6.559754) (xy 297.95152 -6.64223) (xy 297.920544 -6.722189)
			(xy 297.882322 -6.798949) (xy 297.837181 -6.871855) (xy 297.785505 -6.940284) (xy 297.727736 -7.003654)
			(xy 297.664366 -7.061423) (xy 297.595937 -7.113099) (xy 297.523031 -7.15824) (xy 297.446271 -7.196462)
			(xy 297.366312 -7.227438) (xy 297.283836 -7.250905) (xy 297.199546 -7.266661) (xy 297.114163 -7.274573)
			(xy 297.028413 -7.274573) (xy 296.94303 -7.266661) (xy 296.85874 -7.250905) (xy 296.776264 -7.227438)
			(xy 296.696305 -7.196462) (xy 296.619545 -7.15824) (xy 296.546639 -7.113099) (xy 296.47821 -7.061423)
			(xy 296.41484 -7.003654) (xy 296.357071 -6.940284) (xy 296.305395 -6.871855) (xy 296.260254 -6.798949)
			(xy 296.222032 -6.722189) (xy 296.191056 -6.64223) (xy 296.167589 -6.559754) (xy 296.151833 -6.475464)
			(xy 296.143921 -6.390081) (xy 216.865975 -6.390081) (xy 216.858063 -6.475464) (xy 216.842307 -6.559754)
			(xy 216.81884 -6.64223) (xy 216.787864 -6.722189) (xy 216.749642 -6.798949) (xy 216.704501 -6.871855)
			(xy 216.652825 -6.940284) (xy 216.595056 -7.003654) (xy 216.531686 -7.061423) (xy 216.463257 -7.113099)
			(xy 216.390351 -7.15824) (xy 216.313591 -7.196462) (xy 216.233632 -7.227438) (xy 216.151156 -7.250905)
			(xy 216.066866 -7.266661) (xy 215.981483 -7.274573) (xy 215.895733 -7.274573) (xy 215.81035 -7.266661)
			(xy 215.72606 -7.250905) (xy 215.643584 -7.227438) (xy 215.563625 -7.196462) (xy 215.486865 -7.15824)
			(xy 215.413959 -7.113099) (xy 215.34553 -7.061423) (xy 215.28216 -7.003654) (xy 215.224391 -6.940284)
			(xy 215.172715 -6.871855) (xy 215.127574 -6.798949) (xy 215.089352 -6.722189) (xy 215.058376 -6.64223)
			(xy 215.034909 -6.559754) (xy 215.019153 -6.475464) (xy 215.011241 -6.390081) (xy 210.515975 -6.390081)
			(xy 210.508063 -6.475464) (xy 210.492307 -6.559754) (xy 210.46884 -6.64223) (xy 210.437864 -6.722189)
			(xy 210.399642 -6.798949) (xy 210.354501 -6.871855) (xy 210.302825 -6.940284) (xy 210.245056 -7.003654)
			(xy 210.181686 -7.061423) (xy 210.113257 -7.113099) (xy 210.040351 -7.15824) (xy 209.963591 -7.196462)
			(xy 209.883632 -7.227438) (xy 209.801156 -7.250905) (xy 209.716866 -7.266661) (xy 209.631483 -7.274573)
			(xy 209.545733 -7.274573) (xy 209.46035 -7.266661) (xy 209.37606 -7.250905) (xy 209.293584 -7.227438)
			(xy 209.213625 -7.196462) (xy 209.136865 -7.15824) (xy 209.063959 -7.113099) (xy 208.99553 -7.061423)
			(xy 208.93216 -7.003654) (xy 208.874391 -6.940284) (xy 208.822715 -6.871855) (xy 208.777574 -6.798949)
			(xy 208.739352 -6.722189) (xy 208.708376 -6.64223) (xy 208.684909 -6.559754) (xy 208.669153 -6.475464)
			(xy 208.661241 -6.390081) (xy 197.210934 -6.390081) (xy 197.210934 -7.78002) (xy 197.211456 -7.835788)
			(xy 197.219793 -7.947013) (xy 197.236418 -8.057304) (xy 197.261239 -8.166044) (xy 197.294116 -8.272625)
			(xy 197.334866 -8.376451) (xy 197.383261 -8.476941) (xy 197.439031 -8.573534) (xy 197.501863 -8.66569)
			(xy 197.571406 -8.752892) (xy 197.647271 -8.834653) (xy 197.729034 -8.910516) (xy 197.816238 -8.980057)
			(xy 197.908394 -9.042887) (xy 198.004989 -9.098654) (xy 198.10548 -9.147047) (xy 198.209307 -9.187795)
			(xy 198.315889 -9.22067) (xy 198.42463 -9.245488) (xy 198.534921 -9.262111) (xy 198.646146 -9.270445)
			(xy 198.701914 -9.271) (xy 223.300036 -9.271) (xy 223.370417 -9.271495) (xy 223.510959 -9.279389)
			(xy 223.650836 -9.295152) (xy 223.78961 -9.318732) (xy 223.926844 -9.350057) (xy 224.062105 -9.389027)
			(xy 224.194968 -9.435519) (xy 224.325015 -9.489388) (xy 224.451838 -9.550465) (xy 224.575036 -9.618556)
			(xy 224.694222 -9.693447) (xy 224.809022 -9.774904) (xy 224.919074 -9.862669) (xy 225.024032 -9.956467)
			(xy 225.123566 -10.056003) (xy 225.217361 -10.160962) (xy 225.305125 -10.271016) (xy 225.386579 -10.385818)
			(xy 225.461469 -10.505006) (xy 225.529557 -10.628205) (xy 225.590631 -10.755029) (xy 225.644498 -10.885077)
			(xy 225.690988 -11.017941) (xy 225.729955 -11.153203) (xy 225.761277 -11.290437) (xy 225.784855 -11.429211)
			(xy 225.800615 -11.569089) (xy 225.808507 -11.709631) (xy 225.809048 -11.780012) (xy 225.809048 -33.120076)
			(xy 225.809549 -33.152224) (xy 225.817939 -33.21597) (xy 225.834578 -33.278076) (xy 225.859182 -33.337478)
			(xy 225.891329 -33.39316) (xy 225.93047 -33.44417) (xy 225.975934 -33.489634) (xy 226.026945 -33.528774)
			(xy 226.082627 -33.560921) (xy 226.14203 -33.585524) (xy 226.204136 -33.602162) (xy 226.267882 -33.610551)
			(xy 226.30003 -33.611058)
		)
		(stroke
			(width 0)
			(type solid)
		)
		(fill yes)
		(layer "In3.Cu")
		(net "DELTA_L_GND_1")
	)
	(gr_poly
		(pts
			(xy 194.445128 -441.480956) (xy 194.455142 -441.480531) (xy 194.473642 -441.472854) (xy 194.487795 -441.458682)
			(xy 194.495445 -441.440171) (xy 194.495928 -441.430156) (xy 194.495928 -441.17006) (xy 194.49641 -441.126022)
			(xy 194.50409 -441.03828) (xy 194.519387 -440.951542) (xy 194.542185 -440.866466) (xy 194.572311 -440.783702)
			(xy 194.609536 -440.703878) (xy 194.653576 -440.627602) (xy 194.704095 -440.555454) (xy 194.760711 -440.487984)
			(xy 194.822991 -440.425704) (xy 194.890462 -440.369089) (xy 194.96261 -440.31857) (xy 195.038887 -440.274531)
			(xy 195.118711 -440.237308) (xy 195.201476 -440.207182) (xy 195.286551 -440.184385) (xy 195.37329 -440.169088)
			(xy 195.461032 -440.16141) (xy 195.50507 -440.160918) (xy 276.314916 -440.160918) (xy 276.358955 -440.161399)
			(xy 276.446699 -440.169077) (xy 276.533439 -440.184372) (xy 276.618516 -440.207169) (xy 276.701283 -440.237294)
			(xy 276.781109 -440.274518) (xy 276.857388 -440.318557) (xy 276.929538 -440.369076) (xy 276.99701 -440.425692)
			(xy 277.059292 -440.487972) (xy 277.115909 -440.555443) (xy 277.16643 -440.627592) (xy 277.210471 -440.703869)
			(xy 277.247697 -440.783695) (xy 277.277823 -440.866461) (xy 277.300622 -440.951538) (xy 277.31592 -441.038278)
			(xy 277.3236 -441.126021) (xy 277.324058 -441.17006) (xy 277.324058 -441.430156) (xy 277.324469 -441.440186)
			(xy 277.33213 -441.458725) (xy 277.346302 -441.472922) (xy 277.364828 -441.480614) (xy 277.374858 -441.480956)
			(xy 463.300064 -441.480956) (xy 463.355834 -441.480449) (xy 463.467062 -441.472116) (xy 463.577357 -441.455494)
			(xy 463.686101 -441.430676) (xy 463.792686 -441.397801) (xy 463.896517 -441.357052) (xy 463.997011 -441.308658)
			(xy 464.093608 -441.252889) (xy 464.185768 -441.190057) (xy 464.272974 -441.120513) (xy 464.354739 -441.044647)
			(xy 464.430606 -440.962883) (xy 464.50015 -440.875677) (xy 464.562982 -440.783519) (xy 464.618752 -440.686922)
			(xy 464.667147 -440.586428) (xy 464.707897 -440.482598) (xy 464.740773 -440.376013) (xy 464.765592 -440.267269)
			(xy 464.782215 -440.156974) (xy 464.790548 -440.045746) (xy 464.791044 -439.989976) (xy 464.791044 -409.528264)
			(xy 464.791546 -409.457891) (xy 464.799454 -409.317366) (xy 464.815227 -409.177505) (xy 464.838815 -409.038749)
			(xy 464.870143 -408.901532) (xy 464.909113 -408.766288) (xy 464.955604 -408.633441) (xy 465.009467 -408.503408)
			(xy 465.070535 -408.376599) (xy 465.138615 -408.253413) (xy 465.213493 -408.134236) (xy 465.294933 -408.019444)
			(xy 465.38268 -407.909398) (xy 465.476458 -407.804443) (xy 465.525866 -407.754328) (xy 467.354412 -405.925782)
			(xy 467.391703 -405.887819) (xy 467.461396 -405.807388) (xy 467.525176 -405.722192) (xy 467.582717 -405.632663)
			(xy 467.633725 -405.539259) (xy 467.677942 -405.442454) (xy 467.715142 -405.342742) (xy 467.745135 -405.240631)
			(xy 467.767768 -405.136641) (xy 467.782928 -405.031301) (xy 467.790535 -404.925148) (xy 467.791038 -404.871936)
			(xy 467.791038 -82.82813) (xy 467.791541 -82.757757) (xy 467.799451 -82.617233) (xy 467.815226 -82.477373)
			(xy 467.838815 -82.338618) (xy 467.870145 -82.201402) (xy 467.909116 -82.066159) (xy 467.955608 -81.933313)
			(xy 468.009473 -81.803282) (xy 468.070541 -81.676474) (xy 468.138622 -81.553289) (xy 468.213501 -81.434114)
			(xy 468.294942 -81.319323) (xy 468.382689 -81.209278) (xy 468.476467 -81.104324) (xy 468.52586 -81.054194)
			(xy 470.854278 -78.725776) (xy 470.891569 -78.687813) (xy 470.961264 -78.607383) (xy 471.025045 -78.522187)
			(xy 471.082586 -78.432659) (xy 471.133596 -78.339255) (xy 471.177813 -78.24245) (xy 471.215013 -78.142738)
			(xy 471.245007 -78.040626) (xy 471.267641 -77.936636) (xy 471.2828 -77.831296) (xy 471.290407 -77.725143)
			(xy 471.290904 -77.67193) (xy 471.290904 -13.780008) (xy 471.290383 -13.724238) (xy 471.282048 -13.613011)
			(xy 471.265425 -13.502718) (xy 471.240606 -13.393975) (xy 471.20773 -13.287391) (xy 471.166981 -13.183562)
			(xy 471.118587 -13.083068) (xy 471.062818 -12.986472) (xy 470.999987 -12.894314) (xy 470.930444 -12.807108)
			(xy 470.854579 -12.725344) (xy 470.772816 -12.649477) (xy 470.685612 -12.579932) (xy 470.593455 -12.517099)
			(xy 470.49686 -12.461328) (xy 470.396367 -12.412932) (xy 470.292539 -12.372181) (xy 470.185956 -12.339303)
			(xy 470.077214 -12.314481) (xy 469.966921 -12.297855) (xy 469.855694 -12.289518) (xy 469.799924 -12.289028)
			(xy 458.20203 -12.289028) (xy 458.131647 -12.288544) (xy 457.991102 -12.280653) (xy 457.85122 -12.264894)
			(xy 457.712443 -12.241316) (xy 457.575205 -12.209994) (xy 457.43994 -12.171027) (xy 457.307072 -12.124536)
			(xy 457.177021 -12.070668) (xy 457.050194 -12.009593) (xy 456.926991 -11.941503) (xy 456.8078 -11.866612)
			(xy 456.692996 -11.785156) (xy 456.582939 -11.69739) (xy 456.477977 -11.603592) (xy 456.378439 -11.504056)
			(xy 456.284639 -11.399096) (xy 456.196872 -11.289041) (xy 456.115413 -11.174238) (xy 456.04052 -11.055048)
			(xy 455.972428 -10.931847) (xy 455.911351 -10.805021) (xy 455.857481 -10.674971) (xy 455.810987 -10.542104)
			(xy 455.772017 -10.406839) (xy 455.740693 -10.269603) (xy 455.717113 -10.130825) (xy 455.701351 -9.990944)
			(xy 455.693457 -9.850399) (xy 455.693018 -9.780016) (xy 455.693018 -0.559816) (xy 455.692533 -0.549805)
			(xy 455.684877 -0.531304) (xy 455.670724 -0.517142) (xy 455.652229 -0.509474) (xy 455.642218 -0.509016)
			(xy 388.161784 -0.509016) (xy 388.15178 -0.509507) (xy 388.133296 -0.51717) (xy 388.119152 -0.531323)
			(xy 388.111501 -0.549811) (xy 388.110984 -0.559816) (xy 388.110984 -5.169916) (xy 388.849877 -5.169916)
			(xy 388.853883 -5.081985) (xy 388.865869 -4.994782) (xy 388.885734 -4.90903) (xy 388.913316 -4.82544)
			(xy 388.948384 -4.744705) (xy 388.990649 -4.667493) (xy 389.03976 -4.594444) (xy 389.09531 -4.526164)
			(xy 389.156839 -4.463218) (xy 389.223837 -4.406129) (xy 389.295748 -4.355368) (xy 389.371978 -4.311356)
			(xy 389.451894 -4.274459) (xy 389.534835 -4.244982) (xy 389.620112 -4.22317) (xy 389.707019 -4.209202)
			(xy 389.794837 -4.203195) (xy 389.882836 -4.205199) (xy 389.970289 -4.215196) (xy 390.056471 -4.233105)
			(xy 390.140667 -4.258777) (xy 390.22218 -4.291998) (xy 390.300334 -4.332494) (xy 390.374481 -4.379929)
			(xy 390.444008 -4.433911) (xy 390.508339 -4.493991) (xy 390.566939 -4.559672) (xy 390.619323 -4.63041)
			(xy 390.665059 -4.705618) (xy 390.703765 -4.784674) (xy 390.735123 -4.866921) (xy 390.758871 -4.95168)
			(xy 390.766051 -4.990667) (xy 394.939038 -4.990667) (xy 394.939038 -4.936133) (xy 394.946799 -4.882155)
			(xy 394.962162 -4.82983) (xy 394.984815 -4.780224) (xy 395.014296 -4.734346) (xy 395.050007 -4.693131)
			(xy 395.091219 -4.657417) (xy 395.137094 -4.627931) (xy 395.186698 -4.605274) (xy 395.239021 -4.589906)
			(xy 395.292999 -4.582141) (xy 395.320266 -4.581652) (xy 396.183866 -4.581652) (xy 396.21114 -4.582085)
			(xy 396.265132 -4.589844) (xy 396.317471 -4.605208) (xy 396.36709 -4.627864) (xy 396.41298 -4.657352)
			(xy 396.454205 -4.693071) (xy 396.489928 -4.734293) (xy 396.51942 -4.78018) (xy 396.542081 -4.829797)
			(xy 396.557449 -4.882135) (xy 396.565212 -4.936126) (xy 396.565212 -4.99067) (xy 398.538915 -4.99067)
			(xy 398.538915 -4.93613) (xy 398.546678 -4.882144) (xy 398.562044 -4.829813) (xy 398.584701 -4.780201)
			(xy 398.614188 -4.734318) (xy 398.649905 -4.6931) (xy 398.691125 -4.657383) (xy 398.737008 -4.627897)
			(xy 398.78662 -4.605241) (xy 398.838952 -4.589876) (xy 398.892938 -4.582115) (xy 398.920208 -4.581652)
			(xy 399.783808 -4.581652) (xy 399.811078 -4.582111) (xy 399.865063 -4.589874) (xy 399.917393 -4.60524)
			(xy 399.967004 -4.627898) (xy 400.012886 -4.657385) (xy 400.054104 -4.693102) (xy 400.08982 -4.734321)
			(xy 400.119306 -4.780203) (xy 400.141962 -4.829814) (xy 400.157328 -4.882145) (xy 400.16509 -4.93613)
			(xy 400.16509 -4.990666) (xy 402.138938 -4.990666) (xy 402.138938 -4.936134) (xy 402.146698 -4.882157)
			(xy 402.162061 -4.829833) (xy 402.184712 -4.780228) (xy 402.214192 -4.734351) (xy 402.249901 -4.693136)
			(xy 402.291111 -4.657422) (xy 402.336984 -4.627936) (xy 402.386586 -4.605278) (xy 402.438908 -4.589909)
			(xy 402.492884 -4.582142) (xy 402.52015 -4.581652) (xy 403.38375 -4.581652) (xy 403.411024 -4.582084)
			(xy 403.465019 -4.589841) (xy 403.517359 -4.605203) (xy 403.56698 -4.627859) (xy 403.612872 -4.657346)
			(xy 403.6541 -4.693065) (xy 403.689824 -4.734288) (xy 403.719317 -4.780176) (xy 403.741979 -4.829794)
			(xy 403.757349 -4.882132) (xy 403.765112 -4.936126) (xy 403.765112 -4.990672) (xy 405.739016 -4.990672)
			(xy 405.739016 -4.936128) (xy 405.746779 -4.882139) (xy 405.762147 -4.829805) (xy 405.784807 -4.78019)
			(xy 405.814298 -4.734306) (xy 405.850019 -4.693086) (xy 405.891243 -4.65737) (xy 405.937131 -4.627885)
			(xy 405.986748 -4.605231) (xy 406.039084 -4.589869) (xy 406.093074 -4.582112) (xy 406.120346 -4.581652)
			(xy 406.983946 -4.581652) (xy 407.011214 -4.582114) (xy 407.065195 -4.589881) (xy 407.117521 -4.605251)
			(xy 407.167127 -4.62791) (xy 407.213004 -4.657399) (xy 407.254217 -4.693115) (xy 407.289929 -4.734333)
			(xy 407.319412 -4.780213) (xy 407.342065 -4.829822) (xy 407.357429 -4.88215) (xy 407.36519 -4.936132)
			(xy 407.36519 -4.990668) (xy 407.36519 -4.99067) (xy 414.849015 -4.99067) (xy 414.849015 -4.93613)
			(xy 414.856778 -4.882144) (xy 414.872144 -4.829812) (xy 414.894801 -4.7802) (xy 414.924289 -4.734318)
			(xy 414.960006 -4.693099) (xy 415.001226 -4.657383) (xy 415.047109 -4.627896) (xy 415.096722 -4.60524)
			(xy 415.149054 -4.589875) (xy 415.20304 -4.582115) (xy 415.23031 -4.581652) (xy 416.09391 -4.581652)
			(xy 416.12118 -4.582111) (xy 416.175164 -4.589874) (xy 416.227495 -4.605241) (xy 416.277105 -4.627899)
			(xy 416.322987 -4.657386) (xy 416.364205 -4.693102) (xy 416.39992 -4.734321) (xy 416.429406 -4.780203)
			(xy 416.452062 -4.829815) (xy 416.467428 -4.882145) (xy 416.47519 -4.93613) (xy 416.47519 -4.990666)
			(xy 418.449038 -4.990666) (xy 418.449038 -4.936134) (xy 418.456798 -4.882156) (xy 418.472161 -4.829833)
			(xy 418.494813 -4.780227) (xy 418.524293 -4.734351) (xy 418.560002 -4.693136) (xy 418.601212 -4.657422)
			(xy 418.647085 -4.627936) (xy 418.696688 -4.605278) (xy 418.749009 -4.589909) (xy 418.802986 -4.582142)
			(xy 418.830252 -4.581652) (xy 419.693852 -4.581652) (xy 419.721126 -4.582084) (xy 419.77512 -4.589841)
			(xy 419.827461 -4.605204) (xy 419.877082 -4.627859) (xy 419.922973 -4.657347) (xy 419.9642 -4.693066)
			(xy 419.999924 -4.734288) (xy 420.029418 -4.780176) (xy 420.052079 -4.829794) (xy 420.067449 -4.882133)
			(xy 420.075212 -4.936126) (xy 420.075212 -4.990672) (xy 426.059016 -4.990672) (xy 426.059016 -4.936128)
			(xy 426.066779 -4.882139) (xy 426.082147 -4.829805) (xy 426.104807 -4.78019) (xy 426.134298 -4.734306)
			(xy 426.170019 -4.693086) (xy 426.211243 -4.65737) (xy 426.257131 -4.627885) (xy 426.306748 -4.605231)
			(xy 426.359084 -4.589869) (xy 426.413074 -4.582112) (xy 426.440346 -4.581652) (xy 427.303946 -4.581652)
			(xy 427.331214 -4.582114) (xy 427.385195 -4.589881) (xy 427.437521 -4.605251) (xy 427.487127 -4.62791)
			(xy 427.533004 -4.657399) (xy 427.574217 -4.693115) (xy 427.609929 -4.734333) (xy 427.639412 -4.780213)
			(xy 427.662065 -4.829822) (xy 427.677429 -4.88215) (xy 427.68519 -4.936132) (xy 427.68519 -4.990668)
			(xy 429.659038 -4.990668) (xy 429.659038 -4.936132) (xy 429.666799 -4.882152) (xy 429.682164 -4.829825)
			(xy 429.704818 -4.780217) (xy 429.734302 -4.734339) (xy 429.770014 -4.693123) (xy 429.811229 -4.657409)
			(xy 429.857107 -4.627924) (xy 429.906714 -4.605268) (xy 429.95904 -4.589902) (xy 430.01302 -4.582139)
			(xy 430.040288 -4.581652) (xy 430.903888 -4.581652) (xy 430.931161 -4.582087) (xy 430.985151 -4.589848)
			(xy 431.037487 -4.605214) (xy 431.087103 -4.627871) (xy 431.13299 -4.65736) (xy 431.174213 -4.693078)
			(xy 431.209933 -4.7343) (xy 431.239423 -4.780186) (xy 431.262082 -4.829802) (xy 431.27745 -4.882138)
			(xy 431.285212 -4.936127) (xy 431.285212 -4.990673) (xy 431.27745 -5.044662) (xy 431.262082 -5.096998)
			(xy 431.239423 -5.146614) (xy 431.209933 -5.1925) (xy 431.174213 -5.233722) (xy 431.13299 -5.26944)
			(xy 431.087103 -5.298929) (xy 431.037487 -5.321586) (xy 430.985151 -5.336952) (xy 430.931161 -5.344713)
			(xy 430.903888 -5.345176) (xy 430.040288 -5.345176) (xy 430.01302 -5.344661) (xy 429.95904 -5.336898)
			(xy 429.906714 -5.321532) (xy 429.857107 -5.298876) (xy 429.811229 -5.269391) (xy 429.770014 -5.233677)
			(xy 429.734302 -5.192461) (xy 429.704818 -5.146583) (xy 429.682164 -5.096975) (xy 429.666799 -5.044648)
			(xy 429.659038 -4.990668) (xy 427.68519 -4.990668) (xy 427.677429 -5.04465) (xy 427.662065 -5.096978)
			(xy 427.639412 -5.146587) (xy 427.609929 -5.192467) (xy 427.574217 -5.233685) (xy 427.533004 -5.269401)
			(xy 427.487127 -5.29889) (xy 427.437521 -5.321549) (xy 427.385195 -5.336919) (xy 427.331214 -5.344686)
			(xy 427.303946 -5.345176) (xy 426.440346 -5.345176) (xy 426.413074 -5.344688) (xy 426.359084 -5.336931)
			(xy 426.306748 -5.321569) (xy 426.257131 -5.298915) (xy 426.211243 -5.26943) (xy 426.170019 -5.233714)
			(xy 426.134298 -5.192494) (xy 426.104807 -5.14661) (xy 426.082147 -5.096995) (xy 426.066779 -5.044661)
			(xy 426.059016 -4.990672) (xy 420.075212 -4.990672) (xy 420.075212 -4.990674) (xy 420.067449 -5.044667)
			(xy 420.052079 -5.097006) (xy 420.029418 -5.146624) (xy 419.999924 -5.192512) (xy 419.9642 -5.233734)
			(xy 419.922973 -5.269453) (xy 419.877082 -5.298941) (xy 419.827461 -5.321596) (xy 419.77512 -5.336959)
			(xy 419.721126 -5.344716) (xy 419.693852 -5.345176) (xy 418.830252 -5.345176) (xy 418.802986 -5.344658)
			(xy 418.749009 -5.336891) (xy 418.696688 -5.321522) (xy 418.647085 -5.298864) (xy 418.601212 -5.269378)
			(xy 418.560002 -5.233664) (xy 418.524293 -5.192449) (xy 418.494813 -5.146573) (xy 418.472161 -5.096967)
			(xy 418.456798 -5.044644) (xy 418.449038 -4.990666) (xy 416.47519 -4.990666) (xy 416.47519 -4.99067)
			(xy 416.467428 -5.044655) (xy 416.452062 -5.096985) (xy 416.429406 -5.146597) (xy 416.39992 -5.192479)
			(xy 416.364205 -5.233698) (xy 416.322987 -5.269414) (xy 416.277105 -5.298901) (xy 416.227495 -5.321559)
			(xy 416.175164 -5.336926) (xy 416.12118 -5.344689) (xy 416.09391 -5.345176) (xy 415.23031 -5.345176)
			(xy 415.20304 -5.344685) (xy 415.149054 -5.336925) (xy 415.096722 -5.32156) (xy 415.047109 -5.298904)
			(xy 415.001226 -5.269417) (xy 414.960006 -5.233701) (xy 414.924289 -5.192482) (xy 414.894801 -5.1466)
			(xy 414.872144 -5.096988) (xy 414.856778 -5.044656) (xy 414.849015 -4.99067) (xy 407.36519 -4.99067)
			(xy 407.357429 -5.04465) (xy 407.342065 -5.096978) (xy 407.319412 -5.146587) (xy 407.289929 -5.192467)
			(xy 407.254217 -5.233685) (xy 407.213004 -5.269401) (xy 407.167127 -5.29889) (xy 407.117521 -5.321549)
			(xy 407.065195 -5.336919) (xy 407.011214 -5.344686) (xy 406.983946 -5.345176) (xy 406.120346 -5.345176)
			(xy 406.093074 -5.344688) (xy 406.039084 -5.336931) (xy 405.986748 -5.321569) (xy 405.937131 -5.298915)
			(xy 405.891243 -5.26943) (xy 405.850019 -5.233714) (xy 405.814298 -5.192494) (xy 405.784807 -5.14661)
			(xy 405.762147 -5.096995) (xy 405.746779 -5.044661) (xy 405.739016 -4.990672) (xy 403.765112 -4.990672)
			(xy 403.765112 -4.990674) (xy 403.757349 -5.044668) (xy 403.741979 -5.097006) (xy 403.719317 -5.146624)
			(xy 403.689824 -5.192512) (xy 403.6541 -5.233735) (xy 403.612872 -5.269454) (xy 403.56698 -5.298941)
			(xy 403.517359 -5.321597) (xy 403.465019 -5.336959) (xy 403.411024 -5.344716) (xy 403.38375 -5.345176)
			(xy 402.52015 -5.345176) (xy 402.492884 -5.344658) (xy 402.438908 -5.336891) (xy 402.386586 -5.321522)
			(xy 402.336984 -5.298864) (xy 402.291111 -5.269378) (xy 402.249901 -5.233664) (xy 402.214192 -5.192449)
			(xy 402.184712 -5.146572) (xy 402.162061 -5.096967) (xy 402.146698 -5.044643) (xy 402.138938 -4.990666)
			(xy 400.16509 -4.990666) (xy 400.16509 -4.99067) (xy 400.157328 -5.044655) (xy 400.141962 -5.096986)
			(xy 400.119306 -5.146597) (xy 400.08982 -5.192479) (xy 400.054104 -5.233698) (xy 400.012886 -5.269415)
			(xy 399.967004 -5.298902) (xy 399.917393 -5.32156) (xy 399.865063 -5.336926) (xy 399.811078 -5.344689)
			(xy 399.783808 -5.345176) (xy 398.920208 -5.345176) (xy 398.892938 -5.344685) (xy 398.838952 -5.336924)
			(xy 398.78662 -5.321559) (xy 398.737008 -5.298903) (xy 398.691125 -5.269417) (xy 398.649905 -5.2337)
			(xy 398.614188 -5.192482) (xy 398.584701 -5.146599) (xy 398.562044 -5.096987) (xy 398.546678 -5.044656)
			(xy 398.538915 -4.99067) (xy 396.565212 -4.99067) (xy 396.565212 -4.990674) (xy 396.557449 -5.044665)
			(xy 396.542081 -5.097003) (xy 396.51942 -5.14662) (xy 396.489928 -5.192507) (xy 396.454205 -5.233729)
			(xy 396.41298 -5.269448) (xy 396.36709 -5.298936) (xy 396.317471 -5.321592) (xy 396.265132 -5.336956)
			(xy 396.21114 -5.344715) (xy 396.183866 -5.345176) (xy 395.320266 -5.345176) (xy 395.292999 -5.344659)
			(xy 395.239021 -5.336894) (xy 395.186698 -5.321526) (xy 395.137094 -5.298869) (xy 395.091219 -5.269383)
			(xy 395.050007 -5.233669) (xy 395.014296 -5.192454) (xy 394.984815 -5.146576) (xy 394.962162 -5.09697)
			(xy 394.946799 -5.044645) (xy 394.939038 -4.990667) (xy 390.766051 -4.990667) (xy 390.774813 -5.038247)
			(xy 390.782817 -5.125905) (xy 390.783318 -5.169916) (xy 390.782817 -5.213927) (xy 390.774813 -5.301585)
			(xy 390.758871 -5.388152) (xy 390.735123 -5.472911) (xy 390.703765 -5.555158) (xy 390.665059 -5.634214)
			(xy 390.619323 -5.709422) (xy 390.566939 -5.78016) (xy 390.508339 -5.845841) (xy 390.444008 -5.905921)
			(xy 390.374481 -5.959903) (xy 390.300334 -6.007338) (xy 390.22218 -6.047834) (xy 390.140667 -6.081055)
			(xy 390.056471 -6.106727) (xy 389.970289 -6.124636) (xy 389.882836 -6.134633) (xy 389.794837 -6.136637)
			(xy 389.707019 -6.13063) (xy 389.620112 -6.116662) (xy 389.534835 -6.09485) (xy 389.451894 -6.065373)
			(xy 389.371978 -6.028476) (xy 389.295748 -5.984464) (xy 389.223837 -5.933703) (xy 389.156839 -5.876614)
			(xy 389.09531 -5.813668) (xy 389.03976 -5.745388) (xy 388.990649 -5.672339) (xy 388.948384 -5.595127)
			(xy 388.913316 -5.514392) (xy 388.885734 -5.430802) (xy 388.865869 -5.34505) (xy 388.853883 -5.257847)
			(xy 388.849877 -5.169916) (xy 388.110984 -5.169916) (xy 388.110984 -6.169914) (xy 453.015103 -6.169914)
			(xy 453.019108 -6.082006) (xy 453.031091 -5.994826) (xy 453.050951 -5.909097) (xy 453.078526 -5.825529)
			(xy 453.113585 -5.744815) (xy 453.155838 -5.667623) (xy 453.204936 -5.594594) (xy 453.260472 -5.526332)
			(xy 453.321984 -5.463402) (xy 453.388965 -5.406328) (xy 453.460858 -5.35558) (xy 453.537067 -5.31158)
			(xy 453.616962 -5.274693) (xy 453.699881 -5.245224) (xy 453.785136 -5.223417) (xy 453.87202 -5.209453)
			(xy 453.959814 -5.203447) (xy 454.047791 -5.205451) (xy 454.135221 -5.215446) (xy 454.22138 -5.23335)
			(xy 454.305554 -5.259014) (xy 454.387045 -5.292227) (xy 454.465179 -5.332713) (xy 454.539307 -5.380135)
			(xy 454.608815 -5.434102) (xy 454.673129 -5.494167) (xy 454.731713 -5.559831) (xy 454.784084 -5.63055)
			(xy 454.829807 -5.705738) (xy 454.868504 -5.784773) (xy 454.899853 -5.866999) (xy 454.923595 -5.951735)
			(xy 454.939533 -6.038279) (xy 454.947535 -6.125914) (xy 454.948036 -6.169914) (xy 454.947535 -6.213914)
			(xy 454.939533 -6.301549) (xy 454.923595 -6.388093) (xy 454.899853 -6.472829) (xy 454.868504 -6.555055)
			(xy 454.829807 -6.63409) (xy 454.784084 -6.709278) (xy 454.731713 -6.779997) (xy 454.673129 -6.845661)
			(xy 454.608815 -6.905726) (xy 454.539307 -6.959693) (xy 454.465179 -7.007115) (xy 454.387045 -7.047601)
			(xy 454.305554 -7.080814) (xy 454.22138 -7.106478) (xy 454.135221 -7.124382) (xy 454.047791 -7.134377)
			(xy 453.959814 -7.136381) (xy 453.87202 -7.130375) (xy 453.785136 -7.116411) (xy 453.699881 -7.094604)
			(xy 453.616962 -7.065135) (xy 453.537067 -7.028248) (xy 453.460858 -6.984248) (xy 453.388965 -6.9335)
			(xy 453.321984 -6.876426) (xy 453.260472 -6.813496) (xy 453.204936 -6.745234) (xy 453.155838 -6.672205)
			(xy 453.113585 -6.595013) (xy 453.078526 -6.514299) (xy 453.050951 -6.430731) (xy 453.031091 -6.345002)
			(xy 453.019108 -6.257822) (xy 453.015103 -6.169914) (xy 388.110984 -6.169914) (xy 388.110984 -6.752472)
			(xy 393.134283 -6.752472) (xy 393.134283 -6.697928) (xy 393.142045 -6.643939) (xy 393.157412 -6.591604)
			(xy 393.18007 -6.541988) (xy 393.209559 -6.496103) (xy 393.245278 -6.454881) (xy 393.286499 -6.419161)
			(xy 393.332385 -6.389672) (xy 393.382 -6.367013) (xy 393.434335 -6.351646) (xy 393.488324 -6.343883)
			(xy 393.515596 -6.343396) (xy 394.379196 -6.343396) (xy 394.406464 -6.343943) (xy 394.460446 -6.351704)
			(xy 394.512773 -6.367068) (xy 394.562381 -6.389723) (xy 394.60826 -6.419207) (xy 394.649476 -6.454921)
			(xy 394.68519 -6.496136) (xy 394.714675 -6.542015) (xy 394.73733 -6.591623) (xy 394.752695 -6.643951)
			(xy 394.760457 -6.697932) (xy 394.760457 -6.752468) (xy 394.760456 -6.752476) (xy 396.73416 -6.752476)
			(xy 396.73416 -6.697924) (xy 396.741924 -6.643928) (xy 396.757294 -6.591587) (xy 396.779956 -6.541966)
			(xy 396.809451 -6.496075) (xy 396.845176 -6.454849) (xy 396.886405 -6.419128) (xy 396.932299 -6.389638)
			(xy 396.981922 -6.36698) (xy 397.034265 -6.351616) (xy 397.088262 -6.343857) (xy 397.115538 -6.343396)
			(xy 397.979138 -6.343396) (xy 398.006403 -6.343969) (xy 398.060376 -6.351734) (xy 398.112695 -6.367101)
			(xy 398.162295 -6.389757) (xy 398.208166 -6.419241) (xy 398.249375 -6.454952) (xy 398.285082 -6.496164)
			(xy 398.314561 -6.542038) (xy 398.337212 -6.59164) (xy 398.352574 -6.643961) (xy 398.360334 -6.697935)
			(xy 398.360334 -6.752465) (xy 398.360333 -6.752471) (xy 400.334182 -6.752471) (xy 400.334182 -6.697929)
			(xy 400.341944 -6.643941) (xy 400.35731 -6.591607) (xy 400.379968 -6.541993) (xy 400.409455 -6.496108)
			(xy 400.445172 -6.454886) (xy 400.486392 -6.419167) (xy 400.532275 -6.389677) (xy 400.581888 -6.367017)
			(xy 400.634221 -6.351649) (xy 400.688209 -6.343884) (xy 400.71548 -6.343396) (xy 401.57908 -6.343396)
			(xy 401.606349 -6.343942) (xy 401.660332 -6.351701) (xy 401.712661 -6.367064) (xy 401.762272 -6.389718)
			(xy 401.808153 -6.419202) (xy 401.849371 -6.454915) (xy 401.885086 -6.496131) (xy 401.914573 -6.542011)
			(xy 401.937229 -6.59162) (xy 401.952595 -6.643948) (xy 401.960357 -6.697931) (xy 401.960357 -6.752469)
			(xy 401.960357 -6.752471) (xy 403.934382 -6.752471) (xy 403.934382 -6.697929) (xy 403.942144 -6.643941)
			(xy 403.95751 -6.591608) (xy 403.980167 -6.541994) (xy 404.009654 -6.496109) (xy 404.045371 -6.454888)
			(xy 404.08659 -6.419168) (xy 404.132473 -6.389679) (xy 404.182085 -6.367019) (xy 404.234418 -6.351649)
			(xy 404.288405 -6.343884) (xy 404.315676 -6.343396) (xy 405.179276 -6.343396) (xy 405.206545 -6.343942)
			(xy 405.260529 -6.3517) (xy 405.312858 -6.367063) (xy 405.362469 -6.389716) (xy 405.408351 -6.4192)
			(xy 405.449569 -6.454914) (xy 405.485285 -6.49613) (xy 405.514772 -6.54201) (xy 405.537429 -6.591619)
			(xy 405.552795 -6.643948) (xy 405.560557 -6.697931) (xy 405.560557 -6.752469) (xy 405.560556 -6.752476)
			(xy 413.04426 -6.752476) (xy 413.04426 -6.697924) (xy 413.052024 -6.643928) (xy 413.067394 -6.591586)
			(xy 413.090057 -6.541965) (xy 413.119551 -6.496074) (xy 413.155277 -6.454849) (xy 413.196506 -6.419127)
			(xy 413.2424 -6.389638) (xy 413.292024 -6.36698) (xy 413.344367 -6.351615) (xy 413.398364 -6.343857)
			(xy 413.42564 -6.343396) (xy 414.28924 -6.343396) (xy 414.316504 -6.343969) (xy 414.370478 -6.351734)
			(xy 414.422797 -6.367102) (xy 414.472397 -6.389758) (xy 414.518267 -6.419241) (xy 414.559476 -6.454953)
			(xy 414.595183 -6.496165) (xy 414.624662 -6.542039) (xy 414.647312 -6.591641) (xy 414.662674 -6.643961)
			(xy 414.670434 -6.697935) (xy 414.670434 -6.752465) (xy 414.670433 -6.752472) (xy 416.644282 -6.752472)
			(xy 416.644282 -6.697928) (xy 416.652045 -6.64394) (xy 416.667411 -6.591607) (xy 416.690068 -6.541992)
			(xy 416.719555 -6.496107) (xy 416.755273 -6.454885) (xy 416.796493 -6.419166) (xy 416.842376 -6.389677)
			(xy 416.89199 -6.367017) (xy 416.944323 -6.351648) (xy 416.99831 -6.343884) (xy 417.025582 -6.343396)
			(xy 417.889182 -6.343396) (xy 417.916451 -6.343942) (xy 417.970434 -6.351701) (xy 418.022763 -6.367064)
			(xy 418.072373 -6.389718) (xy 418.118254 -6.419202) (xy 418.159471 -6.454916) (xy 418.195187 -6.496132)
			(xy 418.224673 -6.542011) (xy 418.247329 -6.59162) (xy 418.262695 -6.643949) (xy 418.270457 -6.697931)
			(xy 418.270457 -6.752469) (xy 418.270457 -6.752471) (xy 424.254382 -6.752471) (xy 424.254382 -6.697929)
			(xy 424.262144 -6.643941) (xy 424.27751 -6.591608) (xy 424.300167 -6.541994) (xy 424.329654 -6.496109)
			(xy 424.365371 -6.454888) (xy 424.40659 -6.419168) (xy 424.452473 -6.389679) (xy 424.502085 -6.367019)
			(xy 424.554418 -6.351649) (xy 424.608405 -6.343884) (xy 424.635676 -6.343396) (xy 425.499276 -6.343396)
			(xy 425.526545 -6.343942) (xy 425.580529 -6.3517) (xy 425.632858 -6.367063) (xy 425.682469 -6.389716)
			(xy 425.728351 -6.4192) (xy 425.769569 -6.454914) (xy 425.805285 -6.49613) (xy 425.834772 -6.54201)
			(xy 425.857429 -6.591619) (xy 425.872795 -6.643948) (xy 425.880557 -6.697931) (xy 425.880557 -6.752469)
			(xy 425.880556 -6.752475) (xy 427.85426 -6.752475) (xy 427.85426 -6.697925) (xy 427.862023 -6.643931)
			(xy 427.877392 -6.591591) (xy 427.900053 -6.541971) (xy 427.929546 -6.496082) (xy 427.965269 -6.454856)
			(xy 428.006496 -6.419135) (xy 428.052387 -6.389645) (xy 428.102008 -6.366986) (xy 428.154348 -6.351619)
			(xy 428.208343 -6.343858) (xy 428.235618 -6.343396) (xy 429.099218 -6.343396) (xy 429.126484 -6.343968)
			(xy 429.180459 -6.35173) (xy 429.232781 -6.367096) (xy 429.282383 -6.38975) (xy 429.328257 -6.419234)
			(xy 429.369468 -6.454945) (xy 429.405177 -6.496157) (xy 429.434658 -6.542032) (xy 429.457311 -6.591636)
			(xy 429.472673 -6.643958) (xy 429.480434 -6.697934) (xy 429.480434 -6.752466) (xy 429.479412 -6.759571)
			(xy 431.465194 -6.759571) (xy 431.465194 -6.705029) (xy 431.472956 -6.651043) (xy 431.488322 -6.598711)
			(xy 431.510979 -6.549098) (xy 431.540465 -6.503214) (xy 431.576181 -6.461994) (xy 431.6174 -6.426276)
			(xy 431.663282 -6.396787) (xy 431.712894 -6.374128) (xy 431.765225 -6.35876) (xy 431.819211 -6.350996)
			(xy 431.846482 -6.350508) (xy 432.710082 -6.350508) (xy 432.737352 -6.35103) (xy 432.791336 -6.35879)
			(xy 432.843667 -6.374153) (xy 432.893279 -6.396808) (xy 432.939161 -6.426293) (xy 432.98038 -6.462007)
			(xy 433.016096 -6.503225) (xy 433.045583 -6.549106) (xy 433.068241 -6.598716) (xy 433.083607 -6.651046)
			(xy 433.091369 -6.70503) (xy 433.091369 -6.75247) (xy 445.449182 -6.75247) (xy 445.449182 -6.69793)
			(xy 445.456944 -6.643944) (xy 445.472308 -6.591613) (xy 445.494963 -6.542001) (xy 445.524448 -6.496117)
			(xy 445.560162 -6.454896) (xy 445.601379 -6.419177) (xy 445.647258 -6.389686) (xy 445.696868 -6.367025)
			(xy 445.749198 -6.351654) (xy 445.803182 -6.343886) (xy 445.830452 -6.343396) (xy 446.694052 -6.343396)
			(xy 446.721322 -6.34394) (xy 446.775308 -6.351696) (xy 446.827641 -6.367056) (xy 446.877255 -6.389709)
			(xy 446.923139 -6.419192) (xy 446.964361 -6.454905) (xy 447.00008 -6.496122) (xy 447.029568 -6.542003)
			(xy 447.052227 -6.591614) (xy 447.067594 -6.643945) (xy 447.075356 -6.69793) (xy 447.075356 -6.75247)
			(xy 447.067594 -6.806455) (xy 447.052227 -6.858786) (xy 447.029568 -6.908397) (xy 447.000079 -6.954278)
			(xy 446.964361 -6.995495) (xy 446.923139 -7.031208) (xy 446.877255 -7.060691) (xy 446.827641 -7.083344)
			(xy 446.775308 -7.098704) (xy 446.721322 -7.10646) (xy 446.694052 -7.10692) (xy 445.830452 -7.10692)
			(xy 445.803182 -7.106514) (xy 445.749198 -7.098746) (xy 445.696868 -7.083375) (xy 445.647258 -7.060714)
			(xy 445.601378 -7.031223) (xy 445.560162 -6.995504) (xy 445.524448 -6.954283) (xy 445.494963 -6.908399)
			(xy 445.472308 -6.858787) (xy 445.456944 -6.806455) (xy 445.449182 -6.75247) (xy 433.091369 -6.75247)
			(xy 433.091369 -6.75957) (xy 433.083607 -6.813554) (xy 433.068241 -6.865884) (xy 433.045583 -6.915494)
			(xy 433.016096 -6.961375) (xy 432.98038 -7.002593) (xy 432.939161 -7.038307) (xy 432.893279 -7.067792)
			(xy 432.843667 -7.090447) (xy 432.791336 -7.10581) (xy 432.737352 -7.11357) (xy 432.710082 -7.114032)
			(xy 431.846482 -7.114032) (xy 431.819211 -7.113604) (xy 431.765225 -7.10584) (xy 431.712894 -7.090472)
			(xy 431.663282 -7.067813) (xy 431.6174 -7.038324) (xy 431.576181 -7.002606) (xy 431.540465 -6.961386)
			(xy 431.510979 -6.915502) (xy 431.488322 -6.865889) (xy 431.472956 -6.813557) (xy 431.465194 -6.759571)
			(xy 429.479412 -6.759571) (xy 429.472673 -6.806442) (xy 429.457311 -6.858764) (xy 429.434658 -6.908368)
			(xy 429.405177 -6.954243) (xy 429.369468 -6.995455) (xy 429.328257 -7.031166) (xy 429.282383 -7.06065)
			(xy 429.232781 -7.083304) (xy 429.180459 -7.09867) (xy 429.126484 -7.106432) (xy 429.099218 -7.10692)
			(xy 428.235618 -7.10692) (xy 428.208343 -7.106542) (xy 428.154348 -7.098781) (xy 428.102008 -7.083414)
			(xy 428.052387 -7.060755) (xy 428.006496 -7.031265) (xy 427.965269 -6.995544) (xy 427.929546 -6.954318)
			(xy 427.900053 -6.908429) (xy 427.877392 -6.858809) (xy 427.862023 -6.806469) (xy 427.85426 -6.752475)
			(xy 425.880556 -6.752475) (xy 425.872795 -6.806452) (xy 425.857429 -6.858781) (xy 425.834772 -6.90839)
			(xy 425.805285 -6.95427) (xy 425.769569 -6.995486) (xy 425.728351 -7.0312) (xy 425.682469 -7.060684)
			(xy 425.632858 -7.083337) (xy 425.580529 -7.0987) (xy 425.526545 -7.106458) (xy 425.499276 -7.10692)
			(xy 424.635676 -7.10692) (xy 424.608405 -7.106516) (xy 424.554418 -7.098751) (xy 424.502085 -7.083381)
			(xy 424.452473 -7.060721) (xy 424.40659 -7.031232) (xy 424.365371 -6.995512) (xy 424.329654 -6.954291)
			(xy 424.300167 -6.908406) (xy 424.27751 -6.858792) (xy 424.262144 -6.806459) (xy 424.254382 -6.752471)
			(xy 418.270457 -6.752471) (xy 418.262695 -6.806451) (xy 418.247329 -6.85878) (xy 418.224673 -6.908389)
			(xy 418.195187 -6.954268) (xy 418.159471 -6.995484) (xy 418.118254 -7.031198) (xy 418.072373 -7.060682)
			(xy 418.022763 -7.083336) (xy 417.970434 -7.098699) (xy 417.916451 -7.106458) (xy 417.889182 -7.10692)
			(xy 417.025582 -7.10692) (xy 416.99831 -7.106516) (xy 416.944323 -7.098752) (xy 416.89199 -7.083383)
			(xy 416.842376 -7.060723) (xy 416.796493 -7.031234) (xy 416.755273 -6.995515) (xy 416.719555 -6.954293)
			(xy 416.690068 -6.908408) (xy 416.667411 -6.858793) (xy 416.652045 -6.806459) (xy 416.644282 -6.752472)
			(xy 414.670433 -6.752472) (xy 414.662674 -6.806439) (xy 414.647312 -6.858759) (xy 414.624662 -6.908361)
			(xy 414.595183 -6.954235) (xy 414.559476 -6.995447) (xy 414.518267 -7.031159) (xy 414.472397 -7.060642)
			(xy 414.422797 -7.083298) (xy 414.370478 -7.098666) (xy 414.316505 -7.106431) (xy 414.28924 -7.10692)
			(xy 413.42564 -7.10692) (xy 413.398364 -7.106543) (xy 413.344367 -7.098785) (xy 413.292024 -7.08342)
			(xy 413.2424 -7.060762) (xy 413.196506 -7.031273) (xy 413.155277 -6.995551) (xy 413.119551 -6.954326)
			(xy 413.090057 -6.908435) (xy 413.067394 -6.858814) (xy 413.052024 -6.806472) (xy 413.04426 -6.752476)
			(xy 405.560556 -6.752476) (xy 405.552795 -6.806452) (xy 405.537429 -6.858781) (xy 405.514772 -6.90839)
			(xy 405.485285 -6.95427) (xy 405.449569 -6.995486) (xy 405.408351 -7.0312) (xy 405.362469 -7.060684)
			(xy 405.312858 -7.083337) (xy 405.260529 -7.0987) (xy 405.206545 -7.106458) (xy 405.179276 -7.10692)
			(xy 404.315676 -7.10692) (xy 404.288405 -7.106516) (xy 404.234418 -7.098751) (xy 404.182085 -7.083381)
			(xy 404.132473 -7.060721) (xy 404.08659 -7.031232) (xy 404.045371 -6.995512) (xy 404.009654 -6.954291)
			(xy 403.980167 -6.908406) (xy 403.95751 -6.858792) (xy 403.942144 -6.806459) (xy 403.934382 -6.752471)
			(xy 401.960357 -6.752471) (xy 401.952595 -6.806452) (xy 401.937229 -6.85878) (xy 401.914573 -6.908389)
			(xy 401.885086 -6.954269) (xy 401.849371 -6.995485) (xy 401.808153 -7.031198) (xy 401.762272 -7.060682)
			(xy 401.712661 -7.083336) (xy 401.660332 -7.098699) (xy 401.606349 -7.106458) (xy 401.57908 -7.10692)
			(xy 400.71548 -7.10692) (xy 400.688209 -7.106516) (xy 400.634221 -7.098751) (xy 400.581888 -7.083383)
			(xy 400.532275 -7.060723) (xy 400.486392 -7.031233) (xy 400.445172 -6.995514) (xy 400.409455 -6.954292)
			(xy 400.379968 -6.908407) (xy 400.35731 -6.858793) (xy 400.341944 -6.806459) (xy 400.334182 -6.752471)
			(xy 398.360333 -6.752471) (xy 398.352574 -6.806439) (xy 398.337212 -6.85876) (xy 398.314561 -6.908362)
			(xy 398.285082 -6.954236) (xy 398.249375 -6.995448) (xy 398.208166 -7.031159) (xy 398.162295 -7.060643)
			(xy 398.112695 -7.083299) (xy 398.060376 -7.098666) (xy 398.006403 -7.106431) (xy 397.979138 -7.10692)
			(xy 397.115538 -7.10692) (xy 397.088262 -7.106543) (xy 397.034265 -7.098784) (xy 396.981922 -7.08342)
			(xy 396.932299 -7.060762) (xy 396.886405 -7.031272) (xy 396.845176 -6.995551) (xy 396.809451 -6.954325)
			(xy 396.779956 -6.908434) (xy 396.757294 -6.858813) (xy 396.741924 -6.806472) (xy 396.73416 -6.752476)
			(xy 394.760456 -6.752476) (xy 394.752695 -6.806449) (xy 394.73733 -6.858777) (xy 394.714675 -6.908385)
			(xy 394.68519 -6.954264) (xy 394.649476 -6.995479) (xy 394.60826 -7.031193) (xy 394.562381 -7.060677)
			(xy 394.512773 -7.083332) (xy 394.460446 -7.098696) (xy 394.406464 -7.106457) (xy 394.379196 -7.10692)
			(xy 393.515596 -7.10692) (xy 393.488324 -7.106517) (xy 393.434335 -7.098754) (xy 393.382 -7.083387)
			(xy 393.332385 -7.060728) (xy 393.286499 -7.031239) (xy 393.245278 -6.995519) (xy 393.209559 -6.954297)
			(xy 393.18007 -6.908412) (xy 393.157412 -6.858796) (xy 393.142045 -6.806461) (xy 393.134283 -6.752472)
			(xy 388.110984 -6.752472) (xy 388.110984 -9.780016) (xy 388.110499 -9.850398) (xy 388.102605 -9.99094)
			(xy 388.086844 -10.130819) (xy 388.063264 -10.269594) (xy 388.03194 -10.406828) (xy 387.992971 -10.54209)
			(xy 387.946478 -10.674954) (xy 387.892609 -10.805003) (xy 387.831533 -10.931826) (xy 387.763442 -11.055026)
			(xy 387.68855 -11.174213) (xy 387.607093 -11.289014) (xy 387.519328 -11.399067) (xy 387.425529 -11.504025)
			(xy 387.325993 -11.60356) (xy 387.221033 -11.697356) (xy 387.110979 -11.78512) (xy 386.996176 -11.866575)
			(xy 386.876988 -11.941465) (xy 386.753787 -12.009554) (xy 386.626963 -12.070627) (xy 386.496913 -12.124494)
			(xy 386.364048 -12.170984) (xy 386.228785 -12.209951) (xy 386.091551 -12.241273) (xy 385.952775 -12.26485)
			(xy 385.812896 -12.280609) (xy 385.672354 -12.2885) (xy 385.601972 -12.289028) (xy 260.800088 -12.289028)
			(xy 260.744319 -12.28955) (xy 260.633094 -12.297886) (xy 260.522803 -12.314511) (xy 260.414062 -12.339331)
			(xy 260.30748 -12.372208) (xy 260.234662 -12.400788) (xy 436.813452 -12.400788) (xy 436.813941 -12.359678)
			(xy 436.821529 -12.27781) (xy 436.83664 -12.196991) (xy 436.859145 -12.117912) (xy 436.888851 -12.041247)
			(xy 436.925505 -11.96765) (xy 436.968795 -11.89775) (xy 437.01835 -11.832142) (xy 437.073748 -11.771388)
			(xy 437.134516 -11.716006) (xy 437.200136 -11.666467) (xy 437.270047 -11.623195) (xy 437.343653 -11.58656)
			(xy 437.420326 -11.556873) (xy 437.499411 -11.534389) (xy 437.580234 -11.519298) (xy 437.662104 -11.511731)
			(xy 437.703214 -11.51128) (xy 437.747029 -11.511772) (xy 437.83424 -11.520318) (xy 437.920187 -11.537406)
			(xy 438.004035 -11.562868) (xy 438.084971 -11.596458) (xy 438.123838 -11.61669) (xy 438.135191 -11.622017)
			(xy 438.160237 -11.622017) (xy 438.17159 -11.61669) (xy 438.210465 -11.596477) (xy 438.291405 -11.562905)
			(xy 438.375252 -11.537448) (xy 438.461195 -11.520353) (xy 438.548401 -11.511784) (xy 438.592214 -11.51128)
			(xy 438.636029 -11.511772) (xy 438.72324 -11.520318) (xy 438.809187 -11.537406) (xy 438.893035 -11.562868)
			(xy 438.973971 -11.596458) (xy 439.012838 -11.61669) (xy 439.024191 -11.622017) (xy 439.049237 -11.622017)
			(xy 439.06059 -11.61669) (xy 439.099465 -11.596477) (xy 439.180405 -11.562905) (xy 439.264252 -11.537448)
			(xy 439.350195 -11.520353) (xy 439.437401 -11.511784) (xy 439.481214 -11.51128) (xy 439.521951 -11.511719)
			(xy 439.603086 -11.519152) (xy 439.683202 -11.533973) (xy 439.761626 -11.556057) (xy 439.837703 -11.585219)
			(xy 439.910794 -11.621216) (xy 439.94578 -11.64209) (xy 439.954798 -11.647053) (xy 439.975154 -11.650004)
			(xy 439.995036 -11.644737) (xy 440.003438 -11.638788) (xy 440.091322 -11.570462) (xy 440.10072 -11.54049)
			(xy 440.095894 -11.52525) (xy 440.083229 -11.482506) (xy 440.065483 -11.395136) (xy 440.056563 -11.306429)
			(xy 440.056016 -11.261852) (xy 440.056016 -11.26109) (xy 440.056438 -11.22287) (xy 440.062998 -11.146712)
			(xy 440.076079 -11.071399) (xy 440.095582 -10.997489) (xy 440.108086 -10.96137) (xy 440.110695 -10.953059)
			(xy 440.110679 -10.935651) (xy 440.108086 -10.927334) (xy 440.095582 -10.891215) (xy 440.076095 -10.817302)
			(xy 440.063015 -10.74199) (xy 440.056437 -10.665834) (xy 440.056016 -10.627614) (xy 440.056016 -10.626852)
			(xy 440.05652 -10.584504) (xy 440.064571 -10.50019) (xy 440.0806 -10.417024) (xy 440.104461 -10.335757)
			(xy 440.13594 -10.257127) (xy 440.174751 -10.181846) (xy 440.220541 -10.110594) (xy 440.272897 -10.044018)
			(xy 440.331345 -9.98272) (xy 440.395355 -9.927255) (xy 440.464347 -9.878126) (xy 440.537697 -9.835777)
			(xy 440.61474 -9.800593) (xy 440.694779 -9.772891) (xy 440.777088 -9.752923) (xy 440.860923 -9.74087)
			(xy 440.945524 -9.73684) (xy 441.030125 -9.74087) (xy 441.11396 -9.752923) (xy 441.196269 -9.772891)
			(xy 441.276308 -9.800593) (xy 441.353351 -9.835777) (xy 441.426701 -9.878126) (xy 441.495693 -9.927255)
			(xy 441.559703 -9.98272) (xy 441.618151 -10.044018) (xy 441.670507 -10.110594) (xy 441.716297 -10.181846)
			(xy 441.755108 -10.257127) (xy 441.786587 -10.335757) (xy 441.810448 -10.417024) (xy 441.826477 -10.50019)
			(xy 441.834528 -10.584504) (xy 441.835032 -10.626852) (xy 441.835032 -10.627614) (xy 441.834614 -10.665834)
			(xy 441.828053 -10.741992) (xy 441.814972 -10.817305) (xy 441.795467 -10.891215) (xy 441.782962 -10.927334)
			(xy 441.780399 -10.935656) (xy 441.780383 -10.953054) (xy 441.782962 -10.96137) (xy 441.795465 -10.997489)
			(xy 441.814952 -11.071403) (xy 441.828033 -11.146715) (xy 441.834611 -11.22287) (xy 441.835032 -11.26109)
			(xy 441.835032 -11.261852) (xy 441.834502 -11.302954) (xy 441.826922 -11.384807) (xy 441.811821 -11.465611)
			(xy 441.789329 -11.544677) (xy 441.759637 -11.621331) (xy 441.722999 -11.694918) (xy 441.679728 -11.764811)
			(xy 441.630192 -11.830413) (xy 441.574815 -11.891164) (xy 441.514068 -11.946546) (xy 441.44847 -11.996087)
			(xy 441.378581 -12.039364) (xy 441.304997 -12.076008) (xy 441.228346 -12.105706) (xy 441.149281 -12.128204)
			(xy 441.068478 -12.143312) (xy 440.986626 -12.150899) (xy 440.945524 -12.15136) (xy 440.945016 -12.15136)
			(xy 440.904322 -12.150875) (xy 440.823276 -12.143416) (xy 440.74325 -12.128584) (xy 440.664913 -12.106505)
			(xy 440.58892 -12.077363) (xy 440.515907 -12.041401) (xy 440.480958 -12.02055) (xy 440.471926 -12.015614)
			(xy 440.451579 -12.012649) (xy 440.431701 -12.017907) (xy 440.4233 -12.023852) (xy 440.335416 -12.092178)
			(xy 440.326018 -12.12215) (xy 440.330844 -12.13739) (xy 440.343568 -12.180123) (xy 440.361398 -12.267491)
			(xy 440.370394 -12.356204) (xy 440.370976 -12.400788) (xy 440.370415 -12.444238) (xy 440.361895 -12.530719)
			(xy 440.344992 -12.615959) (xy 440.319868 -12.699148) (xy 440.286761 -12.779495) (xy 440.266836 -12.81811)
			(xy 440.262961 -12.82623) (xy 440.260628 -12.84406) (xy 440.262264 -12.852908) (xy 440.272023 -12.900055)
			(xy 440.282457 -12.995773) (xy 440.283092 -13.043916) (xy 440.282667 -13.085188) (xy 440.275027 -13.167377)
			(xy 440.259804 -13.248505) (xy 440.23713 -13.327874) (xy 440.2072 -13.4048) (xy 440.170271 -13.478622)
			(xy 440.126661 -13.548705) (xy 440.076745 -13.614446) (xy 440.020952 -13.675279) (xy 439.959763 -13.730681)
			(xy 439.893704 -13.780175) (xy 439.823344 -13.823336) (xy 439.786522 -13.841984) (xy 439.778885 -13.846179)
			(xy 439.766763 -13.858679) (xy 439.759479 -13.874495) (xy 439.758328 -13.883132) (xy 439.755251 -13.911241)
			(xy 439.741951 -13.966197) (xy 439.720685 -14.018587) (xy 439.69192 -14.067266) (xy 439.656285 -14.111165)
			(xy 439.643167 -14.123162) (xy 440.58586 -14.123162) (xy 440.586283 -14.084873) (xy 440.592885 -14.008579)
			(xy 440.60603 -13.933136) (xy 440.625619 -13.859105) (xy 440.638184 -13.822934) (xy 440.640853 -13.814502)
			(xy 440.64084 -13.796827) (xy 440.638184 -13.78839) (xy 440.625655 -13.752208) (xy 440.606078 -13.678176)
			(xy 440.592927 -13.602738) (xy 440.586298 -13.52645) (xy 440.58586 -13.488162) (xy 440.586364 -13.445801)
			(xy 440.594417 -13.361464) (xy 440.610451 -13.278274) (xy 440.634319 -13.196984) (xy 440.665807 -13.118332)
			(xy 440.704629 -13.043029) (xy 440.750432 -12.971757) (xy 440.802803 -12.905161) (xy 440.861268 -12.843846)
			(xy 440.925296 -12.788365) (xy 440.994308 -12.739222) (xy 441.067678 -12.696862) (xy 441.144743 -12.661667)
			(xy 441.224805 -12.633958) (xy 441.307138 -12.613984) (xy 441.390997 -12.601927) (xy 441.475622 -12.597896)
			(xy 441.560247 -12.601927) (xy 441.644106 -12.613984) (xy 441.726439 -12.633958) (xy 441.806501 -12.661667)
			(xy 441.883566 -12.696862) (xy 441.956936 -12.739222) (xy 442.025948 -12.788365) (xy 442.089976 -12.843846)
			(xy 442.135955 -12.892066) (xy 445.44847 -12.892066) (xy 445.44847 -12.837534) (xy 445.456231 -12.783558)
			(xy 445.471594 -12.731236) (xy 445.494246 -12.681632) (xy 445.523728 -12.635757) (xy 445.559438 -12.594545)
			(xy 445.600649 -12.558834) (xy 445.646523 -12.529351) (xy 445.696126 -12.506697) (xy 445.748448 -12.491333)
			(xy 445.802424 -12.483571) (xy 445.82969 -12.483084) (xy 446.69329 -12.483084) (xy 446.720565 -12.483455)
			(xy 446.774559 -12.491217) (xy 446.826899 -12.506584) (xy 446.87652 -12.529244) (xy 446.92241 -12.558735)
			(xy 446.963636 -12.594456) (xy 446.999359 -12.635682) (xy 447.028851 -12.681571) (xy 447.051512 -12.731191)
			(xy 447.066881 -12.783531) (xy 447.074644 -12.837525) (xy 447.074644 -12.892075) (xy 447.066881 -12.946069)
			(xy 447.051512 -12.998409) (xy 447.028851 -13.048029) (xy 446.999359 -13.093918) (xy 446.963636 -13.135144)
			(xy 446.92241 -13.170865) (xy 446.87652 -13.200356) (xy 446.826899 -13.223016) (xy 446.774559 -13.238383)
			(xy 446.720565 -13.246145) (xy 446.69329 -13.246608) (xy 445.82969 -13.246608) (xy 445.802424 -13.246029)
			(xy 445.748448 -13.238267) (xy 445.696126 -13.222903) (xy 445.646523 -13.200249) (xy 445.600649 -13.170766)
			(xy 445.559438 -13.135055) (xy 445.523728 -13.093843) (xy 445.494246 -13.047968) (xy 445.471594 -12.998364)
			(xy 445.456231 -12.946042) (xy 445.44847 -12.892066) (xy 442.135955 -12.892066) (xy 442.148441 -12.905161)
			(xy 442.200812 -12.971757) (xy 442.246615 -13.043029) (xy 442.285437 -13.118332) (xy 442.316925 -13.196984)
			(xy 442.340793 -13.278274) (xy 442.356827 -13.361464) (xy 442.36488 -13.445801) (xy 442.365384 -13.488162)
			(xy 442.364966 -13.526452) (xy 442.358362 -13.602745) (xy 442.345216 -13.678188) (xy 442.325626 -13.752219)
			(xy 442.31306 -13.78839) (xy 442.310428 -13.796831) (xy 442.310415 -13.814498) (xy 442.31306 -13.822934)
			(xy 442.325598 -13.859113) (xy 442.345172 -13.933146) (xy 442.358321 -14.008585) (xy 442.364947 -14.084874)
			(xy 442.365384 -14.123162) (xy 442.36488 -14.165523) (xy 442.356827 -14.24986) (xy 442.340793 -14.33305)
			(xy 442.316925 -14.41434) (xy 442.285437 -14.492992) (xy 442.268155 -14.526514) (xy 449.780152 -14.526514)
			(xy 449.780656 -14.484153) (xy 449.788709 -14.399816) (xy 449.804743 -14.316626) (xy 449.828611 -14.235336)
			(xy 449.860099 -14.156684) (xy 449.898921 -14.081381) (xy 449.944724 -14.010109) (xy 449.997095 -13.943513)
			(xy 450.05556 -13.882198) (xy 450.119588 -13.826717) (xy 450.1886 -13.777574) (xy 450.26197 -13.735214)
			(xy 450.339035 -13.700019) (xy 450.419097 -13.67231) (xy 450.50143 -13.652336) (xy 450.585289 -13.640279)
			(xy 450.669914 -13.636248) (xy 450.754539 -13.640279) (xy 450.838398 -13.652336) (xy 450.920731 -13.67231)
			(xy 451.000793 -13.700019) (xy 451.077858 -13.735214) (xy 451.151228 -13.777574) (xy 451.22024 -13.826717)
			(xy 451.284268 -13.882198) (xy 451.342733 -13.943513) (xy 451.395104 -14.010109) (xy 451.440907 -14.081381)
			(xy 451.479729 -14.156684) (xy 451.511217 -14.235336) (xy 451.535085 -14.316626) (xy 451.551119 -14.399816)
			(xy 451.559172 -14.484153) (xy 451.559676 -14.526514) (xy 451.559114 -14.571839) (xy 451.549887 -14.662018)
			(xy 451.531531 -14.750791) (xy 451.504235 -14.837234) (xy 451.486778 -14.879066) (xy 451.483143 -14.888844)
			(xy 451.483128 -14.909681) (xy 451.486778 -14.919452) (xy 451.504363 -14.961485) (xy 451.531877 -15.048351)
			(xy 451.550364 -15.137575) (xy 451.559632 -15.228222) (xy 451.560184 -15.273782) (xy 451.559623 -15.318552)
			(xy 451.550621 -15.407639) (xy 451.532717 -15.495371) (xy 451.506092 -15.580861) (xy 451.489064 -15.62227)
			(xy 451.485509 -15.631864) (xy 451.485503 -15.652304) (xy 451.489064 -15.661894) (xy 451.50607 -15.703278)
			(xy 451.532693 -15.788702) (xy 451.550602 -15.876368) (xy 451.559616 -15.96539) (xy 451.560184 -16.010128)
			(xy 451.560184 -16.010382) (xy 451.55968 -16.05273) (xy 451.551629 -16.137044) (xy 451.5356 -16.22021)
			(xy 451.511739 -16.301477) (xy 451.48026 -16.380107) (xy 451.441449 -16.455388) (xy 451.395659 -16.52664)
			(xy 451.343303 -16.593216) (xy 451.284855 -16.654514) (xy 451.220845 -16.709979) (xy 451.151853 -16.759108)
			(xy 451.078503 -16.801457) (xy 451.00146 -16.836641) (xy 450.921421 -16.864343) (xy 450.839112 -16.884311)
			(xy 450.755277 -16.896364) (xy 450.670676 -16.900395) (xy 450.586075 -16.896364) (xy 450.50224 -16.884311)
			(xy 450.419931 -16.864343) (xy 450.339892 -16.836641) (xy 450.262849 -16.801457) (xy 450.189499 -16.759108)
			(xy 450.120507 -16.709979) (xy 450.056497 -16.654514) (xy 449.998049 -16.593216) (xy 449.945693 -16.52664)
			(xy 449.899903 -16.455388) (xy 449.861092 -16.380107) (xy 449.829613 -16.301477) (xy 449.805752 -16.22021)
			(xy 449.789723 -16.137044) (xy 449.781672 -16.05273) (xy 449.781168 -16.010382) (xy 449.781168 -16.010128)
			(xy 449.781731 -15.96539) (xy 449.790749 -15.876368) (xy 449.808655 -15.788701) (xy 449.83527 -15.703273)
			(xy 449.852288 -15.661894) (xy 449.855865 -15.652307) (xy 449.855859 -15.63186) (xy 449.852288 -15.62227)
			(xy 449.835263 -15.580859) (xy 449.808628 -15.495372) (xy 449.790721 -15.40764) (xy 449.781723 -15.318552)
			(xy 449.781168 -15.273782) (xy 449.781749 -15.228458) (xy 449.79099 -15.138283) (xy 449.809345 -15.049513)
			(xy 449.836623 -14.963067) (xy 449.854066 -14.92123) (xy 449.857691 -14.911438) (xy 449.857571 -14.890584)
			(xy 449.853812 -14.880844) (xy 449.836183 -14.838823) (xy 449.808624 -14.751958) (xy 449.790079 -14.662732)
			(xy 449.780742 -14.57208) (xy 449.780152 -14.526514) (xy 442.268155 -14.526514) (xy 442.246615 -14.568295)
			(xy 442.200812 -14.639567) (xy 442.148441 -14.706163) (xy 442.089976 -14.767478) (xy 442.025948 -14.822959)
			(xy 441.956936 -14.872102) (xy 441.883566 -14.914462) (xy 441.806501 -14.949657) (xy 441.726439 -14.977366)
			(xy 441.644106 -14.99734) (xy 441.560247 -15.009397) (xy 441.475622 -15.013429) (xy 441.390997 -15.009397)
			(xy 441.307138 -14.99734) (xy 441.224805 -14.977366) (xy 441.144743 -14.949657) (xy 441.067678 -14.914462)
			(xy 440.994308 -14.872102) (xy 440.925296 -14.822959) (xy 440.861268 -14.767478) (xy 440.802803 -14.706163)
			(xy 440.750432 -14.639567) (xy 440.704629 -14.568295) (xy 440.665807 -14.492992) (xy 440.634319 -14.41434)
			(xy 440.610451 -14.33305) (xy 440.594417 -14.24986) (xy 440.586364 -14.165523) (xy 440.58586 -14.123162)
			(xy 439.643167 -14.123162) (xy 439.614561 -14.149324) (xy 439.567661 -14.180907) (xy 439.516614 -14.205222)
			(xy 439.462537 -14.221736) (xy 439.406615 -14.230088) (xy 439.378344 -14.230604) (xy 439.350975 -14.230111)
			(xy 439.296797 -14.2223) (xy 439.244294 -14.206817) (xy 439.194547 -14.183981) (xy 439.148579 -14.154262)
			(xy 439.127646 -14.136624) (xy 439.127392 -14.13637) (xy 439.120314 -14.130771) (xy 439.103391 -14.124533)
			(xy 439.094372 -14.124178) (xy 439.027316 -14.124178) (xy 439.018301 -14.124547) (xy 439.001384 -14.130787)
			(xy 438.994296 -14.13637) (xy 438.994296 -14.136624) (xy 438.994042 -14.136624) (xy 438.973108 -14.154261)
			(xy 438.927135 -14.183972) (xy 438.877388 -14.206808) (xy 438.824888 -14.2223) (xy 438.770713 -14.230129)
			(xy 438.743344 -14.230604) (xy 438.713998 -14.230028) (xy 438.656001 -14.221024) (xy 438.600065 -14.203253)
			(xy 438.547506 -14.177132) (xy 438.499563 -14.143277) (xy 438.457364 -14.102486) (xy 438.421903 -14.055718)
			(xy 438.394015 -14.004075) (xy 438.38368 -13.976604) (xy 438.380221 -13.968026) (xy 438.368225 -13.953963)
			(xy 438.360312 -13.949172) (xy 438.333388 -13.93444) (xy 438.324705 -13.93016) (xy 438.305508 -13.927807)
			(xy 438.29605 -13.929868) (xy 438.259095 -13.939128) (xy 438.184005 -13.952036) (xy 438.108086 -13.958466)
			(xy 438.06999 -13.958824) (xy 438.028658 -13.958363) (xy 437.94635 -13.95071) (xy 437.865107 -13.935453)
			(xy 437.78563 -13.912724) (xy 437.708605 -13.882718) (xy 437.634696 -13.845694) (xy 437.564542 -13.801972)
			(xy 437.498747 -13.751929) (xy 437.43788 -13.695998) (xy 437.382465 -13.634659) (xy 437.332981 -13.568444)
			(xy 437.289854 -13.497922) (xy 437.253456 -13.423703) (xy 437.224103 -13.346427) (xy 437.202046 -13.266761)
			(xy 437.187477 -13.185391) (xy 437.18353 -13.144246) (xy 437.182106 -13.133691) (xy 437.171856 -13.11505)
			(xy 437.163718 -13.108178) (xy 437.131484 -13.082996) (xy 437.071245 -13.027653) (xy 437.016344 -12.967011)
			(xy 436.967245 -12.901582) (xy 436.924364 -12.831919) (xy 436.888063 -12.758612) (xy 436.858649 -12.682281)
			(xy 436.83637 -12.603571) (xy 436.821416 -12.523147) (xy 436.813913 -12.441689) (xy 436.813452 -12.400788)
			(xy 260.234662 -12.400788) (xy 260.203654 -12.412958) (xy 260.103162 -12.461353) (xy 260.006569 -12.517122)
			(xy 259.914413 -12.579954) (xy 259.82721 -12.649497) (xy 259.745448 -12.725362) (xy 259.669584 -12.807125)
			(xy 259.601843 -12.89207) (xy 431.453248 -12.89207) (xy 431.453248 -12.83753) (xy 431.46101 -12.783546)
			(xy 431.476376 -12.731216) (xy 431.499035 -12.681606) (xy 431.528523 -12.635726) (xy 431.564241 -12.594509)
			(xy 431.605461 -12.558796) (xy 431.651345 -12.529313) (xy 431.700957 -12.506661) (xy 431.753289 -12.4913)
			(xy 431.807274 -12.483544) (xy 431.834544 -12.483084) (xy 432.698144 -12.483084) (xy 432.725415 -12.483482)
			(xy 432.7794 -12.491249) (xy 432.83173 -12.50662) (xy 432.881341 -12.529282) (xy 432.927222 -12.558772)
			(xy 432.968439 -12.594492) (xy 433.004154 -12.635713) (xy 433.033639 -12.681598) (xy 433.056295 -12.731211)
			(xy 433.07166 -12.783543) (xy 433.079422 -12.837529) (xy 433.079422 -12.892071) (xy 433.07166 -12.946057)
			(xy 433.056295 -12.998389) (xy 433.033639 -13.048002) (xy 433.004154 -13.093887) (xy 432.968439 -13.135108)
			(xy 432.927222 -13.170828) (xy 432.881341 -13.200318) (xy 432.83173 -13.22298) (xy 432.7794 -13.238351)
			(xy 432.725415 -13.246118) (xy 432.698144 -13.246608) (xy 431.834544 -13.246608) (xy 431.807274 -13.246056)
			(xy 431.753289 -13.2383) (xy 431.700957 -13.222939) (xy 431.651345 -13.200287) (xy 431.605461 -13.170804)
			(xy 431.564241 -13.135091) (xy 431.528523 -13.093874) (xy 431.499035 -13.047994) (xy 431.476376 -12.998384)
			(xy 431.46101 -12.946054) (xy 431.453248 -12.89207) (xy 259.601843 -12.89207) (xy 259.600042 -12.894329)
			(xy 259.537211 -12.986486) (xy 259.481443 -13.08308) (xy 259.43305 -13.183572) (xy 259.392301 -13.287399)
			(xy 259.359426 -13.393981) (xy 259.334607 -13.502722) (xy 259.317984 -13.613014) (xy 259.309649 -13.724239)
			(xy 259.309108 -13.780008) (xy 259.309108 -17.126458) (xy 310.265572 -17.126458) (xy 310.265992 -17.082972)
			(xy 310.273576 -16.996331) (xy 310.288682 -16.910681) (xy 310.311195 -16.826674) (xy 310.340944 -16.744948)
			(xy 310.377702 -16.666126) (xy 310.421191 -16.590808) (xy 310.471078 -16.519566) (xy 310.526985 -16.452943)
			(xy 310.588485 -16.391447) (xy 310.65511 -16.335544) (xy 310.726355 -16.285661) (xy 310.801676 -16.242177)
			(xy 310.8805 -16.205422) (xy 310.962227 -16.175678) (xy 311.046236 -16.15317) (xy 311.131887 -16.138068)
			(xy 311.218528 -16.13049) (xy 311.262014 -16.130016) (xy 311.287414 -16.130016) (xy 311.33271 -16.130609)
			(xy 311.422936 -16.13873) (xy 311.512071 -16.154907) (xy 311.599397 -16.179009) (xy 311.684211 -16.210841)
			(xy 311.76583 -16.250148) (xy 311.843598 -16.296613) (xy 311.916887 -16.349861) (xy 311.985108 -16.409465)
			(xy 312.047712 -16.474944) (xy 312.104194 -16.545772) (xy 312.1541 -16.621377) (xy 312.197028 -16.701151)
			(xy 312.232632 -16.784452) (xy 312.260626 -16.870609) (xy 312.280784 -16.958929) (xy 312.292944 -17.0487)
			(xy 312.297009 -17.1392) (xy 312.292944 -17.2297) (xy 312.280784 -17.319471) (xy 312.260626 -17.407791)
			(xy 312.232632 -17.493948) (xy 312.197028 -17.577249) (xy 312.163448 -17.639652) (xy 389.652738 -17.639652)
			(xy 389.652738 -17.585148) (xy 389.660494 -17.531197) (xy 389.675849 -17.4789) (xy 389.69849 -17.42932)
			(xy 389.727956 -17.383466) (xy 389.763647 -17.342273) (xy 389.804838 -17.306578) (xy 389.850688 -17.277107)
			(xy 389.900266 -17.254462) (xy 389.952562 -17.239102) (xy 390.006512 -17.23134) (xy 390.033764 -17.230852)
			(xy 390.897364 -17.230852) (xy 390.924616 -17.231393) (xy 390.978565 -17.239145) (xy 391.030862 -17.254496)
			(xy 391.080441 -17.277134) (xy 391.126294 -17.306598) (xy 391.167486 -17.342288) (xy 391.20318 -17.383477)
			(xy 391.232649 -17.429327) (xy 391.255291 -17.478905) (xy 391.270648 -17.5312) (xy 391.278405 -17.585148)
			(xy 391.278405 -17.639652) (xy 395.240738 -17.639652) (xy 395.240738 -17.585148) (xy 395.248494 -17.531197)
			(xy 395.263849 -17.4789) (xy 395.28649 -17.42932) (xy 395.315956 -17.383466) (xy 395.351647 -17.342273)
			(xy 395.392838 -17.306578) (xy 395.438688 -17.277107) (xy 395.488266 -17.254462) (xy 395.540562 -17.239102)
			(xy 395.594512 -17.23134) (xy 395.621764 -17.230852) (xy 396.485364 -17.230852) (xy 396.512616 -17.231393)
			(xy 396.566565 -17.239145) (xy 396.618862 -17.254496) (xy 396.668441 -17.277134) (xy 396.714294 -17.306598)
			(xy 396.755486 -17.342288) (xy 396.79118 -17.383477) (xy 396.820649 -17.429327) (xy 396.843291 -17.478905)
			(xy 396.858648 -17.5312) (xy 396.866405 -17.585148) (xy 396.866405 -17.639652) (xy 400.828738 -17.639652)
			(xy 400.828738 -17.585148) (xy 400.836494 -17.531197) (xy 400.851849 -17.4789) (xy 400.87449 -17.42932)
			(xy 400.903956 -17.383466) (xy 400.939647 -17.342273) (xy 400.980838 -17.306578) (xy 401.026688 -17.277107)
			(xy 401.076266 -17.254462) (xy 401.128562 -17.239102) (xy 401.182512 -17.23134) (xy 401.209764 -17.230852)
			(xy 402.073364 -17.230852) (xy 402.100616 -17.231393) (xy 402.154565 -17.239145) (xy 402.206862 -17.254496)
			(xy 402.256441 -17.277134) (xy 402.302294 -17.306598) (xy 402.343486 -17.342288) (xy 402.37918 -17.383477)
			(xy 402.408649 -17.429327) (xy 402.431291 -17.478905) (xy 402.446648 -17.5312) (xy 402.454405 -17.585148)
			(xy 402.454405 -17.639652) (xy 402.454301 -17.640372) (xy 406.415424 -17.640372) (xy 406.415424 -17.585828)
			(xy 406.423187 -17.53184) (xy 406.438554 -17.479507) (xy 406.461214 -17.429893) (xy 406.490704 -17.38401)
			(xy 406.526425 -17.342791) (xy 406.567649 -17.307076) (xy 406.613536 -17.277591) (xy 406.663152 -17.254938)
			(xy 406.715487 -17.239576) (xy 406.769476 -17.23182) (xy 406.796748 -17.23136) (xy 407.660348 -17.23136)
			(xy 407.687617 -17.231806) (xy 407.741598 -17.239573) (xy 407.793925 -17.254944) (xy 407.843532 -17.277604)
			(xy 407.88941 -17.307093) (xy 407.930624 -17.34281) (xy 407.966336 -17.384029) (xy 407.995819 -17.42991)
			(xy 408.018473 -17.47952) (xy 408.033837 -17.531849) (xy 408.041598 -17.585831) (xy 408.041598 -17.640369)
			(xy 408.041598 -17.640372) (xy 412.003424 -17.640372) (xy 412.003424 -17.585828) (xy 412.011187 -17.53184)
			(xy 412.026554 -17.479507) (xy 412.049214 -17.429893) (xy 412.078704 -17.38401) (xy 412.114425 -17.342791)
			(xy 412.155649 -17.307076) (xy 412.201536 -17.277591) (xy 412.251152 -17.254938) (xy 412.303487 -17.239576)
			(xy 412.357476 -17.23182) (xy 412.384748 -17.23136) (xy 413.248348 -17.23136) (xy 413.275617 -17.231806)
			(xy 413.329598 -17.239573) (xy 413.381925 -17.254944) (xy 413.431532 -17.277604) (xy 413.47741 -17.307093)
			(xy 413.518624 -17.34281) (xy 413.554336 -17.384029) (xy 413.583819 -17.42991) (xy 413.606473 -17.47952)
			(xy 413.621837 -17.531849) (xy 413.629598 -17.585831) (xy 413.629598 -17.639653) (xy 417.898538 -17.639653)
			(xy 417.898538 -17.585147) (xy 417.906295 -17.531195) (xy 417.92165 -17.478897) (xy 417.944292 -17.429315)
			(xy 417.97376 -17.383461) (xy 418.009453 -17.342267) (xy 418.050645 -17.306572) (xy 418.096498 -17.277102)
			(xy 418.146078 -17.254457) (xy 418.198376 -17.239099) (xy 418.252327 -17.231339) (xy 418.27958 -17.230852)
			(xy 419.14318 -17.230852) (xy 419.170431 -17.231394) (xy 419.224378 -17.239148) (xy 419.276673 -17.2545)
			(xy 419.326251 -17.277139) (xy 419.372101 -17.306604) (xy 419.413292 -17.342294) (xy 419.448984 -17.383483)
			(xy 419.478451 -17.429332) (xy 419.501093 -17.478908) (xy 419.516448 -17.531202) (xy 419.524205 -17.585149)
			(xy 419.524205 -17.639651) (xy 419.524205 -17.639653) (xy 423.486538 -17.639653) (xy 423.486538 -17.585147)
			(xy 423.494295 -17.531195) (xy 423.50965 -17.478897) (xy 423.532292 -17.429315) (xy 423.56176 -17.383461)
			(xy 423.597453 -17.342267) (xy 423.638645 -17.306572) (xy 423.684498 -17.277102) (xy 423.734078 -17.254457)
			(xy 423.786376 -17.239099) (xy 423.840327 -17.231339) (xy 423.86758 -17.230852) (xy 424.73118 -17.230852)
			(xy 424.758431 -17.231394) (xy 424.812378 -17.239148) (xy 424.864673 -17.2545) (xy 424.914251 -17.277139)
			(xy 424.960101 -17.306604) (xy 425.001292 -17.342294) (xy 425.036984 -17.383483) (xy 425.066451 -17.429332)
			(xy 425.089093 -17.478908) (xy 425.104448 -17.531202) (xy 425.112205 -17.585149) (xy 425.112205 -17.639651)
			(xy 425.112102 -17.640368) (xy 429.107346 -17.640368) (xy 429.107346 -17.585832) (xy 429.115108 -17.531852)
			(xy 429.130472 -17.479525) (xy 429.153127 -17.429918) (xy 429.182611 -17.38404) (xy 429.218324 -17.342824)
			(xy 429.25954 -17.307111) (xy 429.305418 -17.277627) (xy 429.355025 -17.254972) (xy 429.407352 -17.239608)
			(xy 429.461332 -17.231846) (xy 429.4886 -17.23136) (xy 430.3522 -17.23136) (xy 430.379471 -17.231802)
			(xy 430.433458 -17.239565) (xy 430.48579 -17.254931) (xy 430.535403 -17.277588) (xy 430.581287 -17.307076)
			(xy 430.622507 -17.342793) (xy 430.658224 -17.384013) (xy 430.687712 -17.429897) (xy 430.710369 -17.47951)
			(xy 430.725735 -17.531842) (xy 430.733498 -17.585829) (xy 430.733498 -17.640371) (xy 430.725735 -17.694358)
			(xy 430.710369 -17.74669) (xy 430.687712 -17.796303) (xy 430.658224 -17.842187) (xy 430.622507 -17.883407)
			(xy 430.581287 -17.919124) (xy 430.535403 -17.948612) (xy 430.48579 -17.971269) (xy 430.433458 -17.986635)
			(xy 430.379471 -17.994398) (xy 430.3522 -17.994884) (xy 429.4886 -17.994884) (xy 429.461332 -17.994354)
			(xy 429.407352 -17.986592) (xy 429.355025 -17.971228) (xy 429.305418 -17.948573) (xy 429.25954 -17.919089)
			(xy 429.218324 -17.883376) (xy 429.182611 -17.84216) (xy 429.153127 -17.796282) (xy 429.130472 -17.746675)
			(xy 429.115108 -17.694348) (xy 429.107346 -17.640368) (xy 425.112102 -17.640368) (xy 425.104448 -17.693598)
			(xy 425.089093 -17.745892) (xy 425.066451 -17.795468) (xy 425.036984 -17.841317) (xy 425.001292 -17.882506)
			(xy 424.960101 -17.918196) (xy 424.914251 -17.947661) (xy 424.864673 -17.9703) (xy 424.812378 -17.985652)
			(xy 424.758431 -17.993406) (xy 424.73118 -17.993868) (xy 423.86758 -17.993868) (xy 423.840327 -17.993461)
			(xy 423.786376 -17.985701) (xy 423.734078 -17.970343) (xy 423.684498 -17.947698) (xy 423.638645 -17.918228)
			(xy 423.597453 -17.882533) (xy 423.56176 -17.841339) (xy 423.532292 -17.795485) (xy 423.50965 -17.745903)
			(xy 423.494295 -17.693605) (xy 423.486538 -17.639653) (xy 419.524205 -17.639653) (xy 419.516448 -17.693598)
			(xy 419.501093 -17.745892) (xy 419.478451 -17.795468) (xy 419.448984 -17.841317) (xy 419.413292 -17.882506)
			(xy 419.372101 -17.918196) (xy 419.326251 -17.947661) (xy 419.276673 -17.9703) (xy 419.224378 -17.985652)
			(xy 419.170431 -17.993406) (xy 419.14318 -17.993868) (xy 418.27958 -17.993868) (xy 418.252327 -17.993461)
			(xy 418.198376 -17.985701) (xy 418.146078 -17.970343) (xy 418.096498 -17.947698) (xy 418.050645 -17.918228)
			(xy 418.009453 -17.882533) (xy 417.97376 -17.841339) (xy 417.944292 -17.795485) (xy 417.92165 -17.745903)
			(xy 417.906295 -17.693605) (xy 417.898538 -17.639653) (xy 413.629598 -17.639653) (xy 413.629598 -17.640369)
			(xy 413.621837 -17.694351) (xy 413.606473 -17.74668) (xy 413.583819 -17.79629) (xy 413.554336 -17.842171)
			(xy 413.518624 -17.88339) (xy 413.47741 -17.919107) (xy 413.431532 -17.948596) (xy 413.381925 -17.971256)
			(xy 413.329598 -17.986627) (xy 413.275617 -17.994394) (xy 413.248348 -17.994884) (xy 412.384748 -17.994884)
			(xy 412.357476 -17.99438) (xy 412.303487 -17.986624) (xy 412.251152 -17.971262) (xy 412.201536 -17.948609)
			(xy 412.155649 -17.919124) (xy 412.114425 -17.883409) (xy 412.078704 -17.84219) (xy 412.049214 -17.796307)
			(xy 412.026554 -17.746693) (xy 412.011187 -17.69436) (xy 412.003424 -17.640372) (xy 408.041598 -17.640372)
			(xy 408.033837 -17.694351) (xy 408.018473 -17.74668) (xy 407.995819 -17.79629) (xy 407.966336 -17.842171)
			(xy 407.930624 -17.88339) (xy 407.88941 -17.919107) (xy 407.843532 -17.948596) (xy 407.793925 -17.971256)
			(xy 407.741598 -17.986627) (xy 407.687617 -17.994394) (xy 407.660348 -17.994884) (xy 406.796748 -17.994884)
			(xy 406.769476 -17.99438) (xy 406.715487 -17.986624) (xy 406.663152 -17.971262) (xy 406.613536 -17.948609)
			(xy 406.567649 -17.919124) (xy 406.526425 -17.883409) (xy 406.490704 -17.84219) (xy 406.461214 -17.796307)
			(xy 406.438554 -17.746693) (xy 406.423187 -17.69436) (xy 406.415424 -17.640372) (xy 402.454301 -17.640372)
			(xy 402.446648 -17.6936) (xy 402.431291 -17.745895) (xy 402.408649 -17.795473) (xy 402.37918 -17.841323)
			(xy 402.343486 -17.882512) (xy 402.302294 -17.918202) (xy 402.256441 -17.947666) (xy 402.206862 -17.970304)
			(xy 402.154565 -17.985655) (xy 402.100616 -17.993407) (xy 402.073364 -17.993868) (xy 401.209764 -17.993868)
			(xy 401.182512 -17.99346) (xy 401.128562 -17.985698) (xy 401.076266 -17.970338) (xy 401.026688 -17.947693)
			(xy 400.980838 -17.918222) (xy 400.939647 -17.882527) (xy 400.903956 -17.841334) (xy 400.87449 -17.79548)
			(xy 400.851849 -17.7459) (xy 400.836494 -17.693603) (xy 400.828738 -17.639652) (xy 396.866405 -17.639652)
			(xy 396.858648 -17.6936) (xy 396.843291 -17.745895) (xy 396.820649 -17.795473) (xy 396.79118 -17.841323)
			(xy 396.755486 -17.882512) (xy 396.714294 -17.918202) (xy 396.668441 -17.947666) (xy 396.618862 -17.970304)
			(xy 396.566565 -17.985655) (xy 396.512616 -17.993407) (xy 396.485364 -17.993868) (xy 395.621764 -17.993868)
			(xy 395.594512 -17.99346) (xy 395.540562 -17.985698) (xy 395.488266 -17.970338) (xy 395.438688 -17.947693)
			(xy 395.392838 -17.918222) (xy 395.351647 -17.882527) (xy 395.315956 -17.841334) (xy 395.28649 -17.79548)
			(xy 395.263849 -17.7459) (xy 395.248494 -17.693603) (xy 395.240738 -17.639652) (xy 391.278405 -17.639652)
			(xy 391.270648 -17.6936) (xy 391.255291 -17.745895) (xy 391.232649 -17.795473) (xy 391.20318 -17.841323)
			(xy 391.167486 -17.882512) (xy 391.126294 -17.918202) (xy 391.080441 -17.947666) (xy 391.030862 -17.970304)
			(xy 390.978565 -17.985655) (xy 390.924616 -17.993407) (xy 390.897364 -17.993868) (xy 390.033764 -17.993868)
			(xy 390.006512 -17.99346) (xy 389.952562 -17.985698) (xy 389.900266 -17.970338) (xy 389.850688 -17.947693)
			(xy 389.804838 -17.918222) (xy 389.763647 -17.882527) (xy 389.727956 -17.841334) (xy 389.69849 -17.79548)
			(xy 389.675849 -17.7459) (xy 389.660494 -17.693603) (xy 389.652738 -17.639652) (xy 312.163448 -17.639652)
			(xy 312.1541 -17.657023) (xy 312.104194 -17.732628) (xy 312.047712 -17.803456) (xy 311.985108 -17.868935)
			(xy 311.916887 -17.928539) (xy 311.843598 -17.981787) (xy 311.76583 -18.028252) (xy 311.684211 -18.067559)
			(xy 311.599397 -18.099391) (xy 311.512071 -18.123493) (xy 311.422936 -18.13967) (xy 311.33271 -18.147791)
			(xy 311.287414 -18.1483) (xy 311.28716 -18.1483) (xy 311.242573 -18.147831) (xy 311.153739 -18.140039)
			(xy 311.065923 -18.124536) (xy 310.979792 -18.101438) (xy 310.896001 -18.070922) (xy 310.815188 -18.033221)
			(xy 310.737969 -17.988621) (xy 310.664929 -17.937461) (xy 310.596626 -17.88013) (xy 310.533579 -17.817066)
			(xy 310.476268 -17.748747) (xy 310.425128 -17.675693) (xy 310.380549 -17.598461) (xy 310.34287 -17.517638)
			(xy 310.312377 -17.433839) (xy 310.289303 -17.347701) (xy 310.273824 -17.259881) (xy 310.266056 -17.171045)
			(xy 310.265572 -17.126458) (xy 259.309108 -17.126458) (xy 259.309108 -19.164372) (xy 392.445424 -19.164372)
			(xy 392.445424 -19.109828) (xy 392.453187 -19.05584) (xy 392.468554 -19.003507) (xy 392.491214 -18.953893)
			(xy 392.520704 -18.90801) (xy 392.556425 -18.866791) (xy 392.597649 -18.831076) (xy 392.643536 -18.801591)
			(xy 392.693152 -18.778938) (xy 392.745487 -18.763576) (xy 392.799476 -18.75582) (xy 392.826748 -18.75536)
			(xy 393.690348 -18.75536) (xy 393.717617 -18.755806) (xy 393.771598 -18.763573) (xy 393.823925 -18.778944)
			(xy 393.873532 -18.801604) (xy 393.91941 -18.831093) (xy 393.960624 -18.86681) (xy 393.996336 -18.908029)
			(xy 394.025819 -18.95391) (xy 394.048473 -19.00352) (xy 394.063837 -19.055849) (xy 394.071598 -19.109831)
			(xy 394.071598 -19.163652) (xy 398.034738 -19.163652) (xy 398.034738 -19.109148) (xy 398.042494 -19.055197)
			(xy 398.057849 -19.0029) (xy 398.08049 -18.95332) (xy 398.109956 -18.907466) (xy 398.145647 -18.866273)
			(xy 398.186838 -18.830578) (xy 398.232688 -18.801107) (xy 398.282266 -18.778462) (xy 398.334562 -18.763102)
			(xy 398.388512 -18.75534) (xy 398.415764 -18.754852) (xy 399.279364 -18.754852) (xy 399.306616 -18.755393)
			(xy 399.360565 -18.763145) (xy 399.412862 -18.778496) (xy 399.462441 -18.801134) (xy 399.508294 -18.830598)
			(xy 399.549486 -18.866288) (xy 399.58518 -18.907477) (xy 399.614649 -18.953327) (xy 399.637291 -19.002905)
			(xy 399.652648 -19.0552) (xy 399.660405 -19.109148) (xy 399.660405 -19.163652) (xy 403.622738 -19.163652)
			(xy 403.622738 -19.109148) (xy 403.630494 -19.055197) (xy 403.645849 -19.0029) (xy 403.66849 -18.95332)
			(xy 403.697956 -18.907466) (xy 403.733647 -18.866273) (xy 403.774838 -18.830578) (xy 403.820688 -18.801107)
			(xy 403.870266 -18.778462) (xy 403.922562 -18.763102) (xy 403.976512 -18.75534) (xy 404.003764 -18.754852)
			(xy 404.867364 -18.754852) (xy 404.894616 -18.755393) (xy 404.948565 -18.763145) (xy 405.000862 -18.778496)
			(xy 405.050441 -18.801134) (xy 405.096294 -18.830598) (xy 405.137486 -18.866288) (xy 405.17318 -18.907477)
			(xy 405.202649 -18.953327) (xy 405.225291 -19.002905) (xy 405.240648 -19.0552) (xy 405.248405 -19.109148)
			(xy 405.248405 -19.163652) (xy 409.210738 -19.163652) (xy 409.210738 -19.109148) (xy 409.218494 -19.055197)
			(xy 409.233849 -19.0029) (xy 409.25649 -18.95332) (xy 409.285956 -18.907466) (xy 409.321647 -18.866273)
			(xy 409.362838 -18.830578) (xy 409.408688 -18.801107) (xy 409.458266 -18.778462) (xy 409.510562 -18.763102)
			(xy 409.564512 -18.75534) (xy 409.591764 -18.754852) (xy 410.455364 -18.754852) (xy 410.482616 -18.755393)
			(xy 410.536565 -18.763145) (xy 410.588862 -18.778496) (xy 410.638441 -18.801134) (xy 410.684294 -18.830598)
			(xy 410.725486 -18.866288) (xy 410.76118 -18.907477) (xy 410.790649 -18.953327) (xy 410.813291 -19.002905)
			(xy 410.828648 -19.0552) (xy 410.836405 -19.109148) (xy 410.836405 -19.163652) (xy 410.836405 -19.163653)
			(xy 415.104538 -19.163653) (xy 415.104538 -19.109147) (xy 415.112295 -19.055195) (xy 415.12765 -19.002897)
			(xy 415.150292 -18.953315) (xy 415.17976 -18.907461) (xy 415.215453 -18.866267) (xy 415.256645 -18.830572)
			(xy 415.302498 -18.801102) (xy 415.352078 -18.778457) (xy 415.404376 -18.763099) (xy 415.458327 -18.755339)
			(xy 415.48558 -18.754852) (xy 416.34918 -18.754852) (xy 416.376431 -18.755394) (xy 416.430378 -18.763148)
			(xy 416.482673 -18.7785) (xy 416.532251 -18.801139) (xy 416.578101 -18.830604) (xy 416.619292 -18.866294)
			(xy 416.654984 -18.907483) (xy 416.684451 -18.953332) (xy 416.707093 -19.002908) (xy 416.722448 -19.055202)
			(xy 416.730205 -19.109149) (xy 416.730205 -19.163651) (xy 416.730102 -19.164366) (xy 420.691346 -19.164366)
			(xy 420.691346 -19.109834) (xy 420.699107 -19.055857) (xy 420.714469 -19.003533) (xy 420.737121 -18.953928)
			(xy 420.766602 -18.908051) (xy 420.802312 -18.866837) (xy 420.843523 -18.831124) (xy 420.889396 -18.801639)
			(xy 420.938999 -18.778982) (xy 420.991321 -18.763614) (xy 421.045298 -18.755849) (xy 421.072564 -18.75536)
			(xy 421.936164 -18.75536) (xy 421.963438 -18.755777) (xy 422.017432 -18.763536) (xy 422.069772 -18.7789)
			(xy 422.119393 -18.801556) (xy 422.165284 -18.831045) (xy 422.20651 -18.866764) (xy 422.242234 -18.907988)
			(xy 422.271726 -18.953876) (xy 422.294388 -19.003494) (xy 422.309757 -19.055833) (xy 422.31752 -19.109826)
			(xy 422.31752 -19.163656) (xy 426.314515 -19.163656) (xy 426.314515 -19.109144) (xy 426.322273 -19.055185)
			(xy 426.337632 -19.002881) (xy 426.360278 -18.953294) (xy 426.38975 -18.907436) (xy 426.42545 -18.866238)
			(xy 426.466648 -18.830541) (xy 426.512508 -18.80107) (xy 426.562096 -18.778426) (xy 426.614401 -18.76307)
			(xy 426.66836 -18.755314) (xy 426.695616 -18.754852) (xy 427.559216 -18.754852) (xy 427.586464 -18.755419)
			(xy 427.640404 -18.763177) (xy 427.692691 -18.778532) (xy 427.742261 -18.801171) (xy 427.788105 -18.830635)
			(xy 427.829289 -18.866323) (xy 427.864975 -18.907508) (xy 427.894436 -18.953353) (xy 427.917074 -19.002924)
			(xy 427.932427 -19.055212) (xy 427.940182 -19.109152) (xy 427.940182 -19.163648) (xy 427.940181 -19.163656)
			(xy 431.902515 -19.163656) (xy 431.902515 -19.109144) (xy 431.910273 -19.055185) (xy 431.925632 -19.002881)
			(xy 431.948278 -18.953294) (xy 431.97775 -18.907436) (xy 432.01345 -18.866238) (xy 432.054648 -18.830541)
			(xy 432.100508 -18.80107) (xy 432.150096 -18.778426) (xy 432.202401 -18.76307) (xy 432.25636 -18.755314)
			(xy 432.283616 -18.754852) (xy 433.147216 -18.754852) (xy 433.174464 -18.755419) (xy 433.228404 -18.763177)
			(xy 433.280691 -18.778532) (xy 433.330261 -18.801171) (xy 433.376105 -18.830635) (xy 433.417289 -18.866323)
			(xy 433.452975 -18.907508) (xy 433.482436 -18.953353) (xy 433.505074 -19.002924) (xy 433.520427 -19.055212)
			(xy 433.528182 -19.109152) (xy 433.528182 -19.163648) (xy 433.520427 -19.217588) (xy 433.505074 -19.269876)
			(xy 433.482436 -19.319447) (xy 433.452975 -19.365292) (xy 433.417289 -19.406477) (xy 433.376105 -19.442165)
			(xy 433.330261 -19.471629) (xy 433.280691 -19.494268) (xy 433.228404 -19.509623) (xy 433.174464 -19.517381)
			(xy 433.147216 -19.517868) (xy 432.283616 -19.517868) (xy 432.25636 -19.517486) (xy 432.202401 -19.50973)
			(xy 432.150096 -19.494374) (xy 432.100508 -19.47173) (xy 432.054648 -19.442259) (xy 432.01345 -19.406562)
			(xy 431.97775 -19.365364) (xy 431.948278 -19.319506) (xy 431.925632 -19.269919) (xy 431.910273 -19.217615)
			(xy 431.902515 -19.163656) (xy 427.940181 -19.163656) (xy 427.932427 -19.217588) (xy 427.917074 -19.269876)
			(xy 427.894436 -19.319447) (xy 427.864975 -19.365292) (xy 427.829289 -19.406477) (xy 427.788105 -19.442165)
			(xy 427.742261 -19.471629) (xy 427.692691 -19.494268) (xy 427.640404 -19.509623) (xy 427.586464 -19.517381)
			(xy 427.559216 -19.517868) (xy 426.695616 -19.517868) (xy 426.66836 -19.517486) (xy 426.614401 -19.50973)
			(xy 426.562096 -19.494374) (xy 426.512508 -19.47173) (xy 426.466648 -19.442259) (xy 426.42545 -19.406562)
			(xy 426.38975 -19.365364) (xy 426.360278 -19.319506) (xy 426.337632 -19.269919) (xy 426.322273 -19.217615)
			(xy 426.314515 -19.163656) (xy 422.31752 -19.163656) (xy 422.31752 -19.164374) (xy 422.309757 -19.218367)
			(xy 422.294388 -19.270706) (xy 422.271726 -19.320324) (xy 422.242234 -19.366212) (xy 422.20651 -19.407436)
			(xy 422.165284 -19.443155) (xy 422.119393 -19.472644) (xy 422.069772 -19.4953) (xy 422.017432 -19.510664)
			(xy 421.963438 -19.518423) (xy 421.936164 -19.518884) (xy 421.072564 -19.518884) (xy 421.045298 -19.518351)
			(xy 420.991321 -19.510586) (xy 420.938999 -19.495218) (xy 420.889396 -19.472561) (xy 420.843523 -19.443076)
			(xy 420.802312 -19.407363) (xy 420.766602 -19.366149) (xy 420.737121 -19.320272) (xy 420.714469 -19.270667)
			(xy 420.699107 -19.218343) (xy 420.691346 -19.164366) (xy 416.730102 -19.164366) (xy 416.722448 -19.217598)
			(xy 416.707093 -19.269892) (xy 416.684451 -19.319468) (xy 416.654984 -19.365317) (xy 416.619292 -19.406506)
			(xy 416.578101 -19.442196) (xy 416.532251 -19.471661) (xy 416.482673 -19.4943) (xy 416.430378 -19.509652)
			(xy 416.376431 -19.517406) (xy 416.34918 -19.517868) (xy 415.48558 -19.517868) (xy 415.458327 -19.517461)
			(xy 415.404376 -19.509701) (xy 415.352078 -19.494343) (xy 415.302498 -19.471698) (xy 415.256645 -19.442228)
			(xy 415.215453 -19.406533) (xy 415.17976 -19.365339) (xy 415.150292 -19.319485) (xy 415.12765 -19.269903)
			(xy 415.112295 -19.217605) (xy 415.104538 -19.163653) (xy 410.836405 -19.163653) (xy 410.828648 -19.2176)
			(xy 410.813291 -19.269895) (xy 410.790649 -19.319473) (xy 410.76118 -19.365323) (xy 410.725486 -19.406512)
			(xy 410.684294 -19.442202) (xy 410.638441 -19.471666) (xy 410.588862 -19.494304) (xy 410.536565 -19.509655)
			(xy 410.482616 -19.517407) (xy 410.455364 -19.517868) (xy 409.591764 -19.517868) (xy 409.564512 -19.51746)
			(xy 409.510562 -19.509698) (xy 409.458266 -19.494338) (xy 409.408688 -19.471693) (xy 409.362838 -19.442222)
			(xy 409.321647 -19.406527) (xy 409.285956 -19.365334) (xy 409.25649 -19.31948) (xy 409.233849 -19.2699)
			(xy 409.218494 -19.217603) (xy 409.210738 -19.163652) (xy 405.248405 -19.163652) (xy 405.240648 -19.2176)
			(xy 405.225291 -19.269895) (xy 405.202649 -19.319473) (xy 405.17318 -19.365323) (xy 405.137486 -19.406512)
			(xy 405.096294 -19.442202) (xy 405.050441 -19.471666) (xy 405.000862 -19.494304) (xy 404.948565 -19.509655)
			(xy 404.894616 -19.517407) (xy 404.867364 -19.517868) (xy 404.003764 -19.517868) (xy 403.976512 -19.51746)
			(xy 403.922562 -19.509698) (xy 403.870266 -19.494338) (xy 403.820688 -19.471693) (xy 403.774838 -19.442222)
			(xy 403.733647 -19.406527) (xy 403.697956 -19.365334) (xy 403.66849 -19.31948) (xy 403.645849 -19.2699)
			(xy 403.630494 -19.217603) (xy 403.622738 -19.163652) (xy 399.660405 -19.163652) (xy 399.652648 -19.2176)
			(xy 399.637291 -19.269895) (xy 399.614649 -19.319473) (xy 399.58518 -19.365323) (xy 399.549486 -19.406512)
			(xy 399.508294 -19.442202) (xy 399.462441 -19.471666) (xy 399.412862 -19.494304) (xy 399.360565 -19.509655)
			(xy 399.306616 -19.517407) (xy 399.279364 -19.517868) (xy 398.415764 -19.517868) (xy 398.388512 -19.51746)
			(xy 398.334562 -19.509698) (xy 398.282266 -19.494338) (xy 398.232688 -19.471693) (xy 398.186838 -19.442222)
			(xy 398.145647 -19.406527) (xy 398.109956 -19.365334) (xy 398.08049 -19.31948) (xy 398.057849 -19.2699)
			(xy 398.042494 -19.217603) (xy 398.034738 -19.163652) (xy 394.071598 -19.163652) (xy 394.071598 -19.164369)
			(xy 394.063837 -19.218351) (xy 394.048473 -19.27068) (xy 394.025819 -19.32029) (xy 393.996336 -19.366171)
			(xy 393.960624 -19.40739) (xy 393.91941 -19.443107) (xy 393.873532 -19.472596) (xy 393.823925 -19.495256)
			(xy 393.771598 -19.510627) (xy 393.717617 -19.518394) (xy 393.690348 -19.518884) (xy 392.826748 -19.518884)
			(xy 392.799476 -19.51838) (xy 392.745487 -19.510624) (xy 392.693152 -19.495262) (xy 392.643536 -19.472609)
			(xy 392.597649 -19.443124) (xy 392.556425 -19.407409) (xy 392.520704 -19.36619) (xy 392.491214 -19.320307)
			(xy 392.468554 -19.270693) (xy 392.453187 -19.21836) (xy 392.445424 -19.164372) (xy 259.309108 -19.164372)
			(xy 259.309108 -20.4061) (xy 368.50594 -20.4061) (xy 368.510005 -20.315592) (xy 368.522167 -20.225813)
			(xy 368.542328 -20.137486) (xy 368.570325 -20.051322) (xy 368.605934 -19.968014) (xy 368.648867 -19.888233)
			(xy 368.698779 -19.812623) (xy 368.755267 -19.741791) (xy 368.817878 -19.676308) (xy 368.886107 -19.616701)
			(xy 368.959405 -19.56345) (xy 369.037181 -19.516984) (xy 369.118809 -19.477677) (xy 369.203632 -19.445846)
			(xy 369.290966 -19.421746) (xy 369.38011 -19.405573) (xy 369.470345 -19.397455) (xy 369.515644 -19.396964)
			(xy 369.560233 -19.397442) (xy 369.649072 -19.405219) (xy 369.736895 -19.420711) (xy 369.823033 -19.443798)
			(xy 369.906831 -19.474305) (xy 369.987651 -19.512001) (xy 370.064878 -19.556597) (xy 370.137923 -19.607756)
			(xy 370.206232 -19.665086) (xy 370.269283 -19.728153) (xy 370.326597 -19.796475) (xy 370.377737 -19.869533)
			(xy 370.422315 -19.946771) (xy 370.459991 -20.0276) (xy 370.490478 -20.111405) (xy 370.513544 -20.197549)
			(xy 370.529013 -20.285376) (xy 370.536768 -20.374217) (xy 370.537232 -20.418806) (xy 370.536774 -20.462284)
			(xy 370.529196 -20.54891) (xy 370.514098 -20.634545) (xy 370.491595 -20.71854) (xy 370.485037 -20.73656)
			(xy 440.464956 -20.73656) (xy 440.465378 -20.698271) (xy 440.471981 -20.621977) (xy 440.485126 -20.546534)
			(xy 440.504715 -20.472503) (xy 440.51728 -20.436332) (xy 440.51995 -20.4279) (xy 440.519937 -20.410225)
			(xy 440.51728 -20.401788) (xy 440.50475 -20.365606) (xy 440.485173 -20.291575) (xy 440.472022 -20.216136)
			(xy 440.465394 -20.139848) (xy 440.464956 -20.10156) (xy 440.46549 -20.057765) (xy 440.474106 -19.9706)
			(xy 440.49125 -19.884704) (xy 440.516756 -19.80091) (xy 440.550377 -19.72003) (xy 440.57062 -19.68119)
			(xy 440.576064 -19.669733) (xy 440.576046 -19.644397) (xy 440.57062 -19.63293) (xy 440.550398 -19.594081)
			(xy 440.51679 -19.513198) (xy 440.491286 -19.429406) (xy 440.474133 -19.343514) (xy 440.465497 -19.256354)
			(xy 440.464956 -19.21256) (xy 440.465378 -19.174271) (xy 440.471981 -19.097977) (xy 440.485126 -19.022534)
			(xy 440.504715 -18.948503) (xy 440.51728 -18.912332) (xy 440.51995 -18.9039) (xy 440.519937 -18.886225)
			(xy 440.51728 -18.877788) (xy 440.50475 -18.841606) (xy 440.485173 -18.767575) (xy 440.472022 -18.692136)
			(xy 440.465394 -18.615848) (xy 440.464956 -18.57756) (xy 440.465414 -18.53645) (xy 440.473005 -18.45458)
			(xy 440.488119 -18.373761) (xy 440.510626 -18.294681) (xy 440.540334 -18.218015) (xy 440.576991 -18.144418)
			(xy 440.620282 -18.074518) (xy 440.66984 -18.008911) (xy 440.72524 -17.948157) (xy 440.78601 -17.892775)
			(xy 440.851631 -17.843237) (xy 440.921544 -17.799965) (xy 440.995152 -17.76333) (xy 441.071826 -17.733644)
			(xy 441.150912 -17.71116) (xy 441.231736 -17.69607) (xy 441.313608 -17.688502) (xy 441.354718 -17.688052)
			(xy 441.395668 -17.688478) (xy 441.477223 -17.695989) (xy 441.557742 -17.710965) (xy 441.636544 -17.733279)
			(xy 441.712961 -17.762742) (xy 441.786347 -17.799105) (xy 441.856079 -17.842059) (xy 441.921567 -17.891241)
			(xy 441.982258 -17.946234) (xy 442.010292 -17.976088) (xy 442.017449 -17.983101) (xy 442.035585 -17.991562)
			(xy 442.055576 -17.99248) (xy 442.065156 -17.98955) (xy 442.102033 -17.976445) (xy 442.177582 -17.955997)
			(xy 442.254637 -17.94227) (xy 442.3326 -17.935373) (xy 442.371734 -17.93494) (xy 442.412849 -17.93538)
			(xy 442.494727 -17.942971) (xy 442.575557 -17.958083) (xy 442.654646 -17.980589) (xy 442.731323 -18.010296)
			(xy 442.804931 -18.046951) (xy 442.874843 -18.090241) (xy 442.940462 -18.139797) (xy 443.001229 -18.195196)
			(xy 443.056626 -18.255966) (xy 443.106179 -18.321587) (xy 443.149467 -18.391501) (xy 443.186119 -18.46511)
			(xy 443.213248 -18.535142) (xy 451.165468 -18.535142) (xy 451.165468 -18.534888) (xy 451.166052 -18.49015)
			(xy 451.175063 -18.401129) (xy 451.192964 -18.313462) (xy 451.219572 -18.228034) (xy 451.236588 -18.186654)
			(xy 451.240131 -18.177057) (xy 451.240147 -18.15662) (xy 451.236588 -18.14703) (xy 451.219555 -18.105656)
			(xy 451.192939 -18.020228) (xy 451.175038 -17.932559) (xy 451.166032 -17.843535) (xy 451.165468 -17.798796)
			(xy 451.165468 -17.798542) (xy 451.165972 -17.756194) (xy 451.174023 -17.67188) (xy 451.190052 -17.588714)
			(xy 451.213913 -17.507447) (xy 451.245392 -17.428817) (xy 451.284203 -17.353536) (xy 451.329993 -17.282284)
			(xy 451.382349 -17.215708) (xy 451.440797 -17.15441) (xy 451.504807 -17.098945) (xy 451.573799 -17.049816)
			(xy 451.647149 -17.007467) (xy 451.724192 -16.972283) (xy 451.804231 -16.944581) (xy 451.88654 -16.924613)
			(xy 451.970375 -16.91256) (xy 452.054976 -16.90853) (xy 452.139577 -16.91256) (xy 452.223412 -16.924613)
			(xy 452.305721 -16.944581) (xy 452.38576 -16.972283) (xy 452.462803 -17.007467) (xy 452.536153 -17.049816)
			(xy 452.605145 -17.098945) (xy 452.669155 -17.15441) (xy 452.727603 -17.215708) (xy 452.779959 -17.282284)
			(xy 452.825749 -17.353536) (xy 452.86456 -17.428817) (xy 452.896039 -17.507447) (xy 452.9199 -17.588714)
			(xy 452.935929 -17.67188) (xy 452.94398 -17.756194) (xy 452.944484 -17.798542) (xy 452.944484 -17.798796)
			(xy 452.943898 -17.843534) (xy 452.934888 -17.932555) (xy 452.916988 -18.020222) (xy 452.890379 -18.10565)
			(xy 452.873364 -18.14703) (xy 452.869775 -18.156614) (xy 452.869791 -18.177063) (xy 452.873364 -18.186654)
			(xy 452.890389 -18.228031) (xy 452.917007 -18.313458) (xy 452.934911 -18.401126) (xy 452.943919 -18.490149)
			(xy 452.944484 -18.534888) (xy 452.944484 -18.535142) (xy 452.94398 -18.57749) (xy 452.935929 -18.661804)
			(xy 452.9199 -18.74497) (xy 452.896039 -18.826237) (xy 452.86456 -18.904867) (xy 452.825749 -18.980148)
			(xy 452.779959 -19.0514) (xy 452.727603 -19.117976) (xy 452.669155 -19.179274) (xy 452.605145 -19.234739)
			(xy 452.536153 -19.283868) (xy 452.462803 -19.326217) (xy 452.38576 -19.361401) (xy 452.305721 -19.389103)
			(xy 452.223412 -19.409071) (xy 452.139577 -19.421124) (xy 452.054976 -19.425155) (xy 451.970375 -19.421124)
			(xy 451.88654 -19.409071) (xy 451.804231 -19.389103) (xy 451.724192 -19.361401) (xy 451.647149 -19.326217)
			(xy 451.573799 -19.283868) (xy 451.504807 -19.234739) (xy 451.440797 -19.179274) (xy 451.382349 -19.117976)
			(xy 451.329993 -19.0514) (xy 451.284203 -18.980148) (xy 451.245392 -18.904867) (xy 451.213913 -18.826237)
			(xy 451.190052 -18.74497) (xy 451.174023 -18.661804) (xy 451.165972 -18.57749) (xy 451.165468 -18.535142)
			(xy 443.213248 -18.535142) (xy 443.215823 -18.541788) (xy 443.238325 -18.620878) (xy 443.253434 -18.701708)
			(xy 443.261021 -18.783587) (xy 443.261496 -18.824702) (xy 443.261095 -18.862992) (xy 443.254486 -18.939286)
			(xy 443.241336 -19.014729) (xy 443.221741 -19.088759) (xy 443.209172 -19.12493) (xy 443.206519 -19.133366)
			(xy 443.20652 -19.151037) (xy 443.209172 -19.159474) (xy 443.221718 -19.195651) (xy 443.24129 -19.269684)
			(xy 443.254437 -19.345124) (xy 443.261061 -19.421414) (xy 443.261496 -19.459702) (xy 443.260982 -19.503497)
			(xy 443.252361 -19.590663) (xy 443.235212 -19.676559) (xy 443.209701 -19.760353) (xy 443.176076 -19.841233)
			(xy 443.155832 -19.880072) (xy 443.15041 -19.891537) (xy 443.150411 -19.916866) (xy 443.155832 -19.928332)
			(xy 443.176073 -19.967172) (xy 443.209679 -20.048057) (xy 443.235179 -20.131851) (xy 443.252328 -20.217745)
			(xy 443.260958 -20.304908) (xy 443.261496 -20.348702) (xy 443.261095 -20.386992) (xy 443.254486 -20.463286)
			(xy 443.241336 -20.538729) (xy 443.221741 -20.612759) (xy 443.209172 -20.64893) (xy 443.206519 -20.657366)
			(xy 443.20652 -20.675037) (xy 443.209172 -20.683474) (xy 443.221718 -20.719651) (xy 443.24129 -20.793684)
			(xy 443.254437 -20.869124) (xy 443.261061 -20.945414) (xy 443.261496 -20.983702) (xy 443.260989 -21.024815)
			(xy 443.253402 -21.106691) (xy 443.238293 -21.187518) (xy 443.215791 -21.266605) (xy 443.186088 -21.343279)
			(xy 443.149437 -21.416886) (xy 443.106152 -21.486797) (xy 443.0566 -21.552416) (xy 443.001205 -21.613183)
			(xy 442.94044 -21.66858) (xy 442.874823 -21.718133) (xy 442.804914 -21.761422) (xy 442.731309 -21.798075)
			(xy 442.654636 -21.827781) (xy 442.575549 -21.850286) (xy 442.494723 -21.865398) (xy 442.412847 -21.872988)
			(xy 442.371734 -21.873464) (xy 442.330778 -21.872996) (xy 442.249213 -21.865468) (xy 442.168686 -21.850472)
			(xy 442.089879 -21.828136) (xy 442.013459 -21.798648) (xy 441.940074 -21.762259) (xy 441.870346 -21.719277)
			(xy 441.804865 -21.670066) (xy 441.744186 -21.615042) (xy 441.71616 -21.585174) (xy 441.709037 -21.578124)
			(xy 441.690882 -21.569676) (xy 441.670879 -21.568774) (xy 441.661296 -21.571712) (xy 441.624502 -21.584749)
			(xy 441.549137 -21.605106) (xy 441.472276 -21.618771) (xy 441.394513 -21.625637) (xy 441.35548 -21.626068)
			(xy 441.354718 -21.626068) (xy 441.313612 -21.62557) (xy 441.23175 -21.617988) (xy 441.150936 -21.602885)
			(xy 441.07186 -21.580392) (xy 440.995197 -21.5507) (xy 440.9216 -21.514062) (xy 440.851696 -21.470791)
			(xy 440.786082 -21.421255) (xy 440.725318 -21.365878) (xy 440.669922 -21.305132) (xy 440.620366 -21.239533)
			(xy 440.577073 -21.169643) (xy 440.540412 -21.096058) (xy 440.510696 -21.019403) (xy 440.488178 -20.940335)
			(xy 440.473051 -20.859526) (xy 440.465443 -20.777666) (xy 440.464956 -20.73656) (xy 370.485037 -20.73656)
			(xy 370.461858 -20.800254) (xy 370.425114 -20.879065) (xy 370.381641 -20.954375) (xy 370.331772 -21.02561)
			(xy 370.275884 -21.092228) (xy 370.214404 -21.153723) (xy 370.147799 -21.209627) (xy 370.076576 -21.259513)
			(xy 370.001276 -21.303004) (xy 369.922473 -21.339767) (xy 369.840767 -21.369523) (xy 369.756778 -21.392046)
			(xy 369.671146 -21.407165) (xy 369.584522 -21.414763) (xy 369.541044 -21.415248) (xy 369.515644 -21.415248)
			(xy 369.470345 -21.414745) (xy 369.38011 -21.406627) (xy 369.290966 -21.390454) (xy 369.203632 -21.366354)
			(xy 369.118809 -21.334523) (xy 369.037181 -21.295216) (xy 368.959405 -21.24875) (xy 368.886107 -21.195499)
			(xy 368.817878 -21.135892) (xy 368.755267 -21.070409) (xy 368.698779 -20.999577) (xy 368.648867 -20.923967)
			(xy 368.605934 -20.844186) (xy 368.570325 -20.760878) (xy 368.542328 -20.674714) (xy 368.522167 -20.586387)
			(xy 368.510005 -20.496608) (xy 368.50594 -20.4061) (xy 259.309108 -20.4061) (xy 259.309108 -23.189438)
			(xy 388.04596 -23.189438) (xy 388.046227 -23.181562) (xy 388.051024 -23.166558) (xy 388.055358 -23.159974)
			(xy 389.310626 -21.403564) (xy 389.318228 -21.394044) (xy 389.339863 -21.382914) (xy 389.352028 -21.382228)
			(xy 389.359903 -21.382515) (xy 389.374906 -21.387299) (xy 389.381492 -21.391626) (xy 389.975344 -21.81606)
			(xy 389.984836 -21.823691) (xy 389.995981 -21.845304) (xy 389.99668 -21.857462) (xy 389.996406 -21.865338)
			(xy 389.991613 -21.880341) (xy 389.987282 -21.886926) (xy 388.732014 -23.643336) (xy 390.467088 -23.643336)
			(xy 390.467088 -23.643082) (xy 390.467414 -23.635127) (xy 390.472332 -23.619994) (xy 390.47674 -23.613364)
			(xy 391.748264 -21.868384) (xy 391.75591 -21.859072) (xy 391.77738 -21.848206) (xy 391.789412 -21.847556)
			(xy 391.789666 -21.847556) (xy 391.797618 -21.84791) (xy 391.812751 -21.85281) (xy 391.819384 -21.857208)
			(xy 392.409172 -22.286976) (xy 392.418499 -22.294606) (xy 392.429355 -22.316089) (xy 392.43 -22.328124)
			(xy 392.43 -22.328378) (xy 392.429659 -22.336331) (xy 392.424751 -22.351465) (xy 392.420348 -22.358096)
			(xy 392.298933 -22.52472) (xy 394.044678 -22.52472) (xy 394.044969 -22.516612) (xy 394.050018 -22.501201)
			(xy 394.054584 -22.494494) (xy 395.341856 -20.761198) (xy 395.349487 -20.751994) (xy 395.370811 -20.741254)
			(xy 395.38275 -20.740624) (xy 395.390856 -20.740938) (xy 395.406267 -20.745972) (xy 395.412976 -20.75053)
			(xy 395.999208 -21.185886) (xy 396.008427 -21.193502) (xy 396.019158 -21.214838) (xy 396.019782 -21.22678)
			(xy 396.01948 -21.234887) (xy 396.014437 -21.250297) (xy 396.009876 -21.257006) (xy 394.973116 -22.65299)
			(xy 399.471134 -22.65299) (xy 399.471442 -22.644619) (xy 399.476892 -22.628789) (xy 399.481802 -22.622002)
			(xy 400.7993 -20.911566) (xy 400.806844 -20.902651) (xy 400.827767 -20.892334) (xy 400.839432 -20.891754)
			(xy 400.847804 -20.892048) (xy 400.863635 -20.897507) (xy 400.87042 -20.902422) (xy 401.448778 -21.347938)
			(xy 401.457672 -21.355502) (xy 401.467999 -21.37641) (xy 401.46859 -21.38807) (xy 401.468279 -21.396441)
			(xy 401.462833 -21.412272) (xy 401.457922 -21.419058) (xy 400.140424 -23.129494) (xy 400.13288 -23.138408)
			(xy 400.111956 -23.148723) (xy 400.100292 -23.149306) (xy 400.090285 -23.148818) (xy 400.071794 -23.141157)
			(xy 400.057641 -23.127004) (xy 400.049981 -23.108513) (xy 400.049492 -23.098506) (xy 400.049796 -23.090134)
			(xy 400.055247 -23.074304) (xy 400.06016 -23.067518) (xy 401.315682 -21.437346) (xy 401.321473 -21.429168)
			(xy 401.32665 -21.409823) (xy 401.324019 -21.389971) (xy 401.313983 -21.372642) (xy 401.306284 -21.366226)
			(xy 401.09775 -21.205444) (xy 401.097496 -21.205444) (xy 400.888708 -21.044662) (xy 400.880495 -21.038926)
			(xy 400.861167 -21.03373) (xy 400.841324 -21.036343) (xy 400.824001 -21.046366) (xy 400.817588 -21.05406)
			(xy 399.562066 -22.683978) (xy 399.554501 -22.69287) (xy 399.533593 -22.703198) (xy 399.521934 -22.70379)
			(xy 399.511914 -22.703352) (xy 399.493396 -22.695692) (xy 399.479222 -22.681525) (xy 399.471552 -22.66301)
			(xy 399.471134 -22.65299) (xy 394.973116 -22.65299) (xy 394.722604 -22.990302) (xy 394.714991 -22.999525)
			(xy 394.693653 -23.010254) (xy 394.68171 -23.010876) (xy 394.671686 -23.010472) (xy 394.653165 -23.002801)
			(xy 394.638991 -22.988623) (xy 394.631325 -22.9701) (xy 394.63091 -22.960076) (xy 394.631176 -22.951965)
			(xy 394.636242 -22.936554) (xy 394.640816 -22.92985) (xy 395.867382 -21.278088) (xy 395.873008 -21.269792)
			(xy 395.877882 -21.250364) (xy 395.874966 -21.230548) (xy 395.864704 -21.213346) (xy 395.856968 -21.206968)
			(xy 395.64564 -21.049996) (xy 395.645386 -21.049742) (xy 395.434058 -20.89277) (xy 395.425686 -20.887253)
			(xy 395.406257 -20.882413) (xy 395.386454 -20.885373) (xy 395.369288 -20.895683) (xy 395.362938 -20.903438)
			(xy 394.136372 -22.554946) (xy 394.128736 -22.564145) (xy 394.107415 -22.574885) (xy 394.095478 -22.57552)
			(xy 394.085471 -22.575031) (xy 394.066983 -22.567368) (xy 394.052831 -22.553215) (xy 394.045169 -22.534727)
			(xy 394.044678 -22.52472) (xy 392.298933 -22.52472) (xy 391.148824 -24.103076) (xy 391.141195 -24.112404)
			(xy 391.119711 -24.123259) (xy 391.107676 -24.123904) (xy 391.097667 -24.123432) (xy 391.079176 -24.115765)
			(xy 391.065024 -24.101608) (xy 391.057364 -24.083113) (xy 391.056876 -24.073104) (xy 391.056876 -24.07285)
			(xy 391.05719 -24.064894) (xy 391.062117 -24.049761) (xy 391.066528 -24.043132) (xy 392.290808 -22.363176)
			(xy 392.284458 -22.321774) (xy 392.267186 -22.309328) (xy 391.824464 -21.986748) (xy 391.783062 -21.993098)
			(xy 391.770616 -22.01037) (xy 390.559036 -23.673308) (xy 390.551388 -23.682619) (xy 390.529919 -23.693486)
			(xy 390.517888 -23.694136) (xy 390.507884 -23.693622) (xy 390.489399 -23.685966) (xy 390.475248 -23.671821)
			(xy 390.467582 -23.65334) (xy 390.467088 -23.643336) (xy 388.732014 -23.643336) (xy 388.724394 -23.652838)
			(xy 388.702773 -23.663978) (xy 388.690612 -23.664672) (xy 388.680588 -23.66427) (xy 388.662066 -23.656599)
			(xy 388.647892 -23.642421) (xy 388.640227 -23.623896) (xy 388.639812 -23.613872) (xy 388.640101 -23.605998)
			(xy 388.644885 -23.590994) (xy 388.64921 -23.584408) (xy 389.845296 -21.910548) (xy 389.85074 -21.902143)
			(xy 389.855264 -21.882654) (xy 389.852003 -21.862914) (xy 389.841451 -21.845916) (xy 389.833612 -21.839682)
			(xy 389.61949 -21.68652) (xy 389.619236 -21.68652) (xy 389.405114 -21.533358) (xy 389.396639 -21.528017)
			(xy 389.377145 -21.523527) (xy 389.357417 -21.526835) (xy 389.340454 -21.537437) (xy 389.334248 -21.545296)
			(xy 388.138162 -23.218902) (xy 388.130512 -23.228376) (xy 388.108914 -23.239532) (xy 388.09676 -23.240238)
			(xy 388.086754 -23.239746) (xy 388.068269 -23.23208) (xy 388.054119 -23.217929) (xy 388.046454 -23.199444)
			(xy 388.04596 -23.189438) (xy 259.309108 -23.189438) (xy 259.309108 -24.452326) (xy 395.269212 -24.452326)
			(xy 395.269212 -24.452072) (xy 395.269506 -24.443877) (xy 395.274698 -24.428331) (xy 395.279372 -24.421592)
			(xy 396.581122 -22.699218) (xy 396.588721 -22.690232) (xy 396.609758 -22.679757) (xy 396.621508 -22.679152)
			(xy 396.621762 -22.679152) (xy 396.622016 -22.679152) (xy 396.630209 -22.679463) (xy 396.645755 -22.684645)
			(xy 396.652496 -22.689312) (xy 397.234918 -23.129494) (xy 397.243943 -23.137054) (xy 397.254395 -23.158121)
			(xy 397.254984 -23.16988) (xy 397.254984 -23.170134) (xy 397.254984 -23.170388) (xy 397.254672 -23.178581)
			(xy 397.249492 -23.194128) (xy 397.244824 -23.200868) (xy 396.259825 -24.504142) (xy 400.780758 -24.504142)
			(xy 400.781109 -24.495689) (xy 400.786684 -24.479727) (xy 400.79168 -24.4729) (xy 402.123656 -22.773894)
			(xy 402.13124 -22.765155) (xy 402.151982 -22.75496) (xy 402.163534 -22.754336) (xy 402.171985 -22.754702)
			(xy 402.187947 -22.760267) (xy 402.194776 -22.765258) (xy 402.39731 -22.924008) (xy 404.777194 -22.924008)
			(xy 404.777553 -22.915409) (xy 404.783259 -22.899182) (xy 404.78837 -22.892258) (xy 406.134316 -21.204174)
			(xy 406.141933 -21.195642) (xy 406.16252 -21.18575) (xy 406.17394 -21.185124) (xy 406.182542 -21.185455)
			(xy 406.198769 -21.191179) (xy 406.20569 -21.1963) (xy 406.776428 -21.651468) (xy 406.784938 -21.659105)
			(xy 406.794842 -21.679677) (xy 406.795478 -21.691092) (xy 406.795124 -21.699692) (xy 406.789415 -21.715919)
			(xy 406.784302 -21.722842) (xy 405.438356 -23.410926) (xy 405.430818 -23.419554) (xy 405.410179 -23.42946)
			(xy 405.398732 -23.429976) (xy 405.38871 -23.429554) (xy 405.370189 -23.42189) (xy 405.356015 -23.407718)
			(xy 405.348348 -23.389198) (xy 405.347932 -23.379176) (xy 405.34827 -23.370574) (xy 405.353989 -23.354348)
			(xy 405.359108 -23.347426) (xy 406.641554 -21.738844) (xy 406.647356 -21.730683) (xy 406.652864 -21.71146)
			(xy 406.65061 -21.69159) (xy 406.640937 -21.674088) (xy 406.633426 -21.66747) (xy 406.427686 -21.503386)
			(xy 406.427686 -21.503132) (xy 406.221692 -21.339048) (xy 406.213567 -21.333191) (xy 406.194325 -21.327693)
			(xy 406.174443 -21.329963) (xy 406.156936 -21.339656) (xy 406.150318 -21.347176) (xy 404.867618 -22.955758)
			(xy 404.859992 -22.964279) (xy 404.839412 -22.974176) (xy 404.827994 -22.974808) (xy 404.817987 -22.974317)
			(xy 404.799497 -22.966657) (xy 404.785344 -22.952505) (xy 404.777684 -22.934015) (xy 404.777194 -22.924008)
			(xy 402.39731 -22.924008) (xy 402.769324 -23.2156) (xy 402.778086 -23.223162) (xy 402.788268 -23.243921)
			(xy 402.788882 -23.255478) (xy 402.788533 -23.263931) (xy 402.782956 -23.279893) (xy 402.77796 -23.28672)
			(xy 401.445984 -24.985726) (xy 401.438429 -24.994495) (xy 401.417665 -25.004674) (xy 401.406106 -25.005284)
			(xy 401.396083 -25.004875) (xy 401.377563 -24.997204) (xy 401.36339 -24.983028) (xy 401.355723 -24.964507)
			(xy 401.355306 -24.954484) (xy 401.355641 -24.94603) (xy 401.361228 -24.930068) (xy 401.366228 -24.923242)
			(xy 402.635466 -23.303992) (xy 402.641221 -23.295836) (xy 402.646533 -23.276613) (xy 402.644125 -23.256816)
			(xy 402.634359 -23.239427) (xy 402.62683 -23.232872) (xy 402.212048 -22.907752) (xy 402.203845 -22.902076)
			(xy 402.184647 -22.896763) (xy 402.164871 -22.89915) (xy 402.147489 -22.908879) (xy 402.140928 -22.916388)
			(xy 400.871436 -24.535384) (xy 400.863869 -24.544139) (xy 400.843113 -24.554323) (xy 400.831558 -24.554942)
			(xy 400.821553 -24.554447) (xy 400.803068 -24.546782) (xy 400.788918 -24.532632) (xy 400.781253 -24.514147)
			(xy 400.780758 -24.504142) (xy 396.259825 -24.504142) (xy 395.943074 -24.923242) (xy 395.935488 -24.93224)
			(xy 395.914441 -24.942706) (xy 395.902688 -24.943308) (xy 395.902434 -24.943308) (xy 395.892416 -24.942853)
			(xy 395.873901 -24.935195) (xy 395.859728 -24.921034) (xy 395.852056 -24.902526) (xy 395.851634 -24.892508)
			(xy 395.851634 -24.892254) (xy 395.851917 -24.884058) (xy 395.857117 -24.868512) (xy 395.861794 -24.861774)
			(xy 397.10233 -23.22068) (xy 397.115284 -23.203662) (xy 397.109442 -23.16226) (xy 396.672308 -22.831806)
			(xy 396.65529 -22.818852) (xy 396.613888 -22.824694) (xy 395.360652 -24.48306) (xy 395.353061 -24.492054)
			(xy 395.332018 -24.502525) (xy 395.320266 -24.503126) (xy 395.320012 -24.503126) (xy 395.310008 -24.502603)
			(xy 395.291522 -24.494952) (xy 395.277369 -24.48081) (xy 395.269705 -24.462329) (xy 395.269212 -24.452326)
			(xy 259.309108 -24.452326) (xy 259.309108 -25.128728) (xy 405.747982 -25.128728) (xy 405.748326 -25.120038)
			(xy 405.754182 -25.103674) (xy 405.759412 -25.096724) (xy 407.119074 -23.419562) (xy 407.126681 -23.41115)
			(xy 407.14712 -23.401389) (xy 407.158444 -23.400766) (xy 407.167135 -23.401105) (xy 407.1835 -23.406963)
			(xy 407.190448 -23.412196) (xy 407.192956 -23.414228) (xy 409.889706 -23.414228) (xy 409.890079 -23.405452)
			(xy 409.896056 -23.388949) (xy 409.90139 -23.38197) (xy 411.274006 -21.715476) (xy 411.281567 -21.707142)
			(xy 411.301883 -21.697527) (xy 411.313122 -21.696934) (xy 411.321899 -21.697298) (xy 411.3384 -21.703283)
			(xy 411.34538 -21.708618) (xy 411.908752 -22.172676) (xy 411.917061 -22.180261) (xy 411.926693 -22.200559)
			(xy 411.927294 -22.211792) (xy 411.926931 -22.220569) (xy 411.920947 -22.237072) (xy 411.91561 -22.24405)
			(xy 411.653263 -22.562566) (xy 419.182042 -22.562566) (xy 419.182412 -22.553463) (xy 419.188802 -22.536412)
			(xy 419.194488 -22.529292) (xy 420.607236 -20.89658) (xy 420.614801 -20.888678) (xy 420.634666 -20.879582)
			(xy 420.64559 -20.879054) (xy 420.654691 -20.879443) (xy 420.671742 -20.88582) (xy 420.678864 -20.8915)
			(xy 421.23106 -21.36902) (xy 421.239006 -21.376545) (xy 421.248076 -21.396441) (xy 421.248586 -21.407374)
			(xy 421.248181 -21.416474) (xy 421.241814 -21.433524) (xy 421.23614 -21.440648) (xy 420.086689 -22.769068)
			(xy 424.560238 -22.769068) (xy 424.560645 -22.759789) (xy 424.567295 -22.742463) (xy 424.573192 -22.735286)
			(xy 426.009308 -21.123402) (xy 426.01682 -21.115704) (xy 426.036411 -21.106881) (xy 426.047154 -21.106384)
			(xy 426.056433 -21.106792) (xy 426.073758 -21.113443) (xy 426.080936 -21.119338) (xy 426.62602 -21.604986)
			(xy 426.633756 -21.612464) (xy 426.642556 -21.632081) (xy 426.643038 -21.642832) (xy 426.642637 -21.652112)
			(xy 426.635983 -21.669439) (xy 426.630084 -21.676614) (xy 425.193968 -23.288498) (xy 425.186466 -23.296207)
			(xy 425.166867 -23.305024) (xy 425.156122 -23.305516) (xy 425.146104 -23.305063) (xy 425.127591 -23.297403)
			(xy 425.113418 -23.283241) (xy 425.105745 -23.264734) (xy 425.105322 -23.254716) (xy 425.105756 -23.24544)
			(xy 425.112388 -23.228113) (xy 425.118276 -23.220934) (xy 426.486828 -21.684742) (xy 426.493192 -21.676995)
			(xy 426.499745 -21.658062) (xy 426.498533 -21.638063) (xy 426.489742 -21.620059) (xy 426.48251 -21.613114)
			(xy 426.285914 -21.437854) (xy 426.089064 -21.262594) (xy 426.081336 -21.256217) (xy 426.062432 -21.249615)
			(xy 426.042441 -21.250755) (xy 426.024411 -21.259463) (xy 426.017436 -21.266658) (xy 424.648884 -22.80285)
			(xy 424.641383 -22.810559) (xy 424.621783 -22.819374) (xy 424.611038 -22.819868) (xy 424.601015 -22.819448)
			(xy 424.582493 -22.811785) (xy 424.568318 -22.797612) (xy 424.560653 -22.779091) (xy 424.560238 -22.769068)
			(xy 420.086689 -22.769068) (xy 419.823392 -23.07336) (xy 419.815862 -23.0813) (xy 419.79597 -23.090373)
			(xy 419.785038 -23.090886) (xy 419.775017 -23.090449) (xy 419.756499 -23.082789) (xy 419.742325 -23.068621)
			(xy 419.734656 -23.050106) (xy 419.734238 -23.040086) (xy 419.734618 -23.030984) (xy 419.741002 -23.013933)
			(xy 419.746684 -23.006812) (xy 421.092884 -21.450808) (xy 421.099065 -21.442927) (xy 421.105307 -21.423913)
			(xy 421.103812 -21.403957) (xy 421.094807 -21.386085) (xy 421.08755 -21.37918) (xy 420.888414 -21.206968)
			(xy 420.689024 -21.034756) (xy 420.681148 -21.028559) (xy 420.662161 -21.02221) (xy 420.64219 -21.023613)
			(xy 420.624276 -21.032553) (xy 420.617396 -21.039836) (xy 419.271196 -22.59584) (xy 419.263662 -22.603776)
			(xy 419.243773 -22.612852) (xy 419.232842 -22.613366) (xy 419.222819 -22.612945) (xy 419.204297 -22.605283)
			(xy 419.190122 -22.59111) (xy 419.182456 -22.572589) (xy 419.182042 -22.562566) (xy 411.653263 -22.562566)
			(xy 410.542994 -23.910544) (xy 410.53542 -23.918865) (xy 410.515114 -23.92849) (xy 410.503878 -23.929086)
			(xy 410.493867 -23.92863) (xy 410.475372 -23.92096) (xy 410.461219 -23.906798) (xy 410.453563 -23.888297)
			(xy 410.453078 -23.878286) (xy 410.453436 -23.869509) (xy 410.459424 -23.853006) (xy 410.464762 -23.846028)
			(xy 411.772608 -22.257766) (xy 411.778615 -22.249749) (xy 411.784427 -22.230597) (xy 411.782449 -22.210681)
			(xy 411.772982 -22.193047) (xy 411.765496 -22.186392) (xy 411.56255 -22.019006) (xy 411.562296 -22.019006)
			(xy 411.359096 -21.85162) (xy 411.351096 -21.845632) (xy 411.331988 -21.839836) (xy 411.312113 -21.841756)
			(xy 411.294468 -21.851102) (xy 411.287722 -21.858478) (xy 409.979622 -23.446486) (xy 409.972043 -23.454801)
			(xy 409.951741 -23.464428) (xy 409.940506 -23.465028) (xy 409.930502 -23.464508) (xy 409.912016 -23.456855)
			(xy 409.897864 -23.442713) (xy 409.890199 -23.424231) (xy 409.889706 -23.414228) (xy 407.192956 -23.414228)
			(xy 407.75763 -23.871682) (xy 407.766045 -23.879287) (xy 407.775804 -23.899727) (xy 407.776426 -23.911052)
			(xy 407.776071 -23.919741) (xy 407.770222 -23.936105) (xy 407.764996 -23.943056) (xy 407.336279 -24.471884)
			(xy 412.050992 -24.471884) (xy 412.051404 -24.462967) (xy 412.057505 -24.446206) (xy 412.06293 -24.439118)
			(xy 413.451294 -22.785578) (xy 413.4589 -22.777463) (xy 413.479049 -22.768108) (xy 413.490156 -22.767544)
			(xy 413.499076 -22.767927) (xy 413.515837 -22.774046) (xy 413.522922 -22.779482) (xy 414.081722 -23.248874)
			(xy 414.089828 -23.256488) (xy 414.099188 -23.276631) (xy 414.099756 -23.287736) (xy 414.099364 -23.296656)
			(xy 414.093251 -23.313417) (xy 414.087818 -23.320502) (xy 413.141555 -24.4475) (xy 420.291006 -24.4475)
			(xy 420.291402 -24.438308) (xy 420.297908 -24.421115) (xy 420.303706 -24.413972) (xy 421.728392 -22.791674)
			(xy 421.735898 -22.783839) (xy 421.755652 -22.774906) (xy 421.766492 -22.774402) (xy 421.775684 -22.774803)
			(xy 421.792876 -22.781306) (xy 421.80002 -22.787102) (xy 422.348406 -23.26894) (xy 422.356215 -23.276469)
			(xy 422.365164 -23.296205) (xy 422.365678 -23.30704) (xy 422.365282 -23.316232) (xy 422.358774 -23.333423)
			(xy 422.352978 -23.340568) (xy 421.067259 -24.804624) (xy 425.482512 -24.804624) (xy 425.482961 -24.795261)
			(xy 425.489732 -24.7778) (xy 425.49572 -24.770588) (xy 426.942758 -23.168356) (xy 426.950214 -23.160725)
			(xy 426.96969 -23.152055) (xy 426.98035 -23.151592) (xy 426.989711 -23.152058) (xy 427.007172 -23.158818)
			(xy 427.014386 -23.1648) (xy 427.556168 -23.654004) (xy 427.563779 -23.661477) (xy 427.57246 -23.68094)
			(xy 427.572628 -23.684738) (xy 428.88408 -23.684738) (xy 428.884479 -23.675309) (xy 428.891268 -23.657717)
			(xy 428.897288 -23.650448) (xy 430.3522 -22.055328) (xy 430.359766 -22.047877) (xy 430.379187 -22.03935)
			(xy 430.389792 -22.038818) (xy 430.399215 -22.039266) (xy 430.416807 -22.046023) (xy 430.424082 -22.052026)
			(xy 430.963578 -22.54377) (xy 430.971016 -22.551346) (xy 430.979551 -22.570759) (xy 430.980088 -22.581362)
			(xy 430.979673 -22.590789) (xy 430.972893 -22.60838) (xy 430.96688 -22.615652) (xy 429.511968 -24.210772)
			(xy 429.504414 -24.218237) (xy 429.484984 -24.226756) (xy 429.474376 -24.227282) (xy 429.464365 -24.226831)
			(xy 429.445869 -24.21916) (xy 429.431716 -24.204996) (xy 429.42406 -24.186494) (xy 429.423576 -24.176482)
			(xy 429.423998 -24.167056) (xy 429.430771 -24.149463) (xy 429.436784 -24.142192) (xy 430.823116 -22.622256)
			(xy 430.83734 -22.606762) (xy 430.835562 -22.564598) (xy 430.430686 -22.195536) (xy 430.415192 -22.181312)
			(xy 430.373028 -22.18309) (xy 428.972472 -23.719028) (xy 428.964911 -23.726485) (xy 428.945487 -23.73501)
			(xy 428.93488 -23.735538) (xy 428.924876 -23.735029) (xy 428.906391 -23.72737) (xy 428.89224 -23.713224)
			(xy 428.884574 -23.694742) (xy 428.88408 -23.684738) (xy 427.572628 -23.684738) (xy 427.572932 -23.691596)
			(xy 427.572483 -23.700959) (xy 427.565711 -23.718419) (xy 427.559724 -23.725632) (xy 426.112686 -25.327864)
			(xy 426.105216 -25.335478) (xy 426.08575 -25.344157) (xy 426.075094 -25.344628) (xy 426.065089 -25.344117)
			(xy 426.046603 -25.336461) (xy 426.032451 -25.322316) (xy 426.024787 -25.303832) (xy 426.024294 -25.293828)
			(xy 426.024749 -25.284465) (xy 426.031517 -25.267005) (xy 426.037502 -25.259792) (xy 427.416214 -23.732998)
			(xy 427.422515 -23.725197) (xy 427.429241 -23.706336) (xy 427.428264 -23.686335) (xy 427.419731 -23.668219)
			(xy 427.412658 -23.661116) (xy 427.021498 -23.308056) (xy 427.0138 -23.301638) (xy 426.99492 -23.294949)
			(xy 426.97492 -23.296019) (xy 426.956861 -23.304683) (xy 426.94987 -23.311866) (xy 425.570904 -24.83866)
			(xy 425.563427 -24.846266) (xy 425.543967 -24.854949) (xy 425.533312 -24.855424) (xy 425.523308 -24.854903)
			(xy 425.504821 -24.847252) (xy 425.490669 -24.833109) (xy 425.483004 -24.814628) (xy 425.482512 -24.804624)
			(xy 421.067259 -24.804624) (xy 420.928292 -24.962866) (xy 420.920745 -24.970654) (xy 420.901023 -24.979616)
			(xy 420.890192 -24.980138) (xy 420.880189 -24.979619) (xy 420.861704 -24.971964) (xy 420.847553 -24.957821)
			(xy 420.839887 -24.939341) (xy 420.839392 -24.929338) (xy 420.839761 -24.920143) (xy 420.846286 -24.902951)
			(xy 420.852092 -24.89581) (xy 422.209722 -23.349712) (xy 422.215974 -23.341894) (xy 422.222428 -23.322965)
			(xy 422.22115 -23.303007) (xy 422.212334 -23.285056) (xy 422.20515 -23.278084) (xy 422.007284 -23.104348)
			(xy 422.00703 -23.104094) (xy 421.809164 -22.930358) (xy 421.801306 -22.924164) (xy 421.782396 -22.917703)
			(xy 421.762454 -22.918965) (xy 421.744509 -22.927758) (xy 421.737536 -22.93493) (xy 420.379906 -24.481028)
			(xy 420.372401 -24.488864) (xy 420.352646 -24.497797) (xy 420.341806 -24.4983) (xy 420.331785 -24.497876)
			(xy 420.313268 -24.490208) (xy 420.299096 -24.476037) (xy 420.291426 -24.457521) (xy 420.291006 -24.4475)
			(xy 413.141555 -24.4475) (xy 412.699454 -24.974042) (xy 412.691873 -24.982183) (xy 412.671705 -24.991523)
			(xy 412.660592 -24.992076) (xy 412.650567 -24.991686) (xy 412.632046 -24.984009) (xy 412.617873 -24.969828)
			(xy 412.610207 -24.951301) (xy 412.609792 -24.941276) (xy 412.610201 -24.932358) (xy 412.616303 -24.915598)
			(xy 412.62173 -24.90851) (xy 413.944562 -23.332948) (xy 413.950662 -23.32499) (xy 413.956726 -23.305897)
			(xy 413.955023 -23.285937) (xy 413.94581 -23.268148) (xy 413.938466 -23.26132) (xy 413.737044 -23.092156)
			(xy 413.73679 -23.091902) (xy 413.535368 -22.922738) (xy 413.52743 -22.916597) (xy 413.508318 -22.910521)
			(xy 413.488335 -22.912221) (xy 413.470525 -22.921439) (xy 413.46374 -22.928834) (xy 412.140654 -24.50465)
			(xy 412.133074 -24.512793) (xy 412.112905 -24.522131) (xy 412.101792 -24.522684) (xy 412.091768 -24.522287)
			(xy 412.073248 -24.514611) (xy 412.059076 -24.500432) (xy 412.051409 -24.481908) (xy 412.050992 -24.471884)
			(xy 407.336279 -24.471884) (xy 406.405334 -25.620218) (xy 406.39772 -25.628623) (xy 406.377287 -25.638388)
			(xy 406.365964 -25.639014) (xy 406.355956 -25.638542) (xy 406.337466 -25.630873) (xy 406.323315 -25.616716)
			(xy 406.315654 -25.598222) (xy 406.315164 -25.588214) (xy 406.315531 -25.579526) (xy 406.32137 -25.563161)
			(xy 406.326594 -25.55621) (xy 407.622248 -23.957788) (xy 407.628232 -23.949742) (xy 407.63391 -23.930526)
			(xy 407.631782 -23.910602) (xy 407.622173 -23.893019) (xy 407.614628 -23.886414) (xy 407.20518 -23.554944)
			(xy 407.197139 -23.548953) (xy 407.177921 -23.543278) (xy 407.157996 -23.545408) (xy 407.140412 -23.555019)
			(xy 407.133806 -23.562564) (xy 405.838152 -25.160732) (xy 405.830533 -25.169131) (xy 405.810103 -25.178899)
			(xy 405.798782 -25.179528) (xy 405.788777 -25.179028) (xy 405.77029 -25.171367) (xy 405.756138 -25.157219)
			(xy 405.748474 -25.138733) (xy 405.747982 -25.128728) (xy 259.309108 -25.128728) (xy 259.309108 -26.486358)
			(xy 413.072072 -26.486358) (xy 413.072463 -26.477345) (xy 413.078688 -26.460428) (xy 413.084264 -26.453338)
			(xy 414.485074 -24.810466) (xy 414.492653 -24.802451) (xy 414.512665 -24.793229) (xy 414.523682 -24.792686)
			(xy 414.532698 -24.793055) (xy 414.549615 -24.799294) (xy 414.556702 -24.804878) (xy 415.1122 -25.278334)
			(xy 415.120236 -25.285894) (xy 415.129447 -25.30592) (xy 415.12998 -25.316942) (xy 415.129599 -25.325957)
			(xy 415.123369 -25.342874) (xy 415.117788 -25.349962) (xy 414.578515 -25.982422) (xy 440.239912 -25.982422)
			(xy 440.240419 -25.939461) (xy 440.248702 -25.85394) (xy 440.265193 -25.769616) (xy 440.289738 -25.687275)
			(xy 440.322109 -25.607684) (xy 440.362003 -25.531586) (xy 440.40905 -25.459689) (xy 440.46281 -25.392664)
			(xy 440.522782 -25.331135) (xy 440.588408 -25.275676) (xy 440.659076 -25.226803) (xy 440.69635 -25.205436)
			(xy 440.704332 -25.200469) (xy 440.716316 -25.186006) (xy 440.719718 -25.177242) (xy 440.733823 -25.137039)
			(xy 440.768699 -25.059297) (xy 440.810847 -24.985247) (xy 440.859883 -24.915565) (xy 440.915357 -24.850891)
			(xy 440.97676 -24.791817) (xy 441.043529 -24.738885) (xy 441.115054 -24.692579) (xy 441.190679 -24.653323)
			(xy 441.26971 -24.621478) (xy 441.351424 -24.597336) (xy 441.435072 -24.581116) (xy 441.519887 -24.572969)
			(xy 441.56249 -24.572468) (xy 441.562998 -24.572468) (xy 441.606762 -24.572982) (xy 441.693869 -24.581557)
			(xy 441.77971 -24.598653) (xy 441.863455 -24.624106) (xy 441.944293 -24.657667) (xy 441.983114 -24.677878)
			(xy 441.994467 -24.683205) (xy 442.019513 -24.683205) (xy 442.030866 -24.677878) (xy 442.069745 -24.657673)
			(xy 442.150684 -24.6241) (xy 442.23453 -24.598641) (xy 442.320472 -24.581544) (xy 442.407677 -24.572973)
			(xy 442.45149 -24.572468) (xy 442.495305 -24.572971) (xy 442.582516 -24.581515) (xy 442.668462 -24.5986)
			(xy 442.752311 -24.62406) (xy 442.833246 -24.657648) (xy 442.872114 -24.677878) (xy 442.883467 -24.683205)
			(xy 442.908513 -24.683205) (xy 442.919866 -24.677878) (xy 442.959061 -24.657499) (xy 443.040701 -24.623735)
			(xy 443.125286 -24.598229) (xy 443.211982 -24.581233) (xy 443.255908 -24.576532) (xy 443.266358 -24.575008)
			(xy 443.284755 -24.564681) (xy 443.297434 -24.547819) (xy 443.300358 -24.53767) (xy 443.310609 -24.496358)
			(xy 443.337964 -24.415751) (xy 443.372893 -24.338124) (xy 443.415077 -24.264189) (xy 443.464129 -24.19462)
			(xy 443.519603 -24.130055) (xy 443.580989 -24.071084) (xy 443.647727 -24.018245) (xy 443.719207 -23.972023)
			(xy 443.794775 -23.932839) (xy 443.87374 -23.901052) (xy 443.955381 -23.876952) (xy 444.038949 -23.86076)
			(xy 444.123683 -23.852625) (xy 444.166244 -23.852124) (xy 444.207348 -23.852525) (xy 444.289205 -23.860114)
			(xy 444.370013 -23.875224) (xy 444.449082 -23.897725) (xy 444.525738 -23.927425) (xy 444.599326 -23.964072)
			(xy 444.669219 -24.007352) (xy 444.734821 -24.056897) (xy 444.795571 -24.112283) (xy 444.850952 -24.173038)
			(xy 444.900491 -24.238644) (xy 444.943765 -24.30854) (xy 444.980405 -24.382132) (xy 445.0101 -24.45879)
			(xy 445.032594 -24.537861) (xy 445.047697 -24.61867) (xy 445.055279 -24.700528) (xy 445.055752 -24.741632)
			(xy 445.055238 -24.782654) (xy 445.04768 -24.864348) (xy 445.032631 -24.944999) (xy 445.01022 -25.023921)
			(xy 444.980635 -25.100445) (xy 444.94413 -25.173919) (xy 444.901014 -25.243719) (xy 444.851653 -25.309252)
			(xy 444.796467 -25.369961) (xy 444.735925 -25.425331) (xy 444.670542 -25.47489) (xy 444.600873 -25.518217)
			(xy 444.52751 -25.554945) (xy 444.451076 -25.584761) (xy 444.372222 -25.607412) (xy 444.291617 -25.622705)
			(xy 444.250826 -25.627076) (xy 444.240379 -25.628618) (xy 444.221981 -25.638935) (xy 444.2093 -25.655791)
			(xy 444.206376 -25.665938) (xy 444.196473 -25.705794) (xy 444.170375 -25.783666) (xy 444.137208 -25.8588)
			(xy 444.097254 -25.930555) (xy 444.050854 -25.998321) (xy 443.998403 -26.061519) (xy 443.940348 -26.119612)
			(xy 443.877184 -26.172104) (xy 443.809448 -26.218548) (xy 443.773814 -26.238962) (xy 443.765845 -26.243946)
			(xy 443.753852 -26.258396) (xy 443.750446 -26.267156) (xy 443.736369 -26.307378) (xy 443.701515 -26.385148)
			(xy 443.659384 -26.459228) (xy 443.61036 -26.528939) (xy 443.554893 -26.593641) (xy 443.493492 -26.652741)
			(xy 443.42672 -26.705698) (xy 443.355189 -26.752025) (xy 443.279554 -26.791298) (xy 443.200511 -26.823158)
			(xy 443.118782 -26.847311) (xy 443.035118 -26.863536) (xy 442.950285 -26.871685) (xy 442.907674 -26.872184)
			(xy 442.863879 -26.871639) (xy 442.776715 -26.863025) (xy 442.690819 -26.845883) (xy 442.607025 -26.82038)
			(xy 442.526144 -26.786761) (xy 442.487304 -26.76652) (xy 442.475838 -26.761102) (xy 442.45051 -26.761102)
			(xy 442.439044 -26.76652) (xy 442.400209 -26.786769) (xy 442.319322 -26.820374) (xy 442.235526 -26.845873)
			(xy 442.149632 -26.863019) (xy 442.062468 -26.871647) (xy 442.018674 -26.872184) (xy 441.974879 -26.871639)
			(xy 441.887715 -26.863025) (xy 441.801819 -26.845883) (xy 441.718025 -26.82038) (xy 441.637144 -26.786761)
			(xy 441.598304 -26.76652) (xy 441.586838 -26.761102) (xy 441.56151 -26.761102) (xy 441.550044 -26.76652)
			(xy 441.511209 -26.786769) (xy 441.430322 -26.820374) (xy 441.346526 -26.845873) (xy 441.260632 -26.863019)
			(xy 441.173468 -26.871647) (xy 441.129674 -26.872184) (xy 441.08856 -26.871712) (xy 441.006683 -26.864123)
			(xy 440.925855 -26.849012) (xy 440.846767 -26.826507) (xy 440.770092 -26.796802) (xy 440.696485 -26.760149)
			(xy 440.626574 -26.71686) (xy 440.560955 -26.667306) (xy 440.500188 -26.61191) (xy 440.444791 -26.551142)
			(xy 440.395237 -26.485523) (xy 440.351949 -26.415612) (xy 440.315297 -26.342004) (xy 440.285592 -26.265329)
			(xy 440.263088 -26.186241) (xy 440.247977 -26.105413) (xy 440.240388 -26.023536) (xy 440.239912 -25.982422)
			(xy 414.578515 -25.982422) (xy 413.716978 -26.992834) (xy 413.709418 -27.00087) (xy 413.689392 -27.01008)
			(xy 413.67837 -27.010614) (xy 413.668362 -27.010137) (xy 413.649872 -27.00247) (xy 413.635721 -26.988314)
			(xy 413.62806 -26.969822) (xy 413.62757 -26.959814) (xy 413.62794 -26.950799) (xy 413.634179 -26.933882)
			(xy 413.639762 -26.926794) (xy 414.974532 -25.361138) (xy 414.980643 -25.3532) (xy 414.986841 -25.334175)
			(xy 414.98529 -25.314226) (xy 414.976226 -25.296387) (xy 414.968944 -25.28951) (xy 414.567878 -24.948134)
			(xy 414.560023 -24.941887) (xy 414.540948 -24.935683) (xy 414.520951 -24.937255) (xy 414.50308 -24.946366)
			(xy 414.49625 -24.953722) (xy 413.16148 -26.519378) (xy 413.153926 -26.52742) (xy 413.133895 -26.536625)
			(xy 413.122872 -26.537158) (xy 413.112844 -26.536803) (xy 413.094318 -26.529116) (xy 413.080145 -26.514923)
			(xy 413.072484 -26.496387) (xy 413.072072 -26.486358) (xy 259.309108 -26.486358) (xy 259.309108 -32.117846)
			(xy 455.218281 -32.117846) (xy 455.218281 -31.988706) (xy 455.226231 -31.859811) (xy 455.242101 -31.731651)
			(xy 455.26583 -31.60471) (xy 455.297329 -31.479471) (xy 455.336478 -31.356408) (xy 455.383129 -31.235989)
			(xy 455.437104 -31.11867) (xy 455.498199 -31.004896) (xy 455.566182 -30.895099) (xy 455.640796 -30.789696)
			(xy 455.721757 -30.689086) (xy 455.808757 -30.593651) (xy 455.901468 -30.503752) (xy 455.999538 -30.419731)
			(xy 456.102593 -30.341907) (xy 456.210244 -30.270575) (xy 456.322083 -30.206005) (xy 456.437684 -30.148443)
			(xy 456.556609 -30.098106) (xy 456.678408 -30.055186) (xy 456.802618 -30.019845) (xy 456.928767 -29.992218)
			(xy 457.056379 -29.972409) (xy 457.184968 -29.960493) (xy 457.314046 -29.956517) (xy 457.443124 -29.960493)
			(xy 457.571713 -29.972409) (xy 457.699325 -29.992218) (xy 457.825474 -30.019845) (xy 457.949684 -30.055186)
			(xy 458.071483 -30.098106) (xy 458.190408 -30.148443) (xy 458.306009 -30.206005) (xy 458.417848 -30.270575)
			(xy 458.525499 -30.341907) (xy 458.628554 -30.419731) (xy 458.726624 -30.503752) (xy 458.819335 -30.593651)
			(xy 458.906335 -30.689086) (xy 458.987296 -30.789696) (xy 459.06191 -30.895099) (xy 459.129893 -31.004896)
			(xy 459.190988 -31.11867) (xy 459.244963 -31.235989) (xy 459.291614 -31.356408) (xy 459.330763 -31.479471)
			(xy 459.362262 -31.60471) (xy 459.385991 -31.731651) (xy 459.401861 -31.859811) (xy 459.409811 -31.988706)
			(xy 459.410308 -32.053276) (xy 459.409811 -32.117846) (xy 459.401861 -32.246741) (xy 459.385991 -32.374901)
			(xy 459.362262 -32.501842) (xy 459.330763 -32.627081) (xy 459.291614 -32.750144) (xy 459.244963 -32.870563)
			(xy 459.190988 -32.987882) (xy 459.129893 -33.101656) (xy 459.06191 -33.211453) (xy 458.987296 -33.316856)
			(xy 458.906335 -33.417466) (xy 458.819335 -33.512901) (xy 458.726624 -33.6028) (xy 458.628554 -33.686821)
			(xy 458.525499 -33.764645) (xy 458.417848 -33.835977) (xy 458.307206 -33.899856) (xy 461.798924 -33.899856)
			(xy 461.798924 -32.299656) (xy 461.799422 -32.222373) (xy 461.807378 -32.068013) (xy 461.823271 -31.914267)
			(xy 461.847057 -31.761543) (xy 461.878674 -31.610247) (xy 461.918037 -31.460778) (xy 461.965042 -31.313534)
			(xy 462.019566 -31.168904) (xy 462.081462 -31.027274) (xy 462.150567 -30.889017) (xy 462.226698 -30.754502)
			(xy 462.309652 -30.624083) (xy 462.399211 -30.498108) (xy 462.495135 -30.376911) (xy 462.597172 -30.260812)
			(xy 462.705049 -30.15012) (xy 462.818482 -30.045128) (xy 462.93717 -29.946115) (xy 463.060797 -29.853342)
			(xy 463.189036 -29.767057) (xy 463.321547 -29.687488) (xy 463.457979 -29.614846) (xy 463.597969 -29.549324)
			(xy 463.741146 -29.491095) (xy 463.887131 -29.440314) (xy 464.035537 -29.397115) (xy 464.185969 -29.361613)
			(xy 464.33803 -29.333903) (xy 464.491316 -29.314057) (xy 464.64542 -29.302128) (xy 464.799934 -29.298149)
			(xy 464.954448 -29.302128) (xy 465.108552 -29.314057) (xy 465.261838 -29.333903) (xy 465.413899 -29.361613)
			(xy 465.564331 -29.397115) (xy 465.712737 -29.440314) (xy 465.858722 -29.491095) (xy 466.001899 -29.549324)
			(xy 466.141889 -29.614846) (xy 466.278321 -29.687488) (xy 466.410832 -29.767057) (xy 466.539071 -29.853342)
			(xy 466.662698 -29.946115) (xy 466.781386 -30.045128) (xy 466.894819 -30.15012) (xy 467.002696 -30.260812)
			(xy 467.104733 -30.376911) (xy 467.200657 -30.498108) (xy 467.290216 -30.624083) (xy 467.37317 -30.754502)
			(xy 467.449301 -30.889017) (xy 467.518406 -31.027274) (xy 467.580302 -31.168904) (xy 467.634826 -31.313534)
			(xy 467.681831 -31.460778) (xy 467.721194 -31.610247) (xy 467.752811 -31.761543) (xy 467.776597 -31.914267)
			(xy 467.79249 -32.068013) (xy 467.800446 -32.222373) (xy 467.800944 -32.299656) (xy 467.800944 -33.899856)
			(xy 467.800446 -33.977139) (xy 467.79249 -34.131499) (xy 467.776597 -34.285245) (xy 467.752811 -34.437969)
			(xy 467.721194 -34.589265) (xy 467.681831 -34.738734) (xy 467.634826 -34.885978) (xy 467.580302 -35.030608)
			(xy 467.518406 -35.172238) (xy 467.449301 -35.310495) (xy 467.37317 -35.44501) (xy 467.290216 -35.575429)
			(xy 467.200657 -35.701404) (xy 467.104733 -35.822601) (xy 467.002696 -35.9387) (xy 466.894819 -36.049392)
			(xy 466.781386 -36.154384) (xy 466.662698 -36.253397) (xy 466.539071 -36.34617) (xy 466.410832 -36.432455)
			(xy 466.278321 -36.512024) (xy 466.141889 -36.584666) (xy 466.001899 -36.650188) (xy 465.858722 -36.708417)
			(xy 465.712737 -36.759198) (xy 465.564331 -36.802397) (xy 465.413899 -36.837899) (xy 465.261838 -36.865609)
			(xy 465.108552 -36.885455) (xy 464.954448 -36.897384) (xy 464.799934 -36.901364) (xy 464.64542 -36.897384)
			(xy 464.491316 -36.885455) (xy 464.33803 -36.865609) (xy 464.185969 -36.837899) (xy 464.035537 -36.802397)
			(xy 463.887131 -36.759198) (xy 463.741146 -36.708417) (xy 463.597969 -36.650188) (xy 463.457979 -36.584666)
			(xy 463.321547 -36.512024) (xy 463.189036 -36.432455) (xy 463.060797 -36.34617) (xy 462.93717 -36.253397)
			(xy 462.818482 -36.154384) (xy 462.705049 -36.049392) (xy 462.597172 -35.9387) (xy 462.495135 -35.822601)
			(xy 462.399211 -35.701404) (xy 462.309652 -35.575429) (xy 462.226698 -35.44501) (xy 462.150567 -35.310495)
			(xy 462.081462 -35.172238) (xy 462.019566 -35.030608) (xy 461.965042 -34.885978) (xy 461.918037 -34.738734)
			(xy 461.878674 -34.589265) (xy 461.847057 -34.437969) (xy 461.823271 -34.285245) (xy 461.807378 -34.131499)
			(xy 461.799422 -33.977139) (xy 461.798924 -33.899856) (xy 458.307206 -33.899856) (xy 458.306009 -33.900547)
			(xy 458.190408 -33.958109) (xy 458.071483 -34.008446) (xy 457.949684 -34.051366) (xy 457.825474 -34.086707)
			(xy 457.699325 -34.114334) (xy 457.571713 -34.134143) (xy 457.443124 -34.146059) (xy 457.314046 -34.150036)
			(xy 457.184968 -34.146059) (xy 457.056379 -34.134143) (xy 456.928767 -34.114334) (xy 456.802618 -34.086707)
			(xy 456.678408 -34.051366) (xy 456.556609 -34.008446) (xy 456.437684 -33.958109) (xy 456.322083 -33.900547)
			(xy 456.210244 -33.835977) (xy 456.102593 -33.764645) (xy 455.999538 -33.686821) (xy 455.901468 -33.6028)
			(xy 455.808757 -33.512901) (xy 455.721757 -33.417466) (xy 455.640796 -33.316856) (xy 455.566182 -33.211453)
			(xy 455.498199 -33.101656) (xy 455.437104 -32.987882) (xy 455.383129 -32.870563) (xy 455.336478 -32.750144)
			(xy 455.297329 -32.627081) (xy 455.26583 -32.501842) (xy 455.242101 -32.374901) (xy 455.226231 -32.246741)
			(xy 455.218281 -32.117846) (xy 259.309108 -32.117846) (xy 259.309108 -34.120074) (xy 259.308624 -34.190457)
			(xy 259.300733 -34.331001) (xy 259.284973 -34.470882) (xy 259.261395 -34.609659) (xy 259.230073 -34.746896)
			(xy 259.191105 -34.882161) (xy 259.144614 -35.015028) (xy 259.090747 -35.145079) (xy 259.029671 -35.271905)
			(xy 258.961581 -35.395107) (xy 258.88669 -35.514297) (xy 258.805233 -35.629101) (xy 258.717468 -35.739156)
			(xy 258.62367 -35.844118) (xy 258.524134 -35.943655) (xy 258.419173 -36.037454) (xy 258.309118 -36.12522)
			(xy 258.194315 -36.206678) (xy 258.075126 -36.28157) (xy 257.951924 -36.349661) (xy 257.825099 -36.410738)
			(xy 257.695048 -36.464606) (xy 257.562182 -36.511099) (xy 257.426917 -36.550068) (xy 257.289681 -36.581391)
			(xy 257.150904 -36.60497) (xy 257.011023 -36.620731) (xy 256.870479 -36.628623) (xy 256.800096 -36.629086)
			(xy 225.300032 -36.629086) (xy 225.229649 -36.628602) (xy 225.089105 -36.620711) (xy 224.949224 -36.604952)
			(xy 224.810447 -36.581374) (xy 224.673211 -36.550052) (xy 224.537946 -36.511084) (xy 224.40508 -36.464594)
			(xy 224.275029 -36.410726) (xy 224.148203 -36.349651) (xy 224.025001 -36.28156) (xy 223.905811 -36.206669)
			(xy 223.791008 -36.125213) (xy 223.680953 -36.037447) (xy 223.575992 -35.943648) (xy 223.476456 -35.844112)
			(xy 223.382657 -35.739152) (xy 223.294891 -35.629097) (xy 223.213434 -35.514294) (xy 223.138543 -35.395104)
			(xy 223.070452 -35.271902) (xy 223.009377 -35.145077) (xy 222.955509 -35.015026) (xy 222.909017 -34.882159)
			(xy 222.870049 -34.746895) (xy 222.838727 -34.609659) (xy 222.815149 -34.470882) (xy 222.799389 -34.331001)
			(xy 222.791498 -34.190457) (xy 222.79102 -34.120074) (xy 222.79102 -13.780008) (xy 222.790499 -13.724238)
			(xy 222.782164 -13.613011) (xy 222.765541 -13.502717) (xy 222.740722 -13.393974) (xy 222.707846 -13.287389)
			(xy 222.667097 -13.183559) (xy 222.618703 -13.083065) (xy 222.562935 -12.986469) (xy 222.500103 -12.894309)
			(xy 222.430561 -12.807103) (xy 222.354696 -12.725338) (xy 222.272933 -12.64947) (xy 222.185729 -12.579925)
			(xy 222.093572 -12.517091) (xy 221.996977 -12.461319) (xy 221.896485 -12.412922) (xy 221.792656 -12.37217)
			(xy 221.686073 -12.339291) (xy 221.57733 -12.314468) (xy 221.467037 -12.297841) (xy 221.35581 -12.289503)
			(xy 221.30004 -12.289028) (xy 196.701918 -12.289028) (xy 196.631535 -12.288544) (xy 196.49099 -12.280652)
			(xy 196.35111 -12.264892) (xy 196.212332 -12.241314) (xy 196.075095 -12.209992) (xy 195.939831 -12.171024)
			(xy 195.806964 -12.124532) (xy 195.676913 -12.070665) (xy 195.550086 -12.009589) (xy 195.426884 -11.941499)
			(xy 195.307694 -11.866608) (xy 195.19289 -11.785152) (xy 195.082834 -11.697386) (xy 194.977873 -11.603588)
			(xy 194.878335 -11.504052) (xy 194.784536 -11.399092) (xy 194.696769 -11.289037) (xy 194.615311 -11.174234)
			(xy 194.540418 -11.055045) (xy 194.472326 -10.931844) (xy 194.411249 -10.805018) (xy 194.35738 -10.674968)
			(xy 194.310887 -10.542102) (xy 194.271917 -10.406837) (xy 194.240593 -10.269601) (xy 194.217013 -10.130824)
			(xy 194.201251 -9.990943) (xy 194.193357 -9.850399) (xy 194.192906 -9.780016) (xy 194.192906 -5.839714)
			(xy 194.192489 -5.82969) (xy 194.184822 -5.811168) (xy 194.170649 -5.79699) (xy 194.152129 -5.789315)
			(xy 194.142106 -5.788914) (xy 126.661926 -5.788914) (xy 126.651902 -5.789329) (xy 126.633379 -5.796995)
			(xy 126.619202 -5.811169) (xy 126.611531 -5.82969) (xy 126.611126 -5.839714) (xy 126.611126 -9.780016)
			(xy 126.610632 -9.850398) (xy 126.602738 -9.990941) (xy 126.586977 -10.13082) (xy 126.563397 -10.269595)
			(xy 126.532074 -10.40683) (xy 126.51969 -10.449814) (xy 127.350019 -10.449814) (xy 127.354025 -10.361883)
			(xy 127.366011 -10.27468) (xy 127.385876 -10.188928) (xy 127.413458 -10.105338) (xy 127.448526 -10.024603)
			(xy 127.490791 -9.947391) (xy 127.539902 -9.874342) (xy 127.595452 -9.806062) (xy 127.656981 -9.743116)
			(xy 127.723979 -9.686027) (xy 127.79589 -9.635266) (xy 127.87212 -9.591254) (xy 127.952036 -9.554357)
			(xy 128.034977 -9.52488) (xy 128.120254 -9.503068) (xy 128.207161 -9.4891) (xy 128.294979 -9.483093)
			(xy 128.382978 -9.485097) (xy 128.470431 -9.495094) (xy 128.556613 -9.513003) (xy 128.640809 -9.538675)
			(xy 128.722322 -9.571896) (xy 128.800476 -9.612392) (xy 128.874623 -9.659827) (xy 128.94415 -9.713809)
			(xy 129.008481 -9.773889) (xy 129.067081 -9.83957) (xy 129.119465 -9.910308) (xy 129.165201 -9.985516)
			(xy 129.203907 -10.064572) (xy 129.235265 -10.146819) (xy 129.259013 -10.231578) (xy 129.26619 -10.270552)
			(xy 131.639267 -10.270552) (xy 131.639267 -10.216048) (xy 131.647024 -10.162097) (xy 131.66238 -10.1098)
			(xy 131.685023 -10.060221) (xy 131.714491 -10.014369) (xy 131.750185 -9.973177) (xy 131.791377 -9.937485)
			(xy 131.83723 -9.908018) (xy 131.88681 -9.885377) (xy 131.939107 -9.870022) (xy 131.993058 -9.862267)
			(xy 132.02031 -9.861804) (xy 132.88391 -9.861804) (xy 132.911162 -9.862266) (xy 132.96511 -9.870024)
			(xy 133.017405 -9.885381) (xy 133.066983 -9.908023) (xy 133.112833 -9.937491) (xy 133.154024 -9.973183)
			(xy 133.189715 -10.014375) (xy 133.219181 -10.060226) (xy 133.241823 -10.109804) (xy 133.257178 -10.1621)
			(xy 133.264934 -10.216048) (xy 133.264934 -10.270552) (xy 133.257178 -10.3245) (xy 133.241823 -10.376796)
			(xy 133.219181 -10.426374) (xy 133.189715 -10.472225) (xy 133.154024 -10.513417) (xy 133.112833 -10.549109)
			(xy 133.066983 -10.578577) (xy 133.017405 -10.601219) (xy 132.96511 -10.616576) (xy 132.911162 -10.624334)
			(xy 132.88391 -10.62482) (xy 132.02031 -10.62482) (xy 131.993058 -10.624333) (xy 131.939107 -10.616578)
			(xy 131.88681 -10.601223) (xy 131.83723 -10.578582) (xy 131.791377 -10.549115) (xy 131.750185 -10.513423)
			(xy 131.714491 -10.472231) (xy 131.685023 -10.426379) (xy 131.66238 -10.3768) (xy 131.647024 -10.324503)
			(xy 131.639267 -10.270552) (xy 129.26619 -10.270552) (xy 129.274955 -10.318145) (xy 129.282959 -10.405803)
			(xy 129.28346 -10.449814) (xy 129.282959 -10.493825) (xy 129.274955 -10.581483) (xy 129.259013 -10.66805)
			(xy 129.235265 -10.752809) (xy 129.212257 -10.813156) (xy 169.954611 -10.813156) (xy 169.954611 -10.758644)
			(xy 169.962369 -10.704687) (xy 169.977727 -10.652382) (xy 170.000372 -10.602796) (xy 170.029844 -10.556938)
			(xy 170.065542 -10.51574) (xy 170.106739 -10.480043) (xy 170.152598 -10.450571) (xy 170.202184 -10.427926)
			(xy 170.254488 -10.412568) (xy 170.308446 -10.404811) (xy 170.335702 -10.404348) (xy 171.199302 -10.404348)
			(xy 171.22655 -10.404922) (xy 171.280491 -10.412678) (xy 171.33278 -10.428032) (xy 171.382351 -10.45067)
			(xy 171.428196 -10.480133) (xy 171.469381 -10.515821) (xy 171.505068 -10.557006) (xy 171.534531 -10.602851)
			(xy 171.557169 -10.652422) (xy 171.572522 -10.704711) (xy 171.580278 -10.758652) (xy 171.580278 -10.813148)
			(xy 171.572522 -10.867089) (xy 171.557169 -10.919378) (xy 171.534531 -10.968949) (xy 171.505068 -11.014794)
			(xy 171.469381 -11.055979) (xy 171.428196 -11.091667) (xy 171.382351 -11.12113) (xy 171.33278 -11.143768)
			(xy 171.280491 -11.159122) (xy 171.22655 -11.166878) (xy 171.199302 -11.167364) (xy 170.335702 -11.167364)
			(xy 170.308446 -11.166989) (xy 170.254488 -11.159232) (xy 170.202184 -11.143874) (xy 170.152598 -11.121229)
			(xy 170.106739 -11.091757) (xy 170.065542 -11.05606) (xy 170.029844 -11.014862) (xy 170.000372 -10.969004)
			(xy 169.977727 -10.919418) (xy 169.962369 -10.867113) (xy 169.954611 -10.813156) (xy 129.212257 -10.813156)
			(xy 129.203907 -10.835056) (xy 129.165201 -10.914112) (xy 129.119465 -10.98932) (xy 129.067081 -11.060058)
			(xy 129.008481 -11.125739) (xy 128.94415 -11.185819) (xy 128.874623 -11.239801) (xy 128.800476 -11.287236)
			(xy 128.722322 -11.327732) (xy 128.640809 -11.360953) (xy 128.556613 -11.386625) (xy 128.470431 -11.404534)
			(xy 128.382978 -11.414531) (xy 128.294979 -11.416535) (xy 128.207161 -11.410528) (xy 128.120254 -11.39656)
			(xy 128.034977 -11.374748) (xy 127.952036 -11.345271) (xy 127.87212 -11.308374) (xy 127.79589 -11.264362)
			(xy 127.723979 -11.213601) (xy 127.656981 -11.156512) (xy 127.595452 -11.093566) (xy 127.539902 -11.025286)
			(xy 127.490791 -10.952237) (xy 127.448526 -10.875025) (xy 127.413458 -10.79429) (xy 127.385876 -10.7107)
			(xy 127.366011 -10.624948) (xy 127.354025 -10.537745) (xy 127.350019 -10.449814) (xy 126.51969 -10.449814)
			(xy 126.493105 -10.542092) (xy 126.446613 -10.674957) (xy 126.392744 -10.805006) (xy 126.331668 -10.93183)
			(xy 126.263578 -11.05503) (xy 126.188687 -11.174218) (xy 126.10723 -11.28902) (xy 126.019465 -11.399074)
			(xy 125.925667 -11.504033) (xy 125.826132 -11.603569) (xy 125.721172 -11.697366) (xy 125.611118 -11.785131)
			(xy 125.496317 -11.866588) (xy 125.495706 -11.866972) (xy 129.833804 -11.866972) (xy 129.833804 -11.812428)
			(xy 129.841567 -11.758438) (xy 129.856934 -11.706103) (xy 129.879594 -11.656488) (xy 129.909085 -11.610603)
			(xy 129.944805 -11.569383) (xy 129.986029 -11.533665) (xy 130.031916 -11.504179) (xy 130.081533 -11.481523)
			(xy 130.13387 -11.46616) (xy 130.18786 -11.458401) (xy 130.215132 -11.45794) (xy 131.078732 -11.45794)
			(xy 131.106 -11.458425) (xy 131.15998 -11.46619) (xy 131.212306 -11.481558) (xy 131.261913 -11.504216)
			(xy 131.30779 -11.533703) (xy 131.349004 -11.569419) (xy 131.384716 -11.610636) (xy 131.414199 -11.656515)
			(xy 131.436853 -11.706124) (xy 131.452217 -11.758451) (xy 131.459978 -11.812432) (xy 131.459978 -11.866968)
			(xy 131.452217 -11.920949) (xy 131.436853 -11.973276) (xy 131.432747 -11.982267) (xy 135.233942 -11.982267)
			(xy 135.233942 -11.927733) (xy 135.241703 -11.873755) (xy 135.257066 -11.82143) (xy 135.279719 -11.771824)
			(xy 135.309201 -11.725946) (xy 135.344912 -11.684731) (xy 135.386124 -11.649018) (xy 135.431999 -11.619533)
			(xy 135.481603 -11.596876) (xy 135.533927 -11.581509) (xy 135.587905 -11.573744) (xy 135.615172 -11.573256)
			(xy 136.478772 -11.573256) (xy 136.506046 -11.573682) (xy 136.560038 -11.581441) (xy 136.612377 -11.596805)
			(xy 136.661996 -11.619462) (xy 136.707885 -11.648951) (xy 136.74911 -11.68467) (xy 136.784832 -11.725893)
			(xy 136.814324 -11.77178) (xy 136.836985 -11.821397) (xy 136.852353 -11.873735) (xy 136.860116 -11.927726)
			(xy 136.860116 -11.982274) (xy 136.852353 -12.036265) (xy 136.836985 -12.088603) (xy 136.814324 -12.13822)
			(xy 136.784832 -12.184107) (xy 136.74911 -12.22533) (xy 136.707885 -12.261049) (xy 136.661996 -12.290538)
			(xy 136.612377 -12.313195) (xy 136.560038 -12.328559) (xy 136.506046 -12.336318) (xy 136.478772 -12.33678)
			(xy 135.615172 -12.33678) (xy 135.587905 -12.336256) (xy 135.533927 -12.328491) (xy 135.481603 -12.313124)
			(xy 135.431999 -12.290467) (xy 135.386124 -12.260982) (xy 135.344912 -12.225269) (xy 135.309201 -12.184054)
			(xy 135.279719 -12.138176) (xy 135.257066 -12.08857) (xy 135.241703 -12.036245) (xy 135.233942 -11.982267)
			(xy 131.432747 -11.982267) (xy 131.414199 -12.022885) (xy 131.384716 -12.068764) (xy 131.349004 -12.109981)
			(xy 131.30779 -12.145697) (xy 131.261913 -12.175184) (xy 131.212306 -12.197842) (xy 131.15998 -12.21321)
			(xy 131.106 -12.220975) (xy 131.078732 -12.221464) (xy 130.215132 -12.221464) (xy 130.18786 -12.220999)
			(xy 130.13387 -12.21324) (xy 130.081533 -12.197877) (xy 130.031916 -12.175221) (xy 129.986029 -12.145735)
			(xy 129.944805 -12.110017) (xy 129.909085 -12.068797) (xy 129.879594 -12.022912) (xy 129.856934 -11.973297)
			(xy 129.841567 -11.920962) (xy 129.833804 -11.866972) (xy 125.495706 -11.866972) (xy 125.377128 -11.941479)
			(xy 125.253928 -12.009569) (xy 125.127104 -12.070645) (xy 124.997055 -12.124513) (xy 124.86419 -12.171005)
			(xy 124.728928 -12.209974) (xy 124.591693 -12.241298) (xy 124.452918 -12.264877) (xy 124.313039 -12.280639)
			(xy 124.172496 -12.288532) (xy 124.102114 -12.289028) (xy 83.70189 -12.289028) (xy 83.631508 -12.288534)
			(xy 83.490965 -12.280641) (xy 83.351086 -12.26488) (xy 83.21231 -12.2413) (xy 83.075075 -12.209977)
			(xy 82.939812 -12.171008) (xy 82.806947 -12.124516) (xy 82.676898 -12.070648) (xy 82.550073 -12.009572)
			(xy 82.426873 -11.941482) (xy 82.307684 -11.866591) (xy 82.192882 -11.785134) (xy 82.082828 -11.697369)
			(xy 81.977868 -11.603571) (xy 81.878333 -11.504036) (xy 81.784535 -11.399076) (xy 81.696769 -11.289022)
			(xy 81.615313 -11.174221) (xy 81.540421 -11.055032) (xy 81.47233 -10.931832) (xy 81.411254 -10.805008)
			(xy 81.357386 -10.674959) (xy 81.310894 -10.542094) (xy 81.271924 -10.406831) (xy 81.240601 -10.269596)
			(xy 81.217021 -10.13082) (xy 81.20126 -9.990941) (xy 81.193366 -9.850398) (xy 81.192878 -9.780016)
			(xy 81.192878 -0.559816) (xy 81.192461 -0.549794) (xy 81.184793 -0.531276) (xy 81.170619 -0.517104)
			(xy 81.1521 -0.509438) (xy 81.142078 -0.509016) (xy 13.661898 -0.509016) (xy 13.651878 -0.509436)
			(xy 13.633365 -0.517107) (xy 13.619197 -0.53128) (xy 13.611532 -0.549796) (xy 13.611098 -0.559816)
			(xy 13.611098 -5.169916) (xy 14.349991 -5.169916) (xy 14.353997 -5.081985) (xy 14.365983 -4.994782)
			(xy 14.385848 -4.90903) (xy 14.41343 -4.82544) (xy 14.448498 -4.744705) (xy 14.490763 -4.667493)
			(xy 14.539874 -4.594444) (xy 14.595424 -4.526164) (xy 14.656953 -4.463218) (xy 14.723951 -4.406129)
			(xy 14.795862 -4.355368) (xy 14.872092 -4.311356) (xy 14.952008 -4.274459) (xy 15.034949 -4.244982)
			(xy 15.120226 -4.22317) (xy 15.207133 -4.209202) (xy 15.294951 -4.203195) (xy 15.38295 -4.205199)
			(xy 15.470403 -4.215196) (xy 15.556585 -4.233105) (xy 15.640781 -4.258777) (xy 15.722294 -4.291998)
			(xy 15.800448 -4.332494) (xy 15.874595 -4.379929) (xy 15.944122 -4.433911) (xy 16.008453 -4.493991)
			(xy 16.067053 -4.559672) (xy 16.119437 -4.63041) (xy 16.165173 -4.705618) (xy 16.203879 -4.784674)
			(xy 16.235237 -4.866921) (xy 16.258985 -4.95168) (xy 16.266165 -4.990667) (xy 20.439138 -4.990667)
			(xy 20.439138 -4.936133) (xy 20.446899 -4.882153) (xy 20.462263 -4.829827) (xy 20.484917 -4.78022)
			(xy 20.5144 -4.734341) (xy 20.550112 -4.693126) (xy 20.591325 -4.657412) (xy 20.637202 -4.627926)
			(xy 20.686808 -4.60527) (xy 20.739133 -4.589903) (xy 20.793113 -4.58214) (xy 20.82038 -4.581652)
			(xy 21.68398 -4.581652) (xy 21.711253 -4.582086) (xy 21.765244 -4.589846) (xy 21.817581 -4.605211)
			(xy 21.867198 -4.627869) (xy 21.913086 -4.657357) (xy 21.95431 -4.693076) (xy 21.990031 -4.734298)
			(xy 22.019522 -4.780184) (xy 22.042182 -4.8298) (xy 22.057549 -4.882136) (xy 22.065312 -4.936127)
			(xy 22.065312 -4.990671) (xy 24.039016 -4.990671) (xy 24.039016 -4.936129) (xy 24.046778 -4.882142)
			(xy 24.062145 -4.82981) (xy 24.084803 -4.780197) (xy 24.114292 -4.734314) (xy 24.15001 -4.693095)
			(xy 24.191231 -4.657379) (xy 24.237116 -4.627893) (xy 24.28673 -4.605237) (xy 24.339064 -4.589873)
			(xy 24.393051 -4.582114) (xy 24.420322 -4.581652) (xy 25.283922 -4.581652) (xy 25.311191 -4.582112)
			(xy 25.365175 -4.589876) (xy 25.417503 -4.605244) (xy 25.467113 -4.627903) (xy 25.512992 -4.65739)
			(xy 25.554209 -4.693107) (xy 25.589923 -4.734325) (xy 25.619408 -4.780207) (xy 25.642063 -4.829817)
			(xy 25.657428 -4.882147) (xy 25.66519 -4.936131) (xy 25.66519 -4.990667) (xy 27.639038 -4.990667)
			(xy 27.639038 -4.936133) (xy 27.646799 -4.882155) (xy 27.662162 -4.82983) (xy 27.684814 -4.780224)
			(xy 27.714296 -4.734347) (xy 27.750006 -4.693131) (xy 27.791218 -4.657417) (xy 27.837092 -4.627932)
			(xy 27.886696 -4.605274) (xy 27.93902 -4.589906) (xy 27.992997 -4.582141) (xy 28.020264 -4.581652)
			(xy 28.883864 -4.581652) (xy 28.911138 -4.582085) (xy 28.96513 -4.589843) (xy 29.017469 -4.605207)
			(xy 29.067089 -4.627863) (xy 29.112979 -4.657351) (xy 29.154205 -4.69307) (xy 29.189927 -4.734292)
			(xy 29.219419 -4.78018) (xy 29.24208 -4.829797) (xy 29.257449 -4.882134) (xy 29.265212 -4.936126)
			(xy 29.265212 -4.990667) (xy 31.239238 -4.990667) (xy 31.239238 -4.936133) (xy 31.246999 -4.882155)
			(xy 31.262361 -4.829831) (xy 31.285014 -4.780225) (xy 31.314495 -4.734348) (xy 31.350205 -4.693133)
			(xy 31.391416 -4.657419) (xy 31.43729 -4.627933) (xy 31.486893 -4.605275) (xy 31.539216 -4.589907)
			(xy 31.593193 -4.582141) (xy 31.62046 -4.581652) (xy 32.48406 -4.581652) (xy 32.511334 -4.582085)
			(xy 32.565327 -4.589843) (xy 32.617666 -4.605206) (xy 32.667286 -4.627862) (xy 32.713177 -4.65735)
			(xy 32.754403 -4.693068) (xy 32.790126 -4.734291) (xy 32.819619 -4.780178) (xy 32.84228 -4.829796)
			(xy 32.857649 -4.882134) (xy 32.865412 -4.936126) (xy 32.865412 -4.990671) (xy 40.349116 -4.990671)
			(xy 40.349116 -4.936129) (xy 40.356878 -4.882142) (xy 40.372245 -4.829809) (xy 40.394903 -4.780196)
			(xy 40.424392 -4.734313) (xy 40.460111 -4.693094) (xy 40.501332 -4.657378) (xy 40.547217 -4.627892)
			(xy 40.596832 -4.605237) (xy 40.649165 -4.589873) (xy 40.703153 -4.582114) (xy 40.730424 -4.581652)
			(xy 41.594024 -4.581652) (xy 41.621293 -4.582112) (xy 41.675276 -4.589877) (xy 41.727605 -4.605245)
			(xy 41.777214 -4.627903) (xy 41.823093 -4.657391) (xy 41.86431 -4.693107) (xy 41.900024 -4.734326)
			(xy 41.929508 -4.780207) (xy 41.952164 -4.829818) (xy 41.967528 -4.882147) (xy 41.97529 -4.936131)
			(xy 41.97529 -4.990667) (xy 43.949138 -4.990667) (xy 43.949138 -4.936133) (xy 43.956899 -4.882155)
			(xy 43.972262 -4.82983) (xy 43.994915 -4.780224) (xy 44.024396 -4.734346) (xy 44.060107 -4.693131)
			(xy 44.101319 -4.657417) (xy 44.147194 -4.627931) (xy 44.196798 -4.605274) (xy 44.249121 -4.589906)
			(xy 44.303099 -4.582141) (xy 44.330366 -4.581652) (xy 45.193966 -4.581652) (xy 45.22124 -4.582085)
			(xy 45.275232 -4.589844) (xy 45.327571 -4.605208) (xy 45.37719 -4.627864) (xy 45.42308 -4.657352)
			(xy 45.464305 -4.693071) (xy 45.500028 -4.734293) (xy 45.52952 -4.78018) (xy 45.552181 -4.829797)
			(xy 45.567549 -4.882135) (xy 45.575312 -4.936126) (xy 45.575312 -4.990667) (xy 51.559238 -4.990667)
			(xy 51.559238 -4.936133) (xy 51.566999 -4.882155) (xy 51.582361 -4.829831) (xy 51.605014 -4.780225)
			(xy 51.634495 -4.734348) (xy 51.670205 -4.693133) (xy 51.711416 -4.657419) (xy 51.75729 -4.627933)
			(xy 51.806893 -4.605275) (xy 51.859216 -4.589907) (xy 51.913193 -4.582141) (xy 51.94046 -4.581652)
			(xy 52.80406 -4.581652) (xy 52.831334 -4.582085) (xy 52.885327 -4.589843) (xy 52.937666 -4.605206)
			(xy 52.987286 -4.627862) (xy 53.033177 -4.65735) (xy 53.074403 -4.693068) (xy 53.110126 -4.734291)
			(xy 53.139619 -4.780178) (xy 53.16228 -4.829796) (xy 53.177649 -4.882134) (xy 53.185412 -4.936126)
			(xy 53.185412 -4.99067) (xy 55.159115 -4.99067) (xy 55.159115 -4.93613) (xy 55.166877 -4.882145)
			(xy 55.182243 -4.829814) (xy 55.2049 -4.780202) (xy 55.234387 -4.73432) (xy 55.270103 -4.693102)
			(xy 55.311322 -4.657386) (xy 55.357204 -4.627899) (xy 55.406816 -4.605242) (xy 55.459147 -4.589877)
			(xy 55.513132 -4.582115) (xy 55.540402 -4.581652) (xy 56.404002 -4.581652) (xy 56.431272 -4.582111)
			(xy 56.485258 -4.589873) (xy 56.537589 -4.605239) (xy 56.587201 -4.627896) (xy 56.633083 -4.657383)
			(xy 56.674302 -4.6931) (xy 56.710018 -4.734319) (xy 56.739505 -4.780201) (xy 56.762162 -4.829813)
			(xy 56.777528 -4.882144) (xy 56.78529 -4.93613) (xy 56.78529 -4.99067) (xy 56.777528 -5.044656) (xy 56.762162 -5.096987)
			(xy 56.739505 -5.146599) (xy 56.710018 -5.192481) (xy 56.674302 -5.2337) (xy 56.633083 -5.269417)
			(xy 56.587201 -5.298904) (xy 56.537589 -5.321561) (xy 56.485258 -5.336927) (xy 56.431272 -5.344689)
			(xy 56.404002 -5.345176) (xy 55.540402 -5.345176) (xy 55.513132 -5.344685) (xy 55.459147 -5.336923)
			(xy 55.406816 -5.321558) (xy 55.357204 -5.298901) (xy 55.311322 -5.269414) (xy 55.270103 -5.233698)
			(xy 55.234387 -5.19248) (xy 55.2049 -5.146598) (xy 55.182243 -5.096986) (xy 55.166877 -5.044655)
			(xy 55.159115 -4.99067) (xy 53.185412 -4.99067) (xy 53.185412 -4.990674) (xy 53.177649 -5.044666)
			(xy 53.16228 -5.097004) (xy 53.139619 -5.146622) (xy 53.110126 -5.192509) (xy 53.074403 -5.233732)
			(xy 53.033177 -5.26945) (xy 52.987286 -5.298938) (xy 52.937666 -5.321594) (xy 52.885327 -5.336957)
			(xy 52.831334 -5.344715) (xy 52.80406 -5.345176) (xy 51.94046 -5.345176) (xy 51.913194 -5.344659)
			(xy 51.859216 -5.336893) (xy 51.806893 -5.321525) (xy 51.75729 -5.298867) (xy 51.711416 -5.269381)
			(xy 51.670205 -5.233667) (xy 51.634495 -5.192452) (xy 51.605014 -5.146575) (xy 51.582361 -5.096969)
			(xy 51.566999 -5.044645) (xy 51.559238 -4.990667) (xy 45.575312 -4.990667) (xy 45.575312 -4.990674)
			(xy 45.567549 -5.044665) (xy 45.552181 -5.097003) (xy 45.52952 -5.14662) (xy 45.500028 -5.192507)
			(xy 45.464305 -5.233729) (xy 45.42308 -5.269448) (xy 45.37719 -5.298936) (xy 45.327571 -5.321592)
			(xy 45.275232 -5.336956) (xy 45.22124 -5.344715) (xy 45.193966 -5.345176) (xy 44.330366 -5.345176)
			(xy 44.303099 -5.344659) (xy 44.249121 -5.336894) (xy 44.196798 -5.321526) (xy 44.147194 -5.298869)
			(xy 44.101319 -5.269383) (xy 44.060107 -5.233669) (xy 44.024396 -5.192454) (xy 43.994915 -5.146576)
			(xy 43.972262 -5.09697) (xy 43.956899 -5.044645) (xy 43.949138 -4.990667) (xy 41.97529 -4.990667)
			(xy 41.97529 -4.990669) (xy 41.967528 -5.044653) (xy 41.952164 -5.096982) (xy 41.929508 -5.146593)
			(xy 41.900024 -5.192474) (xy 41.86431 -5.233693) (xy 41.823093 -5.269409) (xy 41.777214 -5.298897)
			(xy 41.727605 -5.321555) (xy 41.675276 -5.336923) (xy 41.621293 -5.344688) (xy 41.594024 -5.345176)
			(xy 40.730424 -5.345176) (xy 40.703153 -5.344686) (xy 40.649165 -5.336927) (xy 40.596832 -5.321563)
			(xy 40.547217 -5.298908) (xy 40.501332 -5.269422) (xy 40.460111 -5.233706) (xy 40.424392 -5.192487)
			(xy 40.394903 -5.146604) (xy 40.372245 -5.096991) (xy 40.356878 -5.044658) (xy 40.349116 -4.990671)
			(xy 32.865412 -4.990671) (xy 32.865412 -4.990674) (xy 32.857649 -5.044666) (xy 32.84228 -5.097004)
			(xy 32.819619 -5.146622) (xy 32.790126 -5.192509) (xy 32.754403 -5.233732) (xy 32.713177 -5.26945)
			(xy 32.667286 -5.298938) (xy 32.617666 -5.321594) (xy 32.565327 -5.336957) (xy 32.511334 -5.344715)
			(xy 32.48406 -5.345176) (xy 31.62046 -5.345176) (xy 31.593194 -5.344659) (xy 31.539216 -5.336893)
			(xy 31.486893 -5.321525) (xy 31.43729 -5.298867) (xy 31.391416 -5.269381) (xy 31.350205 -5.233667)
			(xy 31.314495 -5.192452) (xy 31.285014 -5.146575) (xy 31.262361 -5.096969) (xy 31.246999 -5.044645)
			(xy 31.239238 -4.990667) (xy 29.265212 -4.990667) (xy 29.265212 -4.990674) (xy 29.257449 -5.044666)
			(xy 29.24208 -5.097003) (xy 29.219419 -5.14662) (xy 29.189927 -5.192508) (xy 29.154205 -5.23373)
			(xy 29.112979 -5.269449) (xy 29.067089 -5.298937) (xy 29.017469 -5.321593) (xy 28.96513 -5.336957)
			(xy 28.911138 -5.344715) (xy 28.883864 -5.345176) (xy 28.020264 -5.345176) (xy 27.992997 -5.344659)
			(xy 27.93902 -5.336894) (xy 27.886696 -5.321526) (xy 27.837092 -5.298868) (xy 27.791218 -5.269383)
			(xy 27.750006 -5.233669) (xy 27.714296 -5.192453) (xy 27.684814 -5.146576) (xy 27.662162 -5.09697)
			(xy 27.646799 -5.044645) (xy 27.639038 -4.990667) (xy 25.66519 -4.990667) (xy 25.66519 -4.990669)
			(xy 25.657428 -5.044653) (xy 25.642063 -5.096983) (xy 25.619408 -5.146593) (xy 25.589923 -5.192475)
			(xy 25.554209 -5.233693) (xy 25.512992 -5.26941) (xy 25.467113 -5.298897) (xy 25.417503 -5.321556)
			(xy 25.365175 -5.336924) (xy 25.311191 -5.344688) (xy 25.283922 -5.345176) (xy 24.420322 -5.345176)
			(xy 24.393051 -5.344686) (xy 24.339064 -5.336927) (xy 24.28673 -5.321563) (xy 24.237116 -5.298907)
			(xy 24.191231 -5.269421) (xy 24.15001 -5.233705) (xy 24.114292 -5.192486) (xy 24.084803 -5.146603)
			(xy 24.062145 -5.09699) (xy 24.046778 -5.044658) (xy 24.039016 -4.990671) (xy 22.065312 -4.990671)
			(xy 22.065312 -4.990673) (xy 22.057549 -5.044664) (xy 22.042182 -5.097) (xy 22.019522 -5.146616)
			(xy 21.990031 -5.192502) (xy 21.95431 -5.233724) (xy 21.913086 -5.269443) (xy 21.867198 -5.298931)
			(xy 21.817581 -5.321589) (xy 21.765244 -5.336954) (xy 21.711253 -5.344714) (xy 21.68398 -5.345176)
			(xy 20.82038 -5.345176) (xy 20.793113 -5.34466) (xy 20.739133 -5.336897) (xy 20.686808 -5.32153)
			(xy 20.637202 -5.298874) (xy 20.591325 -5.269388) (xy 20.550112 -5.233674) (xy 20.5144 -5.192459)
			(xy 20.484917 -5.14658) (xy 20.462263 -5.096973) (xy 20.446899 -5.044647) (xy 20.439138 -4.990667)
			(xy 16.266165 -4.990667) (xy 16.274927 -5.038247) (xy 16.282931 -5.125905) (xy 16.283432 -5.169916)
			(xy 16.282931 -5.213927) (xy 16.274927 -5.301585) (xy 16.258985 -5.388152) (xy 16.235237 -5.472911)
			(xy 16.203879 -5.555158) (xy 16.165173 -5.634214) (xy 16.119437 -5.709422) (xy 16.067053 -5.78016)
			(xy 16.008453 -5.845841) (xy 15.944122 -5.905921) (xy 15.874595 -5.959903) (xy 15.800448 -6.007338)
			(xy 15.722294 -6.047834) (xy 15.640781 -6.081055) (xy 15.556585 -6.106727) (xy 15.470403 -6.124636)
			(xy 15.38295 -6.134633) (xy 15.294951 -6.136637) (xy 15.207133 -6.13063) (xy 15.120226 -6.116662)
			(xy 15.034949 -6.09485) (xy 14.952008 -6.065373) (xy 14.872092 -6.028476) (xy 14.795862 -5.984464)
			(xy 14.723951 -5.933703) (xy 14.656953 -5.876614) (xy 14.595424 -5.813668) (xy 14.539874 -5.745388)
			(xy 14.490763 -5.672339) (xy 14.448498 -5.595127) (xy 14.41343 -5.514392) (xy 14.385848 -5.430802)
			(xy 14.365983 -5.34505) (xy 14.353997 -5.257847) (xy 14.349991 -5.169916) (xy 13.611098 -5.169916)
			(xy 13.611098 -6.169914) (xy 78.515217 -6.169914) (xy 78.519222 -6.082006) (xy 78.531205 -5.994826)
			(xy 78.551065 -5.909097) (xy 78.57864 -5.825529) (xy 78.613699 -5.744815) (xy 78.655952 -5.667623)
			(xy 78.70505 -5.594594) (xy 78.760586 -5.526332) (xy 78.822098 -5.463402) (xy 78.889079 -5.406328)
			(xy 78.960972 -5.35558) (xy 79.037181 -5.31158) (xy 79.117076 -5.274693) (xy 79.199995 -5.245224)
			(xy 79.28525 -5.223417) (xy 79.372134 -5.209453) (xy 79.459928 -5.203447) (xy 79.547905 -5.205451)
			(xy 79.635335 -5.215446) (xy 79.721494 -5.23335) (xy 79.805668 -5.259014) (xy 79.887159 -5.292227)
			(xy 79.965293 -5.332713) (xy 80.039421 -5.380135) (xy 80.108929 -5.434102) (xy 80.173243 -5.494167)
			(xy 80.231827 -5.559831) (xy 80.284198 -5.63055) (xy 80.329921 -5.705738) (xy 80.368618 -5.784773)
			(xy 80.399967 -5.866999) (xy 80.423709 -5.951735) (xy 80.439647 -6.038279) (xy 80.447649 -6.125914)
			(xy 80.44815 -6.169914) (xy 80.447649 -6.213914) (xy 80.439647 -6.301549) (xy 80.423709 -6.388093)
			(xy 80.399967 -6.472829) (xy 80.368618 -6.555055) (xy 80.329921 -6.63409) (xy 80.284198 -6.709278)
			(xy 80.231827 -6.779997) (xy 80.173243 -6.845661) (xy 80.108929 -6.905726) (xy 80.039421 -6.959693)
			(xy 79.965293 -7.007115) (xy 79.887159 -7.047601) (xy 79.805668 -7.080814) (xy 79.721494 -7.106478)
			(xy 79.635335 -7.124382) (xy 79.547905 -7.134377) (xy 79.459928 -7.136381) (xy 79.372134 -7.130375)
			(xy 79.28525 -7.116411) (xy 79.199995 -7.094604) (xy 79.117076 -7.065135) (xy 79.037181 -7.028248)
			(xy 78.960972 -6.984248) (xy 78.889079 -6.9335) (xy 78.822098 -6.876426) (xy 78.760586 -6.813496)
			(xy 78.70505 -6.745234) (xy 78.655952 -6.672205) (xy 78.613699 -6.595013) (xy 78.57864 -6.514299)
			(xy 78.551065 -6.430731) (xy 78.531205 -6.345002) (xy 78.519222 -6.257822) (xy 78.515217 -6.169914)
			(xy 13.611098 -6.169914) (xy 13.611098 -6.75243) (xy 18.634432 -6.75243) (xy 18.634432 -6.69789)
			(xy 18.642194 -6.643907) (xy 18.65756 -6.591577) (xy 18.680216 -6.541966) (xy 18.709702 -6.496085)
			(xy 18.745417 -6.454867) (xy 18.786635 -6.419152) (xy 18.832516 -6.389666) (xy 18.882127 -6.36701)
			(xy 18.934457 -6.351644) (xy 18.98844 -6.343882) (xy 19.01571 -6.343396) (xy 19.87931 -6.343396)
			(xy 19.906579 -6.343886) (xy 19.960563 -6.351648) (xy 20.012892 -6.367013) (xy 20.062502 -6.389669)
			(xy 20.108382 -6.419155) (xy 20.1496 -6.45487) (xy 20.185315 -6.496088) (xy 20.214801 -6.541968)
			(xy 20.237457 -6.591578) (xy 20.252822 -6.643907) (xy 20.260584 -6.697891) (xy 20.260584 -6.752429)
			(xy 20.260584 -6.752431) (xy 22.234349 -6.752431) (xy 22.234349 -6.697889) (xy 22.242112 -6.643901)
			(xy 22.257478 -6.591568) (xy 22.280136 -6.541955) (xy 22.309624 -6.496071) (xy 22.345342 -6.45485)
			(xy 22.386562 -6.419133) (xy 22.432447 -6.389645) (xy 22.48206 -6.366987) (xy 22.534393 -6.351621)
			(xy 22.588381 -6.343859) (xy 22.615652 -6.343396) (xy 23.479252 -6.343396) (xy 23.506521 -6.343887)
			(xy 23.560504 -6.351648) (xy 23.612833 -6.367014) (xy 23.662443 -6.38967) (xy 23.708323 -6.419156)
			(xy 23.749541 -6.454871) (xy 23.785255 -6.496088) (xy 23.814741 -6.541969) (xy 23.837397 -6.591579)
			(xy 23.852762 -6.643908) (xy 23.860524 -6.697891) (xy 23.860524 -6.752429) (xy 23.860518 -6.752472)
			(xy 25.834283 -6.752472) (xy 25.834283 -6.697928) (xy 25.842045 -6.643939) (xy 25.857412 -6.591604)
			(xy 25.88007 -6.541989) (xy 25.909558 -6.496103) (xy 25.945277 -6.454881) (xy 25.986498 -6.419162)
			(xy 26.032384 -6.389673) (xy 26.081998 -6.367014) (xy 26.134333 -6.351646) (xy 26.188322 -6.343883)
			(xy 26.215594 -6.343396) (xy 27.079194 -6.343396) (xy 27.106462 -6.343943) (xy 27.160444 -6.351704)
			(xy 27.212772 -6.367068) (xy 27.26238 -6.389722) (xy 27.308259 -6.419207) (xy 27.349476 -6.45492)
			(xy 27.38519 -6.496136) (xy 27.414675 -6.542015) (xy 27.43733 -6.591623) (xy 27.452695 -6.64395)
			(xy 27.460457 -6.697932) (xy 27.460457 -6.752468) (xy 27.460456 -6.752472) (xy 29.434483 -6.752472)
			(xy 29.434483 -6.697928) (xy 29.442245 -6.643939) (xy 29.457611 -6.591605) (xy 29.480269 -6.54199)
			(xy 29.509757 -6.496105) (xy 29.545476 -6.454883) (xy 29.586697 -6.419163) (xy 29.632581 -6.389674)
			(xy 29.682196 -6.367015) (xy 29.73453 -6.351647) (xy 29.788518 -6.343883) (xy 29.81579 -6.343396)
			(xy 30.67939 -6.343396) (xy 30.706658 -6.343943) (xy 30.76064 -6.351703) (xy 30.812969 -6.367067)
			(xy 30.862578 -6.389721) (xy 30.908457 -6.419205) (xy 30.949674 -6.454919) (xy 30.985389 -6.496135)
			(xy 31.014874 -6.542014) (xy 31.03753 -6.591622) (xy 31.052895 -6.64395) (xy 31.060657 -6.697932)
			(xy 31.060657 -6.752468) (xy 31.060657 -6.75247) (xy 38.544482 -6.75247) (xy 38.544482 -6.69793)
			(xy 38.552244 -6.643944) (xy 38.567608 -6.591613) (xy 38.590264 -6.542) (xy 38.619749 -6.496116)
			(xy 38.655463 -6.454895) (xy 38.696679 -6.419176) (xy 38.74256 -6.389686) (xy 38.792169 -6.367025)
			(xy 38.844499 -6.351654) (xy 38.898484 -6.343886) (xy 38.925754 -6.343396) (xy 39.789354 -6.343396)
			(xy 39.816624 -6.34394) (xy 39.87061 -6.351696) (xy 39.922943 -6.367057) (xy 39.972556 -6.389709)
			(xy 40.01844 -6.419192) (xy 40.059662 -6.454906) (xy 40.09538 -6.496123) (xy 40.124869 -6.542004)
			(xy 40.147527 -6.591614) (xy 40.162894 -6.643945) (xy 40.170656 -6.69793) (xy 40.170656 -6.75247)
			(xy 40.170656 -6.752472) (xy 42.144383 -6.752472) (xy 42.144383 -6.697928) (xy 42.152145 -6.643939)
			(xy 42.167512 -6.591604) (xy 42.19017 -6.541988) (xy 42.219659 -6.496103) (xy 42.255378 -6.454881)
			(xy 42.296599 -6.419161) (xy 42.342485 -6.389672) (xy 42.3921 -6.367013) (xy 42.444435 -6.351646)
			(xy 42.498424 -6.343883) (xy 42.525696 -6.343396) (xy 43.389296 -6.343396) (xy 43.416564 -6.343943)
			(xy 43.470546 -6.351704) (xy 43.522873 -6.367068) (xy 43.572481 -6.389723) (xy 43.61836 -6.419207)
			(xy 43.659576 -6.454921) (xy 43.69529 -6.496136) (xy 43.724775 -6.542015) (xy 43.74743 -6.591623)
			(xy 43.762795 -6.643951) (xy 43.770557 -6.697932) (xy 43.770557 -6.752468) (xy 43.770556 -6.752472)
			(xy 49.754483 -6.752472) (xy 49.754483 -6.697928) (xy 49.762245 -6.643939) (xy 49.777611 -6.591605)
			(xy 49.800269 -6.54199) (xy 49.829757 -6.496105) (xy 49.865476 -6.454883) (xy 49.906697 -6.419163)
			(xy 49.952581 -6.389674) (xy 50.002196 -6.367015) (xy 50.05453 -6.351647) (xy 50.108518 -6.343883)
			(xy 50.13579 -6.343396) (xy 50.99939 -6.343396) (xy 51.026658 -6.343943) (xy 51.08064 -6.351703)
			(xy 51.132969 -6.367067) (xy 51.182578 -6.389721) (xy 51.228457 -6.419205) (xy 51.269674 -6.454919)
			(xy 51.305389 -6.496135) (xy 51.334874 -6.542014) (xy 51.35753 -6.591622) (xy 51.372895 -6.64395)
			(xy 51.380657 -6.697932) (xy 51.380657 -6.752468) (xy 51.380656 -6.752475) (xy 53.35436 -6.752475)
			(xy 53.35436 -6.697925) (xy 53.362124 -6.643929) (xy 53.377493 -6.591588) (xy 53.400155 -6.541967)
			(xy 53.429649 -6.496077) (xy 53.465374 -6.454851) (xy 53.506603 -6.41913) (xy 53.552495 -6.38964)
			(xy 53.602118 -6.366982) (xy 53.65446 -6.351617) (xy 53.708457 -6.343857) (xy 53.735732 -6.343396)
			(xy 54.599332 -6.343396) (xy 54.626597 -6.343969) (xy 54.680571 -6.351733) (xy 54.732891 -6.367099)
			(xy 54.782492 -6.389755) (xy 54.828364 -6.419238) (xy 54.869573 -6.45495) (xy 54.905281 -6.496162)
			(xy 54.93476 -6.542036) (xy 54.957412 -6.591639) (xy 54.972774 -6.64396) (xy 54.980534 -6.697935)
			(xy 54.980534 -6.752465) (xy 54.980533 -6.752471) (xy 56.954382 -6.752471) (xy 56.954382 -6.697929)
			(xy 56.962144 -6.643942) (xy 56.97751 -6.591608) (xy 57.000167 -6.541994) (xy 57.029654 -6.49611)
			(xy 57.06537 -6.454888) (xy 57.106589 -6.419169) (xy 57.152472 -6.389679) (xy 57.202084 -6.367019)
			(xy 57.254416 -6.35165) (xy 57.308403 -6.343884) (xy 57.335674 -6.343396) (xy 58.199274 -6.343396)
			(xy 58.226543 -6.343942) (xy 58.280527 -6.3517) (xy 58.332857 -6.367062) (xy 58.382468 -6.389716)
			(xy 58.42835 -6.4192) (xy 58.469569 -6.454913) (xy 58.505285 -6.496129) (xy 58.534772 -6.542009)
			(xy 58.557429 -6.591619) (xy 58.564228 -6.614772) (xy 70.948992 -6.614772) (xy 70.948992 -6.560228)
			(xy 70.956754 -6.506238) (xy 70.972121 -6.453903) (xy 70.994781 -6.404288) (xy 71.02427 -6.358403)
			(xy 71.05999 -6.317181) (xy 71.101212 -6.281463) (xy 71.147099 -6.251975) (xy 71.196715 -6.229317)
			(xy 71.24905 -6.213952) (xy 71.30304 -6.206191) (xy 71.330312 -6.205728) (xy 72.193912 -6.205728)
			(xy 72.22118 -6.206235) (xy 72.275161 -6.213998) (xy 72.327488 -6.229364) (xy 72.377095 -6.25202)
			(xy 72.422973 -6.281506) (xy 72.464188 -6.31722) (xy 72.499901 -6.358436) (xy 72.529385 -6.404315)
			(xy 72.55204 -6.453924) (xy 72.567404 -6.506251) (xy 72.575166 -6.560232) (xy 72.575166 -6.614768)
			(xy 72.567404 -6.668749) (xy 72.55204 -6.721076) (xy 72.529385 -6.770685) (xy 72.499901 -6.816564)
			(xy 72.464188 -6.85778) (xy 72.422973 -6.893494) (xy 72.377095 -6.92298) (xy 72.327488 -6.945636)
			(xy 72.275161 -6.961002) (xy 72.22118 -6.968765) (xy 72.193912 -6.969252) (xy 71.330312 -6.969252)
			(xy 71.30304 -6.968809) (xy 71.24905 -6.961048) (xy 71.196715 -6.945683) (xy 71.147099 -6.923025)
			(xy 71.101212 -6.893537) (xy 71.05999 -6.857819) (xy 71.02427 -6.816597) (xy 70.994781 -6.770712)
			(xy 70.972121 -6.721097) (xy 70.956754 -6.668762) (xy 70.948992 -6.614772) (xy 58.564228 -6.614772)
			(xy 58.572795 -6.643948) (xy 58.580557 -6.697931) (xy 58.580557 -6.752469) (xy 58.572795 -6.806452)
			(xy 58.557429 -6.858781) (xy 58.534772 -6.908391) (xy 58.505285 -6.954271) (xy 58.469569 -6.995487)
			(xy 58.42835 -7.0312) (xy 58.382468 -7.060684) (xy 58.332857 -7.083338) (xy 58.280527 -7.0987) (xy 58.226543 -7.106458)
			(xy 58.199274 -7.10692) (xy 57.335674 -7.10692) (xy 57.308403 -7.106516) (xy 57.254416 -7.09875)
			(xy 57.202084 -7.083381) (xy 57.152472 -7.060721) (xy 57.106589 -7.031231) (xy 57.06537 -6.995512)
			(xy 57.029654 -6.95429) (xy 57.000167 -6.908406) (xy 56.97751 -6.858792) (xy 56.962144 -6.806458)
			(xy 56.954382 -6.752471) (xy 54.980533 -6.752471) (xy 54.972774 -6.80644) (xy 54.957412 -6.858761)
			(xy 54.93476 -6.908364) (xy 54.905281 -6.954238) (xy 54.869573 -6.99545) (xy 54.828364 -7.031162)
			(xy 54.782492 -7.060645) (xy 54.732891 -7.083301) (xy 54.680571 -7.098667) (xy 54.626597 -7.106431)
			(xy 54.599332 -7.10692) (xy 53.735732 -7.10692) (xy 53.708457 -7.106543) (xy 53.65446 -7.098783)
			(xy 53.602118 -7.083418) (xy 53.552495 -7.06076) (xy 53.506603 -7.03127) (xy 53.465374 -6.995549)
			(xy 53.429649 -6.954323) (xy 53.400155 -6.908433) (xy 53.377493 -6.858812) (xy 53.362124 -6.806471)
			(xy 53.35436 -6.752475) (xy 51.380656 -6.752475) (xy 51.372895 -6.80645) (xy 51.35753 -6.858778)
			(xy 51.334874 -6.908386) (xy 51.305389 -6.954265) (xy 51.269674 -6.995481) (xy 51.228457 -7.031195)
			(xy 51.182578 -7.060679) (xy 51.132969 -7.083333) (xy 51.08064 -7.098697) (xy 51.026658 -7.106457)
			(xy 50.99939 -7.10692) (xy 50.13579 -7.10692) (xy 50.108518 -7.106517) (xy 50.05453 -7.098753) (xy 50.002196 -7.083385)
			(xy 49.952581 -7.060726) (xy 49.906697 -7.031237) (xy 49.865476 -6.995517) (xy 49.829757 -6.954295)
			(xy 49.800269 -6.90841) (xy 49.777611 -6.858795) (xy 49.762245 -6.806461) (xy 49.754483 -6.752472)
			(xy 43.770556 -6.752472) (xy 43.762795 -6.806449) (xy 43.74743 -6.858777) (xy 43.724775 -6.908385)
			(xy 43.69529 -6.954264) (xy 43.659576 -6.995479) (xy 43.61836 -7.031193) (xy 43.572481 -7.060677)
			(xy 43.522873 -7.083332) (xy 43.470546 -7.098696) (xy 43.416564 -7.106457) (xy 43.389296 -7.10692)
			(xy 42.525696 -7.10692) (xy 42.498424 -7.106517) (xy 42.444435 -7.098754) (xy 42.3921 -7.083387)
			(xy 42.342485 -7.060728) (xy 42.296599 -7.031239) (xy 42.255378 -6.995519) (xy 42.219659 -6.954297)
			(xy 42.19017 -6.908412) (xy 42.167512 -6.858796) (xy 42.152145 -6.806461) (xy 42.144383 -6.752472)
			(xy 40.170656 -6.752472) (xy 40.162894 -6.806455) (xy 40.147527 -6.858786) (xy 40.124869 -6.908396)
			(xy 40.09538 -6.954277) (xy 40.059661 -6.995494) (xy 40.01844 -7.031208) (xy 39.972556 -7.060691)
			(xy 39.922943 -7.083343) (xy 39.87061 -7.098704) (xy 39.816624 -7.10646) (xy 39.789354 -7.10692)
			(xy 38.925754 -7.10692) (xy 38.898484 -7.106514) (xy 38.844499 -7.098746) (xy 38.792169 -7.083375)
			(xy 38.74256 -7.060714) (xy 38.696679 -7.031224) (xy 38.655463 -6.995505) (xy 38.619749 -6.954284)
			(xy 38.590264 -6.9084) (xy 38.567608 -6.858787) (xy 38.552244 -6.806456) (xy 38.544482 -6.75247)
			(xy 31.060657 -6.75247) (xy 31.052895 -6.80645) (xy 31.03753 -6.858778) (xy 31.014874 -6.908386)
			(xy 30.985389 -6.954265) (xy 30.949674 -6.995481) (xy 30.908457 -7.031195) (xy 30.862578 -7.060679)
			(xy 30.812969 -7.083333) (xy 30.76064 -7.098697) (xy 30.706658 -7.106457) (xy 30.67939 -7.10692)
			(xy 29.81579 -7.10692) (xy 29.788518 -7.106517) (xy 29.73453 -7.098753) (xy 29.682196 -7.083385)
			(xy 29.632581 -7.060726) (xy 29.586697 -7.031237) (xy 29.545476 -6.995517) (xy 29.509757 -6.954295)
			(xy 29.480269 -6.90841) (xy 29.457611 -6.858795) (xy 29.442245 -6.806461) (xy 29.434483 -6.752472)
			(xy 27.460456 -6.752472) (xy 27.452695 -6.80645) (xy 27.43733 -6.858777) (xy 27.414675 -6.908385)
			(xy 27.38519 -6.954264) (xy 27.349476 -6.99548) (xy 27.308259 -7.031193) (xy 27.26238 -7.060678)
			(xy 27.212772 -7.083332) (xy 27.160444 -7.098696) (xy 27.106462 -7.106457) (xy 27.079194 -7.10692)
			(xy 26.215594 -7.10692) (xy 26.188322 -7.106517) (xy 26.134333 -7.098754) (xy 26.081998 -7.083386)
			(xy 26.032384 -7.060727) (xy 25.986498 -7.031238) (xy 25.945277 -6.995519) (xy 25.909558 -6.954297)
			(xy 25.88007 -6.908411) (xy 25.857412 -6.858796) (xy 25.842045 -6.806461) (xy 25.834283 -6.752472)
			(xy 23.860518 -6.752472) (xy 23.852762 -6.806412) (xy 23.837397 -6.858741) (xy 23.814741 -6.908351)
			(xy 23.785255 -6.954232) (xy 23.749541 -6.995449) (xy 23.708323 -7.031164) (xy 23.662443 -7.06065)
			(xy 23.612833 -7.083306) (xy 23.560504 -7.098672) (xy 23.506521 -7.106433) (xy 23.479252 -7.10692)
			(xy 22.615652 -7.10692) (xy 22.588381 -7.106461) (xy 22.534393 -7.098699) (xy 22.48206 -7.083333)
			(xy 22.432447 -7.060675) (xy 22.386562 -7.031187) (xy 22.345342 -6.99547) (xy 22.309624 -6.954249)
			(xy 22.280136 -6.908365) (xy 22.257478 -6.858752) (xy 22.242112 -6.806419) (xy 22.234349 -6.752431)
			(xy 20.260584 -6.752431) (xy 20.252822 -6.806413) (xy 20.237457 -6.858742) (xy 20.214801 -6.908352)
			(xy 20.185315 -6.954232) (xy 20.1496 -6.99545) (xy 20.108382 -7.031165) (xy 20.062502 -7.060651)
			(xy 20.012892 -7.083307) (xy 19.960563 -7.098672) (xy 19.906579 -7.106434) (xy 19.87931 -7.10692)
			(xy 19.01571 -7.10692) (xy 18.98844 -7.106438) (xy 18.934457 -7.098676) (xy 18.882127 -7.08331) (xy 18.832516 -7.060654)
			(xy 18.786635 -7.031168) (xy 18.745417 -6.995453) (xy 18.709702 -6.954235) (xy 18.680216 -6.908354)
			(xy 18.65756 -6.858743) (xy 18.642194 -6.806413) (xy 18.634432 -6.75243) (xy 13.611098 -6.75243)
			(xy 13.611098 -9.780016) (xy 13.610604 -9.850398) (xy 13.602711 -9.990941) (xy 13.58695 -10.13082)
			(xy 13.563371 -10.269596) (xy 13.532048 -10.406831) (xy 13.493079 -10.542094) (xy 13.446587 -10.674959)
			(xy 13.392719 -10.805008) (xy 13.331643 -10.931832) (xy 13.263553 -11.055033) (xy 13.188662 -11.174221)
			(xy 13.107205 -11.289023) (xy 13.01944 -11.399077) (xy 12.925642 -11.504037) (xy 12.826107 -11.603572)
			(xy 12.721147 -11.69737) (xy 12.611093 -11.785135) (xy 12.496291 -11.866592) (xy 12.377103 -11.941483)
			(xy 12.253902 -12.009573) (xy 12.127078 -12.070649) (xy 11.997029 -12.124517) (xy 11.864164 -12.171009)
			(xy 11.728901 -12.209978) (xy 11.591666 -12.241301) (xy 11.45289 -12.26488) (xy 11.313011 -12.280641)
			(xy 11.172468 -12.288534) (xy 11.102086 -12.289028) (xy 1.999996 -12.289028) (xy 1.944227 -12.289537)
			(xy 1.833 -12.297872) (xy 1.722707 -12.314497) (xy 1.613965 -12.339317) (xy 1.507382 -12.372193)
			(xy 1.403554 -12.412943) (xy 1.353372 -12.43711) (xy 62.309756 -12.43711) (xy 62.310222 -12.396003)
			(xy 62.317806 -12.314139) (xy 62.332909 -12.233324) (xy 62.355404 -12.154247) (xy 62.385098 -12.077583)
			(xy 62.421737 -12.003984) (xy 62.46501 -11.93408) (xy 62.514548 -11.868466) (xy 62.569927 -11.807701)
			(xy 62.630676 -11.752305) (xy 62.696277 -11.70275) (xy 62.766169 -11.659457) (xy 62.839757 -11.622797)
			(xy 62.916414 -11.593082) (xy 62.995485 -11.570566) (xy 63.076295 -11.55544) (xy 63.158157 -11.547833)
			(xy 63.199264 -11.547348) (xy 63.243059 -11.547873) (xy 63.330225 -11.556491) (xy 63.416121 -11.573637)
			(xy 63.499915 -11.599145) (xy 63.580795 -11.632768) (xy 63.619634 -11.653012) (xy 63.6311 -11.65843)
			(xy 63.656428 -11.65843) (xy 63.667894 -11.653012) (xy 63.706738 -11.632781) (xy 63.787623 -11.599174)
			(xy 63.871416 -11.573672) (xy 63.957309 -11.556521) (xy 64.04447 -11.547888) (xy 64.088264 -11.547348)
			(xy 64.132059 -11.547873) (xy 64.219225 -11.556491) (xy 64.305121 -11.573637) (xy 64.388915 -11.599145)
			(xy 64.469795 -11.632768) (xy 64.508634 -11.653012) (xy 64.5201 -11.65843) (xy 64.545428 -11.65843)
			(xy 64.556894 -11.653012) (xy 64.595738 -11.632781) (xy 64.676623 -11.599174) (xy 64.760416 -11.573672)
			(xy 64.846309 -11.556521) (xy 64.93347 -11.547888) (xy 64.977264 -11.547348) (xy 65.021059 -11.547873)
			(xy 65.108225 -11.556491) (xy 65.194121 -11.573637) (xy 65.277915 -11.599145) (xy 65.358795 -11.632768)
			(xy 65.397634 -11.653012) (xy 65.4091 -11.65843) (xy 65.434428 -11.65843) (xy 65.445894 -11.653012)
			(xy 65.484738 -11.632781) (xy 65.565623 -11.599174) (xy 65.649416 -11.573672) (xy 65.735309 -11.556521)
			(xy 65.82247 -11.547888) (xy 65.866264 -11.547348) (xy 65.904554 -11.547763) (xy 65.980848 -11.554368)
			(xy 66.05629 -11.567515) (xy 66.130321 -11.587105) (xy 66.166492 -11.599672) (xy 66.174929 -11.602323)
			(xy 66.192599 -11.602323) (xy 66.201036 -11.599672) (xy 66.237216 -11.587135) (xy 66.311248 -11.56756)
			(xy 66.386687 -11.554411) (xy 66.462976 -11.547785) (xy 66.501264 -11.547348) (xy 66.54268 -11.547848)
			(xy 66.625149 -11.555593) (xy 66.706543 -11.570964) (xy 66.786158 -11.593827) (xy 66.863305 -11.623986)
			(xy 66.937318 -11.661178) (xy 66.972688 -11.68273) (xy 66.980074 -11.686987) (xy 66.996689 -11.690769)
			(xy 67.013625 -11.688896) (xy 67.021456 -11.685524) (xy 67.057233 -11.668994) (xy 67.131154 -11.641645)
			(xy 67.207206 -11.620946) (xy 67.284791 -11.607058) (xy 67.363301 -11.600092) (xy 67.40271 -11.599672)
			(xy 67.443826 -11.600089) (xy 67.525707 -11.607677) (xy 67.606539 -11.622789) (xy 67.685632 -11.645294)
			(xy 67.76231 -11.675001) (xy 67.835921 -11.711656) (xy 67.905835 -11.754947) (xy 67.971457 -11.804505)
			(xy 68.032226 -11.859906) (xy 68.087623 -11.920677) (xy 68.137178 -11.986301) (xy 68.180465 -12.056218)
			(xy 68.217117 -12.12983) (xy 68.24682 -12.20651) (xy 68.269321 -12.285604) (xy 68.284429 -12.366436)
			(xy 68.292013 -12.448318) (xy 68.292472 -12.489434) (xy 68.291907 -12.533047) (xy 68.283357 -12.619854)
			(xy 68.266352 -12.705408) (xy 68.241056 -12.788886) (xy 68.207711 -12.869488) (xy 68.195659 -12.892068)
			(xy 70.948547 -12.892068) (xy 70.948547 -12.837532) (xy 70.956309 -12.783551) (xy 70.971673 -12.731225)
			(xy 70.994328 -12.681617) (xy 71.023813 -12.635739) (xy 71.059526 -12.594524) (xy 71.100742 -12.558811)
			(xy 71.146621 -12.529327) (xy 71.196228 -12.506672) (xy 71.248555 -12.491308) (xy 71.302536 -12.483547)
			(xy 71.329804 -12.483084) (xy 72.193404 -12.483084) (xy 72.220676 -12.483479) (xy 72.274666 -12.491242)
			(xy 72.327001 -12.506609) (xy 72.376617 -12.529269) (xy 72.422503 -12.558758) (xy 72.463725 -12.594478)
			(xy 72.499444 -12.6357) (xy 72.528933 -12.681586) (xy 72.551592 -12.731202) (xy 72.566959 -12.783538)
			(xy 72.574721 -12.837528) (xy 72.574721 -12.892072) (xy 72.566959 -12.946062) (xy 72.551592 -12.998398)
			(xy 72.528933 -13.048014) (xy 72.499444 -13.0939) (xy 72.488173 -13.106908) (xy 191.037972 -13.106908)
			(xy 191.03849 -13.065179) (xy 191.046314 -12.98209) (xy 191.061883 -12.900098) (xy 191.085062 -12.819924)
			(xy 191.115646 -12.742273) (xy 191.153367 -12.667827) (xy 191.197893 -12.59724) (xy 191.248833 -12.531132)
			(xy 191.305739 -12.470085) (xy 191.368112 -12.414635) (xy 191.435403 -12.365269) (xy 191.507021 -12.32242)
			(xy 191.582336 -12.286466) (xy 191.660687 -12.257723) (xy 191.700912 -12.24661) (xy 191.713612 -12.243308)
			(xy 191.732408 -12.225274) (xy 191.765936 -12.117578) (xy 191.760348 -12.091924) (xy 191.751712 -12.082018)
			(xy 191.723476 -12.048682) (xy 191.672486 -11.977736) (xy 191.628113 -11.902474) (xy 191.590718 -11.823512)
			(xy 191.560607 -11.741496) (xy 191.538028 -11.657095) (xy 191.523163 -11.571) (xy 191.516135 -11.483915)
			(xy 191.517001 -11.39655) (xy 191.525753 -11.309621) (xy 191.542322 -11.223837) (xy 191.56657 -11.139901)
			(xy 191.5983 -11.058497) (xy 191.637253 -10.980292) (xy 191.683109 -10.905925) (xy 191.735495 -10.836003)
			(xy 191.793982 -10.771099) (xy 191.858092 -10.711742) (xy 191.927301 -10.658417) (xy 192.001043 -10.611562)
			(xy 192.078715 -10.571558) (xy 192.159684 -10.538733) (xy 192.243285 -10.513355) (xy 192.328838 -10.495631)
			(xy 192.415641 -10.485707) (xy 192.502986 -10.483662) (xy 192.590159 -10.489515) (xy 192.676446 -10.503218)
			(xy 192.761144 -10.524657) (xy 192.843559 -10.553659) (xy 192.923018 -10.589985) (xy 192.998871 -10.63334)
			(xy 193.070499 -10.683368) (xy 193.137315 -10.739661) (xy 193.198774 -10.801758) (xy 193.254374 -10.869153)
			(xy 193.303659 -10.941294) (xy 193.346227 -11.017591) (xy 193.381731 -11.097421) (xy 193.409879 -11.180131)
			(xy 193.430442 -11.265046) (xy 193.443252 -11.35147) (xy 193.448204 -11.438699) (xy 193.445257 -11.526018)
			(xy 193.434436 -11.612714) (xy 193.415829 -11.698079) (xy 193.389589 -11.781414) (xy 193.355929 -11.862038)
			(xy 193.315124 -11.939293) (xy 193.267509 -12.012547) (xy 193.213473 -12.081201) (xy 193.153457 -12.144694)
			(xy 193.121026 -12.173966) (xy 193.112347 -12.182457) (xy 193.103466 -12.205016) (xy 193.104008 -12.217146)
			(xy 193.112136 -12.298934) (xy 193.113935 -12.310868) (xy 193.126948 -12.331156) (xy 193.137028 -12.337796)
			(xy 193.137282 -12.33805) (xy 193.173525 -12.359702) (xy 193.242152 -12.408882) (xy 193.305811 -12.464344)
			(xy 193.363928 -12.525589) (xy 193.415979 -12.592065) (xy 193.461498 -12.663174) (xy 193.500073 -12.738277)
			(xy 193.531358 -12.816697) (xy 193.555071 -12.897729) (xy 193.570999 -12.980643) (xy 193.578999 -13.064693)
			(xy 193.579496 -13.106908) (xy 193.579055 -13.148019) (xy 193.571467 -13.22989) (xy 193.556355 -13.310712)
			(xy 193.533849 -13.389794) (xy 193.504141 -13.466462) (xy 193.467484 -13.540061) (xy 193.424192 -13.609963)
			(xy 193.374634 -13.675571) (xy 193.319232 -13.736326) (xy 193.25846 -13.791709) (xy 193.192836 -13.841247)
			(xy 193.122921 -13.884518) (xy 193.049311 -13.921151) (xy 192.972634 -13.950836) (xy 192.893545 -13.973317)
			(xy 192.812719 -13.988404) (xy 192.730845 -13.995968) (xy 192.689734 -13.996416) (xy 192.643339 -13.99582)
			(xy 192.551051 -13.986179) (xy 192.460267 -13.966987) (xy 192.371973 -13.938452) (xy 192.329308 -13.920216)
			(xy 192.319366 -13.91641) (xy 192.298102 -13.91641) (xy 192.28816 -13.920216) (xy 192.245553 -13.938427)
			(xy 192.157387 -13.966948) (xy 192.066733 -13.986143) (xy 191.974574 -13.995806) (xy 191.928242 -13.996416)
			(xy 191.927734 -13.996416) (xy 191.886626 -13.995955) (xy 191.804762 -13.988373) (xy 191.723946 -13.973271)
			(xy 191.644867 -13.950778) (xy 191.568202 -13.921085) (xy 191.494602 -13.884445) (xy 191.424697 -13.841172)
			(xy 191.359082 -13.791634) (xy 191.298317 -13.736254) (xy 191.24292 -13.675504) (xy 191.193365 -13.609903)
			(xy 191.150073 -13.540009) (xy 191.113413 -13.46642) (xy 191.083699 -13.389762) (xy 191.061184 -13.31069)
			(xy 191.04606 -13.229878) (xy 191.038456 -13.148015) (xy 191.037972 -13.106908) (xy 72.488173 -13.106908)
			(xy 72.463725 -13.135122) (xy 72.422503 -13.170842) (xy 72.376617 -13.200331) (xy 72.327001 -13.222991)
			(xy 72.274666 -13.238358) (xy 72.220676 -13.246121) (xy 72.193404 -13.246608) (xy 71.329804 -13.246608)
			(xy 71.302536 -13.246053) (xy 71.248555 -13.238292) (xy 71.196228 -13.222928) (xy 71.146621 -13.200273)
			(xy 71.100742 -13.170789) (xy 71.059526 -13.135076) (xy 71.023813 -13.093861) (xy 70.994328 -13.047983)
			(xy 70.971673 -12.998375) (xy 70.956309 -12.946049) (xy 70.948547 -12.892068) (xy 68.195659 -12.892068)
			(xy 68.166638 -12.946439) (xy 68.118231 -13.019001) (xy 68.062955 -13.086478) (xy 68.00134 -13.14822)
			(xy 67.933978 -13.203636) (xy 67.861516 -13.252193) (xy 67.823334 -13.273278) (xy 67.814055 -13.278811)
			(xy 67.800889 -13.295908) (xy 67.797934 -13.306298) (xy 67.787525 -13.3474) (xy 67.759881 -13.427561)
			(xy 67.724737 -13.504728) (xy 67.682409 -13.578201) (xy 67.633283 -13.647314) (xy 67.577804 -13.711439)
			(xy 67.516475 -13.769995) (xy 67.449854 -13.82245) (xy 67.378544 -13.868328) (xy 67.303192 -13.907213)
			(xy 67.224482 -13.938753) (xy 67.143129 -13.96266) (xy 67.05987 -13.978719) (xy 66.975461 -13.986784)
			(xy 66.933064 -13.987272) (xy 66.894775 -13.986847) (xy 66.818481 -13.980245) (xy 66.743038 -13.967101)
			(xy 66.669007 -13.947513) (xy 66.632836 -13.934948) (xy 66.624399 -13.932297) (xy 66.606729 -13.932297)
			(xy 66.598292 -13.934948) (xy 66.56211 -13.947478) (xy 66.488079 -13.967055) (xy 66.41264 -13.980205)
			(xy 66.336352 -13.986834) (xy 66.298064 -13.987272) (xy 66.254269 -13.986733) (xy 66.167104 -13.978118)
			(xy 66.081208 -13.960975) (xy 65.997414 -13.93547) (xy 65.916534 -13.90185) (xy 65.877694 -13.881608)
			(xy 65.866228 -13.87619) (xy 65.8409 -13.87619) (xy 65.829434 -13.881608) (xy 65.790581 -13.901822)
			(xy 65.709699 -13.935433) (xy 65.625908 -13.96094) (xy 65.540018 -13.978094) (xy 65.452857 -13.986731)
			(xy 65.409064 -13.987272) (xy 65.365269 -13.986733) (xy 65.278104 -13.978118) (xy 65.192208 -13.960975)
			(xy 65.108414 -13.93547) (xy 65.027534 -13.90185) (xy 64.988694 -13.881608) (xy 64.977228 -13.87619)
			(xy 64.9519 -13.87619) (xy 64.940434 -13.881608) (xy 64.901581 -13.901822) (xy 64.820699 -13.935433)
			(xy 64.736908 -13.96094) (xy 64.651018 -13.978094) (xy 64.563857 -13.986731) (xy 64.520064 -13.987272)
			(xy 64.476269 -13.986733) (xy 64.389104 -13.978118) (xy 64.303208 -13.960975) (xy 64.219414 -13.93547)
			(xy 64.138534 -13.90185) (xy 64.099694 -13.881608) (xy 64.088228 -13.87619) (xy 64.0629 -13.87619)
			(xy 64.051434 -13.881608) (xy 64.012581 -13.901822) (xy 63.931699 -13.935433) (xy 63.847908 -13.96094)
			(xy 63.762018 -13.978094) (xy 63.674857 -13.986731) (xy 63.631064 -13.987272) (xy 63.588804 -13.98679)
			(xy 63.504665 -13.978779) (xy 63.421665 -13.962822) (xy 63.340553 -13.939064) (xy 63.26206 -13.907718)
			(xy 63.186895 -13.869068) (xy 63.115735 -13.823463) (xy 63.049222 -13.771312) (xy 62.987956 -13.713088)
			(xy 62.93249 -13.649314) (xy 62.883323 -13.580566) (xy 62.840899 -13.507464) (xy 62.805601 -13.430668)
			(xy 62.777747 -13.35087) (xy 62.757589 -13.268789) (xy 62.750954 -13.22705) (xy 62.748768 -13.216225)
			(xy 62.736658 -13.197787) (xy 62.727586 -13.19149) (xy 62.693115 -13.169417) (xy 62.628004 -13.119803)
			(xy 62.567725 -13.064419) (xy 62.512788 -13.003732) (xy 62.463657 -12.938255) (xy 62.420747 -12.868543)
			(xy 62.384422 -12.795185) (xy 62.354987 -12.7188) (xy 62.332693 -12.640034) (xy 62.317728 -12.559554)
			(xy 62.310218 -12.47804) (xy 62.309756 -12.43711) (xy 1.353372 -12.43711) (xy 1.303061 -12.461339)
			(xy 1.206466 -12.517108) (xy 1.114309 -12.579941) (xy 1.027105 -12.649484) (xy 0.945341 -12.72535)
			(xy 0.869476 -12.807114) (xy 0.801731 -12.892064) (xy 56.95347 -12.892064) (xy 56.95347 -12.837536)
			(xy 56.96123 -12.783562) (xy 56.976591 -12.731243) (xy 56.999242 -12.681641) (xy 57.02872 -12.635768)
			(xy 57.064426 -12.594556) (xy 57.105634 -12.558845) (xy 57.151504 -12.529362) (xy 57.201103 -12.506706)
			(xy 57.253421 -12.491339) (xy 57.307394 -12.483573) (xy 57.334658 -12.483084) (xy 58.198258 -12.483084)
			(xy 58.225534 -12.483453) (xy 58.279532 -12.491211) (xy 58.331876 -12.506575) (xy 58.381501 -12.529233)
			(xy 58.427395 -12.558723) (xy 58.468625 -12.594445) (xy 58.504351 -12.635671) (xy 58.533847 -12.681562)
			(xy 58.55651 -12.731184) (xy 58.57188 -12.783527) (xy 58.579644 -12.837524) (xy 58.579644 -12.892076)
			(xy 58.57188 -12.946073) (xy 58.55651 -12.998416) (xy 58.533847 -13.048037) (xy 58.504351 -13.093929)
			(xy 58.468625 -13.135155) (xy 58.427395 -13.170877) (xy 58.381501 -13.200367) (xy 58.331876 -13.223025)
			(xy 58.279532 -13.238389) (xy 58.225534 -13.246147) (xy 58.198258 -13.246608) (xy 57.334658 -13.246608)
			(xy 57.307394 -13.246027) (xy 57.253421 -13.238261) (xy 57.201103 -13.222894) (xy 57.151504 -13.200238)
			(xy 57.105634 -13.170755) (xy 57.064426 -13.135044) (xy 57.02872 -13.093832) (xy 56.999242 -13.047959)
			(xy 56.976591 -12.998357) (xy 56.96123 -12.946038) (xy 56.95347 -12.892064) (xy 0.801731 -12.892064)
			(xy 0.799933 -12.894318) (xy 0.737102 -12.986476) (xy 0.681333 -13.083072) (xy 0.632939 -13.183565)
			(xy 0.59219 -13.287393) (xy 0.559313 -13.393977) (xy 0.534494 -13.502719) (xy 0.517871 -13.613012)
			(xy 0.509536 -13.724239) (xy 0.509016 -13.780008) (xy 0.509016 -16.5207) (xy 76.28834 -16.5207) (xy 76.29237 -16.436094)
			(xy 76.304425 -16.352254) (xy 76.324394 -16.26994) (xy 76.352098 -16.189896) (xy 76.387284 -16.112849)
			(xy 76.429635 -16.039495) (xy 76.478768 -15.970499) (xy 76.534236 -15.906485) (xy 76.595538 -15.848035)
			(xy 76.662118 -15.795676) (xy 76.733375 -15.749883) (xy 76.808661 -15.711071) (xy 76.887296 -15.679591)
			(xy 76.968567 -15.655728) (xy 77.051738 -15.639698) (xy 77.136057 -15.631648) (xy 77.178408 -15.63116)
			(xy 77.178916 -15.63116) (xy 77.224101 -15.631724) (xy 77.314005 -15.640873) (xy 77.402518 -15.659097)
			(xy 77.488725 -15.686205) (xy 77.530452 -15.70355) (xy 77.539034 -15.706862) (xy 77.557395 -15.707764)
			(xy 77.566266 -15.705328) (xy 77.610936 -15.69133) (xy 77.702468 -15.671687) (xy 77.795557 -15.661772)
			(xy 77.842364 -15.661132) (xy 77.84338 -15.661132) (xy 77.885732 -15.661539) (xy 77.970052 -15.669589)
			(xy 78.053225 -15.685618) (xy 78.134498 -15.70948) (xy 78.213134 -15.74096) (xy 78.288422 -15.779772)
			(xy 78.35968 -15.825565) (xy 78.426262 -15.877924) (xy 78.487566 -15.936376) (xy 78.543035 -16.00039)
			(xy 78.592169 -16.069387) (xy 78.634521 -16.142742) (xy 78.669709 -16.219791) (xy 78.697413 -16.299835)
			(xy 78.717383 -16.382151) (xy 78.722326 -16.416528) (xy 191.571372 -16.416528) (xy 191.571784 -16.378238)
			(xy 191.57839 -16.301944) (xy 191.591537 -16.226502) (xy 191.611129 -16.152471) (xy 191.623696 -16.1163)
			(xy 191.626331 -16.10786) (xy 191.62634 -16.090193) (xy 191.623696 -16.081756) (xy 191.611158 -16.045577)
			(xy 191.591583 -15.971544) (xy 191.578434 -15.896105) (xy 191.571809 -15.819816) (xy 191.571372 -15.781528)
			(xy 191.571879 -15.740418) (xy 191.579464 -15.65855) (xy 191.594572 -15.577731) (xy 191.617074 -15.498651)
			(xy 191.646778 -15.421985) (xy 191.68343 -15.348387) (xy 191.726718 -15.278486) (xy 191.776272 -15.212878)
			(xy 191.831669 -15.152124) (xy 191.892437 -15.096741) (xy 191.958056 -15.047202) (xy 192.027967 -15.00393)
			(xy 192.101573 -14.967295) (xy 192.178246 -14.937609) (xy 192.257331 -14.915125) (xy 192.338154 -14.900036)
			(xy 192.420024 -14.89247) (xy 192.461134 -14.89202) (xy 192.499451 -14.892376) (xy 192.575804 -14.898912)
			(xy 192.651311 -14.912) (xy 192.72541 -14.931543) (xy 192.761616 -14.94409) (xy 192.769932 -14.946676)
			(xy 192.787336 -14.946676) (xy 192.795652 -14.94409) (xy 192.831863 -14.931562) (xy 192.905965 -14.912041)
			(xy 192.981469 -14.898959) (xy 193.057819 -14.892413) (xy 193.096134 -14.89202) (xy 193.134451 -14.892376)
			(xy 193.210804 -14.898912) (xy 193.286311 -14.912) (xy 193.36041 -14.931543) (xy 193.396616 -14.94409)
			(xy 193.404932 -14.946676) (xy 193.422336 -14.946676) (xy 193.430652 -14.94409) (xy 193.466772 -14.93159)
			(xy 193.540685 -14.912102) (xy 193.615997 -14.899021) (xy 193.692153 -14.892442) (xy 193.730372 -14.89202)
			(xy 193.731134 -14.89202) (xy 193.772241 -14.89248) (xy 193.854104 -14.900067) (xy 193.934917 -14.915174)
			(xy 194.013993 -14.937671) (xy 194.090656 -14.967367) (xy 194.164253 -15.004008) (xy 194.234156 -15.047282)
			(xy 194.299769 -15.09682) (xy 194.360532 -15.152199) (xy 194.415928 -15.212948) (xy 194.465484 -15.278547)
			(xy 194.508776 -15.348439) (xy 194.545437 -15.422026) (xy 194.575153 -15.498681) (xy 194.597672 -15.577751)
			(xy 194.6128 -15.658561) (xy 194.620409 -15.740421) (xy 194.620896 -15.781528) (xy 194.620451 -15.819809)
			(xy 194.613795 -15.896082) (xy 194.600605 -15.971499) (xy 194.591178 -16.008604) (xy 194.588893 -16.019174)
			(xy 194.592456 -16.040487) (xy 194.598036 -16.049752) (xy 194.621836 -16.08633) (xy 194.662956 -16.163308)
			(xy 194.696348 -16.24394) (xy 194.721691 -16.327453) (xy 194.738741 -16.413043) (xy 194.747336 -16.499892)
			(xy 194.747896 -16.543528) (xy 194.747474 -16.584639) (xy 194.739884 -16.666511) (xy 194.72477 -16.747333)
			(xy 194.702263 -16.826416) (xy 194.672553 -16.903083) (xy 194.635895 -16.976682) (xy 194.592602 -17.046584)
			(xy 194.543042 -17.112192) (xy 194.487639 -17.172947) (xy 194.426866 -17.22833) (xy 194.361241 -17.277868)
			(xy 194.291325 -17.321138) (xy 194.217714 -17.357772) (xy 194.141037 -17.387456) (xy 194.061947 -17.409938)
			(xy 193.98112 -17.425024) (xy 193.899246 -17.432588) (xy 193.858134 -17.433036) (xy 193.814503 -17.432505)
			(xy 193.727659 -17.42397) (xy 193.642069 -17.40697) (xy 193.558556 -17.381667) (xy 193.477923 -17.348306)
			(xy 193.400945 -17.307207) (xy 193.364358 -17.28343) (xy 193.355108 -17.277824) (xy 193.333785 -17.274289)
			(xy 193.32321 -17.276572) (xy 193.286097 -17.285942) (xy 193.210677 -17.299046) (xy 193.134409 -17.305624)
			(xy 193.096134 -17.306036) (xy 193.057818 -17.305656) (xy 192.981465 -17.299127) (xy 192.905958 -17.286046)
			(xy 192.831859 -17.26651) (xy 192.795652 -17.253966) (xy 192.787336 -17.25138) (xy 192.769932 -17.25138)
			(xy 192.761616 -17.253966) (xy 192.725489 -17.266445) (xy 192.651578 -17.285939) (xy 192.576269 -17.299026)
			(xy 192.500115 -17.305611) (xy 192.461896 -17.306036) (xy 192.461134 -17.306036) (xy 192.420027 -17.305555)
			(xy 192.338163 -17.297973) (xy 192.257348 -17.282872) (xy 192.178271 -17.260379) (xy 192.101606 -17.230687)
			(xy 192.028008 -17.194048) (xy 191.958103 -17.150776) (xy 191.892489 -17.10124) (xy 191.831724 -17.045861)
			(xy 191.776328 -16.985113) (xy 191.726772 -16.919513) (xy 191.683479 -16.849621) (xy 191.646819 -16.776033)
			(xy 191.617104 -16.699377) (xy 191.594588 -16.620307) (xy 191.579463 -16.539496) (xy 191.571857 -16.457635)
			(xy 191.571372 -16.416528) (xy 78.722326 -16.416528) (xy 78.729438 -16.465992) (xy 78.733468 -16.5506)
			(xy 78.729438 -16.635208) (xy 78.717383 -16.719049) (xy 78.697413 -16.801365) (xy 78.669709 -16.881409)
			(xy 78.634521 -16.958458) (xy 78.592169 -17.031813) (xy 78.543035 -17.10081) (xy 78.487566 -17.164824)
			(xy 78.426262 -17.223276) (xy 78.35968 -17.275635) (xy 78.288422 -17.321428) (xy 78.213134 -17.36024)
			(xy 78.134498 -17.39172) (xy 78.053225 -17.415582) (xy 77.970052 -17.431611) (xy 77.885732 -17.439661)
			(xy 77.84338 -17.440148) (xy 77.842872 -17.440148) (xy 77.797687 -17.439588) (xy 77.707782 -17.430437)
			(xy 77.61927 -17.412213) (xy 77.533063 -17.385103) (xy 77.491336 -17.367758) (xy 77.482756 -17.36444)
			(xy 77.464393 -17.363542) (xy 77.455522 -17.36598) (xy 77.410853 -17.379982) (xy 77.319321 -17.399623)
			(xy 77.226231 -17.409537) (xy 77.179424 -17.410176) (xy 77.178408 -17.410176) (xy 77.136057 -17.409752)
			(xy 77.051738 -17.401702) (xy 76.968567 -17.385672) (xy 76.887296 -17.361809) (xy 76.808661 -17.330329)
			(xy 76.733375 -17.291517) (xy 76.662118 -17.245724) (xy 76.595538 -17.193365) (xy 76.534236 -17.134915)
			(xy 76.478768 -17.070901) (xy 76.429635 -17.001905) (xy 76.387284 -16.928551) (xy 76.352098 -16.851504)
			(xy 76.324394 -16.77146) (xy 76.304425 -16.689146) (xy 76.29237 -16.605306) (xy 76.28834 -16.5207)
			(xy 0.509016 -16.5207) (xy 0.509016 -17.639611) (xy 15.152858 -17.639611) (xy 15.152858 -17.585109)
			(xy 15.160614 -17.531161) (xy 15.175969 -17.478867) (xy 15.19861 -17.42929) (xy 15.228076 -17.383439)
			(xy 15.263768 -17.342249) (xy 15.304958 -17.306558) (xy 15.350808 -17.277091) (xy 15.400385 -17.25445)
			(xy 15.452679 -17.239095) (xy 15.506627 -17.231338) (xy 15.533878 -17.230852) (xy 16.397478 -17.230852)
			(xy 16.424731 -17.231315) (xy 16.478682 -17.239072) (xy 16.53098 -17.254428) (xy 16.580561 -17.27707)
			(xy 16.626414 -17.306538) (xy 16.667607 -17.342232) (xy 16.703301 -17.383424) (xy 16.732769 -17.429278)
			(xy 16.755412 -17.478858) (xy 16.770768 -17.531156) (xy 16.778525 -17.585107) (xy 16.778525 -17.639611)
			(xy 20.740858 -17.639611) (xy 20.740858 -17.585109) (xy 20.748614 -17.531161) (xy 20.763969 -17.478867)
			(xy 20.78661 -17.42929) (xy 20.816076 -17.383439) (xy 20.851768 -17.342249) (xy 20.892958 -17.306558)
			(xy 20.938808 -17.277091) (xy 20.988385 -17.25445) (xy 21.040679 -17.239095) (xy 21.094627 -17.231338)
			(xy 21.121878 -17.230852) (xy 21.985478 -17.230852) (xy 22.012729 -17.231394) (xy 22.066677 -17.239147)
			(xy 22.118972 -17.2545) (xy 22.168549 -17.277139) (xy 22.2144 -17.306603) (xy 22.255591 -17.342293)
			(xy 22.291284 -17.383482) (xy 22.320751 -17.429331) (xy 22.343392 -17.478908) (xy 22.358748 -17.531202)
			(xy 22.366505 -17.585149) (xy 22.366505 -17.639651) (xy 22.366505 -17.639653) (xy 26.328838 -17.639653)
			(xy 26.328838 -17.585147) (xy 26.336595 -17.531195) (xy 26.35195 -17.478897) (xy 26.374592 -17.429316)
			(xy 26.404059 -17.383462) (xy 26.439752 -17.342268) (xy 26.480944 -17.306573) (xy 26.526797 -17.277103)
			(xy 26.576376 -17.254458) (xy 26.628674 -17.239099) (xy 26.682625 -17.231339) (xy 26.709878 -17.230852)
			(xy 27.573478 -17.230852) (xy 27.600729 -17.231394) (xy 27.654677 -17.239147) (xy 27.706972 -17.2545)
			(xy 27.756549 -17.277139) (xy 27.8024 -17.306603) (xy 27.843591 -17.342293) (xy 27.879284 -17.383482)
			(xy 27.908751 -17.429331) (xy 27.931392 -17.478908) (xy 27.946748 -17.531202) (xy 27.954505 -17.585149)
			(xy 27.954505 -17.639651) (xy 27.954402 -17.640366) (xy 31.915646 -17.640366) (xy 31.915646 -17.585834)
			(xy 31.923406 -17.531857) (xy 31.938769 -17.479533) (xy 31.961421 -17.429928) (xy 31.990902 -17.384052)
			(xy 32.026611 -17.342838) (xy 32.067822 -17.307125) (xy 32.113695 -17.277639) (xy 32.163298 -17.254982)
			(xy 32.21562 -17.239615) (xy 32.269596 -17.231849) (xy 32.296862 -17.23136) (xy 33.160462 -17.23136)
			(xy 33.187736 -17.231777) (xy 33.24173 -17.239535) (xy 33.294071 -17.254899) (xy 33.343691 -17.277556)
			(xy 33.389583 -17.307044) (xy 33.43081 -17.342764) (xy 33.466533 -17.383987) (xy 33.496026 -17.429875)
			(xy 33.518688 -17.479494) (xy 33.534057 -17.531832) (xy 33.54182 -17.585826) (xy 33.54182 -17.640366)
			(xy 37.503646 -17.640366) (xy 37.503646 -17.585834) (xy 37.511406 -17.531857) (xy 37.526769 -17.479533)
			(xy 37.549421 -17.429928) (xy 37.578902 -17.384052) (xy 37.614611 -17.342838) (xy 37.655822 -17.307125)
			(xy 37.701695 -17.277639) (xy 37.751298 -17.254982) (xy 37.80362 -17.239615) (xy 37.857596 -17.231849)
			(xy 37.884862 -17.23136) (xy 38.748462 -17.23136) (xy 38.775736 -17.231777) (xy 38.82973 -17.239535)
			(xy 38.882071 -17.254899) (xy 38.931691 -17.277556) (xy 38.977583 -17.307044) (xy 39.01881 -17.342764)
			(xy 39.054533 -17.383987) (xy 39.084026 -17.429875) (xy 39.106688 -17.479494) (xy 39.122057 -17.531832)
			(xy 39.12982 -17.585826) (xy 39.12982 -17.639654) (xy 43.398638 -17.639654) (xy 43.398638 -17.585146)
			(xy 43.406395 -17.531193) (xy 43.421751 -17.478894) (xy 43.444395 -17.429312) (xy 43.473863 -17.383457)
			(xy 43.509558 -17.342262) (xy 43.550752 -17.306567) (xy 43.596606 -17.277097) (xy 43.646188 -17.254454)
			(xy 43.698487 -17.239096) (xy 43.75244 -17.231338) (xy 43.779694 -17.230852) (xy 44.643294 -17.230852)
			(xy 44.670544 -17.231395) (xy 44.72449 -17.23915) (xy 44.776783 -17.254504) (xy 44.826359 -17.277144)
			(xy 44.872208 -17.306609) (xy 44.913397 -17.342299) (xy 44.949088 -17.383487) (xy 44.978553 -17.429336)
			(xy 45.001194 -17.478911) (xy 45.016548 -17.531204) (xy 45.024305 -17.58515) (xy 45.024305 -17.63965)
			(xy 45.024304 -17.639654) (xy 48.986638 -17.639654) (xy 48.986638 -17.585146) (xy 48.994395 -17.531193)
			(xy 49.009751 -17.478894) (xy 49.032395 -17.429312) (xy 49.061863 -17.383457) (xy 49.097558 -17.342262)
			(xy 49.138752 -17.306567) (xy 49.184606 -17.277097) (xy 49.234188 -17.254454) (xy 49.286487 -17.239096)
			(xy 49.34044 -17.231338) (xy 49.367694 -17.230852) (xy 50.231294 -17.230852) (xy 50.258544 -17.231395)
			(xy 50.31249 -17.23915) (xy 50.364783 -17.254504) (xy 50.414359 -17.277144) (xy 50.460208 -17.306609)
			(xy 50.501397 -17.342299) (xy 50.537088 -17.383487) (xy 50.566553 -17.429336) (xy 50.589194 -17.478911)
			(xy 50.604548 -17.531204) (xy 50.612305 -17.58515) (xy 50.612305 -17.63965) (xy 50.612201 -17.64037)
			(xy 54.607423 -17.64037) (xy 54.607423 -17.58583) (xy 54.615186 -17.531845) (xy 54.630552 -17.479514)
			(xy 54.653209 -17.429903) (xy 54.682696 -17.384021) (xy 54.718413 -17.342803) (xy 54.759632 -17.307088)
			(xy 54.805515 -17.277602) (xy 54.855127 -17.254947) (xy 54.907459 -17.239583) (xy 54.961444 -17.231822)
			(xy 54.988714 -17.23136) (xy 55.852314 -17.23136) (xy 55.879584 -17.231803) (xy 55.933569 -17.239567)
			(xy 55.9859 -17.254935) (xy 56.035512 -17.277593) (xy 56.081393 -17.307081) (xy 56.122612 -17.342798)
			(xy 56.158328 -17.384018) (xy 56.187814 -17.429901) (xy 56.21047 -17.479513) (xy 56.225836 -17.531844)
			(xy 56.233598 -17.58583) (xy 56.233598 -17.64037) (xy 56.225836 -17.694356) (xy 56.21047 -17.746687)
			(xy 56.187814 -17.796299) (xy 56.158328 -17.842182) (xy 56.122612 -17.883402) (xy 56.081393 -17.919119)
			(xy 56.035512 -17.948607) (xy 55.9859 -17.971265) (xy 55.933569 -17.986633) (xy 55.879584 -17.994397)
			(xy 55.852314 -17.994884) (xy 54.988714 -17.994884) (xy 54.961444 -17.994378) (xy 54.907459 -17.986617)
			(xy 54.855127 -17.971253) (xy 54.805515 -17.948598) (xy 54.759632 -17.919112) (xy 54.718413 -17.883397)
			(xy 54.682696 -17.842179) (xy 54.653209 -17.796297) (xy 54.630552 -17.746686) (xy 54.615186 -17.694355)
			(xy 54.607423 -17.64037) (xy 50.612201 -17.64037) (xy 50.604548 -17.693596) (xy 50.589194 -17.745889)
			(xy 50.566553 -17.795464) (xy 50.537088 -17.841313) (xy 50.501397 -17.882501) (xy 50.460208 -17.918191)
			(xy 50.414359 -17.947656) (xy 50.364783 -17.970296) (xy 50.31249 -17.98565) (xy 50.258544 -17.993405)
			(xy 50.231294 -17.993868) (xy 49.367694 -17.993868) (xy 49.34044 -17.993462) (xy 49.286487 -17.985704)
			(xy 49.234188 -17.970346) (xy 49.184606 -17.947703) (xy 49.138752 -17.918233) (xy 49.097558 -17.882538)
			(xy 49.061863 -17.841343) (xy 49.032395 -17.795488) (xy 49.009751 -17.745906) (xy 48.994395 -17.693607)
			(xy 48.986638 -17.639654) (xy 45.024304 -17.639654) (xy 45.016548 -17.693596) (xy 45.001194 -17.745889)
			(xy 44.978553 -17.795464) (xy 44.949088 -17.841313) (xy 44.913397 -17.882501) (xy 44.872208 -17.918191)
			(xy 44.826359 -17.947656) (xy 44.776783 -17.970296) (xy 44.72449 -17.98565) (xy 44.670544 -17.993405)
			(xy 44.643294 -17.993868) (xy 43.779694 -17.993868) (xy 43.75244 -17.993462) (xy 43.698487 -17.985704)
			(xy 43.646188 -17.970346) (xy 43.596606 -17.947703) (xy 43.550752 -17.918233) (xy 43.509558 -17.882538)
			(xy 43.473863 -17.841343) (xy 43.444395 -17.795488) (xy 43.421751 -17.745906) (xy 43.406395 -17.693607)
			(xy 43.398638 -17.639654) (xy 39.12982 -17.639654) (xy 39.12982 -17.640374) (xy 39.122057 -17.694368)
			(xy 39.106688 -17.746706) (xy 39.084026 -17.796325) (xy 39.054533 -17.842213) (xy 39.01881 -17.883436)
			(xy 38.977583 -17.919156) (xy 38.931691 -17.948644) (xy 38.882071 -17.971301) (xy 38.82973 -17.986665)
			(xy 38.775736 -17.994423) (xy 38.748462 -17.994884) (xy 37.884862 -17.994884) (xy 37.857596 -17.994351)
			(xy 37.80362 -17.986585) (xy 37.751298 -17.971218) (xy 37.701695 -17.948561) (xy 37.655822 -17.919075)
			(xy 37.614611 -17.883362) (xy 37.578902 -17.842148) (xy 37.549421 -17.796272) (xy 37.526769 -17.746667)
			(xy 37.511406 -17.694343) (xy 37.503646 -17.640366) (xy 33.54182 -17.640366) (xy 33.54182 -17.640374)
			(xy 33.534057 -17.694368) (xy 33.518688 -17.746706) (xy 33.496026 -17.796325) (xy 33.466533 -17.842213)
			(xy 33.43081 -17.883436) (xy 33.389583 -17.919156) (xy 33.343691 -17.948644) (xy 33.294071 -17.971301)
			(xy 33.24173 -17.986665) (xy 33.187736 -17.994423) (xy 33.160462 -17.994884) (xy 32.296862 -17.994884)
			(xy 32.269596 -17.994351) (xy 32.21562 -17.986585) (xy 32.163298 -17.971218) (xy 32.113695 -17.948561)
			(xy 32.067822 -17.919075) (xy 32.026611 -17.883362) (xy 31.990902 -17.842148) (xy 31.961421 -17.796272)
			(xy 31.938769 -17.746667) (xy 31.923406 -17.694343) (xy 31.915646 -17.640366) (xy 27.954402 -17.640366)
			(xy 27.946748 -17.693598) (xy 27.931392 -17.745892) (xy 27.908751 -17.795469) (xy 27.879284 -17.841318)
			(xy 27.843591 -17.882507) (xy 27.8024 -17.918197) (xy 27.756549 -17.947661) (xy 27.706972 -17.9703)
			(xy 27.654677 -17.985653) (xy 27.600729 -17.993406) (xy 27.573478 -17.993868) (xy 26.709878 -17.993868)
			(xy 26.682625 -17.993461) (xy 26.628674 -17.985701) (xy 26.576376 -17.970342) (xy 26.526797 -17.947697)
			(xy 26.480944 -17.918227) (xy 26.439752 -17.882532) (xy 26.404059 -17.841338) (xy 26.374592 -17.795484)
			(xy 26.35195 -17.745903) (xy 26.336595 -17.693605) (xy 26.328838 -17.639653) (xy 22.366505 -17.639653)
			(xy 22.358748 -17.693598) (xy 22.343392 -17.745892) (xy 22.320751 -17.795469) (xy 22.291284 -17.841318)
			(xy 22.255591 -17.882507) (xy 22.2144 -17.918197) (xy 22.168549 -17.947661) (xy 22.118972 -17.9703)
			(xy 22.066677 -17.985653) (xy 22.012729 -17.993406) (xy 21.985478 -17.993868) (xy 21.121878 -17.993868)
			(xy 21.094627 -17.993382) (xy 21.040679 -17.985625) (xy 20.988385 -17.97027) (xy 20.938808 -17.947629)
			(xy 20.892958 -17.918162) (xy 20.851768 -17.882471) (xy 20.816076 -17.841281) (xy 20.78661 -17.79543)
			(xy 20.763969 -17.745853) (xy 20.748614 -17.693559) (xy 20.740858 -17.639611) (xy 16.778525 -17.639611)
			(xy 16.778525 -17.639613) (xy 16.770768 -17.693564) (xy 16.755412 -17.745862) (xy 16.732769 -17.795442)
			(xy 16.703301 -17.841296) (xy 16.667607 -17.882488) (xy 16.626414 -17.918182) (xy 16.580561 -17.94765)
			(xy 16.53098 -17.970292) (xy 16.478682 -17.985648) (xy 16.424731 -17.993405) (xy 16.397478 -17.993868)
			(xy 15.533878 -17.993868) (xy 15.506627 -17.993382) (xy 15.452679 -17.985625) (xy 15.400385 -17.97027)
			(xy 15.350808 -17.947629) (xy 15.304958 -17.918162) (xy 15.263768 -17.882471) (xy 15.228076 -17.841281)
			(xy 15.19861 -17.79543) (xy 15.175969 -17.745853) (xy 15.160614 -17.693559) (xy 15.152858 -17.639611)
			(xy 0.509016 -17.639611) (xy 0.509016 -19.164391) (xy 17.945563 -19.164391) (xy 17.945563 -19.109849)
			(xy 17.953326 -19.055862) (xy 17.968692 -19.00353) (xy 17.99135 -18.953917) (xy 18.020837 -18.908033)
			(xy 18.056555 -18.866813) (xy 18.097775 -18.831096) (xy 18.143658 -18.801609) (xy 18.193272 -18.778951)
			(xy 18.245604 -18.763585) (xy 18.299591 -18.755823) (xy 18.326862 -18.75536) (xy 19.190462 -18.75536)
			(xy 19.217731 -18.755843) (xy 19.271715 -18.763605) (xy 19.324045 -18.77897) (xy 19.373655 -18.801627)
			(xy 19.419536 -18.831113) (xy 19.460753 -18.866828) (xy 19.496469 -18.908046) (xy 19.525954 -18.953927)
			(xy 19.548611 -19.003537) (xy 19.563976 -19.055867) (xy 19.571738 -19.109851) (xy 19.571738 -19.163653)
			(xy 23.534838 -19.163653) (xy 23.534838 -19.109147) (xy 23.542595 -19.055195) (xy 23.55795 -19.002897)
			(xy 23.580592 -18.953316) (xy 23.610059 -18.907462) (xy 23.645752 -18.866268) (xy 23.686944 -18.830573)
			(xy 23.732797 -18.801103) (xy 23.782376 -18.778458) (xy 23.834674 -18.763099) (xy 23.888625 -18.755339)
			(xy 23.915878 -18.754852) (xy 24.779478 -18.754852) (xy 24.806729 -18.755394) (xy 24.860677 -18.763147)
			(xy 24.912972 -18.7785) (xy 24.962549 -18.801139) (xy 25.0084 -18.830603) (xy 25.049591 -18.866293)
			(xy 25.085284 -18.907482) (xy 25.114751 -18.953331) (xy 25.137392 -19.002908) (xy 25.152748 -19.055202)
			(xy 25.160505 -19.109149) (xy 25.160505 -19.163651) (xy 25.160505 -19.163653) (xy 29.122838 -19.163653)
			(xy 29.122838 -19.109147) (xy 29.130595 -19.055195) (xy 29.14595 -19.002897) (xy 29.168592 -18.953316)
			(xy 29.198059 -18.907462) (xy 29.233752 -18.866268) (xy 29.274944 -18.830573) (xy 29.320797 -18.801103)
			(xy 29.370376 -18.778458) (xy 29.422674 -18.763099) (xy 29.476625 -18.755339) (xy 29.503878 -18.754852)
			(xy 30.367478 -18.754852) (xy 30.394729 -18.755394) (xy 30.448677 -18.763147) (xy 30.500972 -18.7785)
			(xy 30.550549 -18.801139) (xy 30.5964 -18.830603) (xy 30.637591 -18.866293) (xy 30.673284 -18.907482)
			(xy 30.702751 -18.953331) (xy 30.725392 -19.002908) (xy 30.740748 -19.055202) (xy 30.748505 -19.109149)
			(xy 30.748505 -19.163651) (xy 30.748505 -19.163653) (xy 34.710838 -19.163653) (xy 34.710838 -19.109147)
			(xy 34.718595 -19.055195) (xy 34.73395 -19.002897) (xy 34.756592 -18.953316) (xy 34.786059 -18.907462)
			(xy 34.821752 -18.866268) (xy 34.862944 -18.830573) (xy 34.908797 -18.801103) (xy 34.958376 -18.778458)
			(xy 35.010674 -18.763099) (xy 35.064625 -18.755339) (xy 35.091878 -18.754852) (xy 35.955478 -18.754852)
			(xy 35.982729 -18.755394) (xy 36.036677 -18.763147) (xy 36.088972 -18.7785) (xy 36.138549 -18.801139)
			(xy 36.1844 -18.830603) (xy 36.225591 -18.866293) (xy 36.261284 -18.907482) (xy 36.290751 -18.953331)
			(xy 36.313392 -19.002908) (xy 36.328748 -19.055202) (xy 36.336505 -19.109149) (xy 36.336505 -19.163651)
			(xy 36.336505 -19.163654) (xy 40.604638 -19.163654) (xy 40.604638 -19.109146) (xy 40.612395 -19.055193)
			(xy 40.627751 -19.002894) (xy 40.650395 -18.953312) (xy 40.679863 -18.907457) (xy 40.715558 -18.866262)
			(xy 40.756752 -18.830567) (xy 40.802606 -18.801097) (xy 40.852188 -18.778454) (xy 40.904487 -18.763096)
			(xy 40.95844 -18.755338) (xy 40.985694 -18.754852) (xy 41.849294 -18.754852) (xy 41.876544 -18.755395)
			(xy 41.93049 -18.76315) (xy 41.982783 -18.778504) (xy 42.032359 -18.801144) (xy 42.078208 -18.830609)
			(xy 42.119397 -18.866299) (xy 42.155088 -18.907487) (xy 42.184553 -18.953336) (xy 42.207194 -19.002911)
			(xy 42.222548 -19.055204) (xy 42.230305 -19.10915) (xy 42.230305 -19.16365) (xy 42.230202 -19.164367)
			(xy 46.191446 -19.164367) (xy 46.191446 -19.109833) (xy 46.199207 -19.055855) (xy 46.21457 -19.00353)
			(xy 46.237224 -18.953924) (xy 46.266706 -18.908047) (xy 46.302417 -18.866832) (xy 46.343629 -18.831119)
			(xy 46.389505 -18.801634) (xy 46.439109 -18.778978) (xy 46.491433 -18.763612) (xy 46.545411 -18.755848)
			(xy 46.572678 -18.75536) (xy 47.436278 -18.75536) (xy 47.463552 -18.755778) (xy 47.517544 -18.763538)
			(xy 47.569882 -18.778903) (xy 47.619501 -18.801561) (xy 47.66539 -18.83105) (xy 47.706615 -18.866769)
			(xy 47.742337 -18.907992) (xy 47.771828 -18.95388) (xy 47.794489 -19.003497) (xy 47.809857 -19.055835)
			(xy 47.81762 -19.109826) (xy 47.81762 -19.163657) (xy 51.814615 -19.163657) (xy 51.814615 -19.109143)
			(xy 51.822374 -19.055184) (xy 51.837733 -19.002878) (xy 51.86038 -18.95329) (xy 51.889854 -18.907431)
			(xy 51.925554 -18.866233) (xy 51.966755 -18.830536) (xy 52.012617 -18.801065) (xy 52.062206 -18.778422)
			(xy 52.114513 -18.763067) (xy 52.168473 -18.755313) (xy 52.19573 -18.754852) (xy 53.05933 -18.754852)
			(xy 53.086577 -18.75542) (xy 53.140516 -18.763179) (xy 53.192801 -18.778535) (xy 53.24237 -18.801176)
			(xy 53.288211 -18.83064) (xy 53.329394 -18.866328) (xy 53.365078 -18.907513) (xy 53.394538 -18.953357)
			(xy 53.417175 -19.002927) (xy 53.432527 -19.055214) (xy 53.440282 -19.109153) (xy 53.440282 -19.163647)
			(xy 53.440281 -19.163657) (xy 57.402615 -19.163657) (xy 57.402615 -19.109143) (xy 57.410374 -19.055184)
			(xy 57.425733 -19.002878) (xy 57.44838 -18.95329) (xy 57.477854 -18.907431) (xy 57.513554 -18.866233)
			(xy 57.554755 -18.830536) (xy 57.600617 -18.801065) (xy 57.650206 -18.778422) (xy 57.702513 -18.763067)
			(xy 57.756473 -18.755313) (xy 57.78373 -18.754852) (xy 58.64733 -18.754852) (xy 58.674577 -18.75542)
			(xy 58.728516 -18.763179) (xy 58.780801 -18.778535) (xy 58.83037 -18.801176) (xy 58.876211 -18.83064)
			(xy 58.917394 -18.866328) (xy 58.953078 -18.907513) (xy 58.982538 -18.953357) (xy 59.005175 -19.002927)
			(xy 59.020527 -19.055214) (xy 59.028282 -19.109153) (xy 59.028282 -19.163647) (xy 59.020527 -19.217586)
			(xy 59.005175 -19.269873) (xy 58.982538 -19.319443) (xy 58.953078 -19.365287) (xy 58.917394 -19.406472)
			(xy 58.876211 -19.44216) (xy 58.83037 -19.471624) (xy 58.780801 -19.494265) (xy 58.728516 -19.509621)
			(xy 58.674577 -19.51738) (xy 58.64733 -19.517868) (xy 57.78373 -19.517868) (xy 57.756473 -19.517487)
			(xy 57.702513 -19.509733) (xy 57.650206 -19.494378) (xy 57.600617 -19.471735) (xy 57.554755 -19.442264)
			(xy 57.513554 -19.406567) (xy 57.477854 -19.365369) (xy 57.44838 -19.31951) (xy 57.425733 -19.269922)
			(xy 57.410374 -19.217616) (xy 57.402615 -19.163657) (xy 53.440281 -19.163657) (xy 53.432527 -19.217586)
			(xy 53.417175 -19.269873) (xy 53.394538 -19.319443) (xy 53.365078 -19.365287) (xy 53.329394 -19.406472)
			(xy 53.288211 -19.44216) (xy 53.24237 -19.471624) (xy 53.192801 -19.494265) (xy 53.140516 -19.509621)
			(xy 53.086577 -19.51738) (xy 53.05933 -19.517868) (xy 52.19573 -19.517868) (xy 52.168473 -19.517487)
			(xy 52.114513 -19.509733) (xy 52.062206 -19.494378) (xy 52.012617 -19.471735) (xy 51.966755 -19.442264)
			(xy 51.925554 -19.406567) (xy 51.889854 -19.365369) (xy 51.86038 -19.31951) (xy 51.837733 -19.269922)
			(xy 51.822374 -19.217616) (xy 51.814615 -19.163657) (xy 47.81762 -19.163657) (xy 47.81762 -19.164374)
			(xy 47.809857 -19.218365) (xy 47.794489 -19.270703) (xy 47.771828 -19.32032) (xy 47.742337 -19.366208)
			(xy 47.706615 -19.407431) (xy 47.66539 -19.44315) (xy 47.619501 -19.472639) (xy 47.569882 -19.495297)
			(xy 47.517544 -19.510662) (xy 47.463552 -19.518422) (xy 47.436278 -19.518884) (xy 46.572678 -19.518884)
			(xy 46.545411 -19.518352) (xy 46.491433 -19.510588) (xy 46.439109 -19.495222) (xy 46.389505 -19.472566)
			(xy 46.343629 -19.443081) (xy 46.302417 -19.407368) (xy 46.266706 -19.366153) (xy 46.237224 -19.320276)
			(xy 46.21457 -19.27067) (xy 46.199207 -19.218345) (xy 46.191446 -19.164367) (xy 42.230202 -19.164367)
			(xy 42.222548 -19.217596) (xy 42.207194 -19.269889) (xy 42.184553 -19.319464) (xy 42.155088 -19.365313)
			(xy 42.119397 -19.406501) (xy 42.078208 -19.442191) (xy 42.032359 -19.471656) (xy 41.982783 -19.494296)
			(xy 41.93049 -19.50965) (xy 41.876544 -19.517405) (xy 41.849294 -19.517868) (xy 40.985694 -19.517868)
			(xy 40.95844 -19.517462) (xy 40.904487 -19.509704) (xy 40.852188 -19.494346) (xy 40.802606 -19.471703)
			(xy 40.756752 -19.442233) (xy 40.715558 -19.406538) (xy 40.679863 -19.365343) (xy 40.650395 -19.319488)
			(xy 40.627751 -19.269906) (xy 40.612395 -19.217607) (xy 40.604638 -19.163654) (xy 36.336505 -19.163654)
			(xy 36.328748 -19.217598) (xy 36.313392 -19.269892) (xy 36.290751 -19.319469) (xy 36.261284 -19.365318)
			(xy 36.225591 -19.406507) (xy 36.1844 -19.442197) (xy 36.138549 -19.471661) (xy 36.088972 -19.4943)
			(xy 36.036677 -19.509653) (xy 35.982729 -19.517406) (xy 35.955478 -19.517868) (xy 35.091878 -19.517868)
			(xy 35.064625 -19.517461) (xy 35.010674 -19.509701) (xy 34.958376 -19.494342) (xy 34.908797 -19.471697)
			(xy 34.862944 -19.442227) (xy 34.821752 -19.406532) (xy 34.786059 -19.365338) (xy 34.756592 -19.319484)
			(xy 34.73395 -19.269903) (xy 34.718595 -19.217605) (xy 34.710838 -19.163653) (xy 30.748505 -19.163653)
			(xy 30.740748 -19.217598) (xy 30.725392 -19.269892) (xy 30.702751 -19.319469) (xy 30.673284 -19.365318)
			(xy 30.637591 -19.406507) (xy 30.5964 -19.442197) (xy 30.550549 -19.471661) (xy 30.500972 -19.4943)
			(xy 30.448677 -19.509653) (xy 30.394729 -19.517406) (xy 30.367478 -19.517868) (xy 29.503878 -19.517868)
			(xy 29.476625 -19.517461) (xy 29.422674 -19.509701) (xy 29.370376 -19.494342) (xy 29.320797 -19.471697)
			(xy 29.274944 -19.442227) (xy 29.233752 -19.406532) (xy 29.198059 -19.365338) (xy 29.168592 -19.319484)
			(xy 29.14595 -19.269903) (xy 29.130595 -19.217605) (xy 29.122838 -19.163653) (xy 25.160505 -19.163653)
			(xy 25.152748 -19.217598) (xy 25.137392 -19.269892) (xy 25.114751 -19.319469) (xy 25.085284 -19.365318)
			(xy 25.049591 -19.406507) (xy 25.0084 -19.442197) (xy 24.962549 -19.471661) (xy 24.912972 -19.4943)
			(xy 24.860677 -19.509653) (xy 24.806729 -19.517406) (xy 24.779478 -19.517868) (xy 23.915878 -19.517868)
			(xy 23.888625 -19.517461) (xy 23.834674 -19.509701) (xy 23.782376 -19.494342) (xy 23.732797 -19.471697)
			(xy 23.686944 -19.442227) (xy 23.645752 -19.406532) (xy 23.610059 -19.365338) (xy 23.580592 -19.319484)
			(xy 23.55795 -19.269903) (xy 23.542595 -19.217605) (xy 23.534838 -19.163653) (xy 19.571738 -19.163653)
			(xy 19.571738 -19.164389) (xy 19.563976 -19.218373) (xy 19.548611 -19.270703) (xy 19.525954 -19.320313)
			(xy 19.496469 -19.366194) (xy 19.460753 -19.407412) (xy 19.419536 -19.443127) (xy 19.373655 -19.472613)
			(xy 19.324045 -19.49527) (xy 19.271715 -19.510635) (xy 19.217731 -19.518397) (xy 19.190462 -19.518884)
			(xy 18.326862 -19.518884) (xy 18.299591 -19.518417) (xy 18.245604 -19.510655) (xy 18.193272 -19.495289)
			(xy 18.143658 -19.472631) (xy 18.097775 -19.443144) (xy 18.056555 -19.407427) (xy 18.020837 -19.366207)
			(xy 17.99135 -19.320323) (xy 17.968692 -19.27071) (xy 17.953326 -19.218378) (xy 17.945563 -19.164391)
			(xy 0.509016 -19.164391) (xy 0.509016 -20.327366) (xy 65.88506 -20.327366) (xy 65.885484 -20.289077)
			(xy 65.892086 -20.212783) (xy 65.90523 -20.13734) (xy 65.924819 -20.063309) (xy 65.937384 -20.027138)
			(xy 65.940051 -20.018705) (xy 65.94004 -20.001031) (xy 65.937384 -19.992594) (xy 65.924856 -19.956411)
			(xy 65.905279 -19.88238) (xy 65.892127 -19.806942) (xy 65.885498 -19.730654) (xy 65.88506 -19.692366)
			(xy 65.885582 -19.650174) (xy 65.893576 -19.56617) (xy 65.909488 -19.483301) (xy 65.933176 -19.402311)
			(xy 65.964427 -19.323927) (xy 66.00296 -19.248856) (xy 66.048429 -19.17777) (xy 66.074036 -19.144234)
			(xy 66.079883 -19.13601) (xy 66.085128 -19.116537) (xy 66.082515 -19.096539) (xy 66.077846 -19.087592)
			(xy 66.058798 -19.053767) (xy 66.026006 -18.983399) (xy 65.999468 -18.910441) (xy 65.979384 -18.83545)
			(xy 65.965909 -18.758994) (xy 65.959144 -18.681655) (xy 65.95872 -18.642838) (xy 65.95872 -18.642584)
			(xy 65.959137 -18.60148) (xy 65.966724 -18.519622) (xy 65.981831 -18.438814) (xy 66.00433 -18.359744)
			(xy 66.034029 -18.283087) (xy 66.070674 -18.209498) (xy 66.113953 -18.139604) (xy 66.163496 -18.074001)
			(xy 66.218881 -18.01325) (xy 66.279635 -17.957868) (xy 66.34524 -17.908328) (xy 66.415137 -17.865053)
			(xy 66.488728 -17.828411) (xy 66.565386 -17.798716) (xy 66.644456 -17.776221) (xy 66.725266 -17.761118)
			(xy 66.807124 -17.753535) (xy 66.848228 -17.753076) (xy 66.889911 -17.753577) (xy 66.972911 -17.761363)
			(xy 67.054819 -17.776882) (xy 67.134915 -17.799999) (xy 67.212496 -17.830511) (xy 67.286881 -17.868149)
			(xy 67.357417 -17.912584) (xy 67.423485 -17.963425) (xy 67.484504 -18.020226) (xy 67.53994 -18.082488)
			(xy 67.565016 -18.115788) (xy 67.56527 -18.116042) (xy 67.570757 -18.122776) (xy 67.585223 -18.132372)
			(xy 67.602063 -18.136587) (xy 67.610736 -18.136108) (xy 67.697858 -18.127726) (xy 67.706567 -18.126584)
			(xy 67.722478 -18.119178) (xy 67.734922 -18.1068) (xy 67.739006 -18.099024) (xy 67.739006 -18.098516)
			(xy 67.757258 -18.060702) (xy 67.799884 -17.988356) (xy 67.849141 -17.920351) (xy 67.90459 -17.857291)
			(xy 67.965736 -17.79974) (xy 68.032035 -17.748209) (xy 68.102897 -17.703158) (xy 68.17769 -17.664987)
			(xy 68.255748 -17.634037) (xy 68.336377 -17.610583) (xy 68.418857 -17.594835) (xy 68.502455 -17.586933)
			(xy 68.54444 -17.586452) (xy 68.5868 -17.58693) (xy 68.671136 -17.594986) (xy 68.754325 -17.611023)
			(xy 68.835612 -17.634895) (xy 68.914262 -17.666384) (xy 68.989563 -17.705208) (xy 69.060833 -17.751013)
			(xy 69.127426 -17.803385) (xy 69.18874 -17.86185) (xy 69.244218 -17.925878) (xy 69.293359 -17.99489)
			(xy 69.335718 -18.068261) (xy 69.370911 -18.145325) (xy 69.39862 -18.225386) (xy 69.401856 -18.238724)
			(xy 79.0321 -18.238724) (xy 79.032651 -18.193954) (xy 79.041664 -18.104869) (xy 79.059573 -18.017137)
			(xy 79.086195 -17.931647) (xy 79.10322 -17.890236) (xy 79.106772 -17.880641) (xy 79.106781 -17.860202)
			(xy 79.10322 -17.850612) (xy 79.086184 -17.809205) (xy 79.059551 -17.723717) (xy 79.041646 -17.635983)
			(xy 79.032653 -17.546895) (xy 79.0321 -17.502124) (xy 79.032604 -17.459763) (xy 79.040657 -17.375426)
			(xy 79.056691 -17.292236) (xy 79.080559 -17.210946) (xy 79.112047 -17.132294) (xy 79.150869 -17.056991)
			(xy 79.196672 -16.985719) (xy 79.249043 -16.919123) (xy 79.307508 -16.857808) (xy 79.371536 -16.802327)
			(xy 79.440548 -16.753184) (xy 79.513918 -16.710824) (xy 79.590983 -16.675629) (xy 79.671045 -16.64792)
			(xy 79.753378 -16.627946) (xy 79.837237 -16.615889) (xy 79.921862 -16.611858) (xy 80.006487 -16.615889)
			(xy 80.090346 -16.627946) (xy 80.172679 -16.64792) (xy 80.252741 -16.675629) (xy 80.329806 -16.710824)
			(xy 80.403176 -16.753184) (xy 80.472188 -16.802327) (xy 80.536216 -16.857808) (xy 80.594681 -16.919123)
			(xy 80.647052 -16.985719) (xy 80.692855 -17.056991) (xy 80.731677 -17.132294) (xy 80.763165 -17.210946)
			(xy 80.787033 -17.292236) (xy 80.803067 -17.375426) (xy 80.81112 -17.459763) (xy 80.811624 -17.502124)
			(xy 80.811054 -17.546893) (xy 80.802046 -17.635978) (xy 80.784143 -17.723709) (xy 80.757526 -17.809201)
			(xy 80.740504 -17.850612) (xy 80.736924 -17.860198) (xy 80.736933 -17.880645) (xy 80.740504 -17.890236)
			(xy 80.757551 -17.931638) (xy 80.784182 -18.017129) (xy 80.802084 -18.104863) (xy 80.808854 -18.171951)
			(xy 131.633699 -18.171951) (xy 131.633699 -18.117449) (xy 131.641456 -18.063503) (xy 131.656811 -18.011209)
			(xy 131.679453 -17.961633) (xy 131.708919 -17.915784) (xy 131.744611 -17.874596) (xy 131.785802 -17.838906)
			(xy 131.831653 -17.809442) (xy 131.88123 -17.786804) (xy 131.933524 -17.771451) (xy 131.987471 -17.763698)
			(xy 132.014722 -17.763236) (xy 132.878322 -17.763236) (xy 132.905575 -17.763635) (xy 132.959527 -17.771395)
			(xy 133.011825 -17.786754) (xy 133.061405 -17.809399) (xy 133.107258 -17.838869) (xy 133.148451 -17.874565)
			(xy 133.184144 -17.915759) (xy 133.213611 -17.961614) (xy 133.236254 -18.011196) (xy 133.251609 -18.063495)
			(xy 133.259366 -18.117447) (xy 133.259366 -18.171946) (xy 137.033822 -18.171946) (xy 137.033822 -18.117454)
			(xy 137.041577 -18.063516) (xy 137.056928 -18.01123) (xy 137.079564 -17.961661) (xy 137.109023 -17.915818)
			(xy 137.144706 -17.874633) (xy 137.185887 -17.838946) (xy 137.231728 -17.809482) (xy 137.281294 -17.786841)
			(xy 137.333578 -17.771485) (xy 137.387516 -17.763725) (xy 137.414762 -17.763236) (xy 138.278362 -17.763236)
			(xy 138.30562 -17.763608) (xy 138.359581 -17.771362) (xy 138.41189 -17.786716) (xy 138.46148 -17.809359)
			(xy 138.507344 -17.83883) (xy 138.548546 -17.874528) (xy 138.584247 -17.915726) (xy 138.613722 -17.961586)
			(xy 138.63637 -18.011175) (xy 138.65173 -18.063482) (xy 138.659489 -18.117442) (xy 138.659489 -18.17195)
			(xy 140.633699 -18.17195) (xy 140.633699 -18.11745) (xy 140.641455 -18.063505) (xy 140.65681 -18.011213)
			(xy 140.67945 -17.961638) (xy 140.708915 -17.91579) (xy 140.744605 -17.874602) (xy 140.785793 -17.838913)
			(xy 140.831642 -17.809448) (xy 140.881217 -17.786808) (xy 140.933509 -17.771455) (xy 140.987454 -17.763699)
			(xy 141.014704 -17.763236) (xy 141.878304 -17.763236) (xy 141.905558 -17.763634) (xy 141.959512 -17.771392)
			(xy 142.011812 -17.786749) (xy 142.061394 -17.809393) (xy 142.10725 -17.838863) (xy 142.148444 -17.874559)
			(xy 142.184139 -17.915754) (xy 142.213609 -17.961609) (xy 142.236252 -18.011192) (xy 142.251609 -18.063492)
			(xy 142.259366 -18.117446) (xy 142.259366 -18.171954) (xy 142.251609 -18.225908) (xy 142.236252 -18.278208)
			(xy 142.213609 -18.327791) (xy 142.184139 -18.373646) (xy 142.148444 -18.414841) (xy 142.10725 -18.450537)
			(xy 142.061394 -18.480007) (xy 142.011812 -18.502651) (xy 141.959512 -18.518008) (xy 141.905558 -18.525766)
			(xy 141.878304 -18.526252) (xy 141.014704 -18.526252) (xy 140.987454 -18.525701) (xy 140.933509 -18.517945)
			(xy 140.881217 -18.502592) (xy 140.831642 -18.479952) (xy 140.785793 -18.450487) (xy 140.744605 -18.414798)
			(xy 140.708915 -18.37361) (xy 140.67945 -18.327762) (xy 140.65681 -18.278187) (xy 140.641455 -18.225895)
			(xy 140.633699 -18.17195) (xy 138.659489 -18.17195) (xy 138.659489 -18.171958) (xy 138.65173 -18.225918)
			(xy 138.63637 -18.278225) (xy 138.613722 -18.327814) (xy 138.584247 -18.373674) (xy 138.548546 -18.414872)
			(xy 138.507344 -18.45057) (xy 138.46148 -18.480041) (xy 138.41189 -18.502684) (xy 138.359581 -18.518038)
			(xy 138.30562 -18.525792) (xy 138.278362 -18.526252) (xy 137.414762 -18.526252) (xy 137.387516 -18.525675)
			(xy 137.333578 -18.517915) (xy 137.281294 -18.502559) (xy 137.231728 -18.479918) (xy 137.185887 -18.450454)
			(xy 137.144706 -18.414767) (xy 137.109023 -18.373582) (xy 137.079564 -18.327739) (xy 137.056928 -18.27817)
			(xy 137.041577 -18.225884) (xy 137.033822 -18.171946) (xy 133.259366 -18.171946) (xy 133.259366 -18.171953)
			(xy 133.251609 -18.225905) (xy 133.236254 -18.278204) (xy 133.213611 -18.327786) (xy 133.184144 -18.373641)
			(xy 133.148451 -18.414835) (xy 133.107258 -18.450531) (xy 133.061405 -18.480001) (xy 133.011825 -18.502646)
			(xy 132.959527 -18.518005) (xy 132.905575 -18.525765) (xy 132.878322 -18.526252) (xy 132.014722 -18.526252)
			(xy 131.987471 -18.525702) (xy 131.933524 -18.517949) (xy 131.88123 -18.502596) (xy 131.831653 -18.479958)
			(xy 131.785802 -18.450494) (xy 131.744611 -18.414804) (xy 131.708919 -18.373616) (xy 131.679453 -18.327767)
			(xy 131.656811 -18.278191) (xy 131.641456 -18.225897) (xy 131.633699 -18.171951) (xy 80.808854 -18.171951)
			(xy 80.811074 -18.193953) (xy 80.811624 -18.238724) (xy 80.81112 -18.281085) (xy 80.803067 -18.365422)
			(xy 80.787033 -18.448612) (xy 80.763165 -18.529902) (xy 80.731677 -18.608554) (xy 80.692855 -18.683857)
			(xy 80.647052 -18.755129) (xy 80.594681 -18.821725) (xy 80.536216 -18.88304) (xy 80.472188 -18.938521)
			(xy 80.403176 -18.987664) (xy 80.329806 -19.030024) (xy 80.252741 -19.065219) (xy 80.172679 -19.092928)
			(xy 80.090346 -19.112902) (xy 80.006487 -19.124959) (xy 79.921862 -19.128991) (xy 79.837237 -19.124959)
			(xy 79.753378 -19.112902) (xy 79.671045 -19.092928) (xy 79.590983 -19.065219) (xy 79.513918 -19.030024)
			(xy 79.440548 -18.987664) (xy 79.371536 -18.938521) (xy 79.307508 -18.88304) (xy 79.249043 -18.821725)
			(xy 79.196672 -18.755129) (xy 79.150869 -18.683857) (xy 79.112047 -18.608554) (xy 79.080559 -18.529902)
			(xy 79.056691 -18.448612) (xy 79.040657 -18.365422) (xy 79.032604 -18.281085) (xy 79.0321 -18.238724)
			(xy 69.401856 -18.238724) (xy 69.418593 -18.307718) (xy 69.430649 -18.391576) (xy 69.434681 -18.4762)
			(xy 69.430649 -18.560824) (xy 69.418593 -18.644682) (xy 69.39862 -18.727014) (xy 69.370911 -18.807075)
			(xy 69.335718 -18.884139) (xy 69.293359 -18.95751) (xy 69.244218 -19.026522) (xy 69.18874 -19.09055)
			(xy 69.127426 -19.149015) (xy 69.060833 -19.201387) (xy 68.989563 -19.247192) (xy 68.914262 -19.286016)
			(xy 68.835612 -19.317505) (xy 68.754325 -19.341377) (xy 68.671136 -19.357414) (xy 68.5868 -19.36547)
			(xy 68.54444 -19.365976) (xy 68.502753 -19.365468) (xy 68.419745 -19.357644) (xy 68.337834 -19.342089)
			(xy 68.257737 -19.31894) (xy 68.180157 -19.288398) (xy 68.105774 -19.250734) (xy 68.035242 -19.206275)
			(xy 67.969177 -19.155414) (xy 67.90816 -19.098595) (xy 67.852727 -19.036317) (xy 67.827652 -19.00301)
			(xy 67.827398 -19.002756) (xy 67.821873 -18.996058) (xy 67.807425 -18.986454) (xy 67.790601 -18.982223)
			(xy 67.781932 -18.98269) (xy 67.69481 -18.991072) (xy 67.686098 -18.992195) (xy 67.670187 -18.999611)
			(xy 67.657745 -19.011995) (xy 67.653662 -19.019774) (xy 67.653662 -19.020282) (xy 67.63179 -19.065383)
			(xy 67.579339 -19.150805) (xy 67.549014 -19.190716) (xy 67.543272 -19.198996) (xy 67.538026 -19.218428)
			(xy 67.540615 -19.238388) (xy 67.545204 -19.247358) (xy 67.564269 -19.281203) (xy 67.597117 -19.351604)
			(xy 67.623706 -19.424598) (xy 67.643834 -19.499632) (xy 67.657349 -19.576134) (xy 67.664146 -19.653523)
			(xy 67.664584 -19.692366) (xy 67.664167 -19.730656) (xy 67.657563 -19.806949) (xy 67.644416 -19.882392)
			(xy 67.624826 -19.956423) (xy 67.61226 -19.992594) (xy 67.609626 -20.001035) (xy 67.609615 -20.018702)
			(xy 67.61226 -20.027138) (xy 67.624799 -20.063317) (xy 67.644373 -20.13735) (xy 67.653158 -20.187755)
			(xy 138.765443 -20.187755) (xy 138.765443 -20.133245) (xy 138.773201 -20.079289) (xy 138.788559 -20.026987)
			(xy 138.811205 -19.977403) (xy 138.840677 -19.931547) (xy 138.876376 -19.890352) (xy 138.917574 -19.854657)
			(xy 138.963433 -19.825189) (xy 139.013019 -19.802547) (xy 139.065322 -19.787194) (xy 139.119279 -19.779441)
			(xy 139.146534 -19.77898) (xy 140.137134 -19.77898) (xy 140.164383 -19.779493) (xy 140.218325 -19.787253)
			(xy 140.270614 -19.80261) (xy 140.320185 -19.825253) (xy 140.36603 -19.854719) (xy 140.407215 -19.890409)
			(xy 140.442901 -19.931597) (xy 140.449617 -19.942048) (xy 175.988472 -19.942048) (xy 175.988976 -19.899687)
			(xy 175.997029 -19.81535) (xy 176.013063 -19.73216) (xy 176.036931 -19.65087) (xy 176.068419 -19.572218)
			(xy 176.107241 -19.496915) (xy 176.153044 -19.425643) (xy 176.205415 -19.359047) (xy 176.26388 -19.297732)
			(xy 176.327908 -19.242251) (xy 176.39692 -19.193108) (xy 176.47029 -19.150748) (xy 176.547355 -19.115553)
			(xy 176.627417 -19.087844) (xy 176.70975 -19.06787) (xy 176.793609 -19.055813) (xy 176.878234 -19.051782)
			(xy 176.962859 -19.055813) (xy 177.046718 -19.06787) (xy 177.129051 -19.087844) (xy 177.209113 -19.115553)
			(xy 177.286178 -19.150748) (xy 177.359548 -19.193108) (xy 177.42856 -19.242251) (xy 177.492588 -19.297732)
			(xy 177.551053 -19.359047) (xy 177.603424 -19.425643) (xy 177.649227 -19.496915) (xy 177.688049 -19.572218)
			(xy 177.719537 -19.65087) (xy 177.743405 -19.73216) (xy 177.759439 -19.81535) (xy 177.767492 -19.899687)
			(xy 177.767996 -19.942048) (xy 177.767398 -19.98792) (xy 177.757891 -20.079169) (xy 177.739034 -20.168954)
			(xy 177.725578 -20.212812) (xy 177.722752 -20.223379) (xy 177.72523 -20.245087) (xy 177.730404 -20.254722)
			(xy 177.750836 -20.289402) (xy 177.786035 -20.361795) (xy 177.814552 -20.437071) (xy 177.836153 -20.514616)
			(xy 177.850661 -20.593794) (xy 177.857958 -20.67396) (xy 177.85842 -20.714208) (xy 177.85842 -20.715224)
			(xy 177.857839 -20.760561) (xy 177.84856 -20.850758) (xy 177.830152 -20.939544) (xy 177.817018 -20.98294)
			(xy 177.81462 -20.991841) (xy 177.815621 -21.010233) (xy 177.823067 -21.02708) (xy 177.835994 -21.040201)
			(xy 177.844196 -21.044408) (xy 177.8824 -21.062505) (xy 177.955518 -21.104946) (xy 178.024281 -21.15413)
			(xy 178.088069 -21.209614) (xy 178.146306 -21.270898) (xy 178.198469 -21.337429) (xy 178.244087 -21.408608)
			(xy 178.282748 -21.483792) (xy 178.314103 -21.562305) (xy 178.337871 -21.643437) (xy 178.353837 -21.726458)
			(xy 178.361856 -21.810619) (xy 178.362356 -21.85289) (xy 178.361892 -21.894005) (xy 178.354306 -21.975884)
			(xy 178.339197 -22.056714) (xy 178.316694 -22.135805) (xy 178.28699 -22.212482) (xy 178.250337 -22.286091)
			(xy 178.207049 -22.356005) (xy 178.157495 -22.421626) (xy 178.102097 -22.482394) (xy 178.041329 -22.537792)
			(xy 177.975708 -22.587347) (xy 177.905795 -22.630635) (xy 177.832186 -22.667288) (xy 177.755509 -22.696993)
			(xy 177.676418 -22.719496) (xy 177.595588 -22.734605) (xy 177.513709 -22.742192) (xy 177.472594 -22.742652)
			(xy 177.429071 -22.742084) (xy 177.34244 -22.73358) (xy 177.257055 -22.716655) (xy 177.173731 -22.69147)
			(xy 177.093266 -22.658267) (xy 177.016429 -22.617362) (xy 176.943956 -22.569146) (xy 176.876538 -22.514083)
			(xy 176.814822 -22.452697) (xy 176.759398 -22.385575) (xy 176.710795 -22.313361) (xy 176.669479 -22.236745)
			(xy 176.652174 -22.196806) (xy 176.647921 -22.187866) (xy 176.633936 -22.17388) (xy 176.624996 -22.169628)
			(xy 176.585068 -22.152314) (xy 176.508472 -22.110985) (xy 176.436278 -22.062372) (xy 176.369178 -22.006941)
			(xy 176.307813 -21.945221) (xy 176.252769 -21.877802) (xy 176.204574 -21.80533) (xy 176.163687 -21.728496)
			(xy 176.1305 -21.648037) (xy 176.105331 -21.564721) (xy 176.088419 -21.479345) (xy 176.079928 -21.392725)
			(xy 176.079404 -21.349208) (xy 176.079404 -21.348446) (xy 176.079814 -21.310226) (xy 176.086378 -21.234067)
			(xy 176.099462 -21.158755) (xy 176.118968 -21.084845) (xy 176.131474 -21.048726) (xy 176.134055 -21.040409)
			(xy 176.134058 -21.023006) (xy 176.131474 -21.01469) (xy 176.118957 -20.978475) (xy 176.099434 -20.904375)
			(xy 176.086349 -20.828871) (xy 176.079799 -20.752523) (xy 176.079404 -20.714208) (xy 176.07999 -20.668344)
			(xy 176.089425 -20.577104) (xy 176.108186 -20.487316) (xy 176.121568 -20.443444) (xy 176.124428 -20.432883)
			(xy 176.121929 -20.411168) (xy 176.116742 -20.401534) (xy 176.096312 -20.366847) (xy 176.06107 -20.294464)
			(xy 176.032509 -20.219194) (xy 176.010862 -20.141652) (xy 175.996306 -20.062472) (xy 175.988959 -19.982301)
			(xy 175.988472 -19.942048) (xy 140.449617 -19.942048) (xy 140.472364 -19.977445) (xy 140.495002 -20.027018)
			(xy 140.510354 -20.079308) (xy 140.51811 -20.133251) (xy 140.51811 -20.187749) (xy 140.510354 -20.241692)
			(xy 140.495002 -20.293982) (xy 140.472364 -20.343555) (xy 140.442901 -20.389403) (xy 140.407215 -20.430591)
			(xy 140.36603 -20.466281) (xy 140.320185 -20.495747) (xy 140.270614 -20.51839) (xy 140.218325 -20.533747)
			(xy 140.164383 -20.541507) (xy 140.137134 -20.541996) (xy 139.146534 -20.541996) (xy 139.119279 -20.541559)
			(xy 139.065322 -20.533806) (xy 139.013019 -20.518453) (xy 138.963433 -20.495811) (xy 138.917574 -20.466343)
			(xy 138.876376 -20.430648) (xy 138.840677 -20.389453) (xy 138.811205 -20.343597) (xy 138.788559 -20.294013)
			(xy 138.773201 -20.241711) (xy 138.765443 -20.187755) (xy 67.653158 -20.187755) (xy 67.657521 -20.212789)
			(xy 67.664147 -20.289078) (xy 67.664584 -20.327366) (xy 67.66408 -20.369727) (xy 67.656027 -20.454064)
			(xy 67.639993 -20.537254) (xy 67.616125 -20.618544) (xy 67.584637 -20.697196) (xy 67.545815 -20.772499)
			(xy 67.500012 -20.843771) (xy 67.447641 -20.910367) (xy 67.389176 -20.971682) (xy 67.325148 -21.027163)
			(xy 67.256136 -21.076306) (xy 67.182766 -21.118666) (xy 67.105701 -21.153861) (xy 67.025639 -21.18157)
			(xy 66.943306 -21.201544) (xy 66.859447 -21.213601) (xy 66.774822 -21.217633) (xy 66.690197 -21.213601)
			(xy 66.606338 -21.201544) (xy 66.524005 -21.18157) (xy 66.443943 -21.153861) (xy 66.366878 -21.118666)
			(xy 66.293508 -21.076306) (xy 66.224496 -21.027163) (xy 66.160468 -20.971682) (xy 66.102003 -20.910367)
			(xy 66.049632 -20.843771) (xy 66.003829 -20.772499) (xy 65.965007 -20.697196) (xy 65.933519 -20.618544)
			(xy 65.909651 -20.537254) (xy 65.893617 -20.454064) (xy 65.885564 -20.369727) (xy 65.88506 -20.327366)
			(xy 0.509016 -20.327366) (xy 0.509016 -22.309271) (xy 65.993006 -22.309271) (xy 65.993006 -22.224549)
			(xy 66.001059 -22.140212) (xy 66.017093 -22.057022) (xy 66.040961 -21.975732) (xy 66.072449 -21.89708)
			(xy 66.111271 -21.821777) (xy 66.157074 -21.750505) (xy 66.209445 -21.683909) (xy 66.26791 -21.622594)
			(xy 66.331938 -21.567113) (xy 66.40095 -21.51797) (xy 66.47432 -21.47561) (xy 66.551385 -21.440415)
			(xy 66.631447 -21.412706) (xy 66.71378 -21.392732) (xy 66.797639 -21.380675) (xy 66.882264 -21.376644)
			(xy 66.966889 -21.380675) (xy 67.050748 -21.392732) (xy 67.133081 -21.412706) (xy 67.213143 -21.440415)
			(xy 67.290208 -21.47561) (xy 67.363578 -21.51797) (xy 67.43259 -21.567113) (xy 67.496618 -21.622594)
			(xy 67.555083 -21.683909) (xy 67.607454 -21.750505) (xy 67.653257 -21.821777) (xy 67.692079 -21.89708)
			(xy 67.723567 -21.975732) (xy 67.747435 -22.057022) (xy 67.763469 -22.140212) (xy 67.771522 -22.224549)
			(xy 67.772026 -22.26691) (xy 67.771522 -22.309271) (xy 67.763469 -22.393608) (xy 67.747435 -22.476798)
			(xy 67.723567 -22.558088) (xy 67.722853 -22.559872) (xy 114.452596 -22.559872) (xy 114.452596 -22.505328)
			(xy 114.460358 -22.45134) (xy 114.475725 -22.399006) (xy 114.498383 -22.349391) (xy 114.527872 -22.303506)
			(xy 114.563591 -22.262285) (xy 114.604813 -22.226567) (xy 114.650698 -22.19708) (xy 114.700313 -22.174422)
			(xy 114.752648 -22.159056) (xy 114.806636 -22.151295) (xy 114.833908 -22.150832) (xy 115.697508 -22.150832)
			(xy 115.724777 -22.151331) (xy 115.778758 -22.159093) (xy 115.831086 -22.174459) (xy 115.880695 -22.197116)
			(xy 115.926574 -22.226601) (xy 115.96779 -22.262316) (xy 116.003504 -22.303533) (xy 116.032988 -22.349412)
			(xy 116.055644 -22.399021) (xy 116.071008 -22.451349) (xy 116.07877 -22.505331) (xy 116.07877 -22.559869)
			(xy 116.071008 -22.613851) (xy 116.055644 -22.666179) (xy 116.032988 -22.715788) (xy 116.003504 -22.761667)
			(xy 115.96779 -22.802884) (xy 115.926574 -22.838599) (xy 115.880695 -22.868084) (xy 115.831086 -22.890741)
			(xy 115.778758 -22.906107) (xy 115.724777 -22.913869) (xy 115.697508 -22.914356) (xy 114.833908 -22.914356)
			(xy 114.806636 -22.913905) (xy 114.752648 -22.906144) (xy 114.700313 -22.890778) (xy 114.650698 -22.86812)
			(xy 114.604813 -22.838633) (xy 114.563591 -22.802915) (xy 114.527872 -22.761694) (xy 114.498383 -22.715809)
			(xy 114.475725 -22.666194) (xy 114.460358 -22.61386) (xy 114.452596 -22.559872) (xy 67.722853 -22.559872)
			(xy 67.692079 -22.63674) (xy 67.653257 -22.712043) (xy 67.607454 -22.783315) (xy 67.555083 -22.849911)
			(xy 67.496618 -22.911226) (xy 67.43259 -22.966707) (xy 67.363578 -23.01585) (xy 67.361784 -23.016886)
			(xy 136.323137 -23.016886) (xy 136.327046 -22.962479) (xy 136.338661 -22.909183) (xy 136.357746 -22.858084)
			(xy 136.383911 -22.810221) (xy 136.416623 -22.766572) (xy 136.435592 -22.74697) (xy 137.046208 -22.1361)
			(xy 137.06783 -22.115331) (xy 137.116345 -22.080114) (xy 137.169764 -22.052902) (xy 137.226775 -22.034363)
			(xy 137.285982 -22.024951) (xy 137.315956 -22.02434) (xy 137.31621 -22.02434) (xy 137.34348 -22.024815)
			(xy 137.397464 -22.032578) (xy 137.449794 -22.047945) (xy 137.499404 -22.070602) (xy 137.545285 -22.10009)
			(xy 137.586503 -22.135806) (xy 137.622218 -22.177025) (xy 137.651703 -22.222907) (xy 137.674359 -22.272518)
			(xy 137.689724 -22.324848) (xy 137.697486 -22.378832) (xy 137.697972 -22.406102) (xy 137.697972 -22.406356)
			(xy 137.6974 -22.436336) (xy 137.688023 -22.495559) (xy 137.669494 -22.552585) (xy 137.64227 -22.606009)
			(xy 137.60702 -22.654514) (xy 137.586212 -22.676104) (xy 136.975342 -23.28672) (xy 136.955728 -23.305677)
			(xy 136.912079 -23.338389) (xy 136.864216 -23.364554) (xy 136.813117 -23.383639) (xy 136.759821 -23.395254)
			(xy 136.705414 -23.399163) (xy 136.651005 -23.395286) (xy 136.597702 -23.383703) (xy 136.546591 -23.364649)
			(xy 136.498713 -23.338513) (xy 136.455044 -23.305826) (xy 136.416474 -23.267256) (xy 136.383787 -23.223587)
			(xy 136.357651 -23.175709) (xy 136.338597 -23.124598) (xy 136.327014 -23.071295) (xy 136.323137 -23.016886)
			(xy 67.361784 -23.016886) (xy 67.290208 -23.05821) (xy 67.213143 -23.093405) (xy 67.133081 -23.121114)
			(xy 67.050748 -23.141088) (xy 66.966889 -23.153145) (xy 66.882264 -23.157177) (xy 66.797639 -23.153145)
			(xy 66.71378 -23.141088) (xy 66.631447 -23.121114) (xy 66.551385 -23.093405) (xy 66.47432 -23.05821)
			(xy 66.40095 -23.01585) (xy 66.331938 -22.966707) (xy 66.26791 -22.911226) (xy 66.209445 -22.849911)
			(xy 66.157074 -22.783315) (xy 66.111271 -22.712043) (xy 66.072449 -22.63674) (xy 66.040961 -22.558088)
			(xy 66.017093 -22.476798) (xy 66.001059 -22.393608) (xy 65.993006 -22.309271) (xy 0.509016 -22.309271)
			(xy 0.509016 -23.593552) (xy 189.619128 -23.593552) (xy 189.619128 -23.593298) (xy 189.619711 -23.54856)
			(xy 189.628722 -23.459539) (xy 189.646623 -23.371871) (xy 189.673232 -23.286444) (xy 189.690248 -23.245064)
			(xy 189.69384 -23.235481) (xy 189.693822 -23.215031) (xy 189.690248 -23.20544) (xy 189.673222 -23.164064)
			(xy 189.646604 -23.078637) (xy 189.6287 -22.990968) (xy 189.619692 -22.901945) (xy 189.619128 -22.857206)
			(xy 189.619128 -22.856952) (xy 189.619632 -22.814604) (xy 189.627683 -22.73029) (xy 189.643712 -22.647124)
			(xy 189.667573 -22.565857) (xy 189.699052 -22.487227) (xy 189.737863 -22.411946) (xy 189.783653 -22.340694)
			(xy 189.836009 -22.274118) (xy 189.894457 -22.21282) (xy 189.958467 -22.157355) (xy 190.027459 -22.108226)
			(xy 190.100809 -22.065877) (xy 190.177852 -22.030693) (xy 190.257891 -22.002991) (xy 190.3402 -21.983023)
			(xy 190.424035 -21.97097) (xy 190.508636 -21.96694) (xy 190.593237 -21.97097) (xy 190.677072 -21.983023)
			(xy 190.759381 -22.002991) (xy 190.83942 -22.030693) (xy 190.916463 -22.065877) (xy 190.989813 -22.108226)
			(xy 191.058805 -22.157355) (xy 191.122815 -22.21282) (xy 191.181263 -22.274118) (xy 191.233619 -22.340694)
			(xy 191.279409 -22.411946) (xy 191.31822 -22.487227) (xy 191.349699 -22.565857) (xy 191.37356 -22.647124)
			(xy 191.389589 -22.73029) (xy 191.39764 -22.814604) (xy 191.398144 -22.856952) (xy 191.398144 -22.857206)
			(xy 191.397557 -22.901944) (xy 191.388547 -22.990965) (xy 191.370647 -23.078632) (xy 191.344039 -23.16406)
			(xy 191.327024 -23.20544) (xy 191.323489 -23.215039) (xy 191.323471 -23.235473) (xy 191.327024 -23.245064)
			(xy 191.344055 -23.286438) (xy 191.370671 -23.371866) (xy 191.388573 -23.459535) (xy 191.39758 -23.548559)
			(xy 191.398144 -23.593298) (xy 191.398144 -23.593552) (xy 191.39764 -23.6359) (xy 191.389589 -23.720214)
			(xy 191.37356 -23.80338) (xy 191.349699 -23.884647) (xy 191.31822 -23.963277) (xy 191.279409 -24.038558)
			(xy 191.233619 -24.10981) (xy 191.181263 -24.176386) (xy 191.122815 -24.237684) (xy 191.058805 -24.293149)
			(xy 190.989813 -24.342278) (xy 190.916463 -24.384627) (xy 190.83942 -24.419811) (xy 190.759381 -24.447513)
			(xy 190.677072 -24.467481) (xy 190.593237 -24.479534) (xy 190.508636 -24.483565) (xy 190.424035 -24.479534)
			(xy 190.3402 -24.467481) (xy 190.257891 -24.447513) (xy 190.177852 -24.419811) (xy 190.100809 -24.384627)
			(xy 190.027459 -24.342278) (xy 189.958467 -24.293149) (xy 189.894457 -24.237684) (xy 189.836009 -24.176386)
			(xy 189.783653 -24.10981) (xy 189.737863 -24.038558) (xy 189.699052 -23.963277) (xy 189.667573 -23.884647)
			(xy 189.643712 -23.80338) (xy 189.627683 -23.720214) (xy 189.619632 -23.6359) (xy 189.619128 -23.593552)
			(xy 0.509016 -23.593552) (xy 0.509016 -25.56891) (xy 65.510156 -25.56891) (xy 65.510621 -25.527206)
			(xy 65.518403 -25.444163) (xy 65.533928 -25.362214) (xy 65.557059 -25.282079) (xy 65.587593 -25.204462)
			(xy 65.625262 -25.130046) (xy 65.669734 -25.059485) (xy 65.720619 -24.993398) (xy 65.777469 -24.932368)
			(xy 65.839786 -24.876929) (xy 65.873122 -24.851868) (xy 65.88167 -24.844931) (xy 65.892346 -24.825708)
			(xy 65.893696 -24.814784) (xy 65.897332 -24.773398) (xy 65.911399 -24.69151) (xy 65.933041 -24.611291)
			(xy 65.962067 -24.53344) (xy 65.998226 -24.458634) (xy 66.041203 -24.387525) (xy 66.090622 -24.320733)
			(xy 66.146054 -24.25884) (xy 66.207015 -24.202385) (xy 66.272974 -24.15186) (xy 66.343357 -24.107705)
			(xy 66.41755 -24.070304) (xy 66.494907 -24.039985) (xy 66.574755 -24.01701) (xy 66.656396 -24.00158)
			(xy 66.739121 -23.99383) (xy 66.780664 -23.993348) (xy 66.824459 -23.993873) (xy 66.911625 -24.002491)
			(xy 66.997521 -24.019637) (xy 67.081315 -24.045145) (xy 67.162195 -24.078768) (xy 67.201034 -24.099012)
			(xy 67.2125 -24.10443) (xy 67.237828 -24.10443) (xy 67.249294 -24.099012) (xy 67.288138 -24.078781)
			(xy 67.369023 -24.045174) (xy 67.452816 -24.019672) (xy 67.538709 -24.002521) (xy 67.62587 -23.993888)
			(xy 67.669664 -23.993348) (xy 67.713459 -23.993873) (xy 67.800625 -24.002491) (xy 67.886521 -24.019637)
			(xy 67.970315 -24.045145) (xy 68.051195 -24.078768) (xy 68.090034 -24.099012) (xy 68.1015 -24.10443)
			(xy 68.126828 -24.10443) (xy 68.138294 -24.099012) (xy 68.177138 -24.078781) (xy 68.258023 -24.045174)
			(xy 68.341816 -24.019672) (xy 68.427709 -24.002521) (xy 68.51487 -23.993888) (xy 68.558664 -23.993348)
			(xy 68.607651 -23.994055) (xy 68.705028 -24.00487) (xy 68.752974 -24.014938) (xy 68.762324 -24.016604)
			(xy 68.781086 -24.013776) (xy 68.797533 -24.004314) (xy 68.803774 -23.997158) (xy 68.831851 -23.962886)
			(xy 68.893786 -23.899527) (xy 68.961714 -23.842641) (xy 69.034963 -23.792791) (xy 69.112805 -23.750472)
			(xy 69.19447 -23.716104) (xy 69.279148 -23.690027) (xy 69.365999 -23.672499) (xy 69.454163 -23.663695)
			(xy 69.498464 -23.663148) (xy 69.540827 -23.663615) (xy 69.625169 -23.671665) (xy 69.708365 -23.687697)
			(xy 69.789659 -23.711564) (xy 69.868317 -23.743051) (xy 69.943625 -23.781873) (xy 70.014902 -23.827677)
			(xy 70.081502 -23.880049) (xy 70.142823 -23.938516) (xy 70.198307 -24.002546) (xy 70.247454 -24.071561)
			(xy 70.250564 -24.076947) (xy 112.652614 -24.076947) (xy 112.652614 -24.022453) (xy 112.660369 -23.968515)
			(xy 112.67572 -23.916228) (xy 112.698356 -23.866659) (xy 112.727815 -23.820815) (xy 112.763499 -23.77963)
			(xy 112.80468 -23.743942) (xy 112.85052 -23.714477) (xy 112.900087 -23.691836) (xy 112.952372 -23.676478)
			(xy 113.006309 -23.668717) (xy 113.033556 -23.668228) (xy 113.897156 -23.668228) (xy 113.924413 -23.668616)
			(xy 113.978374 -23.676369) (xy 114.030682 -23.691722) (xy 114.080273 -23.714364) (xy 114.126136 -23.743834)
			(xy 114.167338 -23.779531) (xy 114.20304 -23.820729) (xy 114.232514 -23.866588) (xy 114.255162 -23.916176)
			(xy 114.270522 -23.968483) (xy 114.278281 -24.022443) (xy 114.278281 -24.076957) (xy 114.270522 -24.130917)
			(xy 114.255235 -24.182975) (xy 116.218856 -24.182975) (xy 116.218856 -24.128425) (xy 116.226619 -24.074429)
			(xy 116.241989 -24.022088) (xy 116.264651 -23.972468) (xy 116.294144 -23.926577) (xy 116.329868 -23.885352)
			(xy 116.371096 -23.84963) (xy 116.416989 -23.820139) (xy 116.466611 -23.79748) (xy 116.518953 -23.782114)
			(xy 116.572949 -23.774354) (xy 116.600224 -23.773892) (xy 117.463824 -23.773892) (xy 117.491089 -23.774472)
			(xy 117.545063 -23.782235) (xy 117.597384 -23.797601) (xy 117.646985 -23.820256) (xy 117.692857 -23.849739)
			(xy 117.734067 -23.88545) (xy 117.769776 -23.926662) (xy 117.799256 -23.972536) (xy 117.821907 -24.022139)
			(xy 117.83727 -24.07446) (xy 117.84503 -24.128435) (xy 117.84503 -24.182965) (xy 117.83727 -24.23694)
			(xy 117.821907 -24.289261) (xy 117.799256 -24.338864) (xy 117.769776 -24.384738) (xy 117.734067 -24.42595)
			(xy 117.692857 -24.461661) (xy 117.646985 -24.491144) (xy 117.597384 -24.513799) (xy 117.545063 -24.529165)
			(xy 117.491089 -24.536928) (xy 117.463824 -24.537416) (xy 116.600224 -24.537416) (xy 116.572949 -24.537046)
			(xy 116.518953 -24.529286) (xy 116.466611 -24.51392) (xy 116.416989 -24.491261) (xy 116.371096 -24.46177)
			(xy 116.329868 -24.426049) (xy 116.294144 -24.384823) (xy 116.264651 -24.338932) (xy 116.241989 -24.289312)
			(xy 116.226619 -24.236971) (xy 116.218856 -24.182975) (xy 114.255235 -24.182975) (xy 114.255162 -24.183224)
			(xy 114.232514 -24.232812) (xy 114.20304 -24.278671) (xy 114.167338 -24.319869) (xy 114.126136 -24.355566)
			(xy 114.080273 -24.385036) (xy 114.030682 -24.407678) (xy 113.978374 -24.423031) (xy 113.924414 -24.430784)
			(xy 113.897156 -24.431244) (xy 113.033556 -24.431244) (xy 113.006309 -24.430683) (xy 112.952372 -24.422922)
			(xy 112.900087 -24.407564) (xy 112.85052 -24.384923) (xy 112.80468 -24.355458) (xy 112.763499 -24.31977)
			(xy 112.727815 -24.278585) (xy 112.698356 -24.232741) (xy 112.67572 -24.183172) (xy 112.660369 -24.130885)
			(xy 112.652614 -24.076947) (xy 70.250564 -24.076947) (xy 70.289818 -24.144935) (xy 70.325015 -24.222004)
			(xy 70.352727 -24.302069) (xy 70.372702 -24.384407) (xy 70.38476 -24.46827) (xy 70.388792 -24.5529)
			(xy 70.38476 -24.63753) (xy 70.37544 -24.702351) (xy 130.235962 -24.702351) (xy 130.235962 -24.647849)
			(xy 130.243717 -24.593903) (xy 130.259071 -24.541609) (xy 130.28171 -24.492033) (xy 130.311174 -24.446182)
			(xy 130.346863 -24.404991) (xy 130.38805 -24.369298) (xy 130.433897 -24.33983) (xy 130.483472 -24.317185)
			(xy 130.535764 -24.301826) (xy 130.589709 -24.294065) (xy 130.61696 -24.293576) (xy 131.48056 -24.293576)
			(xy 131.507814 -24.294069) (xy 131.561767 -24.301821) (xy 131.614067 -24.317173) (xy 131.66365 -24.339812)
			(xy 131.709506 -24.369277) (xy 131.750702 -24.40497) (xy 131.786399 -24.446162) (xy 131.815869 -24.492015)
			(xy 131.838513 -24.541595) (xy 131.853871 -24.593894) (xy 131.861629 -24.647846) (xy 131.861629 -24.702354)
			(xy 131.853871 -24.756306) (xy 131.838513 -24.808605) (xy 131.815869 -24.858185) (xy 131.786399 -24.904038)
			(xy 131.750702 -24.94523) (xy 131.709506 -24.980923) (xy 131.66365 -25.010388) (xy 131.614067 -25.033027)
			(xy 131.561767 -25.048379) (xy 131.507814 -25.056131) (xy 131.48056 -25.056592) (xy 130.61696 -25.056592)
			(xy 130.589709 -25.056135) (xy 130.535764 -25.048374) (xy 130.483472 -25.033015) (xy 130.433897 -25.01037)
			(xy 130.38805 -24.980902) (xy 130.346863 -24.945209) (xy 130.311174 -24.904018) (xy 130.28171 -24.858167)
			(xy 130.259071 -24.808591) (xy 130.243717 -24.756297) (xy 130.235962 -24.702351) (xy 70.37544 -24.702351)
			(xy 70.372702 -24.721393) (xy 70.352727 -24.803731) (xy 70.325015 -24.883796) (xy 70.289818 -24.960865)
			(xy 70.247454 -25.034239) (xy 70.198307 -25.103254) (xy 70.142823 -25.167284) (xy 70.081502 -25.225751)
			(xy 70.014902 -25.278123) (xy 69.943625 -25.323927) (xy 69.868317 -25.362749) (xy 69.789659 -25.394236)
			(xy 69.708365 -25.418103) (xy 69.625169 -25.434135) (xy 69.540827 -25.442185) (xy 69.498464 -25.442672)
			(xy 69.449476 -25.441976) (xy 69.3521 -25.431154) (xy 69.304154 -25.421082) (xy 69.294812 -25.41935)
			(xy 69.276039 -25.422204) (xy 69.259591 -25.431693) (xy 69.253354 -25.438862) (xy 69.228687 -25.46901)
			(xy 69.174875 -25.52534) (xy 69.116354 -25.57676) (xy 69.085206 -25.600152) (xy 69.076637 -25.607067)
			(xy 69.065975 -25.626306) (xy 69.065849 -25.62733) (xy 133.339332 -25.62733) (xy 133.339332 -24.76373)
			(xy 133.339818 -24.736479) (xy 133.347574 -24.682531) (xy 133.362929 -24.630236) (xy 133.385571 -24.580659)
			(xy 133.415037 -24.534809) (xy 133.450728 -24.493618) (xy 133.491919 -24.457927) (xy 133.537769 -24.428461)
			(xy 133.587346 -24.405819) (xy 133.639641 -24.390464) (xy 133.693589 -24.382708) (xy 133.748091 -24.382708)
			(xy 133.802039 -24.390464) (xy 133.854334 -24.405819) (xy 133.903911 -24.428461) (xy 133.949761 -24.457927)
			(xy 133.990952 -24.493618) (xy 134.026643 -24.534809) (xy 134.056109 -24.580659) (xy 134.078751 -24.630236)
			(xy 134.094106 -24.682531) (xy 134.101862 -24.736479) (xy 134.102348 -24.76373) (xy 134.102348 -25.62733)
			(xy 134.101862 -25.654581) (xy 134.094106 -25.708529) (xy 134.078751 -25.760824) (xy 134.056109 -25.810401)
			(xy 134.026643 -25.856251) (xy 133.990952 -25.897442) (xy 133.949761 -25.933133) (xy 133.903911 -25.962599)
			(xy 133.854334 -25.985241) (xy 133.802039 -26.000596) (xy 133.748091 -26.008352) (xy 133.693589 -26.008352)
			(xy 133.639641 -26.000596) (xy 133.587346 -25.985241) (xy 133.537769 -25.962599) (xy 133.491919 -25.933133)
			(xy 133.450728 -25.897442) (xy 133.415037 -25.856251) (xy 133.385571 -25.810401) (xy 133.362929 -25.760824)
			(xy 133.347574 -25.708529) (xy 133.339818 -25.654581) (xy 133.339332 -25.62733) (xy 69.065849 -25.62733)
			(xy 69.064632 -25.637236) (xy 69.060986 -25.678621) (xy 69.046917 -25.760507) (xy 69.025275 -25.840725)
			(xy 68.996248 -25.918575) (xy 68.960089 -25.99338) (xy 68.917113 -26.064488) (xy 68.867694 -26.131279)
			(xy 68.812263 -26.193171) (xy 68.751303 -26.249626) (xy 68.685345 -26.300151) (xy 68.614964 -26.344307)
			(xy 68.540772 -26.381708) (xy 68.463416 -26.412028) (xy 68.38357 -26.435004) (xy 68.30193 -26.450436)
			(xy 68.219207 -26.458189) (xy 68.177664 -26.458672) (xy 68.133869 -26.458133) (xy 68.046704 -26.449518)
			(xy 67.960808 -26.432375) (xy 67.877014 -26.40687) (xy 67.796134 -26.37325) (xy 67.757294 -26.353008)
			(xy 67.745828 -26.34759) (xy 67.7205 -26.34759) (xy 67.709034 -26.353008) (xy 67.670181 -26.373222)
			(xy 67.589299 -26.406833) (xy 67.505508 -26.43234) (xy 67.419618 -26.449494) (xy 67.332457 -26.458131)
			(xy 67.288664 -26.458672) (xy 67.244869 -26.458133) (xy 67.157704 -26.449518) (xy 67.071808 -26.432375)
			(xy 66.988014 -26.40687) (xy 66.907134 -26.37325) (xy 66.868294 -26.353008) (xy 66.856828 -26.34759)
			(xy 66.8315 -26.34759) (xy 66.820034 -26.353008) (xy 66.781181 -26.373222) (xy 66.700299 -26.406833)
			(xy 66.616508 -26.43234) (xy 66.530618 -26.449494) (xy 66.443457 -26.458131) (xy 66.399664 -26.458672)
			(xy 66.358552 -26.458282) (xy 66.276678 -26.45069) (xy 66.195855 -26.435576) (xy 66.116771 -26.413067)
			(xy 66.040102 -26.383356) (xy 65.966502 -26.346696) (xy 65.8966 -26.3034) (xy 65.830991 -26.253838)
			(xy 65.770236 -26.198433) (xy 65.714853 -26.137658) (xy 65.665316 -26.072031) (xy 65.622046 -26.002113)
			(xy 65.585413 -25.928499) (xy 65.55573 -25.85182) (xy 65.53325 -25.772728) (xy 65.518165 -25.691899)
			(xy 65.510603 -25.610022) (xy 65.510156 -25.56891) (xy 0.509016 -25.56891) (xy 0.509016 -29.026161)
			(xy 11.140205 -29.026161) (xy 11.147539 -28.866724) (xy 11.162812 -28.70785) (xy 11.185984 -28.549934)
			(xy 11.216999 -28.39337) (xy 11.255779 -28.238547) (xy 11.302228 -28.085849) (xy 11.35623 -27.935656)
			(xy 11.417652 -27.788341) (xy 11.48634 -27.644271) (xy 11.562123 -27.503804) (xy 11.644814 -27.367289)
			(xy 11.734207 -27.235065) (xy 11.830079 -27.107461) (xy 11.932193 -26.984794) (xy 12.040293 -26.86737)
			(xy 12.154112 -26.75548) (xy 12.273367 -26.649402) (xy 12.397761 -26.5494) (xy 12.526985 -26.455723)
			(xy 12.660717 -26.368604) (xy 12.798626 -26.288258) (xy 12.940368 -26.214886) (xy 13.085591 -26.148671)
			(xy 13.233934 -26.089776) (xy 13.385028 -26.038349) (xy 13.538498 -25.994517) (xy 13.693962 -25.958388)
			(xy 13.851033 -25.930054) (xy 14.009321 -25.909584) (xy 14.168433 -25.897029) (xy 14.327973 -25.892421)
			(xy 14.487544 -25.895771) (xy 14.64675 -25.90707) (xy 14.805195 -25.92629) (xy 14.962485 -25.953385)
			(xy 15.118229 -25.988285) (xy 15.272039 -26.030905) (xy 15.423535 -26.081139) (xy 15.572338 -26.138862)
			(xy 15.718078 -26.203929) (xy 15.860395 -26.27618) (xy 15.998933 -26.355436) (xy 16.133349 -26.441497)
			(xy 16.263308 -26.534152) (xy 16.388487 -26.633169) (xy 16.508575 -26.738303) (xy 16.623273 -26.849292)
			(xy 16.678148 -26.907236) (xy 17.470427 -27.75458) (xy 130.687572 -27.75458) (xy 130.687572 -26.76398)
			(xy 130.688058 -26.736729) (xy 130.695814 -26.682781) (xy 130.711169 -26.630486) (xy 130.733811 -26.580909)
			(xy 130.763277 -26.535059) (xy 130.798968 -26.493868) (xy 130.840159 -26.458177) (xy 130.886009 -26.428711)
			(xy 130.935586 -26.406069) (xy 130.987881 -26.390714) (xy 131.041829 -26.382958) (xy 131.096331 -26.382958)
			(xy 131.150279 -26.390714) (xy 131.202574 -26.406069) (xy 131.252151 -26.428711) (xy 131.298001 -26.458177)
			(xy 131.339192 -26.493868) (xy 131.374883 -26.535059) (xy 131.404349 -26.580909) (xy 131.426991 -26.630486)
			(xy 131.442346 -26.682781) (xy 131.450102 -26.736729) (xy 131.450588 -26.76398) (xy 131.450588 -26.76779)
			(xy 141.621764 -26.76779) (xy 141.621764 -25.90419) (xy 141.62225 -25.876921) (xy 141.630012 -25.822937)
			(xy 141.645377 -25.770607) (xy 141.668034 -25.720997) (xy 141.69752 -25.675116) (xy 141.733235 -25.633899)
			(xy 141.774452 -25.598184) (xy 141.820333 -25.568698) (xy 141.869943 -25.546041) (xy 141.922273 -25.530676)
			(xy 141.976257 -25.522914) (xy 142.030795 -25.522914) (xy 142.084779 -25.530676) (xy 142.137109 -25.546041)
			(xy 142.186719 -25.568698) (xy 142.2326 -25.598184) (xy 142.273817 -25.633899) (xy 142.309532 -25.675116)
			(xy 142.339018 -25.720997) (xy 142.361675 -25.770607) (xy 142.37704 -25.822937) (xy 142.384802 -25.876921)
			(xy 142.385288 -25.90419) (xy 142.385288 -26.634948) (xy 175.442372 -26.634948) (xy 175.442817 -26.593237)
			(xy 175.450618 -26.510181) (xy 175.466165 -26.428221) (xy 175.489321 -26.348077) (xy 175.519883 -26.270455)
			(xy 175.557582 -26.196038) (xy 175.602086 -26.125479) (xy 175.653004 -26.059399) (xy 175.709888 -25.99838)
			(xy 175.772239 -25.942957) (xy 175.805592 -25.917906) (xy 175.814178 -25.911009) (xy 175.82483 -25.891756)
			(xy 175.826166 -25.880822) (xy 175.829855 -25.839448) (xy 175.843941 -25.757582) (xy 175.865598 -25.677385)
			(xy 175.894637 -25.599556) (xy 175.930804 -25.524774) (xy 175.973785 -25.453688) (xy 176.023205 -25.386918)
			(xy 176.078634 -25.325046) (xy 176.13959 -25.268611) (xy 176.205541 -25.218103) (xy 176.275913 -25.173964)
			(xy 176.350094 -25.136576) (xy 176.427436 -25.106267) (xy 176.507267 -25.083299) (xy 176.588892 -25.067873)
			(xy 176.671599 -25.060123) (xy 176.713134 -25.05964) (xy 176.713642 -25.05964) (xy 176.757406 -25.060139)
			(xy 176.844513 -25.068717) (xy 176.930355 -25.085818) (xy 177.0141 -25.111273) (xy 177.094937 -25.144838)
			(xy 177.133758 -25.16505) (xy 177.145111 -25.170377) (xy 177.170157 -25.170377) (xy 177.18151 -25.16505)
			(xy 177.22038 -25.144826) (xy 177.301322 -25.111257) (xy 177.38517 -25.085803) (xy 177.471113 -25.068709)
			(xy 177.55832 -25.060143) (xy 177.602134 -25.05964) (xy 177.645949 -25.060116) (xy 177.733161 -25.068665)
			(xy 177.819109 -25.085756) (xy 177.902957 -25.111222) (xy 177.983891 -25.144816) (xy 178.022758 -25.16505)
			(xy 178.034111 -25.170377) (xy 178.059157 -25.170377) (xy 178.07051 -25.16505) (xy 178.10938 -25.144826)
			(xy 178.190322 -25.111257) (xy 178.27417 -25.085803) (xy 178.360113 -25.068709) (xy 178.44732 -25.060143)
			(xy 178.491134 -25.05964) (xy 178.541288 -25.060291) (xy 178.640969 -25.071493) (xy 178.690016 -25.081992)
			(xy 178.700529 -25.083816) (xy 178.72144 -25.079687) (xy 178.7389 -25.067462) (xy 178.74488 -25.058624)
			(xy 178.766746 -25.023211) (xy 178.816155 -24.956227) (xy 178.871604 -24.894151) (xy 178.932608 -24.837525)
			(xy 178.998633 -24.786843) (xy 179.069104 -24.742549) (xy 179.143403 -24.705031) (xy 179.220882 -24.674615)
			(xy 179.300862 -24.651569) (xy 179.382645 -24.636093) (xy 179.465517 -24.628322) (xy 179.507134 -24.62784)
			(xy 179.549484 -24.628249) (xy 179.633799 -24.636303) (xy 179.716968 -24.652336) (xy 179.798236 -24.676201)
			(xy 179.876867 -24.707683) (xy 179.95215 -24.746496) (xy 180.023403 -24.79229) (xy 180.08998 -24.844649)
			(xy 180.151278 -24.9031) (xy 180.206744 -24.967112) (xy 180.255873 -25.036107) (xy 180.298222 -25.10946)
			(xy 180.333407 -25.186506) (xy 180.361109 -25.266547) (xy 180.381077 -25.348859) (xy 180.39313 -25.432696)
			(xy 180.397161 -25.5173) (xy 180.39313 -25.601904) (xy 180.381077 -25.685741) (xy 180.361109 -25.768053)
			(xy 180.333407 -25.848094) (xy 180.298222 -25.92514) (xy 180.255873 -25.998493) (xy 180.206744 -26.067488)
			(xy 180.151278 -26.1315) (xy 180.08998 -26.189951) (xy 180.023403 -26.24231) (xy 179.95215 -26.288104)
			(xy 179.876867 -26.326917) (xy 179.798236 -26.358399) (xy 179.716968 -26.382264) (xy 179.633799 -26.398297)
			(xy 179.549484 -26.406351) (xy 179.507134 -26.406856) (xy 179.505864 -26.406856) (xy 179.456029 -26.406131)
			(xy 179.35699 -26.394927) (xy 179.308252 -26.384504) (xy 179.297742 -26.382653) (xy 179.276827 -26.386794)
			(xy 179.259367 -26.39903) (xy 179.253388 -26.407872) (xy 179.230217 -26.445289) (xy 179.177598 -26.515842)
			(xy 179.118275 -26.58086) (xy 179.052827 -26.639708) (xy 179.017676 -26.66619) (xy 179.009104 -26.673102)
			(xy 178.998441 -26.692343) (xy 178.997102 -26.703274) (xy 178.993441 -26.744651) (xy 178.979354 -26.826519)
			(xy 178.957697 -26.906717) (xy 178.928657 -26.984547) (xy 178.892489 -27.059331) (xy 178.849506 -27.130418)
			(xy 178.835198 -27.149749) (xy 180.032656 -27.149749) (xy 180.032656 -27.065027) (xy 180.040709 -26.98069)
			(xy 180.056743 -26.8975) (xy 180.080611 -26.81621) (xy 180.112099 -26.737558) (xy 180.150921 -26.662255)
			(xy 180.196724 -26.590983) (xy 180.249095 -26.524387) (xy 180.30756 -26.463072) (xy 180.371588 -26.407591)
			(xy 180.4406 -26.358448) (xy 180.51397 -26.316088) (xy 180.591035 -26.280893) (xy 180.671097 -26.253184)
			(xy 180.75343 -26.23321) (xy 180.837289 -26.221153) (xy 180.921914 -26.217122) (xy 181.006539 -26.221153)
			(xy 181.090398 -26.23321) (xy 181.172731 -26.253184) (xy 181.252793 -26.280893) (xy 181.329858 -26.316088)
			(xy 181.403228 -26.358448) (xy 181.47224 -26.407591) (xy 181.536268 -26.463072) (xy 181.594733 -26.524387)
			(xy 181.647104 -26.590983) (xy 181.692907 -26.662255) (xy 181.731729 -26.737558) (xy 181.763217 -26.81621)
			(xy 181.787085 -26.8975) (xy 181.803119 -26.98069) (xy 181.811172 -27.065027) (xy 181.811676 -27.107388)
			(xy 181.811172 -27.149749) (xy 181.803119 -27.234086) (xy 181.787085 -27.317276) (xy 181.763217 -27.398566)
			(xy 181.731729 -27.477218) (xy 181.692907 -27.552521) (xy 181.647104 -27.623793) (xy 181.594733 -27.690389)
			(xy 181.536268 -27.751704) (xy 181.47224 -27.807185) (xy 181.403228 -27.856328) (xy 181.329858 -27.898688)
			(xy 181.252793 -27.933883) (xy 181.172731 -27.961592) (xy 181.090398 -27.981566) (xy 181.006539 -27.993623)
			(xy 180.921914 -27.997655) (xy 180.837289 -27.993623) (xy 180.75343 -27.981566) (xy 180.671097 -27.961592)
			(xy 180.591035 -27.933883) (xy 180.51397 -27.898688) (xy 180.4406 -27.856328) (xy 180.371588 -27.807185)
			(xy 180.30756 -27.751704) (xy 180.249095 -27.690389) (xy 180.196724 -27.623793) (xy 180.150921 -27.552521)
			(xy 180.112099 -27.477218) (xy 180.080611 -27.398566) (xy 180.056743 -27.317276) (xy 180.040709 -27.234086)
			(xy 180.032656 -27.149749) (xy 178.835198 -27.149749) (xy 178.800084 -27.197189) (xy 178.744653 -27.259061)
			(xy 178.683695 -27.315497) (xy 178.617742 -27.366004) (xy 178.547367 -27.410143) (xy 178.473184 -27.447529)
			(xy 178.395839 -27.477837) (xy 178.316006 -27.500803) (xy 178.234379 -27.516227) (xy 178.15167 -27.523974)
			(xy 178.110134 -27.524456) (xy 178.109626 -27.524456) (xy 178.065862 -27.523929) (xy 177.978756 -27.515357)
			(xy 177.892915 -27.498263) (xy 177.809169 -27.472814) (xy 177.728331 -27.439255) (xy 177.68951 -27.419046)
			(xy 177.678157 -27.413719) (xy 177.653111 -27.413719) (xy 177.641758 -27.419046) (xy 177.602894 -27.439282)
			(xy 177.521951 -27.472849) (xy 177.438101 -27.498301) (xy 177.352156 -27.515391) (xy 177.264948 -27.523955)
			(xy 177.221134 -27.524456) (xy 177.177318 -27.523994) (xy 177.090106 -27.515442) (xy 177.004158 -27.498348)
			(xy 176.920311 -27.472879) (xy 176.839376 -27.439281) (xy 176.80051 -27.419046) (xy 176.789157 -27.413719)
			(xy 176.764111 -27.413719) (xy 176.752758 -27.419046) (xy 176.713921 -27.439222) (xy 176.633081 -27.472767)
			(xy 176.549339 -27.498216) (xy 176.463504 -27.515325) (xy 176.376404 -27.523927) (xy 176.332642 -27.524456)
			(xy 176.332134 -27.524456) (xy 176.291028 -27.523955) (xy 176.209165 -27.516374) (xy 176.128351 -27.501273)
			(xy 176.049275 -27.47878) (xy 175.972611 -27.449089) (xy 175.899013 -27.412452) (xy 175.829109 -27.369181)
			(xy 175.763495 -27.319646) (xy 175.702731 -27.264268) (xy 175.647335 -27.203522) (xy 175.597779 -27.137923)
			(xy 175.554486 -27.068033) (xy 175.517825 -26.994447) (xy 175.488109 -26.917792) (xy 175.465592 -26.838723)
			(xy 175.450465 -26.757914) (xy 175.442858 -26.676054) (xy 175.442372 -26.634948) (xy 142.385288 -26.634948)
			(xy 142.385288 -26.76779) (xy 142.384802 -26.795059) (xy 142.37704 -26.849043) (xy 142.361675 -26.901373)
			(xy 142.339018 -26.950983) (xy 142.309532 -26.996864) (xy 142.273817 -27.038081) (xy 142.2326 -27.073796)
			(xy 142.186719 -27.103282) (xy 142.137109 -27.125939) (xy 142.084779 -27.141304) (xy 142.030795 -27.149066)
			(xy 141.976257 -27.149066) (xy 141.922273 -27.141304) (xy 141.869943 -27.125939) (xy 141.820333 -27.103282)
			(xy 141.774452 -27.073796) (xy 141.733235 -27.038081) (xy 141.69752 -26.996864) (xy 141.668034 -26.950983)
			(xy 141.645377 -26.901373) (xy 141.630012 -26.849043) (xy 141.62225 -26.795059) (xy 141.621764 -26.76779)
			(xy 131.450588 -26.76779) (xy 131.450588 -27.75458) (xy 131.450102 -27.781831) (xy 131.442346 -27.835779)
			(xy 131.426991 -27.888074) (xy 131.404349 -27.937651) (xy 131.374883 -27.983501) (xy 131.339192 -28.024692)
			(xy 131.298001 -28.060383) (xy 131.252151 -28.089849) (xy 131.202574 -28.112491) (xy 131.150279 -28.127846)
			(xy 131.096331 -28.135602) (xy 131.041829 -28.135602) (xy 130.987881 -28.127846) (xy 130.935586 -28.112491)
			(xy 130.886009 -28.089849) (xy 130.840159 -28.060383) (xy 130.798968 -28.024692) (xy 130.763277 -27.983501)
			(xy 130.733811 -27.937651) (xy 130.711169 -27.888074) (xy 130.695814 -27.835779) (xy 130.688058 -27.781831)
			(xy 130.687572 -27.75458) (xy 17.470427 -27.75458) (xy 17.770856 -28.07589) (xy 17.824996 -28.134528)
			(xy 17.928078 -28.256394) (xy 18.024957 -28.383247) (xy 18.115392 -28.514772) (xy 18.199158 -28.650641)
			(xy 18.276047 -28.790516) (xy 18.345869 -28.934051) (xy 18.408448 -29.080887) (xy 18.463631 -29.230661)
			(xy 18.511279 -29.382999) (xy 18.546379 -29.51861) (xy 101.326696 -29.51861) (xy 101.326696 -28.65501)
			(xy 101.327182 -28.627759) (xy 101.334938 -28.573811) (xy 101.350293 -28.521516) (xy 101.372935 -28.471939)
			(xy 101.402401 -28.426089) (xy 101.438092 -28.384898) (xy 101.479283 -28.349207) (xy 101.525133 -28.319741)
			(xy 101.57471 -28.297099) (xy 101.627005 -28.281744) (xy 101.680953 -28.273988) (xy 101.735455 -28.273988)
			(xy 101.789403 -28.281744) (xy 101.841698 -28.297099) (xy 101.891275 -28.319741) (xy 101.937125 -28.349207)
			(xy 101.978316 -28.384898) (xy 102.014007 -28.426089) (xy 102.043473 -28.471939) (xy 102.066115 -28.521516)
			(xy 102.08147 -28.573811) (xy 102.089226 -28.627759) (xy 102.089712 -28.65501) (xy 102.089712 -29.24302)
			(xy 135.551672 -29.24302) (xy 135.551672 -28.25242) (xy 135.552158 -28.225169) (xy 135.559914 -28.171221)
			(xy 135.575269 -28.118926) (xy 135.597911 -28.069349) (xy 135.627377 -28.023499) (xy 135.663068 -27.982308)
			(xy 135.704259 -27.946617) (xy 135.750109 -27.917151) (xy 135.799686 -27.894509) (xy 135.851981 -27.879154)
			(xy 135.905929 -27.871398) (xy 135.960431 -27.871398) (xy 136.014379 -27.879154) (xy 136.066674 -27.894509)
			(xy 136.116251 -27.917151) (xy 136.162101 -27.946617) (xy 136.203292 -27.982308) (xy 136.238983 -28.023499)
			(xy 136.268449 -28.069349) (xy 136.291091 -28.118926) (xy 136.306446 -28.171221) (xy 136.314202 -28.225169)
			(xy 136.314688 -28.25242) (xy 136.314688 -28.526871) (xy 139.853386 -28.526871) (xy 139.853386 -28.472329)
			(xy 139.861148 -28.418343) (xy 139.876513 -28.366011) (xy 139.89917 -28.316397) (xy 139.928656 -28.270513)
			(xy 139.964371 -28.229293) (xy 140.005589 -28.193574) (xy 140.051471 -28.164084) (xy 140.101082 -28.141424)
			(xy 140.153414 -28.126054) (xy 140.207399 -28.118289) (xy 140.23467 -28.1178) (xy 141.09827 -28.1178)
			(xy 141.12554 -28.118337) (xy 141.179524 -28.126095) (xy 141.231856 -28.141457) (xy 141.281468 -28.164111)
			(xy 141.32735 -28.193595) (xy 141.36857 -28.229309) (xy 141.404287 -28.270526) (xy 141.433775 -28.316406)
			(xy 141.456432 -28.366016) (xy 141.471798 -28.418346) (xy 141.479561 -28.47233) (xy 141.479561 -28.52687)
			(xy 141.471798 -28.580854) (xy 141.456432 -28.633184) (xy 141.433775 -28.682794) (xy 141.404287 -28.728674)
			(xy 141.36857 -28.769891) (xy 141.32735 -28.805605) (xy 141.281468 -28.835089) (xy 141.231856 -28.857743)
			(xy 141.179524 -28.873105) (xy 141.12554 -28.880863) (xy 141.09827 -28.881324) (xy 140.23467 -28.881324)
			(xy 140.207399 -28.880911) (xy 140.153414 -28.873146) (xy 140.101082 -28.857776) (xy 140.051471 -28.835116)
			(xy 140.005589 -28.805626) (xy 139.964371 -28.769907) (xy 139.928656 -28.728687) (xy 139.89917 -28.682803)
			(xy 139.876513 -28.633189) (xy 139.861148 -28.580857) (xy 139.853386 -28.526871) (xy 136.314688 -28.526871)
			(xy 136.314688 -29.24302) (xy 136.314202 -29.270271) (xy 136.306446 -29.324219) (xy 136.291091 -29.376514)
			(xy 136.268449 -29.426091) (xy 136.238983 -29.471941) (xy 136.203292 -29.513132) (xy 136.162101 -29.548823)
			(xy 136.116251 -29.578289) (xy 136.066674 -29.600931) (xy 136.014379 -29.616286) (xy 135.960431 -29.624042)
			(xy 135.905929 -29.624042) (xy 135.851981 -29.616286) (xy 135.799686 -29.600931) (xy 135.750109 -29.578289)
			(xy 135.704259 -29.548823) (xy 135.663068 -29.513132) (xy 135.627377 -29.471941) (xy 135.597911 -29.426091)
			(xy 135.575269 -29.376514) (xy 135.559914 -29.324219) (xy 135.552158 -29.270271) (xy 135.551672 -29.24302)
			(xy 102.089712 -29.24302) (xy 102.089712 -29.51861) (xy 102.089226 -29.545861) (xy 102.08147 -29.599809)
			(xy 102.066115 -29.652104) (xy 102.043473 -29.701681) (xy 102.014007 -29.747531) (xy 101.978316 -29.788722)
			(xy 101.937125 -29.824413) (xy 101.891275 -29.853879) (xy 101.841698 -29.876521) (xy 101.789403 -29.891876)
			(xy 101.735455 -29.899632) (xy 101.680953 -29.899632) (xy 101.627005 -29.891876) (xy 101.57471 -29.876521)
			(xy 101.525133 -29.853879) (xy 101.479283 -29.824413) (xy 101.438092 -29.788722) (xy 101.402401 -29.747531)
			(xy 101.372935 -29.701681) (xy 101.350293 -29.652104) (xy 101.334938 -29.599809) (xy 101.327182 -29.545861)
			(xy 101.326696 -29.51861) (xy 18.546379 -29.51861) (xy 18.551274 -29.537523) (xy 18.583516 -29.693848)
			(xy 18.607926 -29.851586) (xy 18.624443 -30.010345) (xy 18.63109 -30.1338) (xy 197.595716 -30.1338)
			(xy 197.599747 -30.049172) (xy 197.611805 -29.965311) (xy 197.631779 -29.882976) (xy 197.65949 -29.802912)
			(xy 197.694686 -29.725844) (xy 197.737048 -29.652472) (xy 197.786193 -29.583458) (xy 197.841676 -29.519429)
			(xy 197.902994 -29.460963) (xy 197.969592 -29.408591) (xy 198.040866 -29.362787) (xy 198.116172 -29.323965)
			(xy 198.194827 -29.292477) (xy 198.276119 -29.268609) (xy 198.359312 -29.252576) (xy 198.443652 -29.244524)
			(xy 198.486014 -29.244036) (xy 198.524304 -29.244437) (xy 198.600598 -29.251046) (xy 198.676041 -29.264197)
			(xy 198.750071 -29.283791) (xy 198.786242 -29.29636) (xy 198.794679 -29.299011) (xy 198.812349 -29.299011)
			(xy 198.820786 -29.29636) (xy 198.856961 -29.283808) (xy 198.930995 -29.264238) (xy 199.006435 -29.251093)
			(xy 199.082726 -29.244471) (xy 199.121014 -29.244036) (xy 199.159304 -29.244437) (xy 199.235598 -29.251046)
			(xy 199.311041 -29.264197) (xy 199.385071 -29.283791) (xy 199.421242 -29.29636) (xy 199.429679 -29.299011)
			(xy 199.447349 -29.299011) (xy 199.455786 -29.29636) (xy 199.491961 -29.283808) (xy 199.565995 -29.264238)
			(xy 199.641435 -29.251093) (xy 199.717726 -29.244471) (xy 199.756014 -29.244036) (xy 199.794304 -29.244437)
			(xy 199.870598 -29.251046) (xy 199.946041 -29.264197) (xy 200.020071 -29.283791) (xy 200.056242 -29.29636)
			(xy 200.064679 -29.299011) (xy 200.082349 -29.299011) (xy 200.090786 -29.29636) (xy 200.126961 -29.283808)
			(xy 200.200995 -29.264238) (xy 200.276435 -29.251093) (xy 200.352726 -29.244471) (xy 200.391014 -29.244036)
			(xy 200.431702 -29.244422) (xy 200.512738 -29.251848) (xy 200.592757 -29.266645) (xy 200.67109 -29.288689)
			(xy 200.747082 -29.317797) (xy 200.820096 -29.353725) (xy 200.889524 -29.396173) (xy 200.954784 -29.444785)
			(xy 201.015331 -29.499155) (xy 201.070657 -29.558829) (xy 201.120302 -29.623307) (xy 201.163849 -29.69205)
			(xy 201.200934 -29.764484) (xy 201.216514 -29.802074) (xy 201.22098 -29.811942) (xy 201.236608 -29.826918)
			(xy 201.256995 -29.83419) (xy 201.267822 -29.833824) (xy 201.286077 -29.832403) (xy 201.322664 -29.83088)
			(xy 201.340974 -29.830776) (xy 201.383338 -29.831187) (xy 201.467682 -29.839239) (xy 201.550879 -29.855272)
			(xy 201.632176 -29.87914) (xy 201.710835 -29.910629) (xy 201.786145 -29.949452) (xy 201.857423 -29.995258)
			(xy 201.924025 -30.047632) (xy 201.985346 -30.1061) (xy 202.040832 -30.170132) (xy 202.08998 -30.239149)
			(xy 202.132344 -30.312525) (xy 202.167542 -30.389596) (xy 202.195254 -30.469663) (xy 202.21523 -30.552003)
			(xy 202.227288 -30.635868) (xy 202.23132 -30.7205) (xy 202.227288 -30.805132) (xy 202.21523 -30.888997)
			(xy 202.195254 -30.971337) (xy 202.167542 -31.051404) (xy 202.132344 -31.128475) (xy 202.08998 -31.201851)
			(xy 202.040832 -31.270868) (xy 201.985346 -31.3349) (xy 201.924025 -31.393368) (xy 201.857423 -31.445742)
			(xy 201.786145 -31.491548) (xy 201.710835 -31.530371) (xy 201.632176 -31.56186) (xy 201.550879 -31.585728)
			(xy 201.467682 -31.601761) (xy 201.383338 -31.609813) (xy 201.340974 -31.6103) (xy 201.302684 -31.609905)
			(xy 201.226389 -31.603295) (xy 201.150947 -31.590142) (xy 201.076917 -31.570546) (xy 201.040746 -31.557976)
			(xy 201.032309 -31.555325) (xy 201.014639 -31.555325) (xy 201.006202 -31.557976) (xy 200.970027 -31.570528)
			(xy 200.895993 -31.590099) (xy 200.820553 -31.603244) (xy 200.744262 -31.609866) (xy 200.705974 -31.6103)
			(xy 200.667684 -31.609905) (xy 200.591389 -31.603295) (xy 200.515947 -31.590142) (xy 200.441917 -31.570546)
			(xy 200.405746 -31.557976) (xy 200.397309 -31.555325) (xy 200.379639 -31.555325) (xy 200.371202 -31.557976)
			(xy 200.335027 -31.570528) (xy 200.260993 -31.590099) (xy 200.185553 -31.603244) (xy 200.109262 -31.609866)
			(xy 200.070974 -31.6103) (xy 200.032684 -31.609905) (xy 199.956389 -31.603295) (xy 199.880947 -31.590142)
			(xy 199.806917 -31.570546) (xy 199.770746 -31.557976) (xy 199.762309 -31.555325) (xy 199.744639 -31.555325)
			(xy 199.736202 -31.557976) (xy 199.700027 -31.570528) (xy 199.625993 -31.590099) (xy 199.550553 -31.603244)
			(xy 199.474262 -31.609866) (xy 199.435974 -31.6103) (xy 199.395288 -31.609814) (xy 199.314256 -31.602396)
			(xy 199.23424 -31.587608) (xy 199.15591 -31.565572) (xy 199.07992 -31.536472) (xy 199.006906 -31.500553)
			(xy 198.937478 -31.458114) (xy 198.872217 -31.40951) (xy 198.81167 -31.355148) (xy 198.756341 -31.295482)
			(xy 198.706694 -31.231012) (xy 198.663144 -31.162275) (xy 198.626056 -31.089848) (xy 198.610474 -31.052262)
			(xy 198.605924 -31.042441) (xy 198.590335 -31.027459) (xy 198.569982 -31.020164) (xy 198.559166 -31.020512)
			(xy 198.540911 -31.021927) (xy 198.504324 -31.023454) (xy 198.486014 -31.02356) (xy 198.443652 -31.023076)
			(xy 198.359312 -31.015024) (xy 198.276119 -30.998991) (xy 198.194827 -30.975123) (xy 198.116172 -30.943635)
			(xy 198.040866 -30.904813) (xy 197.969592 -30.859009) (xy 197.902994 -30.806637) (xy 197.841676 -30.748171)
			(xy 197.786193 -30.684142) (xy 197.737048 -30.615128) (xy 197.694686 -30.541756) (xy 197.65949 -30.464688)
			(xy 197.631779 -30.384624) (xy 197.611805 -30.302289) (xy 197.599747 -30.218428) (xy 197.595716 -30.1338)
			(xy 18.63109 -30.1338) (xy 18.633025 -30.16973) (xy 18.633652 -30.329344) (xy 18.626321 -30.488792)
			(xy 18.611051 -30.647675) (xy 18.587881 -30.8056) (xy 18.556867 -30.962174) (xy 18.518086 -31.117007)
			(xy 18.471636 -31.269714) (xy 18.417631 -31.419917) (xy 18.356206 -31.56724) (xy 18.287514 -31.711318)
			(xy 18.211725 -31.851793) (xy 18.129028 -31.988316) (xy 18.039629 -32.120546) (xy 17.943749 -32.248156)
			(xy 17.841627 -32.370828) (xy 17.733517 -32.488256) (xy 17.619688 -32.60015) (xy 17.500423 -32.70623)
			(xy 17.376019 -32.806234) (xy 17.246784 -32.899911) (xy 17.173557 -32.94761) (xy 102.642416 -32.94761)
			(xy 102.642416 -31.95701) (xy 102.642902 -31.929759) (xy 102.650658 -31.875811) (xy 102.666013 -31.823516)
			(xy 102.688655 -31.773939) (xy 102.718121 -31.728089) (xy 102.753812 -31.686898) (xy 102.795003 -31.651207)
			(xy 102.840853 -31.621741) (xy 102.89043 -31.599099) (xy 102.942725 -31.583744) (xy 102.996673 -31.575988)
			(xy 103.051175 -31.575988) (xy 103.105123 -31.583744) (xy 103.157418 -31.599099) (xy 103.206995 -31.621741)
			(xy 103.252845 -31.651207) (xy 103.294036 -31.686898) (xy 103.329727 -31.728089) (xy 103.359193 -31.773939)
			(xy 103.381835 -31.823516) (xy 103.39719 -31.875811) (xy 103.404946 -31.929759) (xy 103.405432 -31.95701)
			(xy 103.405432 -32.405066) (xy 105.659936 -32.405066) (xy 105.659936 -31.541466) (xy 105.660422 -31.514215)
			(xy 105.668178 -31.460267) (xy 105.683533 -31.407972) (xy 105.706175 -31.358395) (xy 105.735641 -31.312545)
			(xy 105.771332 -31.271354) (xy 105.812523 -31.235663) (xy 105.858373 -31.206197) (xy 105.90795 -31.183555)
			(xy 105.960245 -31.1682) (xy 106.014193 -31.160444) (xy 106.068695 -31.160444) (xy 106.122643 -31.1682)
			(xy 106.174938 -31.183555) (xy 106.224515 -31.206197) (xy 106.270365 -31.235663) (xy 106.311556 -31.271354)
			(xy 106.347247 -31.312545) (xy 106.376713 -31.358395) (xy 106.399355 -31.407972) (xy 106.41471 -31.460267)
			(xy 106.422466 -31.514215) (xy 106.422952 -31.541466) (xy 106.422952 -31.65856) (xy 140.278612 -31.65856)
			(xy 140.278612 -30.79496) (xy 140.279098 -30.767709) (xy 140.286854 -30.713761) (xy 140.302209 -30.661466)
			(xy 140.324851 -30.611889) (xy 140.354317 -30.566039) (xy 140.390008 -30.524848) (xy 140.431199 -30.489157)
			(xy 140.477049 -30.459691) (xy 140.526626 -30.437049) (xy 140.578921 -30.421694) (xy 140.632869 -30.413938)
			(xy 140.687371 -30.413938) (xy 140.741319 -30.421694) (xy 140.793614 -30.437049) (xy 140.843191 -30.459691)
			(xy 140.889041 -30.489157) (xy 140.930232 -30.524848) (xy 140.965923 -30.566039) (xy 140.995389 -30.611889)
			(xy 141.018031 -30.661466) (xy 141.033386 -30.713761) (xy 141.041142 -30.767709) (xy 141.041628 -30.79496)
			(xy 141.041628 -31.65856) (xy 141.041311 -31.67634) (xy 144.616932 -31.67634) (xy 144.616932 -30.81274)
			(xy 144.617418 -30.785489) (xy 144.625174 -30.731541) (xy 144.640529 -30.679246) (xy 144.663171 -30.629669)
			(xy 144.692637 -30.583819) (xy 144.728328 -30.542628) (xy 144.769519 -30.506937) (xy 144.815369 -30.477471)
			(xy 144.864946 -30.454829) (xy 144.917241 -30.439474) (xy 144.971189 -30.431718) (xy 145.025691 -30.431718)
			(xy 145.079639 -30.439474) (xy 145.131934 -30.454829) (xy 145.181511 -30.477471) (xy 145.227361 -30.506937)
			(xy 145.268552 -30.542628) (xy 145.304243 -30.583819) (xy 145.333709 -30.629669) (xy 145.356351 -30.679246)
			(xy 145.371706 -30.731541) (xy 145.379462 -30.785489) (xy 145.379948 -30.81274) (xy 145.379948 -31.67634)
			(xy 145.379462 -31.703591) (xy 145.371706 -31.757539) (xy 145.356351 -31.809834) (xy 145.333709 -31.859411)
			(xy 145.304243 -31.905261) (xy 145.268552 -31.946452) (xy 145.227361 -31.982143) (xy 145.181511 -32.011609)
			(xy 145.131934 -32.034251) (xy 145.079639 -32.049606) (xy 145.025691 -32.057362) (xy 144.971189 -32.057362)
			(xy 144.917241 -32.049606) (xy 144.864946 -32.034251) (xy 144.815369 -32.011609) (xy 144.769519 -31.982143)
			(xy 144.728328 -31.946452) (xy 144.692637 -31.905261) (xy 144.663171 -31.859411) (xy 144.640529 -31.809834)
			(xy 144.625174 -31.757539) (xy 144.617418 -31.703591) (xy 144.616932 -31.67634) (xy 141.041311 -31.67634)
			(xy 141.041142 -31.685811) (xy 141.033386 -31.739759) (xy 141.018031 -31.792054) (xy 140.995389 -31.841631)
			(xy 140.965923 -31.887481) (xy 140.930232 -31.928672) (xy 140.889041 -31.964363) (xy 140.843191 -31.993829)
			(xy 140.793614 -32.016471) (xy 140.741319 -32.031826) (xy 140.687371 -32.039582) (xy 140.632869 -32.039582)
			(xy 140.578921 -32.031826) (xy 140.526626 -32.016471) (xy 140.477049 -31.993829) (xy 140.431199 -31.964363)
			(xy 140.390008 -31.928672) (xy 140.354317 -31.887481) (xy 140.324851 -31.841631) (xy 140.302209 -31.792054)
			(xy 140.286854 -31.739759) (xy 140.279098 -31.685811) (xy 140.278612 -31.65856) (xy 106.422952 -31.65856)
			(xy 106.422952 -32.405066) (xy 106.422466 -32.432317) (xy 106.41471 -32.486265) (xy 106.399355 -32.53856)
			(xy 106.376713 -32.588137) (xy 106.347247 -32.633987) (xy 106.311556 -32.675178) (xy 106.270365 -32.710869)
			(xy 106.224515 -32.740335) (xy 106.174938 -32.762977) (xy 106.122643 -32.778332) (xy 106.068695 -32.786088)
			(xy 106.014193 -32.786088) (xy 105.960245 -32.778332) (xy 105.90795 -32.762977) (xy 105.858373 -32.740335)
			(xy 105.812523 -32.710869) (xy 105.771332 -32.675178) (xy 105.735641 -32.633987) (xy 105.706175 -32.588137)
			(xy 105.683533 -32.53856) (xy 105.668178 -32.486265) (xy 105.660422 -32.432317) (xy 105.659936 -32.405066)
			(xy 103.405432 -32.405066) (xy 103.405432 -32.94761) (xy 103.404946 -32.974861) (xy 103.39719 -33.028809)
			(xy 103.390276 -33.052356) (xy 119.734235 -33.052356) (xy 119.734235 -32.997844) (xy 119.741993 -32.943888)
			(xy 119.757352 -32.891585) (xy 119.779997 -32.842) (xy 119.80947 -32.796143) (xy 119.845169 -32.754947)
			(xy 119.886367 -32.719252) (xy 119.932226 -32.689783) (xy 119.981813 -32.667141) (xy 120.034117 -32.651787)
			(xy 120.088074 -32.644033) (xy 120.11533 -32.643572) (xy 120.97893 -32.643572) (xy 121.006178 -32.6441)
			(xy 121.06012 -32.65186) (xy 121.112408 -32.667217) (xy 121.161979 -32.689858) (xy 121.207823 -32.719324)
			(xy 121.249008 -32.755014) (xy 121.284694 -32.796201) (xy 121.314156 -32.842047) (xy 121.336794 -32.89162)
			(xy 121.352147 -32.943909) (xy 121.359902 -32.997852) (xy 121.359902 -33.052348) (xy 121.352147 -33.106291)
			(xy 121.336794 -33.15858) (xy 121.314156 -33.208153) (xy 121.284694 -33.253999) (xy 121.249008 -33.295186)
			(xy 121.207823 -33.330876) (xy 121.161979 -33.360342) (xy 121.112408 -33.382983) (xy 121.06012 -33.39834)
			(xy 121.006178 -33.4061) (xy 120.97893 -33.406588) (xy 120.11533 -33.406588) (xy 120.088074 -33.406167)
			(xy 120.034117 -33.398413) (xy 119.981813 -33.383059) (xy 119.932226 -33.360417) (xy 119.886367 -33.330948)
			(xy 119.845169 -33.295253) (xy 119.80947 -33.254057) (xy 119.779997 -33.2082) (xy 119.757352 -33.158615)
			(xy 119.741993 -33.106312) (xy 119.734235 -33.052356) (xy 103.390276 -33.052356) (xy 103.381835 -33.081104)
			(xy 103.359193 -33.130681) (xy 103.329727 -33.176531) (xy 103.294036 -33.217722) (xy 103.252845 -33.253413)
			(xy 103.206995 -33.282879) (xy 103.157418 -33.305521) (xy 103.105123 -33.320876) (xy 103.051175 -33.328632)
			(xy 102.996673 -33.328632) (xy 102.942725 -33.320876) (xy 102.89043 -33.305521) (xy 102.840853 -33.282879)
			(xy 102.795003 -33.253413) (xy 102.753812 -33.217722) (xy 102.718121 -33.176531) (xy 102.688655 -33.130681)
			(xy 102.666013 -33.081104) (xy 102.650658 -33.028809) (xy 102.642902 -32.974861) (xy 102.642416 -32.94761)
			(xy 17.173557 -32.94761) (xy 17.11304 -32.98703) (xy 16.975119 -33.067374) (xy 16.833366 -33.140743)
			(xy 16.688131 -33.206955) (xy 16.539776 -33.265845) (xy 16.38867 -33.317266) (xy 16.235188 -33.361091)
			(xy 16.079713 -33.397211) (xy 15.922631 -33.425536) (xy 15.764332 -33.445995) (xy 15.605209 -33.458538)
			(xy 15.44566 -33.463134) (xy 15.286079 -33.459771) (xy 15.126865 -33.448457) (xy 14.968413 -33.42922)
			(xy 14.811116 -33.402109) (xy 14.655367 -33.367191) (xy 14.501552 -33.324553) (xy 14.350053 -33.2743)
			(xy 14.201248 -33.216557) (xy 14.055506 -33.151469) (xy 13.91319 -33.079197) (xy 13.774653 -32.999921)
			(xy 13.64024 -32.913837) (xy 13.510286 -32.82116) (xy 13.385112 -32.72212) (xy 13.265032 -32.616964)
			(xy 13.150342 -32.505953) (xy 13.095478 -32.447992) (xy 12.00277 -31.279592) (xy 11.948692 -31.220903)
			(xy 11.845626 -31.099035) (xy 11.748763 -30.972182) (xy 11.658343 -30.840658) (xy 11.574591 -30.704792)
			(xy 11.497716 -30.564919) (xy 11.427907 -30.421388) (xy 11.36534 -30.274557) (xy 11.310169 -30.124789)
			(xy 11.262532 -29.972457) (xy 11.222547 -29.81794) (xy 11.190314 -29.661623) (xy 11.165912 -29.503893)
			(xy 11.149402 -29.345143) (xy 11.140826 -29.185767) (xy 11.140205 -29.026161) (xy 0.509016 -29.026161)
			(xy 0.509016 -33.838388) (xy 122.111008 -33.838388) (xy 122.111008 -32.974788) (xy 122.111494 -32.947519)
			(xy 122.119256 -32.893535) (xy 122.134621 -32.841205) (xy 122.157278 -32.791595) (xy 122.186764 -32.745714)
			(xy 122.222479 -32.704497) (xy 122.263696 -32.668782) (xy 122.309577 -32.639296) (xy 122.359187 -32.616639)
			(xy 122.411517 -32.601274) (xy 122.465501 -32.593512) (xy 122.520039 -32.593512) (xy 122.574023 -32.601274)
			(xy 122.626353 -32.616639) (xy 122.675963 -32.639296) (xy 122.721844 -32.668782) (xy 122.763061 -32.704497)
			(xy 122.798776 -32.745714) (xy 122.828262 -32.791595) (xy 122.850919 -32.841205) (xy 122.866284 -32.893535)
			(xy 122.874046 -32.947519) (xy 122.874532 -32.974788) (xy 122.874532 -33.413556) (xy 124.175423 -33.413556)
			(xy 124.175423 -33.359044) (xy 124.183181 -33.305087) (xy 124.198539 -33.252783) (xy 124.221185 -33.203197)
			(xy 124.250658 -33.157339) (xy 124.286357 -33.116142) (xy 124.327555 -33.080446) (xy 124.373415 -33.050976)
			(xy 124.423002 -33.028332) (xy 124.475306 -33.012977) (xy 124.529264 -33.005222) (xy 124.55652 -33.00476)
			(xy 125.42012 -33.00476) (xy 125.447368 -33.005312) (xy 125.501309 -33.01307) (xy 125.553597 -33.028425)
			(xy 125.603167 -33.051066) (xy 125.649011 -33.08053) (xy 125.690196 -33.116218) (xy 125.725882 -33.157405)
			(xy 125.755344 -33.20325) (xy 125.777982 -33.252822) (xy 125.793335 -33.305111) (xy 125.80109 -33.359052)
			(xy 125.80109 -33.413548) (xy 125.793335 -33.467489) (xy 125.777982 -33.519778) (xy 125.755344 -33.56935)
			(xy 125.725882 -33.615195) (xy 125.690196 -33.656382) (xy 125.649011 -33.69207) (xy 125.603167 -33.721534)
			(xy 125.553597 -33.744175) (xy 125.501309 -33.75953) (xy 125.447368 -33.767288) (xy 125.42012 -33.767776)
			(xy 124.55652 -33.767776) (xy 124.529264 -33.767378) (xy 124.475306 -33.759623) (xy 124.423002 -33.744268)
			(xy 124.373415 -33.721624) (xy 124.327555 -33.692154) (xy 124.286357 -33.656458) (xy 124.250658 -33.615261)
			(xy 124.221185 -33.569403) (xy 124.198539 -33.519817) (xy 124.183181 -33.467513) (xy 124.175423 -33.413556)
			(xy 122.874532 -33.413556) (xy 122.874532 -33.838388) (xy 122.874046 -33.865657) (xy 122.866284 -33.919641)
			(xy 122.850919 -33.971971) (xy 122.828262 -34.021581) (xy 122.798776 -34.067462) (xy 122.763061 -34.108679)
			(xy 122.721844 -34.144394) (xy 122.675963 -34.17388) (xy 122.626353 -34.196537) (xy 122.574023 -34.211902)
			(xy 122.520039 -34.219664) (xy 122.465501 -34.219664) (xy 122.411517 -34.211902) (xy 122.359187 -34.196537)
			(xy 122.309577 -34.17388) (xy 122.263696 -34.144394) (xy 122.222479 -34.108679) (xy 122.186764 -34.067462)
			(xy 122.157278 -34.021581) (xy 122.134621 -33.971971) (xy 122.119256 -33.919641) (xy 122.111494 -33.865657)
			(xy 122.111008 -33.838388) (xy 0.509016 -33.838388) (xy 0.509016 -36.080556) (xy 122.143423 -36.080556)
			(xy 122.143423 -36.026044) (xy 122.151181 -35.972087) (xy 122.166539 -35.919783) (xy 122.189185 -35.870197)
			(xy 122.218658 -35.824339) (xy 122.254357 -35.783142) (xy 122.295555 -35.747446) (xy 122.341415 -35.717976)
			(xy 122.391002 -35.695332) (xy 122.443306 -35.679977) (xy 122.497264 -35.672222) (xy 122.52452 -35.67176)
			(xy 123.38812 -35.67176) (xy 123.415368 -35.672312) (xy 123.469309 -35.68007) (xy 123.521597 -35.695425)
			(xy 123.571167 -35.718066) (xy 123.617011 -35.74753) (xy 123.658196 -35.783218) (xy 123.693882 -35.824405)
			(xy 123.723344 -35.87025) (xy 123.745982 -35.919822) (xy 123.761335 -35.972111) (xy 123.76909 -36.026052)
			(xy 123.76909 -36.080548) (xy 123.761335 -36.134489) (xy 123.745982 -36.186778) (xy 123.723344 -36.23635)
			(xy 123.693882 -36.282195) (xy 123.658196 -36.323382) (xy 123.617011 -36.35907) (xy 123.571167 -36.388534)
			(xy 123.521597 -36.411175) (xy 123.469309 -36.42653) (xy 123.415368 -36.434288) (xy 123.38812 -36.434776)
			(xy 122.52452 -36.434776) (xy 122.497264 -36.434378) (xy 122.443306 -36.426623) (xy 122.391002 -36.411268)
			(xy 122.341415 -36.388624) (xy 122.295555 -36.359154) (xy 122.254357 -36.323458) (xy 122.218658 -36.282261)
			(xy 122.189185 -36.236403) (xy 122.166539 -36.186817) (xy 122.151181 -36.134513) (xy 122.143423 -36.080556)
			(xy 0.509016 -36.080556) (xy 0.509016 -39.23137) (xy 9.080235 -39.23137) (xy 9.080235 -39.10223)
			(xy 9.088185 -38.973335) (xy 9.104055 -38.845175) (xy 9.127784 -38.718234) (xy 9.159283 -38.592995)
			(xy 9.198432 -38.469932) (xy 9.245083 -38.349513) (xy 9.299058 -38.232194) (xy 9.360153 -38.11842)
			(xy 9.428136 -38.008623) (xy 9.50275 -37.90322) (xy 9.583711 -37.80261) (xy 9.670711 -37.707175)
			(xy 9.763422 -37.617276) (xy 9.861492 -37.533255) (xy 9.964547 -37.455431) (xy 10.072198 -37.384099)
			(xy 10.184037 -37.319529) (xy 10.299638 -37.261967) (xy 10.418563 -37.21163) (xy 10.540362 -37.16871)
			(xy 10.664572 -37.133369) (xy 10.790721 -37.105742) (xy 10.918333 -37.085933) (xy 11.046922 -37.074017)
			(xy 11.176 -37.070041) (xy 11.305078 -37.074017) (xy 11.433667 -37.085933) (xy 11.521898 -37.099629)
			(xy 170.60087 -37.099629) (xy 170.60087 -37.000299) (xy 170.608862 -36.901292) (xy 170.624796 -36.803249)
			(xy 170.648567 -36.706806) (xy 170.680022 -36.612588) (xy 170.718955 -36.521208) (xy 170.765116 -36.433256)
			(xy 170.818204 -36.349304) (xy 170.877875 -36.269895) (xy 170.943743 -36.195546) (xy 171.01538 -36.126738)
			(xy 171.092321 -36.063918) (xy 171.174067 -36.007493) (xy 171.260089 -35.957828) (xy 171.349828 -35.915246)
			(xy 171.442702 -35.880024) (xy 171.53811 -35.852388) (xy 171.635432 -35.83252) (xy 171.734037 -35.820547)
			(xy 171.833286 -35.816548) (xy 171.932535 -35.820547) (xy 172.03114 -35.83252) (xy 172.128462 -35.852388)
			(xy 172.22387 -35.880024) (xy 172.316744 -35.915246) (xy 172.406483 -35.957828) (xy 172.492505 -36.007493)
			(xy 172.574251 -36.063918) (xy 172.651192 -36.126738) (xy 172.722829 -36.195546) (xy 172.788697 -36.269895)
			(xy 172.848368 -36.349304) (xy 172.901456 -36.433256) (xy 172.947617 -36.521208) (xy 172.98655 -36.612588)
			(xy 173.018005 -36.706806) (xy 173.041776 -36.803249) (xy 173.05771 -36.901292) (xy 173.065702 -37.000299)
			(xy 173.066202 -37.049964) (xy 173.065702 -37.099629) (xy 173.05771 -37.198636) (xy 173.041776 -37.296679)
			(xy 173.034033 -37.328094) (xy 197.270624 -37.328094) (xy 197.271107 -37.28698) (xy 197.278695 -37.205103)
			(xy 197.293804 -37.124275) (xy 197.316307 -37.045187) (xy 197.346011 -36.968512) (xy 197.382664 -36.894904)
			(xy 197.425951 -36.824993) (xy 197.475504 -36.759373) (xy 197.5309 -36.698606) (xy 197.591667 -36.643209)
			(xy 197.657286 -36.593655) (xy 197.727197 -36.550367) (xy 197.800804 -36.513715) (xy 197.877479 -36.48401)
			(xy 197.956568 -36.461506) (xy 198.037395 -36.446396) (xy 198.119272 -36.438808) (xy 198.160386 -36.438332)
			(xy 198.203952 -36.438853) (xy 198.290667 -36.447372) (xy 198.376134 -36.464329) (xy 198.459533 -36.489562)
			(xy 198.540065 -36.522829) (xy 198.616958 -36.563811) (xy 198.689475 -36.612116) (xy 198.756921 -36.66728)
			(xy 198.81865 -36.728775) (xy 198.87407 -36.796011) (xy 198.922649 -36.868345) (xy 198.963923 -36.945081)
			(xy 198.997496 -37.025486) (xy 199.010778 -37.066982) (xy 199.013703 -37.075249) (xy 199.024271 -37.089233)
			(xy 199.038923 -37.098854) (xy 199.047354 -37.101272) (xy 199.088321 -37.111837) (xy 199.168226 -37.13965)
			(xy 199.24513 -37.174922) (xy 199.318339 -37.217334) (xy 199.387193 -37.266504) (xy 199.451068 -37.321986)
			(xy 199.509389 -37.383281) (xy 199.529427 -37.408809) (xy 207.619596 -37.408809) (xy 207.619596 -37.324087)
			(xy 207.627649 -37.23975) (xy 207.643683 -37.15656) (xy 207.667551 -37.07527) (xy 207.699039 -36.996618)
			(xy 207.737861 -36.921315) (xy 207.783664 -36.850043) (xy 207.836035 -36.783447) (xy 207.8945 -36.722132)
			(xy 207.958528 -36.666651) (xy 208.02754 -36.617508) (xy 208.10091 -36.575148) (xy 208.177975 -36.539953)
			(xy 208.258037 -36.512244) (xy 208.34037 -36.49227) (xy 208.424229 -36.480213) (xy 208.508854 -36.476182)
			(xy 208.593479 -36.480213) (xy 208.677338 -36.49227) (xy 208.759671 -36.512244) (xy 208.839733 -36.539953)
			(xy 208.916798 -36.575148) (xy 208.990168 -36.617508) (xy 209.05918 -36.666651) (xy 209.123208 -36.722132)
			(xy 209.181673 -36.783447) (xy 209.234044 -36.850043) (xy 209.279847 -36.921315) (xy 209.318669 -36.996618)
			(xy 209.350157 -37.07527) (xy 209.374025 -37.15656) (xy 209.390059 -37.23975) (xy 209.398112 -37.324087)
			(xy 209.398616 -37.366448) (xy 209.398112 -37.408809) (xy 209.390059 -37.493146) (xy 209.374025 -37.576336)
			(xy 209.350157 -37.657626) (xy 209.318669 -37.736278) (xy 209.279847 -37.811581) (xy 209.234044 -37.882853)
			(xy 209.181673 -37.949449) (xy 209.123208 -38.010764) (xy 209.05918 -38.066245) (xy 208.990168 -38.115388)
			(xy 208.916798 -38.157748) (xy 208.839733 -38.192943) (xy 208.759671 -38.220652) (xy 208.677338 -38.240626)
			(xy 208.593479 -38.252683) (xy 208.508854 -38.256715) (xy 208.424229 -38.252683) (xy 208.34037 -38.240626)
			(xy 208.258037 -38.220652) (xy 208.177975 -38.192943) (xy 208.10091 -38.157748) (xy 208.02754 -38.115388)
			(xy 207.958528 -38.066245) (xy 207.8945 -38.010764) (xy 207.836035 -37.949449) (xy 207.783664 -37.882853)
			(xy 207.737861 -37.811581) (xy 207.699039 -37.736278) (xy 207.667551 -37.657626) (xy 207.643683 -37.576336)
			(xy 207.627649 -37.493146) (xy 207.619596 -37.408809) (xy 199.529427 -37.408809) (xy 199.561629 -37.449835)
			(xy 199.607316 -37.521047) (xy 199.646037 -37.596273) (xy 199.677444 -37.674835) (xy 199.701252 -37.756024)
			(xy 199.717247 -37.839106) (xy 199.725284 -37.92333) (xy 199.725788 -37.965634) (xy 199.72532 -38.006748)
			(xy 199.71773 -38.088625) (xy 199.702618 -38.169453) (xy 199.680113 -38.248541) (xy 199.650407 -38.325216)
			(xy 199.613754 -38.398823) (xy 199.570465 -38.468734) (xy 199.520911 -38.534353) (xy 199.465514 -38.595119)
			(xy 199.404746 -38.650516) (xy 199.339127 -38.70007) (xy 199.269216 -38.743357) (xy 199.195608 -38.78001)
			(xy 199.118933 -38.809716) (xy 199.039845 -38.83222) (xy 198.959017 -38.847331) (xy 198.87714 -38.85492)
			(xy 198.836026 -38.855396) (xy 198.792461 -38.854844) (xy 198.705747 -38.846327) (xy 198.620282 -38.829372)
			(xy 198.536884 -38.804141) (xy 198.456353 -38.770876) (xy 198.379461 -38.729896) (xy 198.306944 -38.681594)
			(xy 198.239498 -38.626432) (xy 198.177769 -38.56494) (xy 198.122348 -38.497707) (xy 198.073767 -38.425377)
			(xy 198.032492 -38.348643) (xy 197.998917 -38.26824) (xy 197.985634 -38.226746) (xy 197.982688 -38.218487)
			(xy 197.97213 -38.204501) (xy 197.957486 -38.194877) (xy 197.949058 -38.192456) (xy 197.908101 -38.181857)
			(xy 197.828197 -38.154046) (xy 197.751293 -38.118776) (xy 197.678085 -38.076367) (xy 197.609232 -38.0272)
			(xy 197.545356 -37.97172) (xy 197.487035 -37.910428) (xy 197.434795 -37.843877) (xy 197.389107 -37.772668)
			(xy 197.350384 -37.697444) (xy 197.318976 -37.618885) (xy 197.295165 -37.537699) (xy 197.279169 -37.454619)
			(xy 197.271129 -37.370397) (xy 197.270624 -37.328094) (xy 173.034033 -37.328094) (xy 173.018005 -37.393122)
			(xy 172.98655 -37.48734) (xy 172.947617 -37.57872) (xy 172.901456 -37.666672) (xy 172.848368 -37.750624)
			(xy 172.788697 -37.830033) (xy 172.722829 -37.904382) (xy 172.651192 -37.97319) (xy 172.574251 -38.03601)
			(xy 172.492505 -38.092435) (xy 172.406483 -38.1421) (xy 172.316744 -38.184682) (xy 172.22387 -38.219904)
			(xy 172.128462 -38.24754) (xy 172.03114 -38.267408) (xy 171.932535 -38.279381) (xy 171.833286 -38.283381)
			(xy 171.734037 -38.279381) (xy 171.635432 -38.267408) (xy 171.53811 -38.24754) (xy 171.442702 -38.219904)
			(xy 171.349828 -38.184682) (xy 171.260089 -38.1421) (xy 171.174067 -38.092435) (xy 171.092321 -38.03601)
			(xy 171.01538 -37.97319) (xy 170.943743 -37.904382) (xy 170.877875 -37.830033) (xy 170.818204 -37.750624)
			(xy 170.765116 -37.666672) (xy 170.718955 -37.57872) (xy 170.680022 -37.48734) (xy 170.648567 -37.393122)
			(xy 170.624796 -37.296679) (xy 170.608862 -37.198636) (xy 170.60087 -37.099629) (xy 11.521898 -37.099629)
			(xy 11.561279 -37.105742) (xy 11.687428 -37.133369) (xy 11.811638 -37.16871) (xy 11.933437 -37.21163)
			(xy 12.052362 -37.261967) (xy 12.167963 -37.319529) (xy 12.279802 -37.384099) (xy 12.387453 -37.455431)
			(xy 12.490508 -37.533255) (xy 12.588578 -37.617276) (xy 12.681289 -37.707175) (xy 12.768289 -37.80261)
			(xy 12.84925 -37.90322) (xy 12.923864 -38.008623) (xy 12.991847 -38.11842) (xy 13.052942 -38.232194)
			(xy 13.106917 -38.349513) (xy 13.153568 -38.469932) (xy 13.192717 -38.592995) (xy 13.224216 -38.718234)
			(xy 13.247945 -38.845175) (xy 13.263815 -38.973335) (xy 13.271765 -39.10223) (xy 13.272262 -39.1668)
			(xy 13.271765 -39.23137) (xy 13.263815 -39.360265) (xy 13.256012 -39.423283) (xy 254.45872 -39.423283)
			(xy 254.45872 -39.338561) (xy 254.466773 -39.254224) (xy 254.482807 -39.171034) (xy 254.506675 -39.089744)
			(xy 254.538163 -39.011092) (xy 254.576985 -38.935789) (xy 254.622788 -38.864517) (xy 254.675159 -38.797921)
			(xy 254.733624 -38.736606) (xy 254.797652 -38.681125) (xy 254.866664 -38.631982) (xy 254.940034 -38.589622)
			(xy 255.017099 -38.554427) (xy 255.097161 -38.526718) (xy 255.179494 -38.506744) (xy 255.263353 -38.494687)
			(xy 255.347978 -38.490656) (xy 255.432603 -38.494687) (xy 255.516462 -38.506744) (xy 255.598795 -38.526718)
			(xy 255.678857 -38.554427) (xy 255.755922 -38.589622) (xy 255.829292 -38.631982) (xy 255.898304 -38.681125)
			(xy 255.962332 -38.736606) (xy 256.020797 -38.797921) (xy 256.073168 -38.864517) (xy 256.118971 -38.935789)
			(xy 256.157793 -39.011092) (xy 256.189281 -39.089744) (xy 256.213149 -39.171034) (xy 256.229183 -39.254224)
			(xy 256.237236 -39.338561) (xy 256.23774 -39.380922) (xy 256.237236 -39.423283) (xy 256.229183 -39.50762)
			(xy 256.213149 -39.59081) (xy 256.189281 -39.6721) (xy 256.157793 -39.750752) (xy 256.118971 -39.826055)
			(xy 256.073168 -39.897327) (xy 256.020797 -39.963923) (xy 255.962332 -40.025238) (xy 255.898304 -40.080719)
			(xy 255.829292 -40.129862) (xy 255.755922 -40.172222) (xy 255.678857 -40.207417) (xy 255.598795 -40.235126)
			(xy 255.516462 -40.2551) (xy 255.432603 -40.267157) (xy 255.347978 -40.271189) (xy 255.263353 -40.267157)
			(xy 255.179494 -40.2551) (xy 255.097161 -40.235126) (xy 255.017099 -40.207417) (xy 254.940034 -40.172222)
			(xy 254.866664 -40.129862) (xy 254.797652 -40.080719) (xy 254.733624 -40.025238) (xy 254.675159 -39.963923)
			(xy 254.622788 -39.897327) (xy 254.576985 -39.826055) (xy 254.538163 -39.750752) (xy 254.506675 -39.6721)
			(xy 254.482807 -39.59081) (xy 254.466773 -39.50762) (xy 254.45872 -39.423283) (xy 13.256012 -39.423283)
			(xy 13.247945 -39.488425) (xy 13.224216 -39.615366) (xy 13.192717 -39.740605) (xy 13.153568 -39.863668)
			(xy 13.106917 -39.984087) (xy 13.052942 -40.101406) (xy 12.991847 -40.21518) (xy 12.923864 -40.324977)
			(xy 12.84925 -40.43038) (xy 12.768289 -40.53099) (xy 12.681289 -40.626425) (xy 12.588578 -40.716324)
			(xy 12.490508 -40.800345) (xy 12.413317 -40.858637) (xy 24.936192 -40.858637) (xy 24.936192 -40.773915)
			(xy 24.944245 -40.689578) (xy 24.960279 -40.606388) (xy 24.984147 -40.525098) (xy 25.015635 -40.446446)
			(xy 25.054457 -40.371143) (xy 25.10026 -40.299871) (xy 25.152631 -40.233275) (xy 25.211096 -40.17196)
			(xy 25.275124 -40.116479) (xy 25.344136 -40.067336) (xy 25.417506 -40.024976) (xy 25.494571 -39.989781)
			(xy 25.574633 -39.962072) (xy 25.656966 -39.942098) (xy 25.740825 -39.930041) (xy 25.82545 -39.92601)
			(xy 25.910075 -39.930041) (xy 25.993934 -39.942098) (xy 26.076267 -39.962072) (xy 26.156329 -39.989781)
			(xy 26.233394 -40.024976) (xy 26.306764 -40.067336) (xy 26.375776 -40.116479) (xy 26.439804 -40.17196)
			(xy 26.498269 -40.233275) (xy 26.55064 -40.299871) (xy 26.596443 -40.371143) (xy 26.635265 -40.446446)
			(xy 26.666753 -40.525098) (xy 26.690621 -40.606388) (xy 26.706655 -40.689578) (xy 26.711938 -40.744902)
			(xy 235.083357 -40.744902) (xy 235.087362 -40.656994) (xy 235.099345 -40.569814) (xy 235.119205 -40.484085)
			(xy 235.14678 -40.400517) (xy 235.181839 -40.319803) (xy 235.224092 -40.242611) (xy 235.27319 -40.169582)
			(xy 235.328726 -40.10132) (xy 235.390238 -40.03839) (xy 235.457219 -39.981316) (xy 235.529112 -39.930568)
			(xy 235.605321 -39.886568) (xy 235.685216 -39.849681) (xy 235.768135 -39.820212) (xy 235.85339 -39.798405)
			(xy 235.940274 -39.784441) (xy 236.028068 -39.778435) (xy 236.116045 -39.780439) (xy 236.203475 -39.790434)
			(xy 236.289634 -39.808338) (xy 236.373808 -39.834002) (xy 236.455299 -39.867215) (xy 236.533433 -39.907701)
			(xy 236.607561 -39.955123) (xy 236.677069 -40.00909) (xy 236.741383 -40.069155) (xy 236.799967 -40.134819)
			(xy 236.852338 -40.205538) (xy 236.898061 -40.280726) (xy 236.936758 -40.359761) (xy 236.968107 -40.441987)
			(xy 236.991849 -40.526723) (xy 237.007787 -40.613267) (xy 237.015789 -40.700902) (xy 237.01629 -40.744902)
			(xy 237.015789 -40.788902) (xy 237.007787 -40.876537) (xy 236.994276 -40.9499) (xy 246.935452 -40.9499)
			(xy 246.939482 -40.865295) (xy 246.951537 -40.781456) (xy 246.971506 -40.699142) (xy 246.999209 -40.619099)
			(xy 247.034396 -40.542053) (xy 247.076747 -40.468699) (xy 247.125879 -40.399704) (xy 247.181347 -40.335692)
			(xy 247.242648 -40.277242) (xy 247.309228 -40.224883) (xy 247.380484 -40.179091) (xy 247.45577 -40.14028)
			(xy 247.534404 -40.1088) (xy 247.615675 -40.084938) (xy 247.698846 -40.06891) (xy 247.783163 -40.060859)
			(xy 247.825514 -40.060372) (xy 247.868043 -40.060872) (xy 247.952713 -40.068982) (xy 248.036223 -40.085137)
			(xy 248.11781 -40.109189) (xy 248.196728 -40.140918) (xy 248.272258 -40.180035) (xy 248.343709 -40.226182)
			(xy 248.41043 -40.278938) (xy 248.441464 -40.308022) (xy 248.441718 -40.308276) (xy 248.44904 -40.314652)
			(xy 248.467069 -40.321822) (xy 248.47677 -40.322246) (xy 248.557288 -40.321992) (xy 248.575576 -40.314626)
			(xy 248.582688 -40.307514) (xy 248.613778 -40.278057) (xy 248.680689 -40.224588) (xy 248.752429 -40.177798)
			(xy 248.828335 -40.13812) (xy 248.907704 -40.105923) (xy 248.9898 -40.081504) (xy 249.073863 -40.065089)
			(xy 249.159115 -40.056831) (xy 249.20194 -40.056308) (xy 249.202448 -40.056308) (xy 249.244796 -40.056782)
			(xy 249.329107 -40.064837) (xy 249.412272 -40.08087) (xy 249.493536 -40.104735) (xy 249.572163 -40.136216)
			(xy 249.647442 -40.175029) (xy 249.718691 -40.220821) (xy 249.785265 -40.273178) (xy 249.84656 -40.331627)
			(xy 249.902022 -40.395637) (xy 249.951149 -40.464629) (xy 249.993496 -40.537978) (xy 250.028678 -40.615021)
			(xy 250.056379 -40.695058) (xy 250.076346 -40.777367) (xy 250.088399 -40.8612) (xy 250.092429 -40.9458)
			(xy 250.088399 -41.0304) (xy 250.076346 -41.114233) (xy 250.056379 -41.196542) (xy 250.028678 -41.276579)
			(xy 249.993496 -41.353622) (xy 249.951149 -41.426971) (xy 249.902022 -41.495963) (xy 249.84656 -41.559973)
			(xy 249.785265 -41.618422) (xy 249.718691 -41.670779) (xy 249.647442 -41.716571) (xy 249.572163 -41.755384)
			(xy 249.493536 -41.786865) (xy 249.412272 -41.81073) (xy 249.329107 -41.826763) (xy 249.244796 -41.834818)
			(xy 249.202448 -41.835324) (xy 249.159919 -41.834822) (xy 249.07525 -41.826709) (xy 248.991741 -41.810552)
			(xy 248.910155 -41.7865) (xy 248.831237 -41.754771) (xy 248.755707 -41.715655) (xy 248.684255 -41.66951)
			(xy 248.617533 -41.616756) (xy 248.586498 -41.587674) (xy 248.586244 -41.58742) (xy 248.578903 -41.58107)
			(xy 248.560888 -41.573885) (xy 248.551192 -41.57345) (xy 248.470674 -41.573704) (xy 248.452386 -41.58107)
			(xy 248.445274 -41.588182) (xy 248.414201 -41.617657) (xy 248.347287 -41.671125) (xy 248.275544 -41.717913)
			(xy 248.199635 -41.757589) (xy 248.120264 -41.789784) (xy 248.038166 -41.8142) (xy 247.954101 -41.830612)
			(xy 247.868848 -41.838866) (xy 247.826022 -41.839388) (xy 247.825514 -41.839388) (xy 247.783163 -41.838941)
			(xy 247.698846 -41.83089) (xy 247.615675 -41.814862) (xy 247.534404 -41.791) (xy 247.45577 -41.75952)
			(xy 247.380484 -41.720709) (xy 247.309228 -41.674917) (xy 247.242648 -41.622558) (xy 247.181347 -41.564108)
			(xy 247.125879 -41.500096) (xy 247.076747 -41.431101) (xy 247.034396 -41.357747) (xy 246.999209 -41.280701)
			(xy 246.971506 -41.200658) (xy 246.951537 -41.118344) (xy 246.939482 -41.034505) (xy 246.935452 -40.9499)
			(xy 236.994276 -40.9499) (xy 236.991849 -40.963081) (xy 236.968107 -41.047817) (xy 236.936758 -41.130043)
			(xy 236.898061 -41.209078) (xy 236.852338 -41.284266) (xy 236.799967 -41.354985) (xy 236.741383 -41.420649)
			(xy 236.677069 -41.480714) (xy 236.607561 -41.534681) (xy 236.533433 -41.582103) (xy 236.455299 -41.622589)
			(xy 236.373808 -41.655802) (xy 236.289634 -41.681466) (xy 236.203475 -41.69937) (xy 236.116045 -41.709365)
			(xy 236.028068 -41.711369) (xy 235.940274 -41.705363) (xy 235.85339 -41.691399) (xy 235.768135 -41.669592)
			(xy 235.685216 -41.640123) (xy 235.605321 -41.603236) (xy 235.529112 -41.559236) (xy 235.457219 -41.508488)
			(xy 235.390238 -41.451414) (xy 235.328726 -41.388484) (xy 235.27319 -41.320222) (xy 235.224092 -41.247193)
			(xy 235.181839 -41.170001) (xy 235.14678 -41.089287) (xy 235.119205 -41.005719) (xy 235.099345 -40.91999)
			(xy 235.087362 -40.83281) (xy 235.083357 -40.744902) (xy 26.711938 -40.744902) (xy 26.714708 -40.773915)
			(xy 26.715212 -40.816276) (xy 26.714708 -40.858637) (xy 26.706655 -40.942974) (xy 26.690621 -41.026164)
			(xy 26.666753 -41.107454) (xy 26.635265 -41.186106) (xy 26.596443 -41.261409) (xy 26.55064 -41.332681)
			(xy 26.498269 -41.399277) (xy 26.439804 -41.460592) (xy 26.375776 -41.516073) (xy 26.306764 -41.565216)
			(xy 26.233394 -41.607576) (xy 26.156329 -41.642771) (xy 26.076267 -41.67048) (xy 25.993934 -41.690454)
			(xy 25.910075 -41.702511) (xy 25.82545 -41.706543) (xy 25.740825 -41.702511) (xy 25.656966 -41.690454)
			(xy 25.574633 -41.67048) (xy 25.494571 -41.642771) (xy 25.417506 -41.607576) (xy 25.344136 -41.565216)
			(xy 25.275124 -41.516073) (xy 25.211096 -41.460592) (xy 25.152631 -41.399277) (xy 25.10026 -41.332681)
			(xy 25.054457 -41.261409) (xy 25.015635 -41.186106) (xy 24.984147 -41.107454) (xy 24.960279 -41.026164)
			(xy 24.944245 -40.942974) (xy 24.936192 -40.858637) (xy 12.413317 -40.858637) (xy 12.387453 -40.878169)
			(xy 12.279802 -40.949501) (xy 12.167963 -41.014071) (xy 12.052362 -41.071633) (xy 11.933437 -41.12197)
			(xy 11.811638 -41.16489) (xy 11.687428 -41.200231) (xy 11.561279 -41.227858) (xy 11.433667 -41.247667)
			(xy 11.305078 -41.259583) (xy 11.176 -41.26356) (xy 11.046922 -41.259583) (xy 10.918333 -41.247667)
			(xy 10.790721 -41.227858) (xy 10.664572 -41.200231) (xy 10.540362 -41.16489) (xy 10.418563 -41.12197)
			(xy 10.299638 -41.071633) (xy 10.184037 -41.014071) (xy 10.072198 -40.949501) (xy 9.964547 -40.878169)
			(xy 9.861492 -40.800345) (xy 9.763422 -40.716324) (xy 9.670711 -40.626425) (xy 9.583711 -40.53099)
			(xy 9.50275 -40.43038) (xy 9.428136 -40.324977) (xy 9.360153 -40.21518) (xy 9.299058 -40.101406)
			(xy 9.245083 -39.984087) (xy 9.198432 -39.863668) (xy 9.159283 -39.740605) (xy 9.127784 -39.615366)
			(xy 9.104055 -39.488425) (xy 9.088185 -39.360265) (xy 9.080235 -39.23137) (xy 0.509016 -39.23137)
			(xy 0.509016 -43.481752) (xy 178.630072 -43.481752) (xy 178.630072 -42.618152) (xy 178.630558 -42.590883)
			(xy 178.63832 -42.536899) (xy 178.653685 -42.484569) (xy 178.676342 -42.434959) (xy 178.705828 -42.389078)
			(xy 178.741543 -42.347861) (xy 178.78276 -42.312146) (xy 178.828641 -42.28266) (xy 178.878251 -42.260003)
			(xy 178.930581 -42.244638) (xy 178.984565 -42.236876) (xy 179.039103 -42.236876) (xy 179.093087 -42.244638)
			(xy 179.145417 -42.260003) (xy 179.195027 -42.28266) (xy 179.240908 -42.312146) (xy 179.282125 -42.347861)
			(xy 179.31784 -42.389078) (xy 179.347326 -42.434959) (xy 179.369983 -42.484569) (xy 179.385348 -42.536899)
			(xy 179.39311 -42.590883) (xy 179.393596 -42.618152) (xy 179.393596 -43.481752) (xy 179.39311 -43.509021)
			(xy 179.385348 -43.563005) (xy 179.369983 -43.615335) (xy 179.347326 -43.664945) (xy 179.31784 -43.710826)
			(xy 179.282125 -43.752043) (xy 179.240908 -43.787758) (xy 179.195027 -43.817244) (xy 179.145417 -43.839901)
			(xy 179.093087 -43.855266) (xy 179.039103 -43.863028) (xy 178.984565 -43.863028) (xy 178.930581 -43.855266)
			(xy 178.878251 -43.839901) (xy 178.828641 -43.817244) (xy 178.78276 -43.787758) (xy 178.741543 -43.752043)
			(xy 178.705828 -43.710826) (xy 178.676342 -43.664945) (xy 178.653685 -43.615335) (xy 178.63832 -43.563005)
			(xy 178.630558 -43.509021) (xy 178.630072 -43.481752) (xy 0.509016 -43.481752) (xy 0.509016 -47.04994)
			(xy 59.582066 -47.04994) (xy 59.586045 -46.890389) (xy 59.597972 -46.731234) (xy 59.617818 -46.572872)
			(xy 59.645532 -46.415696) (xy 59.681047 -46.260096) (xy 59.724273 -46.10646) (xy 59.775104 -45.95517)
			(xy 59.833413 -45.806602) (xy 59.899054 -45.661125) (xy 59.971866 -45.519101) (xy 60.051666 -45.380882)
			(xy 60.138257 -45.246813) (xy 60.231423 -45.117227) (xy 60.330933 -44.992446) (xy 60.436538 -44.87278)
			(xy 60.547978 -44.758527) (xy 60.664973 -44.649971) (xy 60.787235 -44.547381) (xy 60.914458 -44.451014)
			(xy 61.046326 -44.361107) (xy 61.182512 -44.277886) (xy 61.322677 -44.201556) (xy 61.466472 -44.132307)
			(xy 61.613541 -44.070313) (xy 61.763517 -44.015726) (xy 61.916027 -43.968683) (xy 62.070693 -43.9293)
			(xy 62.227129 -43.897676) (xy 62.384947 -43.873888) (xy 62.543755 -43.857997) (xy 62.703158 -43.850041)
			(xy 62.782958 -43.849544) (xy 64.382904 -43.849544) (xy 64.462705 -43.850033) (xy 64.622107 -43.857989)
			(xy 64.780916 -43.87388) (xy 64.938734 -43.897668) (xy 65.095171 -43.929293) (xy 65.249837 -43.968675)
			(xy 65.402347 -44.015719) (xy 65.552323 -44.070306) (xy 65.699392 -44.132301) (xy 65.843188 -44.201549)
			(xy 65.983353 -44.277879) (xy 66.119539 -44.361101) (xy 66.251408 -44.451008) (xy 66.378631 -44.547376)
			(xy 66.500893 -44.649966) (xy 66.617889 -44.758522) (xy 66.729328 -44.872775) (xy 66.834934 -44.992442)
			(xy 66.934444 -45.117223) (xy 67.02761 -45.246809) (xy 67.114201 -45.380878) (xy 67.194001 -45.519097)
			(xy 67.266813 -45.661122) (xy 67.332455 -45.806599) (xy 67.390764 -45.955168) (xy 67.441595 -46.106458)
			(xy 67.484821 -46.260094) (xy 67.520336 -46.415694) (xy 67.54805 -46.572871) (xy 67.567896 -46.731233)
			(xy 67.579823 -46.890388) (xy 67.583802 -47.04994) (xy 89.78165 -47.04994) (xy 89.78563 -46.895439)
			(xy 89.797557 -46.741349) (xy 89.817402 -46.588076) (xy 89.84511 -46.436028) (xy 89.880608 -46.285609)
			(xy 89.923803 -46.137216) (xy 89.97458 -45.991243) (xy 90.032804 -45.848078) (xy 90.098321 -45.708101)
			(xy 90.170957 -45.571681) (xy 90.250519 -45.439181) (xy 90.336796 -45.310953) (xy 90.42956 -45.187337)
			(xy 90.528565 -45.068659) (xy 90.633548 -44.955236) (xy 90.74423 -44.847368) (xy 90.860319 -44.74534)
			(xy 90.981506 -44.649424) (xy 91.10747 -44.559873) (xy 91.237877 -44.476926) (xy 91.372381 -44.400801)
			(xy 91.510626 -44.331702) (xy 91.652244 -44.269811) (xy 91.796861 -44.215293) (xy 91.944092 -44.168291)
			(xy 92.093548 -44.128931) (xy 92.244832 -44.097317) (xy 92.397543 -44.073533) (xy 92.551275 -44.057642)
			(xy 92.705622 -44.049686) (xy 92.782898 -44.049188) (xy 94.383098 -44.049188) (xy 94.460374 -44.049669)
			(xy 94.614722 -44.057625) (xy 94.768456 -44.073516) (xy 94.921168 -44.0973) (xy 95.072452 -44.128914)
			(xy 95.221909 -44.168274) (xy 95.369142 -44.215276) (xy 95.513759 -44.269795) (xy 95.655379 -44.331686)
			(xy 95.793624 -44.400785) (xy 95.928129 -44.47691) (xy 96.058537 -44.559858) (xy 96.184502 -44.649409)
			(xy 96.30569 -44.745326) (xy 96.421779 -44.847354) (xy 96.532463 -44.955223) (xy 96.555487 -44.980098)
			(xy 181.659784 -44.980098) (xy 181.659784 -44.116498) (xy 181.66027 -44.089229) (xy 181.668032 -44.035245)
			(xy 181.683397 -43.982915) (xy 181.706054 -43.933305) (xy 181.73554 -43.887424) (xy 181.771255 -43.846207)
			(xy 181.812472 -43.810492) (xy 181.858353 -43.781006) (xy 181.907963 -43.758349) (xy 181.960293 -43.742984)
			(xy 182.014277 -43.735222) (xy 182.068815 -43.735222) (xy 182.122799 -43.742984) (xy 182.175129 -43.758349)
			(xy 182.224739 -43.781006) (xy 182.27062 -43.810492) (xy 182.311837 -43.846207) (xy 182.347552 -43.887424)
			(xy 182.377038 -43.933305) (xy 182.399695 -43.982915) (xy 182.412218 -44.025566) (xy 236.740192 -44.025566)
			(xy 236.74068 -43.984453) (xy 236.74827 -43.902577) (xy 236.763381 -43.82175) (xy 236.785886 -43.742663)
			(xy 236.815591 -43.665989) (xy 236.852243 -43.592383) (xy 236.895531 -43.522473) (xy 236.945083 -43.456854)
			(xy 237.000479 -43.396088) (xy 237.061245 -43.340691) (xy 237.126863 -43.291137) (xy 237.196773 -43.247849)
			(xy 237.270378 -43.211196) (xy 237.347052 -43.181489) (xy 237.426139 -43.158984) (xy 237.506965 -43.143872)
			(xy 237.588841 -43.136281) (xy 237.629954 -43.135804) (xy 237.672596 -43.136331) (xy 237.757484 -43.144543)
			(xy 237.841197 -43.160838) (xy 237.922968 -43.185068) (xy 237.962694 -43.200574) (xy 237.971356 -43.203655)
			(xy 237.989722 -43.204046) (xy 237.998508 -43.201336) (xy 238.034032 -43.189272) (xy 238.106663 -43.170452)
			(xy 238.18062 -43.157817) (xy 238.25538 -43.151455) (xy 238.292894 -43.151044) (xy 238.332166 -43.151496)
			(xy 238.410399 -43.158477) (xy 238.487712 -43.172332) (xy 238.563501 -43.192954) (xy 238.600488 -43.206162)
			(xy 238.609037 -43.208926) (xy 238.626991 -43.208926) (xy 238.63554 -43.206162) (xy 238.672533 -43.192975)
			(xy 238.748323 -43.172363) (xy 238.825633 -43.158506) (xy 238.903863 -43.151512) (xy 238.943134 -43.151044)
			(xy 238.981423 -43.151469) (xy 239.057717 -43.158071) (xy 239.133159 -43.171215) (xy 239.207191 -43.190803)
			(xy 239.243362 -43.203368) (xy 239.251799 -43.206019) (xy 239.269469 -43.206019) (xy 239.277906 -43.203368)
			(xy 239.314089 -43.190839) (xy 239.38812 -43.171262) (xy 239.463558 -43.158111) (xy 239.539846 -43.151482)
			(xy 239.578134 -43.151044) (xy 239.616423 -43.151469) (xy 239.692717 -43.158071) (xy 239.768159 -43.171215)
			(xy 239.842191 -43.190803) (xy 239.878362 -43.203368) (xy 239.886799 -43.206019) (xy 239.904469 -43.206019)
			(xy 239.912906 -43.203368) (xy 239.949089 -43.190839) (xy 240.02312 -43.171262) (xy 240.098558 -43.158111)
			(xy 240.174846 -43.151482) (xy 240.213134 -43.151044) (xy 240.25606 -43.151581) (xy 240.341511 -43.159862)
			(xy 240.425768 -43.176335) (xy 240.508046 -43.200846) (xy 240.587581 -43.233168) (xy 240.613613 -43.246802)
			(xy 243.62918 -43.246802) (xy 243.629584 -43.208512) (xy 243.636192 -43.132218) (xy 243.649342 -43.056775)
			(xy 243.668936 -42.982745) (xy 243.681504 -42.946574) (xy 243.684156 -42.938137) (xy 243.684156 -42.920466)
			(xy 243.681504 -42.91203) (xy 243.668959 -42.875853) (xy 243.649386 -42.80182) (xy 243.636239 -42.72638)
			(xy 243.629616 -42.65009) (xy 243.62918 -42.611802) (xy 243.629684 -42.569441) (xy 243.637737 -42.485104)
			(xy 243.653771 -42.401914) (xy 243.677639 -42.320624) (xy 243.709127 -42.241972) (xy 243.747949 -42.166669)
			(xy 243.793752 -42.095397) (xy 243.846123 -42.028801) (xy 243.904588 -41.967486) (xy 243.968616 -41.912005)
			(xy 244.037628 -41.862862) (xy 244.110998 -41.820502) (xy 244.188063 -41.785307) (xy 244.268125 -41.757598)
			(xy 244.350458 -41.737624) (xy 244.434317 -41.725567) (xy 244.518942 -41.721536) (xy 244.603567 -41.725567)
			(xy 244.687426 -41.737624) (xy 244.769759 -41.757598) (xy 244.849821 -41.785307) (xy 244.926886 -41.820502)
			(xy 245.000256 -41.862862) (xy 245.069268 -41.912005) (xy 245.133296 -41.967486) (xy 245.191761 -42.028801)
			(xy 245.244132 -42.095397) (xy 245.289935 -42.166669) (xy 245.328757 -42.241972) (xy 245.360245 -42.320624)
			(xy 245.384113 -42.401914) (xy 245.400147 -42.485104) (xy 245.4082 -42.569441) (xy 245.408704 -42.611802)
			(xy 245.408302 -42.650092) (xy 245.401694 -42.726386) (xy 245.388543 -42.801829) (xy 245.368949 -42.875859)
			(xy 245.35638 -42.91203) (xy 245.353727 -42.920466) (xy 245.353728 -42.938137) (xy 245.35638 -42.946574)
			(xy 245.368926 -42.982751) (xy 245.388499 -43.056784) (xy 245.401645 -43.132224) (xy 245.408269 -43.208514)
			(xy 245.408704 -43.246802) (xy 245.4082 -43.289163) (xy 245.400147 -43.3735) (xy 245.384113 -43.45669)
			(xy 245.360245 -43.53798) (xy 245.328757 -43.616632) (xy 245.289935 -43.691935) (xy 245.244132 -43.763207)
			(xy 245.191761 -43.829803) (xy 245.133296 -43.891118) (xy 245.069268 -43.946599) (xy 245.000256 -43.995742)
			(xy 244.926886 -44.038102) (xy 244.849821 -44.073297) (xy 244.769759 -44.101006) (xy 244.687426 -44.12098)
			(xy 244.603567 -44.133037) (xy 244.518942 -44.137069) (xy 244.434317 -44.133037) (xy 244.350458 -44.12098)
			(xy 244.268125 -44.101006) (xy 244.188063 -44.073297) (xy 244.110998 -44.038102) (xy 244.037628 -43.995742)
			(xy 243.968616 -43.946599) (xy 243.904588 -43.891118) (xy 243.846123 -43.829803) (xy 243.793752 -43.763207)
			(xy 243.747949 -43.691935) (xy 243.709127 -43.616632) (xy 243.677639 -43.53798) (xy 243.653771 -43.45669)
			(xy 243.637737 -43.3735) (xy 243.629684 -43.289163) (xy 243.62918 -43.246802) (xy 240.613613 -43.246802)
			(xy 240.663633 -43.272999) (xy 240.735496 -43.31997) (xy 240.802501 -43.373643) (xy 240.864025 -43.433521)
			(xy 240.919496 -43.499046) (xy 240.968398 -43.569608) (xy 241.010277 -43.644552) (xy 241.044744 -43.723182)
			(xy 241.071477 -43.804765) (xy 241.090229 -43.888544) (xy 241.096038 -43.931078) (xy 241.097792 -43.94092)
			(xy 241.107661 -43.958279) (xy 241.123386 -43.970587) (xy 241.132868 -43.97375) (xy 241.172506 -43.985287)
			(xy 241.249638 -44.014728) (xy 241.32371 -44.051189) (xy 241.394086 -44.094356) (xy 241.460159 -44.143858)
			(xy 241.521362 -44.199269) (xy 241.577167 -44.260112) (xy 241.627095 -44.325864) (xy 241.670716 -44.395959)
			(xy 241.707655 -44.469795) (xy 241.737594 -44.546735) (xy 241.760276 -44.626118) (xy 241.775505 -44.707261)
			(xy 241.78315 -44.789466) (xy 241.783616 -44.830746) (xy 241.783231 -44.871862) (xy 241.775639 -44.953744)
			(xy 241.760525 -45.034576) (xy 241.738017 -45.113668) (xy 241.708307 -45.190346) (xy 241.671649 -45.263956)
			(xy 241.628355 -45.333869) (xy 241.578796 -45.39949) (xy 241.523393 -45.460258) (xy 241.462619 -45.515654)
			(xy 241.396993 -45.565207) (xy 241.327075 -45.608494) (xy 241.253462 -45.645144) (xy 241.176781 -45.674846)
			(xy 241.097686 -45.697346) (xy 241.016853 -45.712452) (xy 240.93497 -45.720035) (xy 240.893854 -45.720508)
			(xy 240.848047 -45.719908) (xy 240.756919 -45.710469) (xy 240.667241 -45.691726) (xy 240.579961 -45.663878)
			(xy 240.537746 -45.646086) (xy 240.528923 -45.642621) (xy 240.509997 -45.641842) (xy 240.500916 -45.644562)
			(xy 240.454475 -45.659757) (xy 240.359116 -45.681105) (xy 240.261993 -45.691873) (xy 240.213134 -45.692568)
			(xy 240.174844 -45.692152) (xy 240.09855 -45.685547) (xy 240.023108 -45.672401) (xy 239.949077 -45.652811)
			(xy 239.912906 -45.640244) (xy 239.904469 -45.637593) (xy 239.886799 -45.637593) (xy 239.878362 -45.640244)
			(xy 239.842183 -45.652782) (xy 239.76815 -45.672357) (xy 239.692711 -45.685505) (xy 239.616422 -45.692131)
			(xy 239.578134 -45.692568) (xy 239.539844 -45.692152) (xy 239.46355 -45.685547) (xy 239.388108 -45.672401)
			(xy 239.314077 -45.652811) (xy 239.277906 -45.640244) (xy 239.269469 -45.637593) (xy 239.251799 -45.637593)
			(xy 239.243362 -45.640244) (xy 239.207183 -45.652782) (xy 239.13315 -45.672357) (xy 239.057711 -45.685505)
			(xy 238.981422 -45.692131) (xy 238.943134 -45.692568) (xy 238.903862 -45.692107) (xy 238.825629 -45.685129)
			(xy 238.748316 -45.671276) (xy 238.672527 -45.650657) (xy 238.63554 -45.63745) (xy 238.626991 -45.634686)
			(xy 238.609037 -45.634686) (xy 238.600488 -45.63745) (xy 238.563502 -45.650659) (xy 238.48771 -45.671265)
			(xy 238.410397 -45.685115) (xy 238.332165 -45.692103) (xy 238.292894 -45.692568) (xy 238.24936 -45.692039)
			(xy 238.16271 -45.683524) (xy 238.077306 -45.666586) (xy 237.993965 -45.641387) (xy 237.913484 -45.608168)
			(xy 237.87481 -45.588174) (xy 237.86657 -45.584248) (xy 237.848476 -45.581916) (xy 237.839504 -45.583602)
			(xy 237.790336 -45.594179) (xy 237.690402 -45.605511) (xy 237.640114 -45.606208) (xy 237.599001 -45.605674)
			(xy 237.517127 -45.598088) (xy 237.436301 -45.582981) (xy 237.357214 -45.560481) (xy 237.280541 -45.53078)
			(xy 237.206935 -45.494131) (xy 237.137024 -45.450847) (xy 237.071406 -45.401297) (xy 237.010639 -45.345904)
			(xy 236.955242 -45.285141) (xy 236.905687 -45.219525) (xy 236.862399 -45.149618) (xy 236.825745 -45.076014)
			(xy 236.796038 -44.999343) (xy 236.773533 -44.920257) (xy 236.75842 -44.839433) (xy 236.750829 -44.757559)
			(xy 236.750352 -44.716446) (xy 236.750814 -44.676228) (xy 236.758123 -44.596123) (xy 236.772622 -44.517004)
			(xy 236.794193 -44.439513) (xy 236.80801 -44.40174) (xy 236.811025 -44.392621) (xy 236.810769 -44.373433)
			(xy 236.807502 -44.364402) (xy 236.791394 -44.324025) (xy 236.766206 -44.240819) (xy 236.749266 -44.15555)
			(xy 236.740738 -44.069034) (xy 236.740192 -44.025566) (xy 182.412218 -44.025566) (xy 182.41506 -44.035245)
			(xy 182.422822 -44.089229) (xy 182.423308 -44.116498) (xy 182.423308 -44.980098) (xy 182.422822 -45.007367)
			(xy 182.41506 -45.061351) (xy 182.399695 -45.113681) (xy 182.377038 -45.163291) (xy 182.347552 -45.209172)
			(xy 182.311837 -45.250389) (xy 182.27062 -45.286104) (xy 182.224739 -45.31559) (xy 182.175129 -45.338247)
			(xy 182.122799 -45.353612) (xy 182.068815 -45.361374) (xy 182.014277 -45.361374) (xy 181.960293 -45.353612)
			(xy 181.907963 -45.338247) (xy 181.858353 -45.31559) (xy 181.812472 -45.286104) (xy 181.771255 -45.250389)
			(xy 181.73554 -45.209172) (xy 181.706054 -45.163291) (xy 181.683397 -45.113681) (xy 181.668032 -45.061351)
			(xy 181.66027 -45.007367) (xy 181.659784 -44.980098) (xy 96.555487 -44.980098) (xy 96.637446 -45.068647)
			(xy 96.736452 -45.187325) (xy 96.829216 -45.310943) (xy 96.915495 -45.439171) (xy 96.995057 -45.571672)
			(xy 97.067693 -45.708092) (xy 97.133211 -45.848071) (xy 97.191435 -45.991237) (xy 97.242212 -46.13721)
			(xy 97.285407 -46.285604) (xy 97.320906 -46.436025) (xy 97.329238 -46.481746) (xy 178.630072 -46.481746)
			(xy 178.630072 -45.618146) (xy 178.630558 -45.590877) (xy 178.63832 -45.536893) (xy 178.653685 -45.484563)
			(xy 178.676342 -45.434953) (xy 178.705828 -45.389072) (xy 178.741543 -45.347855) (xy 178.78276 -45.31214)
			(xy 178.828641 -45.282654) (xy 178.878251 -45.259997) (xy 178.930581 -45.244632) (xy 178.984565 -45.23687)
			(xy 179.039103 -45.23687) (xy 179.093087 -45.244632) (xy 179.145417 -45.259997) (xy 179.195027 -45.282654)
			(xy 179.240908 -45.31214) (xy 179.282125 -45.347855) (xy 179.31784 -45.389072) (xy 179.347326 -45.434953)
			(xy 179.369983 -45.484563) (xy 179.385348 -45.536893) (xy 179.39311 -45.590877) (xy 179.393596 -45.618146)
			(xy 179.393596 -46.481746) (xy 179.39311 -46.509015) (xy 179.385348 -46.562999) (xy 179.369983 -46.615329)
			(xy 179.347326 -46.664939) (xy 179.31784 -46.71082) (xy 179.282125 -46.752037) (xy 179.240908 -46.787752)
			(xy 179.195027 -46.817238) (xy 179.145417 -46.839895) (xy 179.093087 -46.85526) (xy 179.039103 -46.863022)
			(xy 178.984565 -46.863022) (xy 178.930581 -46.85526) (xy 178.878251 -46.839895) (xy 178.828641 -46.817238)
			(xy 178.78276 -46.787752) (xy 178.741543 -46.752037) (xy 178.705828 -46.71082) (xy 178.676342 -46.664939)
			(xy 178.653685 -46.615329) (xy 178.63832 -46.562999) (xy 178.630558 -46.509015) (xy 178.630072 -46.481746)
			(xy 97.329238 -46.481746) (xy 97.348615 -46.588073) (xy 97.368459 -46.741347) (xy 97.380387 -46.895438)
			(xy 97.384366 -47.04994) (xy 97.380387 -47.204442) (xy 97.368459 -47.358533) (xy 97.348615 -47.511807)
			(xy 97.320906 -47.663855) (xy 97.285407 -47.814276) (xy 97.242212 -47.96267) (xy 97.219453 -48.028098)
			(xy 181.659784 -48.028098) (xy 181.659784 -47.164498) (xy 181.66027 -47.137229) (xy 181.668032 -47.083245)
			(xy 181.683397 -47.030915) (xy 181.706054 -46.981305) (xy 181.73554 -46.935424) (xy 181.771255 -46.894207)
			(xy 181.812472 -46.858492) (xy 181.858353 -46.829006) (xy 181.907963 -46.806349) (xy 181.960293 -46.790984)
			(xy 182.014277 -46.783222) (xy 182.068815 -46.783222) (xy 182.122799 -46.790984) (xy 182.175129 -46.806349)
			(xy 182.224739 -46.829006) (xy 182.27062 -46.858492) (xy 182.311837 -46.894207) (xy 182.347552 -46.935424)
			(xy 182.377038 -46.981305) (xy 182.399695 -47.030915) (xy 182.41506 -47.083245) (xy 182.422822 -47.137229)
			(xy 182.423308 -47.164498) (xy 182.423308 -48.028098) (xy 182.422822 -48.055367) (xy 182.41506 -48.109351)
			(xy 182.399695 -48.161681) (xy 182.377038 -48.211291) (xy 182.347552 -48.257172) (xy 182.311837 -48.298389)
			(xy 182.27062 -48.334104) (xy 182.224739 -48.36359) (xy 182.175129 -48.386247) (xy 182.122799 -48.401612)
			(xy 182.068815 -48.409374) (xy 182.014277 -48.409374) (xy 181.960293 -48.401612) (xy 181.907963 -48.386247)
			(xy 181.858353 -48.36359) (xy 181.812472 -48.334104) (xy 181.771255 -48.298389) (xy 181.73554 -48.257172)
			(xy 181.706054 -48.211291) (xy 181.683397 -48.161681) (xy 181.668032 -48.109351) (xy 181.66027 -48.055367)
			(xy 181.659784 -48.028098) (xy 97.219453 -48.028098) (xy 97.191435 -48.108643) (xy 97.133211 -48.251809)
			(xy 97.067693 -48.391788) (xy 96.995057 -48.528208) (xy 96.915495 -48.660709) (xy 96.829216 -48.788937)
			(xy 96.736452 -48.912555) (xy 96.637446 -49.031233) (xy 96.532463 -49.144657) (xy 96.421779 -49.252526)
			(xy 96.30569 -49.354554) (xy 96.184502 -49.450471) (xy 96.140518 -49.48174) (xy 178.630072 -49.48174)
			(xy 178.630072 -48.61814) (xy 178.630558 -48.590871) (xy 178.63832 -48.536887) (xy 178.653685 -48.484557)
			(xy 178.676342 -48.434947) (xy 178.705828 -48.389066) (xy 178.741543 -48.347849) (xy 178.78276 -48.312134)
			(xy 178.828641 -48.282648) (xy 178.878251 -48.259991) (xy 178.930581 -48.244626) (xy 178.984565 -48.236864)
			(xy 179.039103 -48.236864) (xy 179.093087 -48.244626) (xy 179.145417 -48.259991) (xy 179.195027 -48.282648)
			(xy 179.240908 -48.312134) (xy 179.282125 -48.347849) (xy 179.31784 -48.389066) (xy 179.347326 -48.434947)
			(xy 179.369983 -48.484557) (xy 179.385348 -48.536887) (xy 179.39311 -48.590871) (xy 179.393596 -48.61814)
			(xy 179.393596 -49.48174) (xy 179.39311 -49.509009) (xy 179.385348 -49.562993) (xy 179.369983 -49.615323)
			(xy 179.347326 -49.664933) (xy 179.31784 -49.710814) (xy 179.282125 -49.752031) (xy 179.240908 -49.787746)
			(xy 179.195027 -49.817232) (xy 179.145417 -49.839889) (xy 179.093087 -49.855254) (xy 179.039103 -49.863016)
			(xy 178.984565 -49.863016) (xy 178.930581 -49.855254) (xy 178.878251 -49.839889) (xy 178.828641 -49.817232)
			(xy 178.78276 -49.787746) (xy 178.741543 -49.752031) (xy 178.705828 -49.710814) (xy 178.676342 -49.664933)
			(xy 178.653685 -49.615323) (xy 178.63832 -49.562993) (xy 178.630558 -49.509009) (xy 178.630072 -49.48174)
			(xy 96.140518 -49.48174) (xy 96.058537 -49.540022) (xy 95.928129 -49.62297) (xy 95.793624 -49.699095)
			(xy 95.655379 -49.768194) (xy 95.513759 -49.830085) (xy 95.369142 -49.884604) (xy 95.221909 -49.931606)
			(xy 95.072452 -49.970966) (xy 94.921168 -50.00258) (xy 94.768456 -50.026364) (xy 94.614722 -50.042255)
			(xy 94.460374 -50.050211) (xy 94.383098 -50.0507) (xy 92.782898 -50.0507) (xy 92.705622 -50.050194)
			(xy 92.551275 -50.042238) (xy 92.397543 -50.026347) (xy 92.244832 -50.002563) (xy 92.093548 -49.970949)
			(xy 91.944092 -49.931589) (xy 91.796861 -49.884587) (xy 91.652244 -49.830069) (xy 91.510626 -49.768178)
			(xy 91.372381 -49.699079) (xy 91.237877 -49.622954) (xy 91.10747 -49.540007) (xy 90.981506 -49.450456)
			(xy 90.860319 -49.35454) (xy 90.74423 -49.252512) (xy 90.633548 -49.144644) (xy 90.528565 -49.031221)
			(xy 90.42956 -48.912543) (xy 90.336796 -48.788927) (xy 90.250519 -48.660699) (xy 90.170957 -48.528199)
			(xy 90.098321 -48.391779) (xy 90.032804 -48.251802) (xy 89.97458 -48.108637) (xy 89.923803 -47.962664)
			(xy 89.880608 -47.814271) (xy 89.84511 -47.663852) (xy 89.817402 -47.511804) (xy 89.797557 -47.358531)
			(xy 89.78563 -47.204441) (xy 89.78165 -47.04994) (xy 67.583802 -47.04994) (xy 67.579823 -47.209492)
			(xy 67.567896 -47.368647) (xy 67.54805 -47.527009) (xy 67.520336 -47.684186) (xy 67.484821 -47.839786)
			(xy 67.441595 -47.993422) (xy 67.390764 -48.144712) (xy 67.332455 -48.293281) (xy 67.266813 -48.438758)
			(xy 67.194001 -48.580783) (xy 67.114201 -48.719002) (xy 67.02761 -48.853071) (xy 66.934444 -48.982657)
			(xy 66.834934 -49.107438) (xy 66.729328 -49.227105) (xy 66.617889 -49.341358) (xy 66.500893 -49.449914)
			(xy 66.378631 -49.552504) (xy 66.251408 -49.648872) (xy 66.119539 -49.738779) (xy 65.983353 -49.822001)
			(xy 65.843188 -49.898331) (xy 65.699392 -49.967579) (xy 65.552323 -50.029574) (xy 65.402347 -50.084161)
			(xy 65.249837 -50.131205) (xy 65.095171 -50.170587) (xy 64.938734 -50.202212) (xy 64.780916 -50.226)
			(xy 64.622107 -50.241891) (xy 64.462705 -50.249847) (xy 64.382904 -50.250344) (xy 62.782958 -50.250344)
			(xy 62.703158 -50.249839) (xy 62.543755 -50.241883) (xy 62.384947 -50.225992) (xy 62.227129 -50.202204)
			(xy 62.070693 -50.17058) (xy 61.916027 -50.131197) (xy 61.763517 -50.084154) (xy 61.613541 -50.029567)
			(xy 61.466472 -49.967573) (xy 61.322677 -49.898324) (xy 61.182512 -49.821994) (xy 61.046326 -49.738773)
			(xy 60.914458 -49.648866) (xy 60.787235 -49.552499) (xy 60.664973 -49.449909) (xy 60.547978 -49.341353)
			(xy 60.436538 -49.2271) (xy 60.330933 -49.107434) (xy 60.231423 -48.982653) (xy 60.138257 -48.853067)
			(xy 60.051666 -48.718998) (xy 59.971866 -48.580779) (xy 59.899054 -48.438755) (xy 59.833413 -48.293278)
			(xy 59.775104 -48.14471) (xy 59.724273 -47.99342) (xy 59.681047 -47.839784) (xy 59.645532 -47.684184)
			(xy 59.617818 -47.527008) (xy 59.597972 -47.368646) (xy 59.586045 -47.209491) (xy 59.582066 -47.04994)
			(xy 0.509016 -47.04994) (xy 0.509016 -50.949098) (xy 181.659784 -50.949098) (xy 181.659784 -50.085498)
			(xy 181.66027 -50.058229) (xy 181.668032 -50.004245) (xy 181.683397 -49.951915) (xy 181.706054 -49.902305)
			(xy 181.73554 -49.856424) (xy 181.771255 -49.815207) (xy 181.812472 -49.779492) (xy 181.858353 -49.750006)
			(xy 181.907963 -49.727349) (xy 181.960293 -49.711984) (xy 182.014277 -49.704222) (xy 182.068815 -49.704222)
			(xy 182.122799 -49.711984) (xy 182.175129 -49.727349) (xy 182.224739 -49.750006) (xy 182.27062 -49.779492)
			(xy 182.311837 -49.815207) (xy 182.347552 -49.856424) (xy 182.377038 -49.902305) (xy 182.399695 -49.951915)
			(xy 182.41506 -50.004245) (xy 182.422822 -50.058229) (xy 182.423308 -50.085498) (xy 182.423308 -50.949098)
			(xy 182.422822 -50.976367) (xy 182.41506 -51.030351) (xy 182.399695 -51.082681) (xy 182.377038 -51.132291)
			(xy 182.347552 -51.178172) (xy 182.311837 -51.219389) (xy 182.27062 -51.255104) (xy 182.224739 -51.28459)
			(xy 182.175129 -51.307247) (xy 182.122799 -51.322612) (xy 182.068815 -51.330374) (xy 182.014277 -51.330374)
			(xy 181.960293 -51.322612) (xy 181.907963 -51.307247) (xy 181.858353 -51.28459) (xy 181.812472 -51.255104)
			(xy 181.771255 -51.219389) (xy 181.73554 -51.178172) (xy 181.706054 -51.132291) (xy 181.683397 -51.082681)
			(xy 181.668032 -51.030351) (xy 181.66027 -50.976367) (xy 181.659784 -50.949098) (xy 0.509016 -50.949098)
			(xy 0.509016 -52.481734) (xy 178.630072 -52.481734) (xy 178.630072 -51.618134) (xy 178.630558 -51.590865)
			(xy 178.63832 -51.536881) (xy 178.653685 -51.484551) (xy 178.676342 -51.434941) (xy 178.705828 -51.38906)
			(xy 178.741543 -51.347843) (xy 178.78276 -51.312128) (xy 178.828641 -51.282642) (xy 178.878251 -51.259985)
			(xy 178.930581 -51.24462) (xy 178.984565 -51.236858) (xy 179.039103 -51.236858) (xy 179.093087 -51.24462)
			(xy 179.145417 -51.259985) (xy 179.195027 -51.282642) (xy 179.240908 -51.312128) (xy 179.282125 -51.347843)
			(xy 179.31784 -51.38906) (xy 179.347326 -51.434941) (xy 179.369983 -51.484551) (xy 179.385348 -51.536881)
			(xy 179.39311 -51.590865) (xy 179.393596 -51.618134) (xy 179.393596 -51.999896) (xy 201.367397 -51.999896)
			(xy 201.371407 -51.837793) (xy 201.38343 -51.676088) (xy 201.403434 -51.515174) (xy 201.431372 -51.355447)
			(xy 201.467175 -51.197297) (xy 201.510755 -51.041111) (xy 201.562006 -50.887271) (xy 201.620802 -50.736154)
			(xy 201.687 -50.58813) (xy 201.760436 -50.44356) (xy 201.840933 -50.302799) (xy 201.928292 -50.166191)
			(xy 202.0223 -50.034071) (xy 202.122727 -49.906761) (xy 202.229327 -49.784573) (xy 202.341839 -49.667807)
			(xy 202.459987 -49.556748) (xy 202.583484 -49.451667) (xy 202.712026 -49.352823) (xy 202.845299 -49.260456)
			(xy 202.982977 -49.174793) (xy 203.124723 -49.096044) (xy 203.27019 -49.024401) (xy 203.419022 -48.960039)
			(xy 203.570854 -48.903117) (xy 203.725316 -48.853773) (xy 203.882029 -48.812128) (xy 204.04061 -48.778283)
			(xy 204.200671 -48.752323) (xy 204.361819 -48.73431) (xy 204.523661 -48.724289) (xy 204.685801 -48.722283)
			(xy 204.847842 -48.728299) (xy 205.009386 -48.74232) (xy 205.17004 -48.764313) (xy 205.32941 -48.794225)
			(xy 205.487105 -48.831981) (xy 205.64274 -48.877489) (xy 205.795934 -48.930639) (xy 205.946312 -48.9913)
			(xy 206.093507 -49.059323) (xy 206.237157 -49.134542) (xy 206.376912 -49.216773) (xy 206.512428 -49.305815)
			(xy 206.643376 -49.40145) (xy 206.769434 -49.503444) (xy 206.890294 -49.611547) (xy 207.00566 -49.725494)
			(xy 207.115249 -49.845008) (xy 207.218794 -49.969795) (xy 207.316041 -50.09955) (xy 207.406753 -50.233955)
			(xy 207.490706 -50.372682) (xy 207.567696 -50.515391) (xy 207.637535 -50.661732) (xy 207.70005 -50.811349)
			(xy 207.755091 -50.963874) (xy 207.802521 -51.118934) (xy 207.842224 -51.27615) (xy 207.874105 -51.435138)
			(xy 207.898083 -51.595507) (xy 207.914102 -51.756866) (xy 207.922121 -51.91882) (xy 207.922622 -51.999896)
			(xy 207.922121 -52.080972) (xy 207.921092 -52.10175) (xy 244.67947 -52.10175) (xy 244.679975 -52.075243)
			(xy 244.687334 -52.022743) (xy 244.701889 -51.971767) (xy 244.723361 -51.923297) (xy 244.751335 -51.878265)
			(xy 244.785274 -51.837539) (xy 244.824523 -51.801903) (xy 244.868327 -51.772043) (xy 244.915843 -51.748534)
			(xy 244.966156 -51.731829) (xy 244.992144 -51.726592) (xy 245.000543 -51.724726) (xy 245.015476 -51.716197)
			(xy 245.026755 -51.703216) (xy 245.030244 -51.69535) (xy 245.045663 -51.657494) (xy 245.082559 -51.584546)
			(xy 245.125992 -51.515291) (xy 245.175596 -51.450313) (xy 245.230952 -51.39016) (xy 245.291595 -51.335341)
			(xy 245.357011 -51.286316) (xy 245.426649 -51.2435) (xy 245.499922 -51.207254) (xy 245.576211 -51.177884)
			(xy 245.654873 -51.155637) (xy 245.735245 -51.140701) (xy 245.816648 -51.133203) (xy 245.857522 -51.13274)
			(xy 245.899843 -51.133258) (xy 245.984099 -51.14133) (xy 246.067208 -51.157371) (xy 246.148416 -51.181236)
			(xy 246.226989 -51.212708) (xy 246.302217 -51.251503) (xy 246.33809 -51.273964) (xy 246.346484 -51.278827)
			(xy 246.365522 -51.28248) (xy 246.38456 -51.278827) (xy 246.392954 -51.273964) (xy 246.42883 -51.25151)
			(xy 246.504063 -51.212731) (xy 246.582638 -51.181268) (xy 246.663845 -51.157405) (xy 246.74695 -51.141356)
			(xy 246.831202 -51.133268) (xy 246.873522 -51.13274) (xy 246.926862 -51.134518) (xy 246.938638 -51.134618)
			(xy 246.960306 -51.125466) (xy 246.975671 -51.107657) (xy 246.979186 -51.096418) (xy 246.990138 -51.056039)
			(xy 247.018713 -50.977397) (xy 247.054545 -50.901785) (xy 247.097317 -50.829872) (xy 247.146653 -50.762292)
			(xy 247.202115 -50.699642) (xy 247.263214 -50.642477) (xy 247.329411 -50.5913) (xy 247.40012 -50.546564)
			(xy 247.474717 -50.508665) (xy 247.552542 -50.477936) (xy 247.632909 -50.45465) (xy 247.715107 -50.439012)
			(xy 247.79841 -50.431161) (xy 247.840246 -50.430684) (xy 247.883752 -50.431235) (xy 247.970347 -50.439729)
			(xy 248.055699 -50.456641) (xy 248.138991 -50.481809) (xy 248.219426 -50.514992) (xy 248.296235 -50.555874)
			(xy 248.332752 -50.579528) (xy 248.341308 -50.584744) (xy 248.360946 -50.588653) (xy 248.380584 -50.584744)
			(xy 248.38914 -50.579528) (xy 248.425663 -50.555885) (xy 248.50248 -50.515022) (xy 248.582916 -50.481847)
			(xy 248.666204 -50.456676) (xy 248.751551 -50.439749) (xy 248.838142 -50.431227) (xy 248.881646 -50.430684)
			(xy 248.926403 -50.431259) (xy 249.015462 -50.440266) (xy 249.103167 -50.458165) (xy 249.188634 -50.484775)
			(xy 249.270999 -50.519828) (xy 249.349431 -50.562968) (xy 249.386598 -50.58791) (xy 249.394939 -50.593062)
			(xy 249.414052 -50.597328) (xy 249.433374 -50.594144) (xy 249.44197 -50.589434) (xy 249.4758 -50.569354)
			(xy 249.546346 -50.534523) (xy 249.619688 -50.506051) (xy 249.695257 -50.484158) (xy 249.772462 -50.469016)
			(xy 249.850701 -50.460742) (xy 249.890026 -50.45964) (xy 249.889772 -50.4444) (xy 249.889772 -50.443892)
			(xy 249.89024 -50.405527) (xy 249.896983 -50.329093) (xy 249.903234 -50.291238) (xy 249.904413 -50.282319)
			(xy 249.901131 -50.26464) (xy 249.891952 -50.249179) (xy 249.8852 -50.243232) (xy 249.851748 -50.215094)
			(xy 249.789907 -50.153305) (xy 249.734424 -50.08575) (xy 249.685833 -50.01308) (xy 249.644603 -49.935995)
			(xy 249.61113 -49.855239) (xy 249.585738 -49.771589) (xy 249.568671 -49.685852) (xy 249.560094 -49.598855)
			(xy 249.559572 -49.555146) (xy 249.560076 -49.512785) (xy 249.568129 -49.428448) (xy 249.584163 -49.345258)
			(xy 249.608031 -49.263968) (xy 249.639519 -49.185316) (xy 249.678341 -49.110013) (xy 249.724144 -49.038741)
			(xy 249.776515 -48.972145) (xy 249.83498 -48.91083) (xy 249.899008 -48.855349) (xy 249.96802 -48.806206)
			(xy 250.04139 -48.763846) (xy 250.118455 -48.728651) (xy 250.198517 -48.700942) (xy 250.28085 -48.680968)
			(xy 250.364709 -48.668911) (xy 250.449334 -48.66488) (xy 250.533959 -48.668911) (xy 250.617818 -48.680968)
			(xy 250.700151 -48.700942) (xy 250.780213 -48.728651) (xy 250.857278 -48.763846) (xy 250.930648 -48.806206)
			(xy 250.99966 -48.855349) (xy 251.063688 -48.91083) (xy 251.122153 -48.972145) (xy 251.174524 -49.038741)
			(xy 251.220327 -49.110013) (xy 251.259149 -49.185316) (xy 251.290637 -49.263968) (xy 251.314505 -49.345258)
			(xy 251.330539 -49.428448) (xy 251.338592 -49.512785) (xy 251.339096 -49.555146) (xy 251.338636 -49.593574)
			(xy 251.331894 -49.670136) (xy 251.325634 -49.708054) (xy 251.324473 -49.716974) (xy 251.32775 -49.73465)
			(xy 251.336921 -49.750111) (xy 251.343668 -49.75606) (xy 251.362142 -49.771471) (xy 251.397596 -49.803999)
			(xy 251.414534 -49.821084) (xy 251.422676 -49.828571) (xy 251.443355 -49.836348) (xy 251.454412 -49.83607)
			(xy 251.469822 -49.835031) (xy 251.50069 -49.833886) (xy 251.516134 -49.833784) (xy 251.557251 -49.834166)
			(xy 251.639133 -49.841757) (xy 251.719966 -49.85687) (xy 251.79906 -49.879378) (xy 251.875739 -49.909087)
			(xy 251.94935 -49.945745) (xy 252.019265 -49.989039) (xy 252.084886 -50.038598) (xy 252.145655 -50.094001)
			(xy 252.201053 -50.154775) (xy 252.250607 -50.220401) (xy 252.293894 -50.29032) (xy 252.330545 -50.363934)
			(xy 252.360248 -50.440616) (xy 252.382748 -50.519712) (xy 252.397854 -50.600546) (xy 252.405438 -50.682429)
			(xy 252.405896 -50.723546) (xy 252.405358 -50.767341) (xy 252.396743 -50.854506) (xy 252.379599 -50.940401)
			(xy 252.354094 -51.024196) (xy 252.320474 -51.105076) (xy 252.300232 -51.143916) (xy 252.29478 -51.15537)
			(xy 252.2948 -51.18071) (xy 252.300232 -51.192176) (xy 252.320452 -51.231026) (xy 252.354062 -51.311909)
			(xy 252.379567 -51.3957) (xy 252.39672 -51.481592) (xy 252.405355 -51.568752) (xy 252.405896 -51.612546)
			(xy 252.405358 -51.656341) (xy 252.396743 -51.743506) (xy 252.379599 -51.829401) (xy 252.354094 -51.913196)
			(xy 252.320474 -51.994076) (xy 252.317441 -51.999896) (xy 265.367523 -51.999896) (xy 265.371533 -51.837793)
			(xy 265.383556 -51.676088) (xy 265.40356 -51.515174) (xy 265.431498 -51.355447) (xy 265.467301 -51.197297)
			(xy 265.510881 -51.041111) (xy 265.562132 -50.887271) (xy 265.620928 -50.736154) (xy 265.687126 -50.58813)
			(xy 265.760562 -50.44356) (xy 265.841059 -50.302799) (xy 265.928418 -50.166191) (xy 266.022426 -50.034071)
			(xy 266.122853 -49.906761) (xy 266.229453 -49.784573) (xy 266.341965 -49.667807) (xy 266.460113 -49.556748)
			(xy 266.58361 -49.451667) (xy 266.712152 -49.352823) (xy 266.845425 -49.260456) (xy 266.983103 -49.174793)
			(xy 267.124849 -49.096044) (xy 267.270316 -49.024401) (xy 267.419148 -48.960039) (xy 267.57098 -48.903117)
			(xy 267.725442 -48.853773) (xy 267.882155 -48.812128) (xy 268.040736 -48.778283) (xy 268.200797 -48.752323)
			(xy 268.361945 -48.73431) (xy 268.523787 -48.724289) (xy 268.685927 -48.722283) (xy 268.847968 -48.728299)
			(xy 269.009512 -48.74232) (xy 269.170166 -48.764313) (xy 269.329536 -48.794225) (xy 269.487231 -48.831981)
			(xy 269.642866 -48.877489) (xy 269.79606 -48.930639) (xy 269.946438 -48.9913) (xy 270.093633 -49.059323)
			(xy 270.237283 -49.134542) (xy 270.377038 -49.216773) (xy 270.512554 -49.305815) (xy 270.643502 -49.40145)
			(xy 270.76956 -49.503444) (xy 270.89042 -49.611547) (xy 271.005786 -49.725494) (xy 271.115375 -49.845008)
			(xy 271.21892 -49.969795) (xy 271.316167 -50.09955) (xy 271.406879 -50.233955) (xy 271.490832 -50.372682)
			(xy 271.567822 -50.515391) (xy 271.637661 -50.661732) (xy 271.700176 -50.811349) (xy 271.755217 -50.963874)
			(xy 271.802647 -51.118934) (xy 271.84235 -51.27615) (xy 271.874231 -51.435138) (xy 271.898209 -51.595507)
			(xy 271.914228 -51.756866) (xy 271.922247 -51.91882) (xy 271.922748 -51.999896) (xy 271.922247 -52.080972)
			(xy 271.914228 -52.242926) (xy 271.898209 -52.404285) (xy 271.874231 -52.564654) (xy 271.84235 -52.723642)
			(xy 271.802647 -52.880858) (xy 271.755217 -53.035918) (xy 271.700176 -53.188443) (xy 271.637661 -53.33806)
			(xy 271.567822 -53.484401) (xy 271.490832 -53.62711) (xy 271.406879 -53.765837) (xy 271.316167 -53.900242)
			(xy 271.21892 -54.029997) (xy 271.115375 -54.154784) (xy 271.005786 -54.274298) (xy 270.89042 -54.388245)
			(xy 270.76956 -54.496348) (xy 270.643502 -54.598342) (xy 270.512554 -54.693977) (xy 270.377038 -54.783019)
			(xy 270.237283 -54.86525) (xy 270.093633 -54.940469) (xy 269.946438 -55.008492) (xy 269.79606 -55.069153)
			(xy 269.642866 -55.122303) (xy 269.487231 -55.167811) (xy 269.329536 -55.205567) (xy 269.170166 -55.235479)
			(xy 269.009512 -55.257472) (xy 268.847968 -55.271493) (xy 268.685927 -55.277509) (xy 268.523787 -55.275503)
			(xy 268.361945 -55.265482) (xy 268.200797 -55.247469) (xy 268.040736 -55.221509) (xy 267.882155 -55.187664)
			(xy 267.725442 -55.146019) (xy 267.57098 -55.096675) (xy 267.419148 -55.039753) (xy 267.270316 -54.975391)
			(xy 267.124849 -54.903748) (xy 266.983103 -54.824999) (xy 266.845425 -54.739336) (xy 266.712152 -54.646969)
			(xy 266.58361 -54.548125) (xy 266.460113 -54.443044) (xy 266.341965 -54.331985) (xy 266.229453 -54.215219)
			(xy 266.122853 -54.093031) (xy 266.022426 -53.965721) (xy 265.928418 -53.833601) (xy 265.841059 -53.696993)
			(xy 265.760562 -53.556232) (xy 265.687126 -53.411662) (xy 265.620928 -53.263638) (xy 265.562132 -53.112521)
			(xy 265.510881 -52.958681) (xy 265.467301 -52.802495) (xy 265.431498 -52.644345) (xy 265.40356 -52.484618)
			(xy 265.383556 -52.323704) (xy 265.371533 -52.161999) (xy 265.367523 -51.999896) (xy 252.317441 -51.999896)
			(xy 252.300232 -52.032916) (xy 252.29478 -52.04437) (xy 252.2948 -52.06971) (xy 252.300232 -52.081176)
			(xy 252.320452 -52.120026) (xy 252.354062 -52.200909) (xy 252.379567 -52.2847) (xy 252.39672 -52.370592)
			(xy 252.405355 -52.457752) (xy 252.405896 -52.501546) (xy 252.405431 -52.54266) (xy 252.39784 -52.624537)
			(xy 252.382728 -52.705364) (xy 252.360222 -52.784452) (xy 252.330515 -52.861127) (xy 252.293861 -52.934733)
			(xy 252.250573 -53.004644) (xy 252.201018 -53.070263) (xy 252.145621 -53.131029) (xy 252.084853 -53.186426)
			(xy 252.019234 -53.235979) (xy 251.949323 -53.279267) (xy 251.875716 -53.31592) (xy 251.799041 -53.345626)
			(xy 251.719952 -53.36813) (xy 251.639125 -53.383242) (xy 251.557248 -53.390832) (xy 251.516134 -53.391308)
			(xy 251.471924 -53.390745) (xy 251.383942 -53.381965) (xy 251.297264 -53.3645) (xy 251.212747 -53.33852)
			(xy 251.131225 -53.304282) (xy 251.053503 -53.262125) (xy 250.980346 -53.212465) (xy 250.912478 -53.15579)
			(xy 250.881134 -53.124608) (xy 250.873005 -53.117104) (xy 250.852316 -53.109337) (xy 250.841256 -53.109622)
			(xy 250.825846 -53.110663) (xy 250.794978 -53.111806) (xy 250.779534 -53.111908) (xy 250.737779 -53.111492)
			(xy 250.654637 -53.103677) (xy 250.572592 -53.088104) (xy 250.492369 -53.064909) (xy 250.414673 -53.034297)
			(xy 250.340188 -52.996537) (xy 250.269571 -52.951961) (xy 250.203442 -52.900963) (xy 250.142385 -52.843991)
			(xy 250.086937 -52.781547) (xy 250.037585 -52.714181) (xy 249.994765 -52.642486) (xy 249.958854 -52.567092)
			(xy 249.930167 -52.488665) (xy 249.908958 -52.407894) (xy 249.895413 -52.32549) (xy 249.892058 -52.283868)
			(xy 249.891061 -52.274773) (xy 249.88348 -52.258135) (xy 249.870549 -52.245209) (xy 249.853908 -52.237634)
			(xy 249.844814 -52.236624) (xy 249.805225 -52.23352) (xy 249.726783 -52.221122) (xy 249.649759 -52.201775)
			(xy 249.574769 -52.175634) (xy 249.50241 -52.142907) (xy 249.433259 -52.103855) (xy 249.400314 -52.081684)
			(xy 249.392012 -52.076461) (xy 249.372875 -52.072218) (xy 249.353539 -52.075433) (xy 249.344942 -52.08016)
			(xy 249.312459 -52.099495) (xy 249.244799 -52.133223) (xy 249.174522 -52.161088) (xy 249.13844 -52.172362)
			(xy 249.128616 -52.175851) (xy 249.112727 -52.189319) (xy 249.103444 -52.207965) (xy 249.102372 -52.218336)
			(xy 249.099675 -52.260463) (xy 249.087279 -52.34397) (xy 249.067027 -52.425926) (xy 249.039099 -52.505595)
			(xy 249.003748 -52.582258) (xy 248.961291 -52.655227) (xy 248.912112 -52.723845) (xy 248.856651 -52.787493)
			(xy 248.795409 -52.8456) (xy 248.728936 -52.897642) (xy 248.657831 -52.943151) (xy 248.582733 -52.981717)
			(xy 248.504319 -53.012994) (xy 248.423294 -53.036699) (xy 248.340387 -53.052621) (xy 248.256345 -53.060614)
			(xy 248.214134 -53.061108) (xy 248.171669 -53.060607) (xy 248.087125 -53.052507) (xy 248.003739 -53.036385)
			(xy 247.922268 -53.01239) (xy 247.843456 -52.98074) (xy 247.768018 -52.941722) (xy 247.696643 -52.895693)
			(xy 247.629979 -52.84307) (xy 247.568634 -52.784334) (xy 247.540526 -52.752498) (xy 247.534176 -52.745132)
			(xy 247.517412 -52.736496) (xy 247.429274 -52.726336) (xy 247.410986 -52.731416) (xy 247.403112 -52.737258)
			(xy 247.370277 -52.761024) (xy 247.301045 -52.803187) (xy 247.228263 -52.838875) (xy 247.152535 -52.867791)
			(xy 247.07449 -52.889697) (xy 246.994775 -52.904409) (xy 246.914052 -52.911805) (xy 246.873522 -52.912264)
			(xy 246.831202 -52.911724) (xy 246.746946 -52.903656) (xy 246.663838 -52.887619) (xy 246.58263 -52.863758)
			(xy 246.504056 -52.83229) (xy 246.428827 -52.793499) (xy 246.392954 -52.77104) (xy 246.38456 -52.766177)
			(xy 246.365522 -52.762524) (xy 246.346484 -52.766177) (xy 246.33809 -52.77104) (xy 246.302222 -52.793507)
			(xy 246.226987 -52.832285) (xy 246.148411 -52.863747) (xy 246.067203 -52.887609) (xy 245.984096 -52.903654)
			(xy 245.899842 -52.911738) (xy 245.857522 -52.912264) (xy 245.813221 -52.911666) (xy 245.725058 -52.90285)
			(xy 245.638208 -52.885314) (xy 245.553531 -52.85923) (xy 245.471867 -52.824858) (xy 245.394025 -52.782538)
			(xy 245.320775 -52.732689) (xy 245.252843 -52.675806) (xy 245.190903 -52.61245) (xy 245.135568 -52.543252)
			(xy 245.111016 -52.506372) (xy 245.106055 -52.499361) (xy 245.092457 -52.488884) (xy 245.076169 -52.483465)
			(xy 245.067582 -52.483258) (xy 245.060978 -52.483258) (xy 245.033722 -52.482865) (xy 244.979766 -52.475104)
			(xy 244.927464 -52.459743) (xy 244.87788 -52.437094) (xy 244.832025 -52.407619) (xy 244.790831 -52.371918)
			(xy 244.755138 -52.330717) (xy 244.725671 -52.284856) (xy 244.703032 -52.235269) (xy 244.68768 -52.182963)
			(xy 244.679929 -52.129006) (xy 244.67947 -52.10175) (xy 207.921092 -52.10175) (xy 207.914102 -52.242926)
			(xy 207.898083 -52.404285) (xy 207.874105 -52.564654) (xy 207.842224 -52.723642) (xy 207.802521 -52.880858)
			(xy 207.755091 -53.035918) (xy 207.70005 -53.188443) (xy 207.637535 -53.33806) (xy 207.567696 -53.484401)
			(xy 207.490706 -53.62711) (xy 207.406753 -53.765837) (xy 207.316041 -53.900242) (xy 207.218794 -54.029997)
			(xy 207.115249 -54.154784) (xy 207.00566 -54.274298) (xy 206.890294 -54.388245) (xy 206.769434 -54.496348)
			(xy 206.643376 -54.598342) (xy 206.512428 -54.693977) (xy 206.376912 -54.783019) (xy 206.237157 -54.86525)
			(xy 206.093507 -54.940469) (xy 205.946312 -55.008492) (xy 205.795934 -55.069153) (xy 205.64274 -55.122303)
			(xy 205.487105 -55.167811) (xy 205.32941 -55.205567) (xy 205.17004 -55.235479) (xy 205.009386 -55.257472)
			(xy 204.847842 -55.271493) (xy 204.685801 -55.277509) (xy 204.523661 -55.275503) (xy 204.361819 -55.265482)
			(xy 204.200671 -55.247469) (xy 204.04061 -55.221509) (xy 203.882029 -55.187664) (xy 203.725316 -55.146019)
			(xy 203.570854 -55.096675) (xy 203.419022 -55.039753) (xy 203.27019 -54.975391) (xy 203.124723 -54.903748)
			(xy 202.982977 -54.824999) (xy 202.845299 -54.739336) (xy 202.712026 -54.646969) (xy 202.583484 -54.548125)
			(xy 202.459987 -54.443044) (xy 202.341839 -54.331985) (xy 202.229327 -54.215219) (xy 202.122727 -54.093031)
			(xy 202.0223 -53.965721) (xy 201.928292 -53.833601) (xy 201.840933 -53.696993) (xy 201.760436 -53.556232)
			(xy 201.687 -53.411662) (xy 201.620802 -53.263638) (xy 201.562006 -53.112521) (xy 201.510755 -52.958681)
			(xy 201.467175 -52.802495) (xy 201.431372 -52.644345) (xy 201.403434 -52.484618) (xy 201.38343 -52.323704)
			(xy 201.371407 -52.161999) (xy 201.367397 -51.999896) (xy 179.393596 -51.999896) (xy 179.393596 -52.481734)
			(xy 179.39311 -52.509003) (xy 179.385348 -52.562987) (xy 179.369983 -52.615317) (xy 179.347326 -52.664927)
			(xy 179.31784 -52.710808) (xy 179.282125 -52.752025) (xy 179.240908 -52.78774) (xy 179.195027 -52.817226)
			(xy 179.145417 -52.839883) (xy 179.093087 -52.855248) (xy 179.039103 -52.86301) (xy 178.984565 -52.86301)
			(xy 178.930581 -52.855248) (xy 178.878251 -52.839883) (xy 178.828641 -52.817226) (xy 178.78276 -52.78774)
			(xy 178.741543 -52.752025) (xy 178.705828 -52.710808) (xy 178.676342 -52.664927) (xy 178.653685 -52.615317)
			(xy 178.63832 -52.562987) (xy 178.630558 -52.509003) (xy 178.630072 -52.481734) (xy 0.509016 -52.481734)
			(xy 0.509016 -53.954934) (xy 181.659784 -53.954934) (xy 181.659784 -53.091334) (xy 181.66027 -53.064065)
			(xy 181.668032 -53.010081) (xy 181.683397 -52.957751) (xy 181.706054 -52.908141) (xy 181.73554 -52.86226)
			(xy 181.771255 -52.821043) (xy 181.812472 -52.785328) (xy 181.858353 -52.755842) (xy 181.907963 -52.733185)
			(xy 181.960293 -52.71782) (xy 182.014277 -52.710058) (xy 182.068815 -52.710058) (xy 182.122799 -52.71782)
			(xy 182.175129 -52.733185) (xy 182.224739 -52.755842) (xy 182.27062 -52.785328) (xy 182.311837 -52.821043)
			(xy 182.347552 -52.86226) (xy 182.377038 -52.908141) (xy 182.399695 -52.957751) (xy 182.41506 -53.010081)
			(xy 182.422822 -53.064065) (xy 182.423308 -53.091334) (xy 182.423308 -53.954934) (xy 182.422822 -53.982203)
			(xy 182.41506 -54.036187) (xy 182.399695 -54.088517) (xy 182.377038 -54.138127) (xy 182.347552 -54.184008)
			(xy 182.311837 -54.225225) (xy 182.27062 -54.26094) (xy 182.224739 -54.290426) (xy 182.175129 -54.313083)
			(xy 182.122799 -54.328448) (xy 182.068815 -54.33621) (xy 182.014277 -54.33621) (xy 181.960293 -54.328448)
			(xy 181.907963 -54.313083) (xy 181.858353 -54.290426) (xy 181.812472 -54.26094) (xy 181.771255 -54.225225)
			(xy 181.73554 -54.184008) (xy 181.706054 -54.138127) (xy 181.683397 -54.088517) (xy 181.668032 -54.036187)
			(xy 181.66027 -53.982203) (xy 181.659784 -53.954934) (xy 0.509016 -53.954934) (xy 0.509016 -55.481728)
			(xy 178.630072 -55.481728) (xy 178.630072 -54.618128) (xy 178.630558 -54.590859) (xy 178.63832 -54.536875)
			(xy 178.653685 -54.484545) (xy 178.676342 -54.434935) (xy 178.705828 -54.389054) (xy 178.741543 -54.347837)
			(xy 178.78276 -54.312122) (xy 178.828641 -54.282636) (xy 178.878251 -54.259979) (xy 178.930581 -54.244614)
			(xy 178.984565 -54.236852) (xy 179.039103 -54.236852) (xy 179.093087 -54.244614) (xy 179.145417 -54.259979)
			(xy 179.195027 -54.282636) (xy 179.240908 -54.312122) (xy 179.282125 -54.347837) (xy 179.31784 -54.389054)
			(xy 179.347326 -54.434935) (xy 179.369983 -54.484545) (xy 179.385348 -54.536875) (xy 179.39311 -54.590859)
			(xy 179.393596 -54.618128) (xy 179.393596 -55.481728) (xy 179.39311 -55.508997) (xy 179.385348 -55.562981)
			(xy 179.369983 -55.615311) (xy 179.347326 -55.664921) (xy 179.31784 -55.710802) (xy 179.282125 -55.752019)
			(xy 179.240908 -55.787734) (xy 179.195027 -55.81722) (xy 179.145417 -55.839877) (xy 179.093087 -55.855242)
			(xy 179.039103 -55.863004) (xy 178.984565 -55.863004) (xy 178.930581 -55.855242) (xy 178.878251 -55.839877)
			(xy 178.828641 -55.81722) (xy 178.78276 -55.787734) (xy 178.741543 -55.752019) (xy 178.705828 -55.710802)
			(xy 178.676342 -55.664921) (xy 178.653685 -55.615311) (xy 178.63832 -55.562981) (xy 178.630558 -55.508997)
			(xy 178.630072 -55.481728) (xy 0.509016 -55.481728) (xy 0.509016 -57.094435) (xy 170.842169 -57.094435)
			(xy 170.842169 -57.005413) (xy 170.850149 -56.916749) (xy 170.866045 -56.829158) (xy 170.889728 -56.743343)
			(xy 170.921008 -56.659998) (xy 170.959634 -56.579792) (xy 171.005293 -56.503371) (xy 171.057619 -56.43135)
			(xy 171.11619 -56.36431) (xy 171.180535 -56.30279) (xy 171.250135 -56.247286) (xy 171.324431 -56.198244)
			(xy 171.402823 -56.156059) (xy 171.484682 -56.121071) (xy 171.569347 -56.093562) (xy 171.656137 -56.073752)
			(xy 171.744353 -56.061802) (xy 171.833286 -56.057809) (xy 171.922219 -56.061802) (xy 172.010435 -56.073752)
			(xy 172.097225 -56.093562) (xy 172.18189 -56.121071) (xy 172.263749 -56.156059) (xy 172.342141 -56.198244)
			(xy 172.416437 -56.247286) (xy 172.486037 -56.30279) (xy 172.550382 -56.36431) (xy 172.608953 -56.43135)
			(xy 172.661279 -56.503371) (xy 172.706938 -56.579792) (xy 172.745564 -56.659998) (xy 172.776844 -56.743343)
			(xy 172.800527 -56.829158) (xy 172.816423 -56.916749) (xy 172.824403 -57.005413) (xy 172.824902 -57.049924)
			(xy 172.824403 -57.094435) (xy 172.816423 -57.183099) (xy 172.800527 -57.27069) (xy 172.776844 -57.356505)
			(xy 172.745564 -57.43985) (xy 172.706938 -57.520056) (xy 172.661279 -57.596477) (xy 172.608953 -57.668498)
			(xy 172.550382 -57.735538) (xy 172.486037 -57.797058) (xy 172.416437 -57.852562) (xy 172.342141 -57.901604)
			(xy 172.263749 -57.943789) (xy 172.18189 -57.978777) (xy 172.097225 -58.006286) (xy 172.010435 -58.026096)
			(xy 171.922219 -58.038046) (xy 171.833286 -58.04204) (xy 171.744353 -58.038046) (xy 171.656137 -58.026096)
			(xy 171.569347 -58.006286) (xy 171.484682 -57.978777) (xy 171.402823 -57.943789) (xy 171.324431 -57.901604)
			(xy 171.250135 -57.852562) (xy 171.180535 -57.797058) (xy 171.11619 -57.735538) (xy 171.057619 -57.668498)
			(xy 171.005293 -57.596477) (xy 170.959634 -57.520056) (xy 170.921008 -57.43985) (xy 170.889728 -57.356505)
			(xy 170.866045 -57.27069) (xy 170.850149 -57.183099) (xy 170.842169 -57.094435) (xy 0.509016 -57.094435)
			(xy 0.509016 -60.375038) (xy 233.333297 -60.375038) (xy 233.337302 -60.28713) (xy 233.349285 -60.19995)
			(xy 233.369145 -60.114221) (xy 233.39672 -60.030653) (xy 233.431779 -59.949939) (xy 233.474032 -59.872747)
			(xy 233.52313 -59.799718) (xy 233.578666 -59.731456) (xy 233.640178 -59.668526) (xy 233.707159 -59.611452)
			(xy 233.779052 -59.560704) (xy 233.855261 -59.516704) (xy 233.935156 -59.479817) (xy 234.018075 -59.450348)
			(xy 234.10333 -59.428541) (xy 234.190214 -59.414577) (xy 234.278008 -59.408571) (xy 234.365985 -59.410575)
			(xy 234.453415 -59.42057) (xy 234.539574 -59.438474) (xy 234.623748 -59.464138) (xy 234.705239 -59.497351)
			(xy 234.783373 -59.537837) (xy 234.857501 -59.585259) (xy 234.927009 -59.639226) (xy 234.991323 -59.699291)
			(xy 235.049907 -59.764955) (xy 235.102278 -59.835674) (xy 235.148001 -59.910862) (xy 235.186698 -59.989897)
			(xy 235.218047 -60.072123) (xy 235.241789 -60.156859) (xy 235.257727 -60.243403) (xy 235.265729 -60.331038)
			(xy 235.26623 -60.375038) (xy 235.265729 -60.419038) (xy 235.257727 -60.506673) (xy 235.241789 -60.593217)
			(xy 235.218047 -60.677953) (xy 235.186698 -60.760179) (xy 235.148001 -60.839214) (xy 235.102278 -60.914402)
			(xy 235.049907 -60.985121) (xy 234.991323 -61.050785) (xy 234.927009 -61.11085) (xy 234.857501 -61.164817)
			(xy 234.783373 -61.212239) (xy 234.705239 -61.252725) (xy 234.623748 -61.285938) (xy 234.539574 -61.311602)
			(xy 234.453415 -61.329506) (xy 234.365985 -61.339501) (xy 234.278008 -61.341505) (xy 234.190214 -61.335499)
			(xy 234.10333 -61.321535) (xy 234.018075 -61.299728) (xy 233.935156 -61.270259) (xy 233.855261 -61.233372)
			(xy 233.779052 -61.189372) (xy 233.707159 -61.138624) (xy 233.640178 -61.08155) (xy 233.578666 -61.01862)
			(xy 233.52313 -60.950358) (xy 233.474032 -60.877329) (xy 233.431779 -60.800137) (xy 233.39672 -60.719423)
			(xy 233.369145 -60.635855) (xy 233.349285 -60.550126) (xy 233.337302 -60.462946) (xy 233.333297 -60.375038)
			(xy 0.509016 -60.375038) (xy 0.509016 -74.760836) (xy 39.554404 -74.760836) (xy 39.554404 -66.060828)
			(xy 39.554909 -65.955304) (xy 39.562993 -65.74441) (xy 39.579149 -65.533981) (xy 39.603352 -65.324324)
			(xy 39.635569 -65.115749) (xy 39.675751 -64.908561) (xy 39.723839 -64.703064) (xy 39.779763 -64.49956)
			(xy 39.84344 -64.298347) (xy 39.914778 -64.09972) (xy 39.993672 -63.903972) (xy 40.080005 -63.71139)
			(xy 40.173652 -63.522255) (xy 40.274474 -63.336846) (xy 40.382324 -63.155435) (xy 40.497043 -62.978288)
			(xy 40.618463 -62.805666) (xy 40.746406 -62.63782) (xy 40.880684 -62.474998) (xy 41.0211 -62.317439)
			(xy 41.167448 -62.165374) (xy 41.319513 -62.019026) (xy 41.477072 -61.87861) (xy 41.639894 -61.744332)
			(xy 41.80774 -61.616389) (xy 41.980362 -61.494969) (xy 42.157509 -61.38025) (xy 42.33892 -61.2724)
			(xy 42.524329 -61.171578) (xy 42.713464 -61.077931) (xy 42.906046 -60.991598) (xy 43.101794 -60.912704)
			(xy 43.300421 -60.841366) (xy 43.501634 -60.777689) (xy 43.705138 -60.721765) (xy 43.910635 -60.673677)
			(xy 44.117823 -60.633495) (xy 44.326398 -60.601278) (xy 44.536055 -60.577075) (xy 44.746484 -60.560919)
			(xy 44.957378 -60.552835) (xy 45.168426 -60.552835) (xy 45.37932 -60.560919) (xy 45.589749 -60.577075)
			(xy 45.799406 -60.601278) (xy 46.007981 -60.633495) (xy 46.215169 -60.673677) (xy 46.420666 -60.721765)
			(xy 46.62417 -60.777689) (xy 46.825383 -60.841366) (xy 47.02401 -60.912704) (xy 47.219758 -60.991598)
			(xy 47.41234 -61.077931) (xy 47.601475 -61.171578) (xy 47.786884 -61.2724) (xy 47.968295 -61.38025)
			(xy 48.145442 -61.494969) (xy 48.318064 -61.616389) (xy 48.48591 -61.744332) (xy 48.648732 -61.87861)
			(xy 48.806291 -62.019026) (xy 48.958356 -62.165374) (xy 49.104704 -62.317439) (xy 49.24512 -62.474998)
			(xy 49.379398 -62.63782) (xy 49.507341 -62.805666) (xy 49.628761 -62.978288) (xy 49.74348 -63.155435)
			(xy 49.85133 -63.336846) (xy 49.952152 -63.522255) (xy 50.045799 -63.71139) (xy 50.132132 -63.903972)
			(xy 50.211026 -64.09972) (xy 50.282364 -64.298347) (xy 50.346041 -64.49956) (xy 50.401965 -64.703064)
			(xy 50.450053 -64.908561) (xy 50.490235 -65.115749) (xy 50.522452 -65.324324) (xy 50.546655 -65.533981)
			(xy 50.562811 -65.74441) (xy 50.570895 -65.955304) (xy 50.5714 -66.060828) (xy 50.5714 -74.760836)
			(xy 50.571366 -74.767948) (xy 173.354492 -74.767948) (xy 173.354492 -66.06794) (xy 173.354997 -65.962416)
			(xy 173.363081 -65.751522) (xy 173.379237 -65.541093) (xy 173.40344 -65.331436) (xy 173.435657 -65.122861)
			(xy 173.475839 -64.915673) (xy 173.523927 -64.710176) (xy 173.579851 -64.506672) (xy 173.643528 -64.305459)
			(xy 173.714866 -64.106832) (xy 173.79376 -63.911084) (xy 173.880093 -63.718502) (xy 173.97374 -63.529367)
			(xy 174.074562 -63.343958) (xy 174.182412 -63.162547) (xy 174.297131 -62.9854) (xy 174.418551 -62.812778)
			(xy 174.546494 -62.644932) (xy 174.680772 -62.48211) (xy 174.821188 -62.324551) (xy 174.967536 -62.172486)
			(xy 175.119601 -62.026138) (xy 175.27716 -61.885722) (xy 175.439982 -61.751444) (xy 175.607828 -61.623501)
			(xy 175.78045 -61.502081) (xy 175.957597 -61.387362) (xy 176.139008 -61.279512) (xy 176.324417 -61.17869)
			(xy 176.513552 -61.085043) (xy 176.706134 -60.99871) (xy 176.901882 -60.919816) (xy 177.100509 -60.848478)
			(xy 177.301722 -60.784801) (xy 177.505226 -60.728877) (xy 177.710723 -60.680789) (xy 177.917911 -60.640607)
			(xy 178.126486 -60.60839) (xy 178.336143 -60.584187) (xy 178.546572 -60.568031) (xy 178.757466 -60.559947)
			(xy 178.968514 -60.559947) (xy 179.179408 -60.568031) (xy 179.389837 -60.584187) (xy 179.599494 -60.60839)
			(xy 179.808069 -60.640607) (xy 180.015257 -60.680789) (xy 180.220754 -60.728877) (xy 180.424258 -60.784801)
			(xy 180.625471 -60.848478) (xy 180.824098 -60.919816) (xy 181.019846 -60.99871) (xy 181.212428 -61.085043)
			(xy 181.401563 -61.17869) (xy 181.586972 -61.279512) (xy 181.768383 -61.387362) (xy 181.94553 -61.502081)
			(xy 182.118152 -61.623501) (xy 182.285998 -61.751444) (xy 182.44882 -61.885722) (xy 182.606379 -62.026138)
			(xy 182.758444 -62.172486) (xy 182.904792 -62.324551) (xy 183.045208 -62.48211) (xy 183.179486 -62.644932)
			(xy 183.307429 -62.812778) (xy 183.428849 -62.9854) (xy 183.543568 -63.162547) (xy 183.651418 -63.343958)
			(xy 183.75224 -63.529367) (xy 183.845887 -63.718502) (xy 183.93222 -63.911084) (xy 184.011114 -64.106832)
			(xy 184.082452 -64.305459) (xy 184.146129 -64.506672) (xy 184.202053 -64.710176) (xy 184.250141 -64.915673)
			(xy 184.290323 -65.122861) (xy 184.32254 -65.331436) (xy 184.346743 -65.541093) (xy 184.362899 -65.751522)
			(xy 184.370983 -65.962416) (xy 184.371488 -66.06794) (xy 184.371488 -74.760836) (xy 287.494472 -74.760836)
			(xy 287.494472 -66.060828) (xy 287.494977 -65.955304) (xy 287.503061 -65.74441) (xy 287.519217 -65.533981)
			(xy 287.54342 -65.324324) (xy 287.575637 -65.115749) (xy 287.615819 -64.908561) (xy 287.663907 -64.703064)
			(xy 287.719831 -64.49956) (xy 287.783508 -64.298347) (xy 287.854846 -64.09972) (xy 287.93374 -63.903972)
			(xy 288.020073 -63.71139) (xy 288.11372 -63.522255) (xy 288.214542 -63.336846) (xy 288.322392 -63.155435)
			(xy 288.437111 -62.978288) (xy 288.558531 -62.805666) (xy 288.686474 -62.63782) (xy 288.820752 -62.474998)
			(xy 288.961168 -62.317439) (xy 289.107516 -62.165374) (xy 289.259581 -62.019026) (xy 289.41714 -61.87861)
			(xy 289.579962 -61.744332) (xy 289.747808 -61.616389) (xy 289.92043 -61.494969) (xy 290.097577 -61.38025)
			(xy 290.278988 -61.2724) (xy 290.464397 -61.171578) (xy 290.653532 -61.077931) (xy 290.846114 -60.991598)
			(xy 291.041862 -60.912704) (xy 291.240489 -60.841366) (xy 291.441702 -60.777689) (xy 291.645206 -60.721765)
			(xy 291.850703 -60.673677) (xy 292.057891 -60.633495) (xy 292.266466 -60.601278) (xy 292.476123 -60.577075)
			(xy 292.686552 -60.560919) (xy 292.897446 -60.552835) (xy 293.108494 -60.552835) (xy 293.319388 -60.560919)
			(xy 293.529817 -60.577075) (xy 293.739474 -60.601278) (xy 293.948049 -60.633495) (xy 294.155237 -60.673677)
			(xy 294.360734 -60.721765) (xy 294.564238 -60.777689) (xy 294.765451 -60.841366) (xy 294.964078 -60.912704)
			(xy 295.159826 -60.991598) (xy 295.352408 -61.077931) (xy 295.541543 -61.171578) (xy 295.726952 -61.2724)
			(xy 295.908363 -61.38025) (xy 296.08551 -61.494969) (xy 296.258132 -61.616389) (xy 296.425978 -61.744332)
			(xy 296.5888 -61.87861) (xy 296.746359 -62.019026) (xy 296.898424 -62.165374) (xy 297.044772 -62.317439)
			(xy 297.185188 -62.474998) (xy 297.319466 -62.63782) (xy 297.447409 -62.805666) (xy 297.568829 -62.978288)
			(xy 297.683548 -63.155435) (xy 297.791398 -63.336846) (xy 297.89222 -63.522255) (xy 297.985867 -63.71139)
			(xy 298.0722 -63.903972) (xy 298.151094 -64.09972) (xy 298.222432 -64.298347) (xy 298.286109 -64.49956)
			(xy 298.342033 -64.703064) (xy 298.390121 -64.908561) (xy 298.430303 -65.115749) (xy 298.46252 -65.324324)
			(xy 298.486723 -65.533981) (xy 298.502879 -65.74441) (xy 298.510963 -65.955304) (xy 298.511468 -66.060828)
			(xy 298.511468 -74.760836) (xy 298.511434 -74.767948) (xy 421.29456 -74.767948) (xy 421.29456 -66.06794)
			(xy 421.295065 -65.962416) (xy 421.303149 -65.751522) (xy 421.319305 -65.541093) (xy 421.343508 -65.331436)
			(xy 421.375725 -65.122861) (xy 421.415907 -64.915673) (xy 421.463995 -64.710176) (xy 421.519919 -64.506672)
			(xy 421.583596 -64.305459) (xy 421.654934 -64.106832) (xy 421.733828 -63.911084) (xy 421.820161 -63.718502)
			(xy 421.913808 -63.529367) (xy 422.01463 -63.343958) (xy 422.12248 -63.162547) (xy 422.237199 -62.9854)
			(xy 422.358619 -62.812778) (xy 422.486562 -62.644932) (xy 422.62084 -62.48211) (xy 422.761256 -62.324551)
			(xy 422.907604 -62.172486) (xy 423.059669 -62.026138) (xy 423.217228 -61.885722) (xy 423.38005 -61.751444)
			(xy 423.547896 -61.623501) (xy 423.720518 -61.502081) (xy 423.897665 -61.387362) (xy 424.079076 -61.279512)
			(xy 424.264485 -61.17869) (xy 424.45362 -61.085043) (xy 424.646202 -60.99871) (xy 424.84195 -60.919816)
			(xy 425.040577 -60.848478) (xy 425.24179 -60.784801) (xy 425.445294 -60.728877) (xy 425.650791 -60.680789)
			(xy 425.857979 -60.640607) (xy 426.066554 -60.60839) (xy 426.276211 -60.584187) (xy 426.48664 -60.568031)
			(xy 426.697534 -60.559947) (xy 426.908582 -60.559947) (xy 427.119476 -60.568031) (xy 427.329905 -60.584187)
			(xy 427.539562 -60.60839) (xy 427.748137 -60.640607) (xy 427.955325 -60.680789) (xy 428.160822 -60.728877)
			(xy 428.364326 -60.784801) (xy 428.565539 -60.848478) (xy 428.764166 -60.919816) (xy 428.959914 -60.99871)
			(xy 429.152496 -61.085043) (xy 429.341631 -61.17869) (xy 429.52704 -61.279512) (xy 429.708451 -61.387362)
			(xy 429.885598 -61.502081) (xy 430.05822 -61.623501) (xy 430.226066 -61.751444) (xy 430.388888 -61.885722)
			(xy 430.546447 -62.026138) (xy 430.698512 -62.172486) (xy 430.84486 -62.324551) (xy 430.985276 -62.48211)
			(xy 431.119554 -62.644932) (xy 431.247497 -62.812778) (xy 431.368917 -62.9854) (xy 431.483636 -63.162547)
			(xy 431.591486 -63.343958) (xy 431.692308 -63.529367) (xy 431.785955 -63.718502) (xy 431.872288 -63.911084)
			(xy 431.951182 -64.106832) (xy 432.02252 -64.305459) (xy 432.086197 -64.506672) (xy 432.142121 -64.710176)
			(xy 432.190209 -64.915673) (xy 432.230391 -65.122861) (xy 432.262608 -65.331436) (xy 432.286811 -65.541093)
			(xy 432.302967 -65.751522) (xy 432.311051 -65.962416) (xy 432.311556 -66.06794) (xy 432.311556 -74.767948)
			(xy 432.311051 -74.873472) (xy 432.302967 -75.084366) (xy 432.286811 -75.294795) (xy 432.262608 -75.504452)
			(xy 432.230391 -75.713027) (xy 432.190209 -75.920215) (xy 432.142121 -76.125712) (xy 432.086197 -76.329216)
			(xy 432.02252 -76.530429) (xy 431.951182 -76.729056) (xy 431.872288 -76.924804) (xy 431.785955 -77.117386)
			(xy 431.692308 -77.306521) (xy 431.591486 -77.49193) (xy 431.483636 -77.673341) (xy 431.368917 -77.850488)
			(xy 431.247497 -78.02311) (xy 431.119554 -78.190956) (xy 430.985276 -78.353778) (xy 430.84486 -78.511337)
			(xy 430.698512 -78.663402) (xy 430.546447 -78.80975) (xy 430.388888 -78.950166) (xy 430.226066 -79.084444)
			(xy 430.05822 -79.212387) (xy 429.885598 -79.333807) (xy 429.708451 -79.448526) (xy 429.52704 -79.556376)
			(xy 429.341631 -79.657198) (xy 429.152496 -79.750845) (xy 428.959914 -79.837178) (xy 428.764166 -79.916072)
			(xy 428.565539 -79.98741) (xy 428.364326 -80.051087) (xy 428.160822 -80.107011) (xy 427.955325 -80.155099)
			(xy 427.748137 -80.195281) (xy 427.539562 -80.227498) (xy 427.329905 -80.251701) (xy 427.119476 -80.267857)
			(xy 426.908582 -80.275941) (xy 426.697534 -80.275941) (xy 426.48664 -80.267857) (xy 426.276211 -80.251701)
			(xy 426.066554 -80.227498) (xy 425.857979 -80.195281) (xy 425.650791 -80.155099) (xy 425.445294 -80.107011)
			(xy 425.24179 -80.051087) (xy 425.040577 -79.98741) (xy 424.84195 -79.916072) (xy 424.646202 -79.837178)
			(xy 424.45362 -79.750845) (xy 424.264485 -79.657198) (xy 424.079076 -79.556376) (xy 423.897665 -79.448526)
			(xy 423.720518 -79.333807) (xy 423.547896 -79.212387) (xy 423.38005 -79.084444) (xy 423.217228 -78.950166)
			(xy 423.059669 -78.80975) (xy 422.907604 -78.663402) (xy 422.761256 -78.511337) (xy 422.62084 -78.353778)
			(xy 422.486562 -78.190956) (xy 422.358619 -78.02311) (xy 422.237199 -77.850488) (xy 422.12248 -77.673341)
			(xy 422.01463 -77.49193) (xy 421.913808 -77.306521) (xy 421.820161 -77.117386) (xy 421.733828 -76.924804)
			(xy 421.654934 -76.729056) (xy 421.583596 -76.530429) (xy 421.519919 -76.329216) (xy 421.463995 -76.125712)
			(xy 421.415907 -75.920215) (xy 421.375725 -75.713027) (xy 421.343508 -75.504452) (xy 421.319305 -75.294795)
			(xy 421.303149 -75.084366) (xy 421.295065 -74.873472) (xy 421.29456 -74.767948) (xy 298.511434 -74.767948)
			(xy 298.510963 -74.86636) (xy 298.502879 -75.077254) (xy 298.486723 -75.287683) (xy 298.46252 -75.49734)
			(xy 298.430303 -75.705915) (xy 298.390121 -75.913103) (xy 298.342033 -76.1186) (xy 298.286109 -76.322104)
			(xy 298.222432 -76.523317) (xy 298.151094 -76.721944) (xy 298.0722 -76.917692) (xy 297.985867 -77.110274)
			(xy 297.89222 -77.299409) (xy 297.791398 -77.484818) (xy 297.683548 -77.666229) (xy 297.568829 -77.843376)
			(xy 297.447409 -78.015998) (xy 297.319466 -78.183844) (xy 297.185188 -78.346666) (xy 297.044772 -78.504225)
			(xy 296.898424 -78.65629) (xy 296.746359 -78.802638) (xy 296.5888 -78.943054) (xy 296.425978 -79.077332)
			(xy 296.258132 -79.205275) (xy 296.08551 -79.326695) (xy 295.908363 -79.441414) (xy 295.726952 -79.549264)
			(xy 295.541543 -79.650086) (xy 295.352408 -79.743733) (xy 295.159826 -79.830066) (xy 294.964078 -79.90896)
			(xy 294.765451 -79.980298) (xy 294.564238 -80.043975) (xy 294.360734 -80.099899) (xy 294.155237 -80.147987)
			(xy 293.948049 -80.188169) (xy 293.739474 -80.220386) (xy 293.529817 -80.244589) (xy 293.319388 -80.260745)
			(xy 293.108494 -80.268829) (xy 292.897446 -80.268829) (xy 292.686552 -80.260745) (xy 292.476123 -80.244589)
			(xy 292.266466 -80.220386) (xy 292.057891 -80.188169) (xy 291.850703 -80.147987) (xy 291.645206 -80.099899)
			(xy 291.441702 -80.043975) (xy 291.240489 -79.980298) (xy 291.041862 -79.90896) (xy 290.846114 -79.830066)
			(xy 290.653532 -79.743733) (xy 290.464397 -79.650086) (xy 290.278988 -79.549264) (xy 290.097577 -79.441414)
			(xy 289.92043 -79.326695) (xy 289.747808 -79.205275) (xy 289.579962 -79.077332) (xy 289.41714 -78.943054)
			(xy 289.259581 -78.802638) (xy 289.107516 -78.65629) (xy 288.961168 -78.504225) (xy 288.820752 -78.346666)
			(xy 288.686474 -78.183844) (xy 288.558531 -78.015998) (xy 288.437111 -77.843376) (xy 288.322392 -77.666229)
			(xy 288.214542 -77.484818) (xy 288.11372 -77.299409) (xy 288.020073 -77.110274) (xy 287.93374 -76.917692)
			(xy 287.854846 -76.721944) (xy 287.783508 -76.523317) (xy 287.719831 -76.322104) (xy 287.663907 -76.1186)
			(xy 287.615819 -75.913103) (xy 287.575637 -75.705915) (xy 287.54342 -75.49734) (xy 287.519217 -75.287683)
			(xy 287.503061 -75.077254) (xy 287.494977 -74.86636) (xy 287.494472 -74.760836) (xy 184.371488 -74.760836)
			(xy 184.371488 -74.767948) (xy 184.370983 -74.873472) (xy 184.362899 -75.084366) (xy 184.346743 -75.294795)
			(xy 184.32254 -75.504452) (xy 184.290323 -75.713027) (xy 184.250141 -75.920215) (xy 184.202053 -76.125712)
			(xy 184.146129 -76.329216) (xy 184.082452 -76.530429) (xy 184.011114 -76.729056) (xy 183.93222 -76.924804)
			(xy 183.845887 -77.117386) (xy 183.75224 -77.306521) (xy 183.651418 -77.49193) (xy 183.543568 -77.673341)
			(xy 183.428849 -77.850488) (xy 183.307429 -78.02311) (xy 183.179486 -78.190956) (xy 183.045208 -78.353778)
			(xy 182.904792 -78.511337) (xy 182.758444 -78.663402) (xy 182.606379 -78.80975) (xy 182.44882 -78.950166)
			(xy 182.285998 -79.084444) (xy 182.118152 -79.212387) (xy 181.94553 -79.333807) (xy 181.768383 -79.448526)
			(xy 181.586972 -79.556376) (xy 181.401563 -79.657198) (xy 181.212428 -79.750845) (xy 181.019846 -79.837178)
			(xy 180.824098 -79.916072) (xy 180.625471 -79.98741) (xy 180.424258 -80.051087) (xy 180.220754 -80.107011)
			(xy 180.015257 -80.155099) (xy 179.808069 -80.195281) (xy 179.599494 -80.227498) (xy 179.389837 -80.251701)
			(xy 179.179408 -80.267857) (xy 178.968514 -80.275941) (xy 178.757466 -80.275941) (xy 178.546572 -80.267857)
			(xy 178.336143 -80.251701) (xy 178.126486 -80.227498) (xy 177.917911 -80.195281) (xy 177.710723 -80.155099)
			(xy 177.505226 -80.107011) (xy 177.301722 -80.051087) (xy 177.100509 -79.98741) (xy 176.901882 -79.916072)
			(xy 176.706134 -79.837178) (xy 176.513552 -79.750845) (xy 176.324417 -79.657198) (xy 176.139008 -79.556376)
			(xy 175.957597 -79.448526) (xy 175.78045 -79.333807) (xy 175.607828 -79.212387) (xy 175.439982 -79.084444)
			(xy 175.27716 -78.950166) (xy 175.119601 -78.80975) (xy 174.967536 -78.663402) (xy 174.821188 -78.511337)
			(xy 174.680772 -78.353778) (xy 174.546494 -78.190956) (xy 174.418551 -78.02311) (xy 174.297131 -77.850488)
			(xy 174.182412 -77.673341) (xy 174.074562 -77.49193) (xy 173.97374 -77.306521) (xy 173.880093 -77.117386)
			(xy 173.79376 -76.924804) (xy 173.714866 -76.729056) (xy 173.643528 -76.530429) (xy 173.579851 -76.329216)
			(xy 173.523927 -76.125712) (xy 173.475839 -75.920215) (xy 173.435657 -75.713027) (xy 173.40344 -75.504452)
			(xy 173.379237 -75.294795) (xy 173.363081 -75.084366) (xy 173.354997 -74.873472) (xy 173.354492 -74.767948)
			(xy 50.571366 -74.767948) (xy 50.570895 -74.86636) (xy 50.562811 -75.077254) (xy 50.546655 -75.287683)
			(xy 50.522452 -75.49734) (xy 50.490235 -75.705915) (xy 50.450053 -75.913103) (xy 50.401965 -76.1186)
			(xy 50.346041 -76.322104) (xy 50.282364 -76.523317) (xy 50.211026 -76.721944) (xy 50.132132 -76.917692)
			(xy 50.045799 -77.110274) (xy 49.952152 -77.299409) (xy 49.85133 -77.484818) (xy 49.74348 -77.666229)
			(xy 49.628761 -77.843376) (xy 49.507341 -78.015998) (xy 49.379398 -78.183844) (xy 49.24512 -78.346666)
			(xy 49.104704 -78.504225) (xy 48.958356 -78.65629) (xy 48.806291 -78.802638) (xy 48.648732 -78.943054)
			(xy 48.48591 -79.077332) (xy 48.318064 -79.205275) (xy 48.145442 -79.326695) (xy 47.968295 -79.441414)
			(xy 47.786884 -79.549264) (xy 47.601475 -79.650086) (xy 47.41234 -79.743733) (xy 47.219758 -79.830066)
			(xy 47.02401 -79.90896) (xy 46.825383 -79.980298) (xy 46.62417 -80.043975) (xy 46.420666 -80.099899)
			(xy 46.215169 -80.147987) (xy 46.007981 -80.188169) (xy 45.799406 -80.220386) (xy 45.589749 -80.244589)
			(xy 45.37932 -80.260745) (xy 45.168426 -80.268829) (xy 44.957378 -80.268829) (xy 44.746484 -80.260745)
			(xy 44.536055 -80.244589) (xy 44.326398 -80.220386) (xy 44.117823 -80.188169) (xy 43.910635 -80.147987)
			(xy 43.705138 -80.099899) (xy 43.501634 -80.043975) (xy 43.300421 -79.980298) (xy 43.101794 -79.90896)
			(xy 42.906046 -79.830066) (xy 42.713464 -79.743733) (xy 42.524329 -79.650086) (xy 42.33892 -79.549264)
			(xy 42.157509 -79.441414) (xy 41.980362 -79.326695) (xy 41.80774 -79.205275) (xy 41.639894 -79.077332)
			(xy 41.477072 -78.943054) (xy 41.319513 -78.802638) (xy 41.167448 -78.65629) (xy 41.0211 -78.504225)
			(xy 40.880684 -78.346666) (xy 40.746406 -78.183844) (xy 40.618463 -78.015998) (xy 40.497043 -77.843376)
			(xy 40.382324 -77.666229) (xy 40.274474 -77.484818) (xy 40.173652 -77.299409) (xy 40.080005 -77.110274)
			(xy 39.993672 -76.917692) (xy 39.914778 -76.721944) (xy 39.84344 -76.523317) (xy 39.779763 -76.322104)
			(xy 39.723839 -76.1186) (xy 39.675751 -75.913103) (xy 39.635569 -75.705915) (xy 39.603352 -75.49734)
			(xy 39.579149 -75.287683) (xy 39.562993 -75.077254) (xy 39.554909 -74.86636) (xy 39.554404 -74.760836)
			(xy 0.509016 -74.760836) (xy 0.509016 -77.67193) (xy 0.5095 -77.725143) (xy 0.517108 -77.831296)
			(xy 0.532269 -77.936637) (xy 0.554904 -78.040627) (xy 0.584899 -78.142739) (xy 0.622101 -78.242451)
			(xy 0.666319 -78.339256) (xy 0.71733 -78.43266) (xy 0.774873 -78.522188) (xy 0.838654 -78.607384)
			(xy 0.90835 -78.687813) (xy 0.945642 -78.725776) (xy 1.77419 -79.554324) (xy 1.823612 -79.604428)
			(xy 1.917404 -79.709374) (xy 2.005163 -79.819414) (xy 2.086614 -79.934202) (xy 2.161501 -80.053377)
			(xy 2.229587 -80.176563) (xy 2.290658 -80.303374) (xy 2.344523 -80.433409) (xy 2.391012 -80.56626)
			(xy 2.429978 -80.701509) (xy 2.461299 -80.83873) (xy 2.484876 -80.977491) (xy 2.500635 -81.117356)
			(xy 2.508527 -81.257885) (xy 2.509012 -81.32826) (xy 2.509012 -81.691972) (xy 232.140715 -81.691972)
			(xy 232.145114 -81.518126) (xy 232.157548 -81.34467) (xy 232.177991 -81.171975) (xy 232.206398 -81.00041)
			(xy 232.242709 -80.830342) (xy 232.286847 -80.662135) (xy 232.338717 -80.49615) (xy 232.398207 -80.332741)
			(xy 232.465191 -80.172258) (xy 232.539525 -80.015044) (xy 232.62105 -79.861437) (xy 232.709592 -79.711764)
			(xy 232.804961 -79.566346) (xy 232.906953 -79.425495) (xy 233.015351 -79.289511) (xy 233.129921 -79.158685)
			(xy 233.250418 -79.033298) (xy 233.376586 -78.913618) (xy 233.508153 -78.799901) (xy 233.644839 -78.69239)
			(xy 233.715306 -78.641448) (xy 238.084614 -78.641448) (xy 238.155081 -78.69239) (xy 238.291767 -78.799901)
			(xy 238.423334 -78.913618) (xy 238.549502 -79.033298) (xy 238.669999 -79.158685) (xy 238.784569 -79.289511)
			(xy 238.892967 -79.425495) (xy 238.994959 -79.566346) (xy 239.090328 -79.711764) (xy 239.17887 -79.861437)
			(xy 239.260395 -80.015044) (xy 239.334729 -80.172258) (xy 239.401713 -80.332741) (xy 239.461203 -80.49615)
			(xy 239.513073 -80.662135) (xy 239.557211 -80.830342) (xy 239.593522 -81.00041) (xy 239.608937 -81.093507)
			(xy 398.275806 -81.093507) (xy 398.275806 -81.008785) (xy 398.283859 -80.924448) (xy 398.299893 -80.841258)
			(xy 398.323761 -80.759968) (xy 398.355249 -80.681316) (xy 398.394071 -80.606013) (xy 398.439874 -80.534741)
			(xy 398.492245 -80.468145) (xy 398.55071 -80.40683) (xy 398.614738 -80.351349) (xy 398.68375 -80.302206)
			(xy 398.75712 -80.259846) (xy 398.834185 -80.224651) (xy 398.914247 -80.196942) (xy 398.99658 -80.176968)
			(xy 399.080439 -80.164911) (xy 399.165064 -80.16088) (xy 399.249689 -80.164911) (xy 399.333548 -80.176968)
			(xy 399.415881 -80.196942) (xy 399.495943 -80.224651) (xy 399.573008 -80.259846) (xy 399.646378 -80.302206)
			(xy 399.71539 -80.351349) (xy 399.779418 -80.40683) (xy 399.837883 -80.468145) (xy 399.890254 -80.534741)
			(xy 399.936057 -80.606013) (xy 399.974879 -80.681316) (xy 400.006367 -80.759968) (xy 400.030235 -80.841258)
			(xy 400.046269 -80.924448) (xy 400.054322 -81.008785) (xy 400.054826 -81.051146) (xy 400.054322 -81.093507)
			(xy 400.046269 -81.177844) (xy 400.030235 -81.261034) (xy 400.006367 -81.342324) (xy 399.974879 -81.420976)
			(xy 399.936057 -81.496279) (xy 399.890254 -81.567551) (xy 399.837883 -81.634147) (xy 399.779418 -81.695462)
			(xy 399.71539 -81.750943) (xy 399.646378 -81.800086) (xy 399.573008 -81.842446) (xy 399.495943 -81.877641)
			(xy 399.415881 -81.90535) (xy 399.333548 -81.925324) (xy 399.249689 -81.937381) (xy 399.165064 -81.941413)
			(xy 399.080439 -81.937381) (xy 398.99658 -81.925324) (xy 398.914247 -81.90535) (xy 398.834185 -81.877641)
			(xy 398.75712 -81.842446) (xy 398.68375 -81.800086) (xy 398.614738 -81.750943) (xy 398.55071 -81.695462)
			(xy 398.492245 -81.634147) (xy 398.439874 -81.567551) (xy 398.394071 -81.496279) (xy 398.355249 -81.420976)
			(xy 398.323761 -81.342324) (xy 398.299893 -81.261034) (xy 398.283859 -81.177844) (xy 398.275806 -81.093507)
			(xy 239.608937 -81.093507) (xy 239.621929 -81.171975) (xy 239.642372 -81.34467) (xy 239.654806 -81.518126)
			(xy 239.659205 -81.691972) (xy 239.655559 -81.865835) (xy 239.643877 -82.039343) (xy 239.624183 -82.212126)
			(xy 239.596519 -82.383812) (xy 239.560945 -82.554036) (xy 239.517536 -82.722432) (xy 239.466387 -82.888641)
			(xy 239.407605 -83.052306) (xy 239.341317 -83.213078) (xy 239.267665 -83.370612) (xy 239.186806 -83.524571)
			(xy 239.098913 -83.674626) (xy 239.004175 -83.820455) (xy 238.902794 -83.961748) (xy 238.794987 -84.0982)
			(xy 238.680985 -84.229521) (xy 238.561032 -84.355429) (xy 238.435384 -84.475655) (xy 238.30431 -84.589941)
			(xy 238.168092 -84.698043) (xy 238.027019 -84.79973) (xy 237.881395 -84.894784) (xy 237.731531 -84.983001)
			(xy 237.577747 -85.064194) (xy 237.420373 -85.138187) (xy 237.259746 -85.204823) (xy 237.096208 -85.263959)
			(xy 236.930111 -85.315469) (xy 236.761809 -85.359242) (xy 236.591663 -85.395185) (xy 236.420037 -85.423221)
			(xy 236.247297 -85.443289) (xy 236.073815 -85.455348) (xy 235.89996 -85.45937) (xy 235.726105 -85.455348)
			(xy 235.552623 -85.443289) (xy 235.379883 -85.423221) (xy 235.208257 -85.395185) (xy 235.038111 -85.359242)
			(xy 234.869809 -85.315469) (xy 234.703712 -85.263959) (xy 234.540174 -85.204823) (xy 234.379547 -85.138187)
			(xy 234.222173 -85.064194) (xy 234.068389 -84.983001) (xy 233.918525 -84.894784) (xy 233.772901 -84.79973)
			(xy 233.631828 -84.698043) (xy 233.49561 -84.589941) (xy 233.364536 -84.475655) (xy 233.238888 -84.355429)
			(xy 233.118935 -84.229521) (xy 233.004933 -84.0982) (xy 232.897126 -83.961748) (xy 232.795745 -83.820455)
			(xy 232.701007 -83.674626) (xy 232.613114 -83.524571) (xy 232.532255 -83.370612) (xy 232.458603 -83.213078)
			(xy 232.392315 -83.052306) (xy 232.333533 -82.888641) (xy 232.282384 -82.722432) (xy 232.238975 -82.554036)
			(xy 232.203401 -82.383812) (xy 232.175737 -82.212126) (xy 232.156043 -82.039343) (xy 232.144361 -81.865835)
			(xy 232.140715 -81.691972) (xy 2.509012 -81.691972) (xy 2.509012 -84.065147) (xy 218.29831 -84.065147)
			(xy 218.29831 -84.010653) (xy 218.306065 -83.956712) (xy 218.321417 -83.904424) (xy 218.344054 -83.854854)
			(xy 218.373515 -83.809009) (xy 218.4092 -83.767823) (xy 218.450383 -83.732134) (xy 218.496225 -83.70267)
			(xy 218.545794 -83.680029) (xy 218.598081 -83.664672) (xy 218.652021 -83.656912) (xy 218.679268 -83.656424)
			(xy 219.542868 -83.656424) (xy 219.570125 -83.656821) (xy 219.624084 -83.664575) (xy 219.67639 -83.679929)
			(xy 219.725978 -83.702572) (xy 219.771839 -83.732041) (xy 219.813039 -83.767738) (xy 219.848739 -83.808935)
			(xy 219.878213 -83.854794) (xy 219.90086 -83.90438) (xy 219.916219 -83.956685) (xy 219.923977 -84.010643)
			(xy 219.923977 -84.065157) (xy 219.916219 -84.119115) (xy 219.90086 -84.17142) (xy 219.878213 -84.221006)
			(xy 219.848739 -84.266865) (xy 219.813039 -84.308062) (xy 219.771839 -84.343759) (xy 219.725978 -84.373228)
			(xy 219.67639 -84.395871) (xy 219.624084 -84.411225) (xy 219.570125 -84.418979) (xy 219.542868 -84.41944)
			(xy 218.679268 -84.41944) (xy 218.652021 -84.418888) (xy 218.598081 -84.411128) (xy 218.545794 -84.395771)
			(xy 218.496225 -84.37313) (xy 218.450383 -84.343666) (xy 218.4092 -84.307977) (xy 218.373515 -84.266791)
			(xy 218.344054 -84.220946) (xy 218.321417 -84.171376) (xy 218.306065 -84.119088) (xy 218.29831 -84.065147)
			(xy 2.509012 -84.065147) (xy 2.509012 -86.948548) (xy 217.344518 -86.948548) (xy 217.344518 -86.894052)
			(xy 217.352274 -86.84011) (xy 217.367627 -86.787821) (xy 217.390266 -86.738249) (xy 217.419729 -86.692404)
			(xy 217.455416 -86.651218) (xy 217.496602 -86.61553) (xy 217.542447 -86.586067) (xy 217.592019 -86.563428)
			(xy 217.644308 -86.548074) (xy 217.69825 -86.540318) (xy 217.725498 -86.539832) (xy 218.589098 -86.539832)
			(xy 218.616354 -86.540215) (xy 218.670311 -86.547972) (xy 218.722614 -86.56333) (xy 218.7722 -86.585975)
			(xy 218.818058 -86.615446) (xy 218.859255 -86.651143) (xy 218.894953 -86.69234) (xy 218.924424 -86.738198)
			(xy 218.947069 -86.787784) (xy 218.962427 -86.840087) (xy 218.970185 -86.894044) (xy 218.970185 -86.948556)
			(xy 218.962427 -87.002513) (xy 218.947069 -87.054816) (xy 218.924424 -87.104402) (xy 218.894953 -87.15026)
			(xy 218.859255 -87.191457) (xy 218.818058 -87.227154) (xy 218.7722 -87.256625) (xy 218.722614 -87.27927)
			(xy 218.670311 -87.294628) (xy 218.616354 -87.302385) (xy 218.589098 -87.302848) (xy 217.725498 -87.302848)
			(xy 217.69825 -87.302282) (xy 217.644308 -87.294526) (xy 217.592019 -87.279172) (xy 217.542447 -87.256533)
			(xy 217.496602 -87.22707) (xy 217.455416 -87.191382) (xy 217.419729 -87.150196) (xy 217.390266 -87.104351)
			(xy 217.367627 -87.054779) (xy 217.352274 -87.00249) (xy 217.344518 -86.948548) (xy 2.509012 -86.948548)
			(xy 2.509012 -106.447336) (xy 11.713464 -106.447336) (xy 11.713464 -105.456736) (xy 11.71395 -105.429467)
			(xy 11.721712 -105.375483) (xy 11.737077 -105.323153) (xy 11.759734 -105.273543) (xy 11.78922 -105.227662)
			(xy 11.824935 -105.186445) (xy 11.866152 -105.15073) (xy 11.912033 -105.121244) (xy 11.961643 -105.098587)
			(xy 12.013973 -105.083222) (xy 12.067957 -105.07546) (xy 12.122495 -105.07546) (xy 12.176479 -105.083222)
			(xy 12.228809 -105.098587) (xy 12.278419 -105.121244) (xy 12.3243 -105.15073) (xy 12.365517 -105.186445)
			(xy 12.401232 -105.227662) (xy 12.430718 -105.273543) (xy 12.453375 -105.323153) (xy 12.46874 -105.375483)
			(xy 12.476502 -105.429467) (xy 12.476988 -105.456736) (xy 12.476988 -105.664) (xy 15.57274 -105.664)
			(xy 15.57274 -104.6734) (xy 15.573226 -104.646131) (xy 15.580988 -104.592147) (xy 15.596353 -104.539817)
			(xy 15.61901 -104.490207) (xy 15.648496 -104.444326) (xy 15.684211 -104.403109) (xy 15.725428 -104.367394)
			(xy 15.771309 -104.337908) (xy 15.820919 -104.315251) (xy 15.873249 -104.299886) (xy 15.927233 -104.292124)
			(xy 15.981771 -104.292124) (xy 16.035755 -104.299886) (xy 16.088085 -104.315251) (xy 16.137695 -104.337908)
			(xy 16.146631 -104.343651) (xy 326.803 -104.343651) (xy 326.803 -104.258929) (xy 326.811053 -104.174592)
			(xy 326.827087 -104.091402) (xy 326.850955 -104.010112) (xy 326.882443 -103.93146) (xy 326.921265 -103.856157)
			(xy 326.967068 -103.784885) (xy 327.019439 -103.718289) (xy 327.077904 -103.656974) (xy 327.141932 -103.601493)
			(xy 327.210944 -103.55235) (xy 327.284314 -103.50999) (xy 327.361379 -103.474795) (xy 327.441441 -103.447086)
			(xy 327.523774 -103.427112) (xy 327.607633 -103.415055) (xy 327.692258 -103.411024) (xy 327.776883 -103.415055)
			(xy 327.860742 -103.427112) (xy 327.943075 -103.447086) (xy 328.023137 -103.474795) (xy 328.100202 -103.50999)
			(xy 328.173572 -103.55235) (xy 328.242584 -103.601493) (xy 328.306612 -103.656974) (xy 328.365077 -103.718289)
			(xy 328.417448 -103.784885) (xy 328.463251 -103.856157) (xy 328.502073 -103.93146) (xy 328.533561 -104.010112)
			(xy 328.557429 -104.091402) (xy 328.573463 -104.174592) (xy 328.581516 -104.258929) (xy 328.58202 -104.30129)
			(xy 328.581516 -104.343651) (xy 328.573463 -104.427988) (xy 328.557429 -104.511178) (xy 328.533561 -104.592468)
			(xy 328.502073 -104.67112) (xy 328.463251 -104.746423) (xy 328.417448 -104.817695) (xy 328.365077 -104.884291)
			(xy 328.306612 -104.945606) (xy 328.242584 -105.001087) (xy 328.173572 -105.05023) (xy 328.100202 -105.09259)
			(xy 328.023137 -105.127785) (xy 327.943075 -105.155494) (xy 327.860742 -105.175468) (xy 327.776883 -105.187525)
			(xy 327.692258 -105.191557) (xy 327.607633 -105.187525) (xy 327.523774 -105.175468) (xy 327.441441 -105.155494)
			(xy 327.361379 -105.127785) (xy 327.284314 -105.09259) (xy 327.210944 -105.05023) (xy 327.141932 -105.001087)
			(xy 327.077904 -104.945606) (xy 327.019439 -104.884291) (xy 326.967068 -104.817695) (xy 326.921265 -104.746423)
			(xy 326.882443 -104.67112) (xy 326.850955 -104.592468) (xy 326.827087 -104.511178) (xy 326.811053 -104.427988)
			(xy 326.803 -104.343651) (xy 16.146631 -104.343651) (xy 16.183576 -104.367394) (xy 16.224793 -104.403109)
			(xy 16.260508 -104.444326) (xy 16.289994 -104.490207) (xy 16.312651 -104.539817) (xy 16.328016 -104.592147)
			(xy 16.335778 -104.646131) (xy 16.336264 -104.6734) (xy 16.336264 -105.664) (xy 16.335778 -105.691269)
			(xy 16.328016 -105.745253) (xy 16.312651 -105.797583) (xy 16.289994 -105.847193) (xy 16.260508 -105.893074)
			(xy 16.224793 -105.934291) (xy 16.183576 -105.970006) (xy 16.137695 -105.999492) (xy 16.088085 -106.022149)
			(xy 16.035755 -106.037514) (xy 15.981771 -106.045276) (xy 15.927233 -106.045276) (xy 15.873249 -106.037514)
			(xy 15.820919 -106.022149) (xy 15.771309 -105.999492) (xy 15.725428 -105.970006) (xy 15.684211 -105.934291)
			(xy 15.648496 -105.893074) (xy 15.61901 -105.847193) (xy 15.596353 -105.797583) (xy 15.580988 -105.745253)
			(xy 15.573226 -105.691269) (xy 15.57274 -105.664) (xy 12.476988 -105.664) (xy 12.476988 -106.447336)
			(xy 12.476502 -106.474605) (xy 12.46874 -106.528589) (xy 12.453375 -106.580919) (xy 12.430718 -106.630529)
			(xy 12.401232 -106.67641) (xy 12.365517 -106.717627) (xy 12.3243 -106.753342) (xy 12.278419 -106.782828)
			(xy 12.228809 -106.805485) (xy 12.176479 -106.82085) (xy 12.122495 -106.828612) (xy 12.067957 -106.828612)
			(xy 12.013973 -106.82085) (xy 11.961643 -106.805485) (xy 11.912033 -106.782828) (xy 11.866152 -106.753342)
			(xy 11.824935 -106.717627) (xy 11.78922 -106.67641) (xy 11.759734 -106.630529) (xy 11.737077 -106.580919)
			(xy 11.721712 -106.528589) (xy 11.71395 -106.474605) (xy 11.713464 -106.447336) (xy 2.509012 -106.447336)
			(xy 2.509012 -108.943971) (xy 11.292822 -108.943971) (xy 11.292822 -108.889469) (xy 11.300578 -108.835522)
			(xy 11.315933 -108.783228) (xy 11.338574 -108.733651) (xy 11.36804 -108.687801) (xy 11.403731 -108.646611)
			(xy 11.444921 -108.61092) (xy 11.490771 -108.581454) (xy 11.540348 -108.558813) (xy 11.592642 -108.543458)
			(xy 11.646589 -108.535702) (xy 11.67384 -108.535216) (xy 12.53744 -108.535216) (xy 12.564692 -108.535694)
			(xy 12.61864 -108.54345) (xy 12.670935 -108.558806) (xy 12.720513 -108.581447) (xy 12.766364 -108.610914)
			(xy 12.807554 -108.646606) (xy 12.843246 -108.687796) (xy 12.872713 -108.733647) (xy 12.895354 -108.783225)
			(xy 12.91071 -108.83552) (xy 12.918466 -108.889468) (xy 12.918466 -108.943972) (xy 12.91071 -108.99792)
			(xy 12.895354 -109.050215) (xy 12.872713 -109.099793) (xy 12.843246 -109.145644) (xy 12.807554 -109.186834)
			(xy 12.766364 -109.222526) (xy 12.720513 -109.251993) (xy 12.670935 -109.274634) (xy 12.61864 -109.28999)
			(xy 12.564692 -109.297746) (xy 12.53744 -109.298232) (xy 11.67384 -109.298232) (xy 11.646589 -109.297738)
			(xy 11.592642 -109.289982) (xy 11.540348 -109.274627) (xy 11.490771 -109.251986) (xy 11.444921 -109.22252)
			(xy 11.403731 -109.186829) (xy 11.36804 -109.145639) (xy 11.338574 -109.099789) (xy 11.315933 -109.050212)
			(xy 11.300578 -108.997918) (xy 11.292822 -108.943971) (xy 2.509012 -108.943971) (xy 2.509012 -109.451973)
			(xy 15.092889 -109.451973) (xy 15.092889 -109.397467) (xy 15.100646 -109.343517) (xy 15.116002 -109.291219)
			(xy 15.138645 -109.241639) (xy 15.168113 -109.195786) (xy 15.203807 -109.154594) (xy 15.244999 -109.118901)
			(xy 15.290853 -109.089433) (xy 15.340433 -109.066791) (xy 15.39273 -109.051435) (xy 15.446681 -109.043679)
			(xy 15.473934 -109.043216) (xy 16.464534 -109.043216) (xy 16.491785 -109.043694) (xy 16.545733 -109.051451)
			(xy 16.598028 -109.066807) (xy 16.647605 -109.089448) (xy 16.693456 -109.118915) (xy 16.734646 -109.154607)
			(xy 16.770337 -109.195798) (xy 16.799804 -109.241648) (xy 16.822445 -109.291226) (xy 16.8378 -109.343521)
			(xy 16.845556 -109.397469) (xy 16.845556 -109.451971) (xy 16.8378 -109.505919) (xy 16.822445 -109.558214)
			(xy 16.799804 -109.607792) (xy 16.770337 -109.653642) (xy 16.734646 -109.694833) (xy 16.693456 -109.730525)
			(xy 16.647605 -109.759992) (xy 16.598028 -109.782633) (xy 16.545733 -109.797989) (xy 16.491785 -109.805746)
			(xy 16.464534 -109.806232) (xy 15.473934 -109.806232) (xy 15.446681 -109.805761) (xy 15.39273 -109.798005)
			(xy 15.340433 -109.782649) (xy 15.290853 -109.760007) (xy 15.244999 -109.730539) (xy 15.203807 -109.694846)
			(xy 15.168113 -109.653654) (xy 15.138645 -109.607801) (xy 15.116002 -109.558221) (xy 15.100646 -109.505923)
			(xy 15.092889 -109.451973) (xy 2.509012 -109.451973) (xy 2.509012 -114.734161) (xy 11.255226 -114.734161)
			(xy 11.255226 -114.679659) (xy 11.262982 -114.625711) (xy 11.278337 -114.573416) (xy 11.300979 -114.523839)
			(xy 11.330445 -114.477988) (xy 11.366136 -114.436798) (xy 11.407326 -114.401106) (xy 11.453177 -114.371639)
			(xy 11.502754 -114.348998) (xy 11.555049 -114.333643) (xy 11.608997 -114.325886) (xy 11.636248 -114.3254)
			(xy 12.499848 -114.3254) (xy 12.527101 -114.325867) (xy 12.581052 -114.333624) (xy 12.633349 -114.34898)
			(xy 12.68293 -114.371622) (xy 12.728783 -114.40109) (xy 12.769975 -114.436783) (xy 12.805669 -114.477976)
			(xy 12.835137 -114.523829) (xy 12.85778 -114.573409) (xy 12.873136 -114.625706) (xy 12.880893 -114.679657)
			(xy 12.880893 -114.734163) (xy 12.873136 -114.788114) (xy 12.85778 -114.840411) (xy 12.835137 -114.889991)
			(xy 12.805669 -114.935844) (xy 12.769975 -114.977037) (xy 12.728783 -115.01273) (xy 12.68293 -115.042198)
			(xy 12.633349 -115.06484) (xy 12.581052 -115.080196) (xy 12.527101 -115.087953) (xy 12.499848 -115.088416)
			(xy 11.636248 -115.088416) (xy 11.608997 -115.087934) (xy 11.555049 -115.080177) (xy 11.502754 -115.064822)
			(xy 11.453177 -115.042181) (xy 11.407326 -115.012714) (xy 11.366136 -114.977022) (xy 11.330445 -114.935832)
			(xy 11.300979 -114.889981) (xy 11.278337 -114.840404) (xy 11.262982 -114.788109) (xy 11.255226 -114.734161)
			(xy 2.509012 -114.734161) (xy 2.509012 -133.480302) (xy 20.179284 -133.480302) (xy 20.179284 -132.489702)
			(xy 20.17977 -132.462451) (xy 20.187526 -132.408503) (xy 20.202881 -132.356208) (xy 20.225523 -132.306631)
			(xy 20.254989 -132.260781) (xy 20.29068 -132.21959) (xy 20.331871 -132.183899) (xy 20.377721 -132.154433)
			(xy 20.427298 -132.131791) (xy 20.479593 -132.116436) (xy 20.533541 -132.10868) (xy 20.588043 -132.10868)
			(xy 20.641991 -132.116436) (xy 20.694286 -132.131791) (xy 20.743863 -132.154433) (xy 20.789713 -132.183899)
			(xy 20.830904 -132.21959) (xy 20.866595 -132.260781) (xy 20.896061 -132.306631) (xy 20.918703 -132.356208)
			(xy 20.934058 -132.408503) (xy 20.941814 -132.462451) (xy 20.9423 -132.489702) (xy 20.9423 -133.480302)
			(xy 20.941814 -133.507553) (xy 20.934058 -133.561501) (xy 20.918703 -133.613796) (xy 20.896061 -133.663373)
			(xy 20.866595 -133.709223) (xy 20.830904 -133.750414) (xy 20.789713 -133.786105) (xy 20.743863 -133.815571)
			(xy 20.694286 -133.838213) (xy 20.641991 -133.853568) (xy 20.588043 -133.861324) (xy 20.533541 -133.861324)
			(xy 20.479593 -133.853568) (xy 20.427298 -133.838213) (xy 20.377721 -133.815571) (xy 20.331871 -133.786105)
			(xy 20.29068 -133.750414) (xy 20.254989 -133.709223) (xy 20.225523 -133.663373) (xy 20.202881 -133.613796)
			(xy 20.187526 -133.561501) (xy 20.17977 -133.507553) (xy 20.179284 -133.480302) (xy 2.509012 -133.480302)
			(xy 2.509012 -138.001502) (xy 20.019264 -138.001502) (xy 20.019264 -137.010902) (xy 20.01975 -136.983651)
			(xy 20.027506 -136.929703) (xy 20.042861 -136.877408) (xy 20.065503 -136.827831) (xy 20.094969 -136.781981)
			(xy 20.13066 -136.74079) (xy 20.171851 -136.705099) (xy 20.217701 -136.675633) (xy 20.267278 -136.652991)
			(xy 20.319573 -136.637636) (xy 20.373521 -136.62988) (xy 20.428023 -136.62988) (xy 20.481971 -136.637636)
			(xy 20.534266 -136.652991) (xy 20.583843 -136.675633) (xy 20.629693 -136.705099) (xy 20.670884 -136.74079)
			(xy 20.706575 -136.781981) (xy 20.736041 -136.827831) (xy 20.758683 -136.877408) (xy 20.774038 -136.929703)
			(xy 20.781794 -136.983651) (xy 20.78228 -137.010902) (xy 20.78228 -138.001502) (xy 20.781794 -138.028753)
			(xy 20.774038 -138.082701) (xy 20.758683 -138.134996) (xy 20.736041 -138.184573) (xy 20.706575 -138.230423)
			(xy 20.670884 -138.271614) (xy 20.629693 -138.307305) (xy 20.583843 -138.336771) (xy 20.534266 -138.359413)
			(xy 20.481971 -138.374768) (xy 20.428023 -138.382524) (xy 20.373521 -138.382524) (xy 20.319573 -138.374768)
			(xy 20.267278 -138.359413) (xy 20.217701 -138.336771) (xy 20.171851 -138.307305) (xy 20.13066 -138.271614)
			(xy 20.094969 -138.230423) (xy 20.065503 -138.184573) (xy 20.042861 -138.134996) (xy 20.027506 -138.082701)
			(xy 20.01975 -138.028753) (xy 20.019264 -138.001502) (xy 2.509012 -138.001502) (xy 2.509012 -145.104166)
			(xy 163.29995 -145.104166) (xy 163.29995 -145.049634) (xy 163.30771 -144.995658) (xy 163.323072 -144.943336)
			(xy 163.345724 -144.893732) (xy 163.375204 -144.847856) (xy 163.410912 -144.806643) (xy 163.452121 -144.77093)
			(xy 163.497993 -144.741445) (xy 163.547595 -144.718788) (xy 163.599915 -144.70342) (xy 163.653891 -144.695653)
			(xy 163.681156 -144.695164) (xy 164.671756 -144.695164) (xy 164.699031 -144.695573) (xy 164.753026 -144.70333)
			(xy 164.805368 -144.718694) (xy 164.85499 -144.74135) (xy 164.900882 -144.770839) (xy 164.94211 -144.806559)
			(xy 164.977835 -144.847783) (xy 165.007329 -144.893672) (xy 165.029991 -144.943291) (xy 165.045361 -144.995631)
			(xy 165.053124 -145.049625) (xy 165.053124 -145.104175) (xy 165.045361 -145.158169) (xy 165.029991 -145.210509)
			(xy 165.007329 -145.260128) (xy 164.977835 -145.306017) (xy 164.94211 -145.347241) (xy 164.900882 -145.382961)
			(xy 164.85499 -145.41245) (xy 164.805368 -145.435106) (xy 164.753026 -145.45047) (xy 164.699031 -145.458227)
			(xy 164.671756 -145.458688) (xy 163.681156 -145.458688) (xy 163.653891 -145.458147) (xy 163.599915 -145.45038)
			(xy 163.547595 -145.435012) (xy 163.497993 -145.412355) (xy 163.452121 -145.38287) (xy 163.410912 -145.347157)
			(xy 163.375204 -145.305944) (xy 163.345724 -145.260068) (xy 163.323072 -145.210464) (xy 163.30771 -145.158142)
			(xy 163.29995 -145.104166) (xy 2.509012 -145.104166) (xy 2.509012 -153.765504) (xy 24.441921 -153.765504)
			(xy 24.445917 -153.555618) (xy 24.457902 -153.346036) (xy 24.477856 -153.137062) (xy 24.505752 -152.929)
			(xy 24.541549 -152.72215) (xy 24.585194 -152.516813) (xy 24.636626 -152.313287) (xy 24.695768 -152.111866)
			(xy 24.762536 -151.912843) (xy 24.836832 -151.716506) (xy 24.91855 -151.52314) (xy 25.007569 -151.333025)
			(xy 25.103762 -151.146437) (xy 25.206989 -150.963646) (xy 25.3171 -150.784918) (xy 25.433935 -150.610511)
			(xy 25.557325 -150.440679) (xy 25.687092 -150.275667) (xy 25.823046 -150.115716) (xy 25.964992 -149.961056)
			(xy 26.112722 -149.811912) (xy 26.266024 -149.668501) (xy 26.424674 -149.53103) (xy 26.588443 -149.399698)
			(xy 26.757093 -149.274697) (xy 26.930379 -149.156206) (xy 27.108051 -149.044399) (xy 27.289851 -148.939437)
			(xy 27.475515 -148.841472) (xy 27.664773 -148.750647) (xy 27.857353 -148.667093) (xy 28.052974 -148.59093)
			(xy 28.251352 -148.522271) (xy 28.452201 -148.461214) (xy 28.655228 -148.407847) (xy 28.860141 -148.362249)
			(xy 29.06664 -148.324484) (xy 29.274427 -148.294609) (xy 29.483202 -148.272666) (xy 29.69266 -148.258687)
			(xy 29.902499 -148.252692) (xy 30.112413 -148.254691) (xy 30.3221 -148.264679) (xy 30.531254 -148.282644)
			(xy 30.739572 -148.308558) (xy 30.946753 -148.342383) (xy 31.152497 -148.384072) (xy 31.356503 -148.433564)
			(xy 31.558478 -148.490786) (xy 31.758128 -148.555656) (xy 31.955163 -148.62808) (xy 32.149299 -148.707953)
			(xy 32.340252 -148.795159) (xy 32.527748 -148.889571) (xy 32.711513 -148.991053) (xy 32.891281 -149.099457)
			(xy 33.066792 -149.214627) (xy 33.237791 -149.336395) (xy 33.404031 -149.464584) (xy 33.56527 -149.59901)
			(xy 33.721274 -149.739477) (xy 33.871817 -149.885781) (xy 34.016681 -150.03771) (xy 34.155656 -150.195044)
			(xy 34.288541 -150.357555) (xy 34.415142 -150.525008) (xy 34.535277 -150.697158) (xy 34.648771 -150.873758)
			(xy 34.688915 -150.941786) (xy 108.742233 -150.941786) (xy 108.746238 -150.836037) (xy 108.758228 -150.730894)
			(xy 108.778137 -150.626959) (xy 108.805848 -150.524827) (xy 108.841205 -150.425083) (xy 108.884003 -150.328299)
			(xy 108.933999 -150.235029) (xy 108.990906 -150.145808) (xy 109.054397 -150.061145) (xy 109.124109 -149.981527)
			(xy 109.199643 -149.907409) (xy 109.280566 -149.839216) (xy 109.366415 -149.777338) (xy 109.456698 -149.722131)
			(xy 109.550897 -149.673909) (xy 109.648474 -149.632949) (xy 109.748869 -149.599487) (xy 109.851507 -149.573713)
			(xy 109.9558 -149.555775) (xy 110.061151 -149.545776) (xy 110.166957 -149.543773) (xy 110.272611 -149.549778)
			(xy 110.377508 -149.563757) (xy 110.481048 -149.585628) (xy 110.582637 -149.615268) (xy 110.681694 -149.652506)
			(xy 110.777651 -149.697128) (xy 110.869958 -149.74888) (xy 110.958087 -149.807465) (xy 111.041533 -149.872547)
			(xy 111.119817 -149.943753) (xy 111.187365 -150.015249) (xy 160.856694 -150.015249) (xy 160.856694 -149.960751)
			(xy 160.86445 -149.906808) (xy 160.879803 -149.854517) (xy 160.902441 -149.804944) (xy 160.931904 -149.759096)
			(xy 160.967592 -149.717909) (xy 161.008777 -149.682219) (xy 161.054623 -149.652753) (xy 161.104195 -149.630111)
			(xy 161.156484 -149.614755) (xy 161.210427 -149.606996) (xy 161.237676 -149.606508) (xy 162.228276 -149.606508)
			(xy 162.255531 -149.606937) (xy 162.309487 -149.614692) (xy 162.36179 -149.630046) (xy 162.411375 -149.652688)
			(xy 162.457233 -149.682157) (xy 162.498431 -149.717852) (xy 162.534128 -149.759047) (xy 162.5636 -149.804904)
			(xy 162.586245 -149.854488) (xy 162.601603 -149.90679) (xy 162.609361 -149.960745) (xy 162.609361 -149.967557)
			(xy 163.793819 -149.967557) (xy 163.793819 -149.913043) (xy 163.801578 -149.859084) (xy 163.816937 -149.806779)
			(xy 163.839584 -149.757192) (xy 163.869057 -149.711333) (xy 163.904758 -149.670135) (xy 163.945958 -149.634438)
			(xy 163.99182 -149.604968) (xy 164.041409 -149.582325) (xy 164.093716 -149.566971) (xy 164.147675 -149.559217)
			(xy 164.174932 -149.558756) (xy 165.165532 -149.558756) (xy 165.192779 -149.559316) (xy 165.246718 -149.567076)
			(xy 165.299004 -149.582432) (xy 165.348573 -149.605073) (xy 165.394415 -149.634537) (xy 165.435597 -149.670226)
			(xy 165.471282 -149.711411) (xy 165.500742 -149.757255) (xy 165.523379 -149.806826) (xy 165.538731 -149.859113)
			(xy 165.546486 -149.913053) (xy 165.546486 -149.967547) (xy 165.538731 -150.021487) (xy 165.523379 -150.073774)
			(xy 165.500742 -150.123345) (xy 165.471282 -150.169189) (xy 165.435597 -150.210374) (xy 165.394415 -150.246063)
			(xy 165.348573 -150.275527) (xy 165.299004 -150.298168) (xy 165.246718 -150.313524) (xy 165.192779 -150.321284)
			(xy 165.165532 -150.321772) (xy 164.174932 -150.321772) (xy 164.147675 -150.321383) (xy 164.093716 -150.313629)
			(xy 164.041409 -150.298275) (xy 163.99182 -150.275632) (xy 163.945958 -150.246162) (xy 163.904758 -150.210465)
			(xy 163.869057 -150.169267) (xy 163.839584 -150.123408) (xy 163.816937 -150.073821) (xy 163.801578 -150.021516)
			(xy 163.793819 -149.967557) (xy 162.609361 -149.967557) (xy 162.609361 -150.015255) (xy 162.601603 -150.06921)
			(xy 162.586245 -150.121512) (xy 162.5636 -150.171096) (xy 162.534128 -150.216953) (xy 162.498431 -150.258148)
			(xy 162.457233 -150.293843) (xy 162.411375 -150.323312) (xy 162.36179 -150.345954) (xy 162.309487 -150.361308)
			(xy 162.255531 -150.369063) (xy 162.228276 -150.369524) (xy 161.237676 -150.369524) (xy 161.210427 -150.369004)
			(xy 161.156484 -150.361245) (xy 161.104195 -150.345889) (xy 161.054623 -150.323247) (xy 161.008777 -150.293781)
			(xy 160.967592 -150.258091) (xy 160.931904 -150.216904) (xy 160.902441 -150.171056) (xy 160.879803 -150.121483)
			(xy 160.86445 -150.069192) (xy 160.856694 -150.015249) (xy 111.187365 -150.015249) (xy 111.192492 -150.020676)
			(xy 111.259142 -150.102876) (xy 111.319384 -150.18988) (xy 111.372873 -150.281191) (xy 111.419304 -150.376286)
			(xy 111.458409 -150.47462) (xy 111.489966 -150.575631) (xy 111.513793 -150.678738) (xy 111.529754 -150.783352)
			(xy 111.537758 -150.888874) (xy 111.538258 -150.941786) (xy 111.537758 -150.994698) (xy 111.529754 -151.10022)
			(xy 111.513793 -151.204834) (xy 111.489966 -151.307941) (xy 111.458409 -151.408952) (xy 111.419304 -151.507286)
			(xy 111.372873 -151.602381) (xy 111.319384 -151.693692) (xy 111.259142 -151.780696) (xy 111.192492 -151.862896)
			(xy 111.119817 -151.939819) (xy 111.041533 -152.011025) (xy 110.958087 -152.076107) (xy 110.869958 -152.134692)
			(xy 110.777651 -152.186444) (xy 110.681694 -152.231066) (xy 110.582637 -152.268304) (xy 110.481048 -152.297944)
			(xy 110.377508 -152.319815) (xy 110.272611 -152.333794) (xy 110.166957 -152.339799) (xy 110.061151 -152.337796)
			(xy 109.9558 -152.327797) (xy 109.851507 -152.309859) (xy 109.748869 -152.284085) (xy 109.648474 -152.250623)
			(xy 109.550897 -152.209663) (xy 109.456698 -152.161441) (xy 109.366415 -152.106234) (xy 109.280566 -152.044356)
			(xy 109.199643 -151.976163) (xy 109.124109 -151.902045) (xy 109.054397 -151.822427) (xy 108.990906 -151.737764)
			(xy 108.933999 -151.648543) (xy 108.884003 -151.555273) (xy 108.841205 -151.458489) (xy 108.805848 -151.358745)
			(xy 108.778137 -151.256613) (xy 108.758228 -151.152678) (xy 108.746238 -151.047535) (xy 108.742233 -150.941786)
			(xy 34.688915 -150.941786) (xy 34.755459 -151.05455) (xy 34.855186 -151.239273) (xy 34.947809 -151.427659)
			(xy 35.033193 -151.619434) (xy 35.111214 -151.814321) (xy 35.181759 -152.012037) (xy 35.244726 -152.212295)
			(xy 35.300023 -152.414805) (xy 35.34757 -152.619274) (xy 35.354948 -152.657556) (xy 115.368832 -152.657556)
			(xy 115.369254 -152.619267) (xy 115.375857 -152.542973) (xy 115.389002 -152.46753) (xy 115.40859 -152.393499)
			(xy 115.421156 -152.357328) (xy 115.423829 -152.348897) (xy 115.423815 -152.331221) (xy 115.421156 -152.322784)
			(xy 115.408624 -152.286603) (xy 115.389048 -152.212571) (xy 115.375898 -152.137132) (xy 115.36927 -152.060844)
			(xy 115.368832 -152.022556) (xy 115.369211 -151.981443) (xy 115.376803 -151.89957) (xy 115.391918 -151.818746)
			(xy 115.414428 -151.739662) (xy 115.44414 -151.662993) (xy 115.480801 -151.589393) (xy 115.524097 -151.51949)
			(xy 115.573659 -151.453881) (xy 115.629065 -151.393126) (xy 115.689841 -151.337743) (xy 115.755469 -151.288206)
			(xy 115.825388 -151.244936) (xy 115.899002 -151.208303) (xy 115.975683 -151.178621) (xy 116.054775 -151.156141)
			(xy 116.135605 -151.141056) (xy 116.217481 -151.133495) (xy 116.258594 -151.133048) (xy 116.29691 -151.133415)
			(xy 116.373264 -151.139947) (xy 116.448771 -151.153032) (xy 116.52287 -151.172572) (xy 116.559076 -151.185118)
			(xy 116.567392 -151.187704) (xy 116.584796 -151.187704) (xy 116.593112 -151.185118) (xy 116.629327 -151.172602)
			(xy 116.703427 -151.153078) (xy 116.778931 -151.139993) (xy 116.855279 -151.133443) (xy 116.893594 -151.133048)
			(xy 116.933808 -151.133478) (xy 117.01391 -151.140701) (xy 117.093031 -151.155132) (xy 117.170525 -151.176654)
			(xy 117.2083 -151.190452) (xy 117.217087 -151.193359) (xy 117.235581 -151.193359) (xy 117.244368 -151.190452)
			(xy 117.282145 -151.176662) (xy 117.359642 -151.155155) (xy 117.438762 -151.140723) (xy 117.518861 -151.133486)
			(xy 117.559074 -151.133048) (xy 117.59739 -151.133421) (xy 117.673744 -151.139951) (xy 117.74925 -151.153034)
			(xy 117.82335 -151.172573) (xy 117.859556 -151.185118) (xy 117.867872 -151.187704) (xy 117.885276 -151.187704)
			(xy 117.893592 -151.185118) (xy 117.929809 -151.172608) (xy 118.003908 -151.153082) (xy 118.079411 -151.139995)
			(xy 118.155759 -151.133444) (xy 118.194074 -151.133048) (xy 118.23239 -151.133421) (xy 118.308744 -151.139951)
			(xy 118.38425 -151.153034) (xy 118.45835 -151.172573) (xy 118.494556 -151.185118) (xy 118.502872 -151.187704)
			(xy 118.520276 -151.187704) (xy 118.528592 -151.185118) (xy 118.564809 -151.172608) (xy 118.638908 -151.153082)
			(xy 118.714411 -151.139995) (xy 118.790759 -151.133444) (xy 118.829074 -151.133048) (xy 118.86739 -151.133421)
			(xy 118.943744 -151.139951) (xy 119.01925 -151.153034) (xy 119.09335 -151.172573) (xy 119.129556 -151.185118)
			(xy 119.137872 -151.187704) (xy 119.155276 -151.187704) (xy 119.163592 -151.185118) (xy 119.199718 -151.172636)
			(xy 119.273629 -151.153143) (xy 119.348939 -151.140056) (xy 119.425093 -151.133472) (xy 119.463312 -151.133048)
			(xy 119.464074 -151.133048) (xy 119.505181 -151.133537) (xy 119.587043 -151.141119) (xy 119.667858 -151.156221)
			(xy 119.746934 -151.178714) (xy 119.823598 -151.208407) (xy 119.897196 -151.245045) (xy 119.9671 -151.288316)
			(xy 120.032714 -151.337852) (xy 120.093479 -151.39323) (xy 120.148875 -151.453978) (xy 120.198431 -151.519577)
			(xy 120.241724 -151.589468) (xy 120.278384 -151.663055) (xy 120.3081 -151.73971) (xy 120.330617 -151.818779)
			(xy 120.345743 -151.899589) (xy 120.35335 -151.98145) (xy 120.353836 -152.022556) (xy 120.353419 -152.060846)
			(xy 120.346814 -152.137139) (xy 120.333668 -152.212582) (xy 120.314078 -152.286613) (xy 120.301512 -152.322784)
			(xy 120.298884 -152.331226) (xy 120.29887 -152.348891) (xy 120.301512 -152.357328) (xy 120.314046 -152.393509)
			(xy 120.333622 -152.467541) (xy 120.346772 -152.542979) (xy 120.353399 -152.619268) (xy 120.353836 -152.657556)
			(xy 120.353306 -152.698665) (xy 120.345722 -152.780533) (xy 120.330616 -152.861351) (xy 120.308115 -152.940431)
			(xy 120.278413 -153.017096) (xy 120.241762 -153.090693) (xy 120.198476 -153.160594) (xy 120.148923 -153.226202)
			(xy 120.093528 -153.286957) (xy 120.032762 -153.34234) (xy 119.967144 -153.391879) (xy 119.897234 -153.435151)
			(xy 119.823629 -153.471786) (xy 119.746958 -153.501473) (xy 119.667874 -153.523957) (xy 119.587052 -153.539047)
			(xy 119.505183 -153.546614) (xy 119.464074 -153.547064) (xy 119.425757 -153.546706) (xy 119.349404 -153.540171)
			(xy 119.273897 -153.527084) (xy 119.199798 -153.507541) (xy 119.163592 -153.494994) (xy 119.155276 -153.492408)
			(xy 119.137872 -153.492408) (xy 119.129556 -153.494994) (xy 119.093344 -153.507519) (xy 119.019243 -153.527041)
			(xy 118.943738 -153.540123) (xy 118.867389 -153.546671) (xy 118.829074 -153.547064) (xy 118.790757 -153.546706)
			(xy 118.714404 -153.540171) (xy 118.638897 -153.527084) (xy 118.564798 -153.507541) (xy 118.528592 -153.494994)
			(xy 118.520276 -153.492408) (xy 118.502872 -153.492408) (xy 118.494556 -153.494994) (xy 118.458344 -153.507519)
			(xy 118.384243 -153.527041) (xy 118.308738 -153.540123) (xy 118.232389 -153.546671) (xy 118.194074 -153.547064)
			(xy 118.155757 -153.546706) (xy 118.079404 -153.540171) (xy 118.003897 -153.527084) (xy 117.929798 -153.507541)
			(xy 117.893592 -153.494994) (xy 117.885276 -153.492408) (xy 117.867872 -153.492408) (xy 117.859556 -153.494994)
			(xy 117.823344 -153.507519) (xy 117.749243 -153.527041) (xy 117.673738 -153.540123) (xy 117.597389 -153.546671)
			(xy 117.559074 -153.547064) (xy 117.51886 -153.546643) (xy 117.438758 -153.539418) (xy 117.359636 -153.524984)
			(xy 117.282143 -153.50346) (xy 117.244368 -153.48966) (xy 117.235581 -153.486753) (xy 117.217087 -153.486753)
			(xy 117.2083 -153.48966) (xy 117.170526 -153.50346) (xy 117.093029 -153.524965) (xy 117.013907 -153.539393)
			(xy 116.933807 -153.546627) (xy 116.893594 -153.547064) (xy 116.855277 -153.5467) (xy 116.778924 -153.540167)
			(xy 116.703417 -153.527082) (xy 116.629318 -153.50754) (xy 116.593112 -153.494994) (xy 116.584796 -153.492408)
			(xy 116.567392 -153.492408) (xy 116.559076 -153.494994) (xy 116.522953 -153.507485) (xy 116.449041 -153.526976)
			(xy 116.37373 -153.54006) (xy 116.297575 -153.546641) (xy 116.259356 -153.547064) (xy 116.258594 -153.547064)
			(xy 116.217487 -153.546593) (xy 116.135624 -153.539008) (xy 116.05481 -153.523904) (xy 115.975734 -153.501409)
			(xy 115.89907 -153.471714) (xy 115.825473 -153.435075) (xy 115.755569 -153.391802) (xy 115.689955 -153.342264)
			(xy 115.629192 -153.286885) (xy 115.573796 -153.226137) (xy 115.52424 -153.160537) (xy 115.480947 -153.090646)
			(xy 115.444287 -153.017059) (xy 115.414571 -152.940403) (xy 115.392053 -152.861333) (xy 115.376926 -152.780524)
			(xy 115.369318 -152.698663) (xy 115.368832 -152.657556) (xy 35.354948 -152.657556) (xy 35.387298 -152.825405)
			(xy 35.41915 -153.032898) (xy 35.44308 -153.241454) (xy 35.459052 -153.45077) (xy 35.467044 -153.660542)
			(xy 35.467544 -153.765504) (xy 35.467044 -153.870466) (xy 35.459052 -154.080238) (xy 35.44308 -154.289554)
			(xy 35.422918 -154.465274) (xy 127.823468 -154.465274) (xy 127.824038 -154.420505) (xy 127.833047 -154.33142)
			(xy 127.850949 -154.243689) (xy 127.877566 -154.158197) (xy 127.894588 -154.116786) (xy 127.89817 -154.1072)
			(xy 127.89816 -154.086753) (xy 127.894588 -154.077162) (xy 127.87754 -154.03576) (xy 127.850909 -153.95027)
			(xy 127.833008 -153.862535) (xy 127.824018 -153.773445) (xy 127.823468 -153.728674) (xy 127.824038 -153.683905)
			(xy 127.833047 -153.59482) (xy 127.850949 -153.507089) (xy 127.877566 -153.421597) (xy 127.894588 -153.380186)
			(xy 127.89817 -153.3706) (xy 127.89816 -153.350153) (xy 127.894588 -153.340562) (xy 127.87754 -153.29916)
			(xy 127.850909 -153.21367) (xy 127.833008 -153.125935) (xy 127.824018 -153.036845) (xy 127.823468 -152.992074)
			(xy 127.823874 -152.950958) (xy 127.831464 -152.869076) (xy 127.846576 -152.788245) (xy 127.869082 -152.709152)
			(xy 127.898791 -152.632473) (xy 127.935447 -152.558863) (xy 127.978739 -152.488949) (xy 128.028297 -152.423328)
			(xy 128.083699 -152.362559) (xy 128.144471 -152.307161) (xy 128.210095 -152.257607) (xy 128.280012 -152.21432)
			(xy 128.353625 -152.177668) (xy 128.430305 -152.147965) (xy 128.509399 -152.125463) (xy 128.590232 -152.110356)
			(xy 128.672114 -152.102771) (xy 128.71323 -152.102312) (xy 128.754841 -152.102773) (xy 128.837698 -152.110553)
			(xy 128.919467 -152.126031) (xy 128.999435 -152.149074) (xy 129.076903 -152.179479) (xy 129.151195 -152.216982)
			(xy 129.186686 -152.23871) (xy 129.195829 -152.243863) (xy 129.216542 -152.24708) (xy 129.236814 -152.241752)
			(xy 129.24536 -152.235662) (xy 129.278989 -152.209671) (xy 129.350383 -152.163546) (xy 129.425854 -152.124445)
			(xy 129.504712 -152.092724) (xy 129.586237 -152.068675) (xy 129.669685 -152.052515) (xy 129.754295 -152.044393)
			(xy 129.796794 -152.043892) (xy 129.837907 -152.044419) (xy 129.919782 -152.052005) (xy 130.000607 -152.067113)
			(xy 130.079694 -152.089613) (xy 130.156368 -152.119315) (xy 130.229974 -152.155965) (xy 130.299884 -152.19925)
			(xy 130.365503 -152.2488) (xy 130.42627 -152.304193) (xy 130.481667 -152.364957) (xy 130.531221 -152.430573)
			(xy 130.57451 -152.500481) (xy 130.611164 -152.574085) (xy 130.64087 -152.650756) (xy 130.663376 -152.729842)
			(xy 130.678488 -152.810667) (xy 130.686079 -152.892541) (xy 130.686556 -152.933654) (xy 130.685993 -152.978424)
			(xy 130.676983 -153.067509) (xy 130.659077 -153.15524) (xy 130.632459 -153.240731) (xy 130.615436 -153.282142)
			(xy 130.611899 -153.291741) (xy 130.611882 -153.312176) (xy 130.615436 -153.321766) (xy 130.63244 -153.363117)
			(xy 130.659051 -153.448479) (xy 130.676958 -153.536082) (xy 130.68598 -153.625039) (xy 130.686556 -153.669746)
			(xy 130.686556 -153.670762) (xy 130.686302 -153.682192) (xy 130.712781 -153.688138) (xy 130.765016 -153.702881)
			(xy 130.790696 -153.711656) (xy 130.798893 -153.71417) (xy 130.816027 -153.71417) (xy 130.824224 -153.711656)
			(xy 130.85944 -153.699695) (xy 130.931444 -153.681041) (xy 131.004765 -153.668532) (xy 131.07888 -153.662259)
			(xy 131.11607 -153.661872) (xy 131.153259 -153.662271) (xy 131.227372 -153.668558) (xy 131.300692 -153.681065)
			(xy 131.372698 -153.699703) (xy 131.407916 -153.711656) (xy 131.416113 -153.71417) (xy 131.433247 -153.71417)
			(xy 131.441444 -153.711656) (xy 131.476659 -153.699689) (xy 131.548662 -153.681037) (xy 131.621984 -153.66853)
			(xy 131.6961 -153.662258) (xy 131.73329 -153.661872) (xy 131.77523 -153.662267) (xy 131.858732 -153.670239)
			(xy 131.941097 -153.686113) (xy 132.02158 -153.709744) (xy 132.099453 -153.740919) (xy 132.165372 -153.774902)
			(xy 188.441847 -153.774902) (xy 188.445843 -153.565016) (xy 188.457828 -153.355434) (xy 188.477782 -153.14646)
			(xy 188.505678 -152.938398) (xy 188.541475 -152.731548) (xy 188.58512 -152.526211) (xy 188.636552 -152.322685)
			(xy 188.695694 -152.121264) (xy 188.762462 -151.922241) (xy 188.836758 -151.725904) (xy 188.918476 -151.532538)
			(xy 189.007495 -151.342423) (xy 189.103688 -151.155835) (xy 189.206915 -150.973044) (xy 189.317026 -150.794316)
			(xy 189.433861 -150.619909) (xy 189.557251 -150.450077) (xy 189.687018 -150.285065) (xy 189.822972 -150.125114)
			(xy 189.964918 -149.970454) (xy 190.112648 -149.82131) (xy 190.26595 -149.677899) (xy 190.4246 -149.540428)
			(xy 190.588369 -149.409096) (xy 190.757019 -149.284095) (xy 190.930305 -149.165604) (xy 191.107977 -149.053797)
			(xy 191.289777 -148.948835) (xy 191.475441 -148.85087) (xy 191.664699 -148.760045) (xy 191.857279 -148.676491)
			(xy 192.0529 -148.600328) (xy 192.251278 -148.531669) (xy 192.452127 -148.470612) (xy 192.655154 -148.417245)
			(xy 192.860067 -148.371647) (xy 193.066566 -148.333882) (xy 193.274353 -148.304007) (xy 193.483128 -148.282064)
			(xy 193.692586 -148.268085) (xy 193.902425 -148.26209) (xy 194.112339 -148.264089) (xy 194.322026 -148.274077)
			(xy 194.53118 -148.292042) (xy 194.739498 -148.317956) (xy 194.946679 -148.351781) (xy 195.152423 -148.39347)
			(xy 195.356429 -148.442962) (xy 195.558404 -148.500184) (xy 195.758054 -148.565054) (xy 195.955089 -148.637478)
			(xy 196.149225 -148.717351) (xy 196.340178 -148.804557) (xy 196.527674 -148.898969) (xy 196.711439 -149.000451)
			(xy 196.891207 -149.108855) (xy 197.066718 -149.224025) (xy 197.237717 -149.345793) (xy 197.403957 -149.473982)
			(xy 197.565196 -149.608408) (xy 197.7212 -149.748875) (xy 197.871743 -149.895179) (xy 198.016607 -150.047108)
			(xy 198.155582 -150.204442) (xy 198.288467 -150.366953) (xy 198.415068 -150.534406) (xy 198.535203 -150.706556)
			(xy 198.648697 -150.883156) (xy 198.755385 -151.063948) (xy 198.855112 -151.248671) (xy 198.947735 -151.437057)
			(xy 199.033119 -151.628832) (xy 199.11114 -151.823719) (xy 199.181685 -152.021435) (xy 199.244652 -152.221693)
			(xy 199.299949 -152.424203) (xy 199.347496 -152.628672) (xy 199.387224 -152.834803) (xy 199.419076 -153.042296)
			(xy 199.443006 -153.250852) (xy 199.458978 -153.460168) (xy 199.46697 -153.66994) (xy 199.467428 -153.766012)
			(xy 272.382243 -153.766012) (xy 272.386239 -153.556126) (xy 272.398224 -153.346544) (xy 272.418178 -153.13757)
			(xy 272.446074 -152.929508) (xy 272.481871 -152.722658) (xy 272.525516 -152.517321) (xy 272.576948 -152.313795)
			(xy 272.63609 -152.112374) (xy 272.702858 -151.913351) (xy 272.777154 -151.717014) (xy 272.858872 -151.523648)
			(xy 272.947891 -151.333533) (xy 273.044084 -151.146945) (xy 273.147311 -150.964154) (xy 273.257422 -150.785426)
			(xy 273.374257 -150.611019) (xy 273.497647 -150.441187) (xy 273.627414 -150.276175) (xy 273.763368 -150.116224)
			(xy 273.905314 -149.961564) (xy 274.053044 -149.81242) (xy 274.206346 -149.669009) (xy 274.364996 -149.531538)
			(xy 274.528765 -149.400206) (xy 274.697415 -149.275205) (xy 274.870701 -149.156714) (xy 275.048373 -149.044907)
			(xy 275.230173 -148.939945) (xy 275.415837 -148.84198) (xy 275.605095 -148.751155) (xy 275.797675 -148.667601)
			(xy 275.993296 -148.591438) (xy 276.191674 -148.522779) (xy 276.392523 -148.461722) (xy 276.59555 -148.408355)
			(xy 276.800463 -148.362757) (xy 277.006962 -148.324992) (xy 277.214749 -148.295117) (xy 277.423524 -148.273174)
			(xy 277.632982 -148.259195) (xy 277.842821 -148.2532) (xy 278.052735 -148.255199) (xy 278.262422 -148.265187)
			(xy 278.471576 -148.283152) (xy 278.679894 -148.309066) (xy 278.887075 -148.342891) (xy 279.092819 -148.38458)
			(xy 279.296825 -148.434072) (xy 279.4988 -148.491294) (xy 279.69845 -148.556164) (xy 279.895485 -148.628588)
			(xy 280.089621 -148.708461) (xy 280.280574 -148.795667) (xy 280.46807 -148.890079) (xy 280.651835 -148.991561)
			(xy 280.831603 -149.099965) (xy 281.007114 -149.215135) (xy 281.178113 -149.336903) (xy 281.344353 -149.465092)
			(xy 281.505592 -149.599518) (xy 281.661596 -149.739985) (xy 281.812139 -149.886289) (xy 281.957003 -150.038218)
			(xy 282.095978 -150.195552) (xy 282.228863 -150.358063) (xy 282.355464 -150.525516) (xy 282.475599 -150.697666)
			(xy 282.589093 -150.874266) (xy 282.695781 -151.055058) (xy 282.795508 -151.239781) (xy 282.888131 -151.428167)
			(xy 282.973515 -151.619942) (xy 283.051536 -151.814829) (xy 283.122081 -152.012545) (xy 283.185048 -152.212803)
			(xy 283.240345 -152.415313) (xy 283.287892 -152.619782) (xy 283.305746 -152.71242) (xy 358.186997 -152.71242)
			(xy 358.191002 -152.606671) (xy 358.202992 -152.501528) (xy 358.222901 -152.397593) (xy 358.250612 -152.295461)
			(xy 358.285969 -152.195717) (xy 358.328767 -152.098933) (xy 358.378763 -152.005663) (xy 358.43567 -151.916442)
			(xy 358.499161 -151.831779) (xy 358.568873 -151.752161) (xy 358.644407 -151.678043) (xy 358.72533 -151.60985)
			(xy 358.811179 -151.547972) (xy 358.901462 -151.492765) (xy 358.995661 -151.444543) (xy 359.093238 -151.403583)
			(xy 359.193633 -151.370121) (xy 359.296271 -151.344347) (xy 359.400564 -151.326409) (xy 359.505915 -151.31641)
			(xy 359.611721 -151.314407) (xy 359.717375 -151.320412) (xy 359.822272 -151.334391) (xy 359.925812 -151.356262)
			(xy 360.027401 -151.385902) (xy 360.126458 -151.42314) (xy 360.222415 -151.467762) (xy 360.314722 -151.519514)
			(xy 360.402851 -151.578099) (xy 360.486297 -151.643181) (xy 360.564581 -151.714387) (xy 360.637256 -151.79131)
			(xy 360.703906 -151.87351) (xy 360.764148 -151.960514) (xy 360.817637 -152.051825) (xy 360.864068 -152.14692)
			(xy 360.903173 -152.245254) (xy 360.93473 -152.346265) (xy 360.958557 -152.449372) (xy 360.974518 -152.553986)
			(xy 360.982522 -152.659508) (xy 360.983022 -152.71242) (xy 360.982522 -152.765332) (xy 360.974518 -152.870854)
			(xy 360.958557 -152.975468) (xy 360.93473 -153.078575) (xy 360.903173 -153.179586) (xy 360.864068 -153.27792)
			(xy 360.817637 -153.373015) (xy 360.764148 -153.464326) (xy 360.703906 -153.55133) (xy 360.637256 -153.63353)
			(xy 360.564581 -153.710453) (xy 360.486297 -153.781659) (xy 360.402851 -153.846741) (xy 360.314722 -153.905326)
			(xy 360.222415 -153.957078) (xy 360.126458 -154.0017) (xy 360.027401 -154.038938) (xy 359.925812 -154.068578)
			(xy 359.822272 -154.090449) (xy 359.717375 -154.104428) (xy 359.611721 -154.110433) (xy 359.505915 -154.10843)
			(xy 359.400564 -154.098431) (xy 359.296271 -154.080493) (xy 359.193633 -154.054719) (xy 359.093238 -154.021257)
			(xy 358.995661 -153.980297) (xy 358.901462 -153.932075) (xy 358.811179 -153.876868) (xy 358.72533 -153.81499)
			(xy 358.644407 -153.746797) (xy 358.568873 -153.672679) (xy 358.499161 -153.593061) (xy 358.43567 -153.508398)
			(xy 358.378763 -153.419177) (xy 358.328767 -153.325907) (xy 358.285969 -153.229123) (xy 358.250612 -153.129379)
			(xy 358.222901 -153.027247) (xy 358.202992 -152.923312) (xy 358.191002 -152.818169) (xy 358.186997 -152.71242)
			(xy 283.305746 -152.71242) (xy 283.32762 -152.825913) (xy 283.359472 -153.033406) (xy 283.383402 -153.241962)
			(xy 283.399374 -153.451278) (xy 283.407366 -153.66105) (xy 283.407866 -153.766012) (xy 283.407366 -153.870974)
			(xy 283.399374 -154.080746) (xy 283.383402 -154.290062) (xy 283.359472 -154.498618) (xy 283.32762 -154.706111)
			(xy 283.287892 -154.912242) (xy 283.240345 -155.116711) (xy 283.185048 -155.319221) (xy 283.122081 -155.519479)
			(xy 283.051536 -155.717195) (xy 282.973515 -155.912082) (xy 282.888131 -156.103857) (xy 282.795508 -156.292243)
			(xy 282.695781 -156.476966) (xy 282.589093 -156.657758) (xy 282.475599 -156.834358) (xy 282.355464 -157.006508)
			(xy 282.228863 -157.173961) (xy 282.095978 -157.336472) (xy 281.957003 -157.493806) (xy 281.812139 -157.645735)
			(xy 281.661596 -157.792039) (xy 281.505592 -157.932506) (xy 281.344353 -158.066932) (xy 281.178113 -158.195121)
			(xy 281.007114 -158.316889) (xy 280.831603 -158.432059) (xy 280.651835 -158.540463) (xy 280.46807 -158.641945)
			(xy 280.280574 -158.736357) (xy 280.089621 -158.823563) (xy 279.895485 -158.903436) (xy 279.69845 -158.97586)
			(xy 279.4988 -159.04073) (xy 279.382794 -159.073596) (xy 343.127076 -159.073596) (xy 343.127653 -159.028827)
			(xy 343.136659 -158.939742) (xy 343.15456 -158.852011) (xy 343.181175 -158.766519) (xy 343.198196 -158.725108)
			(xy 343.201765 -158.715518) (xy 343.201764 -158.695074) (xy 343.198196 -158.685484) (xy 343.181156 -158.644079)
			(xy 343.154522 -158.55859) (xy 343.136619 -158.470856) (xy 343.127627 -158.381767) (xy 343.127076 -158.336996)
			(xy 343.127653 -158.292227) (xy 343.136659 -158.203142) (xy 343.15456 -158.115411) (xy 343.181175 -158.029919)
			(xy 343.198196 -157.988508) (xy 343.201765 -157.978918) (xy 343.201764 -157.958474) (xy 343.198196 -157.948884)
			(xy 343.181156 -157.907479) (xy 343.154522 -157.82199) (xy 343.136619 -157.734256) (xy 343.127627 -157.645167)
			(xy 343.127076 -157.600396) (xy 343.127549 -157.559286) (xy 343.135137 -157.477416) (xy 343.150247 -157.396596)
			(xy 343.172752 -157.317516) (xy 343.202459 -157.240849) (xy 343.239114 -157.167252) (xy 343.282404 -157.097351)
			(xy 343.33196 -157.031743) (xy 343.387359 -156.970988) (xy 343.448129 -156.915605) (xy 343.51375 -156.866067)
			(xy 343.583663 -156.822796) (xy 343.657271 -156.786161) (xy 343.733945 -156.756475) (xy 343.813032 -156.733992)
			(xy 343.893856 -156.718903) (xy 343.975728 -156.711337) (xy 344.016838 -156.710888) (xy 344.058442 -156.711362)
			(xy 344.14129 -156.719094) (xy 344.223055 -156.734524) (xy 344.303022 -156.757517) (xy 344.380495 -156.787874)
			(xy 344.454797 -156.825328) (xy 344.490294 -156.847032) (xy 344.499434 -156.852189) (xy 344.520149 -156.855402)
			(xy 344.540422 -156.850073) (xy 344.548968 -156.843984) (xy 344.582592 -156.818029) (xy 344.653971 -156.771973)
			(xy 344.729414 -156.73293) (xy 344.808235 -156.701255) (xy 344.889716 -156.677237) (xy 344.973116 -156.661094)
			(xy 345.057674 -156.652974) (xy 345.100148 -156.652468) (xy 345.100402 -156.652468) (xy 345.14151 -156.652911)
			(xy 345.223374 -156.660496) (xy 345.30419 -156.6756) (xy 345.383268 -156.698096) (xy 345.459933 -156.727791)
			(xy 345.533532 -156.764433) (xy 345.603437 -156.807707) (xy 345.669051 -156.857246) (xy 345.729816 -156.912627)
			(xy 345.785212 -156.973378) (xy 345.806812 -157.001972) (xy 386.403596 -157.001972) (xy 386.40399 -156.963682)
			(xy 386.410601 -156.887387) (xy 386.423753 -156.811945) (xy 386.44335 -156.737915) (xy 386.45592 -156.701744)
			(xy 386.458586 -156.693311) (xy 386.458577 -156.675637) (xy 386.45592 -156.6672) (xy 386.443367 -156.631026)
			(xy 386.423796 -156.556991) (xy 386.410652 -156.481551) (xy 386.40403 -156.40526) (xy 386.403596 -156.366972)
			(xy 386.404015 -156.328179) (xy 386.410791 -156.25089) (xy 386.424264 -156.174482) (xy 386.44433 -156.099536)
			(xy 386.45719 -156.062934) (xy 386.459858 -156.054502) (xy 386.459846 -156.036827) (xy 386.45719 -156.02839)
			(xy 386.444324 -155.991789) (xy 386.424239 -155.916847) (xy 386.410766 -155.840438) (xy 386.404005 -155.763146)
			(xy 386.403596 -155.724352) (xy 386.404014 -155.686062) (xy 386.410618 -155.609769) (xy 386.423763 -155.534326)
			(xy 386.443354 -155.460295) (xy 386.45592 -155.424124) (xy 386.458596 -155.415693) (xy 386.45858 -155.398017)
			(xy 386.45592 -155.38958) (xy 386.443389 -155.353398) (xy 386.423812 -155.279367) (xy 386.410662 -155.203928)
			(xy 386.404034 -155.12764) (xy 386.403596 -155.089352) (xy 386.40407 -155.049438) (xy 386.411294 -154.969935)
			(xy 386.425601 -154.891398) (xy 386.446874 -154.814455) (xy 386.460492 -154.776932) (xy 386.463345 -154.768269)
			(xy 386.463329 -154.750041) (xy 386.460492 -154.741372) (xy 386.44684 -154.70386) (xy 386.425547 -154.626919)
			(xy 386.411244 -154.548377) (xy 386.404048 -154.468869) (xy 386.403596 -154.428952) (xy 386.404014 -154.390662)
			(xy 386.410618 -154.314369) (xy 386.423763 -154.238926) (xy 386.443354 -154.164895) (xy 386.45592 -154.128724)
			(xy 386.458596 -154.120293) (xy 386.45858 -154.102617) (xy 386.45592 -154.09418) (xy 386.443389 -154.057998)
			(xy 386.423812 -153.983967) (xy 386.410662 -153.908528) (xy 386.404034 -153.83224) (xy 386.403596 -153.793952)
			(xy 386.404007 -153.75284) (xy 386.411599 -153.670969) (xy 386.426714 -153.590147) (xy 386.449223 -153.511065)
			(xy 386.478934 -153.434397) (xy 386.515593 -153.360799) (xy 386.558887 -153.290897) (xy 386.608448 -153.225289)
			(xy 386.663851 -153.164535) (xy 386.724625 -153.109152) (xy 386.79025 -153.059614) (xy 386.860166 -153.016344)
			(xy 386.933777 -152.97971) (xy 387.010455 -152.950026) (xy 387.089545 -152.927544) (xy 387.170372 -152.912457)
			(xy 387.252246 -152.904893) (xy 387.293358 -152.904444) (xy 387.331674 -152.904822) (xy 387.408027 -152.91135)
			(xy 387.483534 -152.924432) (xy 387.557634 -152.94397) (xy 387.59384 -152.956514) (xy 387.602156 -152.9591)
			(xy 387.61956 -152.9591) (xy 387.627876 -152.956514) (xy 387.663994 -152.944008) (xy 387.737908 -152.924522)
			(xy 387.81322 -152.911442) (xy 387.889376 -152.904865) (xy 387.927596 -152.904444) (xy 387.928358 -152.904444)
			(xy 387.969464 -152.904953) (xy 388.051326 -152.912533) (xy 388.13214 -152.927634) (xy 388.211216 -152.950125)
			(xy 388.28788 -152.979816) (xy 388.361478 -153.016453) (xy 388.431382 -153.059723) (xy 388.496996 -153.109258)
			(xy 388.55776 -153.164634) (xy 388.613157 -153.225381) (xy 388.662713 -153.290979) (xy 388.706006 -153.360869)
			(xy 388.742667 -153.434454) (xy 388.772383 -153.511109) (xy 388.7949 -153.590177) (xy 388.810027 -153.670986)
			(xy 388.817634 -153.752846) (xy 388.817889 -153.774394) (xy 436.382169 -153.774394) (xy 436.386165 -153.564508)
			(xy 436.39815 -153.354926) (xy 436.418104 -153.145952) (xy 436.446 -152.93789) (xy 436.481797 -152.73104)
			(xy 436.525442 -152.525703) (xy 436.576874 -152.322177) (xy 436.636016 -152.120756) (xy 436.702784 -151.921733)
			(xy 436.77708 -151.725396) (xy 436.858798 -151.53203) (xy 436.947817 -151.341915) (xy 437.04401 -151.155327)
			(xy 437.147237 -150.972536) (xy 437.257348 -150.793808) (xy 437.374183 -150.619401) (xy 437.497573 -150.449569)
			(xy 437.62734 -150.284557) (xy 437.763294 -150.124606) (xy 437.90524 -149.969946) (xy 438.05297 -149.820802)
			(xy 438.206272 -149.677391) (xy 438.364922 -149.53992) (xy 438.528691 -149.408588) (xy 438.697341 -149.283587)
			(xy 438.870627 -149.165096) (xy 439.048299 -149.053289) (xy 439.230099 -148.948327) (xy 439.415763 -148.850362)
			(xy 439.605021 -148.759537) (xy 439.797601 -148.675983) (xy 439.993222 -148.59982) (xy 440.1916 -148.531161)
			(xy 440.392449 -148.470104) (xy 440.595476 -148.416737) (xy 440.800389 -148.371139) (xy 441.006888 -148.333374)
			(xy 441.214675 -148.303499) (xy 441.42345 -148.281556) (xy 441.632908 -148.267577) (xy 441.842747 -148.261582)
			(xy 442.052661 -148.263581) (xy 442.262348 -148.273569) (xy 442.471502 -148.291534) (xy 442.67982 -148.317448)
			(xy 442.887001 -148.351273) (xy 443.092745 -148.392962) (xy 443.296751 -148.442454) (xy 443.498726 -148.499676)
			(xy 443.698376 -148.564546) (xy 443.895411 -148.63697) (xy 444.089547 -148.716843) (xy 444.2805 -148.804049)
			(xy 444.467996 -148.898461) (xy 444.651761 -148.999943) (xy 444.831529 -149.108347) (xy 445.00704 -149.223517)
			(xy 445.178039 -149.345285) (xy 445.344279 -149.473474) (xy 445.505518 -149.6079) (xy 445.661522 -149.748367)
			(xy 445.812065 -149.894671) (xy 445.956929 -150.0466) (xy 446.095904 -150.203934) (xy 446.228789 -150.366445)
			(xy 446.35539 -150.533898) (xy 446.475525 -150.706048) (xy 446.589019 -150.882648) (xy 446.695707 -151.06344)
			(xy 446.795434 -151.248163) (xy 446.888057 -151.436549) (xy 446.973441 -151.628324) (xy 447.051462 -151.823211)
			(xy 447.122007 -152.020927) (xy 447.184974 -152.221185) (xy 447.240271 -152.423695) (xy 447.287818 -152.628164)
			(xy 447.327546 -152.834295) (xy 447.359398 -153.041788) (xy 447.383328 -153.250344) (xy 447.3993 -153.45966)
			(xy 447.407292 -153.669432) (xy 447.407792 -153.774394) (xy 447.407292 -153.879356) (xy 447.3993 -154.089128)
			(xy 447.383328 -154.298444) (xy 447.359398 -154.507) (xy 447.327546 -154.714493) (xy 447.287818 -154.920624)
			(xy 447.240271 -155.125093) (xy 447.184974 -155.327603) (xy 447.122007 -155.527861) (xy 447.051462 -155.725577)
			(xy 446.973441 -155.920464) (xy 446.888057 -156.112239) (xy 446.795434 -156.300625) (xy 446.695707 -156.485348)
			(xy 446.589019 -156.66614) (xy 446.475525 -156.84274) (xy 446.35539 -157.01489) (xy 446.228789 -157.182343)
			(xy 446.095904 -157.344854) (xy 445.956929 -157.502188) (xy 445.812065 -157.654117) (xy 445.661522 -157.800421)
			(xy 445.505518 -157.940888) (xy 445.344279 -158.075314) (xy 445.178039 -158.203503) (xy 445.00704 -158.325271)
			(xy 444.831529 -158.440441) (xy 444.651761 -158.548845) (xy 444.467996 -158.650327) (xy 444.2805 -158.744739)
			(xy 444.089547 -158.831945) (xy 443.895411 -158.911818) (xy 443.698376 -158.984242) (xy 443.498726 -159.049112)
			(xy 443.296751 -159.106334) (xy 443.092745 -159.155826) (xy 442.887001 -159.197515) (xy 442.67982 -159.23134)
			(xy 442.471502 -159.257254) (xy 442.262348 -159.275219) (xy 442.052661 -159.285207) (xy 441.842747 -159.287206)
			(xy 441.632908 -159.281211) (xy 441.42345 -159.267232) (xy 441.214675 -159.245289) (xy 441.006888 -159.215414)
			(xy 440.800389 -159.177649) (xy 440.595476 -159.132051) (xy 440.392449 -159.078684) (xy 440.1916 -159.017627)
			(xy 439.993222 -158.948968) (xy 439.797601 -158.872805) (xy 439.605021 -158.789251) (xy 439.415763 -158.698426)
			(xy 439.230099 -158.600461) (xy 439.048299 -158.495499) (xy 438.870627 -158.383692) (xy 438.697341 -158.265201)
			(xy 438.528691 -158.1402) (xy 438.364922 -158.008868) (xy 438.206272 -157.871397) (xy 438.05297 -157.727986)
			(xy 437.90524 -157.578842) (xy 437.763294 -157.424182) (xy 437.62734 -157.264231) (xy 437.497573 -157.099219)
			(xy 437.374183 -156.929387) (xy 437.257348 -156.75498) (xy 437.147237 -156.576252) (xy 437.04401 -156.393461)
			(xy 436.947817 -156.206873) (xy 436.858798 -156.016758) (xy 436.77708 -155.823392) (xy 436.702784 -155.627055)
			(xy 436.636016 -155.428032) (xy 436.576874 -155.226611) (xy 436.525442 -155.023085) (xy 436.481797 -154.817748)
			(xy 436.446 -154.610898) (xy 436.418104 -154.402836) (xy 436.39815 -154.193862) (xy 436.386165 -153.98428)
			(xy 436.382169 -153.774394) (xy 388.817889 -153.774394) (xy 388.81812 -153.793952) (xy 388.817702 -153.832242)
			(xy 388.811098 -153.908535) (xy 388.797953 -153.983978) (xy 388.778362 -154.058009) (xy 388.765796 -154.09418)
			(xy 388.763168 -154.102623) (xy 388.763152 -154.120288) (xy 388.765796 -154.128724) (xy 388.778328 -154.164905)
			(xy 388.797905 -154.238937) (xy 388.811055 -154.314375) (xy 388.817683 -154.390664) (xy 388.81812 -154.428952)
			(xy 388.817646 -154.468866) (xy 388.810422 -154.548369) (xy 388.796115 -154.626906) (xy 388.774842 -154.703849)
			(xy 388.761224 -154.741372) (xy 388.758419 -154.750047) (xy 388.758403 -154.768264) (xy 388.761224 -154.776932)
			(xy 388.774878 -154.814443) (xy 388.79617 -154.891385) (xy 388.810472 -154.969927) (xy 388.817668 -155.049435)
			(xy 388.81812 -155.089352) (xy 388.817702 -155.127642) (xy 388.811098 -155.203935) (xy 388.797953 -155.279378)
			(xy 388.778362 -155.353409) (xy 388.765796 -155.38958) (xy 388.763168 -155.398023) (xy 388.763152 -155.415688)
			(xy 388.765796 -155.424124) (xy 388.778328 -155.460305) (xy 388.797905 -155.534337) (xy 388.811055 -155.609775)
			(xy 388.817683 -155.686064) (xy 388.81812 -155.724352) (xy 388.817677 -155.763144) (xy 388.810908 -155.840433)
			(xy 388.797442 -155.916841) (xy 388.777382 -155.991787) (xy 388.764526 -156.02839) (xy 388.761895 -156.036832)
			(xy 388.761883 -156.054497) (xy 388.764526 -156.062934) (xy 388.7774 -156.099532) (xy 388.797482 -156.174476)
			(xy 388.810953 -156.250885) (xy 388.817712 -156.328178) (xy 388.81812 -156.366972) (xy 388.817708 -156.405262)
			(xy 388.811103 -156.481556) (xy 388.797955 -156.556998) (xy 388.778363 -156.631029) (xy 388.765796 -156.6672)
			(xy 388.763157 -156.67564) (xy 388.763148 -156.693308) (xy 388.765796 -156.701744) (xy 388.778334 -156.737923)
			(xy 388.797909 -156.811956) (xy 388.811058 -156.887395) (xy 388.817683 -156.963684) (xy 388.81812 -157.001972)
			(xy 388.817621 -157.043082) (xy 388.810036 -157.124951) (xy 388.794928 -157.20577) (xy 388.772425 -157.284851)
			(xy 388.742721 -157.361517) (xy 388.706068 -157.435115) (xy 388.66278 -157.505016) (xy 388.613226 -157.570624)
			(xy 388.557828 -157.631379) (xy 388.49706 -157.686762) (xy 388.43144 -157.736301) (xy 388.361528 -157.779573)
			(xy 388.287921 -157.816208) (xy 388.211248 -157.845893) (xy 388.132162 -157.868377) (xy 388.051339 -157.883465)
			(xy 387.969468 -157.891031) (xy 387.928358 -157.89148) (xy 387.890041 -157.891126) (xy 387.813688 -157.88459)
			(xy 387.738181 -157.871501) (xy 387.664082 -157.851957) (xy 387.627876 -157.83941) (xy 387.61956 -157.836824)
			(xy 387.602156 -157.836824) (xy 387.59384 -157.83941) (xy 387.557721 -157.851912) (xy 387.483807 -157.871399)
			(xy 387.408495 -157.88448) (xy 387.33234 -157.891059) (xy 387.29412 -157.89148) (xy 387.293358 -157.89148)
			(xy 387.252251 -157.891028) (xy 387.170388 -157.88344) (xy 387.089574 -157.868332) (xy 387.010498 -157.845835)
			(xy 386.933835 -157.816138) (xy 386.860238 -157.779497) (xy 386.790335 -157.736222) (xy 386.724722 -157.686684)
			(xy 386.663959 -157.631304) (xy 386.608563 -157.570555) (xy 386.559008 -157.504955) (xy 386.515715 -157.435063)
			(xy 386.479055 -157.361475) (xy 386.449338 -157.28482) (xy 386.42682 -157.20575) (xy 386.411692 -157.12494)
			(xy 386.404083 -157.043079) (xy 386.403596 -157.001972) (xy 345.806812 -157.001972) (xy 345.834767 -157.03898)
			(xy 345.878059 -157.108874) (xy 345.914719 -157.182463) (xy 345.944433 -157.259121) (xy 345.966949 -157.338193)
			(xy 345.982074 -157.419006) (xy 345.989679 -157.500868) (xy 345.990164 -157.541976) (xy 345.989609 -157.586746)
			(xy 345.980596 -157.675831) (xy 345.962689 -157.763562) (xy 345.936068 -157.849053) (xy 345.919044 -157.890464)
			(xy 345.915494 -157.900059) (xy 345.915485 -157.920497) (xy 345.919044 -157.930088) (xy 345.936056 -157.971436)
			(xy 345.962665 -158.056799) (xy 345.980569 -158.144403) (xy 345.989589 -158.233361) (xy 345.990164 -158.278068)
			(xy 345.990164 -158.279084) (xy 345.98991 -158.290514) (xy 346.016389 -158.296459) (xy 346.068624 -158.311202)
			(xy 346.094304 -158.319978) (xy 346.102501 -158.322492) (xy 346.119635 -158.322492) (xy 346.127832 -158.319978)
			(xy 346.163048 -158.308033) (xy 346.235059 -158.289446) (xy 346.308381 -158.277006) (xy 346.382492 -158.2708)
			(xy 346.419678 -158.270448) (xy 346.456862 -158.27082) (xy 346.53097 -158.277041) (xy 346.60429 -158.289483)
			(xy 346.676301 -158.308056) (xy 346.711524 -158.319978) (xy 346.719721 -158.322492) (xy 346.736855 -158.322492)
			(xy 346.745052 -158.319978) (xy 346.780146 -158.308069) (xy 346.851906 -158.289524) (xy 346.924971 -158.277084)
			(xy 346.998824 -158.270837) (xy 347.035882 -158.270448) (xy 347.036898 -158.270448) (xy 347.078822 -158.270999)
			(xy 347.162292 -158.278969) (xy 347.244625 -158.294837) (xy 347.325078 -158.31846) (xy 347.40292 -158.349624)
			(xy 347.477448 -158.388045) (xy 347.547987 -158.433377) (xy 347.613896 -158.485209) (xy 347.674581 -158.543071)
			(xy 347.72949 -158.60644) (xy 347.778127 -158.674741) (xy 347.820052 -158.747357) (xy 347.854884 -158.823628)
			(xy 347.882308 -158.902865) (xy 347.902076 -158.984351) (xy 347.914009 -159.067346) (xy 347.917999 -159.1511)
			(xy 347.914009 -159.234854) (xy 347.902076 -159.317849) (xy 347.882308 -159.399335) (xy 347.854884 -159.478572)
			(xy 347.820052 -159.554843) (xy 347.778127 -159.627459) (xy 347.72949 -159.69576) (xy 347.674581 -159.759129)
			(xy 347.613896 -159.816991) (xy 347.547987 -159.868823) (xy 347.477448 -159.914155) (xy 347.40292 -159.952576)
			(xy 347.325078 -159.98374) (xy 347.244625 -160.007363) (xy 347.162292 -160.023231) (xy 347.078822 -160.031201)
			(xy 347.036898 -160.031684) (xy 347.035882 -160.031684) (xy 346.998825 -160.031285) (xy 346.924976 -160.025019)
			(xy 346.851913 -160.012575) (xy 346.780153 -159.994041) (xy 346.745052 -159.982154) (xy 346.736855 -159.97964)
			(xy 346.719721 -159.97964) (xy 346.711524 -159.982154) (xy 346.684116 -159.991499) (xy 346.628318 -160.007008)
			(xy 346.600018 -160.013142) (xy 346.590235 -160.015622) (xy 346.573598 -160.027019) (xy 346.562626 -160.04394)
			(xy 346.560394 -160.053782) (xy 346.550929 -160.102889) (xy 346.522417 -160.19875) (xy 346.503498 -160.245044)
			(xy 346.499892 -160.254619) (xy 346.499745 -160.275056) (xy 346.503244 -160.284668) (xy 346.520278 -160.326041)
			(xy 346.546893 -160.41147) (xy 346.564794 -160.499139) (xy 346.5738 -160.588163) (xy 346.574364 -160.632902)
			(xy 346.574364 -160.633156) (xy 346.57386 -160.675504) (xy 346.565809 -160.759818) (xy 346.54978 -160.842984)
			(xy 346.525919 -160.924251) (xy 346.49444 -161.002881) (xy 346.455629 -161.078162) (xy 346.409839 -161.149414)
			(xy 346.357483 -161.21599) (xy 346.299035 -161.277288) (xy 346.235025 -161.332753) (xy 346.166033 -161.381882)
			(xy 346.092683 -161.424231) (xy 346.01564 -161.459415) (xy 345.935601 -161.487117) (xy 345.853292 -161.507085)
			(xy 345.769457 -161.519138) (xy 345.684856 -161.523169) (xy 345.600255 -161.519138) (xy 345.51642 -161.507085)
			(xy 345.434111 -161.487117) (xy 345.354072 -161.459415) (xy 345.277029 -161.424231) (xy 345.203679 -161.381882)
			(xy 345.134687 -161.332753) (xy 345.070677 -161.277288) (xy 345.012229 -161.21599) (xy 344.959873 -161.149414)
			(xy 344.914083 -161.078162) (xy 344.875272 -161.002881) (xy 344.843793 -160.924251) (xy 344.819932 -160.842984)
			(xy 344.803903 -160.759818) (xy 344.795852 -160.675504) (xy 344.795348 -160.633156) (xy 344.795348 -160.632902)
			(xy 344.795938 -160.588164) (xy 344.804948 -160.499143) (xy 344.822847 -160.411476) (xy 344.849453 -160.326048)
			(xy 344.866468 -160.284668) (xy 344.870056 -160.275084) (xy 344.87004 -160.254635) (xy 344.866468 -160.245044)
			(xy 344.849433 -160.203637) (xy 344.822801 -160.118148) (xy 344.804897 -160.030415) (xy 344.795901 -159.941327)
			(xy 344.795348 -159.896556) (xy 344.795678 -159.859467) (xy 344.801776 -159.78554) (xy 344.814009 -159.712377)
			(xy 344.82278 -159.676338) (xy 344.824538 -159.668008) (xy 344.823098 -159.651057) (xy 344.816174 -159.635517)
			(xy 344.810588 -159.629094) (xy 344.770202 -159.586168) (xy 344.758264 -159.588708) (xy 344.749364 -159.591023)
			(xy 344.733871 -159.600904) (xy 344.728038 -159.608012) (xy 344.702891 -159.640664) (xy 344.647483 -159.701681)
			(xy 344.586669 -159.757312) (xy 344.520971 -159.807081) (xy 344.450952 -159.850561) (xy 344.377213 -159.887379)
			(xy 344.300384 -159.917221) (xy 344.221125 -159.93983) (xy 344.140115 -159.955012) (xy 344.058048 -159.962637)
			(xy 344.016838 -159.963104) (xy 343.975733 -159.962551) (xy 343.893874 -159.954971) (xy 343.813062 -159.939871)
			(xy 343.733989 -159.917381) (xy 343.657327 -159.887692) (xy 343.583731 -159.851057) (xy 343.513829 -159.807789)
			(xy 343.448216 -159.758257) (xy 343.387452 -159.702884) (xy 343.332056 -159.642141) (xy 343.2825 -159.576547)
			(xy 343.239206 -159.506661) (xy 343.202543 -159.433078) (xy 343.172826 -159.356428) (xy 343.150306 -159.277363)
			(xy 343.135175 -159.196557) (xy 343.127564 -159.114701) (xy 343.127076 -159.073596) (xy 279.382794 -159.073596)
			(xy 279.296825 -159.097952) (xy 279.092819 -159.147444) (xy 278.887075 -159.189133) (xy 278.679894 -159.222958)
			(xy 278.471576 -159.248872) (xy 278.262422 -159.266837) (xy 278.052735 -159.276825) (xy 277.842821 -159.278824)
			(xy 277.632982 -159.272829) (xy 277.423524 -159.25885) (xy 277.214749 -159.236907) (xy 277.006962 -159.207032)
			(xy 276.800463 -159.169267) (xy 276.59555 -159.123669) (xy 276.392523 -159.070302) (xy 276.191674 -159.009245)
			(xy 275.993296 -158.940586) (xy 275.797675 -158.864423) (xy 275.605095 -158.780869) (xy 275.415837 -158.690044)
			(xy 275.230173 -158.592079) (xy 275.048373 -158.487117) (xy 274.870701 -158.37531) (xy 274.697415 -158.256819)
			(xy 274.528765 -158.131818) (xy 274.364996 -158.000486) (xy 274.206346 -157.863015) (xy 274.053044 -157.719604)
			(xy 273.905314 -157.57046) (xy 273.763368 -157.4158) (xy 273.627414 -157.255849) (xy 273.497647 -157.090837)
			(xy 273.374257 -156.921005) (xy 273.257422 -156.746598) (xy 273.147311 -156.56787) (xy 273.044084 -156.385079)
			(xy 272.947891 -156.198491) (xy 272.858872 -156.008376) (xy 272.777154 -155.81501) (xy 272.702858 -155.618673)
			(xy 272.63609 -155.41965) (xy 272.576948 -155.218229) (xy 272.525516 -155.014703) (xy 272.481871 -154.809366)
			(xy 272.446074 -154.602516) (xy 272.418178 -154.394454) (xy 272.398224 -154.18548) (xy 272.386239 -153.975898)
			(xy 272.382243 -153.766012) (xy 199.467428 -153.766012) (xy 199.46747 -153.774902) (xy 199.46697 -153.879864)
			(xy 199.458978 -154.089636) (xy 199.443006 -154.298952) (xy 199.419076 -154.507508) (xy 199.387224 -154.715001)
			(xy 199.347496 -154.921132) (xy 199.299949 -155.125601) (xy 199.244652 -155.328111) (xy 199.181685 -155.528369)
			(xy 199.11114 -155.726085) (xy 199.033119 -155.920972) (xy 198.947735 -156.112747) (xy 198.855112 -156.301133)
			(xy 198.755385 -156.485856) (xy 198.648697 -156.666648) (xy 198.535203 -156.843248) (xy 198.415068 -157.015398)
			(xy 198.288467 -157.182851) (xy 198.155582 -157.345362) (xy 198.016607 -157.502696) (xy 197.871743 -157.654625)
			(xy 197.7212 -157.800929) (xy 197.565196 -157.941396) (xy 197.403957 -158.075822) (xy 197.237717 -158.204011)
			(xy 197.066718 -158.325779) (xy 196.891207 -158.440949) (xy 196.711439 -158.549353) (xy 196.527674 -158.650835)
			(xy 196.340178 -158.745247) (xy 196.149225 -158.832453) (xy 195.955089 -158.912326) (xy 195.758054 -158.98475)
			(xy 195.558404 -159.04962) (xy 195.356429 -159.106842) (xy 195.152423 -159.156334) (xy 194.946679 -159.198023)
			(xy 194.739498 -159.231848) (xy 194.53118 -159.257762) (xy 194.322026 -159.275727) (xy 194.112339 -159.285715)
			(xy 193.902425 -159.287714) (xy 193.692586 -159.281719) (xy 193.483128 -159.26774) (xy 193.274353 -159.245797)
			(xy 193.066566 -159.215922) (xy 192.860067 -159.178157) (xy 192.655154 -159.132559) (xy 192.452127 -159.079192)
			(xy 192.251278 -159.018135) (xy 192.0529 -158.949476) (xy 191.857279 -158.873313) (xy 191.664699 -158.789759)
			(xy 191.475441 -158.698934) (xy 191.289777 -158.600969) (xy 191.107977 -158.496007) (xy 190.930305 -158.3842)
			(xy 190.757019 -158.265709) (xy 190.588369 -158.140708) (xy 190.4246 -158.009376) (xy 190.26595 -157.871905)
			(xy 190.112648 -157.728494) (xy 189.964918 -157.57935) (xy 189.822972 -157.42469) (xy 189.687018 -157.264739)
			(xy 189.557251 -157.099727) (xy 189.433861 -156.929895) (xy 189.317026 -156.755488) (xy 189.206915 -156.57676)
			(xy 189.103688 -156.393969) (xy 189.007495 -156.207381) (xy 188.918476 -156.017266) (xy 188.836758 -155.8239)
			(xy 188.762462 -155.627563) (xy 188.695694 -155.42854) (xy 188.636552 -155.227119) (xy 188.58512 -155.023593)
			(xy 188.541475 -154.818256) (xy 188.505678 -154.611406) (xy 188.477782 -154.403344) (xy 188.457828 -154.19437)
			(xy 188.445843 -153.984788) (xy 188.441847 -153.774902) (xy 132.165372 -153.774902) (xy 132.17401 -153.779355)
			(xy 132.244575 -153.824704) (xy 132.31051 -153.876555) (xy 132.371218 -153.934439) (xy 132.426149 -153.997832)
			(xy 132.474805 -154.066159) (xy 132.516746 -154.138802) (xy 132.551591 -154.215103) (xy 132.579026 -154.29437)
			(xy 132.598802 -154.375887) (xy 132.61074 -154.458914) (xy 132.614731 -154.5427) (xy 132.61074 -154.626486)
			(xy 132.598802 -154.709513) (xy 132.579026 -154.79103) (xy 132.551591 -154.870297) (xy 132.516746 -154.946598)
			(xy 132.474805 -155.019241) (xy 132.426149 -155.087568) (xy 132.371218 -155.150961) (xy 132.31051 -155.208845)
			(xy 132.244575 -155.260696) (xy 132.17401 -155.306045) (xy 132.099453 -155.344481) (xy 132.02158 -155.375656)
			(xy 131.941097 -155.399287) (xy 131.858732 -155.415161) (xy 131.77523 -155.423133) (xy 131.73329 -155.423616)
			(xy 131.6961 -155.423229) (xy 131.621987 -155.416939) (xy 131.548668 -155.404428) (xy 131.476662 -155.385787)
			(xy 131.441444 -155.373832) (xy 131.433247 -155.371318) (xy 131.416113 -155.371318) (xy 131.407916 -155.373832)
			(xy 131.374578 -155.385154) (xy 131.306486 -155.403082) (xy 131.237181 -155.41552) (xy 131.202176 -155.419298)
			(xy 131.192163 -155.420682) (xy 131.174401 -155.43031) (xy 131.161723 -155.446041) (xy 131.158488 -155.45562)
			(xy 131.151035 -155.480306) (xy 131.133624 -155.528851) (xy 131.12369 -155.552648) (xy 131.120082 -155.562222)
			(xy 131.119936 -155.58266) (xy 131.123436 -155.592272) (xy 131.140471 -155.633645) (xy 131.167086 -155.719073)
			(xy 131.184987 -155.806743) (xy 131.193992 -155.895767) (xy 131.194556 -155.940506) (xy 131.194556 -155.94076)
			(xy 131.194052 -155.983108) (xy 131.186001 -156.067422) (xy 131.169972 -156.150588) (xy 131.146111 -156.231855)
			(xy 131.114632 -156.310485) (xy 131.075821 -156.385766) (xy 131.030031 -156.457018) (xy 130.977675 -156.523594)
			(xy 130.919227 -156.584892) (xy 130.855217 -156.640357) (xy 130.786225 -156.689486) (xy 130.712875 -156.731835)
			(xy 130.635832 -156.767019) (xy 130.555793 -156.794721) (xy 130.473484 -156.814689) (xy 130.389649 -156.826742)
			(xy 130.305048 -156.830773) (xy 130.220447 -156.826742) (xy 130.136612 -156.814689) (xy 130.054303 -156.794721)
			(xy 129.974264 -156.767019) (xy 129.897221 -156.731835) (xy 129.823871 -156.689486) (xy 129.754879 -156.640357)
			(xy 129.690869 -156.584892) (xy 129.632421 -156.523594) (xy 129.580065 -156.457018) (xy 129.534275 -156.385766)
			(xy 129.495464 -156.310485) (xy 129.463985 -156.231855) (xy 129.440124 -156.150588) (xy 129.424095 -156.067422)
			(xy 129.416044 -155.983108) (xy 129.41554 -155.94076) (xy 129.41554 -155.940506) (xy 129.416091 -155.895767)
			(xy 129.425111 -155.806745) (xy 129.443021 -155.719078) (xy 129.46964 -155.633651) (xy 129.48666 -155.592272)
			(xy 129.490247 -155.582688) (xy 129.490232 -155.562239) (xy 129.48666 -155.552648) (xy 129.471663 -155.516314)
			(xy 129.447353 -155.441557) (xy 129.429731 -155.364948) (xy 129.418932 -155.287083) (xy 129.416556 -155.247848)
			(xy 129.415794 -155.233878) (xy 129.400046 -155.21051) (xy 129.29235 -155.160472) (xy 129.264664 -155.16352)
			(xy 129.253234 -155.172156) (xy 129.220015 -155.196974) (xy 129.149739 -155.241) (xy 129.075668 -155.27829)
			(xy 128.998447 -155.308521) (xy 128.918747 -155.33143) (xy 128.83726 -155.346818) (xy 128.754694 -155.354552)
			(xy 128.71323 -155.355036) (xy 128.672115 -155.354573) (xy 128.590235 -155.346988) (xy 128.509404 -155.33188)
			(xy 128.430313 -155.309379) (xy 128.353635 -155.279675) (xy 128.280025 -155.243023) (xy 128.210111 -155.199735)
			(xy 128.144489 -155.150181) (xy 128.08372 -155.094783) (xy 128.028322 -155.034014) (xy 127.978767 -154.968393)
			(xy 127.935479 -154.898479) (xy 127.898826 -154.824869) (xy 127.869122 -154.748191) (xy 127.84662 -154.669099)
			(xy 127.831512 -154.588269) (xy 127.823927 -154.506389) (xy 127.823468 -154.465274) (xy 35.422918 -154.465274)
			(xy 35.41915 -154.49811) (xy 35.387298 -154.705603) (xy 35.34757 -154.911734) (xy 35.300023 -155.116203)
			(xy 35.244726 -155.318713) (xy 35.181759 -155.518971) (xy 35.111214 -155.716687) (xy 35.033193 -155.911574)
			(xy 34.947809 -156.103349) (xy 34.855186 -156.291735) (xy 34.755459 -156.476458) (xy 34.648771 -156.65725)
			(xy 34.535277 -156.83385) (xy 34.415142 -157.006) (xy 34.288541 -157.173453) (xy 34.155656 -157.335964)
			(xy 34.016681 -157.493298) (xy 33.871817 -157.645227) (xy 33.721274 -157.791531) (xy 33.56527 -157.931998)
			(xy 33.404031 -158.066424) (xy 33.237791 -158.194613) (xy 33.066792 -158.316381) (xy 32.891281 -158.431551)
			(xy 32.711513 -158.539955) (xy 32.527748 -158.641437) (xy 32.340252 -158.735849) (xy 32.149299 -158.823055)
			(xy 31.955163 -158.902928) (xy 31.758128 -158.975352) (xy 31.558478 -159.040222) (xy 31.356503 -159.097444)
			(xy 31.152497 -159.146936) (xy 30.946753 -159.188625) (xy 30.739572 -159.22245) (xy 30.531254 -159.248364)
			(xy 30.3221 -159.266329) (xy 30.112413 -159.276317) (xy 29.902499 -159.278316) (xy 29.69266 -159.272321)
			(xy 29.483202 -159.258342) (xy 29.274427 -159.236399) (xy 29.06664 -159.206524) (xy 28.860141 -159.168759)
			(xy 28.655228 -159.123161) (xy 28.452201 -159.069794) (xy 28.251352 -159.008737) (xy 28.052974 -158.940078)
			(xy 27.857353 -158.863915) (xy 27.664773 -158.780361) (xy 27.475515 -158.689536) (xy 27.289851 -158.591571)
			(xy 27.108051 -158.486609) (xy 26.930379 -158.374802) (xy 26.757093 -158.256311) (xy 26.588443 -158.13131)
			(xy 26.424674 -157.999978) (xy 26.266024 -157.862507) (xy 26.112722 -157.719096) (xy 25.964992 -157.569952)
			(xy 25.823046 -157.415292) (xy 25.687092 -157.255341) (xy 25.557325 -157.090329) (xy 25.433935 -156.920497)
			(xy 25.3171 -156.74609) (xy 25.206989 -156.567362) (xy 25.103762 -156.384571) (xy 25.007569 -156.197983)
			(xy 24.91855 -156.007868) (xy 24.836832 -155.814502) (xy 24.762536 -155.618165) (xy 24.695768 -155.419142)
			(xy 24.636626 -155.217721) (xy 24.585194 -155.014195) (xy 24.541549 -154.808858) (xy 24.505752 -154.602008)
			(xy 24.477856 -154.393946) (xy 24.457902 -154.184972) (xy 24.445917 -153.97539) (xy 24.441921 -153.765504)
			(xy 2.509012 -153.765504) (xy 2.509012 -164.097716) (xy 86.129368 -164.097716) (xy 86.129877 -164.05494)
			(xy 86.138089 -163.969783) (xy 86.154448 -163.88581) (xy 86.178803 -163.803797) (xy 86.194392 -163.76396)
			(xy 86.19746 -163.755511) (xy 86.19811 -163.737557) (xy 86.195662 -163.728908) (xy 86.181097 -163.683434)
			(xy 86.160666 -163.590154) (xy 86.150355 -163.495221) (xy 86.149688 -163.447476) (xy 86.150084 -163.409186)
			(xy 86.156694 -163.332892) (xy 86.169846 -163.257449) (xy 86.189443 -163.183419) (xy 86.202012 -163.147248)
			(xy 86.204676 -163.138815) (xy 86.204669 -163.121141) (xy 86.202012 -163.112704) (xy 86.18946 -163.076529)
			(xy 86.169889 -163.002495) (xy 86.156744 -162.927055) (xy 86.150122 -162.850764) (xy 86.149688 -162.812476)
			(xy 86.15013 -162.771365) (xy 86.157719 -162.689494) (xy 86.172832 -162.608673) (xy 86.195339 -162.529592)
			(xy 86.225048 -162.452925) (xy 86.261705 -162.379327) (xy 86.304997 -162.309425) (xy 86.354555 -162.243817)
			(xy 86.409957 -162.183063) (xy 86.470728 -162.12768) (xy 86.536351 -162.078142) (xy 86.606266 -162.034871)
			(xy 86.679876 -161.998237) (xy 86.756552 -161.968552) (xy 86.83564 -161.94607) (xy 86.916466 -161.930982)
			(xy 86.998339 -161.923417) (xy 87.03945 -161.922968) (xy 87.077766 -161.923352) (xy 87.154119 -161.92988)
			(xy 87.229626 -161.94296) (xy 87.303725 -161.962495) (xy 87.339932 -161.975038) (xy 87.348248 -161.977624)
			(xy 87.365652 -161.977624) (xy 87.373968 -161.975038) (xy 87.410177 -161.962503) (xy 87.484279 -161.942985)
			(xy 87.559785 -161.929905) (xy 87.636135 -161.92336) (xy 87.67445 -161.922968) (xy 87.712766 -161.923352)
			(xy 87.789119 -161.92988) (xy 87.864626 -161.94296) (xy 87.938725 -161.962495) (xy 87.974932 -161.975038)
			(xy 87.983248 -161.977624) (xy 88.000652 -161.977624) (xy 88.008968 -161.975038) (xy 88.045177 -161.962503)
			(xy 88.119279 -161.942985) (xy 88.194785 -161.929905) (xy 88.271135 -161.92336) (xy 88.30945 -161.922968)
			(xy 88.347766 -161.923352) (xy 88.424119 -161.92988) (xy 88.499626 -161.94296) (xy 88.573725 -161.962495)
			(xy 88.609932 -161.975038) (xy 88.618248 -161.977624) (xy 88.635652 -161.977624) (xy 88.643968 -161.975038)
			(xy 88.680177 -161.962503) (xy 88.754279 -161.942985) (xy 88.829785 -161.929905) (xy 88.906135 -161.92336)
			(xy 88.94445 -161.922968) (xy 88.982766 -161.923352) (xy 89.059119 -161.92988) (xy 89.134626 -161.94296)
			(xy 89.208725 -161.962495) (xy 89.244932 -161.975038) (xy 89.253248 -161.977624) (xy 89.270652 -161.977624)
			(xy 89.278968 -161.975038) (xy 89.315177 -161.962503) (xy 89.389279 -161.942985) (xy 89.464785 -161.929905)
			(xy 89.541135 -161.92336) (xy 89.57945 -161.922968) (xy 89.62106 -161.923438) (xy 89.703917 -161.931201)
			(xy 89.785687 -161.946663) (xy 89.865658 -161.96969) (xy 89.90457 -161.984436) (xy 89.913248 -161.987466)
			(xy 89.931617 -161.98771) (xy 89.940384 -161.984944) (xy 89.976385 -161.972506) (xy 90.050053 -161.953122)
			(xy 90.125108 -161.940106) (xy 90.201001 -161.933552) (xy 90.239088 -161.933128) (xy 90.23985 -161.933128)
			(xy 90.280956 -161.93366) (xy 90.362817 -161.94124) (xy 90.443629 -161.956339) (xy 90.522705 -161.97883)
			(xy 90.599368 -162.008519) (xy 90.672965 -162.045155) (xy 90.742868 -162.088423) (xy 90.808482 -162.137957)
			(xy 90.869246 -162.193332) (xy 90.924643 -162.254076) (xy 90.974199 -162.319673) (xy 91.017492 -162.389561)
			(xy 91.054154 -162.463145) (xy 91.08387 -162.539798) (xy 91.106389 -162.618865) (xy 91.121517 -162.699672)
			(xy 91.129125 -162.781531) (xy 91.129612 -162.822636) (xy 91.12919 -162.860925) (xy 91.122588 -162.937219)
			(xy 91.109443 -163.012662) (xy 91.089854 -163.086693) (xy 91.077288 -163.122864) (xy 91.076082 -163.126674)
			(xy 119.365268 -163.126674) (xy 119.365838 -163.081905) (xy 119.374847 -162.99282) (xy 119.392749 -162.905089)
			(xy 119.419366 -162.819597) (xy 119.436388 -162.778186) (xy 119.43997 -162.7686) (xy 119.43996 -162.748153)
			(xy 119.436388 -162.738562) (xy 119.41934 -162.69716) (xy 119.392709 -162.61167) (xy 119.374808 -162.523935)
			(xy 119.365818 -162.434845) (xy 119.365268 -162.390074) (xy 119.365838 -162.345305) (xy 119.374847 -162.25622)
			(xy 119.392749 -162.168489) (xy 119.419366 -162.082997) (xy 119.436388 -162.041586) (xy 119.43997 -162.032)
			(xy 119.43996 -162.011553) (xy 119.436388 -162.001962) (xy 119.41934 -161.96056) (xy 119.392709 -161.87507)
			(xy 119.374808 -161.787335) (xy 119.365818 -161.698245) (xy 119.365268 -161.653474) (xy 119.365674 -161.612358)
			(xy 119.373264 -161.530476) (xy 119.388376 -161.449645) (xy 119.410882 -161.370552) (xy 119.440591 -161.293873)
			(xy 119.477247 -161.220263) (xy 119.520539 -161.150349) (xy 119.570097 -161.084728) (xy 119.625499 -161.023959)
			(xy 119.686271 -160.968561) (xy 119.751895 -160.919007) (xy 119.821812 -160.87572) (xy 119.895425 -160.839068)
			(xy 119.972105 -160.809365) (xy 120.051199 -160.786863) (xy 120.132032 -160.771756) (xy 120.213914 -160.764171)
			(xy 120.25503 -160.763712) (xy 120.296641 -160.764173) (xy 120.379498 -160.771953) (xy 120.461267 -160.787431)
			(xy 120.541235 -160.810474) (xy 120.618703 -160.840879) (xy 120.692995 -160.878382) (xy 120.728486 -160.90011)
			(xy 120.737629 -160.905263) (xy 120.758342 -160.90848) (xy 120.778614 -160.903152) (xy 120.78716 -160.897062)
			(xy 120.820789 -160.871071) (xy 120.892183 -160.824946) (xy 120.967654 -160.785845) (xy 121.046512 -160.754124)
			(xy 121.128037 -160.730075) (xy 121.211485 -160.713915) (xy 121.296095 -160.705793) (xy 121.338594 -160.705292)
			(xy 121.379707 -160.705819) (xy 121.461582 -160.713405) (xy 121.542407 -160.728513) (xy 121.621494 -160.751013)
			(xy 121.698168 -160.780715) (xy 121.771774 -160.817365) (xy 121.841684 -160.86065) (xy 121.907303 -160.9102)
			(xy 121.96807 -160.965593) (xy 122.023467 -161.026357) (xy 122.073021 -161.091973) (xy 122.11631 -161.161881)
			(xy 122.152964 -161.235485) (xy 122.18267 -161.312156) (xy 122.205176 -161.391242) (xy 122.220288 -161.472067)
			(xy 122.227879 -161.553941) (xy 122.228356 -161.595054) (xy 122.227793 -161.639824) (xy 122.218783 -161.728909)
			(xy 122.200877 -161.81664) (xy 122.174259 -161.902131) (xy 122.157236 -161.943542) (xy 122.153699 -161.953141)
			(xy 122.153682 -161.973576) (xy 122.157236 -161.983166) (xy 122.17424 -162.024517) (xy 122.200851 -162.109879)
			(xy 122.218758 -162.197482) (xy 122.22778 -162.286439) (xy 122.228356 -162.331146) (xy 122.228356 -162.332162)
			(xy 122.228102 -162.343592) (xy 122.254581 -162.349538) (xy 122.306816 -162.364281) (xy 122.332496 -162.373056)
			(xy 122.340693 -162.37557) (xy 122.357827 -162.37557) (xy 122.366024 -162.373056) (xy 122.40124 -162.361095)
			(xy 122.473244 -162.342441) (xy 122.546565 -162.329932) (xy 122.62068 -162.323659) (xy 122.65787 -162.323272)
			(xy 122.695059 -162.323671) (xy 122.769172 -162.329958) (xy 122.842492 -162.342465) (xy 122.914498 -162.361103)
			(xy 122.949716 -162.373056) (xy 122.957913 -162.37557) (xy 122.975047 -162.37557) (xy 122.983244 -162.373056)
			(xy 123.018459 -162.361089) (xy 123.090462 -162.342437) (xy 123.163784 -162.32993) (xy 123.2379 -162.323658)
			(xy 123.27509 -162.323272) (xy 123.31703 -162.323667) (xy 123.400532 -162.331639) (xy 123.482897 -162.347513)
			(xy 123.56338 -162.371144) (xy 123.641253 -162.402319) (xy 123.71581 -162.440755) (xy 123.786375 -162.486104)
			(xy 123.85231 -162.537955) (xy 123.913018 -162.595839) (xy 123.913877 -162.59683) (xy 376.471695 -162.59683)
			(xy 376.4757 -162.491081) (xy 376.48769 -162.385938) (xy 376.507599 -162.282003) (xy 376.53531 -162.179871)
			(xy 376.570667 -162.080127) (xy 376.613465 -161.983343) (xy 376.663461 -161.890073) (xy 376.720368 -161.800852)
			(xy 376.783859 -161.716189) (xy 376.853571 -161.636571) (xy 376.929105 -161.562453) (xy 377.010028 -161.49426)
			(xy 377.095877 -161.432382) (xy 377.18616 -161.377175) (xy 377.280359 -161.328953) (xy 377.377936 -161.287993)
			(xy 377.478331 -161.254531) (xy 377.580969 -161.228757) (xy 377.685262 -161.210819) (xy 377.790613 -161.20082)
			(xy 377.896419 -161.198817) (xy 378.002073 -161.204822) (xy 378.10697 -161.218801) (xy 378.21051 -161.240672)
			(xy 378.312099 -161.270312) (xy 378.411156 -161.30755) (xy 378.507113 -161.352172) (xy 378.59942 -161.403924)
			(xy 378.687549 -161.462509) (xy 378.770995 -161.527591) (xy 378.849279 -161.598797) (xy 378.921954 -161.67572)
			(xy 378.988604 -161.75792) (xy 379.048846 -161.844924) (xy 379.102335 -161.936235) (xy 379.148766 -162.03133)
			(xy 379.187871 -162.129664) (xy 379.219428 -162.230675) (xy 379.243255 -162.333782) (xy 379.259216 -162.438396)
			(xy 379.26722 -162.543918) (xy 379.26772 -162.59683) (xy 379.26722 -162.649742) (xy 379.266995 -162.65271)
			(xy 385.808735 -162.65271) (xy 385.81274 -162.546961) (xy 385.82473 -162.441818) (xy 385.844639 -162.337883)
			(xy 385.87235 -162.235751) (xy 385.907707 -162.136007) (xy 385.950505 -162.039223) (xy 386.000501 -161.945953)
			(xy 386.057408 -161.856732) (xy 386.120899 -161.772069) (xy 386.190611 -161.692451) (xy 386.266145 -161.618333)
			(xy 386.347068 -161.55014) (xy 386.432917 -161.488262) (xy 386.5232 -161.433055) (xy 386.617399 -161.384833)
			(xy 386.714976 -161.343873) (xy 386.815371 -161.310411) (xy 386.918009 -161.284637) (xy 387.022302 -161.266699)
			(xy 387.127653 -161.2567) (xy 387.233459 -161.254697) (xy 387.339113 -161.260702) (xy 387.44401 -161.274681)
			(xy 387.54755 -161.296552) (xy 387.649139 -161.326192) (xy 387.748196 -161.36343) (xy 387.844153 -161.408052)
			(xy 387.93646 -161.459804) (xy 388.024589 -161.518389) (xy 388.108035 -161.583471) (xy 388.186319 -161.654677)
			(xy 388.231017 -161.701988) (xy 409.929076 -161.701988) (xy 409.92965 -161.657219) (xy 409.938657 -161.568134)
			(xy 409.956559 -161.480403) (xy 409.983175 -161.394911) (xy 410.000196 -161.3535) (xy 410.00377 -161.343912)
			(xy 410.003765 -161.323466) (xy 410.000196 -161.313876) (xy 409.983153 -161.272472) (xy 409.956521 -161.186983)
			(xy 409.938618 -161.099248) (xy 409.929627 -161.010159) (xy 409.929076 -160.965388) (xy 409.92965 -160.920619)
			(xy 409.938657 -160.831534) (xy 409.956559 -160.743803) (xy 409.983175 -160.658311) (xy 410.000196 -160.6169)
			(xy 410.00377 -160.607312) (xy 410.003765 -160.586866) (xy 410.000196 -160.577276) (xy 409.983153 -160.535872)
			(xy 409.956521 -160.450383) (xy 409.938618 -160.362648) (xy 409.929627 -160.273559) (xy 409.929076 -160.228788)
			(xy 409.929541 -160.187678) (xy 409.93713 -160.105808) (xy 409.952241 -160.024988) (xy 409.974747 -159.945907)
			(xy 410.004454 -159.869241) (xy 410.041109 -159.795643) (xy 410.0844 -159.725742) (xy 410.133957 -159.660134)
			(xy 410.189357 -159.59938) (xy 410.250127 -159.543997) (xy 410.315748 -159.494459) (xy 410.385662 -159.451187)
			(xy 410.45927 -159.414553) (xy 410.535944 -159.384867) (xy 410.615031 -159.362384) (xy 410.695856 -159.347295)
			(xy 410.777728 -159.339729) (xy 410.818838 -159.33928) (xy 410.860442 -159.339755) (xy 410.94329 -159.347487)
			(xy 411.025054 -159.362917) (xy 411.105022 -159.38591) (xy 411.182495 -159.416266) (xy 411.256796 -159.45372)
			(xy 411.292294 -159.475424) (xy 411.301434 -159.480582) (xy 411.322149 -159.483796) (xy 411.342422 -159.478466)
			(xy 411.350968 -159.472376) (xy 411.384591 -159.44642) (xy 411.45597 -159.400364) (xy 411.531414 -159.361321)
			(xy 411.610235 -159.329647) (xy 411.691716 -159.305629) (xy 411.775116 -159.289486) (xy 411.859674 -159.281366)
			(xy 411.902148 -159.28086) (xy 411.902402 -159.28086) (xy 411.943509 -159.281311) (xy 412.025374 -159.288895)
			(xy 412.106189 -159.304) (xy 412.185267 -159.326496) (xy 412.261931 -159.356191) (xy 412.33553 -159.392831)
			(xy 412.405434 -159.436106) (xy 412.471048 -159.485644) (xy 412.531813 -159.541025) (xy 412.587209 -159.601775)
			(xy 412.636764 -159.667376) (xy 412.680057 -159.737269) (xy 412.716716 -159.810858) (xy 412.746431 -159.887515)
			(xy 412.768947 -159.966587) (xy 412.784073 -160.047398) (xy 412.791679 -160.129261) (xy 412.792164 -160.170368)
			(xy 412.791606 -160.215138) (xy 412.782594 -160.304223) (xy 412.764688 -160.391954) (xy 412.738068 -160.477445)
			(xy 412.721044 -160.518856) (xy 412.717498 -160.528452) (xy 412.717487 -160.548889) (xy 412.721044 -160.55848)
			(xy 412.738053 -160.599829) (xy 412.764663 -160.685192) (xy 412.782568 -160.772795) (xy 412.791589 -160.861753)
			(xy 412.792164 -160.90646) (xy 412.792164 -160.907476) (xy 412.79191 -160.918906) (xy 412.818389 -160.924851)
			(xy 412.870624 -160.939594) (xy 412.896304 -160.94837) (xy 412.904501 -160.950884) (xy 412.921635 -160.950884)
			(xy 412.929832 -160.94837) (xy 412.96505 -160.936429) (xy 413.037059 -160.91784) (xy 413.110382 -160.905398)
			(xy 413.184492 -160.899192) (xy 413.221678 -160.89884) (xy 413.258862 -160.899213) (xy 413.33297 -160.905434)
			(xy 413.40629 -160.917875) (xy 413.478301 -160.936448) (xy 413.513524 -160.94837) (xy 413.521721 -160.950884)
			(xy 413.538855 -160.950884) (xy 413.547052 -160.94837) (xy 413.582146 -160.93646) (xy 413.653906 -160.917916)
			(xy 413.726971 -160.905476) (xy 413.800824 -160.899229) (xy 413.837882 -160.89884) (xy 413.838898 -160.89884)
			(xy 413.880822 -160.899407) (xy 413.964291 -160.907377) (xy 414.046623 -160.923245) (xy 414.127075 -160.946868)
			(xy 414.204917 -160.978031) (xy 414.279444 -161.016452) (xy 414.349982 -161.061784) (xy 414.415891 -161.113615)
			(xy 414.476575 -161.171477) (xy 414.531484 -161.234845) (xy 414.580121 -161.303146) (xy 414.622045 -161.37576)
			(xy 414.656876 -161.452031) (xy 414.684301 -161.531268) (xy 414.704068 -161.612752) (xy 414.716001 -161.695747)
			(xy 414.719991 -161.7795) (xy 414.716001 -161.863253) (xy 414.704068 -161.946248) (xy 414.684301 -162.027732)
			(xy 414.656876 -162.106969) (xy 414.622045 -162.18324) (xy 414.580121 -162.255854) (xy 414.531484 -162.324155)
			(xy 414.476575 -162.387523) (xy 414.415891 -162.445385) (xy 414.349982 -162.497216) (xy 414.279444 -162.542548)
			(xy 414.204917 -162.580969) (xy 414.127075 -162.612132) (xy 414.046623 -162.635755) (xy 413.964291 -162.651623)
			(xy 413.880822 -162.659593) (xy 413.838898 -162.660076) (xy 413.837882 -162.660076) (xy 413.800825 -162.659672)
			(xy 413.726976 -162.653407) (xy 413.653913 -162.640964) (xy 413.582153 -162.622432) (xy 413.547052 -162.610546)
			(xy 413.538855 -162.608032) (xy 413.521721 -162.608032) (xy 413.513524 -162.610546) (xy 413.484638 -162.620383)
			(xy 413.425785 -162.636529) (xy 413.395922 -162.642804) (xy 413.386334 -162.645159) (xy 413.369889 -162.656054)
			(xy 413.358796 -162.672367) (xy 413.356298 -162.68192) (xy 413.34617 -162.726275) (xy 413.318046 -162.812805)
			(xy 413.300164 -162.85464) (xy 413.296347 -162.864579) (xy 413.296353 -162.885846) (xy 413.300164 -162.895788)
			(xy 413.318394 -162.938388) (xy 413.346909 -163.026556) (xy 413.366099 -163.117213) (xy 413.375757 -163.209373)
			(xy 413.376364 -163.255706) (xy 413.376364 -163.256214) (xy 413.37586 -163.298562) (xy 413.367809 -163.382876)
			(xy 413.35178 -163.466042) (xy 413.327919 -163.547309) (xy 413.29644 -163.625939) (xy 413.257629 -163.70122)
			(xy 413.230169 -163.74395) (xy 431.840894 -163.74395) (xy 431.840894 -163.68945) (xy 431.84865 -163.635505)
			(xy 431.864004 -163.583213) (xy 431.886644 -163.533639) (xy 431.916109 -163.48779) (xy 431.951798 -163.446602)
			(xy 431.992986 -163.410912) (xy 432.038833 -163.381447) (xy 432.088408 -163.358807) (xy 432.140699 -163.343452)
			(xy 432.194644 -163.335695) (xy 432.221894 -163.335208) (xy 433.212494 -163.335208) (xy 433.239748 -163.335638)
			(xy 433.293702 -163.343395) (xy 433.346003 -163.358751) (xy 433.395586 -163.381394) (xy 433.441442 -163.410863)
			(xy 433.482637 -163.446559) (xy 433.518333 -163.487753) (xy 433.547803 -163.533609) (xy 433.570447 -163.583191)
			(xy 433.585804 -163.635492) (xy 433.593561 -163.689446) (xy 433.593561 -163.743954) (xy 433.585804 -163.797908)
			(xy 433.570447 -163.850209) (xy 433.547803 -163.899791) (xy 433.518333 -163.945647) (xy 433.482637 -163.986841)
			(xy 433.441442 -164.022537) (xy 433.395586 -164.052006) (xy 433.346003 -164.074649) (xy 433.293702 -164.090005)
			(xy 433.239748 -164.097762) (xy 433.212494 -164.098224) (xy 432.221894 -164.098224) (xy 432.194644 -164.097705)
			(xy 432.140699 -164.089948) (xy 432.088408 -164.074593) (xy 432.038833 -164.051953) (xy 431.992986 -164.022488)
			(xy 431.951798 -163.986798) (xy 431.916109 -163.94561) (xy 431.886644 -163.899761) (xy 431.864004 -163.850187)
			(xy 431.84865 -163.797895) (xy 431.840894 -163.74395) (xy 413.230169 -163.74395) (xy 413.211839 -163.772472)
			(xy 413.159483 -163.839048) (xy 413.101035 -163.900346) (xy 413.037025 -163.955811) (xy 412.968033 -164.00494)
			(xy 412.894683 -164.047289) (xy 412.81764 -164.082473) (xy 412.737601 -164.110175) (xy 412.655292 -164.130143)
			(xy 412.571457 -164.142196) (xy 412.486856 -164.146227) (xy 412.402255 -164.142196) (xy 412.31842 -164.130143)
			(xy 412.236111 -164.110175) (xy 412.156072 -164.082473) (xy 412.079029 -164.047289) (xy 412.005679 -164.00494)
			(xy 411.936687 -163.955811) (xy 411.872677 -163.900346) (xy 411.814229 -163.839048) (xy 411.761873 -163.772472)
			(xy 411.716083 -163.70122) (xy 411.677272 -163.625939) (xy 411.645793 -163.547309) (xy 411.621932 -163.466042)
			(xy 411.605903 -163.382876) (xy 411.597852 -163.298562) (xy 411.597348 -163.256214) (xy 411.597348 -163.255706)
			(xy 411.597963 -163.209374) (xy 411.607632 -163.117217) (xy 411.626825 -163.026563) (xy 411.655334 -162.938394)
			(xy 411.673548 -162.895788) (xy 411.677348 -162.885844) (xy 411.677353 -162.864582) (xy 411.673548 -162.85464)
			(xy 411.655311 -162.811974) (xy 411.626764 -162.723684) (xy 411.607569 -162.632899) (xy 411.597934 -162.54061)
			(xy 411.597348 -162.494214) (xy 411.597953 -162.446404) (xy 411.608131 -162.351329) (xy 411.617668 -162.304476)
			(xy 411.61964 -162.292071) (xy 411.612727 -162.267957) (xy 411.60446 -162.258502) (xy 411.56382 -162.216338)
			(xy 411.560264 -162.2171) (xy 411.551416 -162.219411) (xy 411.536053 -162.229303) (xy 411.530292 -162.236404)
			(xy 411.505137 -162.269067) (xy 411.449717 -162.33011) (xy 411.388886 -162.385763) (xy 411.323166 -162.435548)
			(xy 411.253121 -162.479037) (xy 411.179352 -162.515858) (xy 411.102492 -162.545694) (xy 411.023201 -162.56829)
			(xy 410.942159 -162.583451) (xy 410.860062 -162.591047) (xy 410.818838 -162.591496) (xy 410.777733 -162.590951)
			(xy 410.695873 -162.583371) (xy 410.615061 -162.568271) (xy 410.535987 -162.54578) (xy 410.459325 -162.516091)
			(xy 410.385729 -162.479456) (xy 410.315826 -162.436187) (xy 410.250213 -162.386655) (xy 410.18945 -162.331281)
			(xy 410.134053 -162.270538) (xy 410.084497 -162.204943) (xy 410.041203 -162.135056) (xy 410.004541 -162.061473)
			(xy 409.974824 -161.984822) (xy 409.952304 -161.905756) (xy 409.937174 -161.82495) (xy 409.929564 -161.743093)
			(xy 409.929076 -161.701988) (xy 388.231017 -161.701988) (xy 388.258994 -161.7316) (xy 388.325644 -161.8138)
			(xy 388.385886 -161.900804) (xy 388.439375 -161.992115) (xy 388.485806 -162.08721) (xy 388.524911 -162.185544)
			(xy 388.556468 -162.286555) (xy 388.580295 -162.389662) (xy 388.596256 -162.494276) (xy 388.60426 -162.599798)
			(xy 388.60476 -162.65271) (xy 388.60426 -162.705622) (xy 388.596256 -162.811144) (xy 388.580295 -162.915758)
			(xy 388.556468 -163.018865) (xy 388.524911 -163.119876) (xy 388.485806 -163.21821) (xy 388.439375 -163.313305)
			(xy 388.385886 -163.404616) (xy 388.325644 -163.49162) (xy 388.258994 -163.57382) (xy 388.186319 -163.650743)
			(xy 388.108035 -163.721949) (xy 388.024589 -163.787031) (xy 387.93646 -163.845616) (xy 387.844153 -163.897368)
			(xy 387.748196 -163.94199) (xy 387.649139 -163.979228) (xy 387.54755 -164.008868) (xy 387.44401 -164.030739)
			(xy 387.339113 -164.044718) (xy 387.233459 -164.050723) (xy 387.127653 -164.04872) (xy 387.022302 -164.038721)
			(xy 386.918009 -164.020783) (xy 386.815371 -163.995009) (xy 386.714976 -163.961547) (xy 386.617399 -163.920587)
			(xy 386.5232 -163.872365) (xy 386.432917 -163.817158) (xy 386.347068 -163.75528) (xy 386.266145 -163.687087)
			(xy 386.190611 -163.612969) (xy 386.120899 -163.533351) (xy 386.057408 -163.448688) (xy 386.000501 -163.359467)
			(xy 385.950505 -163.266197) (xy 385.907707 -163.169413) (xy 385.87235 -163.069669) (xy 385.844639 -162.967537)
			(xy 385.82473 -162.863602) (xy 385.81274 -162.758459) (xy 385.808735 -162.65271) (xy 379.266995 -162.65271)
			(xy 379.259216 -162.755264) (xy 379.243255 -162.859878) (xy 379.219428 -162.962985) (xy 379.187871 -163.063996)
			(xy 379.148766 -163.16233) (xy 379.102335 -163.257425) (xy 379.048846 -163.348736) (xy 378.988604 -163.43574)
			(xy 378.921954 -163.51794) (xy 378.849279 -163.594863) (xy 378.770995 -163.666069) (xy 378.687549 -163.731151)
			(xy 378.59942 -163.789736) (xy 378.507113 -163.841488) (xy 378.411156 -163.88611) (xy 378.312099 -163.923348)
			(xy 378.21051 -163.952988) (xy 378.10697 -163.974859) (xy 378.002073 -163.988838) (xy 377.896419 -163.994843)
			(xy 377.790613 -163.99284) (xy 377.685262 -163.982841) (xy 377.580969 -163.964903) (xy 377.478331 -163.939129)
			(xy 377.377936 -163.905667) (xy 377.280359 -163.864707) (xy 377.18616 -163.816485) (xy 377.095877 -163.761278)
			(xy 377.010028 -163.6994) (xy 376.929105 -163.631207) (xy 376.853571 -163.557089) (xy 376.783859 -163.477471)
			(xy 376.720368 -163.392808) (xy 376.663461 -163.303587) (xy 376.613465 -163.210317) (xy 376.570667 -163.113533)
			(xy 376.53531 -163.013789) (xy 376.507599 -162.911657) (xy 376.48769 -162.807722) (xy 376.4757 -162.702579)
			(xy 376.471695 -162.59683) (xy 123.913877 -162.59683) (xy 123.967949 -162.659232) (xy 124.016605 -162.727559)
			(xy 124.058546 -162.800202) (xy 124.093391 -162.876503) (xy 124.120826 -162.95577) (xy 124.140602 -163.037287)
			(xy 124.15254 -163.120314) (xy 124.156531 -163.2041) (xy 124.15254 -163.287886) (xy 124.140602 -163.370913)
			(xy 124.120826 -163.45243) (xy 124.093391 -163.531697) (xy 124.058546 -163.607998) (xy 124.016605 -163.680641)
			(xy 123.967949 -163.748968) (xy 123.913018 -163.812361) (xy 123.85231 -163.870245) (xy 123.786375 -163.922096)
			(xy 123.71581 -163.967445) (xy 123.641253 -164.005881) (xy 123.56338 -164.037056) (xy 123.482897 -164.060687)
			(xy 123.400532 -164.076561) (xy 123.31703 -164.084533) (xy 123.27509 -164.085016) (xy 123.2379 -164.084629)
			(xy 123.163787 -164.078339) (xy 123.090468 -164.065828) (xy 123.018462 -164.047187) (xy 122.983244 -164.035232)
			(xy 122.975047 -164.032718) (xy 122.957913 -164.032718) (xy 122.949716 -164.035232) (xy 122.907233 -164.049509)
			(xy 122.820068 -164.070379) (xy 122.775726 -164.076888) (xy 122.765804 -164.078672) (xy 122.748385 -164.088778)
			(xy 122.736231 -164.104835) (xy 122.733308 -164.11448) (xy 122.724748 -164.14638) (xy 122.70352 -164.20893)
			(xy 122.69089 -164.239448) (xy 122.687282 -164.249022) (xy 122.687136 -164.26946) (xy 122.690636 -164.279072)
			(xy 122.707671 -164.320445) (xy 122.734286 -164.405873) (xy 122.752187 -164.493543) (xy 122.756237 -164.53358)
			(xy 365.854996 -164.53358) (xy 365.855358 -164.495263) (xy 365.861892 -164.41891) (xy 365.874978 -164.343403)
			(xy 365.89452 -164.269304) (xy 365.907066 -164.233098) (xy 365.909662 -164.224784) (xy 365.909655 -164.207378)
			(xy 365.907066 -164.199062) (xy 365.894569 -164.162941) (xy 365.875081 -164.089028) (xy 365.861998 -164.013717)
			(xy 365.855418 -163.937561) (xy 365.854996 -163.899342) (xy 365.854996 -163.89858) (xy 365.855448 -163.857477)
			(xy 365.863034 -163.775622) (xy 365.878141 -163.694816) (xy 365.900639 -163.615749) (xy 365.930337 -163.539095)
			(xy 365.966981 -163.465508) (xy 366.010258 -163.395615) (xy 366.059799 -163.330014) (xy 366.115181 -163.269264)
			(xy 366.175933 -163.213883) (xy 366.241535 -163.164344) (xy 366.311429 -163.121069) (xy 366.385017 -163.084427)
			(xy 366.461672 -163.054732) (xy 366.54074 -163.032236) (xy 366.621546 -163.017131) (xy 366.703401 -163.009546)
			(xy 366.744504 -163.009072) (xy 366.745266 -163.009072) (xy 366.783487 -163.009474) (xy 366.859645 -163.01604)
			(xy 366.934958 -163.029126) (xy 367.008868 -163.048635) (xy 367.044986 -163.061142) (xy 367.053302 -163.063728)
			(xy 367.070706 -163.063728) (xy 367.079022 -163.061142) (xy 367.115235 -163.04862) (xy 367.189336 -163.029098)
			(xy 367.26484 -163.016015) (xy 367.341189 -163.009466) (xy 367.379504 -163.009072) (xy 367.419718 -163.009498)
			(xy 367.49982 -163.016721) (xy 367.578942 -163.031153) (xy 367.656435 -163.052677) (xy 367.69421 -163.066476)
			(xy 367.702997 -163.069383) (xy 367.721491 -163.069383) (xy 367.730278 -163.066476) (xy 367.768054 -163.052684)
			(xy 367.845551 -163.031177) (xy 367.924672 -163.016746) (xy 368.004771 -163.00951) (xy 368.044984 -163.009072)
			(xy 368.0833 -163.009446) (xy 368.159653 -163.015977) (xy 368.23516 -163.029059) (xy 368.309259 -163.048598)
			(xy 368.345466 -163.061142) (xy 368.353782 -163.063728) (xy 368.371186 -163.063728) (xy 368.379502 -163.061142)
			(xy 368.415717 -163.048626) (xy 368.489817 -163.029103) (xy 368.565321 -163.016017) (xy 368.641669 -163.009467)
			(xy 368.679984 -163.009072) (xy 368.7183 -163.009446) (xy 368.794653 -163.015977) (xy 368.87016 -163.029059)
			(xy 368.944259 -163.048598) (xy 368.980466 -163.061142) (xy 368.988782 -163.063728) (xy 369.006186 -163.063728)
			(xy 369.014502 -163.061142) (xy 369.050717 -163.048626) (xy 369.124817 -163.029103) (xy 369.200321 -163.016017)
			(xy 369.276669 -163.009467) (xy 369.314984 -163.009072) (xy 369.3533 -163.009446) (xy 369.429653 -163.015977)
			(xy 369.50516 -163.029059) (xy 369.579259 -163.048598) (xy 369.615466 -163.061142) (xy 369.623782 -163.063728)
			(xy 369.641186 -163.063728) (xy 369.649502 -163.061142) (xy 369.685717 -163.048626) (xy 369.759817 -163.029103)
			(xy 369.835321 -163.016017) (xy 369.911669 -163.009467) (xy 369.949984 -163.009072) (xy 369.994754 -163.009635)
			(xy 370.083841 -163.018637) (xy 370.171573 -163.03654) (xy 370.257063 -163.063164) (xy 370.298472 -163.080192)
			(xy 370.308063 -163.083757) (xy 370.328505 -163.083757) (xy 370.338096 -163.080192) (xy 370.379479 -163.063183)
			(xy 370.464904 -163.036561) (xy 370.55257 -163.018653) (xy 370.641592 -163.00964) (xy 370.68633 -163.009072)
			(xy 370.686584 -163.009072) (xy 370.727686 -163.009582) (xy 370.809538 -163.017165) (xy 370.890342 -163.032268)
			(xy 370.969408 -163.054763) (xy 371.046061 -163.084457) (xy 371.119647 -163.121096) (xy 371.189538 -163.16437)
			(xy 371.255139 -163.213907) (xy 371.315889 -163.269286) (xy 371.37127 -163.330033) (xy 371.42081 -163.395632)
			(xy 371.464086 -163.465522) (xy 371.500729 -163.539106) (xy 371.530426 -163.615758) (xy 371.552923 -163.694823)
			(xy 371.56803 -163.775626) (xy 371.575616 -163.857478) (xy 371.576092 -163.89858) (xy 371.576092 -163.899342)
			(xy 371.575679 -163.937562) (xy 371.569116 -164.013721) (xy 371.556033 -164.089033) (xy 371.536527 -164.162943)
			(xy 371.524022 -164.199062) (xy 371.521447 -164.207381) (xy 371.52144 -164.224782) (xy 371.524022 -164.233098)
			(xy 371.536535 -164.269314) (xy 371.55606 -164.343414) (xy 371.569146 -164.418917) (xy 371.575697 -164.495265)
			(xy 371.576092 -164.53358) (xy 371.575734 -164.571323) (xy 371.569392 -164.646543) (xy 371.556692 -164.720953)
			(xy 371.537726 -164.794018) (xy 371.525546 -164.829744) (xy 371.522818 -164.838516) (xy 371.52307 -164.85687)
			(xy 371.526054 -164.865558) (xy 371.541045 -164.904681) (xy 371.564495 -164.985121) (xy 371.58028 -165.067409)
			(xy 371.588259 -165.150817) (xy 371.588792 -165.19271) (xy 371.588792 -165.19398) (xy 371.588329 -165.235083)
			(xy 371.580745 -165.316939) (xy 371.565641 -165.397747) (xy 371.543146 -165.476815) (xy 371.51345 -165.553471)
			(xy 371.476808 -165.62706) (xy 371.433533 -165.696954) (xy 371.383993 -165.762556) (xy 371.328611 -165.823308)
			(xy 371.267859 -165.87869) (xy 371.202257 -165.92823) (xy 371.132363 -165.971506) (xy 371.058775 -166.008149)
			(xy 370.982119 -166.037844) (xy 370.90305 -166.06034) (xy 370.822243 -166.075445) (xy 370.740387 -166.083029)
			(xy 370.699284 -166.083488) (xy 370.69903 -166.083488) (xy 370.654291 -166.082927) (xy 370.56527 -166.07391)
			(xy 370.477602 -166.056003) (xy 370.392175 -166.029387) (xy 370.350796 -166.012368) (xy 370.341205 -166.008803)
			(xy 370.320763 -166.008803) (xy 370.311172 -166.012368) (xy 370.269762 -166.029396) (xy 370.184274 -166.056029)
			(xy 370.096542 -166.073935) (xy 370.007454 -166.082933) (xy 369.962684 -166.083488) (xy 369.924367 -166.083126)
			(xy 369.848014 -166.076592) (xy 369.772507 -166.063506) (xy 369.698408 -166.043964) (xy 369.662202 -166.031418)
			(xy 369.653886 -166.028832) (xy 369.636482 -166.028832) (xy 369.628166 -166.031418) (xy 369.591953 -166.043941)
			(xy 369.517852 -166.063463) (xy 369.442348 -166.076546) (xy 369.365999 -166.083094) (xy 369.327684 -166.083488)
			(xy 369.289367 -166.083126) (xy 369.213014 -166.076592) (xy 369.137507 -166.063506) (xy 369.063408 -166.043964)
			(xy 369.027202 -166.031418) (xy 369.018886 -166.028832) (xy 369.001482 -166.028832) (xy 368.993166 -166.031418)
			(xy 368.956953 -166.043941) (xy 368.882852 -166.063463) (xy 368.807348 -166.076546) (xy 368.730999 -166.083094)
			(xy 368.692684 -166.083488) (xy 368.654367 -166.083126) (xy 368.578014 -166.076592) (xy 368.502507 -166.063506)
			(xy 368.428408 -166.043964) (xy 368.392202 -166.031418) (xy 368.383886 -166.028832) (xy 368.366482 -166.028832)
			(xy 368.358166 -166.031418) (xy 368.321953 -166.043941) (xy 368.247852 -166.063463) (xy 368.172348 -166.076546)
			(xy 368.095999 -166.083094) (xy 368.057684 -166.083488) (xy 368.01747 -166.083062) (xy 367.937368 -166.075838)
			(xy 367.858246 -166.061406) (xy 367.780753 -166.039883) (xy 367.742978 -166.026084) (xy 367.734191 -166.023177)
			(xy 367.715697 -166.023177) (xy 367.70691 -166.026084) (xy 367.669134 -166.039877) (xy 367.591637 -166.061385)
			(xy 367.512517 -166.075815) (xy 367.432417 -166.083051) (xy 367.392204 -166.083488) (xy 367.353888 -166.08312)
			(xy 367.277534 -166.076588) (xy 367.202027 -166.063503) (xy 367.127928 -166.043963) (xy 367.091722 -166.031418)
			(xy 367.083406 -166.028832) (xy 367.066002 -166.028832) (xy 367.057686 -166.031418) (xy 367.021563 -166.043908)
			(xy 366.947651 -166.063398) (xy 366.87234 -166.076483) (xy 366.796185 -166.083065) (xy 366.757966 -166.083488)
			(xy 366.757204 -166.083488) (xy 366.7161 -166.083044) (xy 366.634244 -166.075459) (xy 366.553436 -166.060354)
			(xy 366.474367 -166.037857) (xy 366.397711 -166.00816) (xy 366.324122 -165.971516) (xy 366.254228 -165.928239)
			(xy 366.188625 -165.878698) (xy 366.127874 -165.823315) (xy 366.072492 -165.762562) (xy 366.022951 -165.696959)
			(xy 365.979676 -165.627064) (xy 365.943034 -165.553475) (xy 365.913338 -165.476818) (xy 365.890843 -165.397748)
			(xy 365.875739 -165.316941) (xy 365.868155 -165.235084) (xy 365.867696 -165.19398) (xy 365.867696 -165.192964)
			(xy 365.868115 -165.155349) (xy 365.874496 -165.080389) (xy 365.887191 -165.006237) (xy 365.906111 -164.933424)
			(xy 365.918242 -164.897816) (xy 365.920992 -164.889049) (xy 365.920727 -164.87069) (xy 365.917734 -164.862002)
			(xy 365.902679 -164.822733) (xy 365.879172 -164.741978) (xy 365.863391 -164.659366) (xy 365.855475 -164.575633)
			(xy 365.854996 -164.53358) (xy 122.756237 -164.53358) (xy 122.761192 -164.582567) (xy 122.761756 -164.627306)
			(xy 122.761756 -164.62756) (xy 122.761252 -164.669908) (xy 122.753201 -164.754222) (xy 122.737172 -164.837388)
			(xy 122.713311 -164.918655) (xy 122.681832 -164.997285) (xy 122.643021 -165.072566) (xy 122.597231 -165.143818)
			(xy 122.544875 -165.210394) (xy 122.486427 -165.271692) (xy 122.422417 -165.327157) (xy 122.353425 -165.376286)
			(xy 122.280075 -165.418635) (xy 122.203032 -165.453819) (xy 122.122993 -165.481521) (xy 122.040684 -165.501489)
			(xy 121.956849 -165.513542) (xy 121.872248 -165.517573) (xy 121.787647 -165.513542) (xy 121.703812 -165.501489)
			(xy 121.621503 -165.481521) (xy 121.541464 -165.453819) (xy 121.464421 -165.418635) (xy 121.391071 -165.376286)
			(xy 121.322079 -165.327157) (xy 121.258069 -165.271692) (xy 121.199621 -165.210394) (xy 121.147265 -165.143818)
			(xy 121.101475 -165.072566) (xy 121.062664 -164.997285) (xy 121.031185 -164.918655) (xy 121.007324 -164.837388)
			(xy 120.991295 -164.754222) (xy 120.983244 -164.669908) (xy 120.98274 -164.62756) (xy 120.98274 -164.627306)
			(xy 120.983291 -164.582567) (xy 120.992311 -164.493545) (xy 121.010221 -164.405878) (xy 121.03684 -164.320451)
			(xy 121.05386 -164.279072) (xy 121.057447 -164.269488) (xy 121.057432 -164.249039) (xy 121.05386 -164.239448)
			(xy 121.037012 -164.19848) (xy 121.010567 -164.113931) (xy 120.992664 -164.027171) (xy 120.983478 -163.939061)
			(xy 120.98274 -163.89477) (xy 120.982373 -163.885212) (xy 120.975335 -163.867438) (xy 120.962255 -163.853496)
			(xy 120.953784 -163.84905) (xy 120.870726 -163.809934) (xy 120.861899 -163.806187) (xy 120.842781 -163.804911)
			(xy 120.824539 -163.810771) (xy 120.816878 -163.816538) (xy 120.782853 -163.843559) (xy 120.710459 -163.891613)
			(xy 120.633724 -163.93238) (xy 120.55338 -163.965469) (xy 120.470192 -163.990568) (xy 120.384953 -164.007435)
			(xy 120.298476 -164.01591) (xy 120.25503 -164.016436) (xy 120.213915 -164.015973) (xy 120.132035 -164.008388)
			(xy 120.051204 -163.99328) (xy 119.972113 -163.970779) (xy 119.895435 -163.941075) (xy 119.821825 -163.904423)
			(xy 119.751911 -163.861135) (xy 119.686289 -163.811581) (xy 119.62552 -163.756183) (xy 119.570122 -163.695414)
			(xy 119.520567 -163.629793) (xy 119.477279 -163.559879) (xy 119.440626 -163.486269) (xy 119.410922 -163.409591)
			(xy 119.38842 -163.330499) (xy 119.373312 -163.249669) (xy 119.365727 -163.167789) (xy 119.365268 -163.126674)
			(xy 91.076082 -163.126674) (xy 91.074618 -163.131296) (xy 91.074629 -163.148971) (xy 91.077288 -163.157408)
			(xy 91.089816 -163.193591) (xy 91.109393 -163.267622) (xy 91.122545 -163.34306) (xy 91.129174 -163.419348)
			(xy 91.129612 -163.457636) (xy 91.129114 -163.500412) (xy 91.120898 -163.585569) (xy 91.104536 -163.669543)
			(xy 91.080178 -163.751555) (xy 91.064588 -163.791392) (xy 91.061544 -163.799848) (xy 91.060879 -163.817795)
			(xy 91.063318 -163.826444) (xy 91.07787 -163.871922) (xy 91.098306 -163.9652) (xy 91.108623 -164.060131)
			(xy 91.109292 -164.107876) (xy 91.108825 -164.148987) (xy 91.101239 -164.230857) (xy 91.08613 -164.311679)
			(xy 91.063626 -164.390761) (xy 91.033921 -164.467428) (xy 90.997266 -164.541027) (xy 90.953976 -164.610929)
			(xy 90.904419 -164.676538) (xy 90.849019 -164.737293) (xy 90.788249 -164.792677) (xy 90.722626 -164.842215)
			(xy 90.652712 -164.885486) (xy 90.579103 -164.92212) (xy 90.502427 -164.951804) (xy 90.423339 -164.974286)
			(xy 90.342514 -164.989373) (xy 90.260641 -164.996936) (xy 90.21953 -164.997384) (xy 90.177921 -164.996892)
			(xy 90.095064 -164.989136) (xy 90.013294 -164.97368) (xy 89.933323 -164.950659) (xy 89.89441 -164.935916)
			(xy 89.88572 -164.932926) (xy 89.867362 -164.932654) (xy 89.858596 -164.935408) (xy 89.822497 -164.947854)
			(xy 89.748643 -164.967275) (xy 89.673397 -164.980297) (xy 89.597312 -164.986825) (xy 89.55913 -164.987224)
			(xy 89.520814 -164.986846) (xy 89.444461 -164.980317) (xy 89.368954 -164.967235) (xy 89.294855 -164.947698)
			(xy 89.258648 -164.935154) (xy 89.250332 -164.932568) (xy 89.232928 -164.932568) (xy 89.224612 -164.935154)
			(xy 89.188396 -164.947666) (xy 89.114296 -164.96719) (xy 89.038793 -164.980277) (xy 88.962445 -164.986828)
			(xy 88.92413 -164.987224) (xy 88.885814 -164.986846) (xy 88.809461 -164.980317) (xy 88.733954 -164.967235)
			(xy 88.659855 -164.947698) (xy 88.623648 -164.935154) (xy 88.615332 -164.932568) (xy 88.597928 -164.932568)
			(xy 88.589612 -164.935154) (xy 88.553396 -164.947666) (xy 88.479296 -164.96719) (xy 88.403793 -164.980277)
			(xy 88.327445 -164.986828) (xy 88.28913 -164.987224) (xy 88.250814 -164.986846) (xy 88.174461 -164.980317)
			(xy 88.098954 -164.967235) (xy 88.024855 -164.947698) (xy 87.988648 -164.935154) (xy 87.980332 -164.932568)
			(xy 87.962928 -164.932568) (xy 87.954612 -164.935154) (xy 87.918396 -164.947666) (xy 87.844296 -164.96719)
			(xy 87.768793 -164.980277) (xy 87.692445 -164.986828) (xy 87.65413 -164.987224) (xy 87.615814 -164.986846)
			(xy 87.539461 -164.980317) (xy 87.463954 -164.967235) (xy 87.389855 -164.947698) (xy 87.353648 -164.935154)
			(xy 87.345332 -164.932568) (xy 87.327928 -164.932568) (xy 87.319612 -164.935154) (xy 87.283487 -164.947638)
			(xy 87.209575 -164.96713) (xy 87.134265 -164.980216) (xy 87.058111 -164.9868) (xy 87.019892 -164.987224)
			(xy 87.01913 -164.987224) (xy 86.978023 -164.986759) (xy 86.896158 -164.979177) (xy 86.815342 -164.964075)
			(xy 86.736265 -164.941581) (xy 86.659599 -164.911888) (xy 86.586 -164.875249) (xy 86.516095 -164.831976)
			(xy 86.45048 -164.782438) (xy 86.389716 -164.727058) (xy 86.334319 -164.666309) (xy 86.284763 -164.600708)
			(xy 86.241471 -164.530815) (xy 86.204811 -164.457226) (xy 86.175097 -164.380569) (xy 86.152582 -164.301497)
			(xy 86.137457 -164.220686) (xy 86.129853 -164.138823) (xy 86.129368 -164.097716) (xy 2.509012 -164.097716)
			(xy 2.509012 -166.86276) (xy 61.046868 -166.86276) (xy 61.047433 -166.81799) (xy 61.056443 -166.728905)
			(xy 61.074347 -166.641174) (xy 61.100966 -166.555683) (xy 61.117988 -166.514272) (xy 61.121578 -166.504688)
			(xy 61.121563 -166.484239) (xy 61.117988 -166.474648) (xy 61.100968 -166.433235) (xy 61.074329 -166.347749)
			(xy 61.05642 -166.260018) (xy 61.047422 -166.17093) (xy 61.046868 -166.12616) (xy 61.047433 -166.08139)
			(xy 61.056443 -165.992305) (xy 61.074347 -165.904574) (xy 61.100966 -165.819083) (xy 61.117988 -165.777672)
			(xy 61.121578 -165.768088) (xy 61.121563 -165.747639) (xy 61.117988 -165.738048) (xy 61.100968 -165.696635)
			(xy 61.074329 -165.611149) (xy 61.05642 -165.523418) (xy 61.047422 -165.43433) (xy 61.046868 -165.38956)
			(xy 61.047314 -165.348449) (xy 61.054905 -165.266579) (xy 61.070019 -165.185759) (xy 61.092527 -165.106679)
			(xy 61.122236 -165.030013) (xy 61.158893 -164.956415) (xy 61.202185 -164.886514) (xy 61.251743 -164.820907)
			(xy 61.307144 -164.760153) (xy 61.367915 -164.70477) (xy 61.433537 -164.655232) (xy 61.503451 -164.611961)
			(xy 61.57706 -164.575327) (xy 61.653735 -164.545641) (xy 61.732822 -164.523157) (xy 61.813647 -164.508068)
			(xy 61.895519 -164.500502) (xy 61.93663 -164.500052) (xy 61.978234 -164.500535) (xy 62.061081 -164.508266)
			(xy 62.142846 -164.523695) (xy 62.222813 -164.546687) (xy 62.300286 -164.577041) (xy 62.374588 -164.614493)
			(xy 62.410086 -164.636196) (xy 62.419228 -164.641351) (xy 62.439942 -164.644569) (xy 62.460215 -164.639239)
			(xy 62.46876 -164.633148) (xy 62.502383 -164.607191) (xy 62.573762 -164.561136) (xy 62.649206 -164.522094)
			(xy 62.728027 -164.49042) (xy 62.809509 -164.466402) (xy 62.892908 -164.450259) (xy 62.977466 -164.442138)
			(xy 63.01994 -164.441632) (xy 63.020194 -164.441632) (xy 63.0613 -164.442118) (xy 63.143163 -164.449702)
			(xy 63.223977 -164.464805) (xy 63.303052 -164.487299) (xy 63.379716 -164.516993) (xy 63.453313 -164.553631)
			(xy 63.523217 -164.596903) (xy 63.58883 -164.64644) (xy 63.649594 -164.701818) (xy 63.70499 -164.762565)
			(xy 63.754546 -164.828164) (xy 63.797839 -164.898054) (xy 63.8345 -164.971641) (xy 63.864216 -165.048295)
			(xy 63.886734 -165.127364) (xy 63.901861 -165.208173) (xy 63.909469 -165.290034) (xy 63.909956 -165.33114)
			(xy 63.909389 -165.375909) (xy 63.900379 -165.464994) (xy 63.882475 -165.552725) (xy 63.855858 -165.638217)
			(xy 63.838836 -165.679628) (xy 63.83525 -165.689212) (xy 63.835264 -165.709661) (xy 63.838836 -165.719252)
			(xy 63.855836 -165.760605) (xy 63.882448 -165.845966) (xy 63.900356 -165.933568) (xy 63.903248 -165.962076)
			(xy 81.591411 -165.962076) (xy 81.595416 -165.856327) (xy 81.607406 -165.751184) (xy 81.627315 -165.647249)
			(xy 81.655026 -165.545117) (xy 81.690383 -165.445373) (xy 81.733181 -165.348589) (xy 81.783177 -165.255319)
			(xy 81.840084 -165.166098) (xy 81.903575 -165.081435) (xy 81.973287 -165.001817) (xy 82.048821 -164.927699)
			(xy 82.129744 -164.859506) (xy 82.215593 -164.797628) (xy 82.305876 -164.742421) (xy 82.400075 -164.694199)
			(xy 82.497652 -164.653239) (xy 82.598047 -164.619777) (xy 82.700685 -164.594003) (xy 82.804978 -164.576065)
			(xy 82.910329 -164.566066) (xy 83.016135 -164.564063) (xy 83.121789 -164.570068) (xy 83.226686 -164.584047)
			(xy 83.330226 -164.605918) (xy 83.431815 -164.635558) (xy 83.530872 -164.672796) (xy 83.626829 -164.717418)
			(xy 83.719136 -164.76917) (xy 83.807265 -164.827755) (xy 83.890711 -164.892837) (xy 83.968995 -164.964043)
			(xy 84.04167 -165.040966) (xy 84.10832 -165.123166) (xy 84.168562 -165.21017) (xy 84.222051 -165.301481)
			(xy 84.268482 -165.396576) (xy 84.307587 -165.49491) (xy 84.339144 -165.595921) (xy 84.362971 -165.699028)
			(xy 84.378932 -165.803642) (xy 84.386936 -165.909164) (xy 84.387436 -165.962076) (xy 90.989411 -165.962076)
			(xy 90.993416 -165.856327) (xy 91.005406 -165.751184) (xy 91.025315 -165.647249) (xy 91.053026 -165.545117)
			(xy 91.088383 -165.445373) (xy 91.131181 -165.348589) (xy 91.181177 -165.255319) (xy 91.238084 -165.166098)
			(xy 91.301575 -165.081435) (xy 91.371287 -165.001817) (xy 91.446821 -164.927699) (xy 91.527744 -164.859506)
			(xy 91.613593 -164.797628) (xy 91.703876 -164.742421) (xy 91.798075 -164.694199) (xy 91.895652 -164.653239)
			(xy 91.996047 -164.619777) (xy 92.098685 -164.594003) (xy 92.202978 -164.576065) (xy 92.308329 -164.566066)
			(xy 92.414135 -164.564063) (xy 92.519789 -164.570068) (xy 92.624686 -164.584047) (xy 92.728226 -164.605918)
			(xy 92.829815 -164.635558) (xy 92.928872 -164.672796) (xy 93.024829 -164.717418) (xy 93.117136 -164.76917)
			(xy 93.205265 -164.827755) (xy 93.288711 -164.892837) (xy 93.366995 -164.964043) (xy 93.43967 -165.040966)
			(xy 93.50632 -165.123166) (xy 93.566562 -165.21017) (xy 93.620051 -165.301481) (xy 93.666482 -165.396576)
			(xy 93.705587 -165.49491) (xy 93.737144 -165.595921) (xy 93.760971 -165.699028) (xy 93.776932 -165.803642)
			(xy 93.784936 -165.909164) (xy 93.785436 -165.962076) (xy 93.784936 -166.014988) (xy 93.776932 -166.12051)
			(xy 93.760971 -166.225124) (xy 93.737144 -166.328231) (xy 93.705587 -166.429242) (xy 93.666482 -166.527576)
			(xy 93.620051 -166.622671) (xy 93.566562 -166.713982) (xy 93.50632 -166.800986) (xy 93.43967 -166.883186)
			(xy 93.366995 -166.960109) (xy 93.288711 -167.031315) (xy 93.205265 -167.096397) (xy 93.117136 -167.154982)
			(xy 93.024829 -167.206734) (xy 92.928872 -167.251356) (xy 92.829815 -167.288594) (xy 92.728226 -167.318234)
			(xy 92.624686 -167.340105) (xy 92.519789 -167.354084) (xy 92.414135 -167.360089) (xy 92.308329 -167.358086)
			(xy 92.202978 -167.348087) (xy 92.098685 -167.330149) (xy 91.996047 -167.304375) (xy 91.895652 -167.270913)
			(xy 91.798075 -167.229953) (xy 91.703876 -167.181731) (xy 91.613593 -167.126524) (xy 91.527744 -167.064646)
			(xy 91.446821 -166.996453) (xy 91.371287 -166.922335) (xy 91.301575 -166.842717) (xy 91.238084 -166.758054)
			(xy 91.181177 -166.668833) (xy 91.131181 -166.575563) (xy 91.088383 -166.478779) (xy 91.053026 -166.379035)
			(xy 91.025315 -166.276903) (xy 91.005406 -166.172968) (xy 90.993416 -166.067825) (xy 90.989411 -165.962076)
			(xy 84.387436 -165.962076) (xy 84.386936 -166.014988) (xy 84.378932 -166.12051) (xy 84.362971 -166.225124)
			(xy 84.339144 -166.328231) (xy 84.307587 -166.429242) (xy 84.268482 -166.527576) (xy 84.222051 -166.622671)
			(xy 84.168562 -166.713982) (xy 84.10832 -166.800986) (xy 84.04167 -166.883186) (xy 83.968995 -166.960109)
			(xy 83.890711 -167.031315) (xy 83.807265 -167.096397) (xy 83.719136 -167.154982) (xy 83.626829 -167.206734)
			(xy 83.530872 -167.251356) (xy 83.431815 -167.288594) (xy 83.330226 -167.318234) (xy 83.226686 -167.340105)
			(xy 83.121789 -167.354084) (xy 83.016135 -167.360089) (xy 82.910329 -167.358086) (xy 82.804978 -167.348087)
			(xy 82.700685 -167.330149) (xy 82.598047 -167.304375) (xy 82.497652 -167.270913) (xy 82.400075 -167.229953)
			(xy 82.305876 -167.181731) (xy 82.215593 -167.126524) (xy 82.129744 -167.064646) (xy 82.048821 -166.996453)
			(xy 81.973287 -166.922335) (xy 81.903575 -166.842717) (xy 81.840084 -166.758054) (xy 81.783177 -166.668833)
			(xy 81.733181 -166.575563) (xy 81.690383 -166.478779) (xy 81.655026 -166.379035) (xy 81.627315 -166.276903)
			(xy 81.607406 -166.172968) (xy 81.595416 -166.067825) (xy 81.591411 -165.962076) (xy 63.903248 -165.962076)
			(xy 63.909379 -166.022525) (xy 63.909956 -166.067232) (xy 63.909956 -166.068248) (xy 63.909702 -166.079678)
			(xy 63.936181 -166.085625) (xy 63.988416 -166.100367) (xy 64.014096 -166.109142) (xy 64.022293 -166.111656)
			(xy 64.039427 -166.111656) (xy 64.047624 -166.109142) (xy 64.082842 -166.097202) (xy 64.154852 -166.078613)
			(xy 64.228174 -166.066171) (xy 64.302285 -166.059965) (xy 64.33947 -166.059612) (xy 64.376654 -166.059989)
			(xy 64.450761 -166.066209) (xy 64.524081 -166.078649) (xy 64.596093 -166.097221) (xy 64.631316 -166.109142)
			(xy 64.639513 -166.111656) (xy 64.656647 -166.111656) (xy 64.664844 -166.109142) (xy 64.699939 -166.097233)
			(xy 64.771698 -166.078689) (xy 64.844763 -166.066249) (xy 64.918616 -166.060001) (xy 64.955674 -166.059612)
			(xy 64.95669 -166.059612) (xy 64.998618 -166.060035) (xy 65.082094 -166.068005) (xy 65.164434 -166.083874)
			(xy 65.244893 -166.107498) (xy 65.322742 -166.138663) (xy 65.397276 -166.177087) (xy 65.46782 -166.222422)
			(xy 65.533735 -166.274258) (xy 65.594424 -166.332124) (xy 65.649338 -166.395498) (xy 65.69798 -166.463804)
			(xy 65.739908 -166.536425) (xy 65.774743 -166.612703) (xy 65.802169 -166.691946) (xy 65.821939 -166.773438)
			(xy 65.833873 -166.85644) (xy 65.837863 -166.9402) (xy 65.833873 -167.02396) (xy 65.821939 -167.106962)
			(xy 65.802169 -167.188454) (xy 65.774743 -167.267697) (xy 65.739908 -167.343975) (xy 65.69798 -167.416596)
			(xy 65.688295 -167.430196) (xy 351.432876 -167.430196) (xy 351.433453 -167.385427) (xy 351.442459 -167.296342)
			(xy 351.46036 -167.208611) (xy 351.486975 -167.123119) (xy 351.503996 -167.081708) (xy 351.507565 -167.072118)
			(xy 351.507564 -167.051674) (xy 351.503996 -167.042084) (xy 351.486956 -167.000679) (xy 351.460322 -166.91519)
			(xy 351.442419 -166.827456) (xy 351.433427 -166.738367) (xy 351.432876 -166.693596) (xy 351.433453 -166.648827)
			(xy 351.442459 -166.559742) (xy 351.46036 -166.472011) (xy 351.486975 -166.386519) (xy 351.503996 -166.345108)
			(xy 351.507565 -166.335518) (xy 351.507564 -166.315074) (xy 351.503996 -166.305484) (xy 351.486956 -166.264079)
			(xy 351.460322 -166.17859) (xy 351.442419 -166.090856) (xy 351.433427 -166.001767) (xy 351.432876 -165.956996)
			(xy 351.433349 -165.915886) (xy 351.440937 -165.834016) (xy 351.456047 -165.753196) (xy 351.478552 -165.674116)
			(xy 351.508259 -165.597449) (xy 351.544914 -165.523852) (xy 351.588204 -165.453951) (xy 351.63776 -165.388343)
			(xy 351.693159 -165.327588) (xy 351.753929 -165.272205) (xy 351.81955 -165.222667) (xy 351.889463 -165.179396)
			(xy 351.963071 -165.142761) (xy 352.039745 -165.113075) (xy 352.118832 -165.090592) (xy 352.199656 -165.075503)
			(xy 352.281528 -165.067937) (xy 352.322638 -165.067488) (xy 352.364242 -165.067962) (xy 352.44709 -165.075694)
			(xy 352.528855 -165.091124) (xy 352.608822 -165.114117) (xy 352.686295 -165.144474) (xy 352.760597 -165.181928)
			(xy 352.796094 -165.203632) (xy 352.805234 -165.208789) (xy 352.825949 -165.212002) (xy 352.846222 -165.206673)
			(xy 352.854768 -165.200584) (xy 352.888392 -165.174629) (xy 352.959771 -165.128573) (xy 353.035214 -165.08953)
			(xy 353.114035 -165.057855) (xy 353.195516 -165.033837) (xy 353.278916 -165.017694) (xy 353.363474 -165.009574)
			(xy 353.405948 -165.009068) (xy 353.406202 -165.009068) (xy 353.44731 -165.009511) (xy 353.529174 -165.017096)
			(xy 353.60999 -165.0322) (xy 353.689068 -165.054696) (xy 353.765733 -165.084391) (xy 353.839332 -165.121033)
			(xy 353.909237 -165.164307) (xy 353.974851 -165.213846) (xy 354.035616 -165.269227) (xy 354.091012 -165.329978)
			(xy 354.140567 -165.39558) (xy 354.183859 -165.465474) (xy 354.220519 -165.539063) (xy 354.250233 -165.615721)
			(xy 354.272749 -165.694793) (xy 354.287874 -165.775606) (xy 354.295479 -165.857468) (xy 354.295964 -165.898576)
			(xy 354.295409 -165.943346) (xy 354.286396 -166.032431) (xy 354.268489 -166.120162) (xy 354.241868 -166.205653)
			(xy 354.224844 -166.247064) (xy 354.221294 -166.256659) (xy 354.221285 -166.277097) (xy 354.224844 -166.286688)
			(xy 354.241856 -166.328036) (xy 354.268465 -166.413399) (xy 354.286369 -166.501003) (xy 354.289105 -166.527988)
			(xy 401.547076 -166.527988) (xy 401.54765 -166.483219) (xy 401.556657 -166.394134) (xy 401.574559 -166.306403)
			(xy 401.601175 -166.220911) (xy 401.618196 -166.1795) (xy 401.62177 -166.169912) (xy 401.621765 -166.149466)
			(xy 401.618196 -166.139876) (xy 401.601153 -166.098472) (xy 401.574521 -166.012983) (xy 401.556618 -165.925248)
			(xy 401.547627 -165.836159) (xy 401.547076 -165.791388) (xy 401.54765 -165.746619) (xy 401.556657 -165.657534)
			(xy 401.574559 -165.569803) (xy 401.601175 -165.484311) (xy 401.618196 -165.4429) (xy 401.62177 -165.433312)
			(xy 401.621765 -165.412866) (xy 401.618196 -165.403276) (xy 401.601153 -165.361872) (xy 401.574521 -165.276383)
			(xy 401.556618 -165.188648) (xy 401.547627 -165.099559) (xy 401.547076 -165.054788) (xy 401.547541 -165.013678)
			(xy 401.55513 -164.931808) (xy 401.570241 -164.850988) (xy 401.592747 -164.771907) (xy 401.622454 -164.695241)
			(xy 401.659109 -164.621643) (xy 401.7024 -164.551742) (xy 401.751957 -164.486134) (xy 401.807357 -164.42538)
			(xy 401.868127 -164.369997) (xy 401.933748 -164.320459) (xy 402.003662 -164.277187) (xy 402.07727 -164.240553)
			(xy 402.153944 -164.210867) (xy 402.233031 -164.188384) (xy 402.313856 -164.173295) (xy 402.395728 -164.165729)
			(xy 402.436838 -164.16528) (xy 402.478442 -164.165755) (xy 402.56129 -164.173487) (xy 402.643054 -164.188917)
			(xy 402.723022 -164.21191) (xy 402.800495 -164.242266) (xy 402.874796 -164.27972) (xy 402.910294 -164.301424)
			(xy 402.919434 -164.306582) (xy 402.940149 -164.309796) (xy 402.960422 -164.304466) (xy 402.968968 -164.298376)
			(xy 403.002591 -164.27242) (xy 403.07397 -164.226364) (xy 403.149414 -164.187321) (xy 403.228235 -164.155647)
			(xy 403.309716 -164.131629) (xy 403.393116 -164.115486) (xy 403.477674 -164.107366) (xy 403.520148 -164.10686)
			(xy 403.520402 -164.10686) (xy 403.561509 -164.107311) (xy 403.643374 -164.114895) (xy 403.724189 -164.13)
			(xy 403.803267 -164.152496) (xy 403.879931 -164.182191) (xy 403.95353 -164.218831) (xy 404.023434 -164.262106)
			(xy 404.089048 -164.311644) (xy 404.149813 -164.367025) (xy 404.205209 -164.427775) (xy 404.254764 -164.493376)
			(xy 404.298057 -164.563269) (xy 404.334716 -164.636858) (xy 404.364431 -164.713515) (xy 404.386947 -164.792587)
			(xy 404.402073 -164.873398) (xy 404.409679 -164.955261) (xy 404.410164 -164.996368) (xy 404.409606 -165.041138)
			(xy 404.400594 -165.130223) (xy 404.382688 -165.217954) (xy 404.356068 -165.303445) (xy 404.339044 -165.344856)
			(xy 404.335498 -165.354452) (xy 404.335487 -165.374889) (xy 404.339044 -165.38448) (xy 404.356053 -165.425829)
			(xy 404.382663 -165.511192) (xy 404.400568 -165.598795) (xy 404.409589 -165.687753) (xy 404.410164 -165.73246)
			(xy 404.410164 -165.733476) (xy 404.40991 -165.744906) (xy 404.436389 -165.750851) (xy 404.488624 -165.765594)
			(xy 404.514304 -165.77437) (xy 404.522501 -165.776884) (xy 404.539635 -165.776884) (xy 404.547832 -165.77437)
			(xy 404.58305 -165.762429) (xy 404.655059 -165.74384) (xy 404.728382 -165.731398) (xy 404.802492 -165.725192)
			(xy 404.839678 -165.72484) (xy 404.876862 -165.725213) (xy 404.95097 -165.731434) (xy 405.02429 -165.743875)
			(xy 405.096301 -165.762448) (xy 405.131524 -165.77437) (xy 405.139721 -165.776884) (xy 405.156855 -165.776884)
			(xy 405.165052 -165.77437) (xy 405.200146 -165.76246) (xy 405.271906 -165.743916) (xy 405.344971 -165.731476)
			(xy 405.418824 -165.725229) (xy 405.455882 -165.72484) (xy 405.456898 -165.72484) (xy 405.498822 -165.725407)
			(xy 405.582291 -165.733377) (xy 405.664623 -165.749245) (xy 405.745075 -165.772868) (xy 405.822917 -165.804031)
			(xy 405.897444 -165.842452) (xy 405.967982 -165.887784) (xy 406.033891 -165.939615) (xy 406.094575 -165.997477)
			(xy 406.149484 -166.060845) (xy 406.198121 -166.129146) (xy 406.240045 -166.20176) (xy 406.274876 -166.278031)
			(xy 406.302301 -166.357268) (xy 406.322068 -166.438752) (xy 406.334001 -166.521747) (xy 406.337991 -166.6055)
			(xy 406.334001 -166.689253) (xy 406.322068 -166.772248) (xy 406.302301 -166.853732) (xy 406.274876 -166.932969)
			(xy 406.240045 -167.00924) (xy 406.198121 -167.081854) (xy 406.149484 -167.150155) (xy 406.094575 -167.213523)
			(xy 406.033891 -167.271385) (xy 405.967982 -167.323216) (xy 405.897444 -167.368548) (xy 405.822917 -167.406969)
			(xy 405.745075 -167.438132) (xy 405.664623 -167.461755) (xy 405.582291 -167.477623) (xy 405.498822 -167.485593)
			(xy 405.456898 -167.486076) (xy 405.455882 -167.486076) (xy 405.418825 -167.485672) (xy 405.344976 -167.479407)
			(xy 405.271913 -167.466964) (xy 405.200153 -167.448432) (xy 405.165052 -167.436546) (xy 405.156855 -167.434032)
			(xy 405.139721 -167.434032) (xy 405.131524 -167.436546) (xy 405.102638 -167.446383) (xy 405.043785 -167.462529)
			(xy 405.013922 -167.468804) (xy 405.004334 -167.471159) (xy 404.987889 -167.482054) (xy 404.976796 -167.498367)
			(xy 404.974298 -167.50792) (xy 404.96417 -167.552275) (xy 404.936046 -167.638805) (xy 404.918164 -167.68064)
			(xy 404.914347 -167.690579) (xy 404.914353 -167.711846) (xy 404.918164 -167.721788) (xy 404.936394 -167.764388)
			(xy 404.964909 -167.852556) (xy 404.984099 -167.943213) (xy 404.993757 -168.035373) (xy 404.994364 -168.081706)
			(xy 404.994364 -168.082214) (xy 404.99386 -168.124562) (xy 404.985809 -168.208876) (xy 404.96978 -168.292042)
			(xy 404.945919 -168.373309) (xy 404.91444 -168.451939) (xy 404.875629 -168.52722) (xy 404.829839 -168.598472)
			(xy 404.777483 -168.665048) (xy 404.719035 -168.726346) (xy 404.655025 -168.781811) (xy 404.586033 -168.83094)
			(xy 404.512683 -168.873289) (xy 404.43564 -168.908473) (xy 404.355601 -168.936175) (xy 404.273292 -168.956143)
			(xy 404.189457 -168.968196) (xy 404.104856 -168.972227) (xy 404.020255 -168.968196) (xy 403.93642 -168.956143)
			(xy 403.854111 -168.936175) (xy 403.774072 -168.908473) (xy 403.697029 -168.873289) (xy 403.623679 -168.83094)
			(xy 403.554687 -168.781811) (xy 403.490677 -168.726346) (xy 403.432229 -168.665048) (xy 403.379873 -168.598472)
			(xy 403.334083 -168.52722) (xy 403.295272 -168.451939) (xy 403.263793 -168.373309) (xy 403.239932 -168.292042)
			(xy 403.223903 -168.208876) (xy 403.215852 -168.124562) (xy 403.215348 -168.082214) (xy 403.215348 -168.081706)
			(xy 403.215963 -168.035374) (xy 403.225632 -167.943217) (xy 403.244825 -167.852563) (xy 403.273334 -167.764394)
			(xy 403.291548 -167.721788) (xy 403.295348 -167.711844) (xy 403.295353 -167.690582) (xy 403.291548 -167.68064)
			(xy 403.273311 -167.637974) (xy 403.244764 -167.549684) (xy 403.225569 -167.458899) (xy 403.215934 -167.36661)
			(xy 403.215348 -167.320214) (xy 403.215953 -167.272404) (xy 403.226131 -167.177329) (xy 403.235668 -167.130476)
			(xy 403.23764 -167.118071) (xy 403.230727 -167.093957) (xy 403.22246 -167.084502) (xy 403.18182 -167.042338)
			(xy 403.178264 -167.0431) (xy 403.169416 -167.045411) (xy 403.154053 -167.055303) (xy 403.148292 -167.062404)
			(xy 403.123137 -167.095067) (xy 403.067717 -167.15611) (xy 403.006886 -167.211763) (xy 402.941166 -167.261548)
			(xy 402.871121 -167.305037) (xy 402.797352 -167.341858) (xy 402.720492 -167.371694) (xy 402.641201 -167.39429)
			(xy 402.560159 -167.409451) (xy 402.478062 -167.417047) (xy 402.436838 -167.417496) (xy 402.395733 -167.416951)
			(xy 402.313873 -167.409371) (xy 402.233061 -167.394271) (xy 402.153987 -167.37178) (xy 402.077325 -167.342091)
			(xy 402.003729 -167.305456) (xy 401.933826 -167.262187) (xy 401.868213 -167.212655) (xy 401.80745 -167.157281)
			(xy 401.752053 -167.096538) (xy 401.702497 -167.030943) (xy 401.659203 -166.961056) (xy 401.622541 -166.887473)
			(xy 401.592824 -166.810822) (xy 401.570304 -166.731756) (xy 401.555174 -166.65095) (xy 401.547564 -166.569093)
			(xy 401.547076 -166.527988) (xy 354.289105 -166.527988) (xy 354.295389 -166.589961) (xy 354.295964 -166.634668)
			(xy 354.295964 -166.635684) (xy 354.29571 -166.647114) (xy 354.322189 -166.653059) (xy 354.374424 -166.667802)
			(xy 354.400104 -166.676578) (xy 354.408301 -166.679092) (xy 354.425435 -166.679092) (xy 354.433632 -166.676578)
			(xy 354.468848 -166.664633) (xy 354.540859 -166.646046) (xy 354.614181 -166.633606) (xy 354.688292 -166.6274)
			(xy 354.725478 -166.627048) (xy 354.762662 -166.62742) (xy 354.83677 -166.633641) (xy 354.91009 -166.646083)
			(xy 354.982101 -166.664656) (xy 355.017324 -166.676578) (xy 355.025521 -166.679092) (xy 355.042655 -166.679092)
			(xy 355.050852 -166.676578) (xy 355.085946 -166.664669) (xy 355.157706 -166.646124) (xy 355.230771 -166.633684)
			(xy 355.304624 -166.627437) (xy 355.341682 -166.627048) (xy 355.342698 -166.627048) (xy 355.384622 -166.627599)
			(xy 355.468092 -166.635569) (xy 355.550425 -166.651437) (xy 355.630878 -166.67506) (xy 355.70872 -166.706224)
			(xy 355.783248 -166.744645) (xy 355.853787 -166.789977) (xy 355.919696 -166.841809) (xy 355.980381 -166.899671)
			(xy 356.03529 -166.96304) (xy 356.083927 -167.031341) (xy 356.125852 -167.103957) (xy 356.160684 -167.180228)
			(xy 356.188108 -167.259465) (xy 356.207876 -167.340951) (xy 356.219809 -167.423946) (xy 356.223799 -167.5077)
			(xy 356.219809 -167.591454) (xy 356.207876 -167.674449) (xy 356.188108 -167.755935) (xy 356.160684 -167.835172)
			(xy 356.125852 -167.911443) (xy 356.083927 -167.984059) (xy 356.03529 -168.05236) (xy 355.980381 -168.115729)
			(xy 355.919696 -168.173591) (xy 355.853787 -168.225423) (xy 355.783248 -168.270755) (xy 355.70872 -168.309176)
			(xy 355.630878 -168.34034) (xy 355.550425 -168.363963) (xy 355.468092 -168.379831) (xy 355.384622 -168.387801)
			(xy 355.342698 -168.388284) (xy 355.341682 -168.388284) (xy 355.304625 -168.387885) (xy 355.230776 -168.381619)
			(xy 355.157713 -168.369175) (xy 355.085953 -168.350641) (xy 355.050852 -168.338754) (xy 355.042655 -168.33624)
			(xy 355.025521 -168.33624) (xy 355.017324 -168.338754) (xy 354.989546 -168.348208) (xy 354.932984 -168.363843)
			(xy 354.904294 -168.369996) (xy 354.894532 -168.372423) (xy 354.877923 -168.383747) (xy 354.866932 -168.400579)
			(xy 354.86467 -168.410382) (xy 354.855142 -168.457509) (xy 354.827269 -168.549532) (xy 354.809044 -168.594024)
			(xy 354.805459 -168.603609) (xy 354.805473 -168.624057) (xy 354.809044 -168.633648) (xy 354.826071 -168.675024)
			(xy 354.852688 -168.760451) (xy 354.870591 -168.84812) (xy 354.879599 -168.937143) (xy 354.880164 -168.981882)
			(xy 354.880164 -168.982136) (xy 354.87966 -169.024484) (xy 354.871609 -169.108798) (xy 354.85558 -169.191964)
			(xy 354.831719 -169.273231) (xy 354.80024 -169.351861) (xy 354.761429 -169.427142) (xy 354.715639 -169.498394)
			(xy 354.663283 -169.56497) (xy 354.604835 -169.626268) (xy 354.540825 -169.681733) (xy 354.471833 -169.730862)
			(xy 354.398483 -169.773211) (xy 354.32144 -169.808395) (xy 354.241401 -169.836097) (xy 354.159092 -169.856065)
			(xy 354.075257 -169.868118) (xy 353.990656 -169.872149) (xy 353.906055 -169.868118) (xy 353.82222 -169.856065)
			(xy 353.739911 -169.836097) (xy 353.659872 -169.808395) (xy 353.582829 -169.773211) (xy 353.509479 -169.730862)
			(xy 353.440487 -169.681733) (xy 353.376477 -169.626268) (xy 353.318029 -169.56497) (xy 353.265673 -169.498394)
			(xy 353.219883 -169.427142) (xy 353.181072 -169.351861) (xy 353.149593 -169.273231) (xy 353.125732 -169.191964)
			(xy 353.109703 -169.108798) (xy 353.101652 -169.024484) (xy 353.101148 -168.982136) (xy 353.101148 -168.981882)
			(xy 353.101731 -168.937144) (xy 353.110743 -168.848123) (xy 353.128644 -168.760456) (xy 353.155252 -168.675028)
			(xy 353.172268 -168.633648) (xy 353.175811 -168.624051) (xy 353.175824 -168.603615) (xy 353.172268 -168.594024)
			(xy 353.155227 -168.55262) (xy 353.128597 -168.46713) (xy 353.110694 -168.379396) (xy 353.1017 -168.290307)
			(xy 353.101148 -168.245536) (xy 353.10149 -168.209754) (xy 353.107197 -168.138419) (xy 353.118619 -168.067773)
			(xy 353.126802 -168.032938) (xy 353.128529 -168.024629) (xy 353.126997 -168.007741) (xy 353.119979 -167.992303)
			(xy 353.114356 -167.985948) (xy 353.07397 -167.943276) (xy 353.064064 -167.945308) (xy 353.055164 -167.947623)
			(xy 353.039671 -167.957504) (xy 353.033838 -167.964612) (xy 353.008691 -167.997264) (xy 352.953283 -168.058281)
			(xy 352.892469 -168.113912) (xy 352.826771 -168.163681) (xy 352.756752 -168.207161) (xy 352.683013 -168.243979)
			(xy 352.606184 -168.273821) (xy 352.526925 -168.29643) (xy 352.445915 -168.311612) (xy 352.363848 -168.319237)
			(xy 352.322638 -168.319704) (xy 352.281533 -168.319151) (xy 352.199674 -168.311571) (xy 352.118862 -168.296471)
			(xy 352.039789 -168.273981) (xy 351.963127 -168.244292) (xy 351.889531 -168.207657) (xy 351.819629 -168.164389)
			(xy 351.754016 -168.114857) (xy 351.693252 -168.059484) (xy 351.637856 -167.998741) (xy 351.5883 -167.933147)
			(xy 351.545006 -167.863261) (xy 351.508343 -167.789678) (xy 351.478626 -167.713028) (xy 351.456106 -167.633963)
			(xy 351.440975 -167.553157) (xy 351.433364 -167.471301) (xy 351.432876 -167.430196) (xy 65.688295 -167.430196)
			(xy 65.649338 -167.484902) (xy 65.594424 -167.548276) (xy 65.533735 -167.606142) (xy 65.46782 -167.657978)
			(xy 65.397276 -167.703313) (xy 65.322742 -167.741737) (xy 65.244893 -167.772902) (xy 65.164434 -167.796526)
			(xy 65.082094 -167.812395) (xy 64.998618 -167.820365) (xy 64.95669 -167.820848) (xy 64.955674 -167.820848)
			(xy 64.918617 -167.820448) (xy 64.844768 -167.814181) (xy 64.771705 -167.801738) (xy 64.699945 -167.783204)
			(xy 64.664844 -167.771318) (xy 64.656647 -167.768804) (xy 64.639513 -167.768804) (xy 64.631316 -167.771318)
			(xy 64.597889 -167.782662) (xy 64.529607 -167.80059) (xy 64.494918 -167.807132) (xy 64.484907 -167.809437)
			(xy 64.467748 -167.820693) (xy 64.456372 -167.837772) (xy 64.454024 -167.847772) (xy 64.44452 -167.895628)
			(xy 64.416383 -167.989057) (xy 64.39789 -168.034208) (xy 64.394248 -168.043772) (xy 64.394124 -168.064219)
			(xy 64.397636 -168.073832) (xy 64.414658 -168.11521) (xy 64.441276 -168.200636) (xy 64.459181 -168.288304)
			(xy 64.46819 -168.377327) (xy 64.468756 -168.422066) (xy 64.468756 -168.42232) (xy 64.468252 -168.464668)
			(xy 64.460201 -168.548982) (xy 64.444172 -168.632148) (xy 64.420311 -168.713415) (xy 64.388832 -168.792045)
			(xy 64.350021 -168.867326) (xy 64.304231 -168.938578) (xy 64.251875 -169.005154) (xy 64.193427 -169.066452)
			(xy 64.129417 -169.121917) (xy 64.060425 -169.171046) (xy 63.987075 -169.213395) (xy 63.910032 -169.248579)
			(xy 63.829993 -169.276281) (xy 63.747684 -169.296249) (xy 63.663849 -169.308302) (xy 63.579248 -169.312333)
			(xy 63.494647 -169.308302) (xy 63.410812 -169.296249) (xy 63.328503 -169.276281) (xy 63.248464 -169.248579)
			(xy 63.171421 -169.213395) (xy 63.098071 -169.171046) (xy 63.029079 -169.121917) (xy 62.965069 -169.066452)
			(xy 62.906621 -169.005154) (xy 62.854265 -168.938578) (xy 62.808475 -168.867326) (xy 62.769664 -168.792045)
			(xy 62.738185 -168.713415) (xy 62.714324 -168.632148) (xy 62.698295 -168.548982) (xy 62.690244 -168.464668)
			(xy 62.68974 -168.42232) (xy 62.68974 -168.422066) (xy 62.690311 -168.377328) (xy 62.699325 -168.288306)
			(xy 62.71723 -168.200639) (xy 62.743842 -168.115211) (xy 62.76086 -168.073832) (xy 62.764412 -168.064238)
			(xy 62.76442 -168.043799) (xy 62.76086 -168.034208) (xy 62.743813 -167.992806) (xy 62.717185 -167.907315)
			(xy 62.699284 -167.81958) (xy 62.690292 -167.730491) (xy 62.68974 -167.68572) (xy 62.689828 -167.668048)
			(xy 62.691224 -167.632732) (xy 62.692534 -167.615108) (xy 62.692907 -167.605036) (xy 62.68662 -167.585904)
			(xy 62.673425 -167.57069) (xy 62.664594 -167.565832) (xy 62.566296 -167.516556) (xy 62.535816 -167.520366)
			(xy 62.524132 -167.53078) (xy 62.493735 -167.556935) (xy 62.428993 -167.604263) (xy 62.360251 -167.645567)
			(xy 62.288069 -167.680512) (xy 62.213032 -167.708812) (xy 62.135751 -167.730238) (xy 62.056854 -167.744617)
			(xy 61.976982 -167.75183) (xy 61.936884 -167.752268) (xy 61.93663 -167.752268) (xy 61.895524 -167.751759)
			(xy 61.813662 -167.744177) (xy 61.732849 -167.729076) (xy 61.653773 -167.706584) (xy 61.57711 -167.676893)
			(xy 61.503513 -167.640256) (xy 61.433609 -167.596985) (xy 61.367995 -167.547451) (xy 61.307231 -167.492074)
			(xy 61.251835 -167.431328) (xy 61.202279 -167.36573) (xy 61.158986 -167.295841) (xy 61.122325 -167.222256)
			(xy 61.092608 -167.145602) (xy 61.07009 -167.066534) (xy 61.054963 -166.985725) (xy 61.047355 -166.903866)
			(xy 61.046868 -166.86276) (xy 2.509012 -166.86276) (xy 2.509012 -170.29303) (xy 8.7249 -170.29303)
			(xy 8.7249 -169.42943) (xy 8.725386 -169.402179) (xy 8.733142 -169.348231) (xy 8.748497 -169.295936)
			(xy 8.771139 -169.246359) (xy 8.800605 -169.200509) (xy 8.836296 -169.159318) (xy 8.877487 -169.123627)
			(xy 8.923337 -169.094161) (xy 8.972914 -169.071519) (xy 9.025209 -169.056164) (xy 9.079157 -169.048408)
			(xy 9.133659 -169.048408) (xy 9.187607 -169.056164) (xy 9.239902 -169.071519) (xy 9.289479 -169.094161)
			(xy 9.335329 -169.123627) (xy 9.37652 -169.159318) (xy 9.412211 -169.200509) (xy 9.441677 -169.246359)
			(xy 9.464319 -169.295936) (xy 9.479674 -169.348231) (xy 9.48743 -169.402179) (xy 9.487916 -169.42943)
			(xy 9.487916 -169.857674) (xy 111.084868 -169.857674) (xy 111.085438 -169.812905) (xy 111.094447 -169.72382)
			(xy 111.112349 -169.636089) (xy 111.138966 -169.550597) (xy 111.155988 -169.509186) (xy 111.15957 -169.4996)
			(xy 111.15956 -169.479153) (xy 111.155988 -169.469562) (xy 111.13894 -169.42816) (xy 111.112309 -169.34267)
			(xy 111.094408 -169.254935) (xy 111.085418 -169.165845) (xy 111.084868 -169.121074) (xy 111.085438 -169.076305)
			(xy 111.094447 -168.98722) (xy 111.112349 -168.899489) (xy 111.138966 -168.813997) (xy 111.155988 -168.772586)
			(xy 111.15957 -168.763) (xy 111.15956 -168.742553) (xy 111.155988 -168.732962) (xy 111.13894 -168.69156)
			(xy 111.112309 -168.60607) (xy 111.094408 -168.518335) (xy 111.085418 -168.429245) (xy 111.084868 -168.384474)
			(xy 111.085274 -168.343358) (xy 111.092864 -168.261476) (xy 111.107976 -168.180645) (xy 111.130482 -168.101552)
			(xy 111.160191 -168.024873) (xy 111.196847 -167.951263) (xy 111.240139 -167.881349) (xy 111.289697 -167.815728)
			(xy 111.345099 -167.754959) (xy 111.405871 -167.699561) (xy 111.471495 -167.650007) (xy 111.541412 -167.60672)
			(xy 111.615025 -167.570068) (xy 111.691705 -167.540365) (xy 111.770799 -167.517863) (xy 111.851632 -167.502756)
			(xy 111.933514 -167.495171) (xy 111.97463 -167.494712) (xy 112.016241 -167.495173) (xy 112.099098 -167.502953)
			(xy 112.180867 -167.518431) (xy 112.260835 -167.541474) (xy 112.338303 -167.571879) (xy 112.412595 -167.609382)
			(xy 112.448086 -167.63111) (xy 112.457229 -167.636263) (xy 112.477942 -167.63948) (xy 112.498214 -167.634152)
			(xy 112.50676 -167.628062) (xy 112.540389 -167.602071) (xy 112.611783 -167.555946) (xy 112.687254 -167.516845)
			(xy 112.766112 -167.485124) (xy 112.847637 -167.461075) (xy 112.931085 -167.444915) (xy 113.015695 -167.436793)
			(xy 113.058194 -167.436292) (xy 113.099307 -167.436819) (xy 113.181182 -167.444405) (xy 113.262007 -167.459513)
			(xy 113.341094 -167.482013) (xy 113.417768 -167.511715) (xy 113.491374 -167.548365) (xy 113.561284 -167.59165)
			(xy 113.626903 -167.6412) (xy 113.68767 -167.696593) (xy 113.743067 -167.757357) (xy 113.792621 -167.822973)
			(xy 113.83591 -167.892881) (xy 113.872564 -167.966485) (xy 113.90227 -168.043156) (xy 113.924776 -168.122242)
			(xy 113.939888 -168.203067) (xy 113.947479 -168.284941) (xy 113.947956 -168.326054) (xy 113.947393 -168.370824)
			(xy 113.938383 -168.459909) (xy 113.920477 -168.54764) (xy 113.893859 -168.633131) (xy 113.876836 -168.674542)
			(xy 113.873299 -168.684141) (xy 113.873282 -168.704576) (xy 113.876836 -168.714166) (xy 113.89384 -168.755517)
			(xy 113.920451 -168.840879) (xy 113.938358 -168.928482) (xy 113.94738 -169.017439) (xy 113.947956 -169.062146)
			(xy 113.947956 -169.063162) (xy 113.947702 -169.074592) (xy 113.974181 -169.080538) (xy 114.026416 -169.095281)
			(xy 114.052096 -169.104056) (xy 114.060293 -169.10657) (xy 114.077427 -169.10657) (xy 114.085624 -169.104056)
			(xy 114.12084 -169.092095) (xy 114.192844 -169.073441) (xy 114.266165 -169.060932) (xy 114.34028 -169.054659)
			(xy 114.37747 -169.054272) (xy 114.414659 -169.054671) (xy 114.488772 -169.060958) (xy 114.562092 -169.073465)
			(xy 114.634098 -169.092103) (xy 114.669316 -169.104056) (xy 114.677513 -169.10657) (xy 114.694647 -169.10657)
			(xy 114.702844 -169.104056) (xy 114.738059 -169.092089) (xy 114.810062 -169.073437) (xy 114.883384 -169.06093)
			(xy 114.9575 -169.054658) (xy 114.99469 -169.054272) (xy 115.03663 -169.054667) (xy 115.120132 -169.062639)
			(xy 115.202497 -169.078513) (xy 115.28298 -169.102144) (xy 115.360853 -169.133319) (xy 115.43541 -169.171755)
			(xy 115.505975 -169.217104) (xy 115.57191 -169.268955) (xy 115.632618 -169.326839) (xy 115.687549 -169.390232)
			(xy 115.736205 -169.458559) (xy 115.778146 -169.531202) (xy 115.812991 -169.607503) (xy 115.840426 -169.68677)
			(xy 115.860202 -169.768287) (xy 115.87214 -169.851314) (xy 115.876131 -169.9351) (xy 115.87214 -170.018886)
			(xy 115.860202 -170.101913) (xy 115.840426 -170.18343) (xy 115.812991 -170.262697) (xy 115.778146 -170.338998)
			(xy 115.736205 -170.411641) (xy 115.687549 -170.479968) (xy 115.632618 -170.543361) (xy 115.57191 -170.601245)
			(xy 115.505975 -170.653096) (xy 115.498571 -170.657854) (xy 161.052951 -170.657854) (xy 161.052951 -170.603346)
			(xy 161.060709 -170.549393) (xy 161.076066 -170.497093) (xy 161.09871 -170.447511) (xy 161.12818 -170.401657)
			(xy 161.163876 -170.360463) (xy 161.205071 -170.324769) (xy 161.250927 -170.295301) (xy 161.30051 -170.27266)
			(xy 161.352811 -170.257305) (xy 161.406764 -170.24955) (xy 161.434018 -170.249088) (xy 162.297618 -170.249088)
			(xy 162.324868 -170.249583) (xy 162.378813 -170.257342) (xy 162.431105 -170.272698) (xy 162.48068 -170.29534)
			(xy 162.526528 -170.324806) (xy 162.567715 -170.360498) (xy 162.603404 -170.401687) (xy 162.632869 -170.447536)
			(xy 162.655508 -170.497111) (xy 162.670862 -170.549404) (xy 162.678618 -170.60335) (xy 162.678618 -170.65785)
			(xy 162.670862 -170.711796) (xy 162.655508 -170.764089) (xy 162.632869 -170.813664) (xy 162.603404 -170.859513)
			(xy 162.567715 -170.900702) (xy 162.526528 -170.936394) (xy 162.48068 -170.96586) (xy 162.431105 -170.988502)
			(xy 162.378813 -171.003858) (xy 162.324868 -171.011617) (xy 162.297618 -171.012104) (xy 161.434018 -171.012104)
			(xy 161.406764 -171.01165) (xy 161.352811 -171.003895) (xy 161.30051 -170.98854) (xy 161.250927 -170.965899)
			(xy 161.205071 -170.936431) (xy 161.163876 -170.900737) (xy 161.12818 -170.859543) (xy 161.09871 -170.813689)
			(xy 161.076066 -170.764107) (xy 161.060709 -170.711807) (xy 161.052951 -170.657854) (xy 115.498571 -170.657854)
			(xy 115.43541 -170.698445) (xy 115.360853 -170.736881) (xy 115.28298 -170.768056) (xy 115.202497 -170.791687)
			(xy 115.120132 -170.807561) (xy 115.03663 -170.815533) (xy 114.99469 -170.816016) (xy 114.9575 -170.815629)
			(xy 114.883387 -170.809339) (xy 114.810068 -170.796828) (xy 114.738062 -170.778187) (xy 114.702844 -170.766232)
			(xy 114.694647 -170.763718) (xy 114.677513 -170.763718) (xy 114.669316 -170.766232) (xy 114.625188 -170.781068)
			(xy 114.534574 -170.80245) (xy 114.488468 -170.808904) (xy 114.478735 -170.810567) (xy 114.461516 -170.820188)
			(xy 114.449244 -170.83563) (xy 114.44605 -170.844972) (xy 114.43848 -170.870441) (xy 114.420685 -170.920512)
			(xy 114.41049 -170.945048) (xy 114.406882 -170.954622) (xy 114.406736 -170.97506) (xy 114.410236 -170.984672)
			(xy 114.427271 -171.026045) (xy 114.453886 -171.111473) (xy 114.471787 -171.199143) (xy 114.480792 -171.288167)
			(xy 114.481356 -171.332906) (xy 114.481356 -171.33316) (xy 114.480852 -171.375508) (xy 114.472801 -171.459822)
			(xy 114.456772 -171.542988) (xy 114.432911 -171.624255) (xy 114.401432 -171.702885) (xy 114.362621 -171.778166)
			(xy 114.316831 -171.849418) (xy 114.264475 -171.915994) (xy 114.206027 -171.977292) (xy 114.142017 -172.032757)
			(xy 114.073025 -172.081886) (xy 113.999675 -172.124235) (xy 113.922632 -172.159419) (xy 113.842593 -172.187121)
			(xy 113.760284 -172.207089) (xy 113.676449 -172.219142) (xy 113.591848 -172.223173) (xy 113.507247 -172.219142)
			(xy 113.423412 -172.207089) (xy 113.341103 -172.187121) (xy 113.261064 -172.159419) (xy 113.184021 -172.124235)
			(xy 113.110671 -172.081886) (xy 113.041679 -172.032757) (xy 112.977669 -171.977292) (xy 112.919221 -171.915994)
			(xy 112.866865 -171.849418) (xy 112.821075 -171.778166) (xy 112.782264 -171.702885) (xy 112.750785 -171.624255)
			(xy 112.726924 -171.542988) (xy 112.710895 -171.459822) (xy 112.702844 -171.375508) (xy 112.70234 -171.33316)
			(xy 112.70234 -171.332906) (xy 112.702891 -171.288167) (xy 112.711911 -171.199145) (xy 112.729821 -171.111478)
			(xy 112.75644 -171.026051) (xy 112.77346 -170.984672) (xy 112.777047 -170.975088) (xy 112.777032 -170.954639)
			(xy 112.77346 -170.945048) (xy 112.757652 -170.906707) (xy 112.732373 -170.827716) (xy 112.714548 -170.746717)
			(xy 112.70433 -170.664411) (xy 112.702594 -170.622976) (xy 112.702594 -170.622722) (xy 112.701955 -170.613271)
			(xy 112.694549 -170.595846) (xy 112.681333 -170.582289) (xy 112.672876 -170.578018) (xy 112.589818 -170.540172)
			(xy 112.581121 -170.536666) (xy 112.562416 -170.535564) (xy 112.544562 -170.541248) (xy 112.536986 -170.546776)
			(xy 112.536986 -170.54703) (xy 112.536478 -170.54703) (xy 112.502475 -170.574102) (xy 112.430107 -170.622247)
			(xy 112.353386 -170.663099) (xy 112.273043 -170.696267) (xy 112.189846 -170.721435) (xy 112.104591 -170.738363)
			(xy 112.01809 -170.746889) (xy 111.97463 -170.747436) (xy 111.933515 -170.746973) (xy 111.851635 -170.739388)
			(xy 111.770804 -170.72428) (xy 111.691713 -170.701779) (xy 111.615035 -170.672075) (xy 111.541425 -170.635423)
			(xy 111.471511 -170.592135) (xy 111.405889 -170.542581) (xy 111.34512 -170.487183) (xy 111.289722 -170.426414)
			(xy 111.240167 -170.360793) (xy 111.196879 -170.290879) (xy 111.160226 -170.217269) (xy 111.130522 -170.140591)
			(xy 111.10802 -170.061499) (xy 111.092912 -169.980669) (xy 111.085327 -169.898789) (xy 111.084868 -169.857674)
			(xy 9.487916 -169.857674) (xy 9.487916 -170.29303) (xy 9.48743 -170.320281) (xy 9.479674 -170.374229)
			(xy 9.464319 -170.426524) (xy 9.441677 -170.476101) (xy 9.412211 -170.521951) (xy 9.37652 -170.563142)
			(xy 9.335329 -170.598833) (xy 9.289479 -170.628299) (xy 9.239902 -170.650941) (xy 9.187607 -170.666296)
			(xy 9.133659 -170.674052) (xy 9.079157 -170.674052) (xy 9.025209 -170.666296) (xy 8.972914 -170.650941)
			(xy 8.923337 -170.628299) (xy 8.877487 -170.598833) (xy 8.836296 -170.563142) (xy 8.800605 -170.521951)
			(xy 8.771139 -170.476101) (xy 8.748497 -170.426524) (xy 8.733142 -170.374229) (xy 8.725386 -170.320281)
			(xy 8.7249 -170.29303) (xy 2.509012 -170.29303) (xy 2.509012 -173.07814) (xy 8.7249 -173.07814) (xy 8.7249 -172.21454)
			(xy 8.725386 -172.187289) (xy 8.733142 -172.133341) (xy 8.748497 -172.081046) (xy 8.771139 -172.031469)
			(xy 8.800605 -171.985619) (xy 8.836296 -171.944428) (xy 8.877487 -171.908737) (xy 8.923337 -171.879271)
			(xy 8.972914 -171.856629) (xy 9.025209 -171.841274) (xy 9.079157 -171.833518) (xy 9.133659 -171.833518)
			(xy 9.187607 -171.841274) (xy 9.239902 -171.856629) (xy 9.289479 -171.879271) (xy 9.335329 -171.908737)
			(xy 9.37652 -171.944428) (xy 9.412211 -171.985619) (xy 9.441677 -172.031469) (xy 9.464319 -172.081046)
			(xy 9.479674 -172.133341) (xy 9.48743 -172.187289) (xy 9.487916 -172.21454) (xy 9.487916 -173.07814)
			(xy 9.48743 -173.105391) (xy 9.479674 -173.159339) (xy 9.464319 -173.211634) (xy 9.441677 -173.261211)
			(xy 9.412211 -173.307061) (xy 9.37652 -173.348252) (xy 9.335329 -173.383943) (xy 9.289479 -173.413409)
			(xy 9.239902 -173.436051) (xy 9.187607 -173.451406) (xy 9.133659 -173.459162) (xy 9.079157 -173.459162)
			(xy 9.025209 -173.451406) (xy 8.972914 -173.436051) (xy 8.923337 -173.413409) (xy 8.877487 -173.383943)
			(xy 8.836296 -173.348252) (xy 8.800605 -173.307061) (xy 8.771139 -173.261211) (xy 8.748497 -173.211634)
			(xy 8.733142 -173.159339) (xy 8.725386 -173.105391) (xy 8.7249 -173.07814) (xy 2.509012 -173.07814)
			(xy 2.509012 -175.848264) (xy 8.7249 -175.848264) (xy 8.7249 -174.984664) (xy 8.725386 -174.957413)
			(xy 8.733142 -174.903465) (xy 8.748497 -174.85117) (xy 8.771139 -174.801593) (xy 8.800605 -174.755743)
			(xy 8.836296 -174.714552) (xy 8.877487 -174.678861) (xy 8.923337 -174.649395) (xy 8.972914 -174.626753)
			(xy 9.025209 -174.611398) (xy 9.079157 -174.603642) (xy 9.133659 -174.603642) (xy 9.187607 -174.611398)
			(xy 9.239902 -174.626753) (xy 9.289479 -174.649395) (xy 9.335329 -174.678861) (xy 9.37652 -174.714552)
			(xy 9.412211 -174.755743) (xy 9.441677 -174.801593) (xy 9.464319 -174.85117) (xy 9.479674 -174.903465)
			(xy 9.48743 -174.957413) (xy 9.487916 -174.984664) (xy 9.487916 -175.559974) (xy 69.360288 -175.559974)
			(xy 69.360857 -175.515205) (xy 69.369865 -175.42612) (xy 69.387768 -175.338388) (xy 69.414386 -175.252897)
			(xy 69.431408 -175.211486) (xy 69.434989 -175.2019) (xy 69.43498 -175.181453) (xy 69.431408 -175.171862)
			(xy 69.414355 -175.130462) (xy 69.387726 -175.044971) (xy 69.369827 -174.957236) (xy 69.360838 -174.868145)
			(xy 69.360288 -174.823374) (xy 69.360857 -174.778605) (xy 69.369865 -174.68952) (xy 69.387768 -174.601788)
			(xy 69.414386 -174.516297) (xy 69.431408 -174.474886) (xy 69.434989 -174.4653) (xy 69.43498 -174.444853)
			(xy 69.431408 -174.435262) (xy 69.414355 -174.393862) (xy 69.387726 -174.308371) (xy 69.369827 -174.220636)
			(xy 69.360838 -174.131545) (xy 69.360288 -174.086774) (xy 69.360674 -174.045657) (xy 69.368264 -173.963775)
			(xy 69.383377 -173.882942) (xy 69.405884 -173.803848) (xy 69.435593 -173.727169) (xy 69.47225 -173.653557)
			(xy 69.515543 -173.583643) (xy 69.565103 -173.518021) (xy 69.620506 -173.457252) (xy 69.681279 -173.401854)
			(xy 69.746905 -173.3523) (xy 69.816824 -173.309013) (xy 69.890438 -173.272362) (xy 69.96712 -173.24266)
			(xy 70.046216 -173.220159) (xy 70.12705 -173.205053) (xy 70.208933 -173.19747) (xy 70.25005 -173.197012)
			(xy 70.29166 -173.197513) (xy 70.374516 -173.205285) (xy 70.456284 -173.220756) (xy 70.536252 -173.243791)
			(xy 70.613721 -173.274189) (xy 70.688014 -173.311686) (xy 70.723506 -173.33341) (xy 70.73264 -173.338581)
			(xy 70.753359 -173.341792) (xy 70.773635 -173.336456) (xy 70.78218 -173.330362) (xy 70.815836 -173.304408)
			(xy 70.887226 -173.258279) (xy 70.962691 -173.219173) (xy 71.041544 -173.187448) (xy 71.123065 -173.163392)
			(xy 71.20651 -173.147226) (xy 71.291116 -173.139097) (xy 71.333614 -173.138592) (xy 71.374727 -173.139099)
			(xy 71.456602 -173.146687) (xy 71.537428 -173.161797) (xy 71.616516 -173.1843) (xy 71.693189 -173.214003)
			(xy 71.703445 -173.21911) (xy 393.739116 -173.21911) (xy 393.739743 -173.172708) (xy 393.749432 -173.08041)
			(xy 393.768686 -172.989625) (xy 393.797294 -172.90134) (xy 393.81557 -172.858684) (xy 393.819371 -172.84874)
			(xy 393.819374 -172.827478) (xy 393.81557 -172.817536) (xy 393.797307 -172.774875) (xy 393.768715 -172.686587)
			(xy 393.749458 -172.595804) (xy 393.739745 -172.503511) (xy 393.739116 -172.45711) (xy 393.739622 -172.415997)
			(xy 393.747208 -172.33412) (xy 393.762316 -172.253293) (xy 393.784818 -172.174205) (xy 393.81452 -172.097531)
			(xy 393.851171 -172.023924) (xy 393.894457 -171.954012) (xy 393.944008 -171.888393) (xy 393.999403 -171.827626)
			(xy 394.060168 -171.772229) (xy 394.125786 -171.722675) (xy 394.195696 -171.679387) (xy 394.269301 -171.642733)
			(xy 394.345975 -171.613028) (xy 394.425062 -171.590524) (xy 394.505889 -171.575413) (xy 394.587765 -171.567824)
			(xy 394.628878 -171.567348) (xy 394.670013 -171.567796) (xy 394.75193 -171.575416) (xy 394.832794 -171.590566)
			(xy 394.911913 -171.613115) (xy 394.988614 -171.642872) (xy 395.06224 -171.679583) (xy 395.132163 -171.722933)
			(xy 395.197785 -171.772553) (xy 395.258547 -171.828019) (xy 395.313929 -171.888856) (xy 395.339062 -171.921424)
			(xy 395.345281 -171.928954) (xy 395.36201 -171.939002) (xy 395.371574 -171.940982) (xy 395.41286 -171.948033)
			(xy 395.493962 -171.968978) (xy 395.572736 -171.997455) (xy 395.648484 -172.033212) (xy 395.720535 -172.075931)
			(xy 395.78825 -172.125234) (xy 395.851031 -172.180685) (xy 395.908321 -172.241793) (xy 395.959613 -172.308015)
			(xy 396.004452 -172.378766) (xy 396.042441 -172.453419) (xy 396.073244 -172.531313) (xy 396.096588 -172.611757)
			(xy 396.112266 -172.69404) (xy 396.120139 -172.777432) (xy 396.12062 -172.819314) (xy 396.120152 -172.860082)
			(xy 396.112652 -172.941273) (xy 396.097752 -173.021436) (xy 396.075577 -173.099899) (xy 396.046313 -173.176003)
			(xy 396.028672 -173.21276) (xy 396.024359 -173.222451) (xy 396.023438 -173.243625) (xy 396.026894 -173.253654)
			(xy 396.041217 -173.292003) (xy 396.063564 -173.370761) (xy 396.07857 -173.451241) (xy 396.086111 -173.53276)
			(xy 396.086584 -173.573694) (xy 396.086007 -173.618463) (xy 396.077001 -173.707548) (xy 396.0591 -173.795279)
			(xy 396.032485 -173.880771) (xy 396.015464 -173.922182) (xy 396.011903 -173.931774) (xy 396.0119 -173.952215)
			(xy 396.015464 -173.961806) (xy 396.032477 -174.003153) (xy 396.059087 -174.088517) (xy 396.076991 -174.17612)
			(xy 396.08601 -174.265079) (xy 396.086584 -174.309786) (xy 396.086584 -174.310802) (xy 396.08633 -174.322232)
			(xy 396.112809 -174.328178) (xy 396.165044 -174.342921) (xy 396.190724 -174.351696) (xy 396.198921 -174.35421)
			(xy 396.216055 -174.35421) (xy 396.224252 -174.351696) (xy 396.259466 -174.339729) (xy 396.33147 -174.321076)
			(xy 396.404792 -174.308569) (xy 396.478908 -174.302297) (xy 396.516098 -174.301912) (xy 396.553288 -174.302301)
			(xy 396.627401 -174.30859) (xy 396.70072 -174.3211) (xy 396.772726 -174.339741) (xy 396.807944 -174.351696)
			(xy 396.816141 -174.35421) (xy 396.833275 -174.35421) (xy 396.841472 -174.351696) (xy 396.876685 -174.339723)
			(xy 396.948689 -174.321072) (xy 397.022011 -174.308567) (xy 397.096127 -174.302297) (xy 397.133318 -174.301912)
			(xy 397.175254 -174.302444) (xy 397.258746 -174.310418) (xy 397.341102 -174.326292) (xy 397.421577 -174.349923)
			(xy 397.49944 -174.381096) (xy 397.573988 -174.41953) (xy 397.644545 -174.464875) (xy 397.710473 -174.516722)
			(xy 397.771173 -174.574601) (xy 397.826097 -174.637988) (xy 397.874747 -174.706309) (xy 397.916683 -174.778944)
			(xy 397.951524 -174.855237) (xy 397.978955 -174.934497) (xy 397.998729 -175.016005) (xy 398.010665 -175.099023)
			(xy 398.014656 -175.1828) (xy 398.010665 -175.266577) (xy 397.998729 -175.349595) (xy 397.978955 -175.431103)
			(xy 397.951524 -175.510363) (xy 397.916683 -175.586656) (xy 397.874747 -175.659291) (xy 397.826097 -175.727612)
			(xy 397.771173 -175.790999) (xy 397.710473 -175.848878) (xy 397.644545 -175.900725) (xy 397.573988 -175.94607)
			(xy 397.49944 -175.984504) (xy 397.421577 -176.015677) (xy 397.341102 -176.039308) (xy 397.258746 -176.055182)
			(xy 397.175254 -176.063156) (xy 397.133318 -176.063656) (xy 397.096129 -176.063259) (xy 397.022016 -176.056971)
			(xy 396.948696 -176.044464) (xy 396.87669 -176.025825) (xy 396.841472 -176.013872) (xy 396.833275 -176.011358)
			(xy 396.816141 -176.011358) (xy 396.807944 -176.013872) (xy 396.778999 -176.023726) (xy 396.720017 -176.039869)
			(xy 396.690088 -176.04613) (xy 396.680511 -176.048515) (xy 396.664071 -176.059402) (xy 396.652972 -176.0757)
			(xy 396.650464 -176.085246) (xy 396.640294 -176.12901) (xy 396.612299 -176.21439) (xy 396.594584 -176.25568)
			(xy 396.590807 -176.265631) (xy 396.590789 -176.286886) (xy 396.594584 -176.296828) (xy 396.612789 -176.339438)
			(xy 396.641312 -176.427603) (xy 396.660509 -176.518256) (xy 396.670174 -176.610414) (xy 396.670784 -176.656746)
			(xy 396.670784 -176.657254) (xy 396.67028 -176.699602) (xy 396.662229 -176.783916) (xy 396.6462 -176.867082)
			(xy 396.622339 -176.948349) (xy 396.59086 -177.026979) (xy 396.552049 -177.10226) (xy 396.506259 -177.173512)
			(xy 396.453903 -177.240088) (xy 396.395455 -177.301386) (xy 396.331445 -177.356851) (xy 396.262453 -177.40598)
			(xy 396.189103 -177.448329) (xy 396.11206 -177.483513) (xy 396.032021 -177.511215) (xy 395.949712 -177.531183)
			(xy 395.865877 -177.543236) (xy 395.781276 -177.547267) (xy 395.696675 -177.543236) (xy 395.61284 -177.531183)
			(xy 395.530531 -177.511215) (xy 395.450492 -177.483513) (xy 395.373449 -177.448329) (xy 395.300099 -177.40598)
			(xy 395.231107 -177.356851) (xy 395.167097 -177.301386) (xy 395.108649 -177.240088) (xy 395.056293 -177.173512)
			(xy 395.010503 -177.10226) (xy 394.971692 -177.026979) (xy 394.940213 -176.948349) (xy 394.916352 -176.867082)
			(xy 394.900323 -176.783916) (xy 394.892272 -176.699602) (xy 394.891768 -176.657254) (xy 394.891768 -176.656746)
			(xy 394.892395 -176.610415) (xy 394.902061 -176.518257) (xy 394.92125 -176.427603) (xy 394.949756 -176.339434)
			(xy 394.967968 -176.296828) (xy 394.971802 -176.286894) (xy 394.971784 -176.265622) (xy 394.967968 -176.25568)
			(xy 394.949707 -176.213025) (xy 394.921167 -176.12473) (xy 394.901979 -176.033943) (xy 394.89235 -175.941651)
			(xy 394.891768 -175.895254) (xy 394.89209 -175.858508) (xy 394.898067 -175.785262) (xy 394.903706 -175.74895)
			(xy 394.905149 -175.737024) (xy 394.898112 -175.714088) (xy 394.890244 -175.705008) (xy 394.824966 -175.637698)
			(xy 394.80236 -175.629824) (xy 394.790168 -175.631602) (xy 394.748357 -175.636737) (xy 394.664175 -175.639973)
			(xy 394.580064 -175.635239) (xy 394.496776 -175.622575) (xy 394.415059 -175.602096) (xy 394.335643 -175.573985)
			(xy 394.259239 -175.538493) (xy 394.186532 -175.495939) (xy 394.118173 -175.446704) (xy 394.054773 -175.391227)
			(xy 393.996901 -175.330007) (xy 393.945075 -175.26359) (xy 393.899757 -175.192573) (xy 393.861356 -175.11759)
			(xy 393.830213 -175.039313) (xy 393.806608 -174.958443) (xy 393.790753 -174.875704) (xy 393.782789 -174.791836)
			(xy 393.782296 -174.749714) (xy 393.782793 -174.706976) (xy 393.790968 -174.621894) (xy 393.807264 -174.537986)
			(xy 393.831529 -174.456028) (xy 393.847066 -174.416212) (xy 393.850705 -174.406179) (xy 393.85003 -174.384863)
			(xy 393.845796 -174.375064) (xy 393.828734 -174.338786) (xy 393.800425 -174.263775) (xy 393.778984 -174.18652)
			(xy 393.764586 -174.107649) (xy 393.757348 -174.027801) (xy 393.756896 -173.987714) (xy 393.757452 -173.943459)
			(xy 393.766275 -173.855391) (xy 393.783795 -173.768633) (xy 393.809839 -173.684042) (xy 393.826492 -173.643036)
			(xy 393.830085 -173.632871) (xy 393.829579 -173.611348) (xy 393.825476 -173.60138) (xy 393.808875 -173.565511)
			(xy 393.781358 -173.491412) (xy 393.760529 -173.415162) (xy 393.746554 -173.337364) (xy 393.739543 -173.258632)
			(xy 393.739116 -173.21911) (xy 71.703445 -173.21911) (xy 71.766795 -173.250654) (xy 71.836706 -173.29394)
			(xy 71.902324 -173.343492) (xy 71.963091 -173.398886) (xy 72.018488 -173.459651) (xy 72.068042 -173.525268)
			(xy 72.11133 -173.595177) (xy 72.147984 -173.668781) (xy 72.17769 -173.745454) (xy 72.200196 -173.82454)
			(xy 72.215308 -173.905366) (xy 72.222899 -173.987241) (xy 72.223376 -174.028354) (xy 72.22282 -174.073124)
			(xy 72.213808 -174.162209) (xy 72.195901 -174.24994) (xy 72.16928 -174.335431) (xy 72.152256 -174.376842)
			(xy 72.148718 -174.38644) (xy 72.148701 -174.406876) (xy 72.152256 -174.416466) (xy 72.169272 -174.457846)
			(xy 72.195896 -174.543271) (xy 72.213802 -174.630939) (xy 72.222811 -174.719961) (xy 72.223376 -174.7647)
			(xy 72.223376 -174.765208) (xy 72.223122 -174.77867) (xy 72.249601 -174.784615) (xy 72.301836 -174.799358)
			(xy 72.327516 -174.808134) (xy 72.335713 -174.810648) (xy 72.352847 -174.810648) (xy 72.361044 -174.808134)
			(xy 72.39626 -174.796188) (xy 72.46827 -174.777601) (xy 72.541593 -174.765161) (xy 72.615704 -174.758956)
			(xy 72.65289 -174.758604) (xy 72.690074 -174.75897) (xy 72.764182 -174.765192) (xy 72.837502 -174.777635)
			(xy 72.909513 -174.796211) (xy 72.944736 -174.808134) (xy 72.952933 -174.810648) (xy 72.970067 -174.810648)
			(xy 72.978264 -174.808134) (xy 73.013366 -174.796247) (xy 73.085122 -174.777697) (xy 73.158185 -174.765251)
			(xy 73.232036 -174.758997) (xy 73.269094 -174.758604) (xy 73.27011 -174.758604) (xy 73.312036 -174.759059)
			(xy 73.395508 -174.767031) (xy 73.477845 -174.7829) (xy 73.5583 -174.806525) (xy 73.636145 -174.83769)
			(xy 73.710676 -174.876114) (xy 73.781216 -174.921448) (xy 73.847128 -174.973283) (xy 73.907814 -175.031148)
			(xy 73.962725 -175.094519) (xy 74.011364 -175.162823) (xy 74.053289 -175.235441) (xy 74.088123 -175.311716)
			(xy 74.115548 -175.390956) (xy 74.135316 -175.472444) (xy 74.14725 -175.555443) (xy 74.15124 -175.6392)
			(xy 74.14725 -175.722957) (xy 74.135316 -175.805956) (xy 74.115548 -175.887444) (xy 74.088123 -175.966684)
			(xy 74.053289 -176.042959) (xy 74.01685 -176.106074) (xy 102.855268 -176.106074) (xy 102.855838 -176.061305)
			(xy 102.864847 -175.97222) (xy 102.882749 -175.884489) (xy 102.909366 -175.798997) (xy 102.926388 -175.757586)
			(xy 102.92997 -175.748) (xy 102.92996 -175.727553) (xy 102.926388 -175.717962) (xy 102.90934 -175.67656)
			(xy 102.882709 -175.59107) (xy 102.864808 -175.503335) (xy 102.855818 -175.414245) (xy 102.855268 -175.369474)
			(xy 102.855838 -175.324705) (xy 102.864847 -175.23562) (xy 102.882749 -175.147889) (xy 102.909366 -175.062397)
			(xy 102.926388 -175.020986) (xy 102.92997 -175.0114) (xy 102.92996 -174.990953) (xy 102.926388 -174.981362)
			(xy 102.90934 -174.93996) (xy 102.882709 -174.85447) (xy 102.864808 -174.766735) (xy 102.855818 -174.677645)
			(xy 102.855268 -174.632874) (xy 102.855674 -174.591758) (xy 102.863264 -174.509876) (xy 102.878376 -174.429045)
			(xy 102.900882 -174.349952) (xy 102.930591 -174.273273) (xy 102.967247 -174.199663) (xy 103.010539 -174.129749)
			(xy 103.060097 -174.064128) (xy 103.115499 -174.003359) (xy 103.176271 -173.947961) (xy 103.241895 -173.898407)
			(xy 103.311812 -173.85512) (xy 103.385425 -173.818468) (xy 103.462105 -173.788765) (xy 103.541199 -173.766263)
			(xy 103.622032 -173.751156) (xy 103.703914 -173.743571) (xy 103.74503 -173.743112) (xy 103.786641 -173.743573)
			(xy 103.869498 -173.751353) (xy 103.951267 -173.766831) (xy 104.031235 -173.789874) (xy 104.108703 -173.820279)
			(xy 104.182995 -173.857782) (xy 104.218486 -173.87951) (xy 104.227629 -173.884663) (xy 104.248342 -173.88788)
			(xy 104.268614 -173.882552) (xy 104.27716 -173.876462) (xy 104.310789 -173.850471) (xy 104.382183 -173.804346)
			(xy 104.457654 -173.765245) (xy 104.536512 -173.733524) (xy 104.618037 -173.709475) (xy 104.701485 -173.693315)
			(xy 104.786095 -173.685193) (xy 104.828594 -173.684692) (xy 104.869707 -173.685219) (xy 104.951582 -173.692805)
			(xy 105.032407 -173.707913) (xy 105.111494 -173.730413) (xy 105.188168 -173.760115) (xy 105.261774 -173.796765)
			(xy 105.331684 -173.84005) (xy 105.397303 -173.8896) (xy 105.45807 -173.944993) (xy 105.513467 -174.005757)
			(xy 105.563021 -174.071373) (xy 105.60631 -174.141281) (xy 105.642964 -174.214885) (xy 105.67267 -174.291556)
			(xy 105.695176 -174.370642) (xy 105.710288 -174.451467) (xy 105.717879 -174.533341) (xy 105.718356 -174.574454)
			(xy 105.717793 -174.619224) (xy 105.708783 -174.708309) (xy 105.690877 -174.79604) (xy 105.664259 -174.881531)
			(xy 105.647236 -174.922942) (xy 105.643699 -174.932541) (xy 105.643682 -174.952976) (xy 105.647236 -174.962566)
			(xy 105.66424 -175.003917) (xy 105.690851 -175.089279) (xy 105.708758 -175.176882) (xy 105.71778 -175.265839)
			(xy 105.718356 -175.310546) (xy 105.718356 -175.311562) (xy 105.718102 -175.322992) (xy 105.744581 -175.328938)
			(xy 105.796816 -175.343681) (xy 105.822496 -175.352456) (xy 105.830693 -175.35497) (xy 105.847827 -175.35497)
			(xy 105.856024 -175.352456) (xy 105.89124 -175.340495) (xy 105.963244 -175.321841) (xy 106.036565 -175.309332)
			(xy 106.11068 -175.303059) (xy 106.14787 -175.302672) (xy 106.185059 -175.303071) (xy 106.259172 -175.309358)
			(xy 106.332492 -175.321865) (xy 106.404498 -175.340503) (xy 106.439716 -175.352456) (xy 106.447913 -175.35497)
			(xy 106.465047 -175.35497) (xy 106.473244 -175.352456) (xy 106.508459 -175.340489) (xy 106.580462 -175.321837)
			(xy 106.653784 -175.30933) (xy 106.7279 -175.303058) (xy 106.76509 -175.302672) (xy 106.80703 -175.303067)
			(xy 106.890532 -175.311039) (xy 106.972897 -175.326913) (xy 107.05338 -175.350544) (xy 107.131253 -175.381719)
			(xy 107.20581 -175.420155) (xy 107.276375 -175.465504) (xy 107.34231 -175.517355) (xy 107.403018 -175.575239)
			(xy 107.457949 -175.638632) (xy 107.505577 -175.705516) (xy 359.713276 -175.705516) (xy 359.713826 -175.660746)
			(xy 359.72284 -175.571661) (xy 359.740749 -175.48393) (xy 359.767371 -175.398439) (xy 359.784396 -175.357028)
			(xy 359.787954 -175.347435) (xy 359.78796 -175.326994) (xy 359.784396 -175.317404) (xy 359.767362 -175.275997)
			(xy 359.740727 -175.190508) (xy 359.722822 -175.102775) (xy 359.713828 -175.013687) (xy 359.713276 -174.968916)
			(xy 359.713826 -174.924146) (xy 359.72284 -174.835061) (xy 359.740749 -174.74733) (xy 359.767371 -174.661839)
			(xy 359.784396 -174.620428) (xy 359.787954 -174.610835) (xy 359.78796 -174.590394) (xy 359.784396 -174.580804)
			(xy 359.767362 -174.539397) (xy 359.740727 -174.453908) (xy 359.722822 -174.366175) (xy 359.713828 -174.277087)
			(xy 359.713276 -174.232316) (xy 359.713768 -174.191206) (xy 359.721354 -174.109337) (xy 359.736463 -174.028517)
			(xy 359.758966 -173.949437) (xy 359.788671 -173.872771) (xy 359.825324 -173.799173) (xy 359.868613 -173.729272)
			(xy 359.918168 -173.663664) (xy 359.973567 -173.602909) (xy 360.034335 -173.547526) (xy 360.099955 -173.497988)
			(xy 360.169867 -173.454716) (xy 360.243474 -173.418081) (xy 360.320148 -173.388396) (xy 360.399234 -173.365912)
			(xy 360.480057 -173.350823) (xy 360.561928 -173.343257) (xy 360.603038 -173.342808) (xy 360.644642 -173.343279)
			(xy 360.72749 -173.351011) (xy 360.809255 -173.366441) (xy 360.889223 -173.389435) (xy 360.966695 -173.419793)
			(xy 361.040997 -173.457248) (xy 361.076494 -173.478952) (xy 361.08563 -173.48412) (xy 361.106349 -173.487339)
			(xy 361.126625 -173.482001) (xy 361.135168 -173.475904) (xy 361.168794 -173.449952) (xy 361.240172 -173.403895)
			(xy 361.315615 -173.364851) (xy 361.394436 -173.333176) (xy 361.475917 -173.309157) (xy 361.559316 -173.293014)
			(xy 361.643874 -173.284894) (xy 361.686348 -173.284388) (xy 361.686602 -173.284388) (xy 361.72771 -173.284811)
			(xy 361.809576 -173.292396) (xy 361.890393 -173.307501) (xy 361.969472 -173.329998) (xy 362.046138 -173.359694)
			(xy 362.119738 -173.396336) (xy 362.189643 -173.439612) (xy 362.255258 -173.489152) (xy 362.316023 -173.544534)
			(xy 362.371419 -173.605287) (xy 362.420974 -173.67089) (xy 362.464266 -173.740786) (xy 362.500925 -173.814377)
			(xy 362.530638 -173.891036) (xy 362.553153 -173.97011) (xy 362.568276 -174.050924) (xy 362.57588 -174.132788)
			(xy 362.576364 -174.173896) (xy 362.575781 -174.218665) (xy 362.566776 -174.307749) (xy 362.548877 -174.395481)
			(xy 362.522264 -174.480972) (xy 362.505244 -174.522384) (xy 362.501683 -174.531976) (xy 362.501681 -174.552417)
			(xy 362.505244 -174.562008) (xy 362.522284 -174.603413) (xy 362.548917 -174.688902) (xy 362.56682 -174.776636)
			(xy 362.575812 -174.865725) (xy 362.576364 -174.910496) (xy 362.575094 -174.953676) (xy 362.575044 -174.965402)
			(xy 362.584373 -174.986895) (xy 362.602231 -175.002063) (xy 362.613448 -175.005492) (xy 362.632331 -175.010413)
			(xy 362.669682 -175.021721) (xy 362.688124 -175.028098) (xy 362.696321 -175.030612) (xy 362.713455 -175.030612)
			(xy 362.721652 -175.028098) (xy 362.756876 -175.016176) (xy 362.828883 -174.997583) (xy 362.902204 -174.985136)
			(xy 362.976313 -174.978924) (xy 363.013498 -174.978568) (xy 363.050682 -174.978934) (xy 363.12479 -174.985156)
			(xy 363.19811 -174.997599) (xy 363.270121 -175.016175) (xy 363.305344 -175.028098) (xy 363.313541 -175.030612)
			(xy 363.330675 -175.030612) (xy 363.338872 -175.028098) (xy 363.373974 -175.016212) (xy 363.44573 -174.997661)
			(xy 363.518793 -174.985214) (xy 363.592644 -174.978961) (xy 363.629702 -174.978568) (xy 363.630718 -174.978568)
			(xy 363.672642 -174.979095) (xy 363.75611 -174.987067) (xy 363.838443 -175.002937) (xy 363.918894 -175.026561)
			(xy 363.996736 -175.057726) (xy 364.071262 -175.096148) (xy 364.141799 -175.141481) (xy 364.207708 -175.193313)
			(xy 364.268391 -175.251175) (xy 364.323299 -175.314544) (xy 364.371935 -175.382845) (xy 364.413859 -175.45546)
			(xy 364.44869 -175.531731) (xy 364.476114 -175.610968) (xy 364.495881 -175.692452) (xy 364.507814 -175.775447)
			(xy 364.511804 -175.8592) (xy 364.507814 -175.942953) (xy 364.495881 -176.025948) (xy 364.476114 -176.107432)
			(xy 364.44869 -176.186669) (xy 364.413859 -176.26294) (xy 364.371935 -176.335555) (xy 364.323299 -176.403856)
			(xy 364.268391 -176.467225) (xy 364.207708 -176.525087) (xy 364.141799 -176.576919) (xy 364.071262 -176.622252)
			(xy 363.996736 -176.660674) (xy 363.918894 -176.691839) (xy 363.838443 -176.715463) (xy 363.75611 -176.731333)
			(xy 363.672642 -176.739305) (xy 363.630718 -176.739804) (xy 363.629702 -176.739804) (xy 363.592645 -176.739398)
			(xy 363.518796 -176.733134) (xy 363.445733 -176.720692) (xy 363.373973 -176.70216) (xy 363.338872 -176.690274)
			(xy 363.330675 -176.68776) (xy 363.313541 -176.68776) (xy 363.305344 -176.690274) (xy 363.271298 -176.701763)
			(xy 363.201741 -176.719817) (xy 363.166406 -176.726342) (xy 363.157048 -176.728326) (xy 363.140733 -176.738296)
			(xy 363.129218 -176.75356) (xy 363.126274 -176.762664) (xy 363.118487 -176.78918) (xy 363.100057 -176.841287)
			(xy 363.089444 -176.866804) (xy 363.085871 -176.876392) (xy 363.085877 -176.896837) (xy 363.089444 -176.906428)
			(xy 363.106465 -176.947806) (xy 363.133084 -177.033233) (xy 363.150988 -177.120901) (xy 363.159998 -177.209923)
			(xy 363.160564 -177.254662) (xy 363.160564 -177.254916) (xy 363.16006 -177.297264) (xy 363.152009 -177.381578)
			(xy 363.13598 -177.464744) (xy 363.112119 -177.546011) (xy 363.08064 -177.624641) (xy 363.041829 -177.699922)
			(xy 362.996039 -177.771174) (xy 362.943683 -177.83775) (xy 362.885235 -177.899048) (xy 362.821225 -177.954513)
			(xy 362.752233 -178.003642) (xy 362.678883 -178.045991) (xy 362.60184 -178.081175) (xy 362.521801 -178.108877)
			(xy 362.439492 -178.128845) (xy 362.355657 -178.140898) (xy 362.271056 -178.144929) (xy 362.186455 -178.140898)
			(xy 362.10262 -178.128845) (xy 362.020311 -178.108877) (xy 361.940272 -178.081175) (xy 361.863229 -178.045991)
			(xy 361.789879 -178.003642) (xy 361.720887 -177.954513) (xy 361.656877 -177.899048) (xy 361.598429 -177.83775)
			(xy 361.546073 -177.771174) (xy 361.500283 -177.699922) (xy 361.461472 -177.624641) (xy 361.429993 -177.546011)
			(xy 361.406132 -177.464744) (xy 361.390103 -177.381578) (xy 361.382052 -177.297264) (xy 361.381548 -177.254916)
			(xy 361.381548 -177.254662) (xy 361.382124 -177.209924) (xy 361.391138 -177.120903) (xy 361.409041 -177.033235)
			(xy 361.435651 -176.947807) (xy 361.452668 -176.906428) (xy 361.456222 -176.896834) (xy 361.456228 -176.876395)
			(xy 361.452668 -176.866804) (xy 361.435658 -176.825422) (xy 361.409036 -176.739997) (xy 361.391129 -176.65233)
			(xy 361.382115 -176.563308) (xy 361.381548 -176.51857) (xy 361.381548 -176.518316) (xy 361.38189 -176.482968)
			(xy 361.387504 -176.412495) (xy 361.39869 -176.34269) (xy 361.406694 -176.308258) (xy 361.409002 -176.295757)
			(xy 361.402463 -176.271224) (xy 361.394248 -176.261522) (xy 361.353608 -176.218596) (xy 361.34421 -176.220628)
			(xy 361.335443 -176.222892) (xy 361.32021 -176.232657) (xy 361.314492 -176.239678) (xy 361.289344 -176.272353)
			(xy 361.233931 -176.333418) (xy 361.173106 -176.389094) (xy 361.10739 -176.438902) (xy 361.037347 -176.482416)
			(xy 360.963578 -176.519263) (xy 360.886716 -176.549126) (xy 360.807421 -176.571748) (xy 360.726373 -176.586937)
			(xy 360.644268 -176.594561) (xy 360.603038 -176.595024) (xy 360.561931 -176.594551) (xy 360.480067 -176.58697)
			(xy 360.399251 -176.571868) (xy 360.320173 -176.549375) (xy 360.243508 -176.519683) (xy 360.169909 -176.483044)
			(xy 360.100004 -176.439772) (xy 360.034389 -176.390235) (xy 359.973624 -176.334856) (xy 359.918228 -176.274107)
			(xy 359.868672 -176.208506) (xy 359.825379 -176.138613) (xy 359.78872 -176.065025) (xy 359.759005 -175.988368)
			(xy 359.73649 -175.909296) (xy 359.721365 -175.828485) (xy 359.713761 -175.746623) (xy 359.713276 -175.705516)
			(xy 107.505577 -175.705516) (xy 107.506605 -175.706959) (xy 107.548546 -175.779602) (xy 107.583391 -175.855903)
			(xy 107.610826 -175.93517) (xy 107.630602 -176.016687) (xy 107.64254 -176.099714) (xy 107.646531 -176.1835)
			(xy 107.64254 -176.267286) (xy 107.630602 -176.350313) (xy 107.610826 -176.43183) (xy 107.583391 -176.511097)
			(xy 107.548546 -176.587398) (xy 107.506605 -176.660041) (xy 107.457949 -176.728368) (xy 107.403018 -176.791761)
			(xy 107.34231 -176.849645) (xy 107.276375 -176.901496) (xy 107.20581 -176.946845) (xy 107.131253 -176.985281)
			(xy 107.05338 -177.016456) (xy 106.972897 -177.040087) (xy 106.890532 -177.055961) (xy 106.80703 -177.063933)
			(xy 106.76509 -177.064416) (xy 106.7279 -177.064029) (xy 106.653787 -177.057739) (xy 106.580468 -177.045228)
			(xy 106.508462 -177.026587) (xy 106.473244 -177.014632) (xy 106.465047 -177.012118) (xy 106.447913 -177.012118)
			(xy 106.439716 -177.014632) (xy 106.394061 -177.029945) (xy 106.300252 -177.051713) (xy 106.252518 -177.058066)
			(xy 106.242041 -177.059824) (xy 106.223772 -177.070618) (xy 106.211473 -177.087908) (xy 106.20883 -177.098198)
			(xy 106.199325 -177.142161) (xy 106.1726 -177.22805) (xy 106.15549 -177.269648) (xy 106.151882 -177.279222)
			(xy 106.151736 -177.29966) (xy 106.155236 -177.309272) (xy 106.172271 -177.350645) (xy 106.198886 -177.436073)
			(xy 106.216787 -177.523743) (xy 106.225792 -177.612767) (xy 106.226356 -177.657506) (xy 106.226356 -177.65776)
			(xy 106.225852 -177.700108) (xy 106.217801 -177.784422) (xy 106.201772 -177.867588) (xy 106.177911 -177.948855)
			(xy 106.146432 -178.027485) (xy 106.107621 -178.102766) (xy 106.061831 -178.174018) (xy 106.009475 -178.240594)
			(xy 105.951027 -178.301892) (xy 105.887017 -178.357357) (xy 105.818025 -178.406486) (xy 105.744675 -178.448835)
			(xy 105.667632 -178.484019) (xy 105.587593 -178.511721) (xy 105.505284 -178.531689) (xy 105.421449 -178.543742)
			(xy 105.336848 -178.547773) (xy 105.252247 -178.543742) (xy 105.168412 -178.531689) (xy 105.086103 -178.511721)
			(xy 105.006064 -178.484019) (xy 104.929021 -178.448835) (xy 104.855671 -178.406486) (xy 104.786679 -178.357357)
			(xy 104.722669 -178.301892) (xy 104.664221 -178.240594) (xy 104.611865 -178.174018) (xy 104.566075 -178.102766)
			(xy 104.527264 -178.027485) (xy 104.495785 -177.948855) (xy 104.471924 -177.867588) (xy 104.455895 -177.784422)
			(xy 104.447844 -177.700108) (xy 104.44734 -177.65776) (xy 104.44734 -177.657506) (xy 104.447891 -177.612767)
			(xy 104.456911 -177.523745) (xy 104.474821 -177.436078) (xy 104.50144 -177.350651) (xy 104.51846 -177.309272)
			(xy 104.522047 -177.299688) (xy 104.522032 -177.279239) (xy 104.51846 -177.269648) (xy 104.501426 -177.228241)
			(xy 104.474794 -177.142752) (xy 104.456889 -177.055019) (xy 104.447894 -176.965931) (xy 104.44734 -176.92116)
			(xy 104.447594 -176.89703) (xy 104.44745 -176.887477) (xy 104.440882 -176.869548) (xy 104.428227 -176.855249)
			(xy 104.419908 -176.850548) (xy 104.33812 -176.808638) (xy 104.329507 -176.804642) (xy 104.310627 -176.802733)
			(xy 104.292347 -176.807824) (xy 104.284526 -176.81321) (xy 104.284526 -176.813464) (xy 104.284018 -176.813464)
			(xy 104.250823 -176.838169) (xy 104.180649 -176.882028) (xy 104.106709 -176.919187) (xy 104.029639 -176.949324)
			(xy 103.950105 -176.97218) (xy 103.868793 -176.987556) (xy 103.786406 -176.995321) (xy 103.74503 -176.995836)
			(xy 103.703915 -176.995373) (xy 103.622035 -176.987788) (xy 103.541204 -176.97268) (xy 103.462113 -176.950179)
			(xy 103.385435 -176.920475) (xy 103.311825 -176.883823) (xy 103.241911 -176.840535) (xy 103.176289 -176.790981)
			(xy 103.11552 -176.735583) (xy 103.060122 -176.674814) (xy 103.010567 -176.609193) (xy 102.967279 -176.539279)
			(xy 102.930626 -176.465669) (xy 102.900922 -176.388991) (xy 102.87842 -176.309899) (xy 102.863312 -176.229069)
			(xy 102.855727 -176.147189) (xy 102.855268 -176.106074) (xy 74.01685 -176.106074) (xy 74.011364 -176.115577)
			(xy 73.962725 -176.183881) (xy 73.907814 -176.247252) (xy 73.847128 -176.305117) (xy 73.781216 -176.356952)
			(xy 73.710676 -176.402286) (xy 73.636145 -176.44071) (xy 73.5583 -176.471875) (xy 73.477845 -176.4955)
			(xy 73.395508 -176.511369) (xy 73.312036 -176.519341) (xy 73.27011 -176.51984) (xy 73.269094 -176.51984)
			(xy 73.232037 -176.519434) (xy 73.158188 -176.51317) (xy 73.085125 -176.500728) (xy 73.013365 -176.482196)
			(xy 72.978264 -176.47031) (xy 72.970067 -176.467796) (xy 72.952933 -176.467796) (xy 72.944736 -176.47031)
			(xy 72.910756 -176.481853) (xy 72.841327 -176.500034) (xy 72.806052 -176.506632) (xy 72.796116 -176.508916)
			(xy 72.779041 -176.520017) (xy 72.767603 -176.536869) (xy 72.765158 -176.546764) (xy 72.755578 -176.591455)
			(xy 72.728473 -176.67875) (xy 72.711056 -176.721008) (xy 72.70748 -176.730595) (xy 72.707488 -176.751041)
			(xy 72.711056 -176.760632) (xy 72.728073 -176.802012) (xy 72.754694 -176.887437) (xy 72.7726 -176.975105)
			(xy 72.78161 -177.064127) (xy 72.782176 -177.108866) (xy 72.782176 -177.10912) (xy 72.781672 -177.151468)
			(xy 72.773621 -177.235782) (xy 72.757592 -177.318948) (xy 72.733731 -177.400215) (xy 72.702252 -177.478845)
			(xy 72.663441 -177.554126) (xy 72.617651 -177.625378) (xy 72.565295 -177.691954) (xy 72.506847 -177.753252)
			(xy 72.442837 -177.808717) (xy 72.373845 -177.857846) (xy 72.300495 -177.900195) (xy 72.223452 -177.935379)
			(xy 72.143413 -177.963081) (xy 72.061104 -177.983049) (xy 71.977269 -177.995102) (xy 71.892668 -177.999133)
			(xy 71.808067 -177.995102) (xy 71.724232 -177.983049) (xy 71.641923 -177.963081) (xy 71.561884 -177.935379)
			(xy 71.484841 -177.900195) (xy 71.411491 -177.857846) (xy 71.342499 -177.808717) (xy 71.278489 -177.753252)
			(xy 71.220041 -177.691954) (xy 71.167685 -177.625378) (xy 71.121895 -177.554126) (xy 71.083084 -177.478845)
			(xy 71.051605 -177.400215) (xy 71.027744 -177.318948) (xy 71.011715 -177.235782) (xy 71.003664 -177.151468)
			(xy 71.00316 -177.10912) (xy 71.00316 -177.108866) (xy 71.003737 -177.064128) (xy 71.01275 -176.975107)
			(xy 71.030653 -176.887439) (xy 71.057263 -176.802011) (xy 71.07428 -176.760632) (xy 71.077831 -176.751038)
			(xy 71.077839 -176.730599) (xy 71.07428 -176.721008) (xy 71.057235 -176.679605) (xy 71.030605 -176.594115)
			(xy 71.012704 -176.50638) (xy 71.003712 -176.417291) (xy 71.00316 -176.37252) (xy 71.003216 -176.357395)
			(xy 71.004231 -176.327162) (xy 71.005192 -176.312068) (xy 71.005427 -176.302019) (xy 70.999034 -176.282984)
			(xy 70.985815 -176.267867) (xy 70.976998 -176.263046) (xy 70.8787 -176.214532) (xy 70.84822 -176.218596)
			(xy 70.83679 -176.228756) (xy 70.806403 -176.254854) (xy 70.741691 -176.302073) (xy 70.672994 -176.343279)
			(xy 70.60087 -176.378141) (xy 70.525902 -176.406374) (xy 70.4487 -176.427751) (xy 70.369887 -176.442098)
			(xy 70.290104 -176.449298) (xy 70.25005 -176.449736) (xy 70.208935 -176.449254) (xy 70.127056 -176.441671)
			(xy 70.046226 -176.426565) (xy 69.967134 -176.404065) (xy 69.890456 -176.374363) (xy 69.816846 -176.337712)
			(xy 69.746932 -176.294426) (xy 69.68131 -176.244873) (xy 69.620541 -176.189476) (xy 69.565143 -176.128708)
			(xy 69.515588 -176.063088) (xy 69.472299 -175.993175) (xy 69.435647 -175.919566) (xy 69.405943 -175.842889)
			(xy 69.383441 -175.763798) (xy 69.368332 -175.682968) (xy 69.360747 -175.601089) (xy 69.360288 -175.559974)
			(xy 9.487916 -175.559974) (xy 9.487916 -175.848264) (xy 9.48743 -175.875515) (xy 9.479674 -175.929463)
			(xy 9.464319 -175.981758) (xy 9.441677 -176.031335) (xy 9.412211 -176.077185) (xy 9.37652 -176.118376)
			(xy 9.335329 -176.154067) (xy 9.289479 -176.183533) (xy 9.239902 -176.206175) (xy 9.187607 -176.22153)
			(xy 9.133659 -176.229286) (xy 9.079157 -176.229286) (xy 9.025209 -176.22153) (xy 8.972914 -176.206175)
			(xy 8.923337 -176.183533) (xy 8.877487 -176.154067) (xy 8.836296 -176.118376) (xy 8.800605 -176.077185)
			(xy 8.771139 -176.031335) (xy 8.748497 -175.981758) (xy 8.733142 -175.929463) (xy 8.725386 -175.875515)
			(xy 8.7249 -175.848264) (xy 2.509012 -175.848264) (xy 2.509012 -178.618388) (xy 8.7249 -178.618388)
			(xy 8.7249 -177.754788) (xy 8.725386 -177.727537) (xy 8.733142 -177.673589) (xy 8.748497 -177.621294)
			(xy 8.771139 -177.571717) (xy 8.800605 -177.525867) (xy 8.836296 -177.484676) (xy 8.877487 -177.448985)
			(xy 8.923337 -177.419519) (xy 8.972914 -177.396877) (xy 9.025209 -177.381522) (xy 9.079157 -177.373766)
			(xy 9.133659 -177.373766) (xy 9.187607 -177.381522) (xy 9.239902 -177.396877) (xy 9.289479 -177.419519)
			(xy 9.335329 -177.448985) (xy 9.37652 -177.484676) (xy 9.412211 -177.525867) (xy 9.441677 -177.571717)
			(xy 9.464319 -177.621294) (xy 9.479674 -177.673589) (xy 9.48743 -177.727537) (xy 9.487916 -177.754788)
			(xy 9.487916 -178.618388) (xy 9.48743 -178.645639) (xy 9.479674 -178.699587) (xy 9.464319 -178.751882)
			(xy 9.44304 -178.798474) (xy 77.963268 -178.798474) (xy 77.963886 -178.752072) (xy 77.973579 -178.659774)
			(xy 77.992835 -178.568989) (xy 78.021445 -178.480704) (xy 78.039722 -178.438048) (xy 78.043541 -178.42811)
			(xy 78.043531 -178.406843) (xy 78.039722 -178.3969) (xy 78.021451 -178.354243) (xy 77.99286 -178.265953)
			(xy 77.973605 -178.175169) (xy 77.963896 -178.082875) (xy 77.963268 -178.036474) (xy 77.963674 -177.995358)
			(xy 77.971264 -177.913476) (xy 77.986376 -177.832645) (xy 78.008882 -177.753552) (xy 78.038591 -177.676873)
			(xy 78.075247 -177.603263) (xy 78.118539 -177.533349) (xy 78.168097 -177.467728) (xy 78.223499 -177.406959)
			(xy 78.284271 -177.351561) (xy 78.349895 -177.302007) (xy 78.419812 -177.25872) (xy 78.493425 -177.222068)
			(xy 78.570105 -177.192365) (xy 78.649199 -177.169863) (xy 78.730032 -177.154756) (xy 78.811914 -177.147171)
			(xy 78.85303 -177.146712) (xy 78.893848 -177.147168) (xy 78.975141 -177.154659) (xy 79.055405 -177.169568)
			(xy 79.133966 -177.191768) (xy 79.210162 -177.221072) (xy 79.283352 -177.257234) (xy 79.352922 -177.29995)
			(xy 79.418285 -177.348861) (xy 79.478892 -177.403555) (xy 79.534233 -177.463571) (xy 79.559404 -177.495708)
			(xy 79.565179 -177.502627) (xy 79.580393 -177.512264) (xy 79.589122 -177.514504) (xy 79.631283 -177.524073)
			(xy 79.713687 -177.550242) (xy 79.793163 -177.584282) (xy 79.868962 -177.625872) (xy 79.940368 -177.67462)
			(xy 80.006708 -177.730066) (xy 80.067355 -177.791686) (xy 80.121738 -177.8589) (xy 80.169343 -177.931073)
			(xy 80.209721 -178.007525) (xy 80.242492 -178.087533) (xy 80.267345 -178.170343) (xy 80.284047 -178.255173)
			(xy 80.29244 -178.341224) (xy 80.292956 -178.384454) (xy 80.292766 -178.411062) (xy 80.289588 -178.464184)
			(xy 80.286606 -178.490626) (xy 80.285833 -178.501873) (xy 80.292962 -178.523233) (xy 80.300322 -178.531774)
			(xy 80.329261 -178.562798) (xy 80.381784 -178.629432) (xy 80.427728 -178.700761) (xy 80.466676 -178.776139)
			(xy 80.498274 -178.854881) (xy 80.522235 -178.936272) (xy 80.538342 -179.019574) (xy 80.546449 -179.104032)
			(xy 80.546956 -179.146454) (xy 80.546393 -179.191224) (xy 80.537383 -179.280309) (xy 80.519477 -179.36804)
			(xy 80.492859 -179.453531) (xy 80.475836 -179.494942) (xy 80.472299 -179.504541) (xy 80.472282 -179.524976)
			(xy 80.475836 -179.534566) (xy 80.49284 -179.575917) (xy 80.519451 -179.661279) (xy 80.537358 -179.748882)
			(xy 80.54638 -179.837839) (xy 80.546956 -179.882546) (xy 80.546956 -179.883562) (xy 80.546702 -179.894992)
			(xy 80.573181 -179.900938) (xy 80.625416 -179.915681) (xy 80.651096 -179.924456) (xy 80.659293 -179.92697)
			(xy 80.676427 -179.92697) (xy 80.684624 -179.924456) (xy 80.71984 -179.912495) (xy 80.791844 -179.893841)
			(xy 80.865165 -179.881332) (xy 80.93928 -179.875059) (xy 80.97647 -179.874672) (xy 81.013659 -179.875071)
			(xy 81.087772 -179.881358) (xy 81.161092 -179.893865) (xy 81.233098 -179.912503) (xy 81.268316 -179.924456)
			(xy 81.276513 -179.92697) (xy 81.293647 -179.92697) (xy 81.301844 -179.924456) (xy 81.337059 -179.912489)
			(xy 81.409062 -179.893837) (xy 81.482384 -179.88133) (xy 81.5565 -179.875058) (xy 81.59369 -179.874672)
			(xy 81.63563 -179.875067) (xy 81.719132 -179.883039) (xy 81.801497 -179.898913) (xy 81.88198 -179.922544)
			(xy 81.959853 -179.953719) (xy 82.03441 -179.992155) (xy 82.104975 -180.037504) (xy 82.17091 -180.089355)
			(xy 82.231618 -180.147239) (xy 82.286549 -180.210632) (xy 82.335205 -180.278959) (xy 82.377146 -180.351602)
			(xy 82.411991 -180.427903) (xy 82.439426 -180.50717) (xy 82.459202 -180.588687) (xy 82.462267 -180.610002)
			(xy 86.081108 -180.610002) (xy 86.081685 -180.565233) (xy 86.090691 -180.476148) (xy 86.108592 -180.388417)
			(xy 86.135207 -180.302925) (xy 86.152228 -180.261514) (xy 86.155792 -180.251923) (xy 86.155793 -180.231481)
			(xy 86.152228 -180.22189) (xy 86.135186 -180.180486) (xy 86.108554 -180.094996) (xy 86.090651 -180.007262)
			(xy 86.081659 -179.918173) (xy 86.081108 -179.873402) (xy 86.081685 -179.828633) (xy 86.090691 -179.739548)
			(xy 86.108592 -179.651817) (xy 86.135207 -179.566325) (xy 86.152228 -179.524914) (xy 86.155792 -179.515323)
			(xy 86.155793 -179.494881) (xy 86.152228 -179.48529) (xy 86.135186 -179.443886) (xy 86.108554 -179.358396)
			(xy 86.090651 -179.270662) (xy 86.081659 -179.181573) (xy 86.081108 -179.136802) (xy 86.081615 -179.095689)
			(xy 86.089201 -179.013813) (xy 86.10431 -178.932986) (xy 86.126812 -178.853898) (xy 86.156515 -178.777224)
			(xy 86.193165 -178.703617) (xy 86.236451 -178.633706) (xy 86.286003 -178.568087) (xy 86.341397 -178.50732)
			(xy 86.402163 -178.451923) (xy 86.46778 -178.402369) (xy 86.537689 -178.359081) (xy 86.611295 -178.322428)
			(xy 86.687968 -178.292722) (xy 86.767055 -178.270217) (xy 86.847881 -178.255106) (xy 86.929757 -178.247516)
			(xy 86.97087 -178.24704) (xy 87.01248 -178.247527) (xy 87.095336 -178.255301) (xy 87.177105 -178.270774)
			(xy 87.257073 -178.293812) (xy 87.334542 -178.324213) (xy 87.408835 -178.361712) (xy 87.444326 -178.383438)
			(xy 87.453453 -178.388623) (xy 87.474176 -178.391826) (xy 87.494454 -178.386485) (xy 87.503 -178.38039)
			(xy 87.536641 -178.354416) (xy 87.608034 -178.30829) (xy 87.683503 -178.269188) (xy 87.762359 -178.237466)
			(xy 87.843882 -178.213414) (xy 87.927328 -178.19725) (xy 88.011936 -178.189124) (xy 88.054434 -178.18862)
			(xy 88.095548 -178.18908) (xy 88.177426 -178.19667) (xy 88.258254 -178.211782) (xy 88.337343 -178.234287)
			(xy 88.414018 -178.263994) (xy 88.487625 -178.300648) (xy 88.557536 -178.343937) (xy 88.623155 -178.393491)
			(xy 88.683922 -178.448889) (xy 88.739319 -178.509657) (xy 88.788872 -178.575277) (xy 88.83216 -178.645189)
			(xy 88.868813 -178.718797) (xy 88.898518 -178.795473) (xy 88.921021 -178.874562) (xy 88.936132 -178.95539)
			(xy 88.94372 -179.037268) (xy 88.944196 -179.078382) (xy 88.943648 -179.123152) (xy 88.934633 -179.212238)
			(xy 88.916724 -179.299969) (xy 88.890101 -179.38546) (xy 88.873076 -179.42687) (xy 88.869521 -179.436464)
			(xy 88.869514 -179.456904) (xy 88.873076 -179.466494) (xy 88.890086 -179.507843) (xy 88.916696 -179.593206)
			(xy 88.934602 -179.680809) (xy 88.943621 -179.769767) (xy 88.944196 -179.814474) (xy 88.944196 -179.81549)
			(xy 88.943942 -179.82692) (xy 88.970422 -179.832862) (xy 89.022656 -179.847607) (xy 89.048336 -179.856384)
			(xy 89.056533 -179.858898) (xy 89.073667 -179.858898) (xy 89.081864 -179.856384) (xy 89.117077 -179.844413)
			(xy 89.189082 -179.825761) (xy 89.262404 -179.813256) (xy 89.33652 -179.806985) (xy 89.37371 -179.8066)
			(xy 89.4109 -179.806986) (xy 89.485013 -179.813277) (xy 89.558333 -179.825787) (xy 89.630338 -179.844429)
			(xy 89.665556 -179.856384) (xy 89.673753 -179.858898) (xy 89.690887 -179.858898) (xy 89.699084 -179.856384)
			(xy 89.734295 -179.844408) (xy 89.8063 -179.825757) (xy 89.879623 -179.813253) (xy 89.953739 -179.806984)
			(xy 89.99093 -179.8066) (xy 90.032865 -179.807156) (xy 90.116355 -179.815131) (xy 90.198709 -179.831006)
			(xy 90.279182 -179.854637) (xy 90.357043 -179.885811) (xy 90.431589 -179.924244) (xy 90.502144 -179.969589)
			(xy 90.56807 -180.021436) (xy 90.628768 -180.079314) (xy 90.683691 -180.1427) (xy 90.732339 -180.211019)
			(xy 90.774274 -180.283653) (xy 90.809114 -180.359944) (xy 90.836544 -180.439202) (xy 90.856317 -180.520708)
			(xy 90.868253 -180.603725) (xy 90.869375 -180.627274) (xy 94.473268 -180.627274) (xy 94.473838 -180.582505)
			(xy 94.482847 -180.49342) (xy 94.500749 -180.405689) (xy 94.527366 -180.320197) (xy 94.544388 -180.278786)
			(xy 94.54797 -180.2692) (xy 94.54796 -180.248753) (xy 94.544388 -180.239162) (xy 94.52734 -180.19776)
			(xy 94.500709 -180.11227) (xy 94.482808 -180.024535) (xy 94.473818 -179.935445) (xy 94.473268 -179.890674)
			(xy 94.473838 -179.845905) (xy 94.482847 -179.75682) (xy 94.500749 -179.669089) (xy 94.527366 -179.583597)
			(xy 94.544388 -179.542186) (xy 94.54797 -179.5326) (xy 94.54796 -179.512153) (xy 94.544388 -179.502562)
			(xy 94.52734 -179.46116) (xy 94.500709 -179.37567) (xy 94.482808 -179.287935) (xy 94.473818 -179.198845)
			(xy 94.473268 -179.154074) (xy 94.473674 -179.112958) (xy 94.481264 -179.031076) (xy 94.496376 -178.950245)
			(xy 94.518882 -178.871152) (xy 94.548591 -178.794473) (xy 94.585247 -178.720863) (xy 94.628539 -178.650949)
			(xy 94.678097 -178.585328) (xy 94.733499 -178.524559) (xy 94.794271 -178.469161) (xy 94.859895 -178.419607)
			(xy 94.929812 -178.37632) (xy 95.003425 -178.339668) (xy 95.080105 -178.309965) (xy 95.159199 -178.287463)
			(xy 95.240032 -178.272356) (xy 95.321914 -178.264771) (xy 95.36303 -178.264312) (xy 95.404641 -178.264773)
			(xy 95.487498 -178.272553) (xy 95.569267 -178.288031) (xy 95.649235 -178.311074) (xy 95.726703 -178.341479)
			(xy 95.800995 -178.378982) (xy 95.836486 -178.40071) (xy 95.845629 -178.405863) (xy 95.866342 -178.40908)
			(xy 95.886614 -178.403752) (xy 95.89516 -178.397662) (xy 95.928789 -178.371671) (xy 96.000183 -178.325546)
			(xy 96.075654 -178.286445) (xy 96.154512 -178.254724) (xy 96.236037 -178.230675) (xy 96.319485 -178.214515)
			(xy 96.404095 -178.206393) (xy 96.446594 -178.205892) (xy 96.487707 -178.206419) (xy 96.569582 -178.214005)
			(xy 96.650407 -178.229113) (xy 96.729494 -178.251613) (xy 96.806168 -178.281315) (xy 96.879774 -178.317965)
			(xy 96.949684 -178.36125) (xy 97.015303 -178.4108) (xy 97.07607 -178.466193) (xy 97.131467 -178.526957)
			(xy 97.181021 -178.592573) (xy 97.22431 -178.662481) (xy 97.260964 -178.736085) (xy 97.29067 -178.812756)
			(xy 97.313176 -178.891842) (xy 97.328288 -178.972667) (xy 97.335879 -179.054541) (xy 97.336356 -179.095654)
			(xy 97.335793 -179.140424) (xy 97.329275 -179.204874) (xy 368.074448 -179.204874) (xy 368.075006 -179.161932)
			(xy 368.083288 -179.076448) (xy 368.099773 -178.99216) (xy 368.124306 -178.909855) (xy 368.15666 -178.830297)
			(xy 368.196533 -178.75423) (xy 368.243554 -178.682361) (xy 368.297284 -178.615359) (xy 368.357224 -178.55385)
			(xy 368.422813 -178.498405) (xy 368.493443 -178.449542) (xy 368.568454 -178.407716) (xy 368.607594 -178.390042)
			(xy 368.615999 -178.385919) (xy 368.629281 -178.372745) (xy 368.633502 -178.364388) (xy 368.645948 -178.33721)
			(xy 368.64947 -178.328554) (xy 368.650638 -178.309919) (xy 368.648234 -178.300888) (xy 368.635415 -178.257999)
			(xy 368.617464 -178.170297) (xy 368.608423 -178.081234) (xy 368.607848 -178.036474) (xy 368.608352 -177.994113)
			(xy 368.616405 -177.909776) (xy 368.632439 -177.826586) (xy 368.656307 -177.745296) (xy 368.687795 -177.666644)
			(xy 368.726617 -177.591341) (xy 368.77242 -177.520069) (xy 368.824791 -177.453473) (xy 368.883256 -177.392158)
			(xy 368.947284 -177.336677) (xy 369.016296 -177.287534) (xy 369.089666 -177.245174) (xy 369.166731 -177.209979)
			(xy 369.246793 -177.18227) (xy 369.329126 -177.162296) (xy 369.412985 -177.150239) (xy 369.49761 -177.146208)
			(xy 369.582235 -177.150239) (xy 369.666094 -177.162296) (xy 369.748427 -177.18227) (xy 369.828489 -177.209979)
			(xy 369.905554 -177.245174) (xy 369.978924 -177.287534) (xy 370.047936 -177.336677) (xy 370.111964 -177.392158)
			(xy 370.170429 -177.453473) (xy 370.2228 -177.520069) (xy 370.268603 -177.591341) (xy 370.307425 -177.666644)
			(xy 370.338913 -177.745296) (xy 370.362781 -177.826586) (xy 370.378815 -177.909776) (xy 370.386868 -177.994113)
			(xy 370.387372 -178.036474) (xy 370.387372 -178.036728) (xy 370.386948 -178.075094) (xy 370.380306 -178.151538)
			(xy 370.367099 -178.227125) (xy 370.357654 -178.264312) (xy 370.35562 -178.273261) (xy 370.357441 -178.291512)
			(xy 370.365595 -178.307941) (xy 370.37903 -178.320427) (xy 370.387372 -178.324256) (xy 370.427603 -178.341379)
			(xy 370.50477 -178.382506) (xy 370.577528 -178.431007) (xy 370.645175 -178.486413) (xy 370.707059 -178.548191)
			(xy 370.762582 -178.615743) (xy 370.811207 -178.688417) (xy 370.852467 -178.765513) (xy 370.885962 -178.846285)
			(xy 370.911369 -178.929954) (xy 370.928442 -179.015713) (xy 370.937018 -179.102733) (xy 370.937536 -179.146454)
			(xy 370.936975 -179.191224) (xy 370.927964 -179.280309) (xy 370.910058 -179.36804) (xy 370.883439 -179.453531)
			(xy 370.866416 -179.494942) (xy 370.86288 -179.504541) (xy 370.862862 -179.524975) (xy 370.866416 -179.534566)
			(xy 370.883441 -179.575977) (xy 370.910078 -179.661464) (xy 370.927986 -179.749196) (xy 370.936982 -179.838284)
			(xy 370.937536 -179.883054) (xy 370.937282 -179.903882) (xy 370.937631 -179.91519) (xy 370.946776 -179.935848)
			(xy 370.963889 -179.950596) (xy 370.97462 -179.954174) (xy 370.989618 -179.95835) (xy 371.019344 -179.967623)
			(xy 371.034056 -179.972716) (xy 371.042253 -179.97523) (xy 371.059387 -179.97523) (xy 371.067584 -179.972716)
			(xy 371.102796 -179.960741) (xy 371.174801 -179.94209) (xy 371.248123 -179.929585) (xy 371.322239 -179.923316)
			(xy 371.35943 -179.922932) (xy 371.396619 -179.923339) (xy 371.470732 -179.929623) (xy 371.544052 -179.942128)
			(xy 371.616058 -179.960764) (xy 371.651276 -179.972716) (xy 371.659473 -179.97523) (xy 371.676607 -179.97523)
			(xy 371.684804 -179.972716) (xy 371.720023 -179.960763) (xy 371.792025 -179.942106) (xy 371.865345 -179.929595)
			(xy 371.93946 -179.923319) (xy 371.97665 -179.922932) (xy 372.01859 -179.923405) (xy 372.10209 -179.931374)
			(xy 372.184455 -179.947244) (xy 372.264938 -179.970872) (xy 372.34281 -180.002043) (xy 372.417367 -180.040476)
			(xy 372.487932 -180.085822) (xy 372.553868 -180.137671) (xy 372.614576 -180.195553) (xy 372.669507 -180.258944)
			(xy 372.718163 -180.327269) (xy 372.760105 -180.39991) (xy 372.794951 -180.476209) (xy 372.822386 -180.555475)
			(xy 372.842162 -180.63699) (xy 372.848069 -180.678074) (xy 376.477276 -180.678074) (xy 376.477846 -180.633305)
			(xy 376.486854 -180.54422) (xy 376.504757 -180.456489) (xy 376.531374 -180.370997) (xy 376.548396 -180.329586)
			(xy 376.551978 -180.32) (xy 376.551968 -180.299553) (xy 376.548396 -180.289962) (xy 376.531349 -180.24856)
			(xy 376.504717 -180.16307) (xy 376.486816 -180.075335) (xy 376.477826 -179.986245) (xy 376.477276 -179.941474)
			(xy 376.477846 -179.896705) (xy 376.486854 -179.80762) (xy 376.504757 -179.719889) (xy 376.531374 -179.634397)
			(xy 376.548396 -179.592986) (xy 376.551978 -179.5834) (xy 376.551968 -179.562953) (xy 376.548396 -179.553362)
			(xy 376.531349 -179.51196) (xy 376.504717 -179.42647) (xy 376.486816 -179.338735) (xy 376.477826 -179.249645)
			(xy 376.477276 -179.204874) (xy 376.477674 -179.163758) (xy 376.485264 -179.081876) (xy 376.500376 -179.001043)
			(xy 376.522883 -178.92195) (xy 376.552591 -178.845272) (xy 376.589248 -178.771661) (xy 376.632541 -178.701747)
			(xy 376.682099 -178.636125) (xy 376.737501 -178.575356) (xy 376.798274 -178.519958) (xy 376.863899 -178.470404)
			(xy 376.933817 -178.427117) (xy 377.00743 -178.390466) (xy 377.084111 -178.360763) (xy 377.163206 -178.338262)
			(xy 377.244039 -178.323155) (xy 377.325922 -178.315571) (xy 377.367038 -178.315112) (xy 377.408648 -178.315619)
			(xy 377.491503 -178.323389) (xy 377.573272 -178.338859) (xy 377.65324 -178.361894) (xy 377.730709 -178.392291)
			(xy 377.805002 -178.429786) (xy 377.840494 -178.45151) (xy 377.849633 -178.45667) (xy 377.870349 -178.459885)
			(xy 377.890623 -178.454554) (xy 377.899168 -178.448462) (xy 377.932829 -178.422514) (xy 378.004217 -178.376384)
			(xy 378.079682 -178.337278) (xy 378.158534 -178.305551) (xy 378.240054 -178.281495) (xy 378.323498 -178.265328)
			(xy 378.408104 -178.257198) (xy 378.450602 -178.256692) (xy 378.491715 -178.257211) (xy 378.57359 -178.264798)
			(xy 378.654416 -178.279906) (xy 378.733503 -178.302408) (xy 378.810176 -178.33211) (xy 378.883782 -178.368761)
			(xy 378.953693 -178.412046) (xy 379.019312 -178.461597) (xy 379.080078 -178.51699) (xy 379.135475 -178.577755)
			(xy 379.185029 -178.643371) (xy 379.228318 -178.713279) (xy 379.264972 -178.786883) (xy 379.294678 -178.863555)
			(xy 379.317184 -178.942641) (xy 379.332296 -179.023466) (xy 379.339887 -179.105341) (xy 379.340364 -179.146454)
			(xy 379.339801 -179.191224) (xy 379.330791 -179.280309) (xy 379.312886 -179.36804) (xy 379.286267 -179.453531)
			(xy 379.269244 -179.494942) (xy 379.265706 -179.50454) (xy 379.265689 -179.524976) (xy 379.269244 -179.534566)
			(xy 379.286249 -179.575917) (xy 379.31286 -179.661279) (xy 379.330766 -179.748882) (xy 379.339788 -179.837839)
			(xy 379.340364 -179.882546) (xy 379.340364 -179.883562) (xy 379.34011 -179.894992) (xy 379.366589 -179.900938)
			(xy 379.418824 -179.915681) (xy 379.444504 -179.924456) (xy 379.452701 -179.92697) (xy 379.469835 -179.92697)
			(xy 379.478032 -179.924456) (xy 379.513248 -179.912493) (xy 379.585251 -179.893839) (xy 379.658572 -179.881331)
			(xy 379.732688 -179.875058) (xy 379.769878 -179.874672) (xy 379.807067 -179.875069) (xy 379.88118 -179.881356)
			(xy 379.9545 -179.893864) (xy 380.026506 -179.912502) (xy 380.061724 -179.924456) (xy 380.069921 -179.92697)
			(xy 380.087055 -179.92697) (xy 380.095252 -179.924456) (xy 380.130466 -179.912487) (xy 380.20247 -179.893835)
			(xy 380.275792 -179.881329) (xy 380.349908 -179.875057) (xy 380.387098 -179.874672) (xy 380.429038 -179.875067)
			(xy 380.512539 -179.88304) (xy 380.594904 -179.898915) (xy 380.675386 -179.922546) (xy 380.753258 -179.953722)
			(xy 380.827814 -179.992158) (xy 380.898379 -180.037507) (xy 380.964314 -180.089358) (xy 381.025021 -180.147242)
			(xy 381.079951 -180.210635) (xy 381.128607 -180.278962) (xy 381.170547 -180.351604) (xy 381.205392 -180.427905)
			(xy 381.232827 -180.507172) (xy 381.252602 -180.588688) (xy 381.26454 -180.671715) (xy 381.264843 -180.678074)
			(xy 384.808476 -180.678074) (xy 384.809046 -180.633305) (xy 384.818054 -180.54422) (xy 384.835957 -180.456489)
			(xy 384.862574 -180.370997) (xy 384.879596 -180.329586) (xy 384.883178 -180.32) (xy 384.883168 -180.299553)
			(xy 384.879596 -180.289962) (xy 384.862549 -180.24856) (xy 384.835917 -180.16307) (xy 384.818016 -180.075335)
			(xy 384.809026 -179.986245) (xy 384.808476 -179.941474) (xy 384.809046 -179.896705) (xy 384.818054 -179.80762)
			(xy 384.835957 -179.719889) (xy 384.862574 -179.634397) (xy 384.879596 -179.592986) (xy 384.883178 -179.5834)
			(xy 384.883168 -179.562953) (xy 384.879596 -179.553362) (xy 384.862549 -179.51196) (xy 384.835917 -179.42647)
			(xy 384.818016 -179.338735) (xy 384.809026 -179.249645) (xy 384.808476 -179.204874) (xy 384.808874 -179.163758)
			(xy 384.816464 -179.081876) (xy 384.831576 -179.001043) (xy 384.854083 -178.92195) (xy 384.883791 -178.845272)
			(xy 384.920448 -178.771661) (xy 384.963741 -178.701747) (xy 385.013299 -178.636125) (xy 385.068701 -178.575356)
			(xy 385.129474 -178.519958) (xy 385.195099 -178.470404) (xy 385.265017 -178.427117) (xy 385.33863 -178.390466)
			(xy 385.415311 -178.360763) (xy 385.494406 -178.338262) (xy 385.575239 -178.323155) (xy 385.657122 -178.315571)
			(xy 385.698238 -178.315112) (xy 385.739848 -178.315619) (xy 385.822703 -178.323389) (xy 385.904472 -178.338859)
			(xy 385.98444 -178.361894) (xy 386.061909 -178.392291) (xy 386.136202 -178.429786) (xy 386.171694 -178.45151)
			(xy 386.180833 -178.45667) (xy 386.201549 -178.459885) (xy 386.221823 -178.454554) (xy 386.230368 -178.448462)
			(xy 386.264029 -178.422514) (xy 386.335417 -178.376384) (xy 386.410882 -178.337278) (xy 386.489734 -178.305551)
			(xy 386.571254 -178.281495) (xy 386.654698 -178.265328) (xy 386.739304 -178.257198) (xy 386.781802 -178.256692)
			(xy 386.822915 -178.257211) (xy 386.90479 -178.264798) (xy 386.985616 -178.279906) (xy 387.064703 -178.302408)
			(xy 387.141376 -178.33211) (xy 387.214982 -178.368761) (xy 387.284893 -178.412046) (xy 387.350512 -178.461597)
			(xy 387.411278 -178.51699) (xy 387.466675 -178.577755) (xy 387.516229 -178.643371) (xy 387.559518 -178.713279)
			(xy 387.596172 -178.786883) (xy 387.625878 -178.863555) (xy 387.648384 -178.942641) (xy 387.663496 -179.023466)
			(xy 387.671087 -179.105341) (xy 387.671564 -179.146454) (xy 387.671001 -179.191224) (xy 387.661991 -179.280309)
			(xy 387.644086 -179.36804) (xy 387.617467 -179.453531) (xy 387.600444 -179.494942) (xy 387.596906 -179.50454)
			(xy 387.596889 -179.524976) (xy 387.600444 -179.534566) (xy 387.617449 -179.575917) (xy 387.64406 -179.661279)
			(xy 387.661966 -179.748882) (xy 387.670988 -179.837839) (xy 387.671564 -179.882546) (xy 387.671564 -179.883562)
			(xy 387.67131 -179.894992) (xy 387.697789 -179.900938) (xy 387.750024 -179.915681) (xy 387.775704 -179.924456)
			(xy 387.783901 -179.92697) (xy 387.801035 -179.92697) (xy 387.809232 -179.924456) (xy 387.844448 -179.912493)
			(xy 387.916451 -179.893839) (xy 387.989772 -179.881331) (xy 388.063888 -179.875058) (xy 388.101078 -179.874672)
			(xy 388.138267 -179.875069) (xy 388.21238 -179.881356) (xy 388.2857 -179.893864) (xy 388.357706 -179.912502)
			(xy 388.392924 -179.924456) (xy 388.401121 -179.92697) (xy 388.418255 -179.92697) (xy 388.426452 -179.924456)
			(xy 388.461666 -179.912487) (xy 388.53367 -179.893835) (xy 388.606992 -179.881329) (xy 388.681108 -179.875057)
			(xy 388.718298 -179.874672) (xy 388.760238 -179.875067) (xy 388.843739 -179.88304) (xy 388.926104 -179.898915)
			(xy 389.006586 -179.922546) (xy 389.084458 -179.953722) (xy 389.159014 -179.992158) (xy 389.229579 -180.037507)
			(xy 389.295514 -180.089358) (xy 389.356221 -180.147242) (xy 389.411151 -180.210635) (xy 389.459807 -180.278962)
			(xy 389.501747 -180.351604) (xy 389.536592 -180.427905) (xy 389.564027 -180.507172) (xy 389.583802 -180.588688)
			(xy 389.59574 -180.671715) (xy 389.599731 -180.7555) (xy 389.59574 -180.839285) (xy 389.583802 -180.922312)
			(xy 389.564027 -181.003828) (xy 389.536592 -181.083095) (xy 389.501747 -181.159396) (xy 389.459807 -181.232038)
			(xy 389.411151 -181.300365) (xy 389.356221 -181.363758) (xy 389.295514 -181.421642) (xy 389.229579 -181.473493)
			(xy 389.159014 -181.518842) (xy 389.084458 -181.557278) (xy 389.006586 -181.588454) (xy 388.926104 -181.612085)
			(xy 388.843739 -181.62796) (xy 388.760238 -181.635933) (xy 388.718298 -181.636416) (xy 388.681108 -181.636027)
			(xy 388.606996 -181.629737) (xy 388.533676 -181.617227) (xy 388.46167 -181.598587) (xy 388.426452 -181.586632)
			(xy 388.418255 -181.584118) (xy 388.401121 -181.584118) (xy 388.392924 -181.586632) (xy 388.365208 -181.596078)
			(xy 388.308773 -181.611711) (xy 388.280148 -181.617874) (xy 388.270401 -181.620348) (xy 388.25379 -181.63165)
			(xy 388.242792 -181.648464) (xy 388.240524 -181.65826) (xy 388.231054 -181.705587) (xy 388.203179 -181.797995)
			(xy 388.184898 -181.842664) (xy 388.181281 -181.852235) (xy 388.18114 -181.872676) (xy 388.184644 -181.882288)
			(xy 388.201684 -181.923659) (xy 388.228298 -182.009088) (xy 388.246197 -182.096758) (xy 388.255201 -182.185783)
			(xy 388.255764 -182.230522) (xy 388.255764 -182.230776) (xy 388.25526 -182.273124) (xy 388.247209 -182.357438)
			(xy 388.23118 -182.440604) (xy 388.207319 -182.521871) (xy 388.17584 -182.600501) (xy 388.137029 -182.675782)
			(xy 388.091239 -182.747034) (xy 388.038883 -182.81361) (xy 387.980435 -182.874908) (xy 387.916425 -182.930373)
			(xy 387.847433 -182.979502) (xy 387.774083 -183.021851) (xy 387.69704 -183.057035) (xy 387.617001 -183.084737)
			(xy 387.534692 -183.104705) (xy 387.450857 -183.116758) (xy 387.366256 -183.120789) (xy 387.281655 -183.116758)
			(xy 387.19782 -183.104705) (xy 387.115511 -183.084737) (xy 387.035472 -183.057035) (xy 386.958429 -183.021851)
			(xy 386.885079 -182.979502) (xy 386.816087 -182.930373) (xy 386.752077 -182.874908) (xy 386.693629 -182.81361)
			(xy 386.641273 -182.747034) (xy 386.595483 -182.675782) (xy 386.556672 -182.600501) (xy 386.525193 -182.521871)
			(xy 386.501332 -182.440604) (xy 386.485303 -182.357438) (xy 386.477252 -182.273124) (xy 386.476748 -182.230776)
			(xy 386.476748 -182.230522) (xy 386.477311 -182.185784) (xy 386.486329 -182.096762) (xy 386.504235 -182.009095)
			(xy 386.53085 -181.923667) (xy 386.547868 -181.882288) (xy 386.551445 -181.872701) (xy 386.551436 -181.852255)
			(xy 386.547868 -181.842664) (xy 386.53084 -181.801254) (xy 386.504206 -181.715766) (xy 386.4863 -181.628034)
			(xy 386.477302 -181.538946) (xy 386.476748 -181.494176) (xy 386.477087 -181.458262) (xy 386.482864 -181.386666)
			(xy 386.494395 -181.315769) (xy 386.502656 -181.280816) (xy 386.504356 -181.272508) (xy 386.502799 -181.255633)
			(xy 386.495808 -181.240195) (xy 386.49021 -181.233826) (xy 386.44957 -181.1909) (xy 386.43941 -181.193186)
			(xy 386.430637 -181.195432) (xy 386.415405 -181.205208) (xy 386.409692 -181.212236) (xy 386.384552 -181.244927)
			(xy 386.329156 -181.306026) (xy 386.268343 -181.361734) (xy 386.202634 -181.411575) (xy 386.132593 -181.455119)
			(xy 386.058822 -181.491993) (xy 385.981955 -181.521881) (xy 385.902652 -181.544524) (xy 385.821593 -181.55973)
			(xy 385.739474 -181.567368) (xy 385.698238 -181.567836) (xy 385.657123 -181.567365) (xy 385.575243 -181.559781)
			(xy 385.494413 -181.544674) (xy 385.415321 -181.522173) (xy 385.338643 -181.49247) (xy 385.265033 -181.455819)
			(xy 385.195119 -181.412532) (xy 385.129497 -181.362978) (xy 385.068728 -181.30758) (xy 385.01333 -181.246812)
			(xy 384.963775 -181.181191) (xy 384.920487 -181.111277) (xy 384.883834 -181.037668) (xy 384.854131 -180.96099)
			(xy 384.831629 -180.881899) (xy 384.81652 -180.801068) (xy 384.808935 -180.719189) (xy 384.808476 -180.678074)
			(xy 381.264843 -180.678074) (xy 381.268531 -180.7555) (xy 381.26454 -180.839285) (xy 381.252602 -180.922312)
			(xy 381.232827 -181.003828) (xy 381.205392 -181.083095) (xy 381.170547 -181.159396) (xy 381.128607 -181.232038)
			(xy 381.079951 -181.300365) (xy 381.025021 -181.363758) (xy 380.964314 -181.421642) (xy 380.898379 -181.473493)
			(xy 380.827814 -181.518842) (xy 380.753258 -181.557278) (xy 380.675386 -181.588454) (xy 380.594904 -181.612085)
			(xy 380.512539 -181.62796) (xy 380.429038 -181.635933) (xy 380.387098 -181.636416) (xy 380.349908 -181.636027)
			(xy 380.275796 -181.629737) (xy 380.202476 -181.617227) (xy 380.13047 -181.598587) (xy 380.095252 -181.586632)
			(xy 380.087055 -181.584118) (xy 380.069921 -181.584118) (xy 380.061724 -181.586632) (xy 380.034008 -181.596078)
			(xy 379.977573 -181.611711) (xy 379.948948 -181.617874) (xy 379.939201 -181.620348) (xy 379.92259 -181.63165)
			(xy 379.911592 -181.648464) (xy 379.909324 -181.65826) (xy 379.899854 -181.705587) (xy 379.871979 -181.797995)
			(xy 379.853698 -181.842664) (xy 379.850081 -181.852235) (xy 379.84994 -181.872676) (xy 379.853444 -181.882288)
			(xy 379.870484 -181.923659) (xy 379.897098 -182.009088) (xy 379.914997 -182.096758) (xy 379.924001 -182.185783)
			(xy 379.924564 -182.230522) (xy 379.924564 -182.230776) (xy 379.92406 -182.273124) (xy 379.916009 -182.357438)
			(xy 379.89998 -182.440604) (xy 379.876119 -182.521871) (xy 379.84464 -182.600501) (xy 379.805829 -182.675782)
			(xy 379.760039 -182.747034) (xy 379.707683 -182.81361) (xy 379.649235 -182.874908) (xy 379.585225 -182.930373)
			(xy 379.516233 -182.979502) (xy 379.442883 -183.021851) (xy 379.36584 -183.057035) (xy 379.285801 -183.084737)
			(xy 379.203492 -183.104705) (xy 379.119657 -183.116758) (xy 379.035056 -183.120789) (xy 378.950455 -183.116758)
			(xy 378.86662 -183.104705) (xy 378.784311 -183.084737) (xy 378.704272 -183.057035) (xy 378.627229 -183.021851)
			(xy 378.553879 -182.979502) (xy 378.484887 -182.930373) (xy 378.420877 -182.874908) (xy 378.362429 -182.81361)
			(xy 378.310073 -182.747034) (xy 378.264283 -182.675782) (xy 378.225472 -182.600501) (xy 378.193993 -182.521871)
			(xy 378.170132 -182.440604) (xy 378.154103 -182.357438) (xy 378.146052 -182.273124) (xy 378.145548 -182.230776)
			(xy 378.145548 -182.230522) (xy 378.146111 -182.185784) (xy 378.155129 -182.096762) (xy 378.173035 -182.009095)
			(xy 378.19965 -181.923667) (xy 378.216668 -181.882288) (xy 378.220245 -181.872701) (xy 378.220236 -181.852255)
			(xy 378.216668 -181.842664) (xy 378.19964 -181.801254) (xy 378.173006 -181.715766) (xy 378.1551 -181.628034)
			(xy 378.146102 -181.538946) (xy 378.145548 -181.494176) (xy 378.145887 -181.458262) (xy 378.151664 -181.386666)
			(xy 378.163195 -181.315769) (xy 378.171456 -181.280816) (xy 378.173156 -181.272508) (xy 378.171599 -181.255633)
			(xy 378.164608 -181.240195) (xy 378.15901 -181.233826) (xy 378.11837 -181.1909) (xy 378.10821 -181.193186)
			(xy 378.099437 -181.195432) (xy 378.084205 -181.205208) (xy 378.078492 -181.212236) (xy 378.053352 -181.244927)
			(xy 377.997956 -181.306026) (xy 377.937143 -181.361734) (xy 377.871434 -181.411575) (xy 377.801393 -181.455119)
			(xy 377.727622 -181.491993) (xy 377.650755 -181.521881) (xy 377.571452 -181.544524) (xy 377.490393 -181.55973)
			(xy 377.408274 -181.567368) (xy 377.367038 -181.567836) (xy 377.325923 -181.567365) (xy 377.244043 -181.559781)
			(xy 377.163213 -181.544674) (xy 377.084121 -181.522173) (xy 377.007443 -181.49247) (xy 376.933833 -181.455819)
			(xy 376.863919 -181.412532) (xy 376.798297 -181.362978) (xy 376.737528 -181.30758) (xy 376.68213 -181.246812)
			(xy 376.632575 -181.181191) (xy 376.589287 -181.111277) (xy 376.552634 -181.037668) (xy 376.522931 -180.96099)
			(xy 376.500429 -180.881899) (xy 376.48532 -180.801068) (xy 376.477735 -180.719189) (xy 376.477276 -180.678074)
			(xy 372.848069 -180.678074) (xy 372.8541 -180.720015) (xy 372.858091 -180.8038) (xy 372.8541 -180.887585)
			(xy 372.842162 -180.97061) (xy 372.822386 -181.052125) (xy 372.794951 -181.131391) (xy 372.760105 -181.20769)
			(xy 372.718163 -181.280331) (xy 372.669507 -181.348656) (xy 372.614576 -181.412047) (xy 372.553868 -181.469929)
			(xy 372.487932 -181.521778) (xy 372.417367 -181.567124) (xy 372.34281 -181.605557) (xy 372.264938 -181.636728)
			(xy 372.184455 -181.660356) (xy 372.10209 -181.676226) (xy 372.01859 -181.684195) (xy 371.97665 -181.684676)
			(xy 371.939461 -181.684274) (xy 371.865348 -181.677988) (xy 371.792028 -181.665482) (xy 371.720022 -181.646845)
			(xy 371.684804 -181.634892) (xy 371.676607 -181.632378) (xy 371.659473 -181.632378) (xy 371.651276 -181.634892)
			(xy 371.611916 -181.648156) (xy 371.531285 -181.66812) (xy 371.449135 -181.680416) (xy 371.40769 -181.683152)
			(xy 371.397889 -181.684131) (xy 371.380113 -181.692579) (xy 371.36683 -181.707102) (xy 371.362986 -181.716172)
			(xy 371.348 -181.753764) (xy 371.344428 -181.763418) (xy 371.344429 -181.783987) (xy 371.348 -181.793642)
			(xy 371.365038 -181.835014) (xy 371.391656 -181.920442) (xy 371.409557 -182.008112) (xy 371.418559 -182.097137)
			(xy 371.41912 -182.141876) (xy 371.418616 -182.184237) (xy 371.410563 -182.268574) (xy 371.394529 -182.351764)
			(xy 371.370661 -182.433054) (xy 371.339173 -182.511706) (xy 371.300351 -182.587009) (xy 371.254548 -182.658281)
			(xy 371.202177 -182.724877) (xy 371.143712 -182.786192) (xy 371.079684 -182.841673) (xy 371.010672 -182.890816)
			(xy 370.937302 -182.933176) (xy 370.860237 -182.968371) (xy 370.780175 -182.99608) (xy 370.697842 -183.016054)
			(xy 370.613983 -183.028111) (xy 370.529358 -183.032143) (xy 370.444733 -183.028111) (xy 370.360874 -183.016054)
			(xy 370.278541 -182.99608) (xy 370.198479 -182.968371) (xy 370.121414 -182.933176) (xy 370.048044 -182.890816)
			(xy 369.979032 -182.841673) (xy 369.915004 -182.786192) (xy 369.856539 -182.724877) (xy 369.804168 -182.658281)
			(xy 369.758365 -182.587009) (xy 369.719543 -182.511706) (xy 369.688055 -182.433054) (xy 369.664187 -182.351764)
			(xy 369.648153 -182.268574) (xy 369.6401 -182.184237) (xy 369.639596 -182.141876) (xy 369.640165 -182.097107)
			(xy 369.649173 -182.008022) (xy 369.667076 -181.92029) (xy 369.693694 -181.834799) (xy 369.710716 -181.793388)
			(xy 369.714296 -181.783802) (xy 369.714287 -181.763355) (xy 369.710716 -181.753764) (xy 369.693665 -181.712364)
			(xy 369.667035 -181.626872) (xy 369.649135 -181.539137) (xy 369.640146 -181.450047) (xy 369.639596 -181.405276)
			(xy 369.639771 -181.384669) (xy 369.641804 -181.343504) (xy 369.64366 -181.32298) (xy 369.644023 -181.312283)
			(xy 369.63707 -181.292069) (xy 369.630198 -181.283864) (xy 369.57127 -181.22011) (xy 369.551204 -181.211728)
			(xy 369.540282 -181.211982) (xy 369.523264 -181.212236) (xy 369.522756 -181.212236) (xy 369.481649 -181.211766)
			(xy 369.399787 -181.204159) (xy 369.318976 -181.189032) (xy 369.239905 -181.166515) (xy 369.163248 -181.136799)
			(xy 369.08966 -181.100138) (xy 369.019768 -181.056844) (xy 368.954168 -181.007287) (xy 368.893419 -180.95189)
			(xy 368.83804 -180.891125) (xy 368.788503 -180.825509) (xy 368.745231 -180.755604) (xy 368.708592 -180.682005)
			(xy 368.678899 -180.605339) (xy 368.656406 -180.526261) (xy 368.641304 -180.445446) (xy 368.633721 -180.363581)
			(xy 368.633248 -180.322474) (xy 368.6337 -180.283493) (xy 368.640575 -180.205835) (xy 368.654226 -180.129077)
			(xy 368.663982 -180.091334) (xy 368.666037 -180.082278) (xy 368.664208 -180.063813) (xy 368.655908 -180.047218)
			(xy 368.642231 -180.034679) (xy 368.633756 -180.030882) (xy 368.596114 -180.015301) (xy 368.523548 -179.97826)
			(xy 368.454673 -179.934739) (xy 368.390066 -179.885102) (xy 368.330268 -179.829767) (xy 368.27578 -179.769195)
			(xy 368.227059 -179.703896) (xy 368.184512 -179.634415) (xy 368.148496 -179.561335) (xy 368.119314 -179.485268)
			(xy 368.097208 -179.406851) (xy 368.082365 -179.326741) (xy 368.074909 -179.24561) (xy 368.074448 -179.204874)
			(xy 97.329275 -179.204874) (xy 97.326783 -179.229509) (xy 97.308877 -179.31724) (xy 97.282259 -179.402731)
			(xy 97.265236 -179.444142) (xy 97.261699 -179.453741) (xy 97.261682 -179.474176) (xy 97.265236 -179.483766)
			(xy 97.28224 -179.525117) (xy 97.308851 -179.610479) (xy 97.326758 -179.698082) (xy 97.33578 -179.787039)
			(xy 97.336356 -179.831746) (xy 97.336356 -179.832762) (xy 97.336102 -179.844192) (xy 97.362581 -179.850138)
			(xy 97.414816 -179.864881) (xy 97.440496 -179.873656) (xy 97.448693 -179.87617) (xy 97.465827 -179.87617)
			(xy 97.474024 -179.873656) (xy 97.50924 -179.861695) (xy 97.581244 -179.843041) (xy 97.654565 -179.830532)
			(xy 97.72868 -179.824259) (xy 97.76587 -179.823872) (xy 97.803059 -179.824271) (xy 97.877172 -179.830558)
			(xy 97.950492 -179.843065) (xy 98.022498 -179.861703) (xy 98.057716 -179.873656) (xy 98.065913 -179.87617)
			(xy 98.083047 -179.87617) (xy 98.091244 -179.873656) (xy 98.126459 -179.861689) (xy 98.198462 -179.843037)
			(xy 98.271784 -179.83053) (xy 98.3459 -179.824258) (xy 98.38309 -179.823872) (xy 98.42503 -179.824267)
			(xy 98.508532 -179.832239) (xy 98.590897 -179.848113) (xy 98.67138 -179.871744) (xy 98.749253 -179.902919)
			(xy 98.82381 -179.941355) (xy 98.894375 -179.986704) (xy 98.96031 -180.038555) (xy 99.021018 -180.096439)
			(xy 99.075949 -180.159832) (xy 99.124605 -180.228159) (xy 99.166546 -180.300802) (xy 99.201391 -180.377103)
			(xy 99.228826 -180.45637) (xy 99.248602 -180.537887) (xy 99.26054 -180.620914) (xy 99.264531 -180.7047)
			(xy 99.26054 -180.788486) (xy 99.248602 -180.871513) (xy 99.228826 -180.95303) (xy 99.201391 -181.032297)
			(xy 99.166546 -181.108598) (xy 99.124605 -181.181241) (xy 99.075949 -181.249568) (xy 99.021018 -181.312961)
			(xy 98.96031 -181.370845) (xy 98.894375 -181.422696) (xy 98.82381 -181.468045) (xy 98.749253 -181.506481)
			(xy 98.67138 -181.537656) (xy 98.590897 -181.561287) (xy 98.508532 -181.577161) (xy 98.42503 -181.585133)
			(xy 98.38309 -181.585616) (xy 98.3459 -181.585229) (xy 98.271787 -181.578939) (xy 98.198468 -181.566428)
			(xy 98.126462 -181.547787) (xy 98.091244 -181.535832) (xy 98.083047 -181.533318) (xy 98.065913 -181.533318)
			(xy 98.057716 -181.535832) (xy 98.015534 -181.549982) (xy 97.929009 -181.570726) (xy 97.884996 -181.577234)
			(xy 97.875031 -181.57898) (xy 97.85759 -181.589205) (xy 97.845466 -181.605383) (xy 97.842578 -181.61508)
			(xy 97.833805 -181.648299) (xy 97.811813 -181.713397) (xy 97.798636 -181.745128) (xy 97.79505 -181.754712)
			(xy 97.795064 -181.775161) (xy 97.798636 -181.784752) (xy 97.815664 -181.826127) (xy 97.842281 -181.911555)
			(xy 97.860184 -181.999224) (xy 97.869191 -182.088247) (xy 97.869756 -182.132986) (xy 97.869756 -182.13324)
			(xy 97.869252 -182.175588) (xy 97.861201 -182.259902) (xy 97.845172 -182.343068) (xy 97.821311 -182.424335)
			(xy 97.789832 -182.502965) (xy 97.751021 -182.578246) (xy 97.705231 -182.649498) (xy 97.652875 -182.716074)
			(xy 97.594427 -182.777372) (xy 97.530417 -182.832837) (xy 97.461425 -182.881966) (xy 97.388075 -182.924315)
			(xy 97.311032 -182.959499) (xy 97.230993 -182.987201) (xy 97.148684 -183.007169) (xy 97.064849 -183.019222)
			(xy 96.980248 -183.023253) (xy 96.895647 -183.019222) (xy 96.811812 -183.007169) (xy 96.729503 -182.987201)
			(xy 96.649464 -182.959499) (xy 96.572421 -182.924315) (xy 96.499071 -182.881966) (xy 96.430079 -182.832837)
			(xy 96.366069 -182.777372) (xy 96.307621 -182.716074) (xy 96.255265 -182.649498) (xy 96.209475 -182.578246)
			(xy 96.170664 -182.502965) (xy 96.139185 -182.424335) (xy 96.115324 -182.343068) (xy 96.099295 -182.259902)
			(xy 96.091244 -182.175588) (xy 96.09074 -182.13324) (xy 96.09074 -182.132986) (xy 96.091318 -182.088248)
			(xy 96.10033 -181.999226) (xy 96.118232 -181.911559) (xy 96.144843 -181.826131) (xy 96.16186 -181.784752)
			(xy 96.165401 -181.775154) (xy 96.165416 -181.754718) (xy 96.16186 -181.745128) (xy 96.144825 -181.703755)
			(xy 96.11821 -181.618327) (xy 96.100309 -181.530657) (xy 96.091304 -181.441633) (xy 96.09074 -181.396894)
			(xy 96.09074 -181.395878) (xy 96.090368 -181.38632) (xy 96.083332 -181.368547) (xy 96.070254 -181.354605)
			(xy 96.061784 -181.350158) (xy 95.965264 -181.304184) (xy 95.936308 -181.30774) (xy 95.924878 -181.317138)
			(xy 95.890853 -181.344159) (xy 95.818459 -181.392213) (xy 95.741724 -181.43298) (xy 95.66138 -181.466069)
			(xy 95.578192 -181.491168) (xy 95.492953 -181.508035) (xy 95.406476 -181.51651) (xy 95.36303 -181.517036)
			(xy 95.321915 -181.516573) (xy 95.240035 -181.508988) (xy 95.159204 -181.49388) (xy 95.080113 -181.471379)
			(xy 95.003435 -181.441675) (xy 94.929825 -181.405023) (xy 94.859911 -181.361735) (xy 94.794289 -181.312181)
			(xy 94.73352 -181.256783) (xy 94.678122 -181.196014) (xy 94.628567 -181.130393) (xy 94.585279 -181.060479)
			(xy 94.548626 -180.986869) (xy 94.518922 -180.910191) (xy 94.49642 -180.831099) (xy 94.481312 -180.750269)
			(xy 94.473727 -180.668389) (xy 94.473268 -180.627274) (xy 90.869375 -180.627274) (xy 90.872244 -180.6875)
			(xy 90.868253 -180.771275) (xy 90.856317 -180.854292) (xy 90.836544 -180.935798) (xy 90.809114 -181.015056)
			(xy 90.774274 -181.091347) (xy 90.732339 -181.163981) (xy 90.683691 -181.2323) (xy 90.628768 -181.295686)
			(xy 90.56807 -181.353564) (xy 90.502144 -181.405411) (xy 90.431589 -181.450756) (xy 90.357043 -181.489189)
			(xy 90.279182 -181.520363) (xy 90.198709 -181.543994) (xy 90.116355 -181.559869) (xy 90.032865 -181.567844)
			(xy 89.99093 -181.568344) (xy 89.953741 -181.567944) (xy 89.879628 -181.561657) (xy 89.806308 -181.54915)
			(xy 89.734302 -181.530513) (xy 89.699084 -181.51856) (xy 89.690887 -181.516046) (xy 89.673753 -181.516046)
			(xy 89.665556 -181.51856) (xy 89.630433 -181.5305) (xy 89.558617 -181.54912) (xy 89.485489 -181.561626)
			(xy 89.411567 -181.56793) (xy 89.374472 -181.568344) (xy 89.372948 -181.568344) (xy 89.365328 -181.56809)
			(xy 89.355809 -181.6135) (xy 89.328579 -181.702202) (xy 89.310972 -181.745128) (xy 89.307384 -181.754712)
			(xy 89.307399 -181.775161) (xy 89.310972 -181.784752) (xy 89.327996 -181.826163) (xy 89.354632 -181.91165)
			(xy 89.37254 -181.999382) (xy 89.381538 -182.08847) (xy 89.382092 -182.13324) (xy 89.381588 -182.175601)
			(xy 89.373535 -182.259938) (xy 89.357501 -182.343128) (xy 89.333633 -182.424418) (xy 89.302145 -182.50307)
			(xy 89.263323 -182.578373) (xy 89.21752 -182.649645) (xy 89.165149 -182.716241) (xy 89.106684 -182.777556)
			(xy 89.042656 -182.833037) (xy 88.973644 -182.88218) (xy 88.900274 -182.92454) (xy 88.823209 -182.959735)
			(xy 88.743147 -182.987444) (xy 88.660814 -183.007418) (xy 88.576955 -183.019475) (xy 88.49233 -183.023507)
			(xy 88.407705 -183.019475) (xy 88.323846 -183.007418) (xy 88.241513 -182.987444) (xy 88.161451 -182.959735)
			(xy 88.084386 -182.92454) (xy 88.011016 -182.88218) (xy 87.942004 -182.833037) (xy 87.877976 -182.777556)
			(xy 87.819511 -182.716241) (xy 87.76714 -182.649645) (xy 87.721337 -182.578373) (xy 87.682515 -182.50307)
			(xy 87.651027 -182.424418) (xy 87.627159 -182.343128) (xy 87.611125 -182.259938) (xy 87.603072 -182.175601)
			(xy 87.602568 -182.13324) (xy 87.603127 -182.08847) (xy 87.612138 -181.999385) (xy 87.630045 -181.911654)
			(xy 87.656665 -181.826163) (xy 87.673688 -181.784752) (xy 87.677232 -181.775155) (xy 87.677247 -181.754718)
			(xy 87.673688 -181.745128) (xy 87.65877 -181.708939) (xy 87.634581 -181.634489) (xy 87.617023 -181.558202)
			(xy 87.606232 -181.480668) (xy 87.603838 -181.441598) (xy 87.602983 -181.432757) (xy 87.596138 -181.416387)
			(xy 87.58411 -181.403342) (xy 87.576406 -181.398926) (xy 87.486236 -181.352444) (xy 87.459312 -181.35346)
			(xy 87.447882 -181.360826) (xy 87.412209 -181.38294) (xy 87.337447 -181.421096) (xy 87.259425 -181.452047)
			(xy 87.178837 -181.475518) (xy 87.096397 -181.4913) (xy 87.012838 -181.499253) (xy 86.97087 -181.499764)
			(xy 86.929755 -181.499316) (xy 86.847877 -181.491726) (xy 86.767048 -181.476614) (xy 86.687959 -181.454109)
			(xy 86.611283 -181.424402) (xy 86.537675 -181.387748) (xy 86.467763 -181.344458) (xy 86.402144 -181.294902)
			(xy 86.341376 -181.239504) (xy 86.28598 -181.178735) (xy 86.236426 -181.113114) (xy 86.193139 -181.043201)
			(xy 86.156487 -180.969592) (xy 86.126782 -180.892915) (xy 86.10428 -180.813824) (xy 86.08917 -180.732995)
			(xy 86.081583 -180.651117) (xy 86.081108 -180.610002) (xy 82.462267 -180.610002) (xy 82.47114 -180.671714)
			(xy 82.475131 -180.7555) (xy 82.47114 -180.839286) (xy 82.459202 -180.922313) (xy 82.439426 -181.00383)
			(xy 82.411991 -181.083097) (xy 82.377146 -181.159398) (xy 82.335205 -181.232041) (xy 82.286549 -181.300368)
			(xy 82.231618 -181.363761) (xy 82.17091 -181.421645) (xy 82.104975 -181.473496) (xy 82.03441 -181.518845)
			(xy 81.959853 -181.557281) (xy 81.88198 -181.588456) (xy 81.801497 -181.612087) (xy 81.719132 -181.627961)
			(xy 81.63563 -181.635933) (xy 81.59369 -181.636416) (xy 81.5565 -181.636029) (xy 81.482387 -181.629739)
			(xy 81.409068 -181.617228) (xy 81.337062 -181.598587) (xy 81.301844 -181.586632) (xy 81.293647 -181.584118)
			(xy 81.276513 -181.584118) (xy 81.268316 -181.586632) (xy 81.24011 -181.596266) (xy 81.182657 -181.612157)
			(xy 81.153508 -181.618382) (xy 81.143879 -181.620834) (xy 81.127394 -181.631892) (xy 81.116335 -181.648377)
			(xy 81.113884 -181.658006) (xy 81.104396 -181.702491) (xy 81.07755 -181.789404) (xy 81.06029 -181.831488)
			(xy 81.056659 -181.841055) (xy 81.056528 -181.861499) (xy 81.060036 -181.871112) (xy 81.077051 -181.912492)
			(xy 81.103672 -181.997918) (xy 81.121578 -182.085585) (xy 81.130589 -182.174608) (xy 81.131156 -182.219346)
			(xy 81.131156 -182.2196) (xy 81.130652 -182.261948) (xy 81.122601 -182.346262) (xy 81.106572 -182.429428)
			(xy 81.082711 -182.510695) (xy 81.051232 -182.589325) (xy 81.012421 -182.664606) (xy 80.966631 -182.735858)
			(xy 80.914275 -182.802434) (xy 80.855827 -182.863732) (xy 80.791817 -182.919197) (xy 80.722825 -182.968326)
			(xy 80.649475 -183.010675) (xy 80.572432 -183.045859) (xy 80.492393 -183.073561) (xy 80.410084 -183.093529)
			(xy 80.326249 -183.105582) (xy 80.241648 -183.109613) (xy 80.157047 -183.105582) (xy 80.073212 -183.093529)
			(xy 79.990903 -183.073561) (xy 79.910864 -183.045859) (xy 79.833821 -183.010675) (xy 79.760471 -182.968326)
			(xy 79.691479 -182.919197) (xy 79.627469 -182.863732) (xy 79.569021 -182.802434) (xy 79.516665 -182.735858)
			(xy 79.470875 -182.664606) (xy 79.432064 -182.589325) (xy 79.400585 -182.510695) (xy 79.376724 -182.429428)
			(xy 79.360695 -182.346262) (xy 79.352644 -182.261948) (xy 79.35214 -182.2196) (xy 79.35214 -182.219346)
			(xy 79.352704 -182.174608) (xy 79.361721 -182.085586) (xy 79.379627 -181.997918) (xy 79.406242 -181.912491)
			(xy 79.42326 -181.871112) (xy 79.426824 -181.861521) (xy 79.426824 -181.841079) (xy 79.42326 -181.831488)
			(xy 79.406239 -181.790076) (xy 79.379604 -181.704589) (xy 79.361695 -181.616857) (xy 79.352696 -181.52777)
			(xy 79.35214 -181.483) (xy 79.352578 -181.44277) (xy 79.359832 -181.362636) (xy 79.366618 -181.32298)
			(xy 79.366618 -181.322726) (xy 79.368105 -181.310829) (xy 79.361202 -181.287898) (xy 79.35341 -181.278784)
			(xy 79.287878 -181.210204) (xy 79.265018 -181.202076) (xy 79.252826 -181.203854) (xy 79.222877 -181.207733)
			(xy 79.162627 -181.21193) (xy 79.13243 -181.212236) (xy 79.091315 -181.211773) (xy 79.009435 -181.204188)
			(xy 78.928604 -181.18908) (xy 78.849513 -181.166579) (xy 78.772835 -181.136875) (xy 78.699225 -181.100223)
			(xy 78.629311 -181.056935) (xy 78.563689 -181.007381) (xy 78.50292 -180.951983) (xy 78.447522 -180.891214)
			(xy 78.397967 -180.825593) (xy 78.354679 -180.755679) (xy 78.318026 -180.682069) (xy 78.288322 -180.605391)
			(xy 78.26582 -180.526299) (xy 78.250712 -180.445469) (xy 78.243127 -180.363589) (xy 78.242668 -180.322474)
			(xy 78.243154 -180.279736) (xy 78.251333 -180.194653) (xy 78.267631 -180.110746) (xy 78.2919 -180.028788)
			(xy 78.307438 -179.988972) (xy 78.311043 -179.978929) (xy 78.310391 -179.957622) (xy 78.306168 -179.947824)
			(xy 78.289089 -179.911553) (xy 78.260784 -179.836541) (xy 78.239347 -179.759284) (xy 78.224953 -179.680411)
			(xy 78.217719 -179.600562) (xy 78.217268 -179.560474) (xy 78.21746 -179.533866) (xy 78.220637 -179.480744)
			(xy 78.223618 -179.454302) (xy 78.224368 -179.443055) (xy 78.217254 -179.421697) (xy 78.209902 -179.413154)
			(xy 78.180933 -179.382157) (xy 78.128411 -179.31552) (xy 78.082469 -179.244186) (xy 78.043525 -179.168805)
			(xy 78.011931 -179.090059) (xy 77.987974 -179.008663) (xy 77.971872 -178.925358) (xy 77.963772 -178.840898)
			(xy 77.963268 -178.798474) (xy 9.44304 -178.798474) (xy 9.441677 -178.801459) (xy 9.412211 -178.847309)
			(xy 9.37652 -178.8885) (xy 9.335329 -178.924191) (xy 9.289479 -178.953657) (xy 9.239902 -178.976299)
			(xy 9.187607 -178.991654) (xy 9.133659 -178.99941) (xy 9.079157 -178.99941) (xy 9.025209 -178.991654)
			(xy 8.972914 -178.976299) (xy 8.923337 -178.953657) (xy 8.877487 -178.924191) (xy 8.836296 -178.8885)
			(xy 8.800605 -178.847309) (xy 8.771139 -178.801459) (xy 8.748497 -178.751882) (xy 8.733142 -178.699587)
			(xy 8.725386 -178.645639) (xy 8.7249 -178.618388) (xy 2.509012 -178.618388) (xy 2.509012 -190.64715)
			(xy 220.414866 -190.64715) (xy 220.414866 -190.59265) (xy 220.422621 -190.538705) (xy 220.437974 -190.486413)
			(xy 220.460612 -190.436837) (xy 220.490075 -190.390988) (xy 220.525762 -190.349798) (xy 220.566948 -190.314105)
			(xy 220.612793 -190.284636) (xy 220.662366 -190.261992) (xy 220.714656 -190.246632) (xy 220.7686 -190.238869)
			(xy 220.79585 -190.23838) (xy 221.78645 -190.23838) (xy 221.813704 -190.238864) (xy 221.867659 -190.246615)
			(xy 221.919961 -190.261966) (xy 221.969546 -190.284605) (xy 222.015404 -190.314071) (xy 222.056601 -190.349763)
			(xy 222.092299 -190.390956) (xy 222.121771 -190.43681) (xy 222.144416 -190.486392) (xy 222.159775 -190.538692)
			(xy 222.167533 -190.592646) (xy 222.167533 -190.647154) (xy 222.159775 -190.701108) (xy 222.144416 -190.753408)
			(xy 222.121771 -190.80299) (xy 222.092299 -190.848844) (xy 222.056601 -190.890037) (xy 222.015404 -190.925729)
			(xy 221.969546 -190.955195) (xy 221.919961 -190.977834) (xy 221.867659 -190.993185) (xy 221.813704 -191.000936)
			(xy 221.78645 -191.001396) (xy 220.79585 -191.001396) (xy 220.7686 -191.000931) (xy 220.714656 -190.993168)
			(xy 220.662366 -190.977808) (xy 220.612793 -190.955164) (xy 220.566948 -190.925695) (xy 220.525762 -190.890002)
			(xy 220.490075 -190.848812) (xy 220.460612 -190.802963) (xy 220.437974 -190.753387) (xy 220.422621 -190.701095)
			(xy 220.414866 -190.64715) (xy 2.509012 -190.64715) (xy 2.509012 -194.296284) (xy 255.545336 -194.296284)
			(xy 255.545336 -193.432684) (xy 255.545822 -193.405415) (xy 255.553584 -193.351431) (xy 255.568949 -193.299101)
			(xy 255.591606 -193.249491) (xy 255.621092 -193.20361) (xy 255.656807 -193.162393) (xy 255.698024 -193.126678)
			(xy 255.743905 -193.097192) (xy 255.793515 -193.074535) (xy 255.845845 -193.05917) (xy 255.899829 -193.051408)
			(xy 255.954367 -193.051408) (xy 256.008351 -193.05917) (xy 256.060681 -193.074535) (xy 256.110291 -193.097192)
			(xy 256.156172 -193.126678) (xy 256.197389 -193.162393) (xy 256.233104 -193.20361) (xy 256.26259 -193.249491)
			(xy 256.285247 -193.299101) (xy 256.300612 -193.351431) (xy 256.308374 -193.405415) (xy 256.30886 -193.432684)
			(xy 256.30886 -194.296284) (xy 256.308374 -194.323553) (xy 256.300612 -194.377537) (xy 256.285247 -194.429867)
			(xy 256.26259 -194.479477) (xy 256.25414 -194.492626) (xy 260.09346 -194.492626) (xy 260.09346 -193.502026)
			(xy 260.093946 -193.474757) (xy 260.101708 -193.420773) (xy 260.117073 -193.368443) (xy 260.13973 -193.318833)
			(xy 260.169216 -193.272952) (xy 260.204931 -193.231735) (xy 260.246148 -193.19602) (xy 260.292029 -193.166534)
			(xy 260.341639 -193.143877) (xy 260.393969 -193.128512) (xy 260.447953 -193.12075) (xy 260.502491 -193.12075)
			(xy 260.556475 -193.128512) (xy 260.608805 -193.143877) (xy 260.658415 -193.166534) (xy 260.704296 -193.19602)
			(xy 260.745513 -193.231735) (xy 260.781228 -193.272952) (xy 260.810714 -193.318833) (xy 260.833371 -193.368443)
			(xy 260.848736 -193.420773) (xy 260.856498 -193.474757) (xy 260.856984 -193.502026) (xy 260.856984 -194.492626)
			(xy 260.856498 -194.519895) (xy 260.848736 -194.573879) (xy 260.833371 -194.626209) (xy 260.810714 -194.675819)
			(xy 260.781228 -194.7217) (xy 260.745513 -194.762917) (xy 260.704296 -194.798632) (xy 260.658415 -194.828118)
			(xy 260.608805 -194.850775) (xy 260.556475 -194.86614) (xy 260.502491 -194.873902) (xy 260.447953 -194.873902)
			(xy 260.393969 -194.86614) (xy 260.341639 -194.850775) (xy 260.292029 -194.828118) (xy 260.246148 -194.798632)
			(xy 260.204931 -194.762917) (xy 260.169216 -194.7217) (xy 260.13973 -194.675819) (xy 260.117073 -194.626209)
			(xy 260.101708 -194.573879) (xy 260.093946 -194.519895) (xy 260.09346 -194.492626) (xy 256.25414 -194.492626)
			(xy 256.233104 -194.525358) (xy 256.197389 -194.566575) (xy 256.156172 -194.60229) (xy 256.110291 -194.631776)
			(xy 256.060681 -194.654433) (xy 256.008351 -194.669798) (xy 255.954367 -194.67756) (xy 255.899829 -194.67756)
			(xy 255.845845 -194.669798) (xy 255.793515 -194.654433) (xy 255.743905 -194.631776) (xy 255.698024 -194.60229)
			(xy 255.656807 -194.566575) (xy 255.621092 -194.525358) (xy 255.591606 -194.479477) (xy 255.568949 -194.429867)
			(xy 255.553584 -194.377537) (xy 255.545822 -194.323553) (xy 255.545336 -194.296284) (xy 2.509012 -194.296284)
			(xy 2.509012 -197.07352) (xy 255.545336 -197.07352) (xy 255.545336 -196.20992) (xy 255.545822 -196.182651)
			(xy 255.553584 -196.128667) (xy 255.568949 -196.076337) (xy 255.591606 -196.026727) (xy 255.621092 -195.980846)
			(xy 255.656807 -195.939629) (xy 255.698024 -195.903914) (xy 255.743905 -195.874428) (xy 255.793515 -195.851771)
			(xy 255.845845 -195.836406) (xy 255.899829 -195.828644) (xy 255.954367 -195.828644) (xy 256.008351 -195.836406)
			(xy 256.060681 -195.851771) (xy 256.110291 -195.874428) (xy 256.156172 -195.903914) (xy 256.197389 -195.939629)
			(xy 256.233104 -195.980846) (xy 256.26259 -196.026727) (xy 256.285247 -196.076337) (xy 256.300612 -196.128667)
			(xy 256.308374 -196.182651) (xy 256.30886 -196.20992) (xy 256.30886 -197.07352) (xy 256.308374 -197.100789)
			(xy 256.300612 -197.154773) (xy 256.285247 -197.207103) (xy 256.26259 -197.256713) (xy 256.233104 -197.302594)
			(xy 256.197389 -197.343811) (xy 256.156172 -197.379526) (xy 256.110291 -197.409012) (xy 256.060681 -197.431669)
			(xy 256.008351 -197.447034) (xy 255.954367 -197.454796) (xy 255.899829 -197.454796) (xy 255.845845 -197.447034)
			(xy 255.793515 -197.431669) (xy 255.743905 -197.409012) (xy 255.698024 -197.379526) (xy 255.656807 -197.343811)
			(xy 255.621092 -197.302594) (xy 255.591606 -197.256713) (xy 255.568949 -197.207103) (xy 255.553584 -197.154773)
			(xy 255.545822 -197.100789) (xy 255.545336 -197.07352) (xy 2.509012 -197.07352) (xy 2.509012 -199.868028)
			(xy 255.545336 -199.868028) (xy 255.545336 -199.004428) (xy 255.545822 -198.977159) (xy 255.553584 -198.923175)
			(xy 255.568949 -198.870845) (xy 255.591606 -198.821235) (xy 255.621092 -198.775354) (xy 255.656807 -198.734137)
			(xy 255.698024 -198.698422) (xy 255.743905 -198.668936) (xy 255.793515 -198.646279) (xy 255.845845 -198.630914)
			(xy 255.899829 -198.623152) (xy 255.954367 -198.623152) (xy 256.008351 -198.630914) (xy 256.060681 -198.646279)
			(xy 256.110291 -198.668936) (xy 256.156172 -198.698422) (xy 256.197389 -198.734137) (xy 256.233104 -198.775354)
			(xy 256.26259 -198.821235) (xy 256.285247 -198.870845) (xy 256.300612 -198.923175) (xy 256.308374 -198.977159)
			(xy 256.30886 -199.004428) (xy 256.30886 -199.868028) (xy 256.308374 -199.895297) (xy 256.300612 -199.949281)
			(xy 256.285247 -200.001611) (xy 256.26259 -200.051221) (xy 256.233104 -200.097102) (xy 256.197389 -200.138319)
			(xy 256.156172 -200.174034) (xy 256.110291 -200.20352) (xy 256.060681 -200.226177) (xy 256.008351 -200.241542)
			(xy 255.954367 -200.249304) (xy 255.899829 -200.249304) (xy 255.845845 -200.241542) (xy 255.793515 -200.226177)
			(xy 255.743905 -200.20352) (xy 255.698024 -200.174034) (xy 255.656807 -200.138319) (xy 255.621092 -200.097102)
			(xy 255.591606 -200.051221) (xy 255.568949 -200.001611) (xy 255.553584 -199.949281) (xy 255.545822 -199.895297)
			(xy 255.545336 -199.868028) (xy 2.509012 -199.868028) (xy 2.509012 -202.662536) (xy 255.545336 -202.662536)
			(xy 255.545336 -201.798936) (xy 255.545822 -201.771667) (xy 255.553584 -201.717683) (xy 255.568949 -201.665353)
			(xy 255.591606 -201.615743) (xy 255.621092 -201.569862) (xy 255.656807 -201.528645) (xy 255.698024 -201.49293)
			(xy 255.743905 -201.463444) (xy 255.793515 -201.440787) (xy 255.845845 -201.425422) (xy 255.899829 -201.41766)
			(xy 255.954367 -201.41766) (xy 256.008351 -201.425422) (xy 256.060681 -201.440787) (xy 256.110291 -201.463444)
			(xy 256.156172 -201.49293) (xy 256.197389 -201.528645) (xy 256.233104 -201.569862) (xy 256.26259 -201.615743)
			(xy 256.285247 -201.665353) (xy 256.300612 -201.717683) (xy 256.308374 -201.771667) (xy 256.30886 -201.798936)
			(xy 256.30886 -202.662536) (xy 256.308374 -202.689805) (xy 256.300612 -202.743789) (xy 256.285247 -202.796119)
			(xy 256.26259 -202.845729) (xy 256.233104 -202.89161) (xy 256.197389 -202.932827) (xy 256.156172 -202.968542)
			(xy 256.110291 -202.998028) (xy 256.060681 -203.020685) (xy 256.008351 -203.03605) (xy 255.954367 -203.043812)
			(xy 255.899829 -203.043812) (xy 255.845845 -203.03605) (xy 255.793515 -203.020685) (xy 255.743905 -202.998028)
			(xy 255.698024 -202.968542) (xy 255.656807 -202.932827) (xy 255.621092 -202.89161) (xy 255.591606 -202.845729)
			(xy 255.568949 -202.796119) (xy 255.553584 -202.743789) (xy 255.545822 -202.689805) (xy 255.545336 -202.662536)
			(xy 2.509012 -202.662536) (xy 2.509012 -205.439772) (xy 255.545336 -205.439772) (xy 255.545336 -204.576172)
			(xy 255.545822 -204.548903) (xy 255.553584 -204.494919) (xy 255.568949 -204.442589) (xy 255.591606 -204.392979)
			(xy 255.621092 -204.347098) (xy 255.656807 -204.305881) (xy 255.698024 -204.270166) (xy 255.743905 -204.24068)
			(xy 255.793515 -204.218023) (xy 255.845845 -204.202658) (xy 255.899829 -204.194896) (xy 255.954367 -204.194896)
			(xy 256.008351 -204.202658) (xy 256.060681 -204.218023) (xy 256.110291 -204.24068) (xy 256.156172 -204.270166)
			(xy 256.197389 -204.305881) (xy 256.233104 -204.347098) (xy 256.26259 -204.392979) (xy 256.285247 -204.442589)
			(xy 256.300612 -204.494919) (xy 256.308374 -204.548903) (xy 256.30886 -204.576172) (xy 256.30886 -205.439772)
			(xy 256.308374 -205.467041) (xy 256.300612 -205.521025) (xy 256.285247 -205.573355) (xy 256.26259 -205.622965)
			(xy 256.233104 -205.668846) (xy 256.197389 -205.710063) (xy 256.156172 -205.745778) (xy 256.110291 -205.775264)
			(xy 256.060681 -205.797921) (xy 256.008351 -205.813286) (xy 255.954367 -205.821048) (xy 255.899829 -205.821048)
			(xy 255.845845 -205.813286) (xy 255.793515 -205.797921) (xy 255.743905 -205.775264) (xy 255.698024 -205.745778)
			(xy 255.656807 -205.710063) (xy 255.621092 -205.668846) (xy 255.591606 -205.622965) (xy 255.568949 -205.573355)
			(xy 255.553584 -205.521025) (xy 255.545822 -205.467041) (xy 255.545336 -205.439772) (xy 2.509012 -205.439772)
			(xy 2.509012 -207.499458) (xy 97.408492 -207.499458) (xy 97.408492 -206.635858) (xy 97.408978 -206.608589)
			(xy 97.41674 -206.554605) (xy 97.432105 -206.502275) (xy 97.454762 -206.452665) (xy 97.484248 -206.406784)
			(xy 97.519963 -206.365567) (xy 97.56118 -206.329852) (xy 97.607061 -206.300366) (xy 97.656671 -206.277709)
			(xy 97.709001 -206.262344) (xy 97.762985 -206.254582) (xy 97.817523 -206.254582) (xy 97.871507 -206.262344)
			(xy 97.923837 -206.277709) (xy 97.973447 -206.300366) (xy 98.019328 -206.329852) (xy 98.060545 -206.365567)
			(xy 98.09626 -206.406784) (xy 98.125746 -206.452665) (xy 98.148403 -206.502275) (xy 98.163768 -206.554605)
			(xy 98.17153 -206.608589) (xy 98.172016 -206.635858) (xy 98.172016 -207.499458) (xy 98.17153 -207.526727)
			(xy 98.163768 -207.580711) (xy 98.148403 -207.633041) (xy 98.125746 -207.682651) (xy 98.09626 -207.728532)
			(xy 98.060545 -207.769749) (xy 98.019328 -207.805464) (xy 97.973447 -207.83495) (xy 97.923837 -207.857607)
			(xy 97.871507 -207.872972) (xy 97.817523 -207.880734) (xy 97.762985 -207.880734) (xy 97.709001 -207.872972)
			(xy 97.656671 -207.857607) (xy 97.607061 -207.83495) (xy 97.56118 -207.805464) (xy 97.519963 -207.769749)
			(xy 97.484248 -207.728532) (xy 97.454762 -207.682651) (xy 97.432105 -207.633041) (xy 97.41674 -207.580711)
			(xy 97.408978 -207.526727) (xy 97.408492 -207.499458) (xy 2.509012 -207.499458) (xy 2.509012 -209.023458)
			(xy 94.105984 -209.023458) (xy 94.105984 -208.159858) (xy 94.10647 -208.132589) (xy 94.114232 -208.078605)
			(xy 94.129597 -208.026275) (xy 94.152254 -207.976665) (xy 94.18174 -207.930784) (xy 94.217455 -207.889567)
			(xy 94.258672 -207.853852) (xy 94.304553 -207.824366) (xy 94.354163 -207.801709) (xy 94.406493 -207.786344)
			(xy 94.460477 -207.778582) (xy 94.515015 -207.778582) (xy 94.568999 -207.786344) (xy 94.621329 -207.801709)
			(xy 94.670939 -207.824366) (xy 94.71682 -207.853852) (xy 94.758037 -207.889567) (xy 94.793752 -207.930784)
			(xy 94.823238 -207.976665) (xy 94.845895 -208.026275) (xy 94.86126 -208.078605) (xy 94.869022 -208.132589)
			(xy 94.869508 -208.159858) (xy 94.869508 -208.217008) (xy 255.545336 -208.217008) (xy 255.545336 -207.353408)
			(xy 255.545822 -207.326139) (xy 255.553584 -207.272155) (xy 255.568949 -207.219825) (xy 255.591606 -207.170215)
			(xy 255.621092 -207.124334) (xy 255.656807 -207.083117) (xy 255.698024 -207.047402) (xy 255.743905 -207.017916)
			(xy 255.793515 -206.995259) (xy 255.845845 -206.979894) (xy 255.899829 -206.972132) (xy 255.954367 -206.972132)
			(xy 256.008351 -206.979894) (xy 256.060681 -206.995259) (xy 256.110291 -207.017916) (xy 256.156172 -207.047402)
			(xy 256.197389 -207.083117) (xy 256.233104 -207.124334) (xy 256.26259 -207.170215) (xy 256.285247 -207.219825)
			(xy 256.300612 -207.272155) (xy 256.308374 -207.326139) (xy 256.30886 -207.353408) (xy 256.30886 -208.217008)
			(xy 256.308374 -208.244277) (xy 256.300612 -208.298261) (xy 256.285247 -208.350591) (xy 256.26259 -208.400201)
			(xy 256.233104 -208.446082) (xy 256.197389 -208.487299) (xy 256.156172 -208.523014) (xy 256.110291 -208.5525)
			(xy 256.060681 -208.575157) (xy 256.008351 -208.590522) (xy 255.954367 -208.598284) (xy 255.899829 -208.598284)
			(xy 255.845845 -208.590522) (xy 255.793515 -208.575157) (xy 255.743905 -208.5525) (xy 255.698024 -208.523014)
			(xy 255.656807 -208.487299) (xy 255.621092 -208.446082) (xy 255.591606 -208.400201) (xy 255.568949 -208.350591)
			(xy 255.553584 -208.298261) (xy 255.545822 -208.244277) (xy 255.545336 -208.217008) (xy 94.869508 -208.217008)
			(xy 94.869508 -209.023458) (xy 94.869022 -209.050727) (xy 94.86126 -209.104711) (xy 94.845895 -209.157041)
			(xy 94.823238 -209.206651) (xy 94.793752 -209.252532) (xy 94.758037 -209.293749) (xy 94.71682 -209.329464)
			(xy 94.670939 -209.35895) (xy 94.621329 -209.381607) (xy 94.568999 -209.396972) (xy 94.515015 -209.404734)
			(xy 94.460477 -209.404734) (xy 94.406493 -209.396972) (xy 94.354163 -209.381607) (xy 94.304553 -209.35895)
			(xy 94.258672 -209.329464) (xy 94.217455 -209.293749) (xy 94.18174 -209.252532) (xy 94.152254 -209.206651)
			(xy 94.129597 -209.157041) (xy 94.114232 -209.104711) (xy 94.10647 -209.050727) (xy 94.105984 -209.023458)
			(xy 2.509012 -209.023458) (xy 2.509012 -212.98027) (xy 78.81214 -212.98027) (xy 78.81617 -212.837935)
			(xy 78.828245 -212.696055) (xy 78.848328 -212.555087) (xy 78.876355 -212.41548) (xy 78.912235 -212.277682)
			(xy 78.955853 -212.142135) (xy 79.00707 -212.009273) (xy 79.065721 -211.879521) (xy 79.131619 -211.753295)
			(xy 79.204553 -211.630999) (xy 79.28429 -211.513026) (xy 79.370572 -211.399753) (xy 79.463125 -211.291542)
			(xy 79.561652 -211.188741) (xy 79.665837 -211.091679) (xy 79.775346 -211.000667) (xy 79.889829 -210.915995)
			(xy 80.008919 -210.837937) (xy 80.132234 -210.766741) (xy 80.25938 -210.702635) (xy 80.389949 -210.645826)
			(xy 80.523523 -210.596494) (xy 80.659674 -210.554798) (xy 80.797965 -210.520872) (xy 80.937955 -210.494824)
			(xy 81.079194 -210.476738) (xy 81.22123 -210.466671) (xy 81.363608 -210.464656) (xy 81.505872 -210.470699)
			(xy 81.647566 -210.484781) (xy 81.788236 -210.506857) (xy 81.927433 -210.536857) (xy 82.064709 -210.574683)
			(xy 82.199625 -210.620215) (xy 82.331749 -210.673306) (xy 82.460658 -210.733788) (xy 82.585939 -210.801466)
			(xy 82.70719 -210.876123) (xy 82.824023 -210.957521) (xy 82.936064 -211.045398) (xy 83.042954 -211.139473)
			(xy 83.144351 -211.239445) (xy 83.239929 -211.344993) (xy 83.329383 -211.455779) (xy 83.412425 -211.571448)
			(xy 83.488791 -211.691631) (xy 83.558235 -211.815941) (xy 83.620535 -211.943982) (xy 83.675491 -212.075341)
			(xy 83.69835 -212.140038) (xy 94.106492 -212.140038) (xy 94.106492 -211.276438) (xy 94.106978 -211.249187)
			(xy 94.114734 -211.195239) (xy 94.130089 -211.142944) (xy 94.152731 -211.093367) (xy 94.182197 -211.047517)
			(xy 94.217888 -211.006326) (xy 94.259079 -210.970635) (xy 94.304929 -210.941169) (xy 94.354506 -210.918527)
			(xy 94.406801 -210.903172) (xy 94.460749 -210.895416) (xy 94.515251 -210.895416) (xy 94.569199 -210.903172)
			(xy 94.621494 -210.918527) (xy 94.671071 -210.941169) (xy 94.716921 -210.970635) (xy 94.758112 -211.006326)
			(xy 94.793803 -211.047517) (xy 94.823269 -211.093367) (xy 94.845911 -211.142944) (xy 94.861266 -211.195239)
			(xy 94.869022 -211.249187) (xy 94.869508 -211.276438) (xy 94.869508 -212.140038) (xy 94.869022 -212.167289)
			(xy 94.861266 -212.221237) (xy 94.845911 -212.273532) (xy 94.823269 -212.323109) (xy 94.793803 -212.368959)
			(xy 94.758112 -212.41015) (xy 94.716921 -212.445841) (xy 94.671071 -212.475307) (xy 94.621494 -212.497949)
			(xy 94.569199 -212.513304) (xy 94.515251 -212.52106) (xy 94.460749 -212.52106) (xy 94.406801 -212.513304)
			(xy 94.354506 -212.497949) (xy 94.304929 -212.475307) (xy 94.259079 -212.445841) (xy 94.217888 -212.41015)
			(xy 94.182197 -212.368959) (xy 94.152731 -212.323109) (xy 94.130089 -212.273532) (xy 94.114734 -212.221237)
			(xy 94.106978 -212.167289) (xy 94.106492 -212.140038) (xy 83.69835 -212.140038) (xy 83.722928 -212.2096)
			(xy 83.762692 -212.346327) (xy 83.794658 -212.485085) (xy 83.818723 -212.625429) (xy 83.834809 -212.76691)
			(xy 83.842864 -212.909074) (xy 83.843368 -212.98027) (xy 140.011408 -212.98027) (xy 140.015438 -212.837906)
			(xy 140.027516 -212.695998) (xy 140.047604 -212.555001) (xy 140.075636 -212.415366) (xy 140.111523 -212.27754)
			(xy 140.15515 -212.141966) (xy 140.206377 -212.009077) (xy 140.26504 -211.879298) (xy 140.330952 -211.753047)
			(xy 140.403901 -211.630727) (xy 140.483653 -211.51273) (xy 140.569953 -211.399434) (xy 140.662525 -211.291201)
			(xy 140.761071 -211.188379) (xy 140.865277 -211.091298) (xy 140.974809 -211.000267) (xy 141.089315 -210.915579)
			(xy 141.208429 -210.837504) (xy 141.331769 -210.766294) (xy 141.45894 -210.702175) (xy 141.589536 -210.645354)
			(xy 141.723136 -210.596013) (xy 141.859315 -210.554308) (xy 141.997634 -210.520375) (xy 142.137652 -210.494322)
			(xy 142.278919 -210.476232) (xy 142.420984 -210.466163) (xy 142.563391 -210.464148) (xy 142.705684 -210.470192)
			(xy 142.847406 -210.484278) (xy 142.988105 -210.506358) (xy 143.12733 -210.536363) (xy 143.264634 -210.574197)
			(xy 143.399577 -210.619738) (xy 143.531728 -210.672841) (xy 143.660663 -210.733335) (xy 143.785969 -210.801026)
			(xy 143.907245 -210.875699) (xy 144.024101 -210.957113) (xy 144.093464 -211.011516) (xy 255.545336 -211.011516)
			(xy 255.545336 -210.147916) (xy 255.545822 -210.120647) (xy 255.553584 -210.066663) (xy 255.568949 -210.014333)
			(xy 255.591606 -209.964723) (xy 255.621092 -209.918842) (xy 255.656807 -209.877625) (xy 255.698024 -209.84191)
			(xy 255.743905 -209.812424) (xy 255.793515 -209.789767) (xy 255.845845 -209.774402) (xy 255.899829 -209.76664)
			(xy 255.954367 -209.76664) (xy 256.008351 -209.774402) (xy 256.060681 -209.789767) (xy 256.110291 -209.812424)
			(xy 256.156172 -209.84191) (xy 256.197389 -209.877625) (xy 256.233104 -209.918842) (xy 256.26259 -209.964723)
			(xy 256.285247 -210.014333) (xy 256.300612 -210.066663) (xy 256.308374 -210.120647) (xy 256.30886 -210.147916)
			(xy 256.30886 -211.011516) (xy 256.308374 -211.038785) (xy 256.300612 -211.092769) (xy 256.285247 -211.145099)
			(xy 256.26259 -211.194709) (xy 256.233104 -211.24059) (xy 256.197389 -211.281807) (xy 256.156172 -211.317522)
			(xy 256.110291 -211.347008) (xy 256.060681 -211.369665) (xy 256.008351 -211.38503) (xy 255.954367 -211.392792)
			(xy 255.899829 -211.392792) (xy 255.845845 -211.38503) (xy 255.793515 -211.369665) (xy 255.743905 -211.347008)
			(xy 255.698024 -211.317522) (xy 255.656807 -211.281807) (xy 255.621092 -211.24059) (xy 255.591606 -211.194709)
			(xy 255.568949 -211.145099) (xy 255.553584 -211.092769) (xy 255.545822 -211.038785) (xy 255.545336 -211.011516)
			(xy 144.093464 -211.011516) (xy 144.136165 -211.045007) (xy 144.243077 -211.139101) (xy 144.344494 -211.239093)
			(xy 144.440091 -211.344662) (xy 144.529563 -211.455471) (xy 144.612622 -211.571164) (xy 144.689003 -211.691371)
			(xy 144.758461 -211.815706) (xy 144.820774 -211.943772) (xy 144.875741 -212.075159) (xy 144.923187 -212.209444)
			(xy 144.96296 -212.346199) (xy 144.994932 -212.484985) (xy 145.019002 -212.625357) (xy 145.035091 -212.766867)
			(xy 145.043148 -212.909059) (xy 145.043652 -212.98027) (xy 145.043148 -213.051481) (xy 145.035091 -213.193673)
			(xy 145.019002 -213.335183) (xy 144.994932 -213.475555) (xy 144.96296 -213.614341) (xy 144.923187 -213.751096)
			(xy 144.90378 -213.806024) (xy 255.545336 -213.806024) (xy 255.545336 -212.942424) (xy 255.545822 -212.915155)
			(xy 255.553584 -212.861171) (xy 255.568949 -212.808841) (xy 255.591606 -212.759231) (xy 255.621092 -212.71335)
			(xy 255.656807 -212.672133) (xy 255.698024 -212.636418) (xy 255.743905 -212.606932) (xy 255.793515 -212.584275)
			(xy 255.845845 -212.56891) (xy 255.899829 -212.561148) (xy 255.954367 -212.561148) (xy 256.008351 -212.56891)
			(xy 256.060681 -212.584275) (xy 256.110291 -212.606932) (xy 256.156172 -212.636418) (xy 256.197389 -212.672133)
			(xy 256.233104 -212.71335) (xy 256.26259 -212.759231) (xy 256.285247 -212.808841) (xy 256.300612 -212.861171)
			(xy 256.308374 -212.915155) (xy 256.30886 -212.942424) (xy 256.30886 -212.980016) (xy 326.752208 -212.980016)
			(xy 326.756238 -212.837681) (xy 326.768313 -212.695801) (xy 326.788396 -212.554833) (xy 326.816423 -212.415226)
			(xy 326.852303 -212.277428) (xy 326.895921 -212.141881) (xy 326.947138 -212.009019) (xy 327.005789 -211.879267)
			(xy 327.071687 -211.753041) (xy 327.144621 -211.630745) (xy 327.224358 -211.512772) (xy 327.31064 -211.399499)
			(xy 327.403193 -211.291288) (xy 327.50172 -211.188487) (xy 327.605905 -211.091425) (xy 327.715414 -211.000413)
			(xy 327.829897 -210.915741) (xy 327.948987 -210.837683) (xy 328.072302 -210.766487) (xy 328.199448 -210.702381)
			(xy 328.330017 -210.645572) (xy 328.463591 -210.59624) (xy 328.599742 -210.554544) (xy 328.738033 -210.520618)
			(xy 328.878023 -210.49457) (xy 329.019262 -210.476484) (xy 329.161298 -210.466417) (xy 329.303676 -210.464402)
			(xy 329.44594 -210.470445) (xy 329.587634 -210.484527) (xy 329.728304 -210.506603) (xy 329.867501 -210.536603)
			(xy 330.004777 -210.574429) (xy 330.139693 -210.619961) (xy 330.271817 -210.673052) (xy 330.400726 -210.733534)
			(xy 330.526007 -210.801212) (xy 330.647258 -210.875869) (xy 330.764091 -210.957267) (xy 330.876132 -211.045144)
			(xy 330.983022 -211.139219) (xy 331.084419 -211.239191) (xy 331.179997 -211.344739) (xy 331.269451 -211.455525)
			(xy 331.352493 -211.571194) (xy 331.428859 -211.691377) (xy 331.498303 -211.815687) (xy 331.560603 -211.943728)
			(xy 331.615559 -212.075087) (xy 331.662996 -212.209346) (xy 331.70276 -212.346073) (xy 331.734726 -212.484831)
			(xy 331.758791 -212.625175) (xy 331.774877 -212.766656) (xy 331.782932 -212.90882) (xy 331.783436 -212.980016)
			(xy 387.951476 -212.980016) (xy 387.955506 -212.837652) (xy 387.967584 -212.695744) (xy 387.987672 -212.554747)
			(xy 388.015704 -212.415112) (xy 388.051591 -212.277286) (xy 388.095218 -212.141712) (xy 388.146445 -212.008823)
			(xy 388.205108 -211.879044) (xy 388.27102 -211.752793) (xy 388.343969 -211.630473) (xy 388.423721 -211.512476)
			(xy 388.510021 -211.39918) (xy 388.602593 -211.290947) (xy 388.701139 -211.188125) (xy 388.805345 -211.091044)
			(xy 388.914877 -211.000013) (xy 389.029383 -210.915325) (xy 389.148497 -210.83725) (xy 389.271837 -210.76604)
			(xy 389.399008 -210.701921) (xy 389.529604 -210.6451) (xy 389.663204 -210.595759) (xy 389.799383 -210.554054)
			(xy 389.937702 -210.520121) (xy 390.07772 -210.494068) (xy 390.218987 -210.475978) (xy 390.361052 -210.465909)
			(xy 390.503459 -210.463894) (xy 390.645752 -210.469938) (xy 390.787474 -210.484024) (xy 390.928173 -210.506104)
			(xy 391.067398 -210.536109) (xy 391.204702 -210.573943) (xy 391.339645 -210.619484) (xy 391.471796 -210.672587)
			(xy 391.600731 -210.733081) (xy 391.726037 -210.800772) (xy 391.847313 -210.875445) (xy 391.964169 -210.956859)
			(xy 392.076233 -211.044753) (xy 392.183145 -211.138847) (xy 392.284562 -211.238839) (xy 392.380159 -211.344408)
			(xy 392.469631 -211.455217) (xy 392.55269 -211.57091) (xy 392.629071 -211.691117) (xy 392.698529 -211.815452)
			(xy 392.760842 -211.943518) (xy 392.815809 -212.074905) (xy 392.863255 -212.20919) (xy 392.903028 -212.345945)
			(xy 392.935 -212.484731) (xy 392.95907 -212.625103) (xy 392.975159 -212.766613) (xy 392.983216 -212.908805)
			(xy 392.98372 -212.980016) (xy 392.983216 -213.051227) (xy 392.975159 -213.193419) (xy 392.95907 -213.334929)
			(xy 392.935 -213.475301) (xy 392.903028 -213.614087) (xy 392.863255 -213.750842) (xy 392.815809 -213.885127)
			(xy 392.760842 -214.016514) (xy 392.698529 -214.14458) (xy 392.629071 -214.268915) (xy 392.55269 -214.389122)
			(xy 392.469631 -214.504815) (xy 392.380159 -214.615624) (xy 392.284562 -214.721193) (xy 392.183145 -214.821185)
			(xy 392.076233 -214.915279) (xy 391.964169 -215.003173) (xy 391.847313 -215.084587) (xy 391.726037 -215.15926)
			(xy 391.600731 -215.226951) (xy 391.471796 -215.287445) (xy 391.339645 -215.340548) (xy 391.204702 -215.386089)
			(xy 391.067398 -215.423923) (xy 390.928173 -215.453928) (xy 390.787474 -215.476008) (xy 390.645752 -215.490094)
			(xy 390.503459 -215.496138) (xy 390.361052 -215.494123) (xy 390.218987 -215.484054) (xy 390.07772 -215.465964)
			(xy 389.937702 -215.439911) (xy 389.799383 -215.405978) (xy 389.663204 -215.364273) (xy 389.529604 -215.314932)
			(xy 389.399008 -215.258111) (xy 389.271837 -215.193992) (xy 389.148497 -215.122782) (xy 389.029383 -215.044707)
			(xy 388.914877 -214.960019) (xy 388.805345 -214.868988) (xy 388.701139 -214.771907) (xy 388.602593 -214.669085)
			(xy 388.510021 -214.560852) (xy 388.423721 -214.447556) (xy 388.343969 -214.329559) (xy 388.27102 -214.207239)
			(xy 388.205108 -214.080988) (xy 388.146445 -213.951209) (xy 388.095218 -213.81832) (xy 388.051591 -213.682746)
			(xy 388.015704 -213.54492) (xy 387.987672 -213.405285) (xy 387.967584 -213.264288) (xy 387.955506 -213.12238)
			(xy 387.951476 -212.980016) (xy 331.783436 -212.980016) (xy 331.782932 -213.051212) (xy 331.774877 -213.193376)
			(xy 331.758791 -213.334857) (xy 331.734726 -213.475201) (xy 331.70276 -213.613959) (xy 331.662996 -213.750686)
			(xy 331.615559 -213.884945) (xy 331.560603 -214.016304) (xy 331.498303 -214.144345) (xy 331.428859 -214.268655)
			(xy 331.352493 -214.388838) (xy 331.269451 -214.504507) (xy 331.179997 -214.615293) (xy 331.084419 -214.720841)
			(xy 330.983022 -214.820813) (xy 330.876132 -214.914888) (xy 330.764091 -215.002765) (xy 330.647258 -215.084163)
			(xy 330.526007 -215.15882) (xy 330.400726 -215.226498) (xy 330.271817 -215.28698) (xy 330.139693 -215.340071)
			(xy 330.004777 -215.385603) (xy 329.867501 -215.423429) (xy 329.728304 -215.453429) (xy 329.587634 -215.475505)
			(xy 329.44594 -215.489587) (xy 329.303676 -215.49563) (xy 329.161298 -215.493615) (xy 329.019262 -215.483548)
			(xy 328.878023 -215.465462) (xy 328.738033 -215.439414) (xy 328.599742 -215.405488) (xy 328.463591 -215.363792)
			(xy 328.330017 -215.31446) (xy 328.199448 -215.257651) (xy 328.072302 -215.193545) (xy 327.948987 -215.122349)
			(xy 327.829897 -215.044291) (xy 327.715414 -214.959619) (xy 327.605905 -214.868607) (xy 327.50172 -214.771545)
			(xy 327.403193 -214.668744) (xy 327.31064 -214.560533) (xy 327.224358 -214.44726) (xy 327.144621 -214.329287)
			(xy 327.071687 -214.206991) (xy 327.005789 -214.080765) (xy 326.947138 -213.951013) (xy 326.895921 -213.818151)
			(xy 326.852303 -213.682604) (xy 326.816423 -213.544806) (xy 326.788396 -213.405199) (xy 326.768313 -213.264231)
			(xy 326.756238 -213.122351) (xy 326.752208 -212.980016) (xy 256.30886 -212.980016) (xy 256.30886 -213.806024)
			(xy 256.308374 -213.833293) (xy 256.300612 -213.887277) (xy 256.285247 -213.939607) (xy 256.26259 -213.989217)
			(xy 256.233104 -214.035098) (xy 256.197389 -214.076315) (xy 256.156172 -214.11203) (xy 256.110291 -214.141516)
			(xy 256.060681 -214.164173) (xy 256.008351 -214.179538) (xy 255.954367 -214.1873) (xy 255.899829 -214.1873)
			(xy 255.845845 -214.179538) (xy 255.793515 -214.164173) (xy 255.743905 -214.141516) (xy 255.698024 -214.11203)
			(xy 255.656807 -214.076315) (xy 255.621092 -214.035098) (xy 255.591606 -213.989217) (xy 255.568949 -213.939607)
			(xy 255.553584 -213.887277) (xy 255.545822 -213.833293) (xy 255.545336 -213.806024) (xy 144.90378 -213.806024)
			(xy 144.875741 -213.885381) (xy 144.820774 -214.016768) (xy 144.758461 -214.144834) (xy 144.689003 -214.269169)
			(xy 144.612622 -214.389376) (xy 144.529563 -214.505069) (xy 144.440091 -214.615878) (xy 144.344494 -214.721447)
			(xy 144.243077 -214.821439) (xy 144.136165 -214.915533) (xy 144.024101 -215.003427) (xy 143.907245 -215.084841)
			(xy 143.785969 -215.159514) (xy 143.660663 -215.227205) (xy 143.531728 -215.287699) (xy 143.399577 -215.340802)
			(xy 143.264634 -215.386343) (xy 143.12733 -215.424177) (xy 142.988105 -215.454182) (xy 142.847406 -215.476262)
			(xy 142.705684 -215.490348) (xy 142.563391 -215.496392) (xy 142.420984 -215.494377) (xy 142.278919 -215.484308)
			(xy 142.137652 -215.466218) (xy 141.997634 -215.440165) (xy 141.859315 -215.406232) (xy 141.723136 -215.364527)
			(xy 141.589536 -215.315186) (xy 141.45894 -215.258365) (xy 141.331769 -215.194246) (xy 141.208429 -215.123036)
			(xy 141.089315 -215.044961) (xy 140.974809 -214.960273) (xy 140.865277 -214.869242) (xy 140.761071 -214.772161)
			(xy 140.662525 -214.669339) (xy 140.569953 -214.561106) (xy 140.483653 -214.44781) (xy 140.403901 -214.329813)
			(xy 140.330952 -214.207493) (xy 140.26504 -214.081242) (xy 140.206377 -213.951463) (xy 140.15515 -213.818574)
			(xy 140.111523 -213.683) (xy 140.075636 -213.545174) (xy 140.047604 -213.405539) (xy 140.027516 -213.264542)
			(xy 140.015438 -213.122634) (xy 140.011408 -212.98027) (xy 83.843368 -212.98027) (xy 83.842864 -213.051466)
			(xy 83.834809 -213.19363) (xy 83.818723 -213.335111) (xy 83.794658 -213.475455) (xy 83.762692 -213.614213)
			(xy 83.722928 -213.75094) (xy 83.675491 -213.885199) (xy 83.620535 -214.016558) (xy 83.558235 -214.144599)
			(xy 83.488791 -214.268909) (xy 83.412425 -214.389092) (xy 83.329383 -214.504761) (xy 83.239929 -214.615547)
			(xy 83.144351 -214.721095) (xy 83.042954 -214.821067) (xy 82.936064 -214.915142) (xy 82.837488 -214.992458)
			(xy 94.106492 -214.992458) (xy 94.106492 -214.128858) (xy 94.106978 -214.101607) (xy 94.114734 -214.047659)
			(xy 94.130089 -213.995364) (xy 94.152731 -213.945787) (xy 94.182197 -213.899937) (xy 94.217888 -213.858746)
			(xy 94.259079 -213.823055) (xy 94.304929 -213.793589) (xy 94.354506 -213.770947) (xy 94.406801 -213.755592)
			(xy 94.460749 -213.747836) (xy 94.515251 -213.747836) (xy 94.569199 -213.755592) (xy 94.621494 -213.770947)
			(xy 94.671071 -213.793589) (xy 94.716921 -213.823055) (xy 94.758112 -213.858746) (xy 94.793803 -213.899937)
			(xy 94.823269 -213.945787) (xy 94.845911 -213.995364) (xy 94.861266 -214.047659) (xy 94.869022 -214.101607)
			(xy 94.869508 -214.128858) (xy 94.869508 -214.992458) (xy 94.869022 -215.019709) (xy 94.861266 -215.073657)
			(xy 94.845911 -215.125952) (xy 94.823269 -215.175529) (xy 94.793803 -215.221379) (xy 94.758112 -215.26257)
			(xy 94.716921 -215.298261) (xy 94.671071 -215.327727) (xy 94.621494 -215.350369) (xy 94.569199 -215.365724)
			(xy 94.515251 -215.37348) (xy 94.460749 -215.37348) (xy 94.406801 -215.365724) (xy 94.354506 -215.350369)
			(xy 94.304929 -215.327727) (xy 94.259079 -215.298261) (xy 94.217888 -215.26257) (xy 94.182197 -215.221379)
			(xy 94.152731 -215.175529) (xy 94.130089 -215.125952) (xy 94.114734 -215.073657) (xy 94.106978 -215.019709)
			(xy 94.106492 -214.992458) (xy 82.837488 -214.992458) (xy 82.824023 -215.003019) (xy 82.70719 -215.084417)
			(xy 82.585939 -215.159074) (xy 82.460658 -215.226752) (xy 82.331749 -215.287234) (xy 82.199625 -215.340325)
			(xy 82.064709 -215.385857) (xy 81.927433 -215.423683) (xy 81.788236 -215.453683) (xy 81.647566 -215.475759)
			(xy 81.505872 -215.489841) (xy 81.363608 -215.495884) (xy 81.22123 -215.493869) (xy 81.079194 -215.483802)
			(xy 80.937955 -215.465716) (xy 80.797965 -215.439668) (xy 80.659674 -215.405742) (xy 80.523523 -215.364046)
			(xy 80.389949 -215.314714) (xy 80.25938 -215.257905) (xy 80.132234 -215.193799) (xy 80.008919 -215.122603)
			(xy 79.889829 -215.044545) (xy 79.775346 -214.959873) (xy 79.665837 -214.868861) (xy 79.561652 -214.771799)
			(xy 79.463125 -214.668998) (xy 79.370572 -214.560787) (xy 79.28429 -214.447514) (xy 79.204553 -214.329541)
			(xy 79.131619 -214.207245) (xy 79.065721 -214.081019) (xy 79.00707 -213.951267) (xy 78.955853 -213.818405)
			(xy 78.912235 -213.682858) (xy 78.876355 -213.54506) (xy 78.848328 -213.405453) (xy 78.828245 -213.264485)
			(xy 78.81617 -213.122605) (xy 78.81214 -212.98027) (xy 2.509012 -212.98027) (xy 2.509012 -217.548574)
			(xy 338.152884 -217.548574) (xy 338.152884 -217.494026) (xy 338.160647 -217.440032) (xy 338.176017 -217.387693)
			(xy 338.198679 -217.338074) (xy 338.228172 -217.292186) (xy 338.263897 -217.250963) (xy 338.305125 -217.215244)
			(xy 338.351016 -217.185756) (xy 338.400638 -217.1631) (xy 338.452979 -217.147737) (xy 338.506973 -217.13998)
			(xy 338.534248 -217.13952) (xy 339.550248 -217.13952) (xy 339.577514 -217.140046) (xy 339.63149 -217.147813)
			(xy 339.683811 -217.163181) (xy 339.733413 -217.185839) (xy 339.779286 -217.215325) (xy 339.820495 -217.251039)
			(xy 339.856204 -217.292253) (xy 339.885684 -217.338129) (xy 339.908336 -217.387734) (xy 339.923698 -217.440057)
			(xy 339.931458 -217.494034) (xy 339.931458 -217.548566) (xy 339.923698 -217.602543) (xy 339.908336 -217.654866)
			(xy 339.885684 -217.704471) (xy 339.856204 -217.750347) (xy 339.820495 -217.791561) (xy 339.779286 -217.827275)
			(xy 339.733413 -217.856761) (xy 339.683811 -217.879419) (xy 339.63149 -217.894787) (xy 339.577514 -217.902554)
			(xy 339.550248 -217.903044) (xy 338.534248 -217.903044) (xy 338.506973 -217.90262) (xy 338.452979 -217.894863)
			(xy 338.400638 -217.8795) (xy 338.351016 -217.856844) (xy 338.305125 -217.827356) (xy 338.263897 -217.791637)
			(xy 338.228172 -217.750414) (xy 338.198679 -217.704526) (xy 338.176017 -217.654907) (xy 338.160647 -217.602568)
			(xy 338.152884 -217.548574) (xy 2.509012 -217.548574) (xy 2.509012 -219.820372) (xy 129.049982 -219.820372)
			(xy 129.049982 -219.765828) (xy 129.057745 -219.71184) (xy 129.073111 -219.659505) (xy 129.095769 -219.609891)
			(xy 129.125257 -219.564005) (xy 129.160975 -219.522783) (xy 129.202196 -219.487064) (xy 129.24808 -219.457575)
			(xy 129.297694 -219.434915) (xy 129.350028 -219.419547) (xy 129.404016 -219.411783) (xy 129.431288 -219.411296)
			(xy 130.447288 -219.411296) (xy 130.474557 -219.411843) (xy 130.528539 -219.419602) (xy 130.580867 -219.434966)
			(xy 130.630476 -219.45762) (xy 130.676357 -219.487104) (xy 130.717574 -219.522818) (xy 130.753288 -219.564034)
			(xy 130.782774 -219.609913) (xy 130.80543 -219.659522) (xy 130.820795 -219.711849) (xy 130.828557 -219.765831)
			(xy 130.828557 -219.820369) (xy 130.820795 -219.874351) (xy 130.80543 -219.926678) (xy 130.782774 -219.976287)
			(xy 130.753288 -220.022166) (xy 130.717574 -220.063382) (xy 130.676357 -220.099096) (xy 130.630476 -220.12858)
			(xy 130.580867 -220.151234) (xy 130.528539 -220.166598) (xy 130.474557 -220.174357) (xy 130.447288 -220.17482)
			(xy 129.431288 -220.17482) (xy 129.404016 -220.174417) (xy 129.350028 -220.166653) (xy 129.297694 -220.151285)
			(xy 129.24808 -220.128625) (xy 129.202196 -220.099136) (xy 129.160975 -220.063417) (xy 129.125257 -220.022195)
			(xy 129.095769 -219.976309) (xy 129.073111 -219.926695) (xy 129.057745 -219.87436) (xy 129.049982 -219.820372)
			(xy 2.509012 -219.820372) (xy 2.509012 -231.5243) (xy 100.194787 -231.5243) (xy 100.198963 -231.473911)
			(xy 100.211376 -231.424897) (xy 100.231688 -231.378595) (xy 100.259345 -231.336268) (xy 100.293592 -231.299071)
			(xy 100.333495 -231.268018) (xy 100.377964 -231.243958) (xy 100.425788 -231.227546) (xy 100.475661 -231.21923)
			(xy 100.500942 -231.21874) (xy 101.440996 -231.21874) (xy 101.466275 -231.219229) (xy 101.516144 -231.22755)
			(xy 101.563963 -231.243965) (xy 101.608428 -231.268028) (xy 101.648326 -231.299081) (xy 101.682568 -231.336278)
			(xy 101.710221 -231.378604) (xy 101.73053 -231.424903) (xy 101.742941 -231.473914) (xy 101.747117 -231.5243)
			(xy 103.014987 -231.5243) (xy 103.019163 -231.473915) (xy 103.031574 -231.424905) (xy 103.051883 -231.378605)
			(xy 103.079535 -231.33628) (xy 103.113777 -231.299084) (xy 103.153674 -231.268031) (xy 103.198139 -231.243969)
			(xy 103.245957 -231.227554) (xy 103.295825 -231.219233) (xy 103.321104 -231.21874) (xy 104.261158 -231.21874)
			(xy 104.286439 -231.219226) (xy 104.336313 -231.227542) (xy 104.384137 -231.243954) (xy 104.428608 -231.268015)
			(xy 104.468511 -231.299068) (xy 104.502758 -231.336265) (xy 104.530415 -231.378593) (xy 104.550727 -231.424896)
			(xy 104.563141 -231.473911) (xy 104.567317 -231.5243) (xy 105.834887 -231.5243) (xy 105.839063 -231.473914)
			(xy 105.851474 -231.424903) (xy 105.871784 -231.378603) (xy 105.899437 -231.336278) (xy 105.93368 -231.299081)
			(xy 105.973579 -231.268029) (xy 106.018044 -231.243967) (xy 106.065864 -231.227552) (xy 106.115733 -231.219232)
			(xy 106.141012 -231.21874) (xy 107.081066 -231.21874) (xy 107.106347 -231.219226) (xy 107.156219 -231.227544)
			(xy 107.204043 -231.243957) (xy 107.248512 -231.268018) (xy 107.288414 -231.299071) (xy 107.32266 -231.336268)
			(xy 107.350316 -231.378595) (xy 107.370628 -231.424897) (xy 107.383041 -231.473911) (xy 107.387192 -231.524)
			(xy 364.108988 -231.524) (xy 364.113159 -231.473663) (xy 364.125559 -231.4247) (xy 364.145849 -231.378445)
			(xy 364.173476 -231.336161) (xy 364.207685 -231.299001) (xy 364.247545 -231.267979) (xy 364.291968 -231.243941)
			(xy 364.339741 -231.227542) (xy 364.389561 -231.219231) (xy 364.414816 -231.21874) (xy 365.35487 -231.21874)
			(xy 365.380133 -231.219134) (xy 365.429971 -231.227446) (xy 365.477762 -231.243849) (xy 365.5222 -231.267894)
			(xy 365.562074 -231.298925) (xy 365.596297 -231.336097) (xy 365.623934 -231.378396) (xy 365.644231 -231.424666)
			(xy 365.656635 -231.473646) (xy 365.660808 -231.524) (xy 366.928888 -231.524) (xy 366.933059 -231.473662)
			(xy 366.945459 -231.424698) (xy 366.96575 -231.378443) (xy 366.993378 -231.336158) (xy 367.027588 -231.298998)
			(xy 367.067449 -231.267976) (xy 367.111873 -231.243938) (xy 367.159647 -231.227541) (xy 367.209469 -231.219231)
			(xy 367.234724 -231.21874) (xy 368.174778 -231.21874) (xy 368.200041 -231.219135) (xy 368.249878 -231.227448)
			(xy 368.297667 -231.243851) (xy 368.342104 -231.267896) (xy 368.381977 -231.298928) (xy 368.416199 -231.3361)
			(xy 368.443835 -231.378398) (xy 368.464132 -231.424667) (xy 368.476535 -231.473647) (xy 368.480708 -231.524)
			(xy 369.749117 -231.524) (xy 369.753287 -231.473671) (xy 369.765684 -231.424715) (xy 369.78597 -231.378467)
			(xy 369.813591 -231.336189) (xy 369.847793 -231.299033) (xy 369.887645 -231.268014) (xy 369.932059 -231.243976)
			(xy 369.979823 -231.227577) (xy 370.029635 -231.219263) (xy 370.054886 -231.21874) (xy 370.99494 -231.21874)
			(xy 371.020197 -231.219168) (xy 371.070022 -231.227489) (xy 371.117797 -231.243896) (xy 371.162221 -231.267942)
			(xy 371.202082 -231.298971) (xy 371.236292 -231.336138) (xy 371.263919 -231.378429) (xy 371.284209 -231.424689)
			(xy 371.296608 -231.473658) (xy 371.30078 -231.524) (xy 371.296608 -231.574342) (xy 371.284209 -231.623311)
			(xy 371.263919 -231.669571) (xy 371.236292 -231.711862) (xy 371.202082 -231.749029) (xy 371.162221 -231.780058)
			(xy 371.117797 -231.804104) (xy 371.070022 -231.820511) (xy 371.020197 -231.828832) (xy 370.99494 -231.829356)
			(xy 370.054886 -231.829356) (xy 370.029635 -231.828737) (xy 369.979823 -231.820423) (xy 369.932059 -231.804024)
			(xy 369.887645 -231.779986) (xy 369.847793 -231.748967) (xy 369.813591 -231.711811) (xy 369.78597 -231.669533)
			(xy 369.765684 -231.623285) (xy 369.753287 -231.574329) (xy 369.749117 -231.524) (xy 368.480708 -231.524)
			(xy 368.476535 -231.574353) (xy 368.464132 -231.623333) (xy 368.443835 -231.669602) (xy 368.416199 -231.7119)
			(xy 368.381977 -231.749072) (xy 368.342104 -231.780104) (xy 368.297667 -231.804149) (xy 368.249878 -231.820552)
			(xy 368.200041 -231.828865) (xy 368.174778 -231.829356) (xy 367.234724 -231.829356) (xy 367.209469 -231.828769)
			(xy 367.159647 -231.820459) (xy 367.111873 -231.804062) (xy 367.067449 -231.780024) (xy 367.027588 -231.749002)
			(xy 366.993378 -231.711842) (xy 366.96575 -231.669557) (xy 366.945459 -231.623302) (xy 366.933059 -231.574337)
			(xy 366.928888 -231.524) (xy 365.660808 -231.524) (xy 365.656635 -231.574354) (xy 365.644231 -231.623334)
			(xy 365.623934 -231.669604) (xy 365.596297 -231.711903) (xy 365.562074 -231.749075) (xy 365.5222 -231.780106)
			(xy 365.477762 -231.804151) (xy 365.429971 -231.820554) (xy 365.380133 -231.828866) (xy 365.35487 -231.829356)
			(xy 364.414816 -231.829356) (xy 364.389561 -231.828769) (xy 364.339741 -231.820458) (xy 364.291968 -231.804059)
			(xy 364.247545 -231.780021) (xy 364.207685 -231.748999) (xy 364.173476 -231.711839) (xy 364.145849 -231.669555)
			(xy 364.125559 -231.6233) (xy 364.113159 -231.574337) (xy 364.108988 -231.524) (xy 107.387192 -231.524)
			(xy 107.387217 -231.5243) (xy 107.383041 -231.574689) (xy 107.370628 -231.623703) (xy 107.350316 -231.670005)
			(xy 107.32266 -231.712332) (xy 107.288414 -231.749529) (xy 107.248512 -231.780582) (xy 107.204043 -231.804643)
			(xy 107.156219 -231.821056) (xy 107.106347 -231.829374) (xy 107.081066 -231.829864) (xy 106.141012 -231.829864)
			(xy 106.115733 -231.829368) (xy 106.065864 -231.821048) (xy 106.018044 -231.804633) (xy 105.973579 -231.780571)
			(xy 105.93368 -231.749519) (xy 105.899437 -231.712322) (xy 105.871784 -231.669997) (xy 105.851474 -231.623697)
			(xy 105.839063 -231.574686) (xy 105.834887 -231.5243) (xy 104.567317 -231.5243) (xy 104.563141 -231.574689)
			(xy 104.550727 -231.623704) (xy 104.530415 -231.670007) (xy 104.502758 -231.712335) (xy 104.468511 -231.749532)
			(xy 104.428608 -231.780585) (xy 104.384137 -231.804646) (xy 104.336313 -231.821058) (xy 104.286439 -231.829374)
			(xy 104.261158 -231.829864) (xy 103.321104 -231.829864) (xy 103.295825 -231.829367) (xy 103.245957 -231.821046)
			(xy 103.198139 -231.804631) (xy 103.153674 -231.780569) (xy 103.113777 -231.749516) (xy 103.079535 -231.71232)
			(xy 103.051883 -231.669995) (xy 103.031574 -231.623695) (xy 103.019163 -231.574685) (xy 103.014987 -231.5243)
			(xy 101.747117 -231.5243) (xy 101.742941 -231.574686) (xy 101.73053 -231.623697) (xy 101.710221 -231.669996)
			(xy 101.682568 -231.712322) (xy 101.648326 -231.749519) (xy 101.608428 -231.780572) (xy 101.563963 -231.804635)
			(xy 101.516144 -231.82105) (xy 101.466275 -231.829371) (xy 101.440996 -231.829864) (xy 100.500942 -231.829864)
			(xy 100.475661 -231.82937) (xy 100.425788 -231.821054) (xy 100.377964 -231.804642) (xy 100.333495 -231.780582)
			(xy 100.293592 -231.749529) (xy 100.259345 -231.712332) (xy 100.231688 -231.670005) (xy 100.211376 -231.623703)
			(xy 100.198963 -231.574689) (xy 100.194787 -231.5243) (xy 2.509012 -231.5243) (xy 2.509012 -232.3343)
			(xy 108.185148 -232.3343) (xy 108.18932 -232.283956) (xy 108.201721 -232.234986) (xy 108.222014 -232.188725)
			(xy 108.249645 -232.146435) (xy 108.28386 -232.10927) (xy 108.323725 -232.078244) (xy 108.368154 -232.054203)
			(xy 108.415934 -232.037803) (xy 108.465762 -232.029491) (xy 108.49102 -232.029) (xy 109.431074 -232.029)
			(xy 109.456334 -232.029475) (xy 109.506165 -232.037786) (xy 109.553948 -232.054187) (xy 109.59838 -232.078229)
			(xy 109.638249 -232.109256) (xy 109.672466 -232.146423) (xy 109.700099 -232.188716) (xy 109.720393 -232.23498)
			(xy 109.732796 -232.283953) (xy 109.736951 -232.3341) (xy 361.758639 -232.3341) (xy 361.762815 -232.283707)
			(xy 361.775229 -232.234688) (xy 361.795541 -232.188381) (xy 361.823198 -232.14605) (xy 361.857446 -232.108848)
			(xy 361.89735 -232.07779) (xy 361.941822 -232.053724) (xy 361.989649 -232.037306) (xy 362.039525 -232.028985)
			(xy 362.064808 -232.028492) (xy 363.004862 -232.028492) (xy 363.030139 -232.029074) (xy 363.080004 -232.037389)
			(xy 363.127821 -232.053799) (xy 363.172283 -232.077857) (xy 363.21218 -232.108905) (xy 363.246421 -232.146096)
			(xy 363.274073 -232.188417) (xy 363.294382 -232.234712) (xy 363.306793 -232.283719) (xy 363.310969 -232.3341)
			(xy 363.306793 -232.384481) (xy 363.294382 -232.433488) (xy 363.274073 -232.479783) (xy 363.246421 -232.522104)
			(xy 363.21218 -232.559295) (xy 363.172283 -232.590343) (xy 363.127821 -232.614401) (xy 363.080004 -232.630811)
			(xy 363.030139 -232.639126) (xy 363.004862 -232.639616) (xy 362.064808 -232.639616) (xy 362.039525 -232.639215)
			(xy 361.989649 -232.630894) (xy 361.941822 -232.614476) (xy 361.89735 -232.59041) (xy 361.857446 -232.559352)
			(xy 361.823198 -232.52215) (xy 361.795541 -232.479819) (xy 361.775229 -232.433512) (xy 361.762815 -232.384493)
			(xy 361.758639 -232.3341) (xy 109.736951 -232.3341) (xy 109.736968 -232.3343) (xy 109.732796 -232.384647)
			(xy 109.720393 -232.43362) (xy 109.700099 -232.479884) (xy 109.672466 -232.522177) (xy 109.638249 -232.559344)
			(xy 109.59838 -232.590371) (xy 109.553948 -232.614413) (xy 109.506165 -232.630814) (xy 109.456334 -232.639125)
			(xy 109.431074 -232.639616) (xy 108.49102 -232.639616) (xy 108.465762 -232.639109) (xy 108.415934 -232.630797)
			(xy 108.368154 -232.614397) (xy 108.323725 -232.590356) (xy 108.28386 -232.55933) (xy 108.249645 -232.522165)
			(xy 108.222014 -232.479875) (xy 108.201721 -232.433614) (xy 108.18932 -232.384644) (xy 108.185148 -232.3343)
			(xy 2.509012 -232.3343) (xy 2.509012 -233.1443) (xy 97.374899 -233.1443) (xy 97.379075 -233.093914)
			(xy 97.391487 -233.044903) (xy 97.411798 -232.998603) (xy 97.439453 -232.956278) (xy 97.473697 -232.919082)
			(xy 97.513597 -232.888031) (xy 97.558064 -232.863971) (xy 97.605885 -232.847559) (xy 97.655755 -232.839242)
			(xy 97.681034 -232.838752) (xy 98.621088 -232.838752) (xy 98.646369 -232.839216) (xy 98.69624 -232.847536)
			(xy 98.744062 -232.863952) (xy 98.78853 -232.888015) (xy 98.828431 -232.91907) (xy 98.862675 -232.956268)
			(xy 98.89033 -232.998596) (xy 98.910641 -233.044898) (xy 98.923053 -233.093912) (xy 98.927229 -233.1443)
			(xy 100.194799 -233.1443) (xy 100.198975 -233.093913) (xy 100.211388 -233.044901) (xy 100.231699 -232.998601)
			(xy 100.259355 -232.956275) (xy 100.2936 -232.91908) (xy 100.333501 -232.888028) (xy 100.377969 -232.863969)
			(xy 100.425791 -232.847557) (xy 100.475662 -232.839242) (xy 100.500942 -232.838752) (xy 101.440996 -232.838752)
			(xy 101.466276 -232.839217) (xy 101.516147 -232.847538) (xy 101.563968 -232.863954) (xy 101.608434 -232.888018)
			(xy 101.648334 -232.919073) (xy 101.682577 -232.956271) (xy 101.710231 -232.998598) (xy 101.730541 -233.044899)
			(xy 101.742953 -233.093912) (xy 101.747129 -233.1443) (xy 103.014999 -233.1443) (xy 103.019174 -233.093917)
			(xy 103.031585 -233.044909) (xy 103.051893 -232.998611) (xy 103.079545 -232.956288) (xy 103.113785 -232.919093)
			(xy 103.153681 -232.888042) (xy 103.198144 -232.86398) (xy 103.24596 -232.847565) (xy 103.295826 -232.839245)
			(xy 103.321104 -232.838752) (xy 104.261158 -232.838752) (xy 104.28644 -232.839214) (xy 104.336316 -232.84753)
			(xy 104.384142 -232.863943) (xy 104.428614 -232.888005) (xy 104.468519 -232.919059) (xy 104.502768 -232.956258)
			(xy 104.530426 -232.998587) (xy 104.550739 -233.044892) (xy 104.563153 -233.093909) (xy 104.567329 -233.1443)
			(xy 105.834899 -233.1443) (xy 105.839075 -233.093916) (xy 105.851486 -233.044907) (xy 105.871794 -232.998609)
			(xy 105.899447 -232.956285) (xy 105.933688 -232.91909) (xy 105.973585 -232.888039) (xy 106.018049 -232.863978)
			(xy 106.065867 -232.847564) (xy 106.115734 -232.839244) (xy 106.141012 -232.838752) (xy 107.081066 -232.838752)
			(xy 107.106348 -232.839214) (xy 107.156222 -232.847532) (xy 107.204047 -232.863946) (xy 107.248518 -232.888008)
			(xy 107.288422 -232.919062) (xy 107.32267 -232.956261) (xy 107.350327 -232.998589) (xy 107.370639 -233.044893)
			(xy 107.383053 -233.093909) (xy 107.387212 -233.1441) (xy 364.1089 -233.1441) (xy 364.113072 -233.093749)
			(xy 364.125476 -233.044771) (xy 364.145771 -232.998503) (xy 364.173406 -232.956207) (xy 364.207626 -232.919036)
			(xy 364.247497 -232.888005) (xy 364.291932 -232.86396) (xy 364.339719 -232.847557) (xy 364.389554 -232.839244)
			(xy 364.414816 -232.838752) (xy 365.35487 -232.838752) (xy 365.380126 -232.839322) (xy 365.42995 -232.847632)
			(xy 365.477726 -232.864029) (xy 365.522152 -232.888067) (xy 365.562015 -232.91909) (xy 365.596227 -232.956251)
			(xy 365.623856 -232.998537) (xy 365.644148 -233.044794) (xy 365.656548 -233.093761) (xy 365.66072 -233.1441)
			(xy 366.9288 -233.1441) (xy 366.932972 -233.093748) (xy 366.945376 -233.04477) (xy 366.965673 -232.998501)
			(xy 366.993308 -232.956204) (xy 367.027529 -232.919033) (xy 367.067401 -232.888002) (xy 367.111838 -232.863958)
			(xy 367.159626 -232.847555) (xy 367.209462 -232.839243) (xy 367.234724 -232.838752) (xy 368.174778 -232.838752)
			(xy 368.200034 -232.839323) (xy 368.249856 -232.847633) (xy 368.297632 -232.864032) (xy 368.342056 -232.88807)
			(xy 368.381918 -232.919093) (xy 368.416129 -232.956254) (xy 368.443757 -232.99854) (xy 368.464048 -233.044796)
			(xy 368.476449 -233.093761) (xy 368.48062 -233.1441) (xy 369.749029 -233.1441) (xy 369.7532 -233.093757)
			(xy 369.765601 -233.044787) (xy 369.785892 -232.998525) (xy 369.813521 -232.956235) (xy 369.847734 -232.919068)
			(xy 369.887597 -232.88804) (xy 369.932024 -232.863996) (xy 369.979802 -232.847591) (xy 370.029628 -232.839275)
			(xy 370.054886 -232.838752) (xy 370.99494 -232.838752) (xy 371.02019 -232.839357) (xy 371.07 -232.847674)
			(xy 371.117762 -232.864077) (xy 371.162173 -232.888116) (xy 371.202022 -232.919137) (xy 371.236222 -232.956293)
			(xy 371.263841 -232.998571) (xy 371.284125 -233.044818) (xy 371.296521 -233.093773) (xy 371.300691 -233.1441)
			(xy 372.568929 -233.1441) (xy 372.573101 -233.093756) (xy 372.585502 -233.044785) (xy 372.605794 -232.998523)
			(xy 372.633423 -232.956232) (xy 372.667637 -232.919066) (xy 372.707501 -232.888037) (xy 372.751929 -232.863993)
			(xy 372.799708 -232.84759) (xy 372.849536 -232.839274) (xy 372.874794 -232.838752) (xy 373.814848 -232.838752)
			(xy 373.840097 -232.839357) (xy 373.889906 -232.847676) (xy 373.937667 -232.864079) (xy 373.982077 -232.888119)
			(xy 374.021925 -232.919139) (xy 374.056124 -232.956295) (xy 374.083742 -232.998573) (xy 374.104026 -233.044819)
			(xy 374.116421 -233.093773) (xy 374.120591 -233.1441) (xy 374.116421 -233.194427) (xy 374.104026 -233.243381)
			(xy 374.083742 -233.289627) (xy 374.056125 -233.331905) (xy 374.021925 -233.369061) (xy 373.982077 -233.400081)
			(xy 373.937667 -233.424121) (xy 373.889907 -233.440524) (xy 373.840097 -233.448843) (xy 373.814848 -233.449368)
			(xy 372.874794 -233.449368) (xy 372.849536 -233.448926) (xy 372.799708 -233.44061) (xy 372.751929 -233.424207)
			(xy 372.707501 -233.400163) (xy 372.667637 -233.369134) (xy 372.633423 -233.331968) (xy 372.605794 -233.289677)
			(xy 372.585502 -233.243415) (xy 372.573101 -233.194444) (xy 372.568929 -233.1441) (xy 371.300691 -233.1441)
			(xy 371.296521 -233.194427) (xy 371.284125 -233.243382) (xy 371.263841 -233.289629) (xy 371.236222 -233.331907)
			(xy 371.202022 -233.369063) (xy 371.162173 -233.400084) (xy 371.117762 -233.424123) (xy 371.07 -233.440526)
			(xy 371.02019 -233.448843) (xy 370.99494 -233.449368) (xy 370.054886 -233.449368) (xy 370.029628 -233.448925)
			(xy 369.979802 -233.440609) (xy 369.932024 -233.424204) (xy 369.887597 -233.40016) (xy 369.847734 -233.369132)
			(xy 369.813521 -233.331965) (xy 369.785892 -233.289675) (xy 369.765601 -233.243413) (xy 369.7532 -233.194443)
			(xy 369.749029 -233.1441) (xy 368.48062 -233.1441) (xy 368.476449 -233.194439) (xy 368.464048 -233.243404)
			(xy 368.443757 -233.28966) (xy 368.416129 -233.331946) (xy 368.381918 -233.369107) (xy 368.342056 -233.40013)
			(xy 368.297632 -233.424168) (xy 368.249856 -233.440567) (xy 368.200034 -233.448877) (xy 368.174778 -233.449368)
			(xy 367.234724 -233.449368) (xy 367.209462 -233.448957) (xy 367.159626 -233.440645) (xy 367.111838 -233.424242)
			(xy 367.067401 -233.400198) (xy 367.027529 -233.369167) (xy 366.993308 -233.331996) (xy 366.965673 -233.289699)
			(xy 366.945376 -233.24343) (xy 366.932972 -233.194452) (xy 366.9288 -233.1441) (xy 365.66072 -233.1441)
			(xy 365.656548 -233.194439) (xy 365.644148 -233.243406) (xy 365.623856 -233.289663) (xy 365.596227 -233.331949)
			(xy 365.562015 -233.36911) (xy 365.522152 -233.400133) (xy 365.477726 -233.424171) (xy 365.42995 -233.440568)
			(xy 365.380126 -233.448878) (xy 365.35487 -233.449368) (xy 364.414816 -233.449368) (xy 364.389554 -233.448956)
			(xy 364.339719 -233.440643) (xy 364.291932 -233.42424) (xy 364.247497 -233.400195) (xy 364.207626 -233.369164)
			(xy 364.173406 -233.331993) (xy 364.145771 -233.289697) (xy 364.125476 -233.243429) (xy 364.113072 -233.194451)
			(xy 364.1089 -233.1441) (xy 107.387212 -233.1441) (xy 107.387229 -233.1443) (xy 107.383053 -233.194691)
			(xy 107.370639 -233.243707) (xy 107.350327 -233.290011) (xy 107.32267 -233.332339) (xy 107.288422 -233.369538)
			(xy 107.248518 -233.400592) (xy 107.204047 -233.424654) (xy 107.156222 -233.441068) (xy 107.106348 -233.449386)
			(xy 107.081066 -233.449876) (xy 106.141012 -233.449876) (xy 106.115734 -233.449356) (xy 106.065867 -233.441036)
			(xy 106.018049 -233.424622) (xy 105.973585 -233.400561) (xy 105.933688 -233.36951) (xy 105.899447 -233.332315)
			(xy 105.871794 -233.289991) (xy 105.851486 -233.243693) (xy 105.839075 -233.194684) (xy 105.834899 -233.1443)
			(xy 104.567329 -233.1443) (xy 104.563153 -233.194691) (xy 104.550739 -233.243708) (xy 104.530426 -233.290013)
			(xy 104.502768 -233.332342) (xy 104.468519 -233.369541) (xy 104.428614 -233.400595) (xy 104.384142 -233.424657)
			(xy 104.336316 -233.44107) (xy 104.28644 -233.449386) (xy 104.261158 -233.449876) (xy 103.321104 -233.449876)
			(xy 103.295826 -233.449355) (xy 103.24596 -233.441035) (xy 103.198144 -233.42462) (xy 103.153681 -233.400558)
			(xy 103.113785 -233.369507) (xy 103.079545 -233.332312) (xy 103.051893 -233.289989) (xy 103.031585 -233.243691)
			(xy 103.019174 -233.194683) (xy 103.014999 -233.1443) (xy 101.747129 -233.1443) (xy 101.742953 -233.194688)
			(xy 101.730541 -233.243701) (xy 101.710231 -233.290002) (xy 101.682577 -233.332329) (xy 101.648334 -233.369527)
			(xy 101.608434 -233.400582) (xy 101.563968 -233.424646) (xy 101.516147 -233.441062) (xy 101.466276 -233.449383)
			(xy 101.440996 -233.449876) (xy 100.500942 -233.449876) (xy 100.475662 -233.449358) (xy 100.425791 -233.441043)
			(xy 100.377969 -233.424631) (xy 100.333501 -233.400572) (xy 100.2936 -233.36952) (xy 100.259355 -233.332325)
			(xy 100.231699 -233.289999) (xy 100.211388 -233.243699) (xy 100.198975 -233.194687) (xy 100.194799 -233.1443)
			(xy 98.927229 -233.1443) (xy 98.923053 -233.194688) (xy 98.910641 -233.243702) (xy 98.89033 -233.290004)
			(xy 98.862675 -233.332332) (xy 98.828431 -233.36953) (xy 98.78853 -233.400585) (xy 98.744062 -233.424648)
			(xy 98.69624 -233.441064) (xy 98.646369 -233.449384) (xy 98.621088 -233.449876) (xy 97.681034 -233.449876)
			(xy 97.655755 -233.449358) (xy 97.605885 -233.441041) (xy 97.558064 -233.424629) (xy 97.513597 -233.400569)
			(xy 97.473697 -233.369518) (xy 97.439453 -233.332322) (xy 97.411798 -233.289997) (xy 97.391487 -233.243697)
			(xy 97.379075 -233.194686) (xy 97.374899 -233.1443) (xy 2.509012 -233.1443) (xy 2.509012 -233.9543)
			(xy 108.18516 -233.9543) (xy 108.189332 -233.903958) (xy 108.201733 -233.85499) (xy 108.222025 -233.808731)
			(xy 108.249654 -233.766443) (xy 108.283868 -233.729279) (xy 108.323732 -233.698254) (xy 108.368159 -233.674214)
			(xy 108.415937 -233.657814) (xy 108.465763 -233.649503) (xy 108.49102 -233.649012) (xy 109.431074 -233.649012)
			(xy 109.456335 -233.649463) (xy 109.506168 -233.657774) (xy 109.553953 -233.674176) (xy 109.598387 -233.698219)
			(xy 109.638257 -233.729247) (xy 109.672476 -233.766416) (xy 109.70011 -233.80871) (xy 109.720405 -233.854976)
			(xy 109.732808 -233.903951) (xy 109.736963 -233.9541) (xy 361.758651 -233.9541) (xy 361.762827 -233.903709)
			(xy 361.77524 -233.854692) (xy 361.795552 -233.808387) (xy 361.823208 -233.766057) (xy 361.857454 -233.728856)
			(xy 361.897357 -233.6978) (xy 361.941827 -233.673735) (xy 361.989652 -233.657318) (xy 362.039526 -233.648997)
			(xy 362.064808 -233.648504) (xy 363.004862 -233.648504) (xy 363.03014 -233.649062) (xy 363.080007 -233.657378)
			(xy 363.127825 -233.673788) (xy 363.17229 -233.697847) (xy 363.212188 -233.728896) (xy 363.246431 -233.766089)
			(xy 363.274084 -233.808411) (xy 363.294394 -233.854708) (xy 363.306805 -233.903717) (xy 363.310981 -233.9541)
			(xy 363.306805 -234.004483) (xy 363.294394 -234.053492) (xy 363.274084 -234.099789) (xy 363.246431 -234.142111)
			(xy 363.212188 -234.179304) (xy 363.17229 -234.210353) (xy 363.127825 -234.234412) (xy 363.080007 -234.250822)
			(xy 363.03014 -234.259138) (xy 363.004862 -234.259628) (xy 362.064808 -234.259628) (xy 362.039526 -234.259203)
			(xy 361.989652 -234.250882) (xy 361.941827 -234.234465) (xy 361.897357 -234.2104) (xy 361.857454 -234.179344)
			(xy 361.823208 -234.142143) (xy 361.795552 -234.099813) (xy 361.77524 -234.053508) (xy 361.762827 -234.004491)
			(xy 361.758651 -233.9541) (xy 109.736963 -233.9541) (xy 109.73698 -233.9543) (xy 109.732808 -234.004649)
			(xy 109.720405 -234.053624) (xy 109.70011 -234.09989) (xy 109.672476 -234.142184) (xy 109.638257 -234.179353)
			(xy 109.598387 -234.210381) (xy 109.553953 -234.234424) (xy 109.506168 -234.250826) (xy 109.456335 -234.259137)
			(xy 109.431074 -234.259628) (xy 108.49102 -234.259628) (xy 108.465763 -234.259097) (xy 108.415937 -234.250786)
			(xy 108.368159 -234.234386) (xy 108.323732 -234.210346) (xy 108.283868 -234.179321) (xy 108.249654 -234.142157)
			(xy 108.222025 -234.099869) (xy 108.201733 -234.05361) (xy 108.189332 -234.004642) (xy 108.18516 -233.9543)
			(xy 2.509012 -233.9543) (xy 2.509012 -234.7643) (xy 97.374911 -234.7643) (xy 97.379087 -234.713916)
			(xy 97.391499 -234.664906) (xy 97.411808 -234.618609) (xy 97.439462 -234.576285) (xy 97.473705 -234.539091)
			(xy 97.513603 -234.508041) (xy 97.558069 -234.483982) (xy 97.605888 -234.467571) (xy 97.655756 -234.459254)
			(xy 97.681034 -234.458764) (xy 98.621088 -234.458764) (xy 98.64637 -234.459204) (xy 98.696243 -234.467525)
			(xy 98.744067 -234.483941) (xy 98.788537 -234.508005) (xy 98.828439 -234.539061) (xy 98.862685 -234.576261)
			(xy 98.890341 -234.61859) (xy 98.910652 -234.664894) (xy 98.923065 -234.71391) (xy 98.927241 -234.7643)
			(xy 100.194811 -234.7643) (xy 100.198987 -234.713915) (xy 100.211399 -234.664905) (xy 100.23171 -234.618606)
			(xy 100.259364 -234.576283) (xy 100.293608 -234.539088) (xy 100.333508 -234.508038) (xy 100.377974 -234.48398)
			(xy 100.425794 -234.467569) (xy 100.475663 -234.459254) (xy 100.500942 -234.458764) (xy 101.440996 -234.458764)
			(xy 101.466277 -234.459205) (xy 101.51615 -234.467526) (xy 101.563973 -234.483944) (xy 101.608441 -234.508008)
			(xy 101.648342 -234.539064) (xy 101.682587 -234.576263) (xy 101.710242 -234.618592) (xy 101.730553 -234.664896)
			(xy 101.742965 -234.713911) (xy 101.747141 -234.7643) (xy 103.015011 -234.7643) (xy 103.019186 -234.713919)
			(xy 103.031596 -234.664912) (xy 103.051904 -234.618617) (xy 103.079554 -234.576295) (xy 103.113793 -234.539102)
			(xy 103.153688 -234.508052) (xy 103.198148 -234.483991) (xy 103.245963 -234.467577) (xy 103.295827 -234.459257)
			(xy 103.321104 -234.458764) (xy 104.261158 -234.458764) (xy 104.286441 -234.459202) (xy 104.336319 -234.467519)
			(xy 104.384147 -234.483932) (xy 104.428621 -234.507995) (xy 104.468527 -234.53905) (xy 104.502777 -234.576251)
			(xy 104.530436 -234.618582) (xy 104.55075 -234.664888) (xy 104.563164 -234.713907) (xy 104.567341 -234.7643)
			(xy 105.834911 -234.7643) (xy 105.839086 -234.713918) (xy 105.851497 -234.664911) (xy 105.871805 -234.618615)
			(xy 105.899456 -234.576293) (xy 105.933697 -234.539099) (xy 105.973592 -234.508049) (xy 106.018054 -234.483989)
			(xy 106.06587 -234.467575) (xy 106.115735 -234.459256) (xy 106.141012 -234.458764) (xy 107.081066 -234.458764)
			(xy 107.106349 -234.459202) (xy 107.156225 -234.46752) (xy 107.204052 -234.483935) (xy 107.248525 -234.507998)
			(xy 107.28843 -234.539053) (xy 107.322679 -234.576253) (xy 107.350337 -234.618584) (xy 107.370651 -234.66489)
			(xy 107.383065 -234.713907) (xy 107.387224 -234.7641) (xy 364.108912 -234.7641) (xy 364.113084 -234.713751)
			(xy 364.125487 -234.664775) (xy 364.145782 -234.618509) (xy 364.173416 -234.576214) (xy 364.207634 -234.539045)
			(xy 364.247504 -234.508015) (xy 364.291937 -234.483971) (xy 364.339722 -234.467569) (xy 364.389555 -234.459256)
			(xy 364.414816 -234.458764) (xy 365.35487 -234.458764) (xy 365.380127 -234.45931) (xy 365.429953 -234.46762)
			(xy 365.477731 -234.484018) (xy 365.522158 -234.508057) (xy 365.562023 -234.539081) (xy 365.596237 -234.576244)
			(xy 365.623867 -234.618532) (xy 365.644159 -234.664791) (xy 365.65656 -234.713759) (xy 365.660732 -234.7641)
			(xy 366.928812 -234.7641) (xy 366.932984 -234.71375) (xy 366.945387 -234.664774) (xy 366.965683 -234.618507)
			(xy 366.993318 -234.576212) (xy 367.027537 -234.539042) (xy 367.067408 -234.508013) (xy 367.111842 -234.483969)
			(xy 367.159629 -234.467567) (xy 367.209463 -234.459255) (xy 367.234724 -234.458764) (xy 368.174778 -234.458764)
			(xy 368.200035 -234.459311) (xy 368.249859 -234.467622) (xy 368.297636 -234.484021) (xy 368.342063 -234.50806)
			(xy 368.381926 -234.539084) (xy 368.416139 -234.576247) (xy 368.443768 -234.618534) (xy 368.46406 -234.664792)
			(xy 368.47646 -234.713759) (xy 368.480632 -234.7641) (xy 369.749041 -234.7641) (xy 369.753212 -234.713759)
			(xy 369.765612 -234.664791) (xy 369.785903 -234.618531) (xy 369.813531 -234.576242) (xy 369.847742 -234.539077)
			(xy 369.887604 -234.50805) (xy 369.932028 -234.484007) (xy 369.979805 -234.467603) (xy 370.029629 -234.459287)
			(xy 370.054886 -234.458764) (xy 370.99494 -234.458764) (xy 371.020191 -234.459345) (xy 371.070003 -234.467663)
			(xy 371.117767 -234.484066) (xy 371.16218 -234.508106) (xy 371.20203 -234.539128) (xy 371.236232 -234.576285)
			(xy 371.263852 -234.618565) (xy 371.284136 -234.664814) (xy 371.296533 -234.713771) (xy 371.300703 -234.7641)
			(xy 372.568941 -234.7641) (xy 372.573112 -234.713758) (xy 372.585513 -234.664789) (xy 372.605804 -234.618529)
			(xy 372.633433 -234.57624) (xy 372.667645 -234.539074) (xy 372.707508 -234.508047) (xy 372.751934 -234.484004)
			(xy 372.799711 -234.467601) (xy 372.849537 -234.459286) (xy 372.874794 -234.458764) (xy 373.814848 -234.458764)
			(xy 373.840098 -234.459345) (xy 373.889909 -234.467664) (xy 373.937672 -234.484068) (xy 373.982084 -234.508109)
			(xy 374.021933 -234.539131) (xy 374.056134 -234.576288) (xy 374.083753 -234.618567) (xy 374.104037 -234.664815)
			(xy 374.116433 -234.713771) (xy 374.120603 -234.7641) (xy 374.116433 -234.814429) (xy 374.104037 -234.863384)
			(xy 374.083753 -234.909633) (xy 374.056134 -234.951912) (xy 374.021933 -234.989069) (xy 373.982084 -235.020091)
			(xy 373.937672 -235.044132) (xy 373.889909 -235.060536) (xy 373.840098 -235.068855) (xy 373.814848 -235.06938)
			(xy 372.874794 -235.06938) (xy 372.849537 -235.068914) (xy 372.799711 -235.060599) (xy 372.751934 -235.044196)
			(xy 372.707508 -235.020153) (xy 372.667645 -234.989126) (xy 372.633433 -234.95196) (xy 372.605804 -234.909671)
			(xy 372.585513 -234.863411) (xy 372.573112 -234.814442) (xy 372.568941 -234.7641) (xy 371.300703 -234.7641)
			(xy 371.296533 -234.814429) (xy 371.284136 -234.863386) (xy 371.263852 -234.909635) (xy 371.236232 -234.951915)
			(xy 371.20203 -234.989072) (xy 371.16218 -235.020094) (xy 371.117767 -235.044134) (xy 371.070003 -235.060537)
			(xy 371.020191 -235.068855) (xy 370.99494 -235.06938) (xy 370.054886 -235.06938) (xy 370.029629 -235.068913)
			(xy 369.979805 -235.060597) (xy 369.932028 -235.044193) (xy 369.887604 -235.02015) (xy 369.847742 -234.989123)
			(xy 369.813531 -234.951958) (xy 369.785903 -234.909669) (xy 369.765612 -234.863409) (xy 369.753212 -234.814441)
			(xy 369.749041 -234.7641) (xy 368.480632 -234.7641) (xy 368.47646 -234.814441) (xy 368.46406 -234.863408)
			(xy 368.443768 -234.909666) (xy 368.416139 -234.951953) (xy 368.381926 -234.989116) (xy 368.342063 -235.02014)
			(xy 368.297636 -235.044179) (xy 368.249859 -235.060578) (xy 368.200035 -235.068889) (xy 368.174778 -235.06938)
			(xy 367.234724 -235.06938) (xy 367.209463 -235.068945) (xy 367.159629 -235.060633) (xy 367.111842 -235.044231)
			(xy 367.067408 -235.020187) (xy 367.027537 -234.989158) (xy 366.993318 -234.951988) (xy 366.965683 -234.909693)
			(xy 366.945387 -234.863426) (xy 366.932984 -234.81445) (xy 366.928812 -234.7641) (xy 365.660732 -234.7641)
			(xy 365.65656 -234.814441) (xy 365.644159 -234.863409) (xy 365.623867 -234.909668) (xy 365.596237 -234.951956)
			(xy 365.562023 -234.989119) (xy 365.522158 -235.020143) (xy 365.477731 -235.044182) (xy 365.429953 -235.06058)
			(xy 365.380127 -235.06889) (xy 365.35487 -235.06938) (xy 364.414816 -235.06938) (xy 364.389555 -235.068944)
			(xy 364.339722 -235.060631) (xy 364.291937 -235.044229) (xy 364.247504 -235.020185) (xy 364.207634 -234.989155)
			(xy 364.173416 -234.951986) (xy 364.145782 -234.909691) (xy 364.125487 -234.863425) (xy 364.113084 -234.814449)
			(xy 364.108912 -234.7641) (xy 107.387224 -234.7641) (xy 107.387241 -234.7643) (xy 107.383065 -234.814693)
			(xy 107.370651 -234.86371) (xy 107.350337 -234.910016) (xy 107.322679 -234.952347) (xy 107.28843 -234.989547)
			(xy 107.248525 -235.020602) (xy 107.204052 -235.044665) (xy 107.156225 -235.06108) (xy 107.106349 -235.069398)
			(xy 107.081066 -235.069888) (xy 106.141012 -235.069888) (xy 106.115735 -235.069344) (xy 106.06587 -235.061025)
			(xy 106.018054 -235.044611) (xy 105.973592 -235.020551) (xy 105.933697 -234.989501) (xy 105.899456 -234.952307)
			(xy 105.871805 -234.909985) (xy 105.851497 -234.863689) (xy 105.839086 -234.814682) (xy 105.834911 -234.7643)
			(xy 104.567341 -234.7643) (xy 104.563164 -234.814693) (xy 104.55075 -234.863712) (xy 104.530436 -234.910018)
			(xy 104.502777 -234.952349) (xy 104.468527 -234.98955) (xy 104.428621 -235.020605) (xy 104.384147 -235.044668)
			(xy 104.336319 -235.061081) (xy 104.286441 -235.069398) (xy 104.261158 -235.069888) (xy 103.321104 -235.069888)
			(xy 103.295827 -235.069343) (xy 103.245963 -235.061023) (xy 103.198148 -235.044609) (xy 103.153688 -235.020548)
			(xy 103.113793 -234.989498) (xy 103.079554 -234.952305) (xy 103.051904 -234.909983) (xy 103.031596 -234.863688)
			(xy 103.019186 -234.814681) (xy 103.015011 -234.7643) (xy 101.747141 -234.7643) (xy 101.742965 -234.814689)
			(xy 101.730553 -234.863704) (xy 101.710242 -234.910008) (xy 101.682587 -234.952337) (xy 101.648342 -234.989536)
			(xy 101.608441 -235.020592) (xy 101.563973 -235.044656) (xy 101.51615 -235.061074) (xy 101.466277 -235.069395)
			(xy 101.440996 -235.069888) (xy 100.500942 -235.069888) (xy 100.475663 -235.069346) (xy 100.425794 -235.061031)
			(xy 100.377974 -235.04462) (xy 100.333508 -235.020562) (xy 100.293608 -234.989512) (xy 100.259364 -234.952317)
			(xy 100.23171 -234.909994) (xy 100.211399 -234.863695) (xy 100.198987 -234.814685) (xy 100.194811 -234.7643)
			(xy 98.927241 -234.7643) (xy 98.923065 -234.81469) (xy 98.910652 -234.863706) (xy 98.890341 -234.91001)
			(xy 98.862685 -234.952339) (xy 98.828439 -234.989539) (xy 98.788537 -235.020595) (xy 98.744067 -235.044659)
			(xy 98.696243 -235.061075) (xy 98.64637 -235.069396) (xy 98.621088 -235.069888) (xy 97.681034 -235.069888)
			(xy 97.655756 -235.069346) (xy 97.605888 -235.061029) (xy 97.558069 -235.044618) (xy 97.513603 -235.020559)
			(xy 97.473705 -234.989509) (xy 97.439462 -234.952315) (xy 97.411808 -234.909991) (xy 97.391499 -234.863694)
			(xy 97.379087 -234.814684) (xy 97.374911 -234.7643) (xy 2.509012 -234.7643) (xy 2.509012 -235.5743)
			(xy 108.185172 -235.5743) (xy 108.189343 -235.52396) (xy 108.201744 -235.474994) (xy 108.222035 -235.428736)
			(xy 108.249664 -235.38645) (xy 108.283876 -235.349288) (xy 108.323739 -235.318264) (xy 108.368164 -235.294225)
			(xy 108.41594 -235.277826) (xy 108.465764 -235.269515) (xy 108.49102 -235.269024) (xy 109.431074 -235.269024)
			(xy 109.456336 -235.269451) (xy 109.506171 -235.277763) (xy 109.553958 -235.294165) (xy 109.598393 -235.318208)
			(xy 109.638265 -235.349239) (xy 109.672485 -235.386409) (xy 109.70012 -235.428704) (xy 109.720416 -235.474972)
			(xy 109.73282 -235.523949) (xy 109.736975 -235.5741) (xy 361.758663 -235.5741) (xy 361.762839 -235.523711)
			(xy 361.775251 -235.474696) (xy 361.795562 -235.428393) (xy 361.823217 -235.386064) (xy 361.857462 -235.348865)
			(xy 361.897363 -235.31781) (xy 361.941832 -235.293746) (xy 361.989654 -235.27733) (xy 362.039527 -235.269008)
			(xy 362.064808 -235.268516) (xy 363.004862 -235.268516) (xy 363.030141 -235.26905) (xy 363.08001 -235.277366)
			(xy 363.12783 -235.293777) (xy 363.172297 -235.317836) (xy 363.212196 -235.348887) (xy 363.24644 -235.386081)
			(xy 363.274095 -235.428406) (xy 363.294405 -235.474704) (xy 363.306817 -235.523715) (xy 363.310993 -235.5741)
			(xy 363.306817 -235.624485) (xy 363.294405 -235.673496) (xy 363.274095 -235.719795) (xy 363.24644 -235.762119)
			(xy 363.212196 -235.799313) (xy 363.172297 -235.830364) (xy 363.12783 -235.854423) (xy 363.08001 -235.870834)
			(xy 363.030141 -235.87915) (xy 363.004862 -235.87964) (xy 362.064808 -235.87964) (xy 362.039527 -235.879192)
			(xy 361.989654 -235.87087) (xy 361.941832 -235.854454) (xy 361.897363 -235.83039) (xy 361.857462 -235.799335)
			(xy 361.823217 -235.762136) (xy 361.795562 -235.719807) (xy 361.775251 -235.673504) (xy 361.762839 -235.624489)
			(xy 361.758663 -235.5741) (xy 109.736975 -235.5741) (xy 109.736992 -235.5743) (xy 109.73282 -235.624651)
			(xy 109.720416 -235.673628) (xy 109.70012 -235.719896) (xy 109.672485 -235.762191) (xy 109.638265 -235.799361)
			(xy 109.598393 -235.830392) (xy 109.553958 -235.854435) (xy 109.506171 -235.870837) (xy 109.456336 -235.879149)
			(xy 109.431074 -235.87964) (xy 108.49102 -235.87964) (xy 108.465764 -235.879085) (xy 108.41594 -235.870774)
			(xy 108.368164 -235.854375) (xy 108.323739 -235.830336) (xy 108.283876 -235.799312) (xy 108.249664 -235.76215)
			(xy 108.222035 -235.719864) (xy 108.201744 -235.673606) (xy 108.189343 -235.62464) (xy 108.185172 -235.5743)
			(xy 2.509012 -235.5743) (xy 2.509012 -236.3843) (xy 97.374923 -236.3843) (xy 97.379099 -236.333918)
			(xy 97.39151 -236.28491) (xy 97.411819 -236.238614) (xy 97.439471 -236.196293) (xy 97.473713 -236.1591)
			(xy 97.51361 -236.128051) (xy 97.558073 -236.103993) (xy 97.60589 -236.087582) (xy 97.655757 -236.079266)
			(xy 97.681034 -236.078776) (xy 98.621088 -236.078776) (xy 98.646371 -236.079192) (xy 98.696246 -236.087513)
			(xy 98.744072 -236.10393) (xy 98.788543 -236.127995) (xy 98.828447 -236.159052) (xy 98.862694 -236.196253)
			(xy 98.890351 -236.238584) (xy 98.910663 -236.28489) (xy 98.923077 -236.333908) (xy 98.927253 -236.3843)
			(xy 100.194823 -236.3843) (xy 100.198999 -236.333917) (xy 100.21141 -236.284909) (xy 100.23172 -236.238612)
			(xy 100.259374 -236.19629) (xy 100.293616 -236.159097) (xy 100.333514 -236.128048) (xy 100.377979 -236.103991)
			(xy 100.425797 -236.087581) (xy 100.475664 -236.079266) (xy 100.500942 -236.078776) (xy 101.440996 -236.078776)
			(xy 101.466278 -236.079193) (xy 101.516153 -236.087515) (xy 101.563977 -236.103933) (xy 101.608447 -236.127998)
			(xy 101.64835 -236.159055) (xy 101.682596 -236.196256) (xy 101.710252 -236.238586) (xy 101.730564 -236.284892)
			(xy 101.742977 -236.333909) (xy 101.747136 -236.3841) (xy 369.749053 -236.3841) (xy 369.753224 -236.333761)
			(xy 369.765624 -236.284794) (xy 369.785913 -236.238537) (xy 369.81354 -236.19625) (xy 369.84775 -236.159086)
			(xy 369.88761 -236.12806) (xy 369.932033 -236.104018) (xy 369.979808 -236.087615) (xy 370.02963 -236.079299)
			(xy 370.054886 -236.078776) (xy 370.99494 -236.078776) (xy 371.020192 -236.079333) (xy 371.070006 -236.087651)
			(xy 371.117772 -236.104055) (xy 371.162186 -236.128096) (xy 371.202038 -236.159119) (xy 371.236241 -236.196278)
			(xy 371.263862 -236.238559) (xy 371.284148 -236.28481) (xy 371.296545 -236.333769) (xy 371.300715 -236.3841)
			(xy 372.568953 -236.3841) (xy 372.573124 -236.33376) (xy 372.585524 -236.284793) (xy 372.605815 -236.238535)
			(xy 372.633442 -236.196247) (xy 372.667653 -236.159083) (xy 372.707514 -236.128057) (xy 372.751939 -236.104015)
			(xy 372.799714 -236.087613) (xy 372.849538 -236.079298) (xy 372.874794 -236.078776) (xy 373.814848 -236.078776)
			(xy 373.840099 -236.079333) (xy 373.889912 -236.087653) (xy 373.937677 -236.104057) (xy 373.98209 -236.128099)
			(xy 374.021941 -236.159122) (xy 374.056143 -236.196281) (xy 374.083763 -236.238561) (xy 374.104048 -236.284812)
			(xy 374.116445 -236.333769) (xy 374.120615 -236.3841) (xy 374.116445 -236.434431) (xy 374.104048 -236.483388)
			(xy 374.083763 -236.529638) (xy 374.056143 -236.571919) (xy 374.021941 -236.609078) (xy 373.98209 -236.640101)
			(xy 373.937677 -236.664143) (xy 373.889912 -236.680547) (xy 373.840099 -236.688867) (xy 373.814848 -236.689392)
			(xy 372.874794 -236.689392) (xy 372.849538 -236.688902) (xy 372.799714 -236.680587) (xy 372.751939 -236.664185)
			(xy 372.707514 -236.640143) (xy 372.667653 -236.609117) (xy 372.633442 -236.571953) (xy 372.605815 -236.529665)
			(xy 372.585524 -236.483407) (xy 372.573124 -236.43444) (xy 372.568953 -236.3841) (xy 371.300715 -236.3841)
			(xy 371.296545 -236.434431) (xy 371.284148 -236.48339) (xy 371.263862 -236.529641) (xy 371.236241 -236.571922)
			(xy 371.202038 -236.609081) (xy 371.162186 -236.640104) (xy 371.117772 -236.664145) (xy 371.070006 -236.680549)
			(xy 371.020192 -236.688867) (xy 370.99494 -236.689392) (xy 370.054886 -236.689392) (xy 370.02963 -236.688901)
			(xy 369.979808 -236.680585) (xy 369.932033 -236.664182) (xy 369.88761 -236.64014) (xy 369.84775 -236.609114)
			(xy 369.81354 -236.57195) (xy 369.785913 -236.529663) (xy 369.765624 -236.483406) (xy 369.753224 -236.434439)
			(xy 369.749053 -236.3841) (xy 101.747136 -236.3841) (xy 101.747153 -236.3843) (xy 101.742977 -236.434691)
			(xy 101.730564 -236.483708) (xy 101.710252 -236.530014) (xy 101.682596 -236.572344) (xy 101.64835 -236.609545)
			(xy 101.608447 -236.640602) (xy 101.563977 -236.664667) (xy 101.516153 -236.681085) (xy 101.466278 -236.689407)
			(xy 101.440996 -236.6899) (xy 100.500942 -236.6899) (xy 100.475664 -236.689334) (xy 100.425797 -236.681019)
			(xy 100.377979 -236.664609) (xy 100.333514 -236.640552) (xy 100.293616 -236.609503) (xy 100.259374 -236.57231)
			(xy 100.23172 -236.529988) (xy 100.21141 -236.483691) (xy 100.198999 -236.434683) (xy 100.194823 -236.3843)
			(xy 98.927253 -236.3843) (xy 98.923077 -236.434692) (xy 98.910663 -236.48371) (xy 98.890351 -236.530016)
			(xy 98.862694 -236.572347) (xy 98.828447 -236.609548) (xy 98.788543 -236.640605) (xy 98.744072 -236.66467)
			(xy 98.696246 -236.681087) (xy 98.646371 -236.689408) (xy 98.621088 -236.6899) (xy 97.681034 -236.6899)
			(xy 97.655757 -236.689334) (xy 97.60589 -236.681018) (xy 97.558073 -236.664607) (xy 97.51361 -236.640549)
			(xy 97.473713 -236.6095) (xy 97.439471 -236.572307) (xy 97.411819 -236.529986) (xy 97.39151 -236.48369)
			(xy 97.379099 -236.434682) (xy 97.374923 -236.3843) (xy 2.509012 -236.3843) (xy 2.509012 -243.6744)
			(xy 108.185132 -243.6744) (xy 108.189304 -243.624054) (xy 108.201706 -243.575081) (xy 108.222 -243.528817)
			(xy 108.249632 -243.486525) (xy 108.283849 -243.449358) (xy 108.323717 -243.418331) (xy 108.368148 -243.394288)
			(xy 108.41593 -243.377887) (xy 108.465761 -243.369575) (xy 108.49102 -243.369084) (xy 109.431074 -243.369084)
			(xy 109.456332 -243.369591) (xy 109.506161 -243.377902) (xy 109.553942 -243.394301) (xy 109.598371 -243.418342)
			(xy 109.638238 -243.449368) (xy 109.672453 -243.486533) (xy 109.700085 -243.528823) (xy 109.720378 -243.575085)
			(xy 109.73278 -243.624056) (xy 109.736927 -243.6741) (xy 361.758723 -243.6741) (xy 361.762898 -243.623721)
			(xy 361.775308 -243.574716) (xy 361.795615 -243.528421) (xy 361.823265 -243.486101) (xy 361.857503 -243.448909)
			(xy 361.897396 -243.41786) (xy 361.941856 -243.393801) (xy 361.989669 -243.377388) (xy 362.039532 -243.369068)
			(xy 362.064808 -243.368576) (xy 363.004862 -243.368576) (xy 363.030146 -243.36899) (xy 363.080025 -243.377308)
			(xy 363.127854 -243.393722) (xy 363.172329 -243.417786) (xy 363.212237 -243.448843) (xy 363.246487 -243.486045)
			(xy 363.274147 -243.528377) (xy 363.294462 -243.574685) (xy 363.306876 -243.623705) (xy 363.311053 -243.6741)
			(xy 363.306876 -243.724495) (xy 363.294462 -243.773515) (xy 363.274147 -243.819823) (xy 363.246487 -243.862155)
			(xy 363.212237 -243.899357) (xy 363.172329 -243.930414) (xy 363.127854 -243.954478) (xy 363.080025 -243.970892)
			(xy 363.030146 -243.97921) (xy 363.004862 -243.9797) (xy 362.064808 -243.9797) (xy 362.039532 -243.979132)
			(xy 361.989669 -243.970812) (xy 361.941856 -243.954399) (xy 361.897396 -243.93034) (xy 361.857503 -243.899291)
			(xy 361.823265 -243.862099) (xy 361.795615 -243.819779) (xy 361.775308 -243.773484) (xy 361.762898 -243.724479)
			(xy 361.758723 -243.6741) (xy 109.736927 -243.6741) (xy 109.736952 -243.6744) (xy 109.73278 -243.724744)
			(xy 109.720378 -243.773715) (xy 109.700085 -243.819977) (xy 109.672453 -243.862267) (xy 109.638238 -243.899432)
			(xy 109.598371 -243.930458) (xy 109.553942 -243.954499) (xy 109.506161 -243.970898) (xy 109.456332 -243.979209)
			(xy 109.431074 -243.9797) (xy 108.49102 -243.9797) (xy 108.465761 -243.979225) (xy 108.41593 -243.970913)
			(xy 108.368148 -243.954512) (xy 108.323717 -243.930469) (xy 108.283849 -243.899442) (xy 108.249632 -243.862275)
			(xy 108.222 -243.819983) (xy 108.201706 -243.773719) (xy 108.189304 -243.724746) (xy 108.185132 -243.6744)
			(xy 2.509012 -243.6744) (xy 2.509012 -244.4844) (xy 97.374883 -244.4844) (xy 97.379059 -244.434011)
			(xy 97.391472 -244.384997) (xy 97.411784 -244.338695) (xy 97.43944 -244.296368) (xy 97.473686 -244.259171)
			(xy 97.513588 -244.228118) (xy 97.558057 -244.204057) (xy 97.605881 -244.187644) (xy 97.655753 -244.179326)
			(xy 97.681034 -244.178836) (xy 98.621088 -244.178836) (xy 98.646367 -244.179332) (xy 98.696236 -244.187652)
			(xy 98.744056 -244.204067) (xy 98.788521 -244.228129) (xy 98.82842 -244.259181) (xy 98.862663 -244.296378)
			(xy 98.890316 -244.338703) (xy 98.910626 -244.385003) (xy 98.923037 -244.434014) (xy 98.927213 -244.4844)
			(xy 100.194783 -244.4844) (xy 100.198959 -244.434011) (xy 100.211373 -244.384996) (xy 100.231685 -244.338693)
			(xy 100.259342 -244.296365) (xy 100.293589 -244.259168) (xy 100.333492 -244.228115) (xy 100.377963 -244.204054)
			(xy 100.425787 -244.187642) (xy 100.475661 -244.179326) (xy 100.500942 -244.178836) (xy 101.440996 -244.178836)
			(xy 101.466275 -244.179333) (xy 101.516143 -244.187654) (xy 101.563961 -244.204069) (xy 101.608426 -244.228131)
			(xy 101.648323 -244.259184) (xy 101.682565 -244.29638) (xy 101.710217 -244.338705) (xy 101.730526 -244.385005)
			(xy 101.742937 -244.434015) (xy 101.747113 -244.4844) (xy 103.014983 -244.4844) (xy 103.019159 -244.434014)
			(xy 103.03157 -244.385003) (xy 103.051879 -244.338704) (xy 103.079532 -244.296378) (xy 103.113774 -244.259181)
			(xy 103.153672 -244.228128) (xy 103.198137 -244.204065) (xy 103.245956 -244.18765) (xy 103.295825 -244.179329)
			(xy 103.321104 -244.178836) (xy 104.261158 -244.178836) (xy 104.286439 -244.17933) (xy 104.336312 -244.187646)
			(xy 104.384136 -244.204058) (xy 104.428605 -244.228118) (xy 104.468508 -244.259171) (xy 104.502755 -244.296368)
			(xy 104.530412 -244.338695) (xy 104.550724 -244.384997) (xy 104.563137 -244.434011) (xy 104.567313 -244.4844)
			(xy 105.834883 -244.4844) (xy 105.839059 -244.434014) (xy 105.851471 -244.385002) (xy 105.87178 -244.338701)
			(xy 105.899434 -244.296375) (xy 105.933678 -244.259178) (xy 105.973577 -244.228125) (xy 106.018043 -244.204063)
			(xy 106.065863 -244.187648) (xy 106.115732 -244.179328) (xy 106.141012 -244.178836) (xy 107.081066 -244.178836)
			(xy 107.106346 -244.17933) (xy 107.156218 -244.187647) (xy 107.204041 -244.20406) (xy 107.24851 -244.228121)
			(xy 107.288411 -244.259174) (xy 107.322657 -244.29637) (xy 107.350313 -244.338697) (xy 107.370624 -244.384999)
			(xy 107.383037 -244.434012) (xy 107.387188 -244.4841) (xy 364.108984 -244.4841) (xy 364.113155 -244.433763)
			(xy 364.125555 -244.384799) (xy 364.145845 -244.338543) (xy 364.173472 -244.296259) (xy 364.207683 -244.259098)
			(xy 364.247543 -244.228076) (xy 364.291966 -244.204037) (xy 364.33974 -244.187639) (xy 364.389561 -244.179327)
			(xy 364.414816 -244.178836) (xy 365.35487 -244.178836) (xy 365.380133 -244.179238) (xy 365.42997 -244.18755)
			(xy 365.47776 -244.203952) (xy 365.522198 -244.227997) (xy 365.562072 -244.259028) (xy 365.596293 -244.2962)
			(xy 365.62393 -244.338497) (xy 365.644227 -244.384767) (xy 365.656631 -244.433747) (xy 365.660804 -244.4841)
			(xy 366.928884 -244.4841) (xy 366.933055 -244.433762) (xy 366.945456 -244.384797) (xy 366.965746 -244.338541)
			(xy 366.993374 -244.296256) (xy 367.027586 -244.259095) (xy 367.067447 -244.228073) (xy 367.111871 -244.204035)
			(xy 367.159646 -244.187637) (xy 367.209469 -244.179327) (xy 367.234724 -244.178836) (xy 368.174778 -244.178836)
			(xy 368.200041 -244.179239) (xy 368.249877 -244.187552) (xy 368.297665 -244.203955) (xy 368.342102 -244.228)
			(xy 368.381975 -244.259031) (xy 368.416196 -244.296203) (xy 368.443831 -244.3385) (xy 368.464128 -244.384769)
			(xy 368.476531 -244.433748) (xy 368.480704 -244.4841) (xy 369.749113 -244.4841) (xy 369.753283 -244.433771)
			(xy 369.76568 -244.384814) (xy 369.785966 -244.338565) (xy 369.813587 -244.296286) (xy 369.847791 -244.25913)
			(xy 369.887643 -244.22811) (xy 369.932057 -244.204073) (xy 369.979822 -244.187673) (xy 370.029635 -244.179359)
			(xy 370.054886 -244.178836) (xy 370.99494 -244.178836) (xy 371.020197 -244.179272) (xy 371.070021 -244.187592)
			(xy 371.117796 -244.203999) (xy 371.162219 -244.228045) (xy 371.202079 -244.259074) (xy 371.236289 -244.296241)
			(xy 371.263916 -244.33853) (xy 371.284205 -244.38479) (xy 371.296604 -244.433759) (xy 371.300776 -244.4841)
			(xy 372.569013 -244.4841) (xy 372.573183 -244.43377) (xy 372.585581 -244.384812) (xy 372.605867 -244.338563)
			(xy 372.63349 -244.296284) (xy 372.667694 -244.259127) (xy 372.707547 -244.228107) (xy 372.751963 -244.20407)
			(xy 372.799729 -244.187671) (xy 372.849543 -244.179358) (xy 372.874794 -244.178836) (xy 373.814848 -244.178836)
			(xy 373.840104 -244.179273) (xy 373.889927 -244.187594) (xy 373.937701 -244.204002) (xy 373.982123 -244.228048)
			(xy 374.021982 -244.259077) (xy 374.056191 -244.296243) (xy 374.083817 -244.338533) (xy 374.104106 -244.384792)
			(xy 374.116505 -244.43376) (xy 374.120676 -244.4841) (xy 374.116505 -244.53444) (xy 374.104106 -244.583408)
			(xy 374.083817 -244.629667) (xy 374.056191 -244.671957) (xy 374.021982 -244.709123) (xy 373.982123 -244.740152)
			(xy 373.937701 -244.764198) (xy 373.889927 -244.780606) (xy 373.840104 -244.788927) (xy 373.814848 -244.789452)
			(xy 372.874794 -244.789452) (xy 372.849543 -244.788842) (xy 372.799729 -244.780529) (xy 372.751963 -244.76413)
			(xy 372.707547 -244.740093) (xy 372.667694 -244.709073) (xy 372.63349 -244.671916) (xy 372.605867 -244.629637)
			(xy 372.585581 -244.583388) (xy 372.573183 -244.53443) (xy 372.569013 -244.4841) (xy 371.300776 -244.4841)
			(xy 371.296604 -244.534441) (xy 371.284205 -244.58341) (xy 371.263915 -244.62967) (xy 371.236289 -244.671959)
			(xy 371.202079 -244.709126) (xy 371.162219 -244.740155) (xy 371.117796 -244.764201) (xy 371.070021 -244.780608)
			(xy 371.020197 -244.788928) (xy 370.99494 -244.789452) (xy 370.054886 -244.789452) (xy 370.029635 -244.788841)
			(xy 369.979822 -244.780527) (xy 369.932057 -244.764127) (xy 369.887643 -244.74009) (xy 369.847791 -244.70907)
			(xy 369.813587 -244.671914) (xy 369.785966 -244.629635) (xy 369.76568 -244.583386) (xy 369.753283 -244.534429)
			(xy 369.749113 -244.4841) (xy 368.480704 -244.4841) (xy 368.476531 -244.534452) (xy 368.464128 -244.583431)
			(xy 368.443831 -244.6297) (xy 368.416196 -244.671997) (xy 368.381975 -244.709169) (xy 368.342102 -244.7402)
			(xy 368.297665 -244.764245) (xy 368.249877 -244.780648) (xy 368.200041 -244.788961) (xy 368.174778 -244.789452)
			(xy 367.234724 -244.789452) (xy 367.209469 -244.788873) (xy 367.159646 -244.780563) (xy 367.111871 -244.764165)
			(xy 367.067447 -244.740127) (xy 367.027586 -244.709105) (xy 366.993374 -244.671944) (xy 366.965746 -244.629659)
			(xy 366.945456 -244.583403) (xy 366.933055 -244.534438) (xy 366.928884 -244.4841) (xy 365.660804 -244.4841)
			(xy 365.656631 -244.534453) (xy 365.644227 -244.583433) (xy 365.62393 -244.629703) (xy 365.596293 -244.672)
			(xy 365.562072 -244.709172) (xy 365.522198 -244.740203) (xy 365.47776 -244.764248) (xy 365.42997 -244.78065)
			(xy 365.380133 -244.788962) (xy 365.35487 -244.789452) (xy 364.414816 -244.789452) (xy 364.389561 -244.788873)
			(xy 364.33974 -244.780561) (xy 364.291966 -244.764163) (xy 364.247543 -244.740124) (xy 364.207683 -244.709102)
			(xy 364.173472 -244.671941) (xy 364.145845 -244.629657) (xy 364.125555 -244.583401) (xy 364.113155 -244.534437)
			(xy 364.108984 -244.4841) (xy 107.387188 -244.4841) (xy 107.387213 -244.4844) (xy 107.383037 -244.534788)
			(xy 107.370624 -244.583801) (xy 107.350313 -244.630103) (xy 107.322657 -244.67243) (xy 107.288411 -244.709626)
			(xy 107.24851 -244.740679) (xy 107.204041 -244.76474) (xy 107.156218 -244.781153) (xy 107.106346 -244.78947)
			(xy 107.081066 -244.78996) (xy 106.141012 -244.78996) (xy 106.115732 -244.789472) (xy 106.065863 -244.781152)
			(xy 106.018043 -244.764737) (xy 105.973577 -244.740675) (xy 105.933678 -244.709622) (xy 105.899434 -244.672425)
			(xy 105.87178 -244.630099) (xy 105.851471 -244.583798) (xy 105.839059 -244.534786) (xy 105.834883 -244.4844)
			(xy 104.567313 -244.4844) (xy 104.563137 -244.534789) (xy 104.550724 -244.583803) (xy 104.530412 -244.630105)
			(xy 104.502755 -244.672432) (xy 104.468508 -244.709629) (xy 104.428605 -244.740682) (xy 104.384136 -244.764742)
			(xy 104.336312 -244.781154) (xy 104.286439 -244.78947) (xy 104.261158 -244.78996) (xy 103.321104 -244.78996)
			(xy 103.295825 -244.789471) (xy 103.245956 -244.78115) (xy 103.198137 -244.764735) (xy 103.153672 -244.740672)
			(xy 103.113774 -244.709619) (xy 103.079532 -244.672422) (xy 103.051879 -244.630096) (xy 103.03157 -244.583797)
			(xy 103.019159 -244.534786) (xy 103.014983 -244.4844) (xy 101.747113 -244.4844) (xy 101.742937 -244.534785)
			(xy 101.730526 -244.583795) (xy 101.710217 -244.630095) (xy 101.682565 -244.67242) (xy 101.648323 -244.709616)
			(xy 101.608426 -244.740669) (xy 101.563961 -244.764731) (xy 101.516143 -244.781146) (xy 101.466275 -244.789467)
			(xy 101.440996 -244.78996) (xy 100.500942 -244.78996) (xy 100.475661 -244.789474) (xy 100.425787 -244.781158)
			(xy 100.377963 -244.764746) (xy 100.333492 -244.740685) (xy 100.293589 -244.709632) (xy 100.259342 -244.672435)
			(xy 100.231685 -244.630107) (xy 100.211373 -244.583804) (xy 100.198959 -244.534789) (xy 100.194783 -244.4844)
			(xy 98.927213 -244.4844) (xy 98.923037 -244.534786) (xy 98.910626 -244.583797) (xy 98.890316 -244.630097)
			(xy 98.862663 -244.672422) (xy 98.82842 -244.709619) (xy 98.788521 -244.740671) (xy 98.744056 -244.764733)
			(xy 98.696236 -244.781148) (xy 98.646367 -244.789468) (xy 98.621088 -244.78996) (xy 97.681034 -244.78996)
			(xy 97.655753 -244.789474) (xy 97.605881 -244.781156) (xy 97.558057 -244.764743) (xy 97.513588 -244.740682)
			(xy 97.473686 -244.709629) (xy 97.43944 -244.672432) (xy 97.411784 -244.630105) (xy 97.391472 -244.583803)
			(xy 97.379059 -244.534789) (xy 97.374883 -244.4844) (xy 2.509012 -244.4844) (xy 2.509012 -245.2944)
			(xy 108.185144 -245.2944) (xy 108.189316 -245.244056) (xy 108.201717 -245.195085) (xy 108.222011 -245.148823)
			(xy 108.249642 -245.106533) (xy 108.283857 -245.069367) (xy 108.323723 -245.038341) (xy 108.368153 -245.014299)
			(xy 108.415933 -244.997899) (xy 108.465762 -244.989587) (xy 108.49102 -244.989096) (xy 109.431074 -244.989096)
			(xy 109.456333 -244.989579) (xy 109.506164 -244.99789) (xy 109.553947 -245.01429) (xy 109.598378 -245.038332)
			(xy 109.638246 -245.069359) (xy 109.672463 -245.106526) (xy 109.700095 -245.148818) (xy 109.72039 -245.195081)
			(xy 109.732792 -245.244054) (xy 109.736939 -245.2941) (xy 361.758735 -245.2941) (xy 361.76291 -245.243723)
			(xy 361.775319 -245.194719) (xy 361.795626 -245.148427) (xy 361.823274 -245.106109) (xy 361.857511 -245.068918)
			(xy 361.897403 -245.03787) (xy 361.941861 -245.013812) (xy 361.989672 -244.997399) (xy 362.039533 -244.98908)
			(xy 362.064808 -244.988588) (xy 363.004862 -244.988588) (xy 363.030147 -244.988978) (xy 363.080028 -244.997296)
			(xy 363.127859 -245.013711) (xy 363.172336 -245.037776) (xy 363.212245 -245.068834) (xy 363.246497 -245.106037)
			(xy 363.274158 -245.148371) (xy 363.294473 -245.194681) (xy 363.306888 -245.243703) (xy 363.311065 -245.2941)
			(xy 363.306888 -245.344497) (xy 363.294473 -245.393519) (xy 363.274158 -245.439829) (xy 363.246497 -245.482163)
			(xy 363.212245 -245.519366) (xy 363.172336 -245.550424) (xy 363.127859 -245.574489) (xy 363.080028 -245.590904)
			(xy 363.030147 -245.599222) (xy 363.004862 -245.599712) (xy 362.064808 -245.599712) (xy 362.039533 -245.59912)
			(xy 361.989672 -245.590801) (xy 361.941861 -245.574388) (xy 361.897403 -245.55033) (xy 361.857511 -245.519282)
			(xy 361.823274 -245.482091) (xy 361.795626 -245.439773) (xy 361.775319 -245.393481) (xy 361.76291 -245.344477)
			(xy 361.758735 -245.2941) (xy 109.736939 -245.2941) (xy 109.736964 -245.2944) (xy 109.732792 -245.344746)
			(xy 109.72039 -245.393719) (xy 109.700095 -245.439982) (xy 109.672463 -245.482274) (xy 109.638246 -245.519441)
			(xy 109.598378 -245.550468) (xy 109.553947 -245.57451) (xy 109.506164 -245.59091) (xy 109.456333 -245.599221)
			(xy 109.431074 -245.599712) (xy 108.49102 -245.599712) (xy 108.465762 -245.599213) (xy 108.415933 -245.590901)
			(xy 108.368153 -245.574501) (xy 108.323723 -245.550459) (xy 108.283857 -245.519433) (xy 108.249642 -245.482267)
			(xy 108.222011 -245.439977) (xy 108.201717 -245.393715) (xy 108.189316 -245.344744) (xy 108.185144 -245.2944)
			(xy 2.509012 -245.2944) (xy 2.509012 -246.1044) (xy 97.374895 -246.1044) (xy 97.379071 -246.054013)
			(xy 97.391483 -246.005001) (xy 97.411794 -245.958701) (xy 97.439449 -245.916375) (xy 97.473694 -245.879179)
			(xy 97.513595 -245.848128) (xy 97.558062 -245.824068) (xy 97.605884 -245.807655) (xy 97.655754 -245.799338)
			(xy 97.681034 -245.798848) (xy 98.621088 -245.798848) (xy 98.646368 -245.79932) (xy 98.696239 -245.80764)
			(xy 98.744061 -245.824056) (xy 98.788528 -245.848119) (xy 98.828428 -245.879173) (xy 98.862672 -245.91637)
			(xy 98.890327 -245.958698) (xy 98.910637 -246.004999) (xy 98.923049 -246.054012) (xy 98.927225 -246.1044)
			(xy 100.194795 -246.1044) (xy 100.198971 -246.054012) (xy 100.211384 -246.005) (xy 100.231695 -245.958699)
			(xy 100.259351 -245.916373) (xy 100.293597 -245.879177) (xy 100.333499 -245.848125) (xy 100.377968 -245.824065)
			(xy 100.42579 -245.807654) (xy 100.475662 -245.799338) (xy 100.500942 -245.798848) (xy 101.440996 -245.798848)
			(xy 101.466276 -245.799321) (xy 101.516146 -245.807642) (xy 101.563966 -245.824058) (xy 101.608432 -245.848121)
			(xy 101.648331 -245.879175) (xy 101.682574 -245.916373) (xy 101.710228 -245.9587) (xy 101.730538 -246.005001)
			(xy 101.742949 -246.054013) (xy 101.747125 -246.1044) (xy 103.014995 -246.1044) (xy 103.01917 -246.054016)
			(xy 103.031581 -246.005007) (xy 103.05189 -245.958709) (xy 103.079542 -245.916385) (xy 103.113783 -245.87919)
			(xy 103.153679 -245.848138) (xy 103.198142 -245.824076) (xy 103.245959 -245.807661) (xy 103.295826 -245.799341)
			(xy 103.321104 -245.798848) (xy 104.261158 -245.798848) (xy 104.28644 -245.799318) (xy 104.336315 -245.807634)
			(xy 104.38414 -245.824047) (xy 104.428612 -245.848108) (xy 104.468516 -245.879162) (xy 104.502764 -245.91636)
			(xy 104.530422 -245.958689) (xy 104.550735 -246.004993) (xy 104.563149 -246.054009) (xy 104.567325 -246.1044)
			(xy 105.834895 -246.1044) (xy 105.839071 -246.054016) (xy 105.851482 -246.005006) (xy 105.871791 -245.958707)
			(xy 105.899444 -245.916383) (xy 105.933686 -245.879187) (xy 105.973583 -245.848135) (xy 106.018047 -245.824074)
			(xy 106.065866 -245.80766) (xy 106.115733 -245.79934) (xy 106.141012 -245.798848) (xy 107.081066 -245.798848)
			(xy 107.106347 -245.799318) (xy 107.156221 -245.807636) (xy 107.204046 -245.824049) (xy 107.248516 -245.848111)
			(xy 107.288419 -245.879165) (xy 107.322666 -245.916363) (xy 107.350323 -245.958691) (xy 107.370636 -246.004995)
			(xy 107.383049 -246.05401) (xy 107.387208 -246.1042) (xy 364.108896 -246.1042) (xy 364.113068 -246.053848)
			(xy 364.125472 -246.00487) (xy 364.145768 -245.958601) (xy 364.173403 -245.916305) (xy 364.207623 -245.879133)
			(xy 364.247495 -245.848102) (xy 364.291931 -245.824057) (xy 364.339718 -245.807653) (xy 364.389554 -245.79934)
			(xy 364.414816 -245.798848) (xy 365.35487 -245.798848) (xy 365.380126 -245.799426) (xy 365.429949 -245.807736)
			(xy 365.477725 -245.824133) (xy 365.52215 -245.848171) (xy 365.562012 -245.879193) (xy 365.596224 -245.916354)
			(xy 365.623853 -245.958639) (xy 365.644144 -246.004896) (xy 365.656545 -246.053861) (xy 365.660716 -246.1042)
			(xy 366.928796 -246.1042) (xy 366.932969 -246.053847) (xy 366.945372 -246.004868) (xy 366.965669 -245.958599)
			(xy 366.993305 -245.916302) (xy 367.027526 -245.879131) (xy 367.067399 -245.848099) (xy 367.111836 -245.824054)
			(xy 367.159625 -245.807652) (xy 367.209461 -245.799339) (xy 367.234724 -245.798848) (xy 368.174778 -245.798848)
			(xy 368.200033 -245.799427) (xy 368.249855 -245.807737) (xy 368.29763 -245.824135) (xy 368.342054 -245.848173)
			(xy 368.381915 -245.879196) (xy 368.416126 -245.916357) (xy 368.443754 -245.958642) (xy 368.464045 -246.004897)
			(xy 368.476445 -246.053862) (xy 368.480616 -246.1042) (xy 369.749024 -246.1042) (xy 369.753196 -246.053856)
			(xy 369.765597 -246.004885) (xy 369.785888 -245.958623) (xy 369.813518 -245.916332) (xy 369.847731 -245.879165)
			(xy 369.887595 -245.848136) (xy 369.932022 -245.824092) (xy 369.979801 -245.807687) (xy 370.029628 -245.79937)
			(xy 370.054886 -245.798848) (xy 370.99494 -245.798848) (xy 371.02019 -245.799461) (xy 371.069999 -245.807778)
			(xy 371.11776 -245.82418) (xy 371.162171 -245.848219) (xy 371.202019 -245.879239) (xy 371.236219 -245.916395)
			(xy 371.263838 -245.958673) (xy 371.284121 -246.004919) (xy 371.296517 -246.053873) (xy 371.300687 -246.1042)
			(xy 372.568924 -246.1042) (xy 372.573096 -246.053855) (xy 372.585497 -246.004884) (xy 372.60579 -245.958621)
			(xy 372.63342 -245.916329) (xy 372.667634 -245.879162) (xy 372.707499 -245.848133) (xy 372.751927 -245.824089)
			(xy 372.799707 -245.807685) (xy 372.849535 -245.79937) (xy 372.874794 -245.798848) (xy 373.814848 -245.798848)
			(xy 373.840097 -245.799461) (xy 373.889906 -245.80778) (xy 373.937666 -245.824183) (xy 373.982075 -245.848222)
			(xy 374.021923 -245.879242) (xy 374.056121 -245.916398) (xy 374.083739 -245.958675) (xy 374.104022 -246.004921)
			(xy 374.116417 -246.053874) (xy 374.120587 -246.1042) (xy 374.116417 -246.154526) (xy 374.104022 -246.203479)
			(xy 374.083739 -246.249725) (xy 374.056121 -246.292002) (xy 374.021923 -246.329158) (xy 373.982075 -246.360178)
			(xy 373.937666 -246.384217) (xy 373.889906 -246.40062) (xy 373.840097 -246.408939) (xy 373.814848 -246.409464)
			(xy 372.874794 -246.409464) (xy 372.849535 -246.40903) (xy 372.799707 -246.400715) (xy 372.751927 -246.384311)
			(xy 372.707499 -246.360267) (xy 372.667634 -246.329238) (xy 372.63342 -246.292071) (xy 372.60579 -246.249779)
			(xy 372.585497 -246.203516) (xy 372.573096 -246.154545) (xy 372.568924 -246.1042) (xy 371.300687 -246.1042)
			(xy 371.296517 -246.154527) (xy 371.284121 -246.203481) (xy 371.263838 -246.249727) (xy 371.236219 -246.292005)
			(xy 371.202019 -246.329161) (xy 371.162171 -246.360181) (xy 371.11776 -246.38422) (xy 371.069999 -246.400622)
			(xy 371.02019 -246.408939) (xy 370.99494 -246.409464) (xy 370.054886 -246.409464) (xy 370.029628 -246.40903)
			(xy 369.979801 -246.400713) (xy 369.932022 -246.384308) (xy 369.887595 -246.360264) (xy 369.847731 -246.329235)
			(xy 369.813518 -246.292068) (xy 369.785888 -246.249777) (xy 369.765597 -246.203515) (xy 369.753196 -246.154544)
			(xy 369.749024 -246.1042) (xy 368.480616 -246.1042) (xy 368.476445 -246.154538) (xy 368.464045 -246.203503)
			(xy 368.443754 -246.249758) (xy 368.416126 -246.292043) (xy 368.381915 -246.329204) (xy 368.342054 -246.360227)
			(xy 368.29763 -246.384265) (xy 368.249855 -246.400663) (xy 368.200033 -246.408973) (xy 368.174778 -246.409464)
			(xy 367.234724 -246.409464) (xy 367.209461 -246.409061) (xy 367.159625 -246.400748) (xy 367.111836 -246.384346)
			(xy 367.067399 -246.360301) (xy 367.027526 -246.329269) (xy 366.993305 -246.292098) (xy 366.965669 -246.249801)
			(xy 366.945372 -246.203532) (xy 366.932969 -246.154553) (xy 366.928796 -246.1042) (xy 365.660716 -246.1042)
			(xy 365.656545 -246.154539) (xy 365.644144 -246.203504) (xy 365.623853 -246.249761) (xy 365.596224 -246.292046)
			(xy 365.562012 -246.329207) (xy 365.52215 -246.360229) (xy 365.477725 -246.384267) (xy 365.429949 -246.400664)
			(xy 365.380126 -246.408974) (xy 365.35487 -246.409464) (xy 364.414816 -246.409464) (xy 364.389554 -246.40906)
			(xy 364.339718 -246.400747) (xy 364.291931 -246.384343) (xy 364.247495 -246.360298) (xy 364.207623 -246.329267)
			(xy 364.173403 -246.292095) (xy 364.145768 -246.249799) (xy 364.125472 -246.20353) (xy 364.113068 -246.154552)
			(xy 364.108896 -246.1042) (xy 107.387208 -246.1042) (xy 107.387225 -246.1044) (xy 107.383049 -246.15479)
			(xy 107.370636 -246.203805) (xy 107.350323 -246.250109) (xy 107.322666 -246.292437) (xy 107.288419 -246.329635)
			(xy 107.248516 -246.360689) (xy 107.204046 -246.384751) (xy 107.156221 -246.401164) (xy 107.106347 -246.409482)
			(xy 107.081066 -246.409972) (xy 106.141012 -246.409972) (xy 106.115733 -246.40946) (xy 106.065866 -246.40114)
			(xy 106.018047 -246.384726) (xy 105.973583 -246.360665) (xy 105.933686 -246.329613) (xy 105.899444 -246.292417)
			(xy 105.871791 -246.250093) (xy 105.851482 -246.203794) (xy 105.839071 -246.154784) (xy 105.834895 -246.1044)
			(xy 104.567325 -246.1044) (xy 104.563149 -246.154791) (xy 104.550735 -246.203807) (xy 104.530422 -246.250111)
			(xy 104.502764 -246.29244) (xy 104.468516 -246.329638) (xy 104.428612 -246.360692) (xy 104.38414 -246.384753)
			(xy 104.336315 -246.401166) (xy 104.28644 -246.409482) (xy 104.261158 -246.409972) (xy 103.321104 -246.409972)
			(xy 103.295826 -246.409459) (xy 103.245959 -246.401139) (xy 103.198142 -246.384724) (xy 103.153679 -246.360662)
			(xy 103.113783 -246.32961) (xy 103.079542 -246.292415) (xy 103.05189 -246.250091) (xy 103.031581 -246.203793)
			(xy 103.01917 -246.154784) (xy 103.014995 -246.1044) (xy 101.747125 -246.1044) (xy 101.742949 -246.154787)
			(xy 101.730538 -246.203799) (xy 101.710228 -246.2501) (xy 101.682574 -246.292427) (xy 101.648331 -246.329625)
			(xy 101.608432 -246.360679) (xy 101.563966 -246.384742) (xy 101.516146 -246.401158) (xy 101.466276 -246.409479)
			(xy 101.440996 -246.409972) (xy 100.500942 -246.409972) (xy 100.475662 -246.409462) (xy 100.42579 -246.401146)
			(xy 100.377968 -246.384735) (xy 100.333499 -246.360675) (xy 100.293597 -246.329623) (xy 100.259351 -246.292427)
			(xy 100.231695 -246.250101) (xy 100.211384 -246.2038) (xy 100.198971 -246.154788) (xy 100.194795 -246.1044)
			(xy 98.927225 -246.1044) (xy 98.923049 -246.154788) (xy 98.910637 -246.203801) (xy 98.890327 -246.250102)
			(xy 98.862672 -246.29243) (xy 98.828428 -246.329627) (xy 98.788528 -246.360681) (xy 98.744061 -246.384744)
			(xy 98.696239 -246.40116) (xy 98.646368 -246.40948) (xy 98.621088 -246.409972) (xy 97.681034 -246.409972)
			(xy 97.655754 -246.409462) (xy 97.605884 -246.401145) (xy 97.558062 -246.384732) (xy 97.513595 -246.360672)
			(xy 97.473694 -246.329621) (xy 97.439449 -246.292425) (xy 97.411794 -246.250099) (xy 97.391483 -246.203799)
			(xy 97.379071 -246.154787) (xy 97.374895 -246.1044) (xy 2.509012 -246.1044) (xy 2.509012 -246.9144)
			(xy 108.185156 -246.9144) (xy 108.189328 -246.864058) (xy 108.201729 -246.815089) (xy 108.222021 -246.768829)
			(xy 108.249651 -246.72654) (xy 108.283865 -246.689376) (xy 108.32373 -246.658351) (xy 108.368157 -246.63431)
			(xy 108.415936 -246.617911) (xy 108.465763 -246.609599) (xy 108.49102 -246.609108) (xy 109.431074 -246.609108)
			(xy 109.456334 -246.609567) (xy 109.506167 -246.617878) (xy 109.553951 -246.634279) (xy 109.598385 -246.658322)
			(xy 109.638254 -246.68935) (xy 109.672472 -246.726518) (xy 109.700106 -246.768812) (xy 109.720401 -246.815077)
			(xy 109.732804 -246.864052) (xy 109.736959 -246.9142) (xy 361.758647 -246.9142) (xy 361.762823 -246.863808)
			(xy 361.775236 -246.814791) (xy 361.795548 -246.768485) (xy 361.823205 -246.726155) (xy 361.857452 -246.688953)
			(xy 361.897355 -246.657897) (xy 361.941825 -246.633831) (xy 361.989651 -246.617414) (xy 362.039526 -246.609093)
			(xy 362.064808 -246.6086) (xy 363.004862 -246.6086) (xy 363.03014 -246.609166) (xy 363.080006 -246.617481)
			(xy 363.127824 -246.633892) (xy 363.172288 -246.65795) (xy 363.212185 -246.688999) (xy 363.246428 -246.726191)
			(xy 363.274081 -246.768513) (xy 363.29439 -246.81481) (xy 363.306801 -246.863818) (xy 363.310977 -246.9142)
			(xy 363.306801 -246.964582) (xy 363.29439 -247.01359) (xy 363.274081 -247.059887) (xy 363.246428 -247.102209)
			(xy 363.212185 -247.139401) (xy 363.172288 -247.17045) (xy 363.127824 -247.194508) (xy 363.080006 -247.210919)
			(xy 363.03014 -247.219234) (xy 363.004862 -247.219724) (xy 362.064808 -247.219724) (xy 362.039526 -247.219307)
			(xy 361.989651 -247.210986) (xy 361.941825 -247.194569) (xy 361.897355 -247.170503) (xy 361.857452 -247.139447)
			(xy 361.823205 -247.102245) (xy 361.795548 -247.059915) (xy 361.775236 -247.013609) (xy 361.762823 -246.964592)
			(xy 361.758647 -246.9142) (xy 109.736959 -246.9142) (xy 109.736976 -246.9144) (xy 109.732804 -246.964748)
			(xy 109.720401 -247.013723) (xy 109.700106 -247.059988) (xy 109.672472 -247.102282) (xy 109.638254 -247.13945)
			(xy 109.598385 -247.170478) (xy 109.553951 -247.194521) (xy 109.506167 -247.210922) (xy 109.456334 -247.219233)
			(xy 109.431074 -247.219724) (xy 108.49102 -247.219724) (xy 108.465763 -247.219201) (xy 108.415936 -247.210889)
			(xy 108.368157 -247.19449) (xy 108.32373 -247.170449) (xy 108.283865 -247.139424) (xy 108.249651 -247.10226)
			(xy 108.222021 -247.059971) (xy 108.201729 -247.013711) (xy 108.189328 -246.964742) (xy 108.185156 -246.9144)
			(xy 2.509012 -246.9144) (xy 2.509012 -247.7244) (xy 97.374907 -247.7244) (xy 97.379083 -247.674015)
			(xy 97.391495 -247.625005) (xy 97.411805 -247.578707) (xy 97.439459 -247.536383) (xy 97.473702 -247.499188)
			(xy 97.513601 -247.468138) (xy 97.558067 -247.444079) (xy 97.605887 -247.427667) (xy 97.655755 -247.41935)
			(xy 97.681034 -247.41886) (xy 98.621088 -247.41886) (xy 98.646369 -247.419308) (xy 98.696242 -247.427629)
			(xy 98.744066 -247.444045) (xy 98.788534 -247.468109) (xy 98.828436 -247.499164) (xy 98.862682 -247.536363)
			(xy 98.890337 -247.578692) (xy 98.910648 -247.624995) (xy 98.923061 -247.67401) (xy 98.927237 -247.7244)
			(xy 100.194807 -247.7244) (xy 100.198983 -247.674014) (xy 100.211395 -247.625004) (xy 100.231706 -247.578704)
			(xy 100.259361 -247.53638) (xy 100.293605 -247.499185) (xy 100.333506 -247.468135) (xy 100.377972 -247.444076)
			(xy 100.425793 -247.427665) (xy 100.475663 -247.41935) (xy 100.500942 -247.41886) (xy 101.440996 -247.41886)
			(xy 101.466277 -247.419309) (xy 101.516149 -247.42763) (xy 101.563971 -247.444047) (xy 101.608439 -247.468111)
			(xy 101.648339 -247.499167) (xy 101.682584 -247.536366) (xy 101.710238 -247.578694) (xy 101.730549 -247.624997)
			(xy 101.742961 -247.674011) (xy 101.747137 -247.7244) (xy 103.015007 -247.7244) (xy 103.019182 -247.674018)
			(xy 103.031593 -247.625011) (xy 103.0519 -247.578715) (xy 103.079551 -247.536393) (xy 103.113791 -247.499199)
			(xy 103.153685 -247.468148) (xy 103.198147 -247.444087) (xy 103.245962 -247.427673) (xy 103.295827 -247.419353)
			(xy 103.321104 -247.41886) (xy 104.261158 -247.41886) (xy 104.286441 -247.419306) (xy 104.336318 -247.427622)
			(xy 104.384145 -247.444036) (xy 104.428619 -247.468098) (xy 104.468524 -247.499153) (xy 104.502774 -247.536353)
			(xy 104.530433 -247.578683) (xy 104.550746 -247.624989) (xy 104.56316 -247.674007) (xy 104.567337 -247.7244)
			(xy 105.834907 -247.7244) (xy 105.839082 -247.674018) (xy 105.851493 -247.62501) (xy 105.871801 -247.578713)
			(xy 105.899453 -247.53639) (xy 105.933694 -247.499196) (xy 105.97359 -247.468145) (xy 106.018052 -247.444085)
			(xy 106.065869 -247.427671) (xy 106.115734 -247.419352) (xy 106.141012 -247.41886) (xy 107.081066 -247.41886)
			(xy 107.106348 -247.419306) (xy 107.156224 -247.427624) (xy 107.204051 -247.444038) (xy 107.248523 -247.468101)
			(xy 107.288427 -247.499156) (xy 107.322676 -247.536356) (xy 107.350334 -247.578686) (xy 107.370647 -247.624991)
			(xy 107.383061 -247.674008) (xy 107.38722 -247.7242) (xy 364.108908 -247.7242) (xy 364.11308 -247.67385)
			(xy 364.125483 -247.624874) (xy 364.145778 -247.578607) (xy 364.173412 -247.536312) (xy 364.207631 -247.499142)
			(xy 364.247501 -247.468112) (xy 364.291935 -247.444068) (xy 364.339721 -247.427665) (xy 364.389555 -247.419352)
			(xy 364.414816 -247.41886) (xy 365.35487 -247.41886) (xy 365.380127 -247.419414) (xy 365.429952 -247.427724)
			(xy 365.477729 -247.444122) (xy 365.522156 -247.468161) (xy 365.56202 -247.499184) (xy 365.596233 -247.536347)
			(xy 365.623863 -247.578634) (xy 365.644155 -247.624892) (xy 365.656556 -247.673859) (xy 365.660728 -247.7242)
			(xy 366.928808 -247.7242) (xy 366.93298 -247.673849) (xy 366.945384 -247.624872) (xy 366.96568 -247.578605)
			(xy 366.993314 -247.536309) (xy 367.027534 -247.499139) (xy 367.067406 -247.468109) (xy 367.111841 -247.444065)
			(xy 367.159628 -247.427663) (xy 367.209462 -247.419351) (xy 367.234724 -247.41886) (xy 368.174778 -247.41886)
			(xy 368.200034 -247.419415) (xy 368.249858 -247.427726) (xy 368.297635 -247.444124) (xy 368.34206 -247.468163)
			(xy 368.381923 -247.499187) (xy 368.416136 -247.536349) (xy 368.443764 -247.578636) (xy 368.464056 -247.624893)
			(xy 368.476457 -247.67386) (xy 368.480628 -247.7242) (xy 369.749037 -247.7242) (xy 369.753208 -247.673858)
			(xy 369.765609 -247.624889) (xy 369.785899 -247.578629) (xy 369.813527 -247.53634) (xy 369.847739 -247.499174)
			(xy 369.887601 -247.468147) (xy 369.932027 -247.444103) (xy 369.979804 -247.427699) (xy 370.029629 -247.419383)
			(xy 370.054886 -247.41886) (xy 370.99494 -247.41886) (xy 371.020191 -247.419449) (xy 371.070002 -247.427767)
			(xy 371.117765 -247.444169) (xy 371.162177 -247.468209) (xy 371.202028 -247.499231) (xy 371.236229 -247.536388)
			(xy 371.263848 -247.578667) (xy 371.284133 -247.624915) (xy 371.296529 -247.673871) (xy 371.300699 -247.7242)
			(xy 372.568937 -247.7242) (xy 372.573108 -247.673857) (xy 372.585509 -247.624888) (xy 372.605801 -247.578627)
			(xy 372.63343 -247.536337) (xy 372.667642 -247.499171) (xy 372.707506 -247.468144) (xy 372.751932 -247.444101)
			(xy 372.79971 -247.427698) (xy 372.849536 -247.419382) (xy 372.874794 -247.41886) (xy 373.814848 -247.41886)
			(xy 373.840098 -247.419449) (xy 373.889908 -247.427768) (xy 373.93767 -247.444172) (xy 373.982082 -247.468212)
			(xy 374.021931 -247.499233) (xy 374.056131 -247.53639) (xy 374.083749 -247.578669) (xy 374.104033 -247.624917)
			(xy 374.116429 -247.673872) (xy 374.120599 -247.7242) (xy 374.116429 -247.774528) (xy 374.104033 -247.823483)
			(xy 374.083749 -247.869731) (xy 374.056131 -247.91201) (xy 374.021931 -247.949166) (xy 373.982082 -247.980188)
			(xy 373.937671 -248.004228) (xy 373.889908 -248.020632) (xy 373.840098 -248.028951) (xy 373.814848 -248.029476)
			(xy 372.874794 -248.029476) (xy 372.849536 -248.029018) (xy 372.79971 -248.020702) (xy 372.751932 -248.004299)
			(xy 372.707506 -247.980256) (xy 372.667642 -247.949229) (xy 372.63343 -247.912063) (xy 372.605801 -247.869773)
			(xy 372.585509 -247.823512) (xy 372.573108 -247.774543) (xy 372.568937 -247.7242) (xy 371.300699 -247.7242)
			(xy 371.296529 -247.774529) (xy 371.284133 -247.823485) (xy 371.263848 -247.869733) (xy 371.236229 -247.912012)
			(xy 371.202028 -247.949169) (xy 371.162177 -247.980191) (xy 371.117765 -248.004231) (xy 371.070002 -248.020633)
			(xy 371.020191 -248.028951) (xy 370.99494 -248.029476) (xy 370.054886 -248.029476) (xy 370.029629 -248.029017)
			(xy 369.979804 -248.020701) (xy 369.932027 -248.004297) (xy 369.887601 -247.980253) (xy 369.847739 -247.949226)
			(xy 369.813527 -247.91206) (xy 369.785899 -247.869771) (xy 369.765609 -247.823511) (xy 369.753208 -247.774542)
			(xy 369.749037 -247.7242) (xy 368.480628 -247.7242) (xy 368.476457 -247.77454) (xy 368.464056 -247.823507)
			(xy 368.443764 -247.869764) (xy 368.416136 -247.912051) (xy 368.381923 -247.949213) (xy 368.34206 -247.980237)
			(xy 368.297635 -248.004276) (xy 368.249858 -248.020674) (xy 368.200034 -248.028985) (xy 368.174778 -248.029476)
			(xy 367.234724 -248.029476) (xy 367.209462 -248.029049) (xy 367.159628 -248.020737) (xy 367.111841 -248.004335)
			(xy 367.067406 -247.980291) (xy 367.027534 -247.949261) (xy 366.993314 -247.912091) (xy 366.96568 -247.869795)
			(xy 366.945384 -247.823528) (xy 366.93298 -247.774551) (xy 366.928808 -247.7242) (xy 365.660728 -247.7242)
			(xy 365.656556 -247.774541) (xy 365.644155 -247.823508) (xy 365.623863 -247.869766) (xy 365.596233 -247.912053)
			(xy 365.56202 -247.949216) (xy 365.522156 -247.980239) (xy 365.477729 -248.004278) (xy 365.429952 -248.020676)
			(xy 365.380127 -248.028986) (xy 365.35487 -248.029476) (xy 364.414816 -248.029476) (xy 364.389555 -248.029048)
			(xy 364.339721 -248.020735) (xy 364.291935 -248.004332) (xy 364.247501 -247.980288) (xy 364.207631 -247.949258)
			(xy 364.173412 -247.912088) (xy 364.145778 -247.869793) (xy 364.125483 -247.823526) (xy 364.11308 -247.77455)
			(xy 364.108908 -247.7242) (xy 107.38722 -247.7242) (xy 107.387237 -247.7244) (xy 107.383061 -247.774792)
			(xy 107.370647 -247.823809) (xy 107.350334 -247.870114) (xy 107.322676 -247.912444) (xy 107.288427 -247.949644)
			(xy 107.248523 -247.980699) (xy 107.204051 -248.004762) (xy 107.156224 -248.021176) (xy 107.106348 -248.029494)
			(xy 107.081066 -248.029984) (xy 106.141012 -248.029984) (xy 106.115734 -248.029448) (xy 106.065869 -248.021129)
			(xy 106.018052 -248.004715) (xy 105.97359 -247.980655) (xy 105.933694 -247.949604) (xy 105.899453 -247.91241)
			(xy 105.871801 -247.870087) (xy 105.851493 -247.82379) (xy 105.839082 -247.774782) (xy 105.834907 -247.7244)
			(xy 104.567337 -247.7244) (xy 104.56316 -247.774793) (xy 104.550746 -247.823811) (xy 104.530433 -247.870117)
			(xy 104.502774 -247.912447) (xy 104.468524 -247.949647) (xy 104.428619 -247.980702) (xy 104.384145 -248.004764)
			(xy 104.336318 -248.021178) (xy 104.286441 -248.029494) (xy 104.261158 -248.029984) (xy 103.321104 -248.029984)
			(xy 103.295827 -248.029447) (xy 103.245962 -248.021127) (xy 103.198147 -248.004713) (xy 103.153685 -247.980652)
			(xy 103.113791 -247.949601) (xy 103.079551 -247.912407) (xy 103.0519 -247.870085) (xy 103.031593 -247.823789)
			(xy 103.019182 -247.774782) (xy 103.015007 -247.7244) (xy 101.747137 -247.7244) (xy 101.742961 -247.774789)
			(xy 101.730549 -247.823803) (xy 101.710238 -247.870106) (xy 101.682584 -247.912434) (xy 101.648339 -247.949633)
			(xy 101.608439 -247.980689) (xy 101.563971 -248.004753) (xy 101.516149 -248.02117) (xy 101.466277 -248.029491)
			(xy 101.440996 -248.029984) (xy 100.500942 -248.029984) (xy 100.475663 -248.02945) (xy 100.425793 -248.021135)
			(xy 100.377972 -248.004724) (xy 100.333506 -247.980665) (xy 100.293605 -247.949615) (xy 100.259361 -247.91242)
			(xy 100.231706 -247.870096) (xy 100.211395 -247.823796) (xy 100.198983 -247.774786) (xy 100.194807 -247.7244)
			(xy 98.927237 -247.7244) (xy 98.923061 -247.77479) (xy 98.910648 -247.823805) (xy 98.890337 -247.870108)
			(xy 98.862682 -247.912437) (xy 98.828436 -247.949636) (xy 98.788534 -247.980691) (xy 98.744066 -248.004755)
			(xy 98.696242 -248.021171) (xy 98.646369 -248.029492) (xy 98.621088 -248.029984) (xy 97.681034 -248.029984)
			(xy 97.655755 -248.02945) (xy 97.605887 -248.021133) (xy 97.558067 -248.004721) (xy 97.513601 -247.980662)
			(xy 97.473702 -247.949612) (xy 97.439459 -247.912417) (xy 97.411805 -247.870093) (xy 97.391495 -247.823795)
			(xy 97.379083 -247.774785) (xy 97.374907 -247.7244) (xy 2.509012 -247.7244) (xy 2.509012 -248.5344)
			(xy 108.185168 -248.5344) (xy 108.189339 -248.48406) (xy 108.20174 -248.435093) (xy 108.222032 -248.388834)
			(xy 108.249661 -248.346547) (xy 108.283873 -248.309385) (xy 108.323736 -248.278361) (xy 108.368162 -248.254321)
			(xy 108.415939 -248.237922) (xy 108.465764 -248.229611) (xy 108.49102 -248.22912) (xy 109.431074 -248.22912)
			(xy 109.456335 -248.229555) (xy 109.50617 -248.237867) (xy 109.553956 -248.254268) (xy 109.598391 -248.278312)
			(xy 109.638262 -248.309342) (xy 109.672482 -248.346511) (xy 109.700117 -248.388806) (xy 109.720412 -248.435073)
			(xy 109.732816 -248.48405) (xy 109.736971 -248.5342) (xy 361.758659 -248.5342) (xy 361.762835 -248.48381)
			(xy 361.775248 -248.434795) (xy 361.795559 -248.388491) (xy 361.823214 -248.346162) (xy 361.85746 -248.308962)
			(xy 361.897361 -248.277907) (xy 361.94183 -248.253842) (xy 361.989653 -248.237426) (xy 362.039527 -248.229104)
			(xy 362.064808 -248.228612) (xy 363.004862 -248.228612) (xy 363.030141 -248.229154) (xy 363.080009 -248.23747)
			(xy 363.127829 -248.253881) (xy 363.172294 -248.27794) (xy 363.212193 -248.30899) (xy 363.246437 -248.346184)
			(xy 363.274091 -248.388507) (xy 363.294401 -248.434806) (xy 363.306813 -248.483816) (xy 363.310989 -248.5342)
			(xy 363.306813 -248.584584) (xy 363.294401 -248.633594) (xy 363.274091 -248.679893) (xy 363.246437 -248.722216)
			(xy 363.212193 -248.75941) (xy 363.172294 -248.79046) (xy 363.127829 -248.814519) (xy 363.080009 -248.83093)
			(xy 363.030141 -248.839246) (xy 363.004862 -248.839736) (xy 362.064808 -248.839736) (xy 362.039527 -248.839296)
			(xy 361.989653 -248.830974) (xy 361.94183 -248.814558) (xy 361.897361 -248.790493) (xy 361.85746 -248.759438)
			(xy 361.823214 -248.722238) (xy 361.795559 -248.679909) (xy 361.775248 -248.633605) (xy 361.762835 -248.58459)
			(xy 361.758659 -248.5342) (xy 109.736971 -248.5342) (xy 109.736988 -248.5344) (xy 109.732816 -248.58475)
			(xy 109.720412 -248.633727) (xy 109.700117 -248.679994) (xy 109.672482 -248.722289) (xy 109.638262 -248.759458)
			(xy 109.598391 -248.790488) (xy 109.553956 -248.814532) (xy 109.50617 -248.830933) (xy 109.456335 -248.839245)
			(xy 109.431074 -248.839736) (xy 108.49102 -248.839736) (xy 108.465764 -248.839189) (xy 108.415939 -248.830878)
			(xy 108.368162 -248.814479) (xy 108.323736 -248.790439) (xy 108.283873 -248.759415) (xy 108.249661 -248.722253)
			(xy 108.222032 -248.679966) (xy 108.20174 -248.633707) (xy 108.189339 -248.58474) (xy 108.185168 -248.5344)
			(xy 2.509012 -248.5344) (xy 2.509012 -258.880356) (xy 67.312036 -258.880356) (xy 67.316066 -258.738021)
			(xy 67.328141 -258.596141) (xy 67.348224 -258.455173) (xy 67.376251 -258.315566) (xy 67.412131 -258.177768)
			(xy 67.455749 -258.042221) (xy 67.506966 -257.909359) (xy 67.565617 -257.779607) (xy 67.631515 -257.653381)
			(xy 67.704449 -257.531085) (xy 67.784186 -257.413112) (xy 67.870468 -257.299839) (xy 67.963021 -257.191628)
			(xy 68.061548 -257.088827) (xy 68.165733 -256.991765) (xy 68.275242 -256.900753) (xy 68.389725 -256.816081)
			(xy 68.508815 -256.738023) (xy 68.63213 -256.666827) (xy 68.759276 -256.602721) (xy 68.889845 -256.545912)
			(xy 69.023419 -256.49658) (xy 69.15957 -256.454884) (xy 69.297861 -256.420958) (xy 69.437851 -256.39491)
			(xy 69.57909 -256.376824) (xy 69.721126 -256.366757) (xy 69.863504 -256.364742) (xy 70.005768 -256.370785)
			(xy 70.147462 -256.384867) (xy 70.288132 -256.406943) (xy 70.427329 -256.436943) (xy 70.564605 -256.474769)
			(xy 70.699521 -256.520301) (xy 70.831645 -256.573392) (xy 70.960554 -256.633874) (xy 71.085835 -256.701552)
			(xy 71.207086 -256.776209) (xy 71.323919 -256.857607) (xy 71.43596 -256.945484) (xy 71.54285 -257.039559)
			(xy 71.644247 -257.139531) (xy 71.739825 -257.245079) (xy 71.829279 -257.355865) (xy 71.912321 -257.471534)
			(xy 71.988687 -257.591717) (xy 72.058131 -257.716027) (xy 72.120431 -257.844068) (xy 72.175387 -257.975427)
			(xy 72.222824 -258.109686) (xy 72.262588 -258.246413) (xy 72.294554 -258.385171) (xy 72.318619 -258.525515)
			(xy 72.334705 -258.666996) (xy 72.34276 -258.80916) (xy 72.343264 -258.880356) (xy 151.51202 -258.880356)
			(xy 151.51605 -258.738021) (xy 151.528125 -258.596141) (xy 151.548208 -258.455173) (xy 151.576235 -258.315566)
			(xy 151.612115 -258.177768) (xy 151.655733 -258.042221) (xy 151.70695 -257.909359) (xy 151.765601 -257.779607)
			(xy 151.831499 -257.653381) (xy 151.904433 -257.531085) (xy 151.98417 -257.413112) (xy 152.070452 -257.299839)
			(xy 152.163005 -257.191628) (xy 152.261532 -257.088827) (xy 152.365717 -256.991765) (xy 152.475226 -256.900753)
			(xy 152.589709 -256.816081) (xy 152.708799 -256.738023) (xy 152.832114 -256.666827) (xy 152.95926 -256.602721)
			(xy 153.089829 -256.545912) (xy 153.223403 -256.49658) (xy 153.359554 -256.454884) (xy 153.497845 -256.420958)
			(xy 153.637835 -256.39491) (xy 153.779074 -256.376824) (xy 153.92111 -256.366757) (xy 154.063488 -256.364742)
			(xy 154.205752 -256.370785) (xy 154.347446 -256.384867) (xy 154.488116 -256.406943) (xy 154.627313 -256.436943)
			(xy 154.764589 -256.474769) (xy 154.899505 -256.520301) (xy 155.031629 -256.573392) (xy 155.160538 -256.633874)
			(xy 155.285819 -256.701552) (xy 155.40707 -256.776209) (xy 155.523903 -256.857607) (xy 155.635944 -256.945484)
			(xy 155.742834 -257.039559) (xy 155.844231 -257.139531) (xy 155.939809 -257.245079) (xy 156.029263 -257.355865)
			(xy 156.112305 -257.471534) (xy 156.188671 -257.591717) (xy 156.258115 -257.716027) (xy 156.320415 -257.844068)
			(xy 156.375371 -257.975427) (xy 156.422808 -258.109686) (xy 156.462572 -258.246413) (xy 156.494538 -258.385171)
			(xy 156.518603 -258.525515) (xy 156.534689 -258.666996) (xy 156.542744 -258.80916) (xy 156.543246 -258.880102)
			(xy 315.252104 -258.880102) (xy 315.256134 -258.737767) (xy 315.268209 -258.595887) (xy 315.288292 -258.454919)
			(xy 315.316319 -258.315312) (xy 315.352199 -258.177514) (xy 315.395817 -258.041967) (xy 315.447034 -257.909105)
			(xy 315.505685 -257.779353) (xy 315.571583 -257.653127) (xy 315.644517 -257.530831) (xy 315.724254 -257.412858)
			(xy 315.810536 -257.299585) (xy 315.903089 -257.191374) (xy 316.001616 -257.088573) (xy 316.105801 -256.991511)
			(xy 316.21531 -256.900499) (xy 316.329793 -256.815827) (xy 316.448883 -256.737769) (xy 316.572198 -256.666573)
			(xy 316.699344 -256.602467) (xy 316.829913 -256.545658) (xy 316.963487 -256.496326) (xy 317.099638 -256.45463)
			(xy 317.237929 -256.420704) (xy 317.377919 -256.394656) (xy 317.519158 -256.37657) (xy 317.661194 -256.366503)
			(xy 317.803572 -256.364488) (xy 317.945836 -256.370531) (xy 318.08753 -256.384613) (xy 318.2282 -256.406689)
			(xy 318.367397 -256.436689) (xy 318.504673 -256.474515) (xy 318.639589 -256.520047) (xy 318.771713 -256.573138)
			(xy 318.900622 -256.63362) (xy 319.025903 -256.701298) (xy 319.147154 -256.775955) (xy 319.263987 -256.857353)
			(xy 319.376028 -256.94523) (xy 319.482918 -257.039305) (xy 319.584315 -257.139277) (xy 319.679893 -257.244825)
			(xy 319.769347 -257.355611) (xy 319.852389 -257.47128) (xy 319.928755 -257.591463) (xy 319.998199 -257.715773)
			(xy 320.060499 -257.843814) (xy 320.115455 -257.975173) (xy 320.162892 -258.109432) (xy 320.202656 -258.246159)
			(xy 320.234622 -258.384917) (xy 320.258687 -258.525261) (xy 320.274773 -258.666742) (xy 320.282828 -258.808906)
			(xy 320.283332 -258.880102) (xy 399.452088 -258.880102) (xy 399.456118 -258.737767) (xy 399.468193 -258.595887)
			(xy 399.488276 -258.454919) (xy 399.516303 -258.315312) (xy 399.552183 -258.177514) (xy 399.595801 -258.041967)
			(xy 399.647018 -257.909105) (xy 399.705669 -257.779353) (xy 399.771567 -257.653127) (xy 399.844501 -257.530831)
			(xy 399.924238 -257.412858) (xy 400.01052 -257.299585) (xy 400.103073 -257.191374) (xy 400.2016 -257.088573)
			(xy 400.305785 -256.991511) (xy 400.415294 -256.900499) (xy 400.529777 -256.815827) (xy 400.648867 -256.737769)
			(xy 400.772182 -256.666573) (xy 400.899328 -256.602467) (xy 401.029897 -256.545658) (xy 401.163471 -256.496326)
			(xy 401.299622 -256.45463) (xy 401.437913 -256.420704) (xy 401.577903 -256.394656) (xy 401.719142 -256.37657)
			(xy 401.861178 -256.366503) (xy 402.003556 -256.364488) (xy 402.14582 -256.370531) (xy 402.287514 -256.384613)
			(xy 402.428184 -256.406689) (xy 402.567381 -256.436689) (xy 402.704657 -256.474515) (xy 402.839573 -256.520047)
			(xy 402.971697 -256.573138) (xy 403.100606 -256.63362) (xy 403.225887 -256.701298) (xy 403.347138 -256.775955)
			(xy 403.463971 -256.857353) (xy 403.576012 -256.94523) (xy 403.682902 -257.039305) (xy 403.784299 -257.139277)
			(xy 403.879877 -257.244825) (xy 403.969331 -257.355611) (xy 404.052373 -257.47128) (xy 404.128739 -257.591463)
			(xy 404.198183 -257.715773) (xy 404.260483 -257.843814) (xy 404.315439 -257.975173) (xy 404.362876 -258.109432)
			(xy 404.40264 -258.246159) (xy 404.434606 -258.384917) (xy 404.458671 -258.525261) (xy 404.474757 -258.666742)
			(xy 404.482812 -258.808906) (xy 404.483316 -258.880102) (xy 404.482812 -258.951298) (xy 404.474757 -259.093462)
			(xy 404.458671 -259.234943) (xy 404.434606 -259.375287) (xy 404.40264 -259.514045) (xy 404.362876 -259.650772)
			(xy 404.315439 -259.785031) (xy 404.260483 -259.91639) (xy 404.198183 -260.044431) (xy 404.128739 -260.168741)
			(xy 404.052373 -260.288924) (xy 403.969331 -260.404593) (xy 403.879877 -260.515379) (xy 403.784299 -260.620927)
			(xy 403.682902 -260.720899) (xy 403.576012 -260.814974) (xy 403.463971 -260.902851) (xy 403.347138 -260.984249)
			(xy 403.225887 -261.058906) (xy 403.100606 -261.126584) (xy 402.971697 -261.187066) (xy 402.839573 -261.240157)
			(xy 402.704657 -261.285689) (xy 402.567381 -261.323515) (xy 402.428184 -261.353515) (xy 402.287514 -261.375591)
			(xy 402.14582 -261.389673) (xy 402.003556 -261.395716) (xy 401.861178 -261.393701) (xy 401.719142 -261.383634)
			(xy 401.577903 -261.365548) (xy 401.437913 -261.3395) (xy 401.299622 -261.305574) (xy 401.163471 -261.263878)
			(xy 401.029897 -261.214546) (xy 400.899328 -261.157737) (xy 400.772182 -261.093631) (xy 400.648867 -261.022435)
			(xy 400.529777 -260.944377) (xy 400.415294 -260.859705) (xy 400.305785 -260.768693) (xy 400.2016 -260.671631)
			(xy 400.103073 -260.56883) (xy 400.01052 -260.460619) (xy 399.924238 -260.347346) (xy 399.844501 -260.229373)
			(xy 399.771567 -260.107077) (xy 399.705669 -259.980851) (xy 399.647018 -259.851099) (xy 399.595801 -259.718237)
			(xy 399.552183 -259.58269) (xy 399.516303 -259.444892) (xy 399.488276 -259.305285) (xy 399.468193 -259.164317)
			(xy 399.456118 -259.022437) (xy 399.452088 -258.880102) (xy 320.283332 -258.880102) (xy 320.282828 -258.951298)
			(xy 320.274773 -259.093462) (xy 320.258687 -259.234943) (xy 320.234622 -259.375287) (xy 320.202656 -259.514045)
			(xy 320.162892 -259.650772) (xy 320.115455 -259.785031) (xy 320.060499 -259.91639) (xy 319.998199 -260.044431)
			(xy 319.928755 -260.168741) (xy 319.852389 -260.288924) (xy 319.769347 -260.404593) (xy 319.679893 -260.515379)
			(xy 319.584315 -260.620927) (xy 319.482918 -260.720899) (xy 319.376028 -260.814974) (xy 319.263987 -260.902851)
			(xy 319.147154 -260.984249) (xy 319.025903 -261.058906) (xy 318.900622 -261.126584) (xy 318.771713 -261.187066)
			(xy 318.639589 -261.240157) (xy 318.504673 -261.285689) (xy 318.367397 -261.323515) (xy 318.2282 -261.353515)
			(xy 318.08753 -261.375591) (xy 317.945836 -261.389673) (xy 317.803572 -261.395716) (xy 317.661194 -261.393701)
			(xy 317.519158 -261.383634) (xy 317.377919 -261.365548) (xy 317.237929 -261.3395) (xy 317.099638 -261.305574)
			(xy 316.963487 -261.263878) (xy 316.829913 -261.214546) (xy 316.699344 -261.157737) (xy 316.572198 -261.093631)
			(xy 316.448883 -261.022435) (xy 316.329793 -260.944377) (xy 316.21531 -260.859705) (xy 316.105801 -260.768693)
			(xy 316.001616 -260.671631) (xy 315.903089 -260.56883) (xy 315.810536 -260.460619) (xy 315.724254 -260.347346)
			(xy 315.644517 -260.229373) (xy 315.571583 -260.107077) (xy 315.505685 -259.980851) (xy 315.447034 -259.851099)
			(xy 315.395817 -259.718237) (xy 315.352199 -259.58269) (xy 315.316319 -259.444892) (xy 315.288292 -259.305285)
			(xy 315.268209 -259.164317) (xy 315.256134 -259.022437) (xy 315.252104 -258.880102) (xy 156.543246 -258.880102)
			(xy 156.543248 -258.880356) (xy 156.542744 -258.951552) (xy 156.534689 -259.093716) (xy 156.518603 -259.235197)
			(xy 156.494538 -259.375541) (xy 156.462572 -259.514299) (xy 156.422808 -259.651026) (xy 156.375371 -259.785285)
			(xy 156.320415 -259.916644) (xy 156.258115 -260.044685) (xy 156.188671 -260.168995) (xy 156.112305 -260.289178)
			(xy 156.029263 -260.404847) (xy 155.939809 -260.515633) (xy 155.844231 -260.621181) (xy 155.742834 -260.721153)
			(xy 155.635944 -260.815228) (xy 155.523903 -260.903105) (xy 155.40707 -260.984503) (xy 155.285819 -261.05916)
			(xy 155.160538 -261.126838) (xy 155.031629 -261.18732) (xy 154.899505 -261.240411) (xy 154.764589 -261.285943)
			(xy 154.627313 -261.323769) (xy 154.488116 -261.353769) (xy 154.347446 -261.375845) (xy 154.205752 -261.389927)
			(xy 154.063488 -261.39597) (xy 153.92111 -261.393955) (xy 153.779074 -261.383888) (xy 153.637835 -261.365802)
			(xy 153.497845 -261.339754) (xy 153.359554 -261.305828) (xy 153.223403 -261.264132) (xy 153.089829 -261.2148)
			(xy 152.95926 -261.157991) (xy 152.832114 -261.093885) (xy 152.708799 -261.022689) (xy 152.589709 -260.944631)
			(xy 152.475226 -260.859959) (xy 152.365717 -260.768947) (xy 152.261532 -260.671885) (xy 152.163005 -260.569084)
			(xy 152.070452 -260.460873) (xy 151.98417 -260.3476) (xy 151.904433 -260.229627) (xy 151.831499 -260.107331)
			(xy 151.765601 -259.981105) (xy 151.70695 -259.851353) (xy 151.655733 -259.718491) (xy 151.612115 -259.582944)
			(xy 151.576235 -259.445146) (xy 151.548208 -259.305539) (xy 151.528125 -259.164571) (xy 151.51605 -259.022691)
			(xy 151.51202 -258.880356) (xy 72.343264 -258.880356) (xy 72.34276 -258.951552) (xy 72.334705 -259.093716)
			(xy 72.318619 -259.235197) (xy 72.294554 -259.375541) (xy 72.262588 -259.514299) (xy 72.222824 -259.651026)
			(xy 72.175387 -259.785285) (xy 72.120431 -259.916644) (xy 72.058131 -260.044685) (xy 71.988687 -260.168995)
			(xy 71.912321 -260.289178) (xy 71.829279 -260.404847) (xy 71.739825 -260.515633) (xy 71.644247 -260.621181)
			(xy 71.54285 -260.721153) (xy 71.43596 -260.815228) (xy 71.323919 -260.903105) (xy 71.207086 -260.984503)
			(xy 71.085835 -261.05916) (xy 70.960554 -261.126838) (xy 70.831645 -261.18732) (xy 70.699521 -261.240411)
			(xy 70.564605 -261.285943) (xy 70.427329 -261.323769) (xy 70.288132 -261.353769) (xy 70.147462 -261.375845)
			(xy 70.005768 -261.389927) (xy 69.863504 -261.39597) (xy 69.721126 -261.393955) (xy 69.57909 -261.383888)
			(xy 69.437851 -261.365802) (xy 69.297861 -261.339754) (xy 69.15957 -261.305828) (xy 69.023419 -261.264132)
			(xy 68.889845 -261.2148) (xy 68.759276 -261.157991) (xy 68.63213 -261.093885) (xy 68.508815 -261.022689)
			(xy 68.389725 -260.944631) (xy 68.275242 -260.859959) (xy 68.165733 -260.768947) (xy 68.061548 -260.671885)
			(xy 67.963021 -260.569084) (xy 67.870468 -260.460873) (xy 67.784186 -260.3476) (xy 67.704449 -260.229627)
			(xy 67.631515 -260.107331) (xy 67.565617 -259.981105) (xy 67.506966 -259.851353) (xy 67.455749 -259.718491)
			(xy 67.412131 -259.582944) (xy 67.376251 -259.445146) (xy 67.348224 -259.305539) (xy 67.328141 -259.164571)
			(xy 67.316066 -259.022691) (xy 67.312036 -258.880356) (xy 2.509012 -258.880356) (xy 2.509012 -281.3764)
			(xy 97.674859 -281.3764) (xy 97.679035 -281.32601) (xy 97.691448 -281.276995) (xy 97.711759 -281.230691)
			(xy 97.739414 -281.188362) (xy 97.77366 -281.151162) (xy 97.813561 -281.120107) (xy 97.85803 -281.096042)
			(xy 97.905853 -281.079626) (xy 97.955727 -281.071304) (xy 97.981008 -281.070812) (xy 98.921062 -281.070812)
			(xy 98.946341 -281.071354) (xy 98.996209 -281.07967) (xy 99.044029 -281.096081) (xy 99.088494 -281.12014)
			(xy 99.128393 -281.15119) (xy 99.162637 -281.188384) (xy 99.190291 -281.230707) (xy 99.210601 -281.277006)
			(xy 99.223013 -281.326016) (xy 99.227189 -281.3764) (xy 100.495088 -281.3764) (xy 100.499263 -281.326019)
			(xy 100.511672 -281.277012) (xy 100.531978 -281.230715) (xy 100.559627 -281.188392) (xy 100.593865 -281.151197)
			(xy 100.633757 -281.120144) (xy 100.678216 -281.09608) (xy 100.72603 -281.079662) (xy 100.775893 -281.071336)
			(xy 100.80117 -281.070812) (xy 101.741224 -281.070812) (xy 101.766497 -281.071388) (xy 101.816353 -281.079711)
			(xy 101.864159 -281.096126) (xy 101.908611 -281.120186) (xy 101.948498 -281.151233) (xy 101.98273 -281.188422)
			(xy 102.010375 -281.230738) (xy 102.030678 -281.277027) (xy 102.043086 -281.326027) (xy 102.04726 -281.3764)
			(xy 122.108688 -281.3764) (xy 122.112863 -281.326017) (xy 122.125274 -281.277007) (xy 122.145582 -281.230709)
			(xy 122.173233 -281.188385) (xy 122.207473 -281.151189) (xy 122.247369 -281.120136) (xy 122.291831 -281.096074)
			(xy 122.339648 -281.079657) (xy 122.389514 -281.071335) (xy 122.414792 -281.070812) (xy 123.354846 -281.070812)
			(xy 123.380118 -281.071389) (xy 123.429971 -281.079715) (xy 123.477774 -281.096133) (xy 123.522223 -281.120193)
			(xy 123.562106 -281.151241) (xy 123.596336 -281.18843) (xy 123.623978 -281.230745) (xy 123.64428 -281.277032)
			(xy 123.656686 -281.326029) (xy 123.66086 -281.3764) (xy 124.928589 -281.3764) (xy 124.932763 -281.326016)
			(xy 124.945174 -281.277006) (xy 124.965483 -281.230707) (xy 124.993135 -281.188382) (xy 125.027376 -281.151186)
			(xy 125.067273 -281.120134) (xy 125.111736 -281.096071) (xy 125.159554 -281.079655) (xy 125.209422 -281.071334)
			(xy 125.2347 -281.070812) (xy 126.174754 -281.070812) (xy 126.200033 -281.071353) (xy 126.249903 -281.079668)
			(xy 126.297723 -281.096079) (xy 126.34219 -281.120137) (xy 126.38209 -281.151187) (xy 126.416335 -281.188381)
			(xy 126.44399 -281.230705) (xy 126.464301 -281.277004) (xy 126.476713 -281.326015) (xy 126.480864 -281.3761)
			(xy 345.615289 -281.3761) (xy 345.619459 -281.325768) (xy 345.631857 -281.276808) (xy 345.652144 -281.230557)
			(xy 345.679766 -281.188275) (xy 345.713971 -281.151116) (xy 345.753825 -281.120094) (xy 345.798241 -281.096054)
			(xy 345.846008 -281.079652) (xy 345.895824 -281.071335) (xy 345.921076 -281.070812) (xy 346.86113 -281.070812)
			(xy 346.886385 -281.071296) (xy 346.936207 -281.079614) (xy 346.983979 -281.096019) (xy 347.028401 -281.120062)
			(xy 347.068259 -281.151089) (xy 347.102467 -281.188252) (xy 347.130092 -281.230539) (xy 347.150381 -281.276796)
			(xy 347.16278 -281.325762) (xy 347.166951 -281.3761) (xy 348.43536 -281.3761) (xy 348.439532 -281.325756)
			(xy 348.451934 -281.276786) (xy 348.472227 -281.230526) (xy 348.499859 -281.188237) (xy 348.534075 -281.151073)
			(xy 348.573942 -281.120048) (xy 348.618371 -281.096009) (xy 348.666152 -281.079611) (xy 348.71598 -281.071302)
			(xy 348.741238 -281.070812) (xy 349.681292 -281.070812) (xy 349.706552 -281.071264) (xy 349.756383 -281.079578)
			(xy 349.804165 -281.095981) (xy 349.848596 -281.120025) (xy 349.888464 -281.151054) (xy 349.92268 -281.188222)
			(xy 349.950312 -281.230515) (xy 349.970606 -281.276779) (xy 349.983008 -281.325753) (xy 349.98718 -281.3761)
			(xy 370.049089 -281.3761) (xy 370.053259 -281.325769) (xy 370.065656 -281.276811) (xy 370.085941 -281.230561)
			(xy 370.113562 -281.18828) (xy 370.147764 -281.151122) (xy 370.187616 -281.120099) (xy 370.23203 -281.096058)
			(xy 370.279795 -281.079655) (xy 370.329608 -281.071337) (xy 370.35486 -281.070812) (xy 371.294914 -281.070812)
			(xy 371.32017 -281.071295) (xy 371.369993 -281.079611) (xy 371.417768 -281.096014) (xy 371.462192 -281.120057)
			(xy 371.502053 -281.151083) (xy 371.536263 -281.188247) (xy 371.56389 -281.230535) (xy 371.58418 -281.276793)
			(xy 371.59658 -281.32576) (xy 371.600751 -281.3761) (xy 372.868989 -281.3761) (xy 372.873159 -281.325768)
			(xy 372.885556 -281.27681) (xy 372.905842 -281.230559) (xy 372.933464 -281.188278) (xy 372.967667 -281.151119)
			(xy 373.00752 -281.120096) (xy 373.051935 -281.096056) (xy 373.099702 -281.079653) (xy 373.149516 -281.071336)
			(xy 373.174768 -281.070812) (xy 374.114822 -281.070812) (xy 374.140078 -281.071295) (xy 374.1899 -281.079613)
			(xy 374.237674 -281.096016) (xy 374.282096 -281.120059) (xy 374.321956 -281.151086) (xy 374.356165 -281.18825)
			(xy 374.383791 -281.230537) (xy 374.404081 -281.276795) (xy 374.41648 -281.325761) (xy 374.420651 -281.3761)
			(xy 374.41648 -281.426439) (xy 374.404081 -281.475405) (xy 374.383791 -281.521663) (xy 374.356165 -281.56395)
			(xy 374.321956 -281.601114) (xy 374.282096 -281.632141) (xy 374.237674 -281.656184) (xy 374.1899 -281.672587)
			(xy 374.140078 -281.680905) (xy 374.114822 -281.681428) (xy 373.174768 -281.681428) (xy 373.149516 -281.680864)
			(xy 373.099702 -281.672547) (xy 373.051935 -281.656144) (xy 373.00752 -281.632104) (xy 372.967667 -281.601081)
			(xy 372.933464 -281.563922) (xy 372.905842 -281.521641) (xy 372.885556 -281.47539) (xy 372.873159 -281.426432)
			(xy 372.868989 -281.3761) (xy 371.600751 -281.3761) (xy 371.59658 -281.42644) (xy 371.58418 -281.475407)
			(xy 371.56389 -281.521665) (xy 371.536263 -281.563953) (xy 371.502053 -281.601117) (xy 371.462192 -281.632143)
			(xy 371.417768 -281.656186) (xy 371.369993 -281.672589) (xy 371.32017 -281.680905) (xy 371.294914 -281.681428)
			(xy 370.35486 -281.681428) (xy 370.329609 -281.680863) (xy 370.279795 -281.672545) (xy 370.23203 -281.656142)
			(xy 370.187616 -281.632101) (xy 370.147764 -281.601078) (xy 370.113562 -281.56392) (xy 370.085941 -281.521639)
			(xy 370.065656 -281.475389) (xy 370.053259 -281.426431) (xy 370.049089 -281.3761) (xy 349.98718 -281.3761)
			(xy 349.983008 -281.426447) (xy 349.970606 -281.475421) (xy 349.950312 -281.521685) (xy 349.92268 -281.563978)
			(xy 349.888464 -281.601146) (xy 349.848596 -281.632175) (xy 349.804165 -281.656219) (xy 349.756383 -281.672622)
			(xy 349.706552 -281.680936) (xy 349.681292 -281.681428) (xy 348.741238 -281.681428) (xy 348.71598 -281.680898)
			(xy 348.666152 -281.672589) (xy 348.618371 -281.656191) (xy 348.573941 -281.632152) (xy 348.534075 -281.601127)
			(xy 348.499859 -281.563963) (xy 348.472227 -281.521674) (xy 348.451934 -281.475414) (xy 348.439532 -281.426444)
			(xy 348.43536 -281.3761) (xy 347.166951 -281.3761) (xy 347.16278 -281.426438) (xy 347.150381 -281.475404)
			(xy 347.130092 -281.521661) (xy 347.102467 -281.563948) (xy 347.068259 -281.601111) (xy 347.028401 -281.632138)
			(xy 346.983979 -281.656181) (xy 346.936207 -281.672586) (xy 346.886385 -281.680904) (xy 346.86113 -281.681428)
			(xy 345.921076 -281.681428) (xy 345.895824 -281.680865) (xy 345.846008 -281.672548) (xy 345.798241 -281.656146)
			(xy 345.753825 -281.632106) (xy 345.713971 -281.601084) (xy 345.679766 -281.563925) (xy 345.652144 -281.521643)
			(xy 345.631857 -281.475392) (xy 345.619459 -281.426432) (xy 345.615289 -281.3761) (xy 126.480864 -281.3761)
			(xy 126.480889 -281.3764) (xy 126.476713 -281.426785) (xy 126.464301 -281.475796) (xy 126.44399 -281.522095)
			(xy 126.416335 -281.564419) (xy 126.38209 -281.601613) (xy 126.34219 -281.632663) (xy 126.297723 -281.656721)
			(xy 126.249903 -281.673132) (xy 126.200033 -281.681447) (xy 126.174754 -281.681936) (xy 125.2347 -281.681936)
			(xy 125.209422 -281.681466) (xy 125.159554 -281.673145) (xy 125.111736 -281.656729) (xy 125.067273 -281.632666)
			(xy 125.027376 -281.601614) (xy 124.993135 -281.564418) (xy 124.965483 -281.522093) (xy 124.945174 -281.475794)
			(xy 124.932763 -281.426784) (xy 124.928589 -281.3764) (xy 123.66086 -281.3764) (xy 123.656686 -281.426771)
			(xy 123.64428 -281.475768) (xy 123.623978 -281.522055) (xy 123.596336 -281.56437) (xy 123.562106 -281.601559)
			(xy 123.522223 -281.632607) (xy 123.477774 -281.656667) (xy 123.429971 -281.673085) (xy 123.380118 -281.681411)
			(xy 123.354846 -281.681936) (xy 122.414792 -281.681936) (xy 122.389514 -281.681465) (xy 122.339648 -281.673143)
			(xy 122.291831 -281.656726) (xy 122.247369 -281.632664) (xy 122.207473 -281.601611) (xy 122.173233 -281.564415)
			(xy 122.145582 -281.522091) (xy 122.125274 -281.475793) (xy 122.112863 -281.426783) (xy 122.108688 -281.3764)
			(xy 102.04726 -281.3764) (xy 102.043086 -281.426773) (xy 102.030678 -281.475773) (xy 102.010375 -281.522062)
			(xy 101.98273 -281.564378) (xy 101.948498 -281.601567) (xy 101.908611 -281.632614) (xy 101.864159 -281.656674)
			(xy 101.816353 -281.673089) (xy 101.766497 -281.681412) (xy 101.741224 -281.681936) (xy 100.80117 -281.681936)
			(xy 100.775893 -281.681464) (xy 100.72603 -281.673138) (xy 100.678216 -281.65672) (xy 100.633757 -281.632656)
			(xy 100.593865 -281.601603) (xy 100.559627 -281.564408) (xy 100.531978 -281.522085) (xy 100.511672 -281.475788)
			(xy 100.499263 -281.426781) (xy 100.495088 -281.3764) (xy 99.227189 -281.3764) (xy 99.223013 -281.426784)
			(xy 99.210601 -281.475794) (xy 99.190291 -281.522093) (xy 99.162637 -281.564416) (xy 99.128393 -281.60161)
			(xy 99.088494 -281.63266) (xy 99.044029 -281.656719) (xy 98.996209 -281.67313) (xy 98.946341 -281.681446)
			(xy 98.921062 -281.681936) (xy 97.981008 -281.681936) (xy 97.955727 -281.681496) (xy 97.905853 -281.673174)
			(xy 97.85803 -281.656758) (xy 97.813561 -281.632693) (xy 97.77366 -281.601638) (xy 97.739414 -281.564438)
			(xy 97.711759 -281.522109) (xy 97.691448 -281.475805) (xy 97.679035 -281.42679) (xy 97.674859 -281.3764)
			(xy 2.509012 -281.3764) (xy 2.509012 -282.1864) (xy 108.485149 -282.1864) (xy 108.48932 -282.136059)
			(xy 108.50172 -282.087092) (xy 108.522011 -282.040833) (xy 108.549639 -281.998544) (xy 108.58385 -281.96138)
			(xy 108.623712 -281.930354) (xy 108.668137 -281.906312) (xy 108.715913 -281.889909) (xy 108.765737 -281.881594)
			(xy 108.790994 -281.881072) (xy 109.731048 -281.881072) (xy 109.756299 -281.881637) (xy 109.806111 -281.889957)
			(xy 109.853875 -281.906361) (xy 109.898288 -281.930402) (xy 109.938139 -281.961425) (xy 109.97234 -281.998583)
			(xy 109.99996 -282.040863) (xy 110.020245 -282.087113) (xy 110.032641 -282.13607) (xy 110.036811 -282.1864)
			(xy 114.11882 -282.1864) (xy 114.122992 -282.136052) (xy 114.135394 -282.087078) (xy 114.155689 -282.040813)
			(xy 114.183321 -281.99852) (xy 114.217539 -281.961352) (xy 114.257407 -281.930323) (xy 114.301839 -281.906279)
			(xy 114.349622 -281.889877) (xy 114.399454 -281.881564) (xy 114.424714 -281.881072) (xy 115.364768 -281.881072)
			(xy 115.390026 -281.881602) (xy 115.439853 -281.889912) (xy 115.487633 -281.90631) (xy 115.532062 -281.93035)
			(xy 115.571927 -281.961375) (xy 115.606142 -281.998539) (xy 115.633773 -282.040827) (xy 115.654067 -282.087088)
			(xy 115.666468 -282.136057) (xy 115.670615 -282.1861) (xy 356.42504 -282.1861) (xy 356.429214 -282.135728)
			(xy 356.441621 -282.08673) (xy 356.461923 -282.040442) (xy 356.489566 -281.998127) (xy 356.523797 -281.960938)
			(xy 356.563681 -281.92989) (xy 356.608132 -281.90583) (xy 356.655936 -281.889414) (xy 356.70579 -281.881089)
			(xy 356.731062 -281.880564) (xy 357.671116 -281.880564) (xy 357.696394 -281.881035) (xy 357.746259 -281.889359)
			(xy 357.794074 -281.905776) (xy 357.838536 -281.929839) (xy 357.87843 -281.960892) (xy 357.912669 -281.998088)
			(xy 357.940319 -282.040411) (xy 357.960627 -282.086709) (xy 357.973037 -282.135717) (xy 357.977212 -282.1861)
			(xy 362.05874 -282.1861) (xy 362.062914 -282.135726) (xy 362.075322 -282.086726) (xy 362.095626 -282.040437)
			(xy 362.123271 -281.99812) (xy 362.157505 -281.960931) (xy 362.197392 -281.929883) (xy 362.241845 -281.905824)
			(xy 362.289652 -281.88941) (xy 362.339509 -281.881087) (xy 362.364782 -281.880564) (xy 363.304836 -281.880564)
			(xy 363.330113 -281.881037) (xy 363.379975 -281.889363) (xy 363.427788 -281.905782) (xy 363.472246 -281.929846)
			(xy 363.512138 -281.960899) (xy 363.546374 -281.998094) (xy 363.574022 -282.040417) (xy 363.594328 -282.086713)
			(xy 363.606737 -282.135719) (xy 363.610912 -282.1861) (xy 363.606737 -282.236481) (xy 363.594328 -282.285487)
			(xy 363.574022 -282.331783) (xy 363.546374 -282.374106) (xy 363.512138 -282.411301) (xy 363.472246 -282.442354)
			(xy 363.427788 -282.466418) (xy 363.379975 -282.482837) (xy 363.330113 -282.491163) (xy 363.304836 -282.491688)
			(xy 362.364782 -282.491688) (xy 362.339509 -282.491113) (xy 362.289652 -282.48279) (xy 362.241845 -282.466376)
			(xy 362.197392 -282.442317) (xy 362.157505 -282.411269) (xy 362.123271 -282.37408) (xy 362.095626 -282.331763)
			(xy 362.075322 -282.285474) (xy 362.062914 -282.236474) (xy 362.05874 -282.1861) (xy 357.977212 -282.1861)
			(xy 357.973037 -282.236483) (xy 357.960627 -282.285491) (xy 357.940319 -282.331789) (xy 357.912669 -282.374112)
			(xy 357.87843 -282.411308) (xy 357.838536 -282.442361) (xy 357.794074 -282.466424) (xy 357.746259 -282.482841)
			(xy 357.696394 -282.491165) (xy 357.671116 -282.491688) (xy 356.731062 -282.491688) (xy 356.70579 -282.491111)
			(xy 356.655936 -282.482786) (xy 356.608132 -282.46637) (xy 356.563681 -282.44231) (xy 356.523797 -282.411262)
			(xy 356.489566 -282.374073) (xy 356.461923 -282.331758) (xy 356.441621 -282.28547) (xy 356.429214 -282.236472)
			(xy 356.42504 -282.1861) (xy 115.670615 -282.1861) (xy 115.67064 -282.1864) (xy 115.666468 -282.236743)
			(xy 115.654067 -282.285712) (xy 115.633773 -282.331973) (xy 115.606142 -282.374261) (xy 115.571927 -282.411425)
			(xy 115.532062 -282.44245) (xy 115.487633 -282.46649) (xy 115.439853 -282.482888) (xy 115.390026 -282.491198)
			(xy 115.364768 -282.491688) (xy 114.424714 -282.491688) (xy 114.399454 -282.491236) (xy 114.349622 -282.482923)
			(xy 114.301839 -282.466521) (xy 114.257407 -282.442477) (xy 114.217539 -282.411448) (xy 114.183321 -282.37428)
			(xy 114.155689 -282.331987) (xy 114.135394 -282.285722) (xy 114.122992 -282.236748) (xy 114.11882 -282.1864)
			(xy 110.036811 -282.1864) (xy 110.032641 -282.23673) (xy 110.020245 -282.285687) (xy 109.99996 -282.331937)
			(xy 109.97234 -282.374217) (xy 109.938139 -282.411375) (xy 109.898288 -282.442398) (xy 109.853875 -282.466439)
			(xy 109.806111 -282.482843) (xy 109.756299 -282.491163) (xy 109.731048 -282.491688) (xy 108.790994 -282.491688)
			(xy 108.765737 -282.491206) (xy 108.715913 -282.482891) (xy 108.668137 -282.466488) (xy 108.623712 -282.442446)
			(xy 108.58385 -282.41142) (xy 108.549639 -282.374256) (xy 108.522011 -282.331967) (xy 108.50172 -282.285708)
			(xy 108.48932 -282.236741) (xy 108.485149 -282.1864) (xy 2.509012 -282.1864) (xy 2.509012 -282.9964)
			(xy 97.674871 -282.9964) (xy 97.679047 -282.946012) (xy 97.691459 -282.896999) (xy 97.711769 -282.850697)
			(xy 97.739424 -282.808369) (xy 97.773668 -282.771171) (xy 97.813568 -282.740117) (xy 97.858035 -282.716053)
			(xy 97.905856 -282.699637) (xy 97.955728 -282.691316) (xy 97.981008 -282.690824) (xy 98.921062 -282.690824)
			(xy 98.946342 -282.691342) (xy 98.996212 -282.699658) (xy 99.044033 -282.71607) (xy 99.088501 -282.74013)
			(xy 99.128401 -282.771181) (xy 99.162646 -282.808377) (xy 99.190302 -282.850702) (xy 99.210613 -282.897002)
			(xy 99.223025 -282.946014) (xy 99.227201 -282.9964) (xy 100.4951 -282.9964) (xy 100.499275 -282.946021)
			(xy 100.511684 -282.897016) (xy 100.531989 -282.850721) (xy 100.559637 -282.8084) (xy 100.593873 -282.771206)
			(xy 100.633764 -282.740154) (xy 100.678221 -282.716091) (xy 100.726032 -282.699673) (xy 100.775894 -282.691348)
			(xy 100.80117 -282.690824) (xy 101.741224 -282.690824) (xy 101.766498 -282.691376) (xy 101.816356 -282.699699)
			(xy 101.864164 -282.716115) (xy 101.908618 -282.740176) (xy 101.948506 -282.771224) (xy 101.98274 -282.808415)
			(xy 102.010385 -282.850733) (xy 102.030689 -282.897024) (xy 102.043098 -282.946025) (xy 102.047272 -282.9964)
			(xy 103.315 -282.9964) (xy 103.319175 -282.94602) (xy 103.331584 -282.897014) (xy 103.35189 -282.850719)
			(xy 103.379539 -282.808397) (xy 103.413776 -282.771203) (xy 103.453668 -282.740151) (xy 103.498126 -282.716089)
			(xy 103.545939 -282.699672) (xy 103.595802 -282.691348) (xy 103.621078 -282.690824) (xy 104.561132 -282.690824)
			(xy 104.586405 -282.691376) (xy 104.636262 -282.699701) (xy 104.684069 -282.716117) (xy 104.728522 -282.740178)
			(xy 104.768409 -282.771227) (xy 104.802642 -282.808418) (xy 104.830287 -282.850735) (xy 104.85059 -282.897025)
			(xy 104.862998 -282.946026) (xy 104.867172 -282.9964) (xy 106.1349 -282.9964) (xy 106.139075 -282.946019)
			(xy 106.151485 -282.897012) (xy 106.171791 -282.850717) (xy 106.199441 -282.808394) (xy 106.233679 -282.7712)
			(xy 106.273572 -282.740149) (xy 106.318032 -282.716086) (xy 106.365846 -282.69967) (xy 106.415709 -282.691347)
			(xy 106.440986 -282.690824) (xy 107.38104 -282.690824) (xy 107.406313 -282.691377) (xy 107.456169 -282.699702)
			(xy 107.503975 -282.71612) (xy 107.548426 -282.740181) (xy 107.588312 -282.77123) (xy 107.622544 -282.80842)
			(xy 107.650188 -282.850737) (xy 107.67049 -282.897027) (xy 107.682898 -282.946026) (xy 107.687072 -282.9964)
			(xy 116.468571 -282.9964) (xy 116.472747 -282.946011) (xy 116.48516 -282.896996) (xy 116.505471 -282.850693)
			(xy 116.533127 -282.808365) (xy 116.567373 -282.771166) (xy 116.607275 -282.740112) (xy 116.651744 -282.716049)
			(xy 116.699568 -282.699634) (xy 116.749441 -282.691315) (xy 116.774722 -282.690824) (xy 117.714776 -282.690824)
			(xy 117.740055 -282.691343) (xy 117.789924 -282.699661) (xy 117.837743 -282.716074) (xy 117.882208 -282.740135)
			(xy 117.922107 -282.771186) (xy 117.95635 -282.808381) (xy 117.984004 -282.850706) (xy 118.004313 -282.897005)
			(xy 118.016725 -282.946015) (xy 118.020901 -282.9964) (xy 119.288471 -282.9964) (xy 119.292647 -282.94601)
			(xy 119.30506 -282.896994) (xy 119.325373 -282.850691) (xy 119.353029 -282.808362) (xy 119.387276 -282.771163)
			(xy 119.427179 -282.740109) (xy 119.47165 -282.716047) (xy 119.519474 -282.699633) (xy 119.569348 -282.691315)
			(xy 119.59463 -282.690824) (xy 120.534684 -282.690824) (xy 120.559962 -282.691344) (xy 120.60983 -282.699663)
			(xy 120.657648 -282.716077) (xy 120.702113 -282.740137) (xy 120.74201 -282.771189) (xy 120.776252 -282.808384)
			(xy 120.803905 -282.850708) (xy 120.824214 -282.897006) (xy 120.836625 -282.946016) (xy 120.840801 -282.9964)
			(xy 122.1087 -282.9964) (xy 122.112875 -282.946019) (xy 122.125285 -282.897011) (xy 122.145592 -282.850715)
			(xy 122.173242 -282.808392) (xy 122.207481 -282.771198) (xy 122.247375 -282.740147) (xy 122.291836 -282.716085)
			(xy 122.33965 -282.699669) (xy 122.389515 -282.691347) (xy 122.414792 -282.690824) (xy 123.354846 -282.690824)
			(xy 123.380119 -282.691377) (xy 123.429974 -282.699704) (xy 123.477779 -282.716122) (xy 123.52223 -282.740183)
			(xy 123.562114 -282.771232) (xy 123.596345 -282.808422) (xy 123.623989 -282.850739) (xy 123.644291 -282.897028)
			(xy 123.656698 -282.946027) (xy 123.660872 -282.9964) (xy 124.928601 -282.9964) (xy 124.932775 -282.946018)
			(xy 124.945186 -282.89701) (xy 124.965494 -282.850713) (xy 124.993144 -282.80839) (xy 125.027384 -282.771195)
			(xy 125.067279 -282.740144) (xy 125.111741 -282.716082) (xy 125.159557 -282.699667) (xy 125.209423 -282.691346)
			(xy 125.2347 -282.690824) (xy 126.174754 -282.690824) (xy 126.200034 -282.691341) (xy 126.249906 -282.699657)
			(xy 126.297728 -282.716068) (xy 126.342197 -282.740127) (xy 126.382098 -282.771178) (xy 126.416344 -282.808374)
			(xy 126.444 -282.850699) (xy 126.464312 -282.897) (xy 126.476725 -282.946013) (xy 126.480876 -282.9961)
			(xy 345.615301 -282.9961) (xy 345.619471 -282.94577) (xy 345.631868 -282.896812) (xy 345.652154 -282.850562)
			(xy 345.679775 -282.808282) (xy 345.713979 -282.771125) (xy 345.753831 -282.740104) (xy 345.798246 -282.716065)
			(xy 345.846011 -282.699663) (xy 345.895825 -282.691347) (xy 345.921076 -282.690824) (xy 346.86113 -282.690824)
			(xy 346.886386 -282.691284) (xy 346.936209 -282.699603) (xy 346.983984 -282.716008) (xy 347.028407 -282.740052)
			(xy 347.068267 -282.77108) (xy 347.102477 -282.808245) (xy 347.130103 -282.850534) (xy 347.150393 -282.896792)
			(xy 347.162792 -282.94576) (xy 347.166963 -282.9961) (xy 348.435372 -282.9961) (xy 348.439544 -282.945758)
			(xy 348.451945 -282.89679) (xy 348.472238 -282.850531) (xy 348.499869 -282.808244) (xy 348.534083 -282.771081)
			(xy 348.573948 -282.740058) (xy 348.618376 -282.71602) (xy 348.666155 -282.699622) (xy 348.715981 -282.691314)
			(xy 348.741238 -282.690824) (xy 349.681292 -282.690824) (xy 349.706553 -282.691252) (xy 349.756386 -282.699567)
			(xy 349.80417 -282.71597) (xy 349.848603 -282.740015) (xy 349.888472 -282.771045) (xy 349.92269 -282.808215)
			(xy 349.950323 -282.850509) (xy 349.970617 -282.896775) (xy 349.98302 -282.945751) (xy 349.987192 -282.9961)
			(xy 351.255272 -282.9961) (xy 351.259444 -282.945758) (xy 351.271846 -282.896789) (xy 351.292139 -282.850529)
			(xy 351.319771 -282.808241) (xy 351.353986 -282.771079) (xy 351.393852 -282.740055) (xy 351.438281 -282.716017)
			(xy 351.486061 -282.699621) (xy 351.535888 -282.691313) (xy 351.561146 -282.690824) (xy 352.5012 -282.690824)
			(xy 352.526458 -282.691282) (xy 352.576285 -282.699596) (xy 352.624064 -282.715999) (xy 352.668491 -282.740042)
			(xy 352.708355 -282.771069) (xy 352.742569 -282.808235) (xy 352.770198 -282.850525) (xy 352.79049 -282.896786)
			(xy 352.802891 -282.945757) (xy 352.807063 -282.9961) (xy 354.075301 -282.9961) (xy 354.079471 -282.945772)
			(xy 354.091867 -282.896816) (xy 354.112151 -282.850569) (xy 354.13977 -282.80829) (xy 354.17397 -282.771133)
			(xy 354.213819 -282.740111) (xy 354.258231 -282.716071) (xy 354.305993 -282.699668) (xy 354.355804 -282.691349)
			(xy 354.381054 -282.690824) (xy 355.321108 -282.690824) (xy 355.346366 -282.691282) (xy 355.396191 -282.699598)
			(xy 355.443969 -282.716001) (xy 355.488395 -282.740045) (xy 355.528258 -282.771072) (xy 355.562471 -282.808238)
			(xy 355.5901 -282.850528) (xy 355.610391 -282.896788) (xy 355.622792 -282.945757) (xy 355.626963 -282.9961)
			(xy 364.409001 -282.9961) (xy 364.413172 -282.945768) (xy 364.425569 -282.896809) (xy 364.445856 -282.850559)
			(xy 364.473479 -282.808278) (xy 364.507684 -282.77112) (xy 364.547539 -282.740099) (xy 364.591955 -282.71606)
			(xy 364.639723 -282.69966) (xy 364.689538 -282.691346) (xy 364.71479 -282.690824) (xy 365.654844 -282.690824)
			(xy 365.6801 -282.691285) (xy 365.729921 -282.699605) (xy 365.777694 -282.716012) (xy 365.822115 -282.740057)
			(xy 365.861972 -282.771085) (xy 365.89618 -282.80825) (xy 365.923805 -282.850538) (xy 365.944094 -282.896795)
			(xy 365.956492 -282.945761) (xy 365.960663 -282.9961) (xy 367.228901 -282.9961) (xy 367.233072 -282.945767)
			(xy 367.24547 -282.896808) (xy 367.265758 -282.850556) (xy 367.293381 -282.808275) (xy 367.327587 -282.771117)
			(xy 367.367443 -282.740096) (xy 367.411861 -282.716058) (xy 367.459629 -282.699659) (xy 367.509445 -282.691346)
			(xy 367.534698 -282.690824) (xy 368.474752 -282.690824) (xy 368.500015 -282.691249) (xy 368.549853 -282.699558)
			(xy 368.597643 -282.715958) (xy 368.642082 -282.740001) (xy 368.681956 -282.771031) (xy 368.716179 -282.808201)
			(xy 368.743817 -282.850498) (xy 368.764115 -282.896767) (xy 368.776519 -282.945747) (xy 368.780692 -282.9961)
			(xy 370.049101 -282.9961) (xy 370.053271 -282.945771) (xy 370.065667 -282.896815) (xy 370.085952 -282.850567)
			(xy 370.113571 -282.808288) (xy 370.147772 -282.771131) (xy 370.187623 -282.740109) (xy 370.232035 -282.716069)
			(xy 370.279798 -282.699667) (xy 370.329609 -282.691349) (xy 370.35486 -282.690824) (xy 371.294914 -282.690824)
			(xy 371.320171 -282.691283) (xy 371.369996 -282.699599) (xy 371.417773 -282.716003) (xy 371.462199 -282.740047)
			(xy 371.502061 -282.771074) (xy 371.536273 -282.80824) (xy 371.563901 -282.850529) (xy 371.584191 -282.896789)
			(xy 371.596592 -282.945758) (xy 371.600763 -282.9961) (xy 372.869001 -282.9961) (xy 372.873171 -282.94577)
			(xy 372.885568 -282.896814) (xy 372.905853 -282.850565) (xy 372.933473 -282.808285) (xy 372.967676 -282.771128)
			(xy 373.007527 -282.740106) (xy 373.05194 -282.716067) (xy 373.099705 -282.699665) (xy 373.149517 -282.691348)
			(xy 373.174768 -282.690824) (xy 374.114822 -282.690824) (xy 374.140079 -282.691283) (xy 374.189903 -282.699601)
			(xy 374.237679 -282.716005) (xy 374.282103 -282.740049) (xy 374.321964 -282.771077) (xy 374.356175 -282.808242)
			(xy 374.383802 -282.850531) (xy 374.404092 -282.896791) (xy 374.416492 -282.945759) (xy 374.420663 -282.9961)
			(xy 374.416492 -283.046441) (xy 374.404092 -283.095409) (xy 374.383802 -283.141669) (xy 374.356175 -283.183958)
			(xy 374.321964 -283.221123) (xy 374.282103 -283.252151) (xy 374.237679 -283.276195) (xy 374.189903 -283.292599)
			(xy 374.140079 -283.300917) (xy 374.114822 -283.30144) (xy 373.174768 -283.30144) (xy 373.149517 -283.300852)
			(xy 373.099705 -283.292535) (xy 373.05194 -283.276133) (xy 373.007527 -283.252094) (xy 372.967676 -283.221072)
			(xy 372.933473 -283.183915) (xy 372.905853 -283.141635) (xy 372.885568 -283.095386) (xy 372.873171 -283.04643)
			(xy 372.869001 -282.9961) (xy 371.600763 -282.9961) (xy 371.596592 -283.046442) (xy 371.584191 -283.095411)
			(xy 371.563901 -283.141671) (xy 371.536273 -283.18396) (xy 371.502061 -283.221126) (xy 371.462199 -283.252153)
			(xy 371.417773 -283.276197) (xy 371.369996 -283.292601) (xy 371.320171 -283.300917) (xy 371.294914 -283.30144)
			(xy 370.35486 -283.30144) (xy 370.329609 -283.300851) (xy 370.279798 -283.292533) (xy 370.232035 -283.276131)
			(xy 370.187623 -283.252091) (xy 370.147772 -283.221069) (xy 370.113571 -283.183912) (xy 370.085952 -283.141633)
			(xy 370.065667 -283.095385) (xy 370.053271 -283.046429) (xy 370.049101 -282.9961) (xy 368.780692 -282.9961)
			(xy 368.776519 -283.046453) (xy 368.764115 -283.095433) (xy 368.743817 -283.141702) (xy 368.716179 -283.183999)
			(xy 368.681956 -283.221169) (xy 368.642082 -283.252199) (xy 368.597643 -283.276242) (xy 368.549853 -283.292642)
			(xy 368.500015 -283.300951) (xy 368.474752 -283.30144) (xy 367.534698 -283.30144) (xy 367.509445 -283.300854)
			(xy 367.459629 -283.292541) (xy 367.411861 -283.276142) (xy 367.367443 -283.252104) (xy 367.327587 -283.221083)
			(xy 367.293381 -283.183925) (xy 367.265758 -283.141644) (xy 367.24547 -283.095392) (xy 367.233072 -283.046433)
			(xy 367.228901 -282.9961) (xy 365.960663 -282.9961) (xy 365.956492 -283.046439) (xy 365.944094 -283.095405)
			(xy 365.923805 -283.141662) (xy 365.89618 -283.18395) (xy 365.861972 -283.221115) (xy 365.822115 -283.252143)
			(xy 365.777694 -283.276188) (xy 365.729921 -283.292595) (xy 365.6801 -283.300915) (xy 365.654844 -283.30144)
			(xy 364.71479 -283.30144) (xy 364.689538 -283.300854) (xy 364.639723 -283.29254) (xy 364.591955 -283.27614)
			(xy 364.547539 -283.252101) (xy 364.507684 -283.22108) (xy 364.473479 -283.183922) (xy 364.445856 -283.141641)
			(xy 364.425569 -283.095391) (xy 364.413172 -283.046432) (xy 364.409001 -282.9961) (xy 355.626963 -282.9961)
			(xy 355.622792 -283.046443) (xy 355.610391 -283.095412) (xy 355.5901 -283.141672) (xy 355.562471 -283.183962)
			(xy 355.528258 -283.221128) (xy 355.488395 -283.252155) (xy 355.443969 -283.276199) (xy 355.396191 -283.292602)
			(xy 355.346366 -283.300918) (xy 355.321108 -283.30144) (xy 354.381054 -283.30144) (xy 354.355804 -283.300851)
			(xy 354.305993 -283.292532) (xy 354.258231 -283.276129) (xy 354.213819 -283.252089) (xy 354.17397 -283.221067)
			(xy 354.13977 -283.18391) (xy 354.112151 -283.141631) (xy 354.091867 -283.095384) (xy 354.079471 -283.046428)
			(xy 354.075301 -282.9961) (xy 352.807063 -282.9961) (xy 352.802891 -283.046443) (xy 352.79049 -283.095414)
			(xy 352.770198 -283.141675) (xy 352.742569 -283.183965) (xy 352.708355 -283.221131) (xy 352.668491 -283.252158)
			(xy 352.624064 -283.276201) (xy 352.576285 -283.292604) (xy 352.526458 -283.300918) (xy 352.5012 -283.30144)
			(xy 351.561146 -283.30144) (xy 351.535888 -283.300887) (xy 351.486061 -283.292579) (xy 351.438281 -283.276183)
			(xy 351.393852 -283.252145) (xy 351.353986 -283.221121) (xy 351.319771 -283.183959) (xy 351.292139 -283.141671)
			(xy 351.271846 -283.095411) (xy 351.259444 -283.046442) (xy 351.255272 -282.9961) (xy 349.987192 -282.9961)
			(xy 349.98302 -283.046449) (xy 349.970617 -283.095425) (xy 349.950323 -283.141691) (xy 349.92269 -283.183985)
			(xy 349.888472 -283.221155) (xy 349.848603 -283.252185) (xy 349.80417 -283.27623) (xy 349.756386 -283.292633)
			(xy 349.706553 -283.300948) (xy 349.681292 -283.30144) (xy 348.741238 -283.30144) (xy 348.715981 -283.300886)
			(xy 348.666155 -283.292578) (xy 348.618376 -283.27618) (xy 348.573948 -283.252142) (xy 348.534083 -283.221119)
			(xy 348.499869 -283.183956) (xy 348.472238 -283.141669) (xy 348.451945 -283.09541) (xy 348.439544 -283.046442)
			(xy 348.435372 -282.9961) (xy 347.166963 -282.9961) (xy 347.162792 -283.04644) (xy 347.150393 -283.095408)
			(xy 347.130103 -283.141666) (xy 347.102477 -283.183955) (xy 347.068267 -283.22112) (xy 347.028407 -283.252148)
			(xy 346.983984 -283.276192) (xy 346.936209 -283.292597) (xy 346.886386 -283.300916) (xy 346.86113 -283.30144)
			(xy 345.921076 -283.30144) (xy 345.895825 -283.300853) (xy 345.846011 -283.292537) (xy 345.798246 -283.276135)
			(xy 345.753831 -283.252096) (xy 345.713979 -283.221075) (xy 345.679775 -283.183918) (xy 345.652154 -283.141638)
			(xy 345.631868 -283.095388) (xy 345.619471 -283.04643) (xy 345.615301 -282.9961) (xy 126.480876 -282.9961)
			(xy 126.480901 -282.9964) (xy 126.476725 -283.046787) (xy 126.464312 -283.0958) (xy 126.444 -283.142101)
			(xy 126.416344 -283.184426) (xy 126.382098 -283.221622) (xy 126.342197 -283.252673) (xy 126.297728 -283.276732)
			(xy 126.249906 -283.293143) (xy 126.200034 -283.301459) (xy 126.174754 -283.301948) (xy 125.2347 -283.301948)
			(xy 125.209423 -283.301454) (xy 125.159557 -283.293133) (xy 125.111741 -283.276718) (xy 125.067279 -283.252656)
			(xy 125.027384 -283.221605) (xy 124.993144 -283.18441) (xy 124.965494 -283.142087) (xy 124.945186 -283.09579)
			(xy 124.932775 -283.046782) (xy 124.928601 -282.9964) (xy 123.660872 -282.9964) (xy 123.656698 -283.046773)
			(xy 123.644291 -283.095772) (xy 123.623989 -283.142061) (xy 123.596345 -283.184378) (xy 123.562114 -283.221568)
			(xy 123.52223 -283.252617) (xy 123.477779 -283.276678) (xy 123.429974 -283.293096) (xy 123.380119 -283.301423)
			(xy 123.354846 -283.301948) (xy 122.414792 -283.301948) (xy 122.389515 -283.301453) (xy 122.33965 -283.293131)
			(xy 122.291836 -283.276715) (xy 122.247375 -283.252653) (xy 122.207481 -283.221602) (xy 122.173242 -283.184408)
			(xy 122.145592 -283.142085) (xy 122.125285 -283.095789) (xy 122.112875 -283.046781) (xy 122.1087 -282.9964)
			(xy 120.840801 -282.9964) (xy 120.836625 -283.046784) (xy 120.824214 -283.095794) (xy 120.803905 -283.142092)
			(xy 120.776252 -283.184416) (xy 120.74201 -283.221611) (xy 120.702113 -283.252663) (xy 120.657648 -283.276723)
			(xy 120.60983 -283.293137) (xy 120.559962 -283.301456) (xy 120.534684 -283.301948) (xy 119.59463 -283.301948)
			(xy 119.569348 -283.301485) (xy 119.519474 -283.293167) (xy 119.47165 -283.276753) (xy 119.427179 -283.252691)
			(xy 119.387276 -283.221637) (xy 119.353029 -283.184438) (xy 119.325373 -283.142109) (xy 119.30506 -283.095806)
			(xy 119.292647 -283.04679) (xy 119.288471 -282.9964) (xy 118.020901 -282.9964) (xy 118.016725 -283.046785)
			(xy 118.004313 -283.095795) (xy 117.984004 -283.142094) (xy 117.95635 -283.184419) (xy 117.922107 -283.221614)
			(xy 117.882208 -283.252665) (xy 117.837743 -283.276726) (xy 117.789924 -283.293139) (xy 117.740055 -283.301457)
			(xy 117.714776 -283.301948) (xy 116.774722 -283.301948) (xy 116.749441 -283.301485) (xy 116.699568 -283.293166)
			(xy 116.651744 -283.276751) (xy 116.607275 -283.252688) (xy 116.567373 -283.221634) (xy 116.533127 -283.184435)
			(xy 116.505471 -283.142107) (xy 116.48516 -283.095804) (xy 116.472747 -283.046789) (xy 116.468571 -282.9964)
			(xy 107.687072 -282.9964) (xy 107.682898 -283.046774) (xy 107.67049 -283.095773) (xy 107.650188 -283.142063)
			(xy 107.622544 -283.18438) (xy 107.588312 -283.22157) (xy 107.548426 -283.252619) (xy 107.503975 -283.27668)
			(xy 107.456169 -283.293098) (xy 107.406313 -283.301423) (xy 107.38104 -283.301948) (xy 106.440986 -283.301948)
			(xy 106.415709 -283.301453) (xy 106.365846 -283.29313) (xy 106.318032 -283.276714) (xy 106.273572 -283.252651)
			(xy 106.233679 -283.2216) (xy 106.199441 -283.184406) (xy 106.171791 -283.142083) (xy 106.151485 -283.095788)
			(xy 106.139075 -283.046781) (xy 106.1349 -282.9964) (xy 104.867172 -282.9964) (xy 104.862998 -283.046774)
			(xy 104.85059 -283.095775) (xy 104.830287 -283.142065) (xy 104.802642 -283.184382) (xy 104.768409 -283.221573)
			(xy 104.728522 -283.252622) (xy 104.684069 -283.276683) (xy 104.636262 -283.293099) (xy 104.586405 -283.301424)
			(xy 104.561132 -283.301948) (xy 103.621078 -283.301948) (xy 103.595802 -283.301452) (xy 103.545939 -283.293128)
			(xy 103.498126 -283.276711) (xy 103.453668 -283.252649) (xy 103.413776 -283.221597) (xy 103.379539 -283.184403)
			(xy 103.35189 -283.142081) (xy 103.331584 -283.095786) (xy 103.319175 -283.04678) (xy 103.315 -282.9964)
			(xy 102.047272 -282.9964) (xy 102.043098 -283.046775) (xy 102.030689 -283.095776) (xy 102.010385 -283.142067)
			(xy 101.98274 -283.184385) (xy 101.948506 -283.221576) (xy 101.908618 -283.252624) (xy 101.864164 -283.276685)
			(xy 101.816356 -283.293101) (xy 101.766498 -283.301424) (xy 101.741224 -283.301948) (xy 100.80117 -283.301948)
			(xy 100.775894 -283.301452) (xy 100.726032 -283.293127) (xy 100.678221 -283.276709) (xy 100.633764 -283.252646)
			(xy 100.593873 -283.221594) (xy 100.559637 -283.1844) (xy 100.531989 -283.142079) (xy 100.511684 -283.095784)
			(xy 100.499275 -283.046779) (xy 100.4951 -282.9964) (xy 99.227201 -282.9964) (xy 99.223025 -283.046786)
			(xy 99.210613 -283.095798) (xy 99.190302 -283.142098) (xy 99.162646 -283.184423) (xy 99.128401 -283.221619)
			(xy 99.088501 -283.25267) (xy 99.044033 -283.27673) (xy 98.996212 -283.293142) (xy 98.946342 -283.301458)
			(xy 98.921062 -283.301948) (xy 97.981008 -283.301948) (xy 97.955728 -283.301484) (xy 97.905856 -283.293163)
			(xy 97.858035 -283.276747) (xy 97.813568 -283.252683) (xy 97.773668 -283.221629) (xy 97.739424 -283.184431)
			(xy 97.711769 -283.142103) (xy 97.691459 -283.095801) (xy 97.679047 -283.046788) (xy 97.674871 -282.9964)
			(xy 2.509012 -282.9964) (xy 2.509012 -283.8064) (xy 108.485161 -283.8064) (xy 108.489332 -283.756061)
			(xy 108.501732 -283.707095) (xy 108.522022 -283.660838) (xy 108.549649 -283.618552) (xy 108.583859 -283.581389)
			(xy 108.623719 -283.550364) (xy 108.668142 -283.526323) (xy 108.715916 -283.509921) (xy 108.765738 -283.501606)
			(xy 108.790994 -283.501084) (xy 109.731048 -283.501084) (xy 109.7563 -283.501625) (xy 109.806114 -283.509945)
			(xy 109.85388 -283.52635) (xy 109.898295 -283.550392) (xy 109.938147 -283.581416) (xy 109.97235 -283.618576)
			(xy 109.999971 -283.660858) (xy 110.020256 -283.707109) (xy 110.032653 -283.756068) (xy 110.036823 -283.8064)
			(xy 114.118832 -283.8064) (xy 114.123004 -283.756054) (xy 114.135406 -283.707082) (xy 114.155699 -283.660819)
			(xy 114.183331 -283.618527) (xy 114.217547 -283.581361) (xy 114.257413 -283.550333) (xy 114.301844 -283.52629)
			(xy 114.349625 -283.509889) (xy 114.399455 -283.501576) (xy 114.424714 -283.501084) (xy 115.364768 -283.501084)
			(xy 115.390027 -283.50159) (xy 115.439856 -283.5099) (xy 115.487638 -283.526299) (xy 115.532068 -283.55034)
			(xy 115.571936 -283.581366) (xy 115.606152 -283.618531) (xy 115.633784 -283.660822) (xy 115.654078 -283.707084)
			(xy 115.66648 -283.756055) (xy 115.670627 -283.8061) (xy 356.425052 -283.8061) (xy 356.429226 -283.75573)
			(xy 356.441632 -283.706734) (xy 356.461934 -283.660448) (xy 356.489576 -283.618134) (xy 356.523805 -283.580947)
			(xy 356.563688 -283.5499) (xy 356.608136 -283.525841) (xy 356.655939 -283.509425) (xy 356.705791 -283.501101)
			(xy 356.731062 -283.500576) (xy 357.671116 -283.500576) (xy 357.696395 -283.501023) (xy 357.746262 -283.509347)
			(xy 357.794079 -283.525765) (xy 357.838542 -283.549829) (xy 357.878438 -283.580883) (xy 357.912679 -283.61808)
			(xy 357.94033 -283.660406) (xy 357.960638 -283.706705) (xy 357.973049 -283.755715) (xy 357.977224 -283.8061)
			(xy 362.058752 -283.8061) (xy 362.062926 -283.755728) (xy 362.075334 -283.70673) (xy 362.095637 -283.660442)
			(xy 362.123281 -283.618128) (xy 362.157513 -283.58094) (xy 362.197398 -283.549894) (xy 362.24185 -283.525835)
			(xy 362.289655 -283.509421) (xy 362.33951 -283.501099) (xy 362.364782 -283.500576) (xy 363.304836 -283.500576)
			(xy 363.330114 -283.501025) (xy 363.379978 -283.509351) (xy 363.427793 -283.525771) (xy 363.472253 -283.549836)
			(xy 363.512146 -283.58089) (xy 363.546384 -283.618087) (xy 363.574033 -283.660411) (xy 363.594339 -283.706709)
			(xy 363.606749 -283.755717) (xy 363.610924 -283.8061) (xy 363.606749 -283.856483) (xy 363.594339 -283.905491)
			(xy 363.574033 -283.951789) (xy 363.546384 -283.994113) (xy 363.512146 -284.03131) (xy 363.472253 -284.062364)
			(xy 363.427793 -284.086429) (xy 363.379978 -284.102849) (xy 363.330114 -284.111175) (xy 363.304836 -284.1117)
			(xy 362.364782 -284.1117) (xy 362.33951 -284.111101) (xy 362.289655 -284.102779) (xy 362.24185 -284.086365)
			(xy 362.197398 -284.062306) (xy 362.157513 -284.03126) (xy 362.123281 -283.994072) (xy 362.095637 -283.951758)
			(xy 362.075334 -283.90547) (xy 362.062926 -283.856472) (xy 362.058752 -283.8061) (xy 357.977224 -283.8061)
			(xy 357.973049 -283.856485) (xy 357.960638 -283.905495) (xy 357.94033 -283.951794) (xy 357.912679 -283.99412)
			(xy 357.878438 -284.031317) (xy 357.838542 -284.062371) (xy 357.794079 -284.086435) (xy 357.746262 -284.102853)
			(xy 357.696395 -284.111177) (xy 357.671116 -284.1117) (xy 356.731062 -284.1117) (xy 356.705791 -284.111099)
			(xy 356.655939 -284.102775) (xy 356.608136 -284.086359) (xy 356.563688 -284.0623) (xy 356.523805 -284.031253)
			(xy 356.489576 -283.994066) (xy 356.461934 -283.951752) (xy 356.441632 -283.905466) (xy 356.429226 -283.85647)
			(xy 356.425052 -283.8061) (xy 115.670627 -283.8061) (xy 115.670652 -283.8064) (xy 115.66648 -283.856745)
			(xy 115.654078 -283.905716) (xy 115.633784 -283.951978) (xy 115.606152 -283.994269) (xy 115.571936 -284.031434)
			(xy 115.532068 -284.06246) (xy 115.487638 -284.086501) (xy 115.439856 -284.1029) (xy 115.390027 -284.11121)
			(xy 115.364768 -284.1117) (xy 114.424714 -284.1117) (xy 114.399455 -284.111224) (xy 114.349625 -284.102911)
			(xy 114.301844 -284.08651) (xy 114.257413 -284.062467) (xy 114.217547 -284.031439) (xy 114.183331 -283.994273)
			(xy 114.155699 -283.951981) (xy 114.135406 -283.905718) (xy 114.123004 -283.856746) (xy 114.118832 -283.8064)
			(xy 110.036823 -283.8064) (xy 110.032653 -283.856732) (xy 110.020256 -283.905691) (xy 109.999971 -283.951942)
			(xy 109.97235 -283.994224) (xy 109.938147 -284.031384) (xy 109.898295 -284.062408) (xy 109.85388 -284.08645)
			(xy 109.806114 -284.102855) (xy 109.7563 -284.111175) (xy 109.731048 -284.1117) (xy 108.790994 -284.1117)
			(xy 108.765738 -284.111194) (xy 108.715916 -284.102879) (xy 108.668142 -284.086477) (xy 108.623719 -284.062436)
			(xy 108.583859 -284.031411) (xy 108.549649 -283.994248) (xy 108.522022 -283.951962) (xy 108.501732 -283.905705)
			(xy 108.489332 -283.856739) (xy 108.485161 -283.8064) (xy 2.509012 -283.8064) (xy 2.509012 -284.6164)
			(xy 97.674883 -284.6164) (xy 97.679059 -284.566014) (xy 97.69147 -284.517003) (xy 97.71178 -284.470702)
			(xy 97.739433 -284.428377) (xy 97.773676 -284.39118) (xy 97.813574 -284.360127) (xy 97.85804 -284.336064)
			(xy 97.905859 -284.319649) (xy 97.955729 -284.311328) (xy 97.981008 -284.310836) (xy 98.921062 -284.310836)
			(xy 98.946343 -284.31133) (xy 98.996215 -284.319647) (xy 99.044038 -284.336059) (xy 99.088508 -284.36012)
			(xy 99.12841 -284.391172) (xy 99.162656 -284.428369) (xy 99.190312 -284.470696) (xy 99.210624 -284.516998)
			(xy 99.223037 -284.566012) (xy 99.227213 -284.6164) (xy 100.495112 -284.6164) (xy 100.499287 -284.566023)
			(xy 100.511695 -284.51702) (xy 100.532 -284.470727) (xy 100.559646 -284.428407) (xy 100.593881 -284.391215)
			(xy 100.63377 -284.360164) (xy 100.678226 -284.336102) (xy 100.726035 -284.319685) (xy 100.775895 -284.31136)
			(xy 100.80117 -284.310836) (xy 101.741224 -284.310836) (xy 101.766499 -284.311364) (xy 101.816359 -284.319688)
			(xy 101.864169 -284.336104) (xy 101.908625 -284.360165) (xy 101.948514 -284.391216) (xy 101.982749 -284.428408)
			(xy 102.010396 -284.470727) (xy 102.030701 -284.51702) (xy 102.043109 -284.566023) (xy 102.047284 -284.6164)
			(xy 103.315012 -284.6164) (xy 103.319187 -284.566022) (xy 103.331596 -284.517018) (xy 103.351901 -284.470725)
			(xy 103.379548 -284.428404) (xy 103.413784 -284.391212) (xy 103.453674 -284.360161) (xy 103.498131 -284.3361)
			(xy 103.545942 -284.319683) (xy 103.595803 -284.31136) (xy 103.621078 -284.310836) (xy 104.561132 -284.310836)
			(xy 104.586406 -284.311364) (xy 104.636265 -284.319689) (xy 104.684074 -284.336106) (xy 104.728529 -284.360168)
			(xy 104.768417 -284.391218) (xy 104.802651 -284.42841) (xy 104.830297 -284.470729) (xy 104.850601 -284.517021)
			(xy 104.863009 -284.566024) (xy 104.867184 -284.6164) (xy 106.134912 -284.6164) (xy 106.139087 -284.566021)
			(xy 106.151496 -284.517016) (xy 106.171802 -284.470722) (xy 106.19945 -284.428402) (xy 106.233687 -284.391209)
			(xy 106.273579 -284.360159) (xy 106.318037 -284.336097) (xy 106.365849 -284.319682) (xy 106.41571 -284.311359)
			(xy 106.440986 -284.310836) (xy 107.38104 -284.310836) (xy 107.406314 -284.311365) (xy 107.456172 -284.319691)
			(xy 107.503979 -284.336109) (xy 107.548433 -284.360171) (xy 107.58832 -284.391221) (xy 107.622553 -284.428413)
			(xy 107.650198 -284.470731) (xy 107.670502 -284.517023) (xy 107.68291 -284.566024) (xy 107.687084 -284.6164)
			(xy 116.468583 -284.6164) (xy 116.472759 -284.566013) (xy 116.485171 -284.517) (xy 116.505482 -284.470699)
			(xy 116.533137 -284.428372) (xy 116.567381 -284.391175) (xy 116.607282 -284.360122) (xy 116.651749 -284.33606)
			(xy 116.699571 -284.319646) (xy 116.749442 -284.311327) (xy 116.774722 -284.310836) (xy 117.714776 -284.310836)
			(xy 117.740056 -284.311331) (xy 117.789927 -284.319649) (xy 117.837748 -284.336063) (xy 117.882215 -284.360125)
			(xy 117.922115 -284.391177) (xy 117.95636 -284.428374) (xy 117.984014 -284.4707) (xy 118.004325 -284.517001)
			(xy 118.016737 -284.566013) (xy 118.020913 -284.6164) (xy 119.288483 -284.6164) (xy 119.292659 -284.566012)
			(xy 119.305072 -284.516998) (xy 119.325383 -284.470696) (xy 119.353039 -284.428369) (xy 119.387285 -284.391172)
			(xy 119.427186 -284.360119) (xy 119.471655 -284.336058) (xy 119.519477 -284.319644) (xy 119.569349 -284.311327)
			(xy 119.59463 -284.310836) (xy 120.534684 -284.310836) (xy 120.559963 -284.311332) (xy 120.609833 -284.319651)
			(xy 120.657653 -284.336066) (xy 120.702119 -284.360127) (xy 120.742018 -284.39118) (xy 120.776262 -284.428376)
			(xy 120.803915 -284.470702) (xy 120.824225 -284.517002) (xy 120.836637 -284.566014) (xy 120.840813 -284.6164)
			(xy 122.108712 -284.6164) (xy 122.112887 -284.56602) (xy 122.125297 -284.517015) (xy 122.145603 -284.470721)
			(xy 122.173252 -284.4284) (xy 122.207489 -284.391207) (xy 122.247382 -284.360157) (xy 122.291841 -284.336096)
			(xy 122.339653 -284.31968) (xy 122.389516 -284.311359) (xy 122.414792 -284.310836) (xy 123.354846 -284.310836)
			(xy 123.38012 -284.311366) (xy 123.429977 -284.319692) (xy 123.477783 -284.336111) (xy 123.522236 -284.360173)
			(xy 123.562123 -284.391223) (xy 123.596355 -284.428415) (xy 123.623999 -284.470733) (xy 123.644302 -284.517024)
			(xy 123.65671 -284.566025) (xy 123.660884 -284.6164) (xy 124.928613 -284.6164) (xy 124.932787 -284.56602)
			(xy 124.945197 -284.517014) (xy 124.965504 -284.470718) (xy 124.993154 -284.428397) (xy 125.027393 -284.391204)
			(xy 125.067286 -284.360154) (xy 125.111746 -284.336093) (xy 125.15956 -284.319679) (xy 125.209423 -284.311358)
			(xy 125.2347 -284.310836) (xy 126.174754 -284.310836) (xy 126.200035 -284.311329) (xy 126.249909 -284.319645)
			(xy 126.297733 -284.336057) (xy 126.342203 -284.360117) (xy 126.382107 -284.391169) (xy 126.416354 -284.428366)
			(xy 126.444011 -284.470694) (xy 126.464323 -284.516996) (xy 126.476737 -284.566011) (xy 126.480888 -284.6161)
			(xy 345.615313 -284.6161) (xy 345.619483 -284.565772) (xy 345.63188 -284.516816) (xy 345.652165 -284.470568)
			(xy 345.679785 -284.42829) (xy 345.713987 -284.391134) (xy 345.753838 -284.360114) (xy 345.798251 -284.336076)
			(xy 345.846014 -284.319675) (xy 345.895826 -284.311359) (xy 345.921076 -284.310836) (xy 346.86113 -284.310836)
			(xy 346.886387 -284.311272) (xy 346.936213 -284.31959) (xy 346.983989 -284.335996) (xy 347.028414 -284.360042)
			(xy 347.068275 -284.391071) (xy 347.102487 -284.428237) (xy 347.130114 -284.470528) (xy 347.150404 -284.516788)
			(xy 347.162804 -284.565758) (xy 347.166976 -284.6161) (xy 348.435384 -284.6161) (xy 348.439556 -284.56576)
			(xy 348.451957 -284.516794) (xy 348.472249 -284.470537) (xy 348.499878 -284.428251) (xy 348.534091 -284.39109)
			(xy 348.573955 -284.360068) (xy 348.618381 -284.336031) (xy 348.666158 -284.319634) (xy 348.715982 -284.311326)
			(xy 348.741238 -284.310836) (xy 349.681292 -284.310836) (xy 349.706554 -284.31124) (xy 349.756388 -284.319555)
			(xy 349.804175 -284.335959) (xy 349.848609 -284.360005) (xy 349.88848 -284.391036) (xy 349.922699 -284.428207)
			(xy 349.950333 -284.470504) (xy 349.970629 -284.516772) (xy 349.983032 -284.565749) (xy 349.987204 -284.6161)
			(xy 351.255284 -284.6161) (xy 351.259456 -284.56576) (xy 351.271857 -284.516793) (xy 351.29215 -284.470535)
			(xy 351.31978 -284.428249) (xy 351.353994 -284.391087) (xy 351.393859 -284.360065) (xy 351.438286 -284.336028)
			(xy 351.486064 -284.319632) (xy 351.535889 -284.311325) (xy 351.561146 -284.310836) (xy 352.5012 -284.310836)
			(xy 352.526459 -284.311269) (xy 352.576288 -284.319584) (xy 352.624069 -284.335987) (xy 352.668498 -284.360031)
			(xy 352.708364 -284.39106) (xy 352.742579 -284.428227) (xy 352.770209 -284.470519) (xy 352.790502 -284.516782)
			(xy 352.802904 -284.565755) (xy 352.807076 -284.6161) (xy 354.075313 -284.6161) (xy 354.079483 -284.565774)
			(xy 354.091878 -284.51682) (xy 354.112161 -284.470574) (xy 354.139779 -284.428297) (xy 354.173978 -284.391142)
			(xy 354.213826 -284.360121) (xy 354.258236 -284.336082) (xy 354.305996 -284.31968) (xy 354.355805 -284.311361)
			(xy 354.381054 -284.310836) (xy 355.321108 -284.310836) (xy 355.346367 -284.31127) (xy 355.396195 -284.319586)
			(xy 355.443974 -284.33599) (xy 355.488402 -284.360034) (xy 355.528267 -284.391063) (xy 355.562481 -284.42823)
			(xy 355.590111 -284.470522) (xy 355.610403 -284.516784) (xy 355.622804 -284.565755) (xy 355.626976 -284.6161)
			(xy 364.409013 -284.6161) (xy 364.413183 -284.56577) (xy 364.425581 -284.516813) (xy 364.445867 -284.470564)
			(xy 364.473488 -284.428285) (xy 364.507692 -284.391129) (xy 364.547545 -284.360109) (xy 364.59196 -284.336071)
			(xy 364.639726 -284.319672) (xy 364.689539 -284.311358) (xy 364.71479 -284.310836) (xy 365.654844 -284.310836)
			(xy 365.680101 -284.311273) (xy 365.729924 -284.319593) (xy 365.777699 -284.336) (xy 365.822121 -284.360047)
			(xy 365.861981 -284.391076) (xy 365.89619 -284.428242) (xy 365.923816 -284.470532) (xy 365.944105 -284.516791)
			(xy 365.956505 -284.565759) (xy 365.960676 -284.6161) (xy 367.228913 -284.6161) (xy 367.233084 -284.565769)
			(xy 367.245481 -284.516812) (xy 367.265768 -284.470562) (xy 367.293391 -284.428282) (xy 367.327595 -284.391126)
			(xy 367.367449 -284.360106) (xy 367.411865 -284.336069) (xy 367.459632 -284.31967) (xy 367.509446 -284.311358)
			(xy 367.534698 -284.310836) (xy 368.474752 -284.310836) (xy 368.500016 -284.311237) (xy 368.549856 -284.319547)
			(xy 368.597648 -284.335947) (xy 368.642088 -284.359991) (xy 368.681965 -284.391022) (xy 368.716189 -284.428194)
			(xy 368.743827 -284.470492) (xy 368.764126 -284.516764) (xy 368.776531 -284.565745) (xy 368.780704 -284.6161)
			(xy 370.049113 -284.6161) (xy 370.053283 -284.565773) (xy 370.065679 -284.516819) (xy 370.085962 -284.470573)
			(xy 370.113581 -284.428295) (xy 370.147781 -284.391139) (xy 370.187629 -284.360119) (xy 370.23204 -284.33608)
			(xy 370.279801 -284.319678) (xy 370.32961 -284.311361) (xy 370.35486 -284.310836) (xy 371.294914 -284.310836)
			(xy 371.320172 -284.31127) (xy 371.369999 -284.319587) (xy 371.417778 -284.335992) (xy 371.462205 -284.360036)
			(xy 371.502069 -284.391065) (xy 371.536282 -284.428232) (xy 371.563912 -284.470523) (xy 371.584203 -284.516785)
			(xy 371.596604 -284.565756) (xy 371.600776 -284.6161) (xy 372.869013 -284.6161) (xy 372.873183 -284.565772)
			(xy 372.885579 -284.516818) (xy 372.905864 -284.47057) (xy 372.933483 -284.428292) (xy 372.967684 -284.391137)
			(xy 373.007533 -284.360116) (xy 373.051945 -284.336078) (xy 373.099708 -284.319677) (xy 373.149518 -284.31136)
			(xy 373.174768 -284.310836) (xy 374.114822 -284.310836) (xy 374.14008 -284.311271) (xy 374.189906 -284.319589)
			(xy 374.237684 -284.335994) (xy 374.28211 -284.360039) (xy 374.321972 -284.391068) (xy 374.356184 -284.428235)
			(xy 374.383813 -284.470525) (xy 374.404104 -284.516787) (xy 374.416504 -284.565757) (xy 374.420676 -284.6161)
			(xy 374.416504 -284.666443) (xy 374.404104 -284.715413) (xy 374.383813 -284.761675) (xy 374.356184 -284.803965)
			(xy 374.321972 -284.841132) (xy 374.28211 -284.872161) (xy 374.237684 -284.896206) (xy 374.189906 -284.912611)
			(xy 374.14008 -284.920929) (xy 374.114822 -284.921452) (xy 373.174768 -284.921452) (xy 373.149518 -284.92084)
			(xy 373.099708 -284.912523) (xy 373.051945 -284.896122) (xy 373.007533 -284.872084) (xy 372.967684 -284.841063)
			(xy 372.933483 -284.803908) (xy 372.905864 -284.76163) (xy 372.885579 -284.715382) (xy 372.873183 -284.666428)
			(xy 372.869013 -284.6161) (xy 371.600776 -284.6161) (xy 371.596604 -284.666444) (xy 371.584203 -284.715415)
			(xy 371.563912 -284.761677) (xy 371.536282 -284.803968) (xy 371.502069 -284.841135) (xy 371.462205 -284.872164)
			(xy 371.417778 -284.896208) (xy 371.369999 -284.912613) (xy 371.320172 -284.92093) (xy 371.294914 -284.921452)
			(xy 370.35486 -284.921452) (xy 370.32961 -284.920839) (xy 370.279801 -284.912522) (xy 370.23204 -284.89612)
			(xy 370.187629 -284.872081) (xy 370.147781 -284.841061) (xy 370.113581 -284.803905) (xy 370.085962 -284.761627)
			(xy 370.065679 -284.715381) (xy 370.053283 -284.666427) (xy 370.049113 -284.6161) (xy 368.780704 -284.6161)
			(xy 368.776531 -284.666455) (xy 368.764126 -284.715436) (xy 368.743827 -284.761708) (xy 368.716189 -284.804006)
			(xy 368.681965 -284.841178) (xy 368.642088 -284.872209) (xy 368.597648 -284.896253) (xy 368.549856 -284.912653)
			(xy 368.500016 -284.920963) (xy 368.474752 -284.921452) (xy 367.534698 -284.921452) (xy 367.509446 -284.920842)
			(xy 367.459632 -284.91253) (xy 367.411865 -284.896131) (xy 367.367449 -284.872094) (xy 367.327595 -284.841074)
			(xy 367.293391 -284.803918) (xy 367.265768 -284.761638) (xy 367.245481 -284.715388) (xy 367.233084 -284.666431)
			(xy 367.228913 -284.6161) (xy 365.960676 -284.6161) (xy 365.956505 -284.666441) (xy 365.944105 -284.715409)
			(xy 365.923816 -284.761668) (xy 365.89619 -284.803958) (xy 365.861981 -284.841124) (xy 365.822121 -284.872153)
			(xy 365.777699 -284.8962) (xy 365.729924 -284.912607) (xy 365.680101 -284.920927) (xy 365.654844 -284.921452)
			(xy 364.71479 -284.921452) (xy 364.689539 -284.920842) (xy 364.639726 -284.912528) (xy 364.59196 -284.896129)
			(xy 364.547545 -284.872091) (xy 364.507692 -284.841071) (xy 364.473489 -284.803915) (xy 364.445867 -284.761636)
			(xy 364.425581 -284.715387) (xy 364.413183 -284.66643) (xy 364.409013 -284.6161) (xy 355.626976 -284.6161)
			(xy 355.622804 -284.666445) (xy 355.610403 -284.715416) (xy 355.590111 -284.761678) (xy 355.562481 -284.80397)
			(xy 355.528267 -284.841137) (xy 355.488402 -284.872166) (xy 355.443974 -284.89621) (xy 355.396195 -284.912614)
			(xy 355.346367 -284.92093) (xy 355.321108 -284.921452) (xy 354.381054 -284.921452) (xy 354.355805 -284.920839)
			(xy 354.305996 -284.91252) (xy 354.258236 -284.896118) (xy 354.213826 -284.872079) (xy 354.173978 -284.841058)
			(xy 354.139779 -284.803903) (xy 354.112161 -284.761626) (xy 354.091878 -284.71538) (xy 354.079483 -284.666426)
			(xy 354.075313 -284.6161) (xy 352.807076 -284.6161) (xy 352.802904 -284.666445) (xy 352.790502 -284.715418)
			(xy 352.770209 -284.761681) (xy 352.742579 -284.803973) (xy 352.708364 -284.84114) (xy 352.668498 -284.872169)
			(xy 352.624069 -284.896213) (xy 352.576288 -284.912616) (xy 352.526459 -284.920931) (xy 352.5012 -284.921452)
			(xy 351.561146 -284.921452) (xy 351.535889 -284.920875) (xy 351.486064 -284.912568) (xy 351.438286 -284.896172)
			(xy 351.393859 -284.872135) (xy 351.353994 -284.841113) (xy 351.31978 -284.803951) (xy 351.29215 -284.761665)
			(xy 351.271857 -284.715407) (xy 351.259456 -284.66644) (xy 351.255284 -284.6161) (xy 349.987204 -284.6161)
			(xy 349.983032 -284.666451) (xy 349.970629 -284.715428) (xy 349.950333 -284.761696) (xy 349.922699 -284.803993)
			(xy 349.88848 -284.841164) (xy 349.848609 -284.872195) (xy 349.804175 -284.896241) (xy 349.756388 -284.912645)
			(xy 349.706554 -284.92096) (xy 349.681292 -284.921452) (xy 348.741238 -284.921452) (xy 348.715982 -284.920874)
			(xy 348.666158 -284.912566) (xy 348.618381 -284.896169) (xy 348.573955 -284.872132) (xy 348.534091 -284.84111)
			(xy 348.499878 -284.803949) (xy 348.472249 -284.761663) (xy 348.451957 -284.715406) (xy 348.439556 -284.66644)
			(xy 348.435384 -284.6161) (xy 347.166976 -284.6161) (xy 347.162804 -284.666442) (xy 347.150404 -284.715412)
			(xy 347.130114 -284.761672) (xy 347.102487 -284.803963) (xy 347.068275 -284.841129) (xy 347.028414 -284.872158)
			(xy 346.983989 -284.896204) (xy 346.936213 -284.91261) (xy 346.886387 -284.920928) (xy 346.86113 -284.921452)
			(xy 345.921076 -284.921452) (xy 345.895826 -284.920841) (xy 345.846014 -284.912525) (xy 345.798251 -284.896124)
			(xy 345.753838 -284.872086) (xy 345.713987 -284.841066) (xy 345.679785 -284.80391) (xy 345.652165 -284.761632)
			(xy 345.63188 -284.715384) (xy 345.619483 -284.666428) (xy 345.615313 -284.6161) (xy 126.480888 -284.6161)
			(xy 126.480913 -284.6164) (xy 126.476737 -284.666789) (xy 126.464323 -284.715804) (xy 126.444011 -284.762106)
			(xy 126.416354 -284.804434) (xy 126.382107 -284.841631) (xy 126.342203 -284.872683) (xy 126.297733 -284.896743)
			(xy 126.249909 -284.913155) (xy 126.200035 -284.921471) (xy 126.174754 -284.92196) (xy 125.2347 -284.92196)
			(xy 125.209423 -284.921442) (xy 125.15956 -284.913121) (xy 125.111746 -284.896707) (xy 125.067286 -284.872646)
			(xy 125.027393 -284.841596) (xy 124.993154 -284.804403) (xy 124.965504 -284.762082) (xy 124.945197 -284.715786)
			(xy 124.932787 -284.66678) (xy 124.928613 -284.6164) (xy 123.660884 -284.6164) (xy 123.65671 -284.666775)
			(xy 123.644302 -284.715776) (xy 123.623999 -284.762067) (xy 123.596355 -284.804385) (xy 123.562123 -284.841577)
			(xy 123.522236 -284.872627) (xy 123.477783 -284.896689) (xy 123.429977 -284.913108) (xy 123.38012 -284.921434)
			(xy 123.354846 -284.92196) (xy 122.414792 -284.92196) (xy 122.389516 -284.921441) (xy 122.339653 -284.91312)
			(xy 122.291841 -284.896704) (xy 122.247382 -284.872643) (xy 122.207489 -284.841593) (xy 122.173252 -284.8044)
			(xy 122.145603 -284.762079) (xy 122.125297 -284.715785) (xy 122.112887 -284.66678) (xy 122.108712 -284.6164)
			(xy 120.840813 -284.6164) (xy 120.836637 -284.666786) (xy 120.824225 -284.715798) (xy 120.803915 -284.762098)
			(xy 120.776262 -284.804424) (xy 120.742018 -284.84162) (xy 120.702119 -284.872673) (xy 120.657653 -284.896734)
			(xy 120.609833 -284.913149) (xy 120.559963 -284.921468) (xy 120.534684 -284.92196) (xy 119.59463 -284.92196)
			(xy 119.569349 -284.921473) (xy 119.519477 -284.913156) (xy 119.471655 -284.896742) (xy 119.427186 -284.872681)
			(xy 119.387285 -284.841628) (xy 119.353039 -284.804431) (xy 119.325383 -284.762104) (xy 119.305072 -284.715802)
			(xy 119.292659 -284.666788) (xy 119.288483 -284.6164) (xy 118.020913 -284.6164) (xy 118.016737 -284.666787)
			(xy 118.004325 -284.715799) (xy 117.984014 -284.7621) (xy 117.95636 -284.804426) (xy 117.922115 -284.841623)
			(xy 117.882215 -284.872675) (xy 117.837748 -284.896737) (xy 117.789927 -284.913151) (xy 117.740056 -284.921469)
			(xy 117.714776 -284.92196) (xy 116.774722 -284.92196) (xy 116.749442 -284.921473) (xy 116.699571 -284.913154)
			(xy 116.651749 -284.89674) (xy 116.607282 -284.872678) (xy 116.567381 -284.841625) (xy 116.533137 -284.804428)
			(xy 116.505482 -284.762101) (xy 116.485171 -284.7158) (xy 116.472759 -284.666787) (xy 116.468583 -284.6164)
			(xy 107.687084 -284.6164) (xy 107.68291 -284.666776) (xy 107.670502 -284.715777) (xy 107.650198 -284.762069)
			(xy 107.622553 -284.804387) (xy 107.58832 -284.841579) (xy 107.548433 -284.872629) (xy 107.503979 -284.896691)
			(xy 107.456172 -284.913109) (xy 107.406314 -284.921435) (xy 107.38104 -284.92196) (xy 106.440986 -284.92196)
			(xy 106.41571 -284.921441) (xy 106.365849 -284.913118) (xy 106.318037 -284.896703) (xy 106.273579 -284.872641)
			(xy 106.233687 -284.841591) (xy 106.19945 -284.804398) (xy 106.171802 -284.762078) (xy 106.151496 -284.715784)
			(xy 106.139087 -284.666779) (xy 106.134912 -284.6164) (xy 104.867184 -284.6164) (xy 104.863009 -284.666776)
			(xy 104.850601 -284.715779) (xy 104.830297 -284.762071) (xy 104.802651 -284.80439) (xy 104.768417 -284.841582)
			(xy 104.728529 -284.872632) (xy 104.684074 -284.896694) (xy 104.636265 -284.913111) (xy 104.586406 -284.921436)
			(xy 104.561132 -284.92196) (xy 103.621078 -284.92196) (xy 103.595803 -284.92144) (xy 103.545942 -284.913117)
			(xy 103.498131 -284.8967) (xy 103.453674 -284.872639) (xy 103.413784 -284.841588) (xy 103.379548 -284.804396)
			(xy 103.351901 -284.762075) (xy 103.331596 -284.715782) (xy 103.319187 -284.666778) (xy 103.315012 -284.6164)
			(xy 102.047284 -284.6164) (xy 102.043109 -284.666777) (xy 102.030701 -284.71578) (xy 102.010396 -284.762073)
			(xy 101.982749 -284.804392) (xy 101.948514 -284.841584) (xy 101.908625 -284.872635) (xy 101.864169 -284.896696)
			(xy 101.816359 -284.913112) (xy 101.766499 -284.921436) (xy 101.741224 -284.92196) (xy 100.80117 -284.92196)
			(xy 100.775895 -284.92144) (xy 100.726035 -284.913115) (xy 100.678226 -284.896698) (xy 100.63377 -284.872636)
			(xy 100.593881 -284.841585) (xy 100.559646 -284.804393) (xy 100.532 -284.762073) (xy 100.511695 -284.71578)
			(xy 100.499287 -284.666777) (xy 100.495112 -284.6164) (xy 99.227213 -284.6164) (xy 99.223037 -284.666788)
			(xy 99.210624 -284.715802) (xy 99.190312 -284.762104) (xy 99.162656 -284.804431) (xy 99.12841 -284.841628)
			(xy 99.088508 -284.87268) (xy 99.044038 -284.896741) (xy 98.996215 -284.913153) (xy 98.946343 -284.92147)
			(xy 98.921062 -284.92196) (xy 97.981008 -284.92196) (xy 97.955729 -284.921472) (xy 97.905859 -284.913151)
			(xy 97.85804 -284.896736) (xy 97.813574 -284.872673) (xy 97.773676 -284.84162) (xy 97.739433 -284.804423)
			(xy 97.71178 -284.762098) (xy 97.69147 -284.715797) (xy 97.679059 -284.666786) (xy 97.674883 -284.6164)
			(xy 2.509012 -284.6164) (xy 2.509012 -285.4264) (xy 108.485173 -285.4264) (xy 108.489344 -285.376063)
			(xy 108.501743 -285.327099) (xy 108.522032 -285.280844) (xy 108.549658 -285.238559) (xy 108.583867 -285.201398)
			(xy 108.623725 -285.170374) (xy 108.668147 -285.146334) (xy 108.715919 -285.129932) (xy 108.765739 -285.121618)
			(xy 108.790994 -285.121096) (xy 109.731048 -285.121096) (xy 109.756301 -285.121613) (xy 109.806117 -285.129933)
			(xy 109.853885 -285.146339) (xy 109.898301 -285.170382) (xy 109.938155 -285.201407) (xy 109.972359 -285.238568)
			(xy 109.999981 -285.280852) (xy 110.020267 -285.327105) (xy 110.032665 -285.376066) (xy 110.036835 -285.4264)
			(xy 114.118844 -285.4264) (xy 114.123016 -285.376056) (xy 114.135417 -285.327086) (xy 114.15571 -285.280825)
			(xy 114.18334 -285.238535) (xy 114.217555 -285.201369) (xy 114.25742 -285.170343) (xy 114.301849 -285.146301)
			(xy 114.349628 -285.1299) (xy 114.399456 -285.121588) (xy 114.424714 -285.121096) (xy 115.364768 -285.121096)
			(xy 115.390028 -285.121578) (xy 115.439859 -285.129889) (xy 115.487643 -285.146288) (xy 115.532075 -285.17033)
			(xy 115.571944 -285.201357) (xy 115.606161 -285.238524) (xy 115.633795 -285.280816) (xy 115.654089 -285.32708)
			(xy 115.666492 -285.376053) (xy 115.670639 -285.4261) (xy 356.425064 -285.4261) (xy 356.429238 -285.375732)
			(xy 356.441644 -285.326738) (xy 356.461944 -285.280454) (xy 356.489585 -285.238142) (xy 356.523813 -285.200956)
			(xy 356.563694 -285.16991) (xy 356.608141 -285.145852) (xy 356.655942 -285.129437) (xy 356.705792 -285.121113)
			(xy 356.731062 -285.120588) (xy 357.671116 -285.120588) (xy 357.696396 -285.121011) (xy 357.746265 -285.129335)
			(xy 357.794084 -285.145754) (xy 357.838549 -285.169819) (xy 357.878446 -285.200875) (xy 357.912688 -285.238073)
			(xy 357.940341 -285.2804) (xy 357.960649 -285.326701) (xy 357.97306 -285.375713) (xy 357.977236 -285.4261)
			(xy 362.058764 -285.4261) (xy 362.062938 -285.37573) (xy 362.075345 -285.326734) (xy 362.095647 -285.280448)
			(xy 362.12329 -285.238135) (xy 362.157521 -285.200949) (xy 362.197405 -285.169904) (xy 362.241855 -285.145846)
			(xy 362.289658 -285.129433) (xy 362.339511 -285.121111) (xy 362.364782 -285.120588) (xy 363.304836 -285.120588)
			(xy 363.330115 -285.121013) (xy 363.379981 -285.12934) (xy 363.427798 -285.14576) (xy 363.472259 -285.169826)
			(xy 363.512154 -285.200882) (xy 363.546393 -285.23808) (xy 363.574044 -285.280406) (xy 363.594351 -285.326705)
			(xy 363.606761 -285.375716) (xy 363.610936 -285.4261) (xy 363.606761 -285.476485) (xy 363.594351 -285.525495)
			(xy 363.574044 -285.571794) (xy 363.546393 -285.61412) (xy 363.512154 -285.651318) (xy 363.472259 -285.682374)
			(xy 363.427798 -285.70644) (xy 363.379981 -285.72286) (xy 363.330115 -285.731187) (xy 363.304836 -285.731712)
			(xy 362.364782 -285.731712) (xy 362.339511 -285.731089) (xy 362.289658 -285.722767) (xy 362.241855 -285.706354)
			(xy 362.197405 -285.682296) (xy 362.157521 -285.651251) (xy 362.12329 -285.614065) (xy 362.095647 -285.571752)
			(xy 362.075345 -285.525466) (xy 362.062938 -285.47647) (xy 362.058764 -285.4261) (xy 357.977236 -285.4261)
			(xy 357.97306 -285.476487) (xy 357.960649 -285.525499) (xy 357.940341 -285.5718) (xy 357.912688 -285.614127)
			(xy 357.878446 -285.651325) (xy 357.838549 -285.682381) (xy 357.794084 -285.706446) (xy 357.746265 -285.722865)
			(xy 357.696396 -285.731189) (xy 357.671116 -285.731712) (xy 356.731062 -285.731712) (xy 356.705792 -285.731087)
			(xy 356.655942 -285.722763) (xy 356.608141 -285.706348) (xy 356.563694 -285.68229) (xy 356.523813 -285.651244)
			(xy 356.489585 -285.614058) (xy 356.461944 -285.571746) (xy 356.441644 -285.525462) (xy 356.429238 -285.476468)
			(xy 356.425064 -285.4261) (xy 115.670639 -285.4261) (xy 115.670664 -285.4264) (xy 115.666492 -285.476747)
			(xy 115.654089 -285.52572) (xy 115.633795 -285.571984) (xy 115.606161 -285.614276) (xy 115.571944 -285.651443)
			(xy 115.532075 -285.68247) (xy 115.487643 -285.706512) (xy 115.439859 -285.722911) (xy 115.390028 -285.731222)
			(xy 115.364768 -285.731712) (xy 114.424714 -285.731712) (xy 114.399456 -285.731212) (xy 114.349628 -285.7229)
			(xy 114.301849 -285.706499) (xy 114.25742 -285.682457) (xy 114.217555 -285.651431) (xy 114.18334 -285.614265)
			(xy 114.15571 -285.571975) (xy 114.135417 -285.525714) (xy 114.123016 -285.476744) (xy 114.118844 -285.4264)
			(xy 110.036835 -285.4264) (xy 110.032665 -285.476734) (xy 110.020267 -285.525695) (xy 109.999981 -285.571948)
			(xy 109.972359 -285.614232) (xy 109.938155 -285.651393) (xy 109.898301 -285.682418) (xy 109.853885 -285.706461)
			(xy 109.806117 -285.722867) (xy 109.756301 -285.731187) (xy 109.731048 -285.731712) (xy 108.790994 -285.731712)
			(xy 108.765739 -285.731182) (xy 108.715919 -285.722868) (xy 108.668147 -285.706466) (xy 108.623725 -285.682426)
			(xy 108.583867 -285.651402) (xy 108.549658 -285.614241) (xy 108.522032 -285.571956) (xy 108.501743 -285.525701)
			(xy 108.489344 -285.476737) (xy 108.485173 -285.4264) (xy 2.509012 -285.4264) (xy 2.509012 -286.2364)
			(xy 97.674895 -286.2364) (xy 97.679071 -286.186016) (xy 97.691482 -286.137006) (xy 97.71179 -286.090708)
			(xy 97.739443 -286.048384) (xy 97.773684 -286.011189) (xy 97.813581 -285.980137) (xy 97.858045 -285.956075)
			(xy 97.905862 -285.939661) (xy 97.95573 -285.93134) (xy 97.981008 -285.930848) (xy 98.921062 -285.930848)
			(xy 98.946344 -285.931318) (xy 98.996218 -285.939635) (xy 99.044043 -285.956048) (xy 99.088514 -285.98011)
			(xy 99.128418 -286.011163) (xy 99.162665 -286.048362) (xy 99.190323 -286.09069) (xy 99.210635 -286.136994)
			(xy 99.223049 -286.18601) (xy 99.227225 -286.2364) (xy 100.495124 -286.2364) (xy 100.499298 -286.186025)
			(xy 100.511706 -286.137023) (xy 100.53201 -286.090733) (xy 100.559656 -286.048415) (xy 100.593889 -286.011224)
			(xy 100.633777 -285.980174) (xy 100.678231 -285.956113) (xy 100.726038 -285.939697) (xy 100.775896 -285.931372)
			(xy 100.80117 -285.930848) (xy 101.741224 -285.930848) (xy 101.7665 -285.931352) (xy 101.816362 -285.939676)
			(xy 101.864173 -285.956093) (xy 101.908631 -285.980155) (xy 101.948522 -286.011207) (xy 101.982759 -286.0484)
			(xy 102.010407 -286.090721) (xy 102.030712 -286.137016) (xy 102.043121 -286.186021) (xy 102.047296 -286.2364)
			(xy 103.315024 -286.2364) (xy 103.319199 -286.186024) (xy 103.331607 -286.137022) (xy 103.351911 -286.09073)
			(xy 103.379558 -286.048412) (xy 103.413792 -286.011221) (xy 103.453681 -285.980171) (xy 103.498136 -285.956111)
			(xy 103.545945 -285.939695) (xy 103.595804 -285.931372) (xy 103.621078 -285.930848) (xy 104.561132 -285.930848)
			(xy 104.586407 -285.931352) (xy 104.636268 -285.939678) (xy 104.684079 -285.956095) (xy 104.728535 -285.980158)
			(xy 104.768425 -286.01121) (xy 104.802661 -286.048403) (xy 104.830308 -286.090724) (xy 104.850613 -286.137017)
			(xy 104.863021 -286.186022) (xy 104.867196 -286.2364) (xy 106.134924 -286.2364) (xy 106.139099 -286.186023)
			(xy 106.151508 -286.13702) (xy 106.171813 -286.090728) (xy 106.19946 -286.048409) (xy 106.233695 -286.011218)
			(xy 106.273585 -285.980169) (xy 106.318041 -285.956108) (xy 106.365851 -285.939693) (xy 106.415711 -285.931371)
			(xy 106.440986 -285.930848) (xy 107.38104 -285.930848) (xy 107.406315 -285.931353) (xy 107.456175 -285.939679)
			(xy 107.503984 -285.956098) (xy 107.54844 -285.980161) (xy 107.588328 -286.011213) (xy 107.622563 -286.048406)
			(xy 107.650209 -286.090726) (xy 107.670513 -286.137019) (xy 107.682921 -286.186022) (xy 107.687096 -286.2364)
			(xy 116.468595 -286.2364) (xy 116.472771 -286.186015) (xy 116.485183 -286.137004) (xy 116.505492 -286.090704)
			(xy 116.533146 -286.048379) (xy 116.56739 -286.011184) (xy 116.607288 -285.980132) (xy 116.651754 -285.956071)
			(xy 116.699574 -285.939658) (xy 116.749443 -285.931339) (xy 116.774722 -285.930848) (xy 117.714776 -285.930848)
			(xy 117.740057 -285.931319) (xy 117.789929 -285.939638) (xy 117.837753 -285.956052) (xy 117.882222 -285.980115)
			(xy 117.922123 -286.011168) (xy 117.956369 -286.048366) (xy 117.984025 -286.090694) (xy 118.004336 -286.136997)
			(xy 118.016749 -286.186011) (xy 118.020925 -286.2364) (xy 119.288495 -286.2364) (xy 119.292671 -286.186014)
			(xy 119.305083 -286.137002) (xy 119.325394 -286.090702) (xy 119.353048 -286.048377) (xy 119.387293 -286.011181)
			(xy 119.427193 -285.980129) (xy 119.47166 -285.956069) (xy 119.51948 -285.939656) (xy 119.56935 -285.931339)
			(xy 119.59463 -285.930848) (xy 120.534684 -285.930848) (xy 120.559964 -285.93132) (xy 120.609836 -285.93964)
			(xy 120.657658 -285.956055) (xy 120.702126 -285.980117) (xy 120.742026 -286.011171) (xy 120.776271 -286.048369)
			(xy 120.803926 -286.090696) (xy 120.824237 -286.136998) (xy 120.836649 -286.186012) (xy 120.840825 -286.2364)
			(xy 122.108724 -286.2364) (xy 122.112899 -286.186022) (xy 122.125308 -286.137019) (xy 122.145613 -286.090726)
			(xy 122.173261 -286.048407) (xy 122.207498 -286.011216) (xy 122.247388 -285.980167) (xy 122.291845 -285.956107)
			(xy 122.339656 -285.939692) (xy 122.389517 -285.931371) (xy 122.414792 -285.930848) (xy 123.354846 -285.930848)
			(xy 123.380121 -285.931354) (xy 123.42998 -285.93968) (xy 123.477788 -285.9561) (xy 123.522243 -285.980163)
			(xy 123.562131 -286.011215) (xy 123.596364 -286.048408) (xy 123.62401 -286.090727) (xy 123.644314 -286.13702)
			(xy 123.656722 -286.186023) (xy 123.660896 -286.2364) (xy 124.928625 -286.2364) (xy 124.932799 -286.186022)
			(xy 124.945209 -286.137017) (xy 124.965515 -286.090724) (xy 124.993163 -286.048405) (xy 125.027401 -286.011213)
			(xy 125.067293 -285.980164) (xy 125.111751 -285.956104) (xy 125.159563 -285.93969) (xy 125.209424 -285.93137)
			(xy 125.2347 -285.930848) (xy 126.174754 -285.930848) (xy 126.200036 -285.931317) (xy 126.249912 -285.939633)
			(xy 126.297738 -285.956046) (xy 126.34221 -285.980107) (xy 126.382115 -286.01116) (xy 126.416363 -286.048359)
			(xy 126.444022 -286.090688) (xy 126.464335 -286.136992) (xy 126.476749 -286.186009) (xy 126.480908 -286.2362)
			(xy 345.615224 -286.2362) (xy 345.619396 -286.185857) (xy 345.631796 -286.136887) (xy 345.652087 -286.090626)
			(xy 345.679715 -286.048335) (xy 345.713927 -286.011169) (xy 345.753789 -285.98014) (xy 345.798215 -285.956094)
			(xy 345.845992 -285.939689) (xy 345.895818 -285.931371) (xy 345.921076 -285.930848) (xy 346.86113 -285.930848)
			(xy 346.88638 -285.93146) (xy 346.936191 -285.939776) (xy 346.983954 -285.956177) (xy 347.028366 -285.980216)
			(xy 347.068216 -286.011236) (xy 347.102417 -286.048392) (xy 347.130036 -286.09067) (xy 347.150321 -286.136917)
			(xy 347.162717 -286.185872) (xy 347.166887 -286.2362) (xy 348.435296 -286.2362) (xy 348.439469 -286.185846)
			(xy 348.451873 -286.136866) (xy 348.472171 -286.090595) (xy 348.499809 -286.048297) (xy 348.534032 -286.011126)
			(xy 348.573906 -285.980094) (xy 348.618345 -285.95605) (xy 348.666136 -285.939649) (xy 348.715975 -285.931338)
			(xy 348.741238 -285.930848) (xy 349.681292 -285.930848) (xy 349.706547 -285.931428) (xy 349.756367 -285.93974)
			(xy 349.804139 -285.956139) (xy 349.848561 -285.980178) (xy 349.88842 -286.011201) (xy 349.92263 -286.048361)
			(xy 349.950256 -286.090645) (xy 349.970545 -286.1369) (xy 349.982945 -286.185864) (xy 349.987116 -286.2362)
			(xy 351.255196 -286.2362) (xy 351.259369 -286.185845) (xy 351.271774 -286.136864) (xy 351.292072 -286.090593)
			(xy 351.319711 -286.048295) (xy 351.353935 -286.011123) (xy 351.393811 -285.980092) (xy 351.438251 -285.956048)
			(xy 351.486043 -285.939647) (xy 351.535882 -285.931337) (xy 351.561146 -285.930848) (xy 352.5012 -285.930848)
			(xy 352.526452 -285.931457) (xy 352.576266 -285.93977) (xy 352.624033 -285.956168) (xy 352.66845 -285.980205)
			(xy 352.708304 -286.011225) (xy 352.742509 -286.048382) (xy 352.770132 -286.090661) (xy 352.790419 -286.136911)
			(xy 352.802816 -286.185869) (xy 352.806987 -286.2362) (xy 354.075224 -286.2362) (xy 354.079395 -286.185859)
			(xy 354.091795 -286.136892) (xy 354.112084 -286.090632) (xy 354.139709 -286.048343) (xy 354.173918 -286.011177)
			(xy 354.213778 -285.980147) (xy 354.2582 -285.956101) (xy 354.305974 -285.939694) (xy 354.355797 -285.931373)
			(xy 354.381054 -285.930848) (xy 355.321108 -285.930848) (xy 355.346359 -285.931458) (xy 355.396173 -285.939772)
			(xy 355.443939 -285.956171) (xy 355.488354 -285.980208) (xy 355.528207 -286.011228) (xy 355.562411 -286.048384)
			(xy 355.590033 -286.090664) (xy 355.610319 -286.136913) (xy 355.622717 -286.18587) (xy 355.626887 -286.2362)
			(xy 364.408924 -286.2362) (xy 364.413096 -286.185856) (xy 364.425497 -286.136884) (xy 364.445789 -286.090622)
			(xy 364.473419 -286.048331) (xy 364.507632 -286.011164) (xy 364.547497 -285.980135) (xy 364.591924 -285.95609)
			(xy 364.639704 -285.939686) (xy 364.689532 -285.93137) (xy 364.71479 -285.930848) (xy 365.654844 -285.930848)
			(xy 365.680093 -285.931461) (xy 365.729902 -285.939779) (xy 365.777663 -285.956181) (xy 365.822073 -285.980221)
			(xy 365.861921 -286.011241) (xy 365.89612 -286.048396) (xy 365.923738 -286.090674) (xy 365.944022 -286.13692)
			(xy 365.956417 -286.185874) (xy 365.960587 -286.2362) (xy 367.228824 -286.2362) (xy 367.232996 -286.185855)
			(xy 367.245398 -286.136883) (xy 367.26569 -286.09062) (xy 367.293321 -286.048328) (xy 367.327535 -286.011161)
			(xy 367.367401 -285.980132) (xy 367.41183 -285.956088) (xy 367.45961 -285.939685) (xy 367.509439 -285.931369)
			(xy 367.534698 -285.930848) (xy 368.474752 -285.930848) (xy 368.500009 -285.931425) (xy 368.549834 -285.939732)
			(xy 368.597612 -285.956128) (xy 368.64204 -285.980164) (xy 368.681905 -286.011187) (xy 368.716119 -286.048348)
			(xy 368.74375 -286.090634) (xy 368.764043 -286.136892) (xy 368.776444 -286.185859) (xy 368.780616 -286.2362)
			(xy 370.049024 -286.2362) (xy 370.053196 -286.185859) (xy 370.065595 -286.13689) (xy 370.085885 -286.09063)
			(xy 370.113511 -286.048341) (xy 370.147721 -286.011174) (xy 370.187581 -285.980145) (xy 370.232004 -285.956099)
			(xy 370.279779 -285.939692) (xy 370.329603 -285.931372) (xy 370.35486 -285.930848) (xy 371.294914 -285.930848)
			(xy 371.320165 -285.931459) (xy 371.369978 -285.939773) (xy 371.417743 -285.956173) (xy 371.462157 -285.98021)
			(xy 371.502009 -286.01123) (xy 371.536213 -286.048386) (xy 371.563834 -286.090665) (xy 371.58412 -286.136914)
			(xy 371.596517 -286.185871) (xy 371.600687 -286.2362) (xy 372.868924 -286.2362) (xy 372.873096 -286.185858)
			(xy 372.885495 -286.136889) (xy 372.905786 -286.090628) (xy 372.933413 -286.048338) (xy 372.967624 -286.011172)
			(xy 373.007485 -285.980142) (xy 373.05191 -285.956097) (xy 373.099686 -285.939691) (xy 373.149511 -285.931372)
			(xy 373.174768 -285.930848) (xy 374.114822 -285.930848) (xy 374.140072 -285.931459) (xy 374.189884 -285.939775)
			(xy 374.237648 -285.956175) (xy 374.282061 -285.980213) (xy 374.321912 -286.011233) (xy 374.356115 -286.048389)
			(xy 374.383735 -286.090668) (xy 374.40402 -286.136916) (xy 374.416417 -286.185871) (xy 374.420587 -286.2362)
			(xy 374.416417 -286.286529) (xy 374.40402 -286.335484) (xy 374.383735 -286.381732) (xy 374.356115 -286.424011)
			(xy 374.321912 -286.461167) (xy 374.282061 -286.492187) (xy 374.237648 -286.516225) (xy 374.189884 -286.532625)
			(xy 374.140072 -286.540941) (xy 374.114822 -286.541464) (xy 373.174768 -286.541464) (xy 373.149511 -286.541028)
			(xy 373.099686 -286.532709) (xy 373.05191 -286.516303) (xy 373.007485 -286.492258) (xy 372.967624 -286.461228)
			(xy 372.933413 -286.424062) (xy 372.905786 -286.381772) (xy 372.885495 -286.335511) (xy 372.873096 -286.286542)
			(xy 372.868924 -286.2362) (xy 371.600687 -286.2362) (xy 371.596517 -286.286529) (xy 371.58412 -286.335486)
			(xy 371.563834 -286.381735) (xy 371.536213 -286.424014) (xy 371.502009 -286.46117) (xy 371.462157 -286.49219)
			(xy 371.417743 -286.516227) (xy 371.369978 -286.532627) (xy 371.320165 -286.540941) (xy 371.294914 -286.541464)
			(xy 370.35486 -286.541464) (xy 370.329603 -286.541028) (xy 370.279779 -286.532708) (xy 370.232004 -286.516301)
			(xy 370.187581 -286.492255) (xy 370.147721 -286.461226) (xy 370.113511 -286.424059) (xy 370.085884 -286.38177)
			(xy 370.065595 -286.33551) (xy 370.053196 -286.286541) (xy 370.049024 -286.2362) (xy 368.780616 -286.2362)
			(xy 368.776444 -286.286541) (xy 368.764043 -286.335508) (xy 368.74375 -286.381766) (xy 368.716119 -286.424052)
			(xy 368.681905 -286.461213) (xy 368.64204 -286.492236) (xy 368.597612 -286.516272) (xy 368.549834 -286.532668)
			(xy 368.500009 -286.540975) (xy 368.474752 -286.541464) (xy 367.534698 -286.541464) (xy 367.509439 -286.541031)
			(xy 367.45961 -286.532715) (xy 367.41183 -286.516312) (xy 367.367401 -286.492268) (xy 367.327535 -286.461239)
			(xy 367.293321 -286.424072) (xy 367.26569 -286.38178) (xy 367.245398 -286.335517) (xy 367.232996 -286.286545)
			(xy 367.228824 -286.2362) (xy 365.960587 -286.2362) (xy 365.956417 -286.286526) (xy 365.944022 -286.33548)
			(xy 365.923738 -286.381726) (xy 365.89612 -286.424004) (xy 365.861921 -286.461159) (xy 365.822073 -286.492179)
			(xy 365.777663 -286.516219) (xy 365.729902 -286.532621) (xy 365.680093 -286.540939) (xy 365.654844 -286.541464)
			(xy 364.71479 -286.541464) (xy 364.689532 -286.54103) (xy 364.639704 -286.532714) (xy 364.591924 -286.51631)
			(xy 364.547497 -286.492265) (xy 364.507632 -286.461236) (xy 364.473419 -286.424069) (xy 364.445789 -286.381778)
			(xy 364.425497 -286.335516) (xy 364.413096 -286.286544) (xy 364.408924 -286.2362) (xy 355.626887 -286.2362)
			(xy 355.622717 -286.28653) (xy 355.610319 -286.335487) (xy 355.590033 -286.381736) (xy 355.562411 -286.424016)
			(xy 355.528207 -286.461172) (xy 355.488354 -286.492192) (xy 355.443939 -286.516229) (xy 355.396173 -286.532628)
			(xy 355.346359 -286.540942) (xy 355.321108 -286.541464) (xy 354.381054 -286.541464) (xy 354.355797 -286.541027)
			(xy 354.305974 -286.532706) (xy 354.2582 -286.516299) (xy 354.213778 -286.492253) (xy 354.173918 -286.461223)
			(xy 354.139709 -286.424057) (xy 354.112084 -286.381768) (xy 354.091795 -286.335508) (xy 354.079395 -286.286541)
			(xy 354.075224 -286.2362) (xy 352.806987 -286.2362) (xy 352.802816 -286.286531) (xy 352.790419 -286.335489)
			(xy 352.770132 -286.381739) (xy 352.742509 -286.424018) (xy 352.708304 -286.461175) (xy 352.66845 -286.492195)
			(xy 352.624033 -286.516232) (xy 352.576266 -286.53263) (xy 352.526452 -286.540943) (xy 352.5012 -286.541464)
			(xy 351.561146 -286.541464) (xy 351.535882 -286.541063) (xy 351.486043 -286.532753) (xy 351.438251 -286.516352)
			(xy 351.393811 -286.492309) (xy 351.353935 -286.461277) (xy 351.319711 -286.424105) (xy 351.292072 -286.381807)
			(xy 351.271774 -286.335536) (xy 351.259369 -286.286555) (xy 351.255196 -286.2362) (xy 349.987116 -286.2362)
			(xy 349.982945 -286.286536) (xy 349.970545 -286.3355) (xy 349.950256 -286.381755) (xy 349.92263 -286.424039)
			(xy 349.88842 -286.461199) (xy 349.848561 -286.492222) (xy 349.804139 -286.516261) (xy 349.756367 -286.53266)
			(xy 349.706547 -286.540972) (xy 349.681292 -286.541464) (xy 348.741238 -286.541464) (xy 348.715975 -286.541062)
			(xy 348.666136 -286.532751) (xy 348.618345 -286.51635) (xy 348.573907 -286.492306) (xy 348.534032 -286.461274)
			(xy 348.499809 -286.424103) (xy 348.472171 -286.381805) (xy 348.451873 -286.335534) (xy 348.439469 -286.286554)
			(xy 348.435296 -286.2362) (xy 347.166887 -286.2362) (xy 347.162717 -286.286528) (xy 347.150321 -286.335483)
			(xy 347.130036 -286.38173) (xy 347.102417 -286.424008) (xy 347.068216 -286.461164) (xy 347.028366 -286.492184)
			(xy 346.983954 -286.516223) (xy 346.936191 -286.532624) (xy 346.88638 -286.54094) (xy 346.86113 -286.541464)
			(xy 345.921076 -286.541464) (xy 345.895818 -286.541029) (xy 345.845992 -286.532711) (xy 345.798215 -286.516306)
			(xy 345.753789 -286.49226) (xy 345.713927 -286.461231) (xy 345.679715 -286.424065) (xy 345.652087 -286.381774)
			(xy 345.631796 -286.335513) (xy 345.619396 -286.286543) (xy 345.615224 -286.2362) (xy 126.480908 -286.2362)
			(xy 126.480925 -286.2364) (xy 126.476749 -286.286791) (xy 126.464335 -286.335808) (xy 126.444022 -286.382112)
			(xy 126.416363 -286.424441) (xy 126.382115 -286.46164) (xy 126.34221 -286.492693) (xy 126.297738 -286.516754)
			(xy 126.249912 -286.533167) (xy 126.200036 -286.541483) (xy 126.174754 -286.541972) (xy 125.2347 -286.541972)
			(xy 125.209424 -286.54143) (xy 125.159563 -286.53311) (xy 125.111751 -286.516696) (xy 125.067293 -286.492636)
			(xy 125.027401 -286.461587) (xy 124.993163 -286.424395) (xy 124.965515 -286.382076) (xy 124.945209 -286.335783)
			(xy 124.932799 -286.286778) (xy 124.928625 -286.2364) (xy 123.660896 -286.2364) (xy 123.656722 -286.286777)
			(xy 123.644314 -286.33578) (xy 123.62401 -286.382073) (xy 123.596364 -286.424392) (xy 123.562131 -286.461585)
			(xy 123.522243 -286.492637) (xy 123.477788 -286.5167) (xy 123.42998 -286.53312) (xy 123.380121 -286.541446)
			(xy 123.354846 -286.541972) (xy 122.414792 -286.541972) (xy 122.389517 -286.541429) (xy 122.339656 -286.533108)
			(xy 122.291845 -286.516693) (xy 122.247388 -286.492633) (xy 122.207498 -286.461584) (xy 122.173261 -286.424393)
			(xy 122.145613 -286.382074) (xy 122.125308 -286.335781) (xy 122.112899 -286.286778) (xy 122.108724 -286.2364)
			(xy 120.840825 -286.2364) (xy 120.836649 -286.286788) (xy 120.824237 -286.335802) (xy 120.803926 -286.382104)
			(xy 120.776271 -286.424431) (xy 120.742026 -286.461629) (xy 120.702126 -286.492683) (xy 120.657658 -286.516745)
			(xy 120.609836 -286.53316) (xy 120.559964 -286.54148) (xy 120.534684 -286.541972) (xy 119.59463 -286.541972)
			(xy 119.56935 -286.541461) (xy 119.51948 -286.533144) (xy 119.47166 -286.516731) (xy 119.427193 -286.492671)
			(xy 119.387293 -286.461619) (xy 119.353048 -286.424423) (xy 119.325394 -286.382098) (xy 119.305083 -286.335798)
			(xy 119.292671 -286.286786) (xy 119.288495 -286.2364) (xy 118.020925 -286.2364) (xy 118.016749 -286.286789)
			(xy 118.004336 -286.335803) (xy 117.984025 -286.382106) (xy 117.956369 -286.424434) (xy 117.922123 -286.461632)
			(xy 117.882222 -286.492685) (xy 117.837753 -286.516748) (xy 117.789929 -286.533162) (xy 117.740057 -286.541481)
			(xy 117.714776 -286.541972) (xy 116.774722 -286.541972) (xy 116.749443 -286.541461) (xy 116.699574 -286.533142)
			(xy 116.651754 -286.516729) (xy 116.607288 -286.492668) (xy 116.56739 -286.461616) (xy 116.533146 -286.424421)
			(xy 116.505492 -286.382096) (xy 116.485183 -286.335796) (xy 116.472771 -286.286785) (xy 116.468595 -286.2364)
			(xy 107.687096 -286.2364) (xy 107.682921 -286.286778) (xy 107.670513 -286.335781) (xy 107.650209 -286.382074)
			(xy 107.622563 -286.424394) (xy 107.588328 -286.461587) (xy 107.54844 -286.492639) (xy 107.503984 -286.516702)
			(xy 107.456175 -286.533121) (xy 107.406315 -286.541447) (xy 107.38104 -286.541972) (xy 106.440986 -286.541972)
			(xy 106.415711 -286.541429) (xy 106.365851 -286.533107) (xy 106.318041 -286.516692) (xy 106.273585 -286.492631)
			(xy 106.233695 -286.461582) (xy 106.19946 -286.424391) (xy 106.171813 -286.382072) (xy 106.151508 -286.33578)
			(xy 106.139099 -286.286777) (xy 106.134924 -286.2364) (xy 104.867196 -286.2364) (xy 104.863021 -286.286778)
			(xy 104.850613 -286.335783) (xy 104.830308 -286.382076) (xy 104.802661 -286.424397) (xy 104.768425 -286.46159)
			(xy 104.728535 -286.492642) (xy 104.684079 -286.516705) (xy 104.636268 -286.533122) (xy 104.586407 -286.541448)
			(xy 104.561132 -286.541972) (xy 103.621078 -286.541972) (xy 103.595804 -286.541428) (xy 103.545945 -286.533105)
			(xy 103.498136 -286.516689) (xy 103.453681 -286.492629) (xy 103.413792 -286.461579) (xy 103.379558 -286.424388)
			(xy 103.351911 -286.38207) (xy 103.331607 -286.335778) (xy 103.319199 -286.286776) (xy 103.315024 -286.2364)
			(xy 102.047296 -286.2364) (xy 102.043121 -286.286779) (xy 102.030712 -286.335784) (xy 102.010407 -286.382079)
			(xy 101.982759 -286.4244) (xy 101.948522 -286.461593) (xy 101.908631 -286.492645) (xy 101.864173 -286.516707)
			(xy 101.816362 -286.533124) (xy 101.7665 -286.541448) (xy 101.741224 -286.541972) (xy 100.80117 -286.541972)
			(xy 100.775896 -286.541428) (xy 100.726038 -286.533103) (xy 100.678231 -286.516687) (xy 100.633777 -286.492626)
			(xy 100.593889 -286.461576) (xy 100.559656 -286.424385) (xy 100.53201 -286.382067) (xy 100.511706 -286.335777)
			(xy 100.499298 -286.286775) (xy 100.495124 -286.2364) (xy 99.227225 -286.2364) (xy 99.223049 -286.28679)
			(xy 99.210635 -286.335806) (xy 99.190323 -286.38211) (xy 99.162665 -286.424438) (xy 99.128418 -286.461637)
			(xy 99.088514 -286.49269) (xy 99.044043 -286.516752) (xy 98.996218 -286.533165) (xy 98.946344 -286.541482)
			(xy 98.921062 -286.541972) (xy 97.981008 -286.541972) (xy 97.95573 -286.54146) (xy 97.905862 -286.533139)
			(xy 97.858045 -286.516725) (xy 97.813581 -286.492663) (xy 97.773684 -286.461611) (xy 97.739443 -286.424416)
			(xy 97.71179 -286.382092) (xy 97.691482 -286.335794) (xy 97.679071 -286.286784) (xy 97.674895 -286.2364)
			(xy 2.509012 -286.2364) (xy 2.509012 -287.0462) (xy 108.484876 -287.0462) (xy 108.489052 -286.995814)
			(xy 108.501463 -286.946803) (xy 108.521772 -286.900503) (xy 108.549424 -286.858177) (xy 108.583666 -286.82098)
			(xy 108.623563 -286.789926) (xy 108.668028 -286.765862) (xy 108.715846 -286.749445) (xy 108.765715 -286.741123)
			(xy 108.790994 -286.7406) (xy 109.731048 -286.7406) (xy 109.756319 -286.741202) (xy 109.806169 -286.749527)
			(xy 109.85397 -286.765944) (xy 109.898418 -286.790004) (xy 109.938299 -286.821051) (xy 109.972527 -286.858238)
			(xy 110.000168 -286.900551) (xy 110.020468 -286.946836) (xy 110.032874 -286.995831) (xy 110.037048 -287.0462)
			(xy 114.118547 -287.0462) (xy 114.122723 -286.995807) (xy 114.135137 -286.94679) (xy 114.155449 -286.900484)
			(xy 114.183106 -286.858153) (xy 114.217354 -286.820951) (xy 114.257258 -286.789895) (xy 114.301729 -286.76583)
			(xy 114.349555 -286.749413) (xy 114.399431 -286.741092) (xy 114.424714 -286.7406) (xy 115.364768 -286.7406)
			(xy 115.390045 -286.741166) (xy 115.439911 -286.749483) (xy 115.487728 -286.765894) (xy 115.532191 -286.789952)
			(xy 115.572088 -286.821001) (xy 115.606329 -286.858193) (xy 115.633981 -286.900515) (xy 115.65429 -286.946811)
			(xy 115.666701 -286.995818) (xy 115.670852 -287.0459) (xy 356.425277 -287.0459) (xy 356.429447 -286.995567)
			(xy 356.441845 -286.946607) (xy 356.462131 -286.900355) (xy 356.489753 -286.858072) (xy 356.523957 -286.820912)
			(xy 356.563811 -286.789888) (xy 356.608227 -286.765847) (xy 356.655994 -286.749443) (xy 356.705809 -286.741125)
			(xy 356.731062 -286.7406) (xy 357.671116 -286.7406) (xy 357.696371 -286.741107) (xy 357.746192 -286.749423)
			(xy 357.793965 -286.765826) (xy 357.838387 -286.789867) (xy 357.878245 -286.820893) (xy 357.912454 -286.858055)
			(xy 357.94008 -286.900341) (xy 357.960369 -286.946597) (xy 357.972768 -286.995562) (xy 357.976939 -287.0459)
			(xy 362.058977 -287.0459) (xy 362.063148 -286.995565) (xy 362.075546 -286.946603) (xy 362.095834 -286.900349)
			(xy 362.123458 -286.858066) (xy 362.157665 -286.820905) (xy 362.197521 -286.789881) (xy 362.24194 -286.765841)
			(xy 362.28971 -286.749439) (xy 362.339528 -286.741123) (xy 362.364782 -286.7406) (xy 363.304836 -286.7406)
			(xy 363.33009 -286.741108) (xy 363.379908 -286.749427) (xy 363.427678 -286.765831) (xy 363.472097 -286.789874)
			(xy 363.511953 -286.8209) (xy 363.546159 -286.858062) (xy 363.573783 -286.900347) (xy 363.59407 -286.946601)
			(xy 363.606468 -286.995564) (xy 363.610639 -287.0459) (xy 363.606468 -287.096236) (xy 363.59407 -287.145199)
			(xy 363.573783 -287.191453) (xy 363.546159 -287.233738) (xy 363.511953 -287.2709) (xy 363.472097 -287.301926)
			(xy 363.427678 -287.325969) (xy 363.379908 -287.342373) (xy 363.33009 -287.350692) (xy 363.304836 -287.351216)
			(xy 362.364782 -287.351216) (xy 362.339528 -287.350677) (xy 362.28971 -287.342361) (xy 362.24194 -287.325959)
			(xy 362.197521 -287.301919) (xy 362.157665 -287.270895) (xy 362.123458 -287.233734) (xy 362.095834 -287.191451)
			(xy 362.075546 -287.145197) (xy 362.063148 -287.096235) (xy 362.058977 -287.0459) (xy 357.976939 -287.0459)
			(xy 357.972768 -287.096238) (xy 357.960369 -287.145203) (xy 357.94008 -287.191459) (xy 357.912454 -287.233745)
			(xy 357.878245 -287.270907) (xy 357.838387 -287.301933) (xy 357.793965 -287.325974) (xy 357.746192 -287.342377)
			(xy 357.696371 -287.350693) (xy 357.671116 -287.351216) (xy 356.731062 -287.351216) (xy 356.705809 -287.350675)
			(xy 356.655994 -287.342357) (xy 356.608227 -287.325953) (xy 356.563811 -287.301912) (xy 356.523957 -287.270888)
			(xy 356.489753 -287.233728) (xy 356.462131 -287.191445) (xy 356.441845 -287.145193) (xy 356.429447 -287.096233)
			(xy 356.425277 -287.0459) (xy 115.670852 -287.0459) (xy 115.670877 -287.0462) (xy 115.666701 -287.096582)
			(xy 115.65429 -287.145589) (xy 115.633981 -287.191885) (xy 115.606329 -287.234207) (xy 115.572088 -287.271399)
			(xy 115.532191 -287.302448) (xy 115.487728 -287.326506) (xy 115.439911 -287.342917) (xy 115.390045 -287.351234)
			(xy 115.364768 -287.351724) (xy 114.424714 -287.351724) (xy 114.399431 -287.351308) (xy 114.349555 -287.342987)
			(xy 114.301729 -287.32657) (xy 114.257258 -287.302505) (xy 114.217354 -287.271449) (xy 114.183106 -287.234247)
			(xy 114.155449 -287.191916) (xy 114.135137 -287.14561) (xy 114.122723 -287.096593) (xy 114.118547 -287.0462)
			(xy 110.037048 -287.0462) (xy 110.032874 -287.096569) (xy 110.020468 -287.145564) (xy 110.000168 -287.191849)
			(xy 109.972527 -287.234162) (xy 109.938299 -287.271349) (xy 109.898418 -287.302396) (xy 109.85397 -287.326456)
			(xy 109.806169 -287.342873) (xy 109.756319 -287.351198) (xy 109.731048 -287.351724) (xy 108.790994 -287.351724)
			(xy 108.765715 -287.351277) (xy 108.715846 -287.342955) (xy 108.668028 -287.326538) (xy 108.623563 -287.302474)
			(xy 108.583666 -287.27142) (xy 108.549424 -287.234223) (xy 108.521772 -287.191897) (xy 108.501463 -287.145597)
			(xy 108.489052 -287.096586) (xy 108.484876 -287.0462) (xy 2.509012 -287.0462) (xy 2.509012 -287.8564)
			(xy 97.674907 -287.8564) (xy 97.679082 -287.806018) (xy 97.691493 -287.75701) (xy 97.711801 -287.710714)
			(xy 97.739452 -287.668391) (xy 97.773692 -287.631198) (xy 97.813588 -287.600147) (xy 97.858049 -287.576086)
			(xy 97.905865 -287.559672) (xy 97.955731 -287.551352) (xy 97.981008 -287.55086) (xy 98.921062 -287.55086)
			(xy 98.946345 -287.551306) (xy 98.996221 -287.559623) (xy 99.044048 -287.576037) (xy 99.088521 -287.6001)
			(xy 99.128426 -287.631154) (xy 99.162675 -287.668354) (xy 99.190333 -287.710685) (xy 99.210647 -287.75699)
			(xy 99.223061 -287.806008) (xy 99.227237 -287.8564) (xy 100.495136 -287.8564) (xy 100.49931 -287.806027)
			(xy 100.511718 -287.757027) (xy 100.532021 -287.710738) (xy 100.559665 -287.668422) (xy 100.593897 -287.631232)
			(xy 100.633783 -287.600184) (xy 100.678235 -287.576124) (xy 100.726041 -287.559708) (xy 100.775897 -287.551384)
			(xy 100.80117 -287.55086) (xy 101.741224 -287.55086) (xy 101.766501 -287.55134) (xy 101.816365 -287.559664)
			(xy 101.864178 -287.576082) (xy 101.908638 -287.600145) (xy 101.94853 -287.631198) (xy 101.982768 -287.668393)
			(xy 102.010417 -287.710716) (xy 102.030723 -287.757012) (xy 102.043133 -287.806019) (xy 102.047308 -287.8564)
			(xy 103.315036 -287.8564) (xy 103.31921 -287.806026) (xy 103.331618 -287.757026) (xy 103.351922 -287.710736)
			(xy 103.379567 -287.668419) (xy 103.4138 -287.63123) (xy 103.453687 -287.600182) (xy 103.498141 -287.576122)
			(xy 103.545948 -287.559707) (xy 103.595805 -287.551384) (xy 103.621078 -287.55086) (xy 104.561132 -287.55086)
			(xy 104.586408 -287.551341) (xy 104.636271 -287.559666) (xy 104.684084 -287.576084) (xy 104.728542 -287.600148)
			(xy 104.768433 -287.631201) (xy 104.80267 -287.668396) (xy 104.830318 -287.710718) (xy 104.850624 -287.757013)
			(xy 104.863033 -287.80602) (xy 104.867208 -287.8564) (xy 106.134936 -287.8564) (xy 106.139111 -287.806025)
			(xy 106.151519 -287.757024) (xy 106.171823 -287.710734) (xy 106.199469 -287.668417) (xy 106.233703 -287.631227)
			(xy 106.273592 -287.600179) (xy 106.318046 -287.576119) (xy 106.365854 -287.559705) (xy 106.415712 -287.551383)
			(xy 106.440986 -287.55086) (xy 107.38104 -287.55086) (xy 107.406316 -287.551341) (xy 107.456178 -287.559668)
			(xy 107.503989 -287.576087) (xy 107.548446 -287.600151) (xy 107.588336 -287.631204) (xy 107.622572 -287.668398)
			(xy 107.65022 -287.71072) (xy 107.670524 -287.757015) (xy 107.682933 -287.806021) (xy 107.687108 -287.8564)
			(xy 116.468607 -287.8564) (xy 116.472783 -287.806017) (xy 116.485194 -287.757008) (xy 116.505503 -287.71071)
			(xy 116.533156 -287.668387) (xy 116.567398 -287.631193) (xy 116.607295 -287.600142) (xy 116.651759 -287.576082)
			(xy 116.699577 -287.559669) (xy 116.749444 -287.551351) (xy 116.774722 -287.55086) (xy 117.714776 -287.55086)
			(xy 117.740058 -287.551307) (xy 117.789932 -287.559626) (xy 117.837757 -287.576041) (xy 117.882228 -287.600104)
			(xy 117.922131 -287.631159) (xy 117.956378 -287.668359) (xy 117.984035 -287.710688) (xy 118.004348 -287.756993)
			(xy 118.016761 -287.806009) (xy 118.020937 -287.8564) (xy 119.288507 -287.8564) (xy 119.292683 -287.806016)
			(xy 119.305094 -287.757006) (xy 119.325404 -287.710708) (xy 119.353058 -287.668384) (xy 119.387301 -287.63119)
			(xy 119.427199 -287.600139) (xy 119.471664 -287.57608) (xy 119.519483 -287.559668) (xy 119.569351 -287.551351)
			(xy 119.59463 -287.55086) (xy 120.534684 -287.55086) (xy 120.559965 -287.551308) (xy 120.609839 -287.559628)
			(xy 120.657663 -287.576044) (xy 120.702132 -287.600107) (xy 120.742034 -287.631162) (xy 120.776281 -287.668362)
			(xy 120.803937 -287.710691) (xy 120.824248 -287.756994) (xy 120.836661 -287.80601) (xy 120.840837 -287.8564)
			(xy 122.108736 -287.8564) (xy 122.112911 -287.806024) (xy 122.125319 -287.757023) (xy 122.145624 -287.710732)
			(xy 122.173271 -287.668415) (xy 122.207506 -287.631225) (xy 122.247395 -287.600177) (xy 122.29185 -287.576118)
			(xy 122.339659 -287.559704) (xy 122.389518 -287.551382) (xy 122.414792 -287.55086) (xy 123.354846 -287.55086)
			(xy 123.380122 -287.551342) (xy 123.429983 -287.559669) (xy 123.477793 -287.576089) (xy 123.522249 -287.600153)
			(xy 123.562139 -287.631206) (xy 123.596374 -287.6684) (xy 123.62402 -287.710722) (xy 123.644325 -287.757016)
			(xy 123.656733 -287.806021) (xy 123.660908 -287.8564) (xy 124.928637 -287.8564) (xy 124.932811 -287.806024)
			(xy 124.94522 -287.757021) (xy 124.965525 -287.71073) (xy 124.993173 -287.668412) (xy 125.027409 -287.631222)
			(xy 125.067299 -287.600174) (xy 125.111756 -287.576115) (xy 125.159566 -287.559702) (xy 125.209425 -287.551382)
			(xy 125.2347 -287.55086) (xy 126.174754 -287.55086) (xy 126.200037 -287.551306) (xy 126.249914 -287.559622)
			(xy 126.297743 -287.576035) (xy 126.342216 -287.600097) (xy 126.382123 -287.631152) (xy 126.416373 -287.668352)
			(xy 126.444032 -287.710682) (xy 126.464346 -287.756988) (xy 126.47676 -287.806007) (xy 126.48092 -287.8562)
			(xy 345.615237 -287.8562) (xy 345.619408 -287.805859) (xy 345.631808 -287.756891) (xy 345.652098 -287.710632)
			(xy 345.679725 -287.668343) (xy 345.713935 -287.631178) (xy 345.753796 -287.60015) (xy 345.79822 -287.576106)
			(xy 345.845995 -287.559701) (xy 345.895819 -287.551384) (xy 345.921076 -287.55086) (xy 346.86113 -287.55086)
			(xy 346.886381 -287.551448) (xy 346.936194 -287.559765) (xy 346.983958 -287.576166) (xy 347.028372 -287.600206)
			(xy 347.068224 -287.631227) (xy 347.102426 -287.668384) (xy 347.130047 -287.710664) (xy 347.150332 -287.756913)
			(xy 347.162729 -287.80587) (xy 347.166899 -287.8562) (xy 348.435308 -287.8562) (xy 348.439481 -287.805848)
			(xy 348.451885 -287.756869) (xy 348.472182 -287.710601) (xy 348.499818 -287.668305) (xy 348.53404 -287.631134)
			(xy 348.573913 -287.600104) (xy 348.61835 -287.576061) (xy 348.666139 -287.55966) (xy 348.715976 -287.55135)
			(xy 348.741238 -287.55086) (xy 349.681292 -287.55086) (xy 349.706548 -287.551416) (xy 349.75637 -287.559729)
			(xy 349.804144 -287.576129) (xy 349.848568 -287.600168) (xy 349.888429 -287.631192) (xy 349.922639 -287.668354)
			(xy 349.950266 -287.71064) (xy 349.970557 -287.756896) (xy 349.982957 -287.805862) (xy 349.987128 -287.8562)
			(xy 351.255208 -287.8562) (xy 351.259381 -287.805847) (xy 351.271785 -287.756868) (xy 351.292083 -287.710599)
			(xy 351.31972 -287.668302) (xy 351.353943 -287.631132) (xy 351.393817 -287.600102) (xy 351.438256 -287.576059)
			(xy 351.486046 -287.559659) (xy 351.535883 -287.551349) (xy 351.561146 -287.55086) (xy 352.5012 -287.55086)
			(xy 352.526453 -287.551445) (xy 352.576269 -287.559758) (xy 352.624038 -287.576157) (xy 352.668456 -287.600195)
			(xy 352.708312 -287.631216) (xy 352.742518 -287.668374) (xy 352.770142 -287.710656) (xy 352.79043 -287.756907)
			(xy 352.802828 -287.805867) (xy 352.806999 -287.8562) (xy 354.075237 -287.8562) (xy 354.079408 -287.805861)
			(xy 354.091806 -287.756896) (xy 354.112095 -287.710638) (xy 354.139719 -287.66835) (xy 354.173927 -287.631186)
			(xy 354.213784 -287.600158) (xy 354.258205 -287.576112) (xy 354.305977 -287.559706) (xy 354.355799 -287.551385)
			(xy 354.381054 -287.55086) (xy 355.321108 -287.55086) (xy 355.34636 -287.551446) (xy 355.396176 -287.55976)
			(xy 355.443943 -287.57616) (xy 355.48836 -287.600198) (xy 355.528215 -287.631219) (xy 355.56242 -287.668377)
			(xy 355.590043 -287.710658) (xy 355.610331 -287.756909) (xy 355.622728 -287.805868) (xy 355.626899 -287.8562)
			(xy 364.408937 -287.8562) (xy 364.413108 -287.805858) (xy 364.425509 -287.756888) (xy 364.4458 -287.710628)
			(xy 364.473429 -287.668338) (xy 364.507641 -287.631173) (xy 364.547503 -287.600145) (xy 364.591929 -287.576102)
			(xy 364.639707 -287.559698) (xy 364.689533 -287.551382) (xy 364.71479 -287.55086) (xy 365.654844 -287.55086)
			(xy 365.680094 -287.551449) (xy 365.729905 -287.559767) (xy 365.777668 -287.57617) (xy 365.822079 -287.600211)
			(xy 365.861929 -287.631232) (xy 365.89613 -287.668389) (xy 365.923749 -287.710668) (xy 365.944033 -287.756916)
			(xy 365.956429 -287.805872) (xy 365.960599 -287.8562) (xy 367.228837 -287.8562) (xy 367.233009 -287.805857)
			(xy 367.245409 -287.756887) (xy 367.265701 -287.710626) (xy 367.293331 -287.668336) (xy 367.327544 -287.63117)
			(xy 367.367408 -287.600142) (xy 367.411835 -287.576099) (xy 367.459613 -287.559697) (xy 367.50944 -287.551382)
			(xy 367.534698 -287.55086) (xy 368.474752 -287.55086) (xy 368.50001 -287.551413) (xy 368.549837 -287.55972)
			(xy 368.597617 -287.576117) (xy 368.642047 -287.600154) (xy 368.681913 -287.631178) (xy 368.716129 -287.668341)
			(xy 368.74376 -287.710629) (xy 368.764054 -287.756888) (xy 368.776456 -287.805857) (xy 368.780628 -287.8562)
			(xy 370.049037 -287.8562) (xy 370.053208 -287.805861) (xy 370.065607 -287.756894) (xy 370.085895 -287.710636)
			(xy 370.113521 -287.668348) (xy 370.147729 -287.631184) (xy 370.187588 -287.600156) (xy 370.232009 -287.576111)
			(xy 370.279782 -287.559705) (xy 370.329604 -287.551385) (xy 370.35486 -287.55086) (xy 371.294914 -287.55086)
			(xy 371.320166 -287.551447) (xy 371.369981 -287.559761) (xy 371.417748 -287.576162) (xy 371.462164 -287.6002)
			(xy 371.502017 -287.631221) (xy 371.536222 -287.668379) (xy 371.563844 -287.71066) (xy 371.584131 -287.75691)
			(xy 371.596529 -287.805869) (xy 371.600699 -287.8562) (xy 372.868937 -287.8562) (xy 372.873108 -287.80586)
			(xy 372.885507 -287.756893) (xy 372.905797 -287.710634) (xy 372.933423 -287.668346) (xy 372.967632 -287.631181)
			(xy 373.007492 -287.600153) (xy 373.051915 -287.576108) (xy 373.099689 -287.559703) (xy 373.149512 -287.551384)
			(xy 373.174768 -287.55086) (xy 374.114822 -287.55086) (xy 374.140073 -287.551447) (xy 374.189887 -287.559763)
			(xy 374.237653 -287.576164) (xy 374.282068 -287.600203) (xy 374.321921 -287.631224) (xy 374.356124 -287.668382)
			(xy 374.383746 -287.710662) (xy 374.404031 -287.756912) (xy 374.416429 -287.805869) (xy 374.420599 -287.8562)
			(xy 374.416429 -287.906531) (xy 374.404031 -287.955488) (xy 374.383746 -288.001738) (xy 374.356124 -288.044018)
			(xy 374.321921 -288.081176) (xy 374.282068 -288.112197) (xy 374.237653 -288.136236) (xy 374.189887 -288.152637)
			(xy 374.140073 -288.160953) (xy 374.114822 -288.161476) (xy 373.174768 -288.161476) (xy 373.149512 -288.161016)
			(xy 373.099689 -288.152697) (xy 373.051915 -288.136292) (xy 373.007492 -288.112247) (xy 372.967632 -288.081219)
			(xy 372.933423 -288.044054) (xy 372.905797 -288.001766) (xy 372.885507 -287.955507) (xy 372.873108 -287.90654)
			(xy 372.868937 -287.8562) (xy 371.600699 -287.8562) (xy 371.596529 -287.906531) (xy 371.584131 -287.95549)
			(xy 371.563844 -288.00174) (xy 371.536222 -288.044021) (xy 371.502017 -288.081179) (xy 371.462164 -288.1122)
			(xy 371.417748 -288.136238) (xy 371.369981 -288.152639) (xy 371.320166 -288.160953) (xy 371.294914 -288.161476)
			(xy 370.35486 -288.161476) (xy 370.329604 -288.161015) (xy 370.279782 -288.152695) (xy 370.232009 -288.136289)
			(xy 370.187588 -288.112244) (xy 370.147729 -288.081216) (xy 370.113521 -288.044052) (xy 370.085895 -288.001764)
			(xy 370.065607 -287.955506) (xy 370.053208 -287.906539) (xy 370.049037 -287.8562) (xy 368.780628 -287.8562)
			(xy 368.776456 -287.906543) (xy 368.764054 -287.955512) (xy 368.74376 -288.001771) (xy 368.716129 -288.044059)
			(xy 368.681913 -288.081222) (xy 368.642047 -288.112246) (xy 368.597617 -288.136283) (xy 368.549837 -288.15268)
			(xy 368.50001 -288.160987) (xy 368.474752 -288.161476) (xy 367.534698 -288.161476) (xy 367.50944 -288.161018)
			(xy 367.459613 -288.152703) (xy 367.411835 -288.136301) (xy 367.367408 -288.112258) (xy 367.327544 -288.08123)
			(xy 367.293331 -288.044064) (xy 367.265701 -288.001774) (xy 367.245409 -287.955513) (xy 367.233009 -287.906543)
			(xy 367.228837 -287.8562) (xy 365.960599 -287.8562) (xy 365.956429 -287.906528) (xy 365.944033 -287.955484)
			(xy 365.923749 -288.001732) (xy 365.89613 -288.044011) (xy 365.861929 -288.081168) (xy 365.82208 -288.112189)
			(xy 365.777668 -288.13623) (xy 365.729905 -288.152633) (xy 365.680094 -288.160951) (xy 365.654844 -288.161476)
			(xy 364.71479 -288.161476) (xy 364.689533 -288.161018) (xy 364.639707 -288.152702) (xy 364.591929 -288.136298)
			(xy 364.547503 -288.112255) (xy 364.507641 -288.081227) (xy 364.473429 -288.044062) (xy 364.4458 -288.001772)
			(xy 364.425509 -287.955512) (xy 364.413108 -287.906542) (xy 364.408937 -287.8562) (xy 355.626899 -287.8562)
			(xy 355.622728 -287.906532) (xy 355.610331 -287.955491) (xy 355.590043 -288.001742) (xy 355.56242 -288.044023)
			(xy 355.528215 -288.081181) (xy 355.48836 -288.112202) (xy 355.443943 -288.13624) (xy 355.396176 -288.15264)
			(xy 355.34636 -288.160954) (xy 355.321108 -288.161476) (xy 354.381054 -288.161476) (xy 354.355799 -288.161015)
			(xy 354.305977 -288.152694) (xy 354.258205 -288.136288) (xy 354.213784 -288.112242) (xy 354.173927 -288.081214)
			(xy 354.139719 -288.04405) (xy 354.112095 -288.001762) (xy 354.091806 -287.955504) (xy 354.079408 -287.906539)
			(xy 354.075237 -287.8562) (xy 352.806999 -287.8562) (xy 352.802828 -287.906533) (xy 352.79043 -287.955493)
			(xy 352.770142 -288.001744) (xy 352.742518 -288.044026) (xy 352.708312 -288.081184) (xy 352.668456 -288.112205)
			(xy 352.624038 -288.136243) (xy 352.576269 -288.152642) (xy 352.526453 -288.160955) (xy 352.5012 -288.161476)
			(xy 351.561146 -288.161476) (xy 351.535883 -288.161051) (xy 351.486046 -288.152741) (xy 351.438256 -288.136341)
			(xy 351.393817 -288.112298) (xy 351.353943 -288.081268) (xy 351.31972 -288.044098) (xy 351.292083 -288.001801)
			(xy 351.271785 -287.955532) (xy 351.259381 -287.906553) (xy 351.255208 -287.8562) (xy 349.987128 -287.8562)
			(xy 349.982957 -287.906538) (xy 349.970557 -287.955504) (xy 349.950266 -288.00176) (xy 349.922639 -288.044046)
			(xy 349.888429 -288.081208) (xy 349.848568 -288.112232) (xy 349.804144 -288.136271) (xy 349.75637 -288.152671)
			(xy 349.706548 -288.160984) (xy 349.681292 -288.161476) (xy 348.741238 -288.161476) (xy 348.715976 -288.16105)
			(xy 348.666139 -288.15274) (xy 348.61835 -288.136339) (xy 348.573913 -288.112296) (xy 348.53404 -288.081266)
			(xy 348.499818 -288.044095) (xy 348.472182 -288.001799) (xy 348.451885 -287.955531) (xy 348.439481 -287.906552)
			(xy 348.435308 -287.8562) (xy 347.166899 -287.8562) (xy 347.162729 -287.90653) (xy 347.150332 -287.955487)
			(xy 347.130047 -288.001736) (xy 347.102426 -288.044016) (xy 347.068224 -288.081173) (xy 347.028372 -288.112194)
			(xy 346.983958 -288.136234) (xy 346.936194 -288.152635) (xy 346.886381 -288.160952) (xy 346.86113 -288.161476)
			(xy 345.921076 -288.161476) (xy 345.895819 -288.161016) (xy 345.845995 -288.152699) (xy 345.79822 -288.136294)
			(xy 345.753796 -288.11225) (xy 345.713935 -288.081222) (xy 345.679725 -288.044057) (xy 345.652098 -288.001768)
			(xy 345.631808 -287.955509) (xy 345.619408 -287.906541) (xy 345.615237 -287.8562) (xy 126.48092 -287.8562)
			(xy 126.480937 -287.8564) (xy 126.47676 -287.906793) (xy 126.464346 -287.955812) (xy 126.444032 -288.002118)
			(xy 126.416373 -288.044448) (xy 126.382123 -288.081648) (xy 126.342216 -288.112703) (xy 126.297743 -288.136765)
			(xy 126.249914 -288.153178) (xy 126.200037 -288.161494) (xy 126.174754 -288.161984) (xy 125.2347 -288.161984)
			(xy 125.209425 -288.161418) (xy 125.159566 -288.153098) (xy 125.111756 -288.136685) (xy 125.067299 -288.112626)
			(xy 125.027409 -288.081578) (xy 124.993173 -288.044388) (xy 124.965525 -288.00207) (xy 124.94522 -287.955779)
			(xy 124.932811 -287.906776) (xy 124.928637 -287.8564) (xy 123.660908 -287.8564) (xy 123.656733 -287.906779)
			(xy 123.644325 -287.955784) (xy 123.62402 -288.002078) (xy 123.596374 -288.0444) (xy 123.562139 -288.081594)
			(xy 123.522249 -288.112647) (xy 123.477793 -288.136711) (xy 123.429983 -288.153131) (xy 123.380122 -288.161458)
			(xy 123.354846 -288.161984) (xy 122.414792 -288.161984) (xy 122.389518 -288.161418) (xy 122.339659 -288.153096)
			(xy 122.29185 -288.136682) (xy 122.247395 -288.112623) (xy 122.207506 -288.081575) (xy 122.173271 -288.044385)
			(xy 122.145624 -288.002068) (xy 122.125319 -287.955777) (xy 122.112911 -287.906776) (xy 122.108736 -287.8564)
			(xy 120.840837 -287.8564) (xy 120.836661 -287.90679) (xy 120.824248 -287.955806) (xy 120.803937 -288.002109)
			(xy 120.776281 -288.044438) (xy 120.742034 -288.081638) (xy 120.702132 -288.112693) (xy 120.657663 -288.136756)
			(xy 120.609839 -288.153172) (xy 120.559965 -288.161492) (xy 120.534684 -288.161984) (xy 119.59463 -288.161984)
			(xy 119.569351 -288.161449) (xy 119.519483 -288.153132) (xy 119.471664 -288.13672) (xy 119.427199 -288.112661)
			(xy 119.387301 -288.08161) (xy 119.353058 -288.044416) (xy 119.325404 -288.002092) (xy 119.305094 -287.955794)
			(xy 119.292683 -287.906784) (xy 119.288507 -287.8564) (xy 118.020937 -287.8564) (xy 118.016761 -287.906791)
			(xy 118.004348 -287.955807) (xy 117.984035 -288.002112) (xy 117.956378 -288.044441) (xy 117.922131 -288.081641)
			(xy 117.882228 -288.112696) (xy 117.837757 -288.136759) (xy 117.789932 -288.153174) (xy 117.740058 -288.161493)
			(xy 117.714776 -288.161984) (xy 116.774722 -288.161984) (xy 116.749444 -288.161449) (xy 116.699577 -288.153131)
			(xy 116.651759 -288.136718) (xy 116.607295 -288.112658) (xy 116.567398 -288.081607) (xy 116.533156 -288.044413)
			(xy 116.505503 -288.00209) (xy 116.485194 -287.955792) (xy 116.472783 -287.906783) (xy 116.468607 -287.8564)
			(xy 107.687108 -287.8564) (xy 107.682933 -287.906779) (xy 107.670524 -287.955785) (xy 107.65022 -288.00208)
			(xy 107.622572 -288.044402) (xy 107.588336 -288.081596) (xy 107.548446 -288.112649) (xy 107.503989 -288.136713)
			(xy 107.456178 -288.153132) (xy 107.406316 -288.161459) (xy 107.38104 -288.161984) (xy 106.440986 -288.161984)
			(xy 106.415712 -288.161417) (xy 106.365854 -288.153095) (xy 106.318046 -288.136681) (xy 106.273592 -288.112621)
			(xy 106.233703 -288.081573) (xy 106.199469 -288.044383) (xy 106.171823 -288.002066) (xy 106.151519 -287.955776)
			(xy 106.139111 -287.906775) (xy 106.134936 -287.8564) (xy 104.867208 -287.8564) (xy 104.863033 -287.90678)
			(xy 104.850624 -287.955787) (xy 104.830318 -288.002082) (xy 104.80267 -288.044404) (xy 104.768433 -288.081599)
			(xy 104.728542 -288.112652) (xy 104.684084 -288.136716) (xy 104.636271 -288.153134) (xy 104.586408 -288.161459)
			(xy 104.561132 -288.161984) (xy 103.621078 -288.161984) (xy 103.595805 -288.161416) (xy 103.545948 -288.153093)
			(xy 103.498141 -288.136678) (xy 103.453687 -288.112618) (xy 103.4138 -288.08157) (xy 103.379567 -288.044381)
			(xy 103.351922 -288.002064) (xy 103.331618 -287.955774) (xy 103.31921 -287.906774) (xy 103.315036 -287.8564)
			(xy 102.047308 -287.8564) (xy 102.043133 -287.906781) (xy 102.030723 -287.955788) (xy 102.010417 -288.002084)
			(xy 101.982768 -288.044407) (xy 101.94853 -288.081602) (xy 101.908638 -288.112655) (xy 101.864178 -288.136718)
			(xy 101.816365 -288.153136) (xy 101.766501 -288.16146) (xy 101.741224 -288.161984) (xy 100.80117 -288.161984)
			(xy 100.775897 -288.161416) (xy 100.726041 -288.153092) (xy 100.678235 -288.136676) (xy 100.633783 -288.112616)
			(xy 100.593897 -288.081568) (xy 100.559665 -288.044378) (xy 100.532021 -288.002062) (xy 100.511718 -287.955773)
			(xy 100.49931 -287.906773) (xy 100.495136 -287.8564) (xy 99.227237 -287.8564) (xy 99.223061 -287.906792)
			(xy 99.210647 -287.95581) (xy 99.190333 -288.002115) (xy 99.162675 -288.044446) (xy 99.128426 -288.081646)
			(xy 99.088521 -288.1127) (xy 99.044048 -288.136763) (xy 98.996221 -288.153177) (xy 98.946345 -288.161494)
			(xy 98.921062 -288.161984) (xy 97.981008 -288.161984) (xy 97.955731 -288.161448) (xy 97.905865 -288.153128)
			(xy 97.858049 -288.136714) (xy 97.813588 -288.112653) (xy 97.773692 -288.081602) (xy 97.739452 -288.044409)
			(xy 97.711801 -288.002086) (xy 97.691493 -287.95579) (xy 97.679082 -287.906782) (xy 97.674907 -287.8564)
			(xy 2.509012 -287.8564) (xy 2.509012 -288.6662) (xy 108.484888 -288.6662) (xy 108.489063 -288.615816)
			(xy 108.501474 -288.566807) (xy 108.521782 -288.520509) (xy 108.549433 -288.478184) (xy 108.583674 -288.440989)
			(xy 108.62357 -288.409936) (xy 108.668032 -288.385873) (xy 108.715849 -288.369457) (xy 108.765716 -288.361134)
			(xy 108.790994 -288.360612) (xy 109.731048 -288.360612) (xy 109.75632 -288.36119) (xy 109.806172 -288.369516)
			(xy 109.853975 -288.385933) (xy 109.898424 -288.409994) (xy 109.938307 -288.441042) (xy 109.972536 -288.47823)
			(xy 110.000179 -288.520545) (xy 110.02048 -288.566832) (xy 110.032886 -288.615829) (xy 110.03706 -288.6662)
			(xy 114.118559 -288.6662) (xy 114.122735 -288.615809) (xy 114.135148 -288.566794) (xy 114.15546 -288.520489)
			(xy 114.183116 -288.47816) (xy 114.217362 -288.44096) (xy 114.257264 -288.409905) (xy 114.301734 -288.385841)
			(xy 114.349558 -288.369424) (xy 114.399432 -288.361104) (xy 114.424714 -288.360612) (xy 115.364768 -288.360612)
			(xy 115.390046 -288.361154) (xy 115.439914 -288.369471) (xy 115.487733 -288.385883) (xy 115.532198 -288.409942)
			(xy 115.572096 -288.440992) (xy 115.606339 -288.478186) (xy 115.633992 -288.520509) (xy 115.654302 -288.566807)
			(xy 115.666713 -288.615816) (xy 115.670864 -288.6659) (xy 356.425289 -288.6659) (xy 356.429459 -288.615569)
			(xy 356.441856 -288.566611) (xy 356.462142 -288.520361) (xy 356.489762 -288.47808) (xy 356.523965 -288.440921)
			(xy 356.563817 -288.409898) (xy 356.608231 -288.385858) (xy 356.655997 -288.369455) (xy 356.70581 -288.361136)
			(xy 356.731062 -288.360612) (xy 357.671116 -288.360612) (xy 357.696372 -288.361095) (xy 357.746195 -288.369411)
			(xy 357.79397 -288.385815) (xy 357.838393 -288.409857) (xy 357.878253 -288.440884) (xy 357.912464 -288.478048)
			(xy 357.94009 -288.520335) (xy 357.96038 -288.566594) (xy 357.97278 -288.61556) (xy 357.976951 -288.6659)
			(xy 362.058989 -288.6659) (xy 362.06316 -288.615567) (xy 362.075557 -288.566607) (xy 362.095845 -288.520355)
			(xy 362.123467 -288.478073) (xy 362.157673 -288.440914) (xy 362.197528 -288.409892) (xy 362.241945 -288.385852)
			(xy 362.289713 -288.36945) (xy 362.339529 -288.361135) (xy 362.364782 -288.360612) (xy 363.304836 -288.360612)
			(xy 363.330091 -288.361096) (xy 363.379911 -288.369415) (xy 363.427683 -288.38582) (xy 363.472104 -288.409864)
			(xy 363.511961 -288.440891) (xy 363.546169 -288.478054) (xy 363.573793 -288.520341) (xy 363.594082 -288.566598)
			(xy 363.60648 -288.615562) (xy 363.610651 -288.6659) (xy 363.60648 -288.716238) (xy 363.594082 -288.765202)
			(xy 363.573793 -288.811459) (xy 363.546169 -288.853746) (xy 363.511961 -288.890909) (xy 363.472104 -288.921936)
			(xy 363.427683 -288.94598) (xy 363.379911 -288.962385) (xy 363.330091 -288.970704) (xy 363.304836 -288.971228)
			(xy 362.364782 -288.971228) (xy 362.339529 -288.970665) (xy 362.289713 -288.96235) (xy 362.241945 -288.945948)
			(xy 362.197528 -288.921908) (xy 362.157673 -288.890886) (xy 362.123467 -288.853727) (xy 362.095845 -288.811445)
			(xy 362.075557 -288.765193) (xy 362.06316 -288.716233) (xy 362.058989 -288.6659) (xy 357.976951 -288.6659)
			(xy 357.97278 -288.71624) (xy 357.96038 -288.765206) (xy 357.94009 -288.811465) (xy 357.912464 -288.853752)
			(xy 357.878253 -288.890916) (xy 357.838393 -288.921943) (xy 357.79397 -288.945985) (xy 357.746195 -288.962389)
			(xy 357.696372 -288.970705) (xy 357.671116 -288.971228) (xy 356.731062 -288.971228) (xy 356.70581 -288.970664)
			(xy 356.655997 -288.962345) (xy 356.608231 -288.945942) (xy 356.563817 -288.921902) (xy 356.523965 -288.890879)
			(xy 356.489762 -288.85372) (xy 356.462142 -288.811439) (xy 356.441856 -288.765189) (xy 356.429459 -288.716231)
			(xy 356.425289 -288.6659) (xy 115.670864 -288.6659) (xy 115.670889 -288.6662) (xy 115.666713 -288.716584)
			(xy 115.654302 -288.765593) (xy 115.633992 -288.811891) (xy 115.606339 -288.854214) (xy 115.572096 -288.891408)
			(xy 115.532198 -288.922458) (xy 115.487733 -288.946517) (xy 115.439914 -288.962929) (xy 115.390046 -288.971246)
			(xy 115.364768 -288.971736) (xy 114.424714 -288.971736) (xy 114.399432 -288.971296) (xy 114.349558 -288.962976)
			(xy 114.301734 -288.946559) (xy 114.257264 -288.922495) (xy 114.217362 -288.89144) (xy 114.183116 -288.85424)
			(xy 114.15546 -288.811911) (xy 114.135148 -288.765606) (xy 114.122735 -288.716591) (xy 114.118559 -288.6662)
			(xy 110.03706 -288.6662) (xy 110.032886 -288.716571) (xy 110.02048 -288.765568) (xy 110.000179 -288.811855)
			(xy 109.972536 -288.85417) (xy 109.938307 -288.891358) (xy 109.898424 -288.922406) (xy 109.853975 -288.946467)
			(xy 109.806172 -288.962884) (xy 109.75632 -288.97121) (xy 109.731048 -288.971736) (xy 108.790994 -288.971736)
			(xy 108.765716 -288.971266) (xy 108.715849 -288.962943) (xy 108.668032 -288.946527) (xy 108.62357 -288.922464)
			(xy 108.583674 -288.891411) (xy 108.549433 -288.854216) (xy 108.521782 -288.811891) (xy 108.501474 -288.765593)
			(xy 108.489063 -288.716584) (xy 108.484888 -288.6662) (xy 2.509012 -288.6662) (xy 2.509012 -289.4762)
			(xy 97.67512 -289.4762) (xy 97.679292 -289.425853) (xy 97.691694 -289.376879) (xy 97.711988 -289.330615)
			(xy 97.73962 -289.288322) (xy 97.773836 -289.251154) (xy 97.813704 -289.220125) (xy 97.858135 -289.196081)
			(xy 97.905917 -289.179678) (xy 97.955748 -289.171364) (xy 97.981008 -289.170872) (xy 98.921062 -289.170872)
			(xy 98.94632 -289.171402) (xy 98.996148 -289.179711) (xy 99.043929 -289.196109) (xy 99.088359 -289.220148)
			(xy 99.128225 -289.251173) (xy 99.162441 -289.288337) (xy 99.190073 -289.330626) (xy 99.210366 -289.376886)
			(xy 99.222768 -289.425856) (xy 99.22694 -289.4762) (xy 100.495349 -289.4762) (xy 100.49952 -289.425862)
			(xy 100.511919 -289.376896) (xy 100.532208 -289.330639) (xy 100.559833 -289.288352) (xy 100.594041 -289.251189)
			(xy 100.633899 -289.220162) (xy 100.678321 -289.196119) (xy 100.726093 -289.179714) (xy 100.775915 -289.171396)
			(xy 100.80117 -289.170872) (xy 101.741224 -289.170872) (xy 101.766476 -289.171435) (xy 101.816292 -289.179752)
			(xy 101.864059 -289.196154) (xy 101.908475 -289.220194) (xy 101.948329 -289.251216) (xy 101.982534 -289.288375)
			(xy 102.010156 -289.330657) (xy 102.030443 -289.376908) (xy 102.042841 -289.425868) (xy 102.047011 -289.4762)
			(xy 103.315249 -289.4762) (xy 103.31942 -289.425861) (xy 103.331819 -289.376895) (xy 103.352109 -289.330637)
			(xy 103.379735 -289.28835) (xy 103.413944 -289.251186) (xy 103.453804 -289.220159) (xy 103.498226 -289.196116)
			(xy 103.546 -289.179713) (xy 103.595822 -289.171395) (xy 103.621078 -289.170872) (xy 104.561132 -289.170872)
			(xy 104.586384 -289.171436) (xy 104.636198 -289.179753) (xy 104.683965 -289.196156) (xy 104.72838 -289.220196)
			(xy 104.768233 -289.251219) (xy 104.802436 -289.288378) (xy 104.830058 -289.330659) (xy 104.850344 -289.37691)
			(xy 104.862741 -289.425868) (xy 104.866911 -289.4762) (xy 106.135149 -289.4762) (xy 106.13932 -289.42586)
			(xy 106.15172 -289.376893) (xy 106.17201 -289.330635) (xy 106.199637 -289.288347) (xy 106.233847 -289.251183)
			(xy 106.273708 -289.220157) (xy 106.318132 -289.196114) (xy 106.365907 -289.179711) (xy 106.41573 -289.171395)
			(xy 106.440986 -289.170872) (xy 107.38104 -289.170872) (xy 107.406291 -289.171437) (xy 107.456105 -289.179755)
			(xy 107.50387 -289.196158) (xy 107.548284 -289.220199) (xy 107.588136 -289.251222) (xy 107.622338 -289.28838)
			(xy 107.649959 -289.330661) (xy 107.670244 -289.376911) (xy 107.682641 -289.425869) (xy 107.686811 -289.4762)
			(xy 116.46882 -289.4762) (xy 116.472992 -289.425852) (xy 116.485395 -289.376877) (xy 116.50569 -289.330611)
			(xy 116.533323 -289.288317) (xy 116.567542 -289.251149) (xy 116.607411 -289.22012) (xy 116.651844 -289.196077)
			(xy 116.699629 -289.179675) (xy 116.749461 -289.171363) (xy 116.774722 -289.170872) (xy 117.714776 -289.170872)
			(xy 117.740033 -289.171403) (xy 117.78986 -289.179714) (xy 117.837638 -289.196113) (xy 117.882066 -289.220153)
			(xy 117.92193 -289.251178) (xy 117.956145 -289.288341) (xy 117.983775 -289.33063) (xy 118.004067 -289.376889)
			(xy 118.016468 -289.425858) (xy 118.02064 -289.4762) (xy 119.28872 -289.4762) (xy 119.292892 -289.425851)
			(xy 119.305295 -289.376875) (xy 119.325591 -289.330609) (xy 119.353225 -289.288315) (xy 119.387445 -289.251146)
			(xy 119.427315 -289.220117) (xy 119.47175 -289.196074) (xy 119.519535 -289.179674) (xy 119.569369 -289.171362)
			(xy 119.59463 -289.170872) (xy 120.534684 -289.170872) (xy 120.559941 -289.171403) (xy 120.609766 -289.179715)
			(xy 120.657544 -289.196115) (xy 120.70197 -289.220155) (xy 120.741834 -289.25118) (xy 120.776047 -289.288344)
			(xy 120.803676 -289.330632) (xy 120.823968 -289.376891) (xy 120.836368 -289.425859) (xy 120.84054 -289.4762)
			(xy 122.108949 -289.4762) (xy 122.11312 -289.425859) (xy 122.12552 -289.376892) (xy 122.145811 -289.330633)
			(xy 122.173439 -289.288345) (xy 122.20765 -289.251181) (xy 122.247511 -289.220155) (xy 122.291936 -289.196112)
			(xy 122.339711 -289.17971) (xy 122.389535 -289.171394) (xy 122.414792 -289.170872) (xy 123.354846 -289.170872)
			(xy 123.380097 -289.171437) (xy 123.42991 -289.179756) (xy 123.477674 -289.19616) (xy 123.522087 -289.220201)
			(xy 123.561938 -289.251224) (xy 123.59614 -289.288382) (xy 123.62376 -289.330663) (xy 123.644044 -289.376913)
			(xy 123.656441 -289.42587) (xy 123.660611 -289.4762) (xy 124.928849 -289.4762) (xy 124.93302 -289.425859)
			(xy 124.945421 -289.37689) (xy 124.965712 -289.330631) (xy 124.993341 -289.288342) (xy 125.027553 -289.251178)
			(xy 125.067415 -289.220152) (xy 125.111841 -289.19611) (xy 125.159618 -289.179708) (xy 125.209443 -289.171394)
			(xy 125.2347 -289.170872) (xy 126.174754 -289.170872) (xy 126.200013 -289.171401) (xy 126.249842 -289.179709)
			(xy 126.297623 -289.196106) (xy 126.342054 -289.220145) (xy 126.381922 -289.25117) (xy 126.416139 -289.288334)
			(xy 126.443771 -289.330623) (xy 126.464066 -289.376885) (xy 126.476468 -289.425856) (xy 126.480615 -289.4759)
			(xy 345.61504 -289.4759) (xy 345.619214 -289.425527) (xy 345.631622 -289.376527) (xy 345.651925 -289.330238)
			(xy 345.67957 -289.287922) (xy 345.713802 -289.250733) (xy 345.753689 -289.219686) (xy 345.798141 -289.195626)
			(xy 345.845947 -289.179211) (xy 345.895803 -289.170888) (xy 345.921076 -289.170364) (xy 346.86113 -289.170364)
			(xy 346.886407 -289.170836) (xy 346.93627 -289.179162) (xy 346.984084 -289.19558) (xy 347.028543 -289.219644)
			(xy 347.068435 -289.250697) (xy 347.102673 -289.287892) (xy 347.130322 -289.330215) (xy 347.150628 -289.376512)
			(xy 347.163037 -289.425519) (xy 347.167212 -289.4759) (xy 348.435111 -289.4759) (xy 348.439287 -289.425516)
			(xy 348.451699 -289.376506) (xy 348.472009 -289.330207) (xy 348.499663 -289.287884) (xy 348.533907 -289.25069)
			(xy 348.573806 -289.21964) (xy 348.618271 -289.195581) (xy 348.666091 -289.17917) (xy 348.715959 -289.170854)
			(xy 348.741238 -289.170364) (xy 349.681292 -289.170364) (xy 349.706573 -289.170804) (xy 349.756447 -289.179126)
			(xy 349.80427 -289.195542) (xy 349.848739 -289.219607) (xy 349.88864 -289.250662) (xy 349.922886 -289.287862)
			(xy 349.950541 -289.330191) (xy 349.970852 -289.376495) (xy 349.983265 -289.42551) (xy 349.987441 -289.4759)
			(xy 351.255011 -289.4759) (xy 351.259187 -289.425515) (xy 351.271599 -289.376504) (xy 351.29191 -289.330205)
			(xy 351.319565 -289.287881) (xy 351.35381 -289.250687) (xy 351.39371 -289.219637) (xy 351.438177 -289.195579)
			(xy 351.485997 -289.179168) (xy 351.535867 -289.170853) (xy 351.561146 -289.170364) (xy 352.5012 -289.170364)
			(xy 352.526478 -289.170834) (xy 352.576346 -289.179155) (xy 352.624164 -289.195571) (xy 352.668627 -289.219634)
			(xy 352.708524 -289.250686) (xy 352.742765 -289.287882) (xy 352.770417 -289.330207) (xy 352.790726 -289.376506)
			(xy 352.803137 -289.425516) (xy 352.807312 -289.4759) (xy 354.07504 -289.4759) (xy 354.079214 -289.425529)
			(xy 354.09162 -289.376532) (xy 354.111922 -289.330245) (xy 354.139564 -289.28793) (xy 354.173794 -289.250741)
			(xy 354.213677 -289.219693) (xy 354.258126 -289.195633) (xy 354.305929 -289.179215) (xy 354.355782 -289.170889)
			(xy 354.381054 -289.170364) (xy 355.321108 -289.170364) (xy 355.346386 -289.170835) (xy 355.396252 -289.179157)
			(xy 355.444069 -289.195574) (xy 355.488531 -289.219636) (xy 355.528427 -289.250689) (xy 355.562667 -289.287885)
			(xy 355.590318 -289.330209) (xy 355.610626 -289.376507) (xy 355.623037 -289.425517) (xy 355.627212 -289.4759)
			(xy 364.40874 -289.4759) (xy 364.412915 -289.425525) (xy 364.425323 -289.376525) (xy 364.445627 -289.330235)
			(xy 364.473273 -289.287918) (xy 364.507508 -289.250728) (xy 364.547396 -289.219681) (xy 364.591851 -289.195622)
			(xy 364.639659 -289.179208) (xy 364.689516 -289.170887) (xy 364.71479 -289.170364) (xy 365.654844 -289.170364)
			(xy 365.68012 -289.170837) (xy 365.729982 -289.179165) (xy 365.777793 -289.195584) (xy 365.82225 -289.219649)
			(xy 365.862141 -289.250702) (xy 365.896376 -289.287897) (xy 365.924024 -289.330219) (xy 365.944329 -289.376515)
			(xy 365.956737 -289.42552) (xy 365.960912 -289.4759) (xy 367.22864 -289.4759) (xy 367.232815 -289.425524)
			(xy 367.245224 -289.376523) (xy 367.265528 -289.330232) (xy 367.293176 -289.287915) (xy 367.327411 -289.250725)
			(xy 367.3673 -289.219678) (xy 367.411756 -289.195619) (xy 367.459565 -289.179206) (xy 367.509424 -289.170886)
			(xy 367.534698 -289.170364) (xy 368.474752 -289.170364) (xy 368.500035 -289.170801) (xy 368.549914 -289.179117)
			(xy 368.597743 -289.19553) (xy 368.642218 -289.219593) (xy 368.682125 -289.250648) (xy 368.716375 -289.287849)
			(xy 368.744035 -289.33018) (xy 368.76435 -289.376487) (xy 368.776764 -289.425506) (xy 368.780941 -289.4759)
			(xy 370.04884 -289.4759) (xy 370.053014 -289.425528) (xy 370.065421 -289.376531) (xy 370.085723 -289.330243)
			(xy 370.113366 -289.287928) (xy 370.147596 -289.250739) (xy 370.18748 -289.219691) (xy 370.23193 -289.195631)
			(xy 370.279734 -289.179214) (xy 370.329588 -289.170889) (xy 370.35486 -289.170364) (xy 371.294914 -289.170364)
			(xy 371.320192 -289.170835) (xy 371.370057 -289.179158) (xy 371.417873 -289.195575) (xy 371.462335 -289.219639)
			(xy 371.502229 -289.250691) (xy 371.536469 -289.287887) (xy 371.564119 -289.330211) (xy 371.584426 -289.376509)
			(xy 371.596837 -289.425517) (xy 371.601012 -289.4759) (xy 372.86874 -289.4759) (xy 372.872914 -289.425528)
			(xy 372.885321 -289.376529) (xy 372.905624 -289.330241) (xy 372.933268 -289.287925) (xy 372.967499 -289.250736)
			(xy 373.007384 -289.219688) (xy 373.051836 -289.195628) (xy 373.099641 -289.179212) (xy 373.149496 -289.170888)
			(xy 373.174768 -289.170364) (xy 374.114822 -289.170364) (xy 374.140099 -289.170836) (xy 374.189964 -289.17916)
			(xy 374.237778 -289.195578) (xy 374.282239 -289.219641) (xy 374.322132 -289.250694) (xy 374.356371 -289.28789)
			(xy 374.38402 -289.330213) (xy 374.404327 -289.37651) (xy 374.416737 -289.425518) (xy 374.420912 -289.4759)
			(xy 374.416737 -289.526282) (xy 374.404327 -289.57529) (xy 374.38402 -289.621587) (xy 374.356371 -289.66391)
			(xy 374.322132 -289.701106) (xy 374.282239 -289.732159) (xy 374.237778 -289.756222) (xy 374.189964 -289.77264)
			(xy 374.140099 -289.780964) (xy 374.114822 -289.781488) (xy 373.174768 -289.781488) (xy 373.149496 -289.780912)
			(xy 373.099641 -289.772588) (xy 373.051836 -289.756172) (xy 373.007384 -289.732112) (xy 372.967499 -289.701064)
			(xy 372.933268 -289.663875) (xy 372.905624 -289.621559) (xy 372.885321 -289.575271) (xy 372.872914 -289.526272)
			(xy 372.86874 -289.4759) (xy 371.601012 -289.4759) (xy 371.596837 -289.526283) (xy 371.584426 -289.575291)
			(xy 371.564119 -289.621589) (xy 371.536469 -289.663913) (xy 371.502229 -289.701109) (xy 371.462335 -289.732161)
			(xy 371.417873 -289.756225) (xy 371.370057 -289.772642) (xy 371.320192 -289.780965) (xy 371.294914 -289.781488)
			(xy 370.35486 -289.781488) (xy 370.329588 -289.780911) (xy 370.279734 -289.772586) (xy 370.23193 -289.756169)
			(xy 370.18748 -289.732109) (xy 370.147596 -289.701061) (xy 370.113366 -289.663872) (xy 370.085723 -289.621557)
			(xy 370.065421 -289.575269) (xy 370.053014 -289.526272) (xy 370.04884 -289.4759) (xy 368.780941 -289.4759)
			(xy 368.776764 -289.526294) (xy 368.76435 -289.575313) (xy 368.744035 -289.62162) (xy 368.716375 -289.663951)
			(xy 368.682125 -289.701152) (xy 368.642218 -289.732207) (xy 368.597743 -289.75627) (xy 368.549914 -289.772683)
			(xy 368.500035 -289.780999) (xy 368.474752 -289.781488) (xy 367.534698 -289.781488) (xy 367.509424 -289.780914)
			(xy 367.459565 -289.772594) (xy 367.411756 -289.756181) (xy 367.3673 -289.732122) (xy 367.327411 -289.701075)
			(xy 367.293176 -289.663885) (xy 367.265528 -289.621568) (xy 367.245224 -289.575277) (xy 367.232815 -289.526276)
			(xy 367.22864 -289.4759) (xy 365.960912 -289.4759) (xy 365.956737 -289.52628) (xy 365.944329 -289.575285)
			(xy 365.924024 -289.621581) (xy 365.896376 -289.663903) (xy 365.862141 -289.701098) (xy 365.82225 -289.732151)
			(xy 365.777793 -289.756216) (xy 365.729982 -289.772635) (xy 365.68012 -289.780963) (xy 365.654844 -289.781488)
			(xy 364.71479 -289.781488) (xy 364.689516 -289.780913) (xy 364.639659 -289.772592) (xy 364.591851 -289.756178)
			(xy 364.547396 -289.732119) (xy 364.507508 -289.701072) (xy 364.473273 -289.663882) (xy 364.445627 -289.621565)
			(xy 364.425323 -289.575275) (xy 364.412915 -289.526275) (xy 364.40874 -289.4759) (xy 355.627212 -289.4759)
			(xy 355.623037 -289.526283) (xy 355.610626 -289.575293) (xy 355.590318 -289.621591) (xy 355.562667 -289.663915)
			(xy 355.528427 -289.701111) (xy 355.488531 -289.732164) (xy 355.444069 -289.756226) (xy 355.396252 -289.772643)
			(xy 355.346386 -289.780965) (xy 355.321108 -289.781488) (xy 354.381054 -289.781488) (xy 354.355782 -289.780911)
			(xy 354.305929 -289.772585) (xy 354.258126 -289.756167) (xy 354.213677 -289.732107) (xy 354.173794 -289.701059)
			(xy 354.139564 -289.66387) (xy 354.111922 -289.621555) (xy 354.09162 -289.575268) (xy 354.079214 -289.526271)
			(xy 354.07504 -289.4759) (xy 352.807312 -289.4759) (xy 352.803137 -289.526284) (xy 352.790726 -289.575294)
			(xy 352.770417 -289.621593) (xy 352.742765 -289.663918) (xy 352.708524 -289.701114) (xy 352.668627 -289.732166)
			(xy 352.624164 -289.756229) (xy 352.576346 -289.772645) (xy 352.526478 -289.780966) (xy 352.5012 -289.781488)
			(xy 351.561146 -289.781488) (xy 351.535867 -289.780947) (xy 351.485997 -289.772632) (xy 351.438177 -289.756221)
			(xy 351.39371 -289.732163) (xy 351.35381 -289.701113) (xy 351.319565 -289.663919) (xy 351.29191 -289.621595)
			(xy 351.271599 -289.575296) (xy 351.259187 -289.526285) (xy 351.255011 -289.4759) (xy 349.987441 -289.4759)
			(xy 349.983265 -289.52629) (xy 349.970852 -289.575305) (xy 349.950541 -289.621609) (xy 349.922886 -289.663938)
			(xy 349.88864 -289.701138) (xy 349.848739 -289.732193) (xy 349.80427 -289.756258) (xy 349.756447 -289.772674)
			(xy 349.706573 -289.780996) (xy 349.681292 -289.781488) (xy 348.741238 -289.781488) (xy 348.715959 -289.780946)
			(xy 348.666091 -289.77263) (xy 348.618271 -289.756219) (xy 348.573806 -289.73216) (xy 348.533907 -289.70111)
			(xy 348.499663 -289.663916) (xy 348.472009 -289.621593) (xy 348.451699 -289.575294) (xy 348.439287 -289.526284)
			(xy 348.435111 -289.4759) (xy 347.167212 -289.4759) (xy 347.163037 -289.526281) (xy 347.150628 -289.575288)
			(xy 347.130322 -289.621585) (xy 347.102673 -289.663908) (xy 347.068435 -289.701103) (xy 347.028543 -289.732156)
			(xy 346.984084 -289.75622) (xy 346.93627 -289.772638) (xy 346.886407 -289.780964) (xy 346.86113 -289.781488)
			(xy 345.921076 -289.781488) (xy 345.895803 -289.780912) (xy 345.845947 -289.772589) (xy 345.798141 -289.756174)
			(xy 345.753689 -289.732114) (xy 345.713802 -289.701067) (xy 345.67957 -289.663878) (xy 345.651925 -289.621562)
			(xy 345.631622 -289.575273) (xy 345.619214 -289.526273) (xy 345.61504 -289.4759) (xy 126.480615 -289.4759)
			(xy 126.48064 -289.4762) (xy 126.476468 -289.526544) (xy 126.464066 -289.575515) (xy 126.443771 -289.621777)
			(xy 126.416139 -289.664066) (xy 126.381922 -289.70123) (xy 126.342054 -289.732255) (xy 126.297623 -289.756294)
			(xy 126.249842 -289.772691) (xy 126.200013 -289.780999) (xy 126.174754 -289.781488) (xy 125.2347 -289.781488)
			(xy 125.209443 -289.781006) (xy 125.159618 -289.772692) (xy 125.111841 -289.75629) (xy 125.067415 -289.732248)
			(xy 125.027553 -289.701222) (xy 124.993341 -289.664058) (xy 124.965712 -289.621769) (xy 124.945421 -289.57551)
			(xy 124.93302 -289.526541) (xy 124.928849 -289.4762) (xy 123.660611 -289.4762) (xy 123.656441 -289.52653)
			(xy 123.644044 -289.575487) (xy 123.62376 -289.621737) (xy 123.59614 -289.664018) (xy 123.561938 -289.701176)
			(xy 123.522087 -289.732199) (xy 123.477674 -289.75624) (xy 123.42991 -289.772644) (xy 123.380097 -289.780963)
			(xy 123.354846 -289.781488) (xy 122.414792 -289.781488) (xy 122.389535 -289.781006) (xy 122.339711 -289.77269)
			(xy 122.291936 -289.756288) (xy 122.247511 -289.732245) (xy 122.20765 -289.701219) (xy 122.173439 -289.664055)
			(xy 122.145811 -289.621767) (xy 122.12552 -289.575508) (xy 122.11312 -289.526541) (xy 122.108949 -289.4762)
			(xy 120.84054 -289.4762) (xy 120.836368 -289.526541) (xy 120.823968 -289.575509) (xy 120.803676 -289.621768)
			(xy 120.776047 -289.664056) (xy 120.741834 -289.70122) (xy 120.70197 -289.732245) (xy 120.657544 -289.756285)
			(xy 120.609766 -289.772685) (xy 120.559941 -289.780997) (xy 120.534684 -289.781488) (xy 119.59463 -289.781488)
			(xy 119.569369 -289.781038) (xy 119.519535 -289.772726) (xy 119.47175 -289.756326) (xy 119.427315 -289.732283)
			(xy 119.387445 -289.701254) (xy 119.353225 -289.664085) (xy 119.325591 -289.621791) (xy 119.305295 -289.575525)
			(xy 119.292892 -289.526549) (xy 119.28872 -289.4762) (xy 118.02064 -289.4762) (xy 118.016468 -289.526542)
			(xy 118.004067 -289.575511) (xy 117.983775 -289.62177) (xy 117.956145 -289.664059) (xy 117.92193 -289.701222)
			(xy 117.882066 -289.732247) (xy 117.837638 -289.756287) (xy 117.78986 -289.772686) (xy 117.740033 -289.780997)
			(xy 117.714776 -289.781488) (xy 116.774722 -289.781488) (xy 116.749461 -289.781037) (xy 116.699629 -289.772725)
			(xy 116.651844 -289.756323) (xy 116.607411 -289.73228) (xy 116.567542 -289.701251) (xy 116.533323 -289.664083)
			(xy 116.50569 -289.621789) (xy 116.485395 -289.575523) (xy 116.472992 -289.526548) (xy 116.46882 -289.4762)
			(xy 107.686811 -289.4762) (xy 107.682641 -289.526531) (xy 107.670244 -289.575489) (xy 107.649959 -289.621739)
			(xy 107.622338 -289.66402) (xy 107.588136 -289.701178) (xy 107.548284 -289.732201) (xy 107.50387 -289.756242)
			(xy 107.456105 -289.772645) (xy 107.406292 -289.780963) (xy 107.38104 -289.781488) (xy 106.440986 -289.781488)
			(xy 106.41573 -289.781005) (xy 106.365907 -289.772689) (xy 106.318132 -289.756286) (xy 106.273708 -289.732243)
			(xy 106.233847 -289.701217) (xy 106.199637 -289.664053) (xy 106.17201 -289.621765) (xy 106.15172 -289.575507)
			(xy 106.13932 -289.52654) (xy 106.135149 -289.4762) (xy 104.866911 -289.4762) (xy 104.862741 -289.526532)
			(xy 104.850344 -289.57549) (xy 104.830058 -289.621741) (xy 104.802436 -289.664022) (xy 104.768233 -289.701181)
			(xy 104.72838 -289.732204) (xy 104.683965 -289.756244) (xy 104.636198 -289.772647) (xy 104.586384 -289.780964)
			(xy 104.561132 -289.781488) (xy 103.621078 -289.781488) (xy 103.595822 -289.781005) (xy 103.546 -289.772687)
			(xy 103.498226 -289.756284) (xy 103.453804 -289.732241) (xy 103.413944 -289.701214) (xy 103.379735 -289.66405)
			(xy 103.352109 -289.621763) (xy 103.331819 -289.575505) (xy 103.31942 -289.526539) (xy 103.315249 -289.4762)
			(xy 102.047011 -289.4762) (xy 102.042841 -289.526532) (xy 102.030443 -289.575492) (xy 102.010156 -289.621743)
			(xy 101.982534 -289.664025) (xy 101.948329 -289.701184) (xy 101.908475 -289.732206) (xy 101.864059 -289.756246)
			(xy 101.816292 -289.772648) (xy 101.766476 -289.780965) (xy 101.741224 -289.781488) (xy 100.80117 -289.781488)
			(xy 100.775915 -289.781004) (xy 100.726093 -289.772686) (xy 100.678321 -289.756281) (xy 100.633899 -289.732238)
			(xy 100.594041 -289.701211) (xy 100.559833 -289.664048) (xy 100.532208 -289.621761) (xy 100.511919 -289.575504)
			(xy 100.49952 -289.526538) (xy 100.495349 -289.4762) (xy 99.22694 -289.4762) (xy 99.222768 -289.526544)
			(xy 99.210366 -289.575514) (xy 99.190073 -289.621774) (xy 99.162441 -289.664063) (xy 99.128225 -289.701227)
			(xy 99.088358 -289.732252) (xy 99.043929 -289.756291) (xy 98.996148 -289.772689) (xy 98.94632 -289.780998)
			(xy 98.921062 -289.781488) (xy 97.981008 -289.781488) (xy 97.955748 -289.781036) (xy 97.905917 -289.772722)
			(xy 97.858135 -289.756319) (xy 97.813704 -289.732275) (xy 97.773836 -289.701246) (xy 97.73962 -289.664078)
			(xy 97.711988 -289.621785) (xy 97.691694 -289.575521) (xy 97.679292 -289.526547) (xy 97.67512 -289.4762)
			(xy 2.509012 -289.4762) (xy 2.509012 -290.2862) (xy 108.4849 -290.2862) (xy 108.489075 -290.235818)
			(xy 108.501485 -290.186811) (xy 108.521793 -290.140514) (xy 108.549443 -290.098192) (xy 108.583682 -290.060997)
			(xy 108.623576 -290.029946) (xy 108.668037 -290.005884) (xy 108.715852 -289.989468) (xy 108.765717 -289.981146)
			(xy 108.790994 -289.980624) (xy 109.731048 -289.980624) (xy 109.756321 -289.981178) (xy 109.806175 -289.989504)
			(xy 109.85398 -290.005922) (xy 109.898431 -290.029984) (xy 109.938315 -290.061033) (xy 109.972546 -290.098223)
			(xy 110.000189 -290.140539) (xy 110.020491 -290.186828) (xy 110.032898 -290.235827) (xy 110.037072 -290.2862)
			(xy 114.118571 -290.2862) (xy 114.122747 -290.235811) (xy 114.135159 -290.186797) (xy 114.15547 -290.140495)
			(xy 114.183125 -290.098167) (xy 114.21737 -290.060969) (xy 114.257271 -290.029915) (xy 114.301739 -290.005852)
			(xy 114.349561 -289.989436) (xy 114.399433 -289.981116) (xy 114.424714 -289.980624) (xy 115.364768 -289.980624)
			(xy 115.390047 -289.981142) (xy 115.439917 -289.989459) (xy 115.487738 -290.005872) (xy 115.532204 -290.029932)
			(xy 115.572104 -290.060983) (xy 115.606348 -290.098179) (xy 115.634003 -290.140503) (xy 115.654313 -290.186803)
			(xy 115.666725 -290.235814) (xy 115.670876 -290.2859) (xy 356.425301 -290.2859) (xy 356.429471 -290.235571)
			(xy 356.441867 -290.186615) (xy 356.462152 -290.140366) (xy 356.489772 -290.098087) (xy 356.523973 -290.06093)
			(xy 356.563824 -290.029908) (xy 356.608236 -290.005869) (xy 356.656 -289.989466) (xy 356.705811 -289.981148)
			(xy 356.731062 -289.980624) (xy 357.671116 -289.980624) (xy 357.696373 -289.981083) (xy 357.746198 -289.9894)
			(xy 357.793975 -290.005804) (xy 357.8384 -290.029847) (xy 357.878262 -290.060875) (xy 357.912473 -290.09804)
			(xy 357.940101 -290.14033) (xy 357.960392 -290.18659) (xy 357.972792 -290.235558) (xy 357.976963 -290.2859)
			(xy 362.059001 -290.2859) (xy 362.063171 -290.235569) (xy 362.075569 -290.186611) (xy 362.095855 -290.140361)
			(xy 362.123477 -290.09808) (xy 362.157681 -290.060923) (xy 362.197534 -290.029902) (xy 362.24195 -290.005863)
			(xy 362.289716 -289.989462) (xy 362.33953 -289.981147) (xy 362.364782 -289.980624) (xy 363.304836 -289.980624)
			(xy 363.330092 -289.981084) (xy 363.379914 -289.989404) (xy 363.427688 -290.005809) (xy 363.47211 -290.029854)
			(xy 363.511969 -290.060882) (xy 363.546178 -290.098047) (xy 363.573804 -290.140335) (xy 363.594093 -290.186594)
			(xy 363.606492 -290.23556) (xy 363.610663 -290.2859) (xy 363.606492 -290.33624) (xy 363.594093 -290.385206)
			(xy 363.573804 -290.431465) (xy 363.546178 -290.473753) (xy 363.511969 -290.510918) (xy 363.47211 -290.541946)
			(xy 363.427688 -290.565991) (xy 363.379914 -290.582396) (xy 363.330092 -290.590716) (xy 363.304836 -290.59124)
			(xy 362.364782 -290.59124) (xy 362.33953 -290.590653) (xy 362.289716 -290.582338) (xy 362.24195 -290.565937)
			(xy 362.197534 -290.541898) (xy 362.157681 -290.510877) (xy 362.123477 -290.47372) (xy 362.095855 -290.431439)
			(xy 362.075569 -290.385189) (xy 362.063171 -290.336231) (xy 362.059001 -290.2859) (xy 357.976963 -290.2859)
			(xy 357.972792 -290.336242) (xy 357.960392 -290.38521) (xy 357.940101 -290.43147) (xy 357.912473 -290.47376)
			(xy 357.878262 -290.510925) (xy 357.8384 -290.541953) (xy 357.793975 -290.565996) (xy 357.746198 -290.5824)
			(xy 357.696373 -290.590717) (xy 357.671116 -290.59124) (xy 356.731062 -290.59124) (xy 356.705811 -290.590652)
			(xy 356.656 -290.582334) (xy 356.608236 -290.565931) (xy 356.563824 -290.541892) (xy 356.523973 -290.51087)
			(xy 356.489772 -290.473713) (xy 356.462152 -290.431434) (xy 356.441867 -290.385185) (xy 356.429471 -290.336229)
			(xy 356.425301 -290.2859) (xy 115.670876 -290.2859) (xy 115.670901 -290.2862) (xy 115.666725 -290.336586)
			(xy 115.654313 -290.385597) (xy 115.634003 -290.431897) (xy 115.606348 -290.474221) (xy 115.572104 -290.511417)
			(xy 115.532204 -290.542468) (xy 115.487738 -290.566528) (xy 115.439917 -290.582941) (xy 115.390047 -290.591258)
			(xy 115.364768 -290.591748) (xy 114.424714 -290.591748) (xy 114.399433 -290.591284) (xy 114.349561 -290.582964)
			(xy 114.301739 -290.566548) (xy 114.257271 -290.542485) (xy 114.21737 -290.511431) (xy 114.183125 -290.474233)
			(xy 114.15547 -290.431905) (xy 114.135159 -290.385603) (xy 114.122747 -290.336589) (xy 114.118571 -290.2862)
			(xy 110.037072 -290.2862) (xy 110.032898 -290.336573) (xy 110.020491 -290.385572) (xy 110.000189 -290.431861)
			(xy 109.972546 -290.474177) (xy 109.938315 -290.511367) (xy 109.898431 -290.542416) (xy 109.85398 -290.566478)
			(xy 109.806175 -290.582896) (xy 109.756321 -290.591222) (xy 109.731048 -290.591748) (xy 108.790994 -290.591748)
			(xy 108.765717 -290.591254) (xy 108.715852 -290.582932) (xy 108.668037 -290.566516) (xy 108.623576 -290.542454)
			(xy 108.583682 -290.511403) (xy 108.549443 -290.474208) (xy 108.521793 -290.431886) (xy 108.501485 -290.385589)
			(xy 108.489075 -290.336582) (xy 108.4849 -290.2862) (xy 2.509012 -290.2862) (xy 2.509012 -291.0962)
			(xy 97.675132 -291.0962) (xy 97.679304 -291.045855) (xy 97.691705 -290.996883) (xy 97.711998 -290.950621)
			(xy 97.739629 -290.908329) (xy 97.773844 -290.871163) (xy 97.81371 -290.840135) (xy 97.85814 -290.816092)
			(xy 97.90592 -290.79969) (xy 97.955749 -290.791376) (xy 97.981008 -290.790884) (xy 98.921062 -290.790884)
			(xy 98.946321 -290.79139) (xy 98.996151 -290.799699) (xy 99.043934 -290.816098) (xy 99.088365 -290.840138)
			(xy 99.128233 -290.871164) (xy 99.16245 -290.908329) (xy 99.190083 -290.95062) (xy 99.210377 -290.996882)
			(xy 99.22278 -291.045854) (xy 99.226952 -291.0962) (xy 100.495361 -291.0962) (xy 100.499532 -291.045864)
			(xy 100.51193 -290.9969) (xy 100.532218 -290.950645) (xy 100.559842 -290.90836) (xy 100.594049 -290.871198)
			(xy 100.633906 -290.840172) (xy 100.678326 -290.81613) (xy 100.726096 -290.799726) (xy 100.775916 -290.791408)
			(xy 100.80117 -290.790884) (xy 101.741224 -290.790884) (xy 101.766477 -290.791423) (xy 101.816295 -290.79974)
			(xy 101.864064 -290.816143) (xy 101.908482 -290.840184) (xy 101.948338 -290.871207) (xy 101.982544 -290.908368)
			(xy 102.010167 -290.950651) (xy 102.030454 -290.996904) (xy 102.042852 -291.045866) (xy 102.047023 -291.0962)
			(xy 103.315261 -291.0962) (xy 103.319432 -291.045863) (xy 103.331831 -290.996899) (xy 103.352119 -290.950643)
			(xy 103.379744 -290.908357) (xy 103.413952 -290.871195) (xy 103.45381 -290.840169) (xy 103.498231 -290.816127)
			(xy 103.546003 -290.799724) (xy 103.595823 -290.791407) (xy 103.621078 -290.790884) (xy 104.561132 -290.790884)
			(xy 104.586385 -290.791424) (xy 104.636201 -290.799742) (xy 104.683969 -290.816145) (xy 104.728386 -290.840186)
			(xy 104.768241 -290.87121) (xy 104.802446 -290.90837) (xy 104.830068 -290.950653) (xy 104.850355 -290.996906)
			(xy 104.862753 -291.045867) (xy 104.866923 -291.0962) (xy 106.135161 -291.0962) (xy 106.139332 -291.045862)
			(xy 106.151731 -290.996897) (xy 106.172021 -290.950641) (xy 106.199646 -290.908354) (xy 106.233855 -290.871192)
			(xy 106.273715 -290.840167) (xy 106.318136 -290.816125) (xy 106.36591 -290.799722) (xy 106.415731 -290.791407)
			(xy 106.440986 -290.790884) (xy 107.38104 -290.790884) (xy 107.406292 -290.791425) (xy 107.456108 -290.799743)
			(xy 107.503875 -290.816147) (xy 107.548291 -290.840189) (xy 107.588144 -290.871213) (xy 107.622348 -290.908373)
			(xy 107.649969 -290.950655) (xy 107.670255 -290.996907) (xy 107.682653 -291.045867) (xy 107.686823 -291.0962)
			(xy 116.468832 -291.0962) (xy 116.473004 -291.045853) (xy 116.485406 -290.99688) (xy 116.5057 -290.950617)
			(xy 116.533333 -290.908325) (xy 116.56755 -290.871158) (xy 116.607418 -290.84013) (xy 116.651849 -290.816088)
			(xy 116.699632 -290.799687) (xy 116.749462 -290.791375) (xy 116.774722 -290.790884) (xy 117.714776 -290.790884)
			(xy 117.740034 -290.791391) (xy 117.789863 -290.799702) (xy 117.837643 -290.816102) (xy 117.882072 -290.840143)
			(xy 117.921939 -290.871169) (xy 117.956154 -290.908334) (xy 117.983785 -290.950624) (xy 118.004078 -290.996885)
			(xy 118.01648 -291.045856) (xy 118.020652 -291.0962) (xy 119.288732 -291.0962) (xy 119.292904 -291.045853)
			(xy 119.305307 -290.996879) (xy 119.325602 -290.950615) (xy 119.353235 -290.908322) (xy 119.387453 -290.871155)
			(xy 119.427322 -290.840127) (xy 119.471755 -290.816085) (xy 119.519538 -290.799685) (xy 119.56937 -290.791374)
			(xy 119.59463 -290.790884) (xy 120.534684 -290.790884) (xy 120.559942 -290.791391) (xy 120.609769 -290.799704)
			(xy 120.657549 -290.816104) (xy 120.701977 -290.840145) (xy 120.741842 -290.871172) (xy 120.776056 -290.908336)
			(xy 120.803686 -290.950626) (xy 120.823979 -290.996887) (xy 120.83638 -291.045857) (xy 120.840552 -291.0962)
			(xy 122.108961 -291.0962) (xy 122.113132 -291.045861) (xy 122.125532 -290.996896) (xy 122.145821 -290.950639)
			(xy 122.173448 -290.908352) (xy 122.207658 -290.87119) (xy 122.247518 -290.840165) (xy 122.29194 -290.816123)
			(xy 122.339714 -290.799721) (xy 122.389536 -290.791406) (xy 122.414792 -290.790884) (xy 123.354846 -290.790884)
			(xy 123.380098 -290.791425) (xy 123.429913 -290.799745) (xy 123.477679 -290.816149) (xy 123.522094 -290.840191)
			(xy 123.561946 -290.871215) (xy 123.596149 -290.908375) (xy 123.62377 -290.950657) (xy 123.644056 -290.996909)
			(xy 123.656453 -291.045868) (xy 123.660623 -291.0962) (xy 124.928861 -291.0962) (xy 124.933032 -291.045861)
			(xy 124.945432 -290.996894) (xy 124.965723 -290.950637) (xy 124.99335 -290.90835) (xy 125.027561 -290.871187)
			(xy 125.067422 -290.840162) (xy 125.111846 -290.816121) (xy 125.159621 -290.79972) (xy 125.209444 -290.791406)
			(xy 125.2347 -290.790884) (xy 126.174754 -290.790884) (xy 126.200014 -290.791389) (xy 126.249845 -290.799697)
			(xy 126.297628 -290.816095) (xy 126.342061 -290.840135) (xy 126.38193 -290.871161) (xy 126.416148 -290.908327)
			(xy 126.443782 -290.950618) (xy 126.464077 -290.996881) (xy 126.47648 -291.045854) (xy 126.480627 -291.0959)
			(xy 345.615052 -291.0959) (xy 345.619226 -291.045529) (xy 345.631633 -290.996531) (xy 345.651936 -290.950244)
			(xy 345.679579 -290.90793) (xy 345.71381 -290.870742) (xy 345.753695 -290.839696) (xy 345.798146 -290.815637)
			(xy 345.84595 -290.799222) (xy 345.895804 -290.7909) (xy 345.921076 -290.790376) (xy 346.86113 -290.790376)
			(xy 346.886408 -290.790824) (xy 346.936273 -290.79915) (xy 346.984089 -290.815569) (xy 347.02855 -290.839634)
			(xy 347.068443 -290.870688) (xy 347.102682 -290.907885) (xy 347.130332 -290.95021) (xy 347.150639 -290.996508)
			(xy 347.163049 -291.045517) (xy 347.167224 -291.0959) (xy 348.435123 -291.0959) (xy 348.439299 -291.045518)
			(xy 348.45171 -290.99651) (xy 348.472019 -290.950213) (xy 348.499672 -290.907891) (xy 348.533915 -290.870699)
			(xy 348.573812 -290.83965) (xy 348.618276 -290.815592) (xy 348.666094 -290.799181) (xy 348.71596 -290.790866)
			(xy 348.741238 -290.790376) (xy 349.681292 -290.790376) (xy 349.706574 -290.790793) (xy 349.756449 -290.799114)
			(xy 349.804275 -290.815531) (xy 349.848745 -290.839597) (xy 349.888648 -290.870653) (xy 349.922895 -290.907855)
			(xy 349.950552 -290.950185) (xy 349.970864 -290.996491) (xy 349.983277 -291.045508) (xy 349.987453 -291.0959)
			(xy 351.255023 -291.0959) (xy 351.259199 -291.045517) (xy 351.271611 -290.996508) (xy 351.291921 -290.950211)
			(xy 351.319575 -290.907889) (xy 351.353818 -290.870696) (xy 351.393716 -290.839647) (xy 351.438182 -290.81559)
			(xy 351.486 -290.79918) (xy 351.535868 -290.790865) (xy 351.561146 -290.790376) (xy 352.5012 -290.790376)
			(xy 352.526479 -290.790822) (xy 352.576349 -290.799144) (xy 352.624168 -290.81556) (xy 352.668634 -290.839624)
			(xy 352.708532 -290.870678) (xy 352.742774 -290.907875) (xy 352.770428 -290.950201) (xy 352.790737 -290.996502)
			(xy 352.803148 -291.045514) (xy 352.807324 -291.0959) (xy 354.075052 -291.0959) (xy 354.079226 -291.045531)
			(xy 354.091632 -290.996536) (xy 354.111932 -290.95025) (xy 354.139574 -290.907937) (xy 354.173802 -290.87075)
			(xy 354.213684 -290.839703) (xy 354.258131 -290.815644) (xy 354.305932 -290.799227) (xy 354.355783 -290.790901)
			(xy 354.381054 -290.790376) (xy 355.321108 -290.790376) (xy 355.346387 -290.790823) (xy 355.396255 -290.799145)
			(xy 355.444074 -290.815563) (xy 355.488538 -290.839626) (xy 355.528435 -290.87068) (xy 355.562677 -290.907878)
			(xy 355.590329 -290.950204) (xy 355.610637 -290.996503) (xy 355.623049 -291.045515) (xy 355.627224 -291.0959)
			(xy 364.408752 -291.0959) (xy 364.412926 -291.045527) (xy 364.425334 -290.996529) (xy 364.445638 -290.95024)
			(xy 364.473283 -290.907925) (xy 364.507516 -290.870737) (xy 364.547403 -290.839691) (xy 364.591855 -290.815633)
			(xy 364.639662 -290.79922) (xy 364.689517 -290.790899) (xy 364.71479 -290.790376) (xy 365.654844 -290.790376)
			(xy 365.680121 -290.790826) (xy 365.729985 -290.799153) (xy 365.777798 -290.815573) (xy 365.822257 -290.839639)
			(xy 365.862149 -290.870693) (xy 365.896386 -290.90789) (xy 365.924034 -290.950214) (xy 365.94434 -290.996511)
			(xy 365.956749 -291.045518) (xy 365.960924 -291.0959) (xy 367.228652 -291.0959) (xy 367.232827 -291.045526)
			(xy 367.245235 -290.996527) (xy 367.265539 -290.950238) (xy 367.293185 -290.907922) (xy 367.327419 -290.870734)
			(xy 367.367307 -290.839688) (xy 367.411761 -290.81563) (xy 367.459568 -290.799218) (xy 367.509425 -290.790898)
			(xy 367.534698 -290.790376) (xy 368.474752 -290.790376) (xy 368.500036 -290.790789) (xy 368.549917 -290.799106)
			(xy 368.597748 -290.815519) (xy 368.642224 -290.839583) (xy 368.682133 -290.870639) (xy 368.716385 -290.907841)
			(xy 368.744046 -290.950174) (xy 368.764361 -290.996483) (xy 368.776776 -291.045504) (xy 368.780953 -291.0959)
			(xy 370.048852 -291.0959) (xy 370.053026 -291.04553) (xy 370.065432 -290.996535) (xy 370.085733 -290.950249)
			(xy 370.113375 -290.907935) (xy 370.147604 -290.870748) (xy 370.187487 -290.839701) (xy 370.231935 -290.815642)
			(xy 370.279737 -290.799226) (xy 370.329589 -290.790901) (xy 370.35486 -290.790376) (xy 371.294914 -290.790376)
			(xy 371.320193 -290.790823) (xy 371.37006 -290.799147) (xy 371.417878 -290.815564) (xy 371.462341 -290.839629)
			(xy 371.502237 -290.870683) (xy 371.536478 -290.90788) (xy 371.56413 -290.950205) (xy 371.584438 -290.996505)
			(xy 371.596849 -291.045515) (xy 371.601024 -291.0959) (xy 372.868752 -291.0959) (xy 372.872926 -291.04553)
			(xy 372.885333 -290.996533) (xy 372.905634 -290.950246) (xy 372.933277 -290.907932) (xy 372.967507 -290.870745)
			(xy 373.007391 -290.839698) (xy 373.05184 -290.815639) (xy 373.099644 -290.799224) (xy 373.149497 -290.7909)
			(xy 373.174768 -290.790376) (xy 374.114822 -290.790376) (xy 374.1401 -290.790824) (xy 374.189967 -290.799148)
			(xy 374.237783 -290.815567) (xy 374.282245 -290.839631) (xy 374.32214 -290.870685) (xy 374.35638 -290.907882)
			(xy 374.384031 -290.950207) (xy 374.404338 -290.996506) (xy 374.416749 -291.045516) (xy 374.420924 -291.0959)
			(xy 374.416749 -291.146284) (xy 374.404338 -291.195294) (xy 374.384031 -291.241593) (xy 374.35638 -291.283918)
			(xy 374.32214 -291.321115) (xy 374.282245 -291.352169) (xy 374.237783 -291.376233) (xy 374.189967 -291.392652)
			(xy 374.1401 -291.400976) (xy 374.114822 -291.4015) (xy 373.174768 -291.4015) (xy 373.149497 -291.4009)
			(xy 373.099644 -291.392576) (xy 373.05184 -291.376161) (xy 373.007391 -291.352102) (xy 372.967507 -291.321055)
			(xy 372.933277 -291.283868) (xy 372.905634 -291.241554) (xy 372.885333 -291.195267) (xy 372.872926 -291.14627)
			(xy 372.868752 -291.0959) (xy 371.601024 -291.0959) (xy 371.596849 -291.146285) (xy 371.584438 -291.195295)
			(xy 371.56413 -291.241595) (xy 371.536478 -291.28392) (xy 371.502237 -291.321117) (xy 371.462341 -291.352171)
			(xy 371.417878 -291.376236) (xy 371.37006 -291.392653) (xy 371.320193 -291.400977) (xy 371.294914 -291.4015)
			(xy 370.35486 -291.4015) (xy 370.329589 -291.400899) (xy 370.279737 -291.392574) (xy 370.231935 -291.376158)
			(xy 370.187487 -291.352099) (xy 370.147604 -291.321052) (xy 370.113375 -291.283865) (xy 370.085733 -291.241551)
			(xy 370.065432 -291.195265) (xy 370.053026 -291.14627) (xy 370.048852 -291.0959) (xy 368.780953 -291.0959)
			(xy 368.776776 -291.146296) (xy 368.764361 -291.195317) (xy 368.744046 -291.241626) (xy 368.716385 -291.283959)
			(xy 368.682133 -291.321161) (xy 368.642224 -291.352217) (xy 368.597748 -291.376281) (xy 368.549917 -291.392694)
			(xy 368.500036 -291.401011) (xy 368.474752 -291.4015) (xy 367.534698 -291.4015) (xy 367.509425 -291.400902)
			(xy 367.459568 -291.392582) (xy 367.411761 -291.37617) (xy 367.367307 -291.352112) (xy 367.327419 -291.321066)
			(xy 367.293185 -291.283878) (xy 367.265539 -291.241562) (xy 367.245235 -291.195273) (xy 367.232827 -291.146274)
			(xy 367.228652 -291.0959) (xy 365.960924 -291.0959) (xy 365.956749 -291.146282) (xy 365.94434 -291.195289)
			(xy 365.924034 -291.241586) (xy 365.896386 -291.28391) (xy 365.862149 -291.321107) (xy 365.822257 -291.352161)
			(xy 365.777798 -291.376227) (xy 365.729985 -291.392647) (xy 365.680121 -291.400974) (xy 365.654844 -291.4015)
			(xy 364.71479 -291.4015) (xy 364.689517 -291.400901) (xy 364.639662 -291.39258) (xy 364.591855 -291.376167)
			(xy 364.547403 -291.352109) (xy 364.507516 -291.321063) (xy 364.473283 -291.283875) (xy 364.445638 -291.24156)
			(xy 364.425334 -291.195271) (xy 364.412926 -291.146273) (xy 364.408752 -291.0959) (xy 355.627224 -291.0959)
			(xy 355.623049 -291.146285) (xy 355.610637 -291.195297) (xy 355.590329 -291.241596) (xy 355.562677 -291.283922)
			(xy 355.528435 -291.32112) (xy 355.488538 -291.352174) (xy 355.444074 -291.376237) (xy 355.396255 -291.392655)
			(xy 355.346387 -291.400977) (xy 355.321108 -291.4015) (xy 354.381054 -291.4015) (xy 354.355783 -291.400899)
			(xy 354.305932 -291.392573) (xy 354.258131 -291.376157) (xy 354.213684 -291.352097) (xy 354.173802 -291.32105)
			(xy 354.139574 -291.283863) (xy 354.111932 -291.24155) (xy 354.091632 -291.195264) (xy 354.079226 -291.146269)
			(xy 354.075052 -291.0959) (xy 352.807324 -291.0959) (xy 352.803148 -291.146286) (xy 352.790737 -291.195298)
			(xy 352.770428 -291.241599) (xy 352.742774 -291.283925) (xy 352.708532 -291.321122) (xy 352.668634 -291.352176)
			(xy 352.624168 -291.37624) (xy 352.576349 -291.392656) (xy 352.526479 -291.400978) (xy 352.5012 -291.4015)
			(xy 351.561146 -291.4015) (xy 351.535868 -291.400935) (xy 351.486 -291.39262) (xy 351.438182 -291.37621)
			(xy 351.393716 -291.352153) (xy 351.353818 -291.321104) (xy 351.319575 -291.283911) (xy 351.291921 -291.241589)
			(xy 351.271611 -291.195292) (xy 351.259199 -291.146283) (xy 351.255023 -291.0959) (xy 349.987453 -291.0959)
			(xy 349.983277 -291.146292) (xy 349.970864 -291.195309) (xy 349.950552 -291.241615) (xy 349.922895 -291.283945)
			(xy 349.888648 -291.321147) (xy 349.848745 -291.352203) (xy 349.804275 -291.376269) (xy 349.756449 -291.392686)
			(xy 349.706574 -291.401007) (xy 349.681292 -291.4015) (xy 348.741238 -291.4015) (xy 348.71596 -291.400934)
			(xy 348.666094 -291.392619) (xy 348.618276 -291.376208) (xy 348.573812 -291.35215) (xy 348.533915 -291.321101)
			(xy 348.499672 -291.283909) (xy 348.472019 -291.241587) (xy 348.45171 -291.19529) (xy 348.439299 -291.146282)
			(xy 348.435123 -291.0959) (xy 347.167224 -291.0959) (xy 347.163049 -291.146283) (xy 347.150639 -291.195292)
			(xy 347.130332 -291.24159) (xy 347.102682 -291.283915) (xy 347.068443 -291.321112) (xy 347.02855 -291.352166)
			(xy 346.984089 -291.376231) (xy 346.936273 -291.39265) (xy 346.886408 -291.400976) (xy 346.86113 -291.4015)
			(xy 345.921076 -291.4015) (xy 345.895804 -291.4009) (xy 345.84595 -291.392578) (xy 345.798146 -291.376163)
			(xy 345.753695 -291.352104) (xy 345.71381 -291.321058) (xy 345.679579 -291.28387) (xy 345.651936 -291.241556)
			(xy 345.631633 -291.195269) (xy 345.619226 -291.146271) (xy 345.615052 -291.0959) (xy 126.480627 -291.0959)
			(xy 126.480652 -291.0962) (xy 126.47648 -291.146546) (xy 126.464077 -291.195519) (xy 126.443782 -291.241782)
			(xy 126.416148 -291.284074) (xy 126.38193 -291.321239) (xy 126.342061 -291.352265) (xy 126.297628 -291.376305)
			(xy 126.249845 -291.392703) (xy 126.200014 -291.401011) (xy 126.174754 -291.4015) (xy 125.2347 -291.4015)
			(xy 125.209444 -291.400994) (xy 125.159621 -291.39268) (xy 125.111846 -291.376279) (xy 125.067422 -291.352238)
			(xy 125.027561 -291.321213) (xy 124.99335 -291.28405) (xy 124.965723 -291.241763) (xy 124.945432 -291.195506)
			(xy 124.933032 -291.146539) (xy 124.928861 -291.0962) (xy 123.660623 -291.0962) (xy 123.656453 -291.146532)
			(xy 123.644056 -291.195491) (xy 123.62377 -291.241743) (xy 123.596149 -291.284025) (xy 123.561946 -291.321185)
			(xy 123.522094 -291.352209) (xy 123.477679 -291.376251) (xy 123.429913 -291.392655) (xy 123.380098 -291.400975)
			(xy 123.354846 -291.4015) (xy 122.414792 -291.4015) (xy 122.389536 -291.400994) (xy 122.339714 -291.392679)
			(xy 122.29194 -291.376277) (xy 122.247518 -291.352235) (xy 122.207658 -291.32121) (xy 122.173448 -291.284048)
			(xy 122.145821 -291.241761) (xy 122.125532 -291.195504) (xy 122.113132 -291.146539) (xy 122.108961 -291.0962)
			(xy 120.840552 -291.0962) (xy 120.83638 -291.146543) (xy 120.823979 -291.195513) (xy 120.803686 -291.241774)
			(xy 120.776056 -291.284064) (xy 120.741842 -291.321228) (xy 120.701977 -291.352255) (xy 120.657549 -291.376296)
			(xy 120.609769 -291.392696) (xy 120.559942 -291.401009) (xy 120.534684 -291.4015) (xy 119.59463 -291.4015)
			(xy 119.56937 -291.401026) (xy 119.519538 -291.392715) (xy 119.471755 -291.376315) (xy 119.427322 -291.352273)
			(xy 119.387453 -291.321245) (xy 119.353235 -291.284078) (xy 119.325602 -291.241785) (xy 119.305307 -291.195521)
			(xy 119.292904 -291.146547) (xy 119.288732 -291.0962) (xy 118.020652 -291.0962) (xy 118.01648 -291.146544)
			(xy 118.004078 -291.195515) (xy 117.983785 -291.241776) (xy 117.956154 -291.284066) (xy 117.921939 -291.321231)
			(xy 117.882072 -291.352257) (xy 117.837643 -291.376298) (xy 117.789863 -291.392698) (xy 117.740034 -291.401009)
			(xy 117.714776 -291.4015) (xy 116.774722 -291.4015) (xy 116.749462 -291.401025) (xy 116.699632 -291.392713)
			(xy 116.651849 -291.376312) (xy 116.607418 -291.35227) (xy 116.56755 -291.321242) (xy 116.533333 -291.284075)
			(xy 116.5057 -291.241783) (xy 116.485406 -291.19552) (xy 116.473004 -291.146547) (xy 116.468832 -291.0962)
			(xy 107.686823 -291.0962) (xy 107.682653 -291.146533) (xy 107.670255 -291.195493) (xy 107.649969 -291.241745)
			(xy 107.622348 -291.284027) (xy 107.588144 -291.321187) (xy 107.548291 -291.352211) (xy 107.503875 -291.376253)
			(xy 107.456108 -291.392657) (xy 107.406292 -291.400975) (xy 107.38104 -291.4015) (xy 106.440986 -291.4015)
			(xy 106.415731 -291.400993) (xy 106.36591 -291.392678) (xy 106.318136 -291.376275) (xy 106.273715 -291.352233)
			(xy 106.233855 -291.321208) (xy 106.199646 -291.284046) (xy 106.172021 -291.241759) (xy 106.151731 -291.195503)
			(xy 106.139332 -291.146538) (xy 106.135161 -291.0962) (xy 104.866923 -291.0962) (xy 104.862753 -291.146533)
			(xy 104.850355 -291.195494) (xy 104.830068 -291.241747) (xy 104.802446 -291.28403) (xy 104.768241 -291.32119)
			(xy 104.728386 -291.352214) (xy 104.683969 -291.376255) (xy 104.636201 -291.392658) (xy 104.586385 -291.400976)
			(xy 104.561132 -291.4015) (xy 103.621078 -291.4015) (xy 103.595823 -291.400993) (xy 103.546003 -291.392676)
			(xy 103.498231 -291.376273) (xy 103.45381 -291.352231) (xy 103.413952 -291.321205) (xy 103.379744 -291.284043)
			(xy 103.352119 -291.241757) (xy 103.331831 -291.195501) (xy 103.319432 -291.146537) (xy 103.315261 -291.0962)
			(xy 102.047023 -291.0962) (xy 102.042852 -291.146534) (xy 102.030454 -291.195496) (xy 102.010167 -291.241749)
			(xy 101.982544 -291.284032) (xy 101.948338 -291.321193) (xy 101.908482 -291.352216) (xy 101.864064 -291.376257)
			(xy 101.816295 -291.39266) (xy 101.766477 -291.400977) (xy 101.741224 -291.4015) (xy 100.80117 -291.4015)
			(xy 100.775916 -291.400992) (xy 100.726096 -291.392674) (xy 100.678326 -291.37627) (xy 100.633906 -291.352228)
			(xy 100.594049 -291.321202) (xy 100.559842 -291.28404) (xy 100.532218 -291.241755) (xy 100.51193 -291.1955)
			(xy 100.499532 -291.146536) (xy 100.495361 -291.0962) (xy 99.226952 -291.0962) (xy 99.22278 -291.146546)
			(xy 99.210377 -291.195518) (xy 99.190083 -291.24178) (xy 99.16245 -291.284071) (xy 99.128233 -291.321236)
			(xy 99.088365 -291.352262) (xy 99.043934 -291.376302) (xy 98.996151 -291.392701) (xy 98.946321 -291.40101)
			(xy 98.921062 -291.4015) (xy 97.981008 -291.4015) (xy 97.955749 -291.401024) (xy 97.90592 -291.39271)
			(xy 97.85814 -291.376308) (xy 97.81371 -291.352265) (xy 97.773844 -291.321237) (xy 97.739629 -291.284071)
			(xy 97.711998 -291.241779) (xy 97.691705 -291.195517) (xy 97.679304 -291.146545) (xy 97.675132 -291.0962)
			(xy 2.509012 -291.0962) (xy 2.509012 -300.146974) (xy 340.219284 -300.146974) (xy 340.219284 -299.130974)
			(xy 340.21977 -299.103723) (xy 340.227526 -299.049775) (xy 340.242881 -298.99748) (xy 340.265523 -298.947903)
			(xy 340.294989 -298.902053) (xy 340.33068 -298.860862) (xy 340.371871 -298.825171) (xy 340.417721 -298.795705)
			(xy 340.467298 -298.773063) (xy 340.519593 -298.757708) (xy 340.573541 -298.749952) (xy 340.628043 -298.749952)
			(xy 340.681991 -298.757708) (xy 340.734286 -298.773063) (xy 340.783863 -298.795705) (xy 340.829713 -298.825171)
			(xy 340.870904 -298.860862) (xy 340.906595 -298.902053) (xy 340.936061 -298.947903) (xy 340.958703 -298.99748)
			(xy 340.974058 -299.049775) (xy 340.981814 -299.103723) (xy 340.9823 -299.130974) (xy 340.9823 -300.146974)
			(xy 340.981814 -300.174225) (xy 340.974058 -300.228173) (xy 340.958703 -300.280468) (xy 340.936061 -300.330045)
			(xy 340.906595 -300.375895) (xy 340.870904 -300.417086) (xy 340.829713 -300.452777) (xy 340.783863 -300.482243)
			(xy 340.734286 -300.504885) (xy 340.681991 -300.52024) (xy 340.628043 -300.527996) (xy 340.573541 -300.527996)
			(xy 340.519593 -300.52024) (xy 340.467298 -300.504885) (xy 340.417721 -300.482243) (xy 340.371871 -300.452777)
			(xy 340.33068 -300.417086) (xy 340.294989 -300.375895) (xy 340.265523 -300.330045) (xy 340.242881 -300.280468)
			(xy 340.227526 -300.228173) (xy 340.21977 -300.174225) (xy 340.219284 -300.146974) (xy 2.509012 -300.146974)
			(xy 2.509012 -304.780442) (xy 78.811886 -304.780442) (xy 78.815916 -304.638092) (xy 78.827993 -304.496199)
			(xy 78.848078 -304.355216) (xy 78.876107 -304.215595) (xy 78.911991 -304.077783) (xy 78.955613 -303.942222)
			(xy 79.006835 -303.809347) (xy 79.065493 -303.679582) (xy 79.131398 -303.553343) (xy 79.204339 -303.431035)
			(xy 79.284083 -303.31305) (xy 79.370375 -303.199765) (xy 79.462937 -303.091544) (xy 79.561474 -302.988732)
			(xy 79.665669 -302.89166) (xy 79.77519 -302.800639) (xy 79.889684 -302.715959) (xy 80.008786 -302.637893)
			(xy 80.132114 -302.566689) (xy 80.259272 -302.502577) (xy 80.389854 -302.445762) (xy 80.523442 -302.396425)
			(xy 80.659606 -302.354725) (xy 80.797912 -302.320796) (xy 80.937915 -302.294745) (xy 81.079169 -302.276657)
			(xy 81.221219 -302.266589) (xy 81.363611 -302.264574) (xy 81.50589 -302.270618) (xy 81.647598 -302.284701)
			(xy 81.788283 -302.30678) (xy 81.927493 -302.336782) (xy 82.064783 -302.374612) (xy 82.199713 -302.420148)
			(xy 82.331851 -302.473246) (xy 82.460773 -302.533733) (xy 82.586066 -302.601418) (xy 82.707329 -302.676083)
			(xy 82.824174 -302.757489) (xy 82.936227 -302.845375) (xy 83.043127 -302.939459) (xy 83.144534 -303.039441)
			(xy 83.240122 -303.144999) (xy 83.329585 -303.255797) (xy 83.412636 -303.371478) (xy 83.489009 -303.491673)
			(xy 83.55846 -303.615996) (xy 83.620766 -303.744049) (xy 83.675728 -303.875422) (xy 83.723169 -304.009694)
			(xy 83.762938 -304.146435) (xy 83.794907 -304.285207) (xy 83.818974 -304.425565) (xy 83.835062 -304.56706)
			(xy 83.843118 -304.709239) (xy 83.843622 -304.780442) (xy 140.011408 -304.780442) (xy 140.015438 -304.638078)
			(xy 140.027516 -304.49617) (xy 140.047604 -304.355173) (xy 140.075636 -304.215538) (xy 140.111523 -304.077712)
			(xy 140.15515 -303.942138) (xy 140.206377 -303.809249) (xy 140.26504 -303.67947) (xy 140.330952 -303.553219)
			(xy 140.403901 -303.430899) (xy 140.483653 -303.312902) (xy 140.569953 -303.199606) (xy 140.662525 -303.091373)
			(xy 140.761071 -302.988551) (xy 140.865277 -302.89147) (xy 140.974809 -302.800439) (xy 141.089315 -302.715751)
			(xy 141.208429 -302.637676) (xy 141.331769 -302.566466) (xy 141.45894 -302.502347) (xy 141.589536 -302.445526)
			(xy 141.723136 -302.396185) (xy 141.859315 -302.35448) (xy 141.997634 -302.320547) (xy 142.137652 -302.294494)
			(xy 142.278919 -302.276404) (xy 142.420984 -302.266335) (xy 142.563391 -302.26432) (xy 142.705684 -302.270364)
			(xy 142.847406 -302.28445) (xy 142.988105 -302.30653) (xy 143.12733 -302.336535) (xy 143.264634 -302.374369)
			(xy 143.399577 -302.41991) (xy 143.531728 -302.473013) (xy 143.660663 -302.533507) (xy 143.785969 -302.601198)
			(xy 143.907245 -302.675871) (xy 144.024101 -302.757285) (xy 144.136165 -302.845179) (xy 144.243077 -302.939273)
			(xy 144.344494 -303.039265) (xy 144.440091 -303.144834) (xy 144.529563 -303.255643) (xy 144.612622 -303.371336)
			(xy 144.689003 -303.491543) (xy 144.758461 -303.615878) (xy 144.820774 -303.743944) (xy 144.875741 -303.875331)
			(xy 144.923187 -304.009616) (xy 144.96296 -304.146371) (xy 144.994932 -304.285157) (xy 145.019002 -304.425529)
			(xy 145.035091 -304.567039) (xy 145.043148 -304.709231) (xy 145.04365 -304.780188) (xy 326.751954 -304.780188)
			(xy 326.755984 -304.637838) (xy 326.768061 -304.495945) (xy 326.788146 -304.354962) (xy 326.816175 -304.215341)
			(xy 326.852059 -304.077529) (xy 326.895681 -303.941968) (xy 326.946903 -303.809093) (xy 327.005561 -303.679328)
			(xy 327.071466 -303.553089) (xy 327.144407 -303.430781) (xy 327.224151 -303.312796) (xy 327.310443 -303.199511)
			(xy 327.403005 -303.09129) (xy 327.501542 -302.988478) (xy 327.605737 -302.891406) (xy 327.715258 -302.800385)
			(xy 327.829752 -302.715705) (xy 327.948854 -302.637639) (xy 328.072182 -302.566435) (xy 328.19934 -302.502323)
			(xy 328.329922 -302.445508) (xy 328.46351 -302.396171) (xy 328.599674 -302.354471) (xy 328.73798 -302.320542)
			(xy 328.877983 -302.294491) (xy 329.019237 -302.276403) (xy 329.161287 -302.266335) (xy 329.303679 -302.26432)
			(xy 329.445958 -302.270364) (xy 329.587666 -302.284447) (xy 329.728351 -302.306526) (xy 329.867561 -302.336528)
			(xy 330.004851 -302.374358) (xy 330.139781 -302.419894) (xy 330.271919 -302.472992) (xy 330.400841 -302.533479)
			(xy 330.526134 -302.601164) (xy 330.647397 -302.675829) (xy 330.764242 -302.757235) (xy 330.876295 -302.845121)
			(xy 330.983195 -302.939205) (xy 331.084602 -303.039187) (xy 331.18019 -303.144745) (xy 331.269653 -303.255543)
			(xy 331.352704 -303.371224) (xy 331.429077 -303.491419) (xy 331.498528 -303.615742) (xy 331.560834 -303.743795)
			(xy 331.615796 -303.875168) (xy 331.663237 -304.00944) (xy 331.703006 -304.146181) (xy 331.734975 -304.284953)
			(xy 331.759042 -304.425311) (xy 331.77513 -304.566806) (xy 331.781608 -304.681128) (xy 333.795116 -304.681128)
			(xy 333.795116 -303.817528) (xy 333.795602 -303.790259) (xy 333.803364 -303.736275) (xy 333.818729 -303.683945)
			(xy 333.841386 -303.634335) (xy 333.870872 -303.588454) (xy 333.906587 -303.547237) (xy 333.947804 -303.511522)
			(xy 333.993685 -303.482036) (xy 334.043295 -303.459379) (xy 334.095625 -303.444014) (xy 334.149609 -303.436252)
			(xy 334.204147 -303.436252) (xy 334.258131 -303.444014) (xy 334.310461 -303.459379) (xy 334.360071 -303.482036)
			(xy 334.405952 -303.511522) (xy 334.447169 -303.547237) (xy 334.482884 -303.588454) (xy 334.51237 -303.634335)
			(xy 334.535027 -303.683945) (xy 334.550392 -303.736275) (xy 334.558154 -303.790259) (xy 334.55864 -303.817528)
			(xy 334.55864 -304.681128) (xy 334.558154 -304.708397) (xy 334.550392 -304.762381) (xy 334.545164 -304.780188)
			(xy 387.951476 -304.780188) (xy 387.955506 -304.637824) (xy 387.967584 -304.495916) (xy 387.987672 -304.354919)
			(xy 388.015704 -304.215284) (xy 388.051591 -304.077458) (xy 388.095218 -303.941884) (xy 388.146445 -303.808995)
			(xy 388.205108 -303.679216) (xy 388.27102 -303.552965) (xy 388.343969 -303.430645) (xy 388.423721 -303.312648)
			(xy 388.510021 -303.199352) (xy 388.602593 -303.091119) (xy 388.701139 -302.988297) (xy 388.805345 -302.891216)
			(xy 388.914877 -302.800185) (xy 389.029383 -302.715497) (xy 389.148497 -302.637422) (xy 389.271837 -302.566212)
			(xy 389.399008 -302.502093) (xy 389.529604 -302.445272) (xy 389.663204 -302.395931) (xy 389.799383 -302.354226)
			(xy 389.937702 -302.320293) (xy 390.07772 -302.29424) (xy 390.218987 -302.27615) (xy 390.361052 -302.266081)
			(xy 390.503459 -302.264066) (xy 390.645752 -302.27011) (xy 390.787474 -302.284196) (xy 390.928173 -302.306276)
			(xy 391.067398 -302.336281) (xy 391.204702 -302.374115) (xy 391.339645 -302.419656) (xy 391.471796 -302.472759)
			(xy 391.600731 -302.533253) (xy 391.726037 -302.600944) (xy 391.847313 -302.675617) (xy 391.964169 -302.757031)
			(xy 392.076233 -302.844925) (xy 392.183145 -302.939019) (xy 392.284562 -303.039011) (xy 392.380159 -303.14458)
			(xy 392.469631 -303.255389) (xy 392.55269 -303.371082) (xy 392.629071 -303.491289) (xy 392.698529 -303.615624)
			(xy 392.760842 -303.74369) (xy 392.815809 -303.875077) (xy 392.863255 -304.009362) (xy 392.903028 -304.146117)
			(xy 392.935 -304.284903) (xy 392.95907 -304.425275) (xy 392.975159 -304.566785) (xy 392.983216 -304.708977)
			(xy 392.98372 -304.780188) (xy 392.983216 -304.851399) (xy 392.975159 -304.993591) (xy 392.95907 -305.135101)
			(xy 392.935 -305.275473) (xy 392.903028 -305.414259) (xy 392.863255 -305.551014) (xy 392.815809 -305.685299)
			(xy 392.760842 -305.816686) (xy 392.698529 -305.944752) (xy 392.629071 -306.069087) (xy 392.55269 -306.189294)
			(xy 392.469631 -306.304987) (xy 392.380159 -306.415796) (xy 392.284562 -306.521365) (xy 392.183145 -306.621357)
			(xy 392.076233 -306.715451) (xy 391.964169 -306.803345) (xy 391.847313 -306.884759) (xy 391.726037 -306.959432)
			(xy 391.600731 -307.027123) (xy 391.471796 -307.087617) (xy 391.339645 -307.14072) (xy 391.204702 -307.186261)
			(xy 391.067398 -307.224095) (xy 390.928173 -307.2541) (xy 390.787474 -307.27618) (xy 390.645752 -307.290266)
			(xy 390.503459 -307.29631) (xy 390.361052 -307.294295) (xy 390.218987 -307.284226) (xy 390.07772 -307.266136)
			(xy 389.937702 -307.240083) (xy 389.799383 -307.20615) (xy 389.663204 -307.164445) (xy 389.529604 -307.115104)
			(xy 389.399008 -307.058283) (xy 389.271837 -306.994164) (xy 389.148497 -306.922954) (xy 389.029383 -306.844879)
			(xy 388.914877 -306.760191) (xy 388.805345 -306.66916) (xy 388.701139 -306.572079) (xy 388.602593 -306.469257)
			(xy 388.510021 -306.361024) (xy 388.423721 -306.247728) (xy 388.343969 -306.129731) (xy 388.27102 -306.007411)
			(xy 388.205108 -305.88116) (xy 388.146445 -305.751381) (xy 388.095218 -305.618492) (xy 388.051591 -305.482918)
			(xy 388.015704 -305.345092) (xy 387.987672 -305.205457) (xy 387.967584 -305.06446) (xy 387.955506 -304.922552)
			(xy 387.951476 -304.780188) (xy 334.545164 -304.780188) (xy 334.535027 -304.814711) (xy 334.51237 -304.864321)
			(xy 334.482884 -304.910202) (xy 334.447169 -304.951419) (xy 334.405952 -304.987134) (xy 334.360071 -305.01662)
			(xy 334.310461 -305.039277) (xy 334.258131 -305.054642) (xy 334.204147 -305.062404) (xy 334.149609 -305.062404)
			(xy 334.095625 -305.054642) (xy 334.043295 -305.039277) (xy 333.993685 -305.01662) (xy 333.947804 -304.987134)
			(xy 333.906587 -304.951419) (xy 333.870872 -304.910202) (xy 333.841386 -304.864321) (xy 333.818729 -304.814711)
			(xy 333.803364 -304.762381) (xy 333.795602 -304.708397) (xy 333.795116 -304.681128) (xy 331.781608 -304.681128)
			(xy 331.783186 -304.708985) (xy 331.78369 -304.780188) (xy 331.783186 -304.851391) (xy 331.77513 -304.99357)
			(xy 331.759042 -305.135065) (xy 331.734975 -305.275423) (xy 331.703006 -305.414195) (xy 331.663237 -305.550936)
			(xy 331.615796 -305.685208) (xy 331.560834 -305.816581) (xy 331.498528 -305.944634) (xy 331.429077 -306.068957)
			(xy 331.352704 -306.189152) (xy 331.269653 -306.304833) (xy 331.18019 -306.415631) (xy 331.164492 -306.432966)
			(xy 340.495636 -306.432966) (xy 340.495636 -305.569366) (xy 340.496122 -305.542115) (xy 340.503878 -305.488167)
			(xy 340.519233 -305.435872) (xy 340.541875 -305.386295) (xy 340.571341 -305.340445) (xy 340.607032 -305.299254)
			(xy 340.648223 -305.263563) (xy 340.694073 -305.234097) (xy 340.74365 -305.211455) (xy 340.795945 -305.1961)
			(xy 340.849893 -305.188344) (xy 340.904395 -305.188344) (xy 340.958343 -305.1961) (xy 341.010638 -305.211455)
			(xy 341.060215 -305.234097) (xy 341.106065 -305.263563) (xy 341.147256 -305.299254) (xy 341.182947 -305.340445)
			(xy 341.212413 -305.386295) (xy 341.235055 -305.435872) (xy 341.25041 -305.488167) (xy 341.258166 -305.542115)
			(xy 341.258652 -305.569366) (xy 341.258652 -306.432966) (xy 341.258166 -306.460217) (xy 341.25041 -306.514165)
			(xy 341.235055 -306.56646) (xy 341.212413 -306.616037) (xy 341.182947 -306.661887) (xy 341.147256 -306.703078)
			(xy 341.106065 -306.738769) (xy 341.060215 -306.768235) (xy 341.010638 -306.790877) (xy 340.958343 -306.806232)
			(xy 340.904395 -306.813988) (xy 340.849893 -306.813988) (xy 340.795945 -306.806232) (xy 340.74365 -306.790877)
			(xy 340.694073 -306.768235) (xy 340.648223 -306.738769) (xy 340.607032 -306.703078) (xy 340.571341 -306.661887)
			(xy 340.541875 -306.616037) (xy 340.519233 -306.56646) (xy 340.503878 -306.514165) (xy 340.496122 -306.460217)
			(xy 340.495636 -306.432966) (xy 331.164492 -306.432966) (xy 331.084602 -306.521189) (xy 330.983195 -306.621171)
			(xy 330.876295 -306.715255) (xy 330.764242 -306.803141) (xy 330.647397 -306.884547) (xy 330.526134 -306.959212)
			(xy 330.400841 -307.026897) (xy 330.271919 -307.087384) (xy 330.139781 -307.140482) (xy 330.004851 -307.186018)
			(xy 329.867561 -307.223848) (xy 329.728351 -307.25385) (xy 329.587666 -307.275929) (xy 329.445958 -307.290012)
			(xy 329.303679 -307.296056) (xy 329.161287 -307.294041) (xy 329.019237 -307.283973) (xy 328.877983 -307.265885)
			(xy 328.73798 -307.239834) (xy 328.599674 -307.205905) (xy 328.46351 -307.164205) (xy 328.329922 -307.114868)
			(xy 328.19934 -307.058053) (xy 328.072182 -306.993941) (xy 327.948854 -306.922737) (xy 327.829752 -306.844671)
			(xy 327.715258 -306.759991) (xy 327.605737 -306.66897) (xy 327.501542 -306.571898) (xy 327.403005 -306.469086)
			(xy 327.310443 -306.360865) (xy 327.224151 -306.24758) (xy 327.144407 -306.129595) (xy 327.071466 -306.007287)
			(xy 327.005561 -305.881048) (xy 326.946903 -305.751283) (xy 326.895681 -305.618408) (xy 326.852059 -305.482847)
			(xy 326.816175 -305.345035) (xy 326.788146 -305.205414) (xy 326.768061 -305.064431) (xy 326.755984 -304.922538)
			(xy 326.751954 -304.780188) (xy 145.04365 -304.780188) (xy 145.043652 -304.780442) (xy 145.043148 -304.851653)
			(xy 145.035091 -304.993845) (xy 145.019002 -305.135355) (xy 144.994932 -305.275727) (xy 144.96296 -305.414513)
			(xy 144.923187 -305.551268) (xy 144.875741 -305.685553) (xy 144.820774 -305.81694) (xy 144.758461 -305.945006)
			(xy 144.689003 -306.069341) (xy 144.612622 -306.189548) (xy 144.529563 -306.305241) (xy 144.440091 -306.41605)
			(xy 144.344494 -306.521619) (xy 144.243077 -306.621611) (xy 144.136165 -306.715705) (xy 144.024101 -306.803599)
			(xy 143.907245 -306.885013) (xy 143.785969 -306.959686) (xy 143.660663 -307.027377) (xy 143.531728 -307.087871)
			(xy 143.399577 -307.140974) (xy 143.264634 -307.186515) (xy 143.12733 -307.224349) (xy 142.988105 -307.254354)
			(xy 142.847406 -307.276434) (xy 142.705684 -307.29052) (xy 142.563391 -307.296564) (xy 142.420984 -307.294549)
			(xy 142.278919 -307.28448) (xy 142.137652 -307.26639) (xy 141.997634 -307.240337) (xy 141.859315 -307.206404)
			(xy 141.723136 -307.164699) (xy 141.589536 -307.115358) (xy 141.45894 -307.058537) (xy 141.331769 -306.994418)
			(xy 141.208429 -306.923208) (xy 141.089315 -306.845133) (xy 140.974809 -306.760445) (xy 140.865277 -306.669414)
			(xy 140.761071 -306.572333) (xy 140.662525 -306.469511) (xy 140.569953 -306.361278) (xy 140.483653 -306.247982)
			(xy 140.403901 -306.129985) (xy 140.330952 -306.007665) (xy 140.26504 -305.881414) (xy 140.206377 -305.751635)
			(xy 140.15515 -305.618746) (xy 140.111523 -305.483172) (xy 140.075636 -305.345346) (xy 140.047604 -305.205711)
			(xy 140.027516 -305.064714) (xy 140.015438 -304.922806) (xy 140.011408 -304.780442) (xy 83.843622 -304.780442)
			(xy 83.843118 -304.851645) (xy 83.835062 -304.993824) (xy 83.818974 -305.135319) (xy 83.794907 -305.275677)
			(xy 83.762938 -305.414449) (xy 83.723169 -305.55119) (xy 83.675728 -305.685462) (xy 83.620766 -305.816835)
			(xy 83.55846 -305.944888) (xy 83.489009 -306.069211) (xy 83.412636 -306.189406) (xy 83.329585 -306.305087)
			(xy 83.240122 -306.415885) (xy 83.144534 -306.521443) (xy 83.043127 -306.621425) (xy 82.936227 -306.715509)
			(xy 82.824174 -306.803395) (xy 82.707329 -306.884801) (xy 82.586066 -306.959466) (xy 82.460773 -307.027151)
			(xy 82.331851 -307.087638) (xy 82.199713 -307.140736) (xy 82.064783 -307.186272) (xy 81.927493 -307.224102)
			(xy 81.788283 -307.254104) (xy 81.647598 -307.276183) (xy 81.50589 -307.290266) (xy 81.363611 -307.29631)
			(xy 81.221219 -307.294295) (xy 81.079169 -307.284227) (xy 80.937915 -307.266139) (xy 80.797912 -307.240088)
			(xy 80.659606 -307.206159) (xy 80.523442 -307.164459) (xy 80.389854 -307.115122) (xy 80.259272 -307.058307)
			(xy 80.132114 -306.994195) (xy 80.008786 -306.922991) (xy 79.889684 -306.844925) (xy 79.77519 -306.760245)
			(xy 79.665669 -306.669224) (xy 79.561474 -306.572152) (xy 79.462937 -306.46934) (xy 79.370375 -306.361119)
			(xy 79.284083 -306.247834) (xy 79.204339 -306.129849) (xy 79.131398 -306.007541) (xy 79.065493 -305.881302)
			(xy 79.006835 -305.751537) (xy 78.955613 -305.618662) (xy 78.911991 -305.483101) (xy 78.876107 -305.345289)
			(xy 78.848078 -305.205668) (xy 78.827993 -305.064685) (xy 78.815916 -304.922792) (xy 78.811886 -304.780442)
			(xy 2.509012 -304.780442) (xy 2.509012 -309.504588) (xy 79.192628 -309.504588) (xy 79.192628 -308.640988)
			(xy 79.193114 -308.613737) (xy 79.20087 -308.559789) (xy 79.216225 -308.507494) (xy 79.238867 -308.457917)
			(xy 79.268333 -308.412067) (xy 79.304024 -308.370876) (xy 79.345215 -308.335185) (xy 79.391065 -308.305719)
			(xy 79.440642 -308.283077) (xy 79.492937 -308.267722) (xy 79.546885 -308.259966) (xy 79.601387 -308.259966)
			(xy 79.655335 -308.267722) (xy 79.70763 -308.283077) (xy 79.757207 -308.305719) (xy 79.803057 -308.335185)
			(xy 79.844248 -308.370876) (xy 79.879939 -308.412067) (xy 79.909405 -308.457917) (xy 79.92811 -308.498873)
			(xy 93.275072 -308.498873) (xy 93.275072 -308.444327) (xy 93.282834 -308.390335) (xy 93.298202 -308.337998)
			(xy 93.320862 -308.288381) (xy 93.350352 -308.242493) (xy 93.386073 -308.20127) (xy 93.427297 -308.16555)
			(xy 93.473184 -308.13606) (xy 93.522802 -308.113401) (xy 93.575139 -308.098034) (xy 93.629131 -308.090271)
			(xy 93.656404 -308.089808) (xy 94.520004 -308.089808) (xy 94.547271 -308.090355) (xy 94.60125 -308.098116)
			(xy 94.653575 -308.113481) (xy 94.703181 -308.136135) (xy 94.749058 -308.165619) (xy 94.790271 -308.201331)
			(xy 94.825983 -308.242546) (xy 94.855467 -308.288423) (xy 94.878121 -308.338029) (xy 94.893485 -308.390354)
			(xy 94.901246 -308.444333) (xy 94.901246 -308.498867) (xy 94.893485 -308.552846) (xy 94.878121 -308.605171)
			(xy 94.855467 -308.654777) (xy 94.825983 -308.700654) (xy 94.790271 -308.741869) (xy 94.749058 -308.777581)
			(xy 94.703181 -308.807065) (xy 94.653575 -308.829719) (xy 94.60125 -308.845084) (xy 94.547271 -308.852845)
			(xy 94.520004 -308.853332) (xy 93.656404 -308.853332) (xy 93.629131 -308.852929) (xy 93.575139 -308.845166)
			(xy 93.522802 -308.829799) (xy 93.473184 -308.80714) (xy 93.427297 -308.77765) (xy 93.386073 -308.74193)
			(xy 93.350352 -308.700707) (xy 93.320862 -308.654819) (xy 93.298202 -308.605202) (xy 93.282834 -308.552865)
			(xy 93.275072 -308.498873) (xy 79.92811 -308.498873) (xy 79.932047 -308.507494) (xy 79.947402 -308.559789)
			(xy 79.955158 -308.613737) (xy 79.955644 -308.640988) (xy 79.955644 -309.303166) (xy 341.51824 -309.303166)
			(xy 341.51824 -308.439566) (xy 341.518726 -308.412297) (xy 341.526488 -308.358313) (xy 341.541853 -308.305983)
			(xy 341.56451 -308.256373) (xy 341.593996 -308.210492) (xy 341.629711 -308.169275) (xy 341.670928 -308.13356)
			(xy 341.716809 -308.104074) (xy 341.766419 -308.081417) (xy 341.818749 -308.066052) (xy 341.872733 -308.05829)
			(xy 341.927271 -308.05829) (xy 341.981255 -308.066052) (xy 342.033585 -308.081417) (xy 342.083195 -308.104074)
			(xy 342.129076 -308.13356) (xy 342.170293 -308.169275) (xy 342.206008 -308.210492) (xy 342.235494 -308.256373)
			(xy 342.258151 -308.305983) (xy 342.273516 -308.358313) (xy 342.281278 -308.412297) (xy 342.281764 -308.439566)
			(xy 342.281764 -309.303166) (xy 342.281278 -309.330435) (xy 342.273516 -309.384419) (xy 342.258151 -309.436749)
			(xy 342.235494 -309.486359) (xy 342.206008 -309.53224) (xy 342.170293 -309.573457) (xy 342.129076 -309.609172)
			(xy 342.083195 -309.638658) (xy 342.033585 -309.661315) (xy 341.981255 -309.67668) (xy 341.927271 -309.684442)
			(xy 341.872733 -309.684442) (xy 341.818749 -309.67668) (xy 341.766419 -309.661315) (xy 341.716809 -309.638658)
			(xy 341.670928 -309.609172) (xy 341.629711 -309.573457) (xy 341.593996 -309.53224) (xy 341.56451 -309.486359)
			(xy 341.541853 -309.436749) (xy 341.526488 -309.384419) (xy 341.518726 -309.330435) (xy 341.51824 -309.303166)
			(xy 79.955644 -309.303166) (xy 79.955644 -309.504588) (xy 79.955158 -309.531839) (xy 79.947402 -309.585787)
			(xy 79.932047 -309.638082) (xy 79.909405 -309.687659) (xy 79.879939 -309.733509) (xy 79.844248 -309.7747)
			(xy 79.803057 -309.810391) (xy 79.757207 -309.839857) (xy 79.70763 -309.862499) (xy 79.655335 -309.877854)
			(xy 79.601387 -309.88561) (xy 79.546885 -309.88561) (xy 79.492937 -309.877854) (xy 79.440642 -309.862499)
			(xy 79.391065 -309.839857) (xy 79.345215 -309.810391) (xy 79.304024 -309.7747) (xy 79.268333 -309.733509)
			(xy 79.238867 -309.687659) (xy 79.216225 -309.638082) (xy 79.20087 -309.585787) (xy 79.193114 -309.531839)
			(xy 79.192628 -309.504588) (xy 2.509012 -309.504588) (xy 2.509012 -310.603646) (xy 98.925888 -310.603646)
			(xy 98.925888 -309.740046) (xy 98.926374 -309.712795) (xy 98.93413 -309.658847) (xy 98.949485 -309.606552)
			(xy 98.972127 -309.556975) (xy 99.001593 -309.511125) (xy 99.037284 -309.469934) (xy 99.078475 -309.434243)
			(xy 99.124325 -309.404777) (xy 99.173902 -309.382135) (xy 99.226197 -309.36678) (xy 99.280145 -309.359024)
			(xy 99.334647 -309.359024) (xy 99.388595 -309.36678) (xy 99.44089 -309.382135) (xy 99.490467 -309.404777)
			(xy 99.536317 -309.434243) (xy 99.577508 -309.469934) (xy 99.613199 -309.511125) (xy 99.642665 -309.556975)
			(xy 99.665307 -309.606552) (xy 99.680662 -309.658847) (xy 99.688418 -309.712795) (xy 99.688904 -309.740046)
			(xy 99.688904 -310.603646) (xy 99.688418 -310.630897) (xy 99.680662 -310.684845) (xy 99.665307 -310.73714)
			(xy 99.642665 -310.786717) (xy 99.613199 -310.832567) (xy 99.577508 -310.873758) (xy 99.536317 -310.909449)
			(xy 99.490467 -310.938915) (xy 99.44089 -310.961557) (xy 99.388595 -310.976912) (xy 99.334647 -310.984668)
			(xy 99.280145 -310.984668) (xy 99.226197 -310.976912) (xy 99.173902 -310.961557) (xy 99.124325 -310.938915)
			(xy 99.078475 -310.909449) (xy 99.037284 -310.873758) (xy 99.001593 -310.832567) (xy 98.972127 -310.786717)
			(xy 98.949485 -310.73714) (xy 98.93413 -310.684845) (xy 98.926374 -310.630897) (xy 98.925888 -310.603646)
			(xy 2.509012 -310.603646) (xy 2.509012 -311.513728) (xy 347.772228 -311.513728) (xy 347.772228 -310.650128)
			(xy 347.772714 -310.622859) (xy 347.780476 -310.568875) (xy 347.795841 -310.516545) (xy 347.818498 -310.466935)
			(xy 347.847984 -310.421054) (xy 347.883699 -310.379837) (xy 347.924916 -310.344122) (xy 347.970797 -310.314636)
			(xy 348.020407 -310.291979) (xy 348.072737 -310.276614) (xy 348.126721 -310.268852) (xy 348.181259 -310.268852)
			(xy 348.235243 -310.276614) (xy 348.287573 -310.291979) (xy 348.337183 -310.314636) (xy 348.383064 -310.344122)
			(xy 348.424281 -310.379837) (xy 348.459996 -310.421054) (xy 348.489482 -310.466935) (xy 348.512139 -310.516545)
			(xy 348.527504 -310.568875) (xy 348.535266 -310.622859) (xy 348.535752 -310.650128) (xy 348.535752 -311.513728)
			(xy 348.535266 -311.540997) (xy 348.527504 -311.594981) (xy 348.512139 -311.647311) (xy 348.489482 -311.696921)
			(xy 348.459996 -311.742802) (xy 348.424281 -311.784019) (xy 348.383064 -311.819734) (xy 348.337183 -311.84922)
			(xy 348.287573 -311.871877) (xy 348.235243 -311.887242) (xy 348.181259 -311.895004) (xy 348.126721 -311.895004)
			(xy 348.072737 -311.887242) (xy 348.020407 -311.871877) (xy 347.970797 -311.84922) (xy 347.924916 -311.819734)
			(xy 347.883699 -311.784019) (xy 347.847984 -311.742802) (xy 347.818498 -311.696921) (xy 347.795841 -311.647311)
			(xy 347.780476 -311.594981) (xy 347.772714 -311.540997) (xy 347.772228 -311.513728) (xy 2.509012 -311.513728)
			(xy 2.509012 -314.997338) (xy 98.330512 -314.997338) (xy 98.330512 -314.133738) (xy 98.330998 -314.106487)
			(xy 98.338754 -314.052539) (xy 98.354109 -314.000244) (xy 98.376751 -313.950667) (xy 98.406217 -313.904817)
			(xy 98.441908 -313.863626) (xy 98.483099 -313.827935) (xy 98.528949 -313.798469) (xy 98.578526 -313.775827)
			(xy 98.630821 -313.760472) (xy 98.684769 -313.752716) (xy 98.739271 -313.752716) (xy 98.793219 -313.760472)
			(xy 98.845514 -313.775827) (xy 98.895091 -313.798469) (xy 98.940941 -313.827935) (xy 98.982132 -313.863626)
			(xy 99.017823 -313.904817) (xy 99.047289 -313.950667) (xy 99.069931 -314.000244) (xy 99.085286 -314.052539)
			(xy 99.093042 -314.106487) (xy 99.093528 -314.133738) (xy 99.093528 -314.997338) (xy 99.093042 -315.024589)
			(xy 99.085286 -315.078537) (xy 99.069931 -315.130832) (xy 99.047289 -315.180409) (xy 99.017823 -315.226259)
			(xy 98.982132 -315.26745) (xy 98.940941 -315.303141) (xy 98.895091 -315.332607) (xy 98.845514 -315.355249)
			(xy 98.793219 -315.370604) (xy 98.739271 -315.37836) (xy 98.684769 -315.37836) (xy 98.630821 -315.370604)
			(xy 98.578526 -315.355249) (xy 98.528949 -315.332607) (xy 98.483099 -315.303141) (xy 98.441908 -315.26745)
			(xy 98.406217 -315.226259) (xy 98.376751 -315.180409) (xy 98.354109 -315.130832) (xy 98.338754 -315.078537)
			(xy 98.330998 -315.024589) (xy 98.330512 -314.997338) (xy 2.509012 -314.997338) (xy 2.509012 -336.9884)
			(xy 70.218517 -336.9884) (xy 70.222508 -336.904617) (xy 70.234446 -336.821593) (xy 70.254221 -336.74008)
			(xy 70.281655 -336.660815) (xy 70.3165 -336.584518) (xy 70.35844 -336.511878) (xy 70.407095 -336.443554)
			(xy 70.462025 -336.380164) (xy 70.522731 -336.322283) (xy 70.588664 -336.270435) (xy 70.659228 -336.225089)
			(xy 70.733783 -336.186656) (xy 70.811653 -336.155484) (xy 70.892134 -336.131855) (xy 70.974497 -336.115984)
			(xy 71.057995 -336.108014) (xy 71.099934 -336.107532) (xy 71.137123 -336.107938) (xy 71.211236 -336.114223)
			(xy 71.284556 -336.126727) (xy 71.356562 -336.145363) (xy 71.39178 -336.157316) (xy 71.399977 -336.15983)
			(xy 71.417111 -336.15983) (xy 71.425308 -336.157316) (xy 71.460496 -336.145371) (xy 71.532436 -336.126725)
			(xy 71.605692 -336.114215) (xy 71.679742 -336.107929) (xy 71.7169 -336.107532) (xy 71.717408 -336.107532)
			(xy 71.748142 -336.108294) (xy 71.757646 -336.056715) (xy 71.787316 -335.956115) (xy 71.807324 -335.907634)
			(xy 71.810983 -335.897931) (xy 71.810971 -335.877211) (xy 71.807324 -335.867502) (xy 71.790219 -335.826242)
			(xy 71.763427 -335.741032) (xy 71.74539 -335.653549) (xy 71.736293 -335.564691) (xy 71.735696 -335.52003)
			(xy 71.735696 -335.519268) (xy 71.736195 -335.477343) (xy 71.744165 -335.393872) (xy 71.760034 -335.311537)
			(xy 71.783657 -335.231083) (xy 71.814821 -335.153239) (xy 71.853244 -335.078709) (xy 71.898577 -335.00817)
			(xy 71.95041 -334.942259) (xy 72.008273 -334.881573) (xy 72.071643 -334.826663) (xy 72.139946 -334.778025)
			(xy 72.212563 -334.7361) (xy 72.288836 -334.701267) (xy 72.368075 -334.673842) (xy 72.449561 -334.654073)
			(xy 72.532558 -334.64214) (xy 72.616314 -334.638151) (xy 72.70007 -334.64214) (xy 72.783067 -334.654073)
			(xy 72.864553 -334.673842) (xy 72.943792 -334.701267) (xy 73.020065 -334.7361) (xy 73.092682 -334.778025)
			(xy 73.160985 -334.826663) (xy 73.224355 -334.881573) (xy 73.282218 -334.942259) (xy 73.334051 -335.00817)
			(xy 73.379384 -335.078709) (xy 73.417807 -335.153239) (xy 73.448971 -335.231083) (xy 73.472594 -335.311537)
			(xy 73.488463 -335.393872) (xy 73.496433 -335.477343) (xy 73.496932 -335.519268) (xy 73.496932 -335.52003)
			(xy 73.496371 -335.564694) (xy 73.487295 -335.653559) (xy 73.46926 -335.741047) (xy 73.442452 -335.826257)
			(xy 73.425304 -335.867502) (xy 73.421681 -335.877216) (xy 73.421669 -335.897926) (xy 73.425304 -335.907634)
			(xy 73.441139 -335.945575) (xy 73.466487 -336.02379) (xy 73.484436 -336.104027) (xy 73.494829 -336.185587)
			(xy 73.496678 -336.226658) (xy 73.496932 -336.24012) (xy 73.51141 -336.263234) (xy 73.61301 -336.31759)
			(xy 73.639934 -336.316828) (xy 73.651618 -336.309462) (xy 73.686811 -336.288202) (xy 73.76042 -336.251553)
			(xy 73.837094 -336.221845) (xy 73.91618 -336.199333) (xy 73.997005 -336.184209) (xy 74.07888 -336.1766)
			(xy 74.119994 -336.176112) (xy 74.161107 -336.176619) (xy 74.242983 -336.184205) (xy 74.32381 -336.199313)
			(xy 74.402898 -336.221815) (xy 74.479573 -336.251518) (xy 74.553179 -336.288168) (xy 74.623091 -336.331454)
			(xy 74.68871 -336.381006) (xy 74.749477 -336.4364) (xy 74.804874 -336.497166) (xy 74.854428 -336.562783)
			(xy 74.897716 -336.632693) (xy 74.934369 -336.706298) (xy 74.964075 -336.782971) (xy 74.986579 -336.862059)
			(xy 75.001691 -336.942885) (xy 75.005252 -336.9813) (xy 78.574105 -336.9813) (xy 78.578096 -336.897517)
			(xy 78.590033 -336.814493) (xy 78.609809 -336.732979) (xy 78.637243 -336.653715) (xy 78.672087 -336.577417)
			(xy 78.714027 -336.504776) (xy 78.762681 -336.436452) (xy 78.81761 -336.373061) (xy 78.878316 -336.31518)
			(xy 78.94425 -336.26333) (xy 79.014813 -336.217984) (xy 79.089367 -336.179549) (xy 79.167237 -336.148376)
			(xy 79.247718 -336.124747) (xy 79.330081 -336.108874) (xy 79.413579 -336.100902) (xy 79.455518 -336.10042)
			(xy 79.492708 -336.100802) (xy 79.566821 -336.107094) (xy 79.640141 -336.119606) (xy 79.712146 -336.138248)
			(xy 79.747364 -336.150204) (xy 79.755561 -336.152718) (xy 79.772695 -336.152718) (xy 79.780892 -336.150204)
			(xy 79.816103 -336.138226) (xy 79.888108 -336.119576) (xy 79.961431 -336.107072) (xy 80.035547 -336.100804)
			(xy 80.072738 -336.10042) (xy 80.10906 -336.101182) (xy 80.115245 -336.066241) (xy 80.132513 -335.997409)
			(xy 80.155273 -335.930194) (xy 80.169004 -335.897474) (xy 80.172641 -335.887764) (xy 80.172644 -335.86705)
			(xy 80.169004 -335.857342) (xy 80.151879 -335.81609) (xy 80.125092 -335.730877) (xy 80.107061 -335.643392)
			(xy 80.09797 -335.554532) (xy 80.097376 -335.50987) (xy 80.097376 -335.509108) (xy 80.097875 -335.467183)
			(xy 80.105845 -335.383712) (xy 80.121714 -335.301377) (xy 80.145337 -335.220923) (xy 80.176501 -335.143079)
			(xy 80.214924 -335.068549) (xy 80.260257 -334.99801) (xy 80.31209 -334.932099) (xy 80.369953 -334.871413)
			(xy 80.433323 -334.816503) (xy 80.501626 -334.767865) (xy 80.574243 -334.72594) (xy 80.650516 -334.691107)
			(xy 80.729755 -334.663682) (xy 80.811241 -334.643913) (xy 80.894238 -334.63198) (xy 80.977994 -334.627991)
			(xy 81.06175 -334.63198) (xy 81.144747 -334.643913) (xy 81.226233 -334.663682) (xy 81.305472 -334.691107)
			(xy 81.381745 -334.72594) (xy 81.454362 -334.767865) (xy 81.522665 -334.816503) (xy 81.586035 -334.871413)
			(xy 81.643898 -334.932099) (xy 81.695731 -334.99801) (xy 81.741064 -335.068549) (xy 81.779487 -335.143079)
			(xy 81.810651 -335.220923) (xy 81.834274 -335.301377) (xy 81.850143 -335.383712) (xy 81.858113 -335.467183)
			(xy 81.858612 -335.509108) (xy 81.858612 -335.50987) (xy 81.858066 -335.554534) (xy 81.848986 -335.6434)
			(xy 81.830947 -335.730888) (xy 81.804134 -335.816098) (xy 81.786984 -335.857342) (xy 81.783338 -335.867049)
			(xy 81.783341 -335.887765) (xy 81.786984 -335.897474) (xy 81.802748 -335.935334) (xy 81.827987 -336.013369)
			(xy 81.845871 -336.093411) (xy 81.856247 -336.174768) (xy 81.858104 -336.215736) (xy 81.858828 -336.22455)
			(xy 81.865419 -336.240944) (xy 81.877182 -336.254128) (xy 81.884774 -336.258662) (xy 81.973928 -336.306922)
			(xy 82.000852 -336.30616) (xy 82.012536 -336.299048) (xy 82.047432 -336.278305) (xy 82.120306 -336.242523)
			(xy 82.19614 -336.213534) (xy 82.2743 -336.191579) (xy 82.354137 -336.176843) (xy 82.434985 -336.169448)
			(xy 82.475578 -336.169) (xy 82.516691 -336.169534) (xy 82.598566 -336.177119) (xy 82.679391 -336.192225)
			(xy 82.758479 -336.214725) (xy 82.835153 -336.244426) (xy 82.908759 -336.281075) (xy 82.97867 -336.324359)
			(xy 83.044289 -336.373909) (xy 83.105056 -336.429302) (xy 83.160453 -336.490065) (xy 83.210007 -336.555681)
			(xy 83.253296 -336.625589) (xy 83.28995 -336.699193) (xy 83.319656 -336.775864) (xy 83.342161 -336.85495)
			(xy 83.357273 -336.935775) (xy 83.360149 -336.9668) (xy 86.931981 -336.9668) (xy 86.935971 -336.883042)
			(xy 86.947905 -336.800043) (xy 86.967674 -336.718554) (xy 86.9951 -336.639313) (xy 87.029935 -336.563039)
			(xy 87.071862 -336.490421) (xy 87.120503 -336.422117) (xy 87.175416 -336.358746) (xy 87.236104 -336.300883)
			(xy 87.302018 -336.24905) (xy 87.37256 -336.203717) (xy 87.447092 -336.165296) (xy 87.52494 -336.134133)
			(xy 87.605396 -336.110512) (xy 87.687734 -336.094645) (xy 87.771208 -336.086677) (xy 87.813134 -336.086196)
			(xy 87.81415 -336.086196) (xy 87.851207 -336.086587) (xy 87.925057 -336.092856) (xy 87.998119 -336.105302)
			(xy 88.069879 -336.123838) (xy 88.10498 -336.135726) (xy 88.113177 -336.13824) (xy 88.130311 -336.13824)
			(xy 88.138508 -336.135726) (xy 88.173727 -336.123789) (xy 88.245736 -336.1052) (xy 88.319058 -336.092757)
			(xy 88.393169 -336.086549) (xy 88.430354 -336.086196) (xy 88.454992 -336.08645) (xy 88.464629 -336.040549)
			(xy 88.49238 -335.950951) (xy 88.510364 -335.907634) (xy 88.514021 -335.89793) (xy 88.514009 -335.877211)
			(xy 88.510364 -335.867502) (xy 88.493256 -335.826243) (xy 88.466465 -335.741033) (xy 88.448429 -335.65355)
			(xy 88.439333 -335.564691) (xy 88.438736 -335.52003) (xy 88.438736 -335.519268) (xy 88.439235 -335.477343)
			(xy 88.447205 -335.393872) (xy 88.463074 -335.311537) (xy 88.486697 -335.231083) (xy 88.517861 -335.153239)
			(xy 88.556284 -335.078709) (xy 88.601617 -335.00817) (xy 88.65345 -334.942259) (xy 88.711313 -334.881573)
			(xy 88.774683 -334.826663) (xy 88.842986 -334.778025) (xy 88.915603 -334.7361) (xy 88.991876 -334.701267)
			(xy 89.071115 -334.673842) (xy 89.152601 -334.654073) (xy 89.235598 -334.64214) (xy 89.319354 -334.638151)
			(xy 89.40311 -334.64214) (xy 89.486107 -334.654073) (xy 89.567593 -334.673842) (xy 89.646832 -334.701267)
			(xy 89.723105 -334.7361) (xy 89.795722 -334.778025) (xy 89.864025 -334.826663) (xy 89.927395 -334.881573)
			(xy 89.985258 -334.942259) (xy 90.037091 -335.00817) (xy 90.082424 -335.078709) (xy 90.120847 -335.153239)
			(xy 90.152011 -335.231083) (xy 90.175634 -335.311537) (xy 90.191503 -335.393872) (xy 90.199473 -335.477343)
			(xy 90.199972 -335.519268) (xy 90.199972 -335.52003) (xy 90.199408 -335.564694) (xy 90.190332 -335.653559)
			(xy 90.172298 -335.741047) (xy 90.145491 -335.826257) (xy 90.128344 -335.867502) (xy 90.124724 -335.877216)
			(xy 90.124712 -335.897925) (xy 90.128344 -335.907634) (xy 90.14352 -335.944017) (xy 90.168055 -336.018939)
			(xy 90.185802 -336.095753) (xy 90.196619 -336.173844) (xy 90.198956 -336.213196) (xy 90.198956 -336.21345)
			(xy 90.199799 -336.222253) (xy 90.206694 -336.238523) (xy 90.218709 -336.251482) (xy 90.226388 -336.255868)
			(xy 90.316812 -336.302604) (xy 90.343482 -336.301334) (xy 90.355166 -336.293968) (xy 90.390883 -336.271832)
			(xy 90.465707 -336.233583) (xy 90.543804 -336.20256) (xy 90.624479 -336.17904) (xy 90.707013 -336.163233)
			(xy 90.790669 -336.155279) (xy 90.832686 -336.154776) (xy 90.833194 -336.154776) (xy 90.874302 -336.155218)
			(xy 90.956167 -336.162803) (xy 91.036983 -336.177907) (xy 91.116061 -336.200402) (xy 91.192727 -336.230097)
			(xy 91.266326 -336.266738) (xy 91.336231 -336.310013) (xy 91.401845 -336.359552) (xy 91.46261 -336.414933)
			(xy 91.518006 -336.475684) (xy 91.567562 -336.541286) (xy 91.610854 -336.61118) (xy 91.647513 -336.68477)
			(xy 91.677227 -336.761428) (xy 91.699742 -336.840501) (xy 91.714867 -336.921313) (xy 91.722471 -337.003176)
			(xy 91.722641 -337.0176) (xy 95.263181 -337.0176) (xy 95.267171 -336.933842) (xy 95.279105 -336.850843)
			(xy 95.298874 -336.769354) (xy 95.3263 -336.690113) (xy 95.361135 -336.613839) (xy 95.403062 -336.541221)
			(xy 95.451703 -336.472917) (xy 95.506616 -336.409546) (xy 95.567304 -336.351683) (xy 95.633218 -336.29985)
			(xy 95.70376 -336.254517) (xy 95.778292 -336.216096) (xy 95.85614 -336.184933) (xy 95.936596 -336.161312)
			(xy 96.018934 -336.145445) (xy 96.102408 -336.137477) (xy 96.144334 -336.136996) (xy 96.14535 -336.136996)
			(xy 96.182407 -336.137387) (xy 96.256257 -336.143656) (xy 96.329319 -336.156102) (xy 96.401079 -336.174638)
			(xy 96.43618 -336.186526) (xy 96.444377 -336.18904) (xy 96.461511 -336.18904) (xy 96.469708 -336.186526)
			(xy 96.504897 -336.174599) (xy 96.576843 -336.15602) (xy 96.650101 -336.143577) (xy 96.724146 -336.137359)
			(xy 96.7613 -336.136996) (xy 96.761808 -336.136996) (xy 96.796352 -336.137504) (xy 96.805918 -336.09484)
			(xy 96.832381 -336.0115) (xy 96.849184 -335.971134) (xy 96.852845 -335.961431) (xy 96.852833 -335.940711)
			(xy 96.849184 -335.931002) (xy 96.832077 -335.889743) (xy 96.805286 -335.804532) (xy 96.78725 -335.717049)
			(xy 96.778153 -335.628191) (xy 96.777556 -335.58353) (xy 96.777556 -335.582768) (xy 96.778055 -335.540843)
			(xy 96.786025 -335.457372) (xy 96.801894 -335.375037) (xy 96.825517 -335.294583) (xy 96.856681 -335.216739)
			(xy 96.895104 -335.142209) (xy 96.940437 -335.07167) (xy 96.99227 -335.005759) (xy 97.050133 -334.945073)
			(xy 97.113503 -334.890163) (xy 97.181806 -334.841525) (xy 97.254423 -334.7996) (xy 97.330696 -334.764767)
			(xy 97.409935 -334.737342) (xy 97.491421 -334.717573) (xy 97.574418 -334.70564) (xy 97.658174 -334.701651)
			(xy 97.74193 -334.70564) (xy 97.824927 -334.717573) (xy 97.906413 -334.737342) (xy 97.985652 -334.764767)
			(xy 98.061925 -334.7996) (xy 98.134542 -334.841525) (xy 98.202845 -334.890163) (xy 98.266215 -334.945073)
			(xy 98.324078 -335.005759) (xy 98.375911 -335.07167) (xy 98.421244 -335.142209) (xy 98.459667 -335.216739)
			(xy 98.490831 -335.294583) (xy 98.514454 -335.375037) (xy 98.530323 -335.457372) (xy 98.538293 -335.540843)
			(xy 98.538792 -335.582768) (xy 98.538792 -335.58353) (xy 98.538226 -335.628194) (xy 98.529151 -335.717059)
			(xy 98.511117 -335.804547) (xy 98.484311 -335.889757) (xy 98.467164 -335.931002) (xy 98.463542 -335.940716)
			(xy 98.463531 -335.961426) (xy 98.467164 -335.971134) (xy 98.48433 -336.012473) (xy 98.511159 -336.097874)
			(xy 98.529194 -336.185554) (xy 98.538249 -336.27461) (xy 98.538792 -336.319368) (xy 98.538552 -336.350973)
			(xy 98.534101 -336.414026) (xy 98.529902 -336.445352) (xy 98.528378 -336.45602) (xy 98.53422 -336.477102)
			(xy 98.590608 -336.543396) (xy 98.597904 -336.55118) (xy 98.617064 -336.560504) (xy 98.627692 -336.56143)
			(xy 98.6282 -336.56143) (xy 98.671147 -336.563026) (xy 98.756458 -336.573467) (xy 98.840365 -336.592088)
			(xy 98.922084 -336.618714) (xy 99.000854 -336.653099) (xy 99.07594 -336.69492) (xy 99.146643 -336.743788)
			(xy 99.212303 -336.799248) (xy 99.272307 -336.860782) (xy 99.326097 -336.927817) (xy 99.362614 -336.9836)
			(xy 318.155561 -336.9836) (xy 318.15955 -336.899842) (xy 318.171484 -336.816843) (xy 318.191253 -336.735354)
			(xy 318.218678 -336.656114) (xy 318.253512 -336.579839) (xy 318.295438 -336.50722) (xy 318.344078 -336.438916)
			(xy 318.398989 -336.375544) (xy 318.459676 -336.317679) (xy 318.525589 -336.265845) (xy 318.59613 -336.220511)
			(xy 318.670661 -336.182087) (xy 318.748507 -336.150922) (xy 318.828963 -336.127298) (xy 318.911301 -336.111429)
			(xy 318.994774 -336.103459) (xy 319.0367 -336.10296) (xy 319.037716 -336.10296) (xy 319.074773 -336.103363)
			(xy 319.148622 -336.109628) (xy 319.221685 -336.122071) (xy 319.293445 -336.140604) (xy 319.328546 -336.15249)
			(xy 319.336743 -336.155004) (xy 319.353877 -336.155004) (xy 319.362074 -336.15249) (xy 319.397267 -336.140575)
			(xy 319.469212 -336.121992) (xy 319.542468 -336.109546) (xy 319.616513 -336.103324) (xy 319.653666 -336.10296)
			(xy 319.654174 -336.10296) (xy 319.681606 -336.103214) (xy 319.687655 -336.066844) (xy 319.704988 -335.995173)
			(xy 319.728195 -335.925184) (xy 319.742312 -335.891124) (xy 319.745871 -335.881532) (xy 319.745875 -335.86109)
			(xy 319.742312 -335.8515) (xy 319.725303 -335.810117) (xy 319.698681 -335.724692) (xy 319.680772 -335.637026)
			(xy 319.671759 -335.548004) (xy 319.671192 -335.503266) (xy 319.671192 -335.503012) (xy 319.671696 -335.460664)
			(xy 319.679747 -335.37635) (xy 319.695776 -335.293184) (xy 319.719637 -335.211917) (xy 319.751116 -335.133287)
			(xy 319.789927 -335.058006) (xy 319.835717 -334.986754) (xy 319.888073 -334.920178) (xy 319.946521 -334.85888)
			(xy 320.010531 -334.803415) (xy 320.079523 -334.754286) (xy 320.152873 -334.711937) (xy 320.229916 -334.676753)
			(xy 320.309955 -334.649051) (xy 320.392264 -334.629083) (xy 320.476099 -334.61703) (xy 320.5607 -334.613)
			(xy 320.645301 -334.61703) (xy 320.729136 -334.629083) (xy 320.811445 -334.649051) (xy 320.891484 -334.676753)
			(xy 320.968527 -334.711937) (xy 321.041877 -334.754286) (xy 321.110869 -334.803415) (xy 321.174879 -334.85888)
			(xy 321.233327 -334.920178) (xy 321.285683 -334.986754) (xy 321.331473 -335.058006) (xy 321.370284 -335.133287)
			(xy 321.401763 -335.211917) (xy 321.425624 -335.293184) (xy 321.441653 -335.37635) (xy 321.449704 -335.460664)
			(xy 321.450208 -335.503012) (xy 321.450208 -335.503266) (xy 321.449645 -335.548004) (xy 321.440627 -335.637026)
			(xy 321.422721 -335.724694) (xy 321.396107 -335.810121) (xy 321.379088 -335.8515) (xy 321.375596 -335.861115)
			(xy 321.37573 -335.881553) (xy 321.379342 -335.891124) (xy 321.395061 -335.929255) (xy 321.42019 -336.007817)
			(xy 321.437947 -336.088366) (xy 321.448179 -336.170212) (xy 321.449954 -336.211418) (xy 321.450208 -336.22488)
			(xy 321.464178 -336.24774) (xy 321.564762 -336.303112) (xy 321.591432 -336.302604) (xy 321.603116 -336.295746)
			(xy 321.637431 -336.275914) (xy 321.708951 -336.241747) (xy 321.783227 -336.214078) (xy 321.859671 -336.193127)
			(xy 321.937675 -336.179058) (xy 322.016621 -336.171985) (xy 322.056252 -336.17154) (xy 322.05676 -336.17154)
			(xy 322.097864 -336.17199) (xy 322.179721 -336.179572) (xy 322.26053 -336.194675) (xy 322.3396 -336.21717)
			(xy 322.416257 -336.246866) (xy 322.489847 -336.283508) (xy 322.559742 -336.326784) (xy 322.625346 -336.376325)
			(xy 322.686098 -336.431708) (xy 322.74148 -336.492461) (xy 322.791021 -336.558064) (xy 322.834296 -336.62796)
			(xy 322.870938 -336.70155) (xy 322.900632 -336.778207) (xy 322.923127 -336.857278) (xy 322.938229 -336.938087)
			(xy 322.941787 -336.9765) (xy 326.511148 -336.9765) (xy 326.515138 -336.892742) (xy 326.527072 -336.809743)
			(xy 326.546841 -336.728254) (xy 326.574266 -336.649013) (xy 326.609099 -336.572737) (xy 326.651025 -336.500118)
			(xy 326.699664 -336.431814) (xy 326.754575 -336.368441) (xy 326.815262 -336.310576) (xy 326.881174 -336.258741)
			(xy 326.951715 -336.213406) (xy 327.026246 -336.174981) (xy 327.104092 -336.143815) (xy 327.184547 -336.12019)
			(xy 327.266885 -336.104319) (xy 327.350358 -336.096347) (xy 327.392284 -336.095848) (xy 327.3933 -336.095848)
			(xy 327.430357 -336.096256) (xy 327.504206 -336.10252) (xy 327.577268 -336.114961) (xy 327.649028 -336.133493)
			(xy 327.68413 -336.145378) (xy 327.692327 -336.147892) (xy 327.709461 -336.147892) (xy 327.717658 -336.145378)
			(xy 327.752881 -336.133453) (xy 327.824889 -336.114861) (xy 327.898209 -336.102415) (xy 327.972319 -336.096203)
			(xy 328.009504 -336.095848) (xy 328.043286 -336.096356) (xy 328.05281 -336.047304) (xy 328.081456 -335.951571)
			(xy 328.100436 -335.905348) (xy 328.10398 -335.895751) (xy 328.103994 -335.875314) (xy 328.100436 -335.865724)
			(xy 328.083404 -335.82435) (xy 328.056787 -335.738922) (xy 328.038886 -335.651253) (xy 328.02988 -335.562229)
			(xy 328.029316 -335.51749) (xy 328.029316 -335.517236) (xy 328.02982 -335.474888) (xy 328.037871 -335.390574)
			(xy 328.0539 -335.307408) (xy 328.077761 -335.226141) (xy 328.10924 -335.147511) (xy 328.148051 -335.07223)
			(xy 328.193841 -335.000978) (xy 328.246197 -334.934402) (xy 328.304645 -334.873104) (xy 328.368655 -334.817639)
			(xy 328.437647 -334.76851) (xy 328.510997 -334.726161) (xy 328.58804 -334.690977) (xy 328.668079 -334.663275)
			(xy 328.750388 -334.643307) (xy 328.834223 -334.631254) (xy 328.918824 -334.627224) (xy 329.003425 -334.631254)
			(xy 329.08726 -334.643307) (xy 329.169569 -334.663275) (xy 329.249608 -334.690977) (xy 329.326651 -334.726161)
			(xy 329.400001 -334.76851) (xy 329.468993 -334.817639) (xy 329.533003 -334.873104) (xy 329.591451 -334.934402)
			(xy 329.643807 -335.000978) (xy 329.689597 -335.07223) (xy 329.728408 -335.147511) (xy 329.759887 -335.226141)
			(xy 329.783748 -335.307408) (xy 329.799777 -335.390574) (xy 329.807828 -335.474888) (xy 329.808332 -335.517236)
			(xy 329.808332 -335.51749) (xy 329.807775 -335.562229) (xy 329.798756 -335.651251) (xy 329.780848 -335.738918)
			(xy 329.754231 -335.824345) (xy 329.737212 -335.865724) (xy 329.733624 -335.875308) (xy 329.733638 -335.895757)
			(xy 329.737212 -335.905348) (xy 329.752022 -335.941175) (xy 329.776095 -336.014872) (xy 329.793653 -336.090386)
			(xy 329.804563 -336.167144) (xy 329.807062 -336.20583) (xy 329.807824 -336.219038) (xy 329.822048 -336.24139)
			(xy 329.91044 -336.288888) (xy 329.918254 -336.292745) (xy 329.93547 -336.295369) (xy 329.95256 -336.292022)
			(xy 329.960224 -336.287872) (xy 329.994483 -336.268147) (xy 330.065868 -336.23417) (xy 330.139986 -336.206662)
			(xy 330.216254 -336.18584) (xy 330.294068 -336.171868) (xy 330.372815 -336.164856) (xy 330.412344 -336.164428)
			(xy 330.453448 -336.164825) (xy 330.535306 -336.172414) (xy 330.616114 -336.187524) (xy 330.695183 -336.210025)
			(xy 330.771839 -336.239726) (xy 330.845427 -336.276373) (xy 330.91532 -336.319653) (xy 330.980922 -336.369198)
			(xy 331.041672 -336.424584) (xy 331.097053 -336.48534) (xy 331.146592 -336.550946) (xy 331.189866 -336.620843)
			(xy 331.226507 -336.694434) (xy 331.256201 -336.771093) (xy 331.278695 -336.850164) (xy 331.293797 -336.930973)
			(xy 331.296671 -336.962) (xy 334.868517 -336.962) (xy 334.872507 -336.878219) (xy 334.884444 -336.795197)
			(xy 334.904219 -336.713686) (xy 334.931652 -336.634423) (xy 334.966495 -336.558127) (xy 335.008433 -336.485488)
			(xy 335.057086 -336.417165) (xy 335.112013 -336.353776) (xy 335.172717 -336.295895) (xy 335.238647 -336.244046)
			(xy 335.309208 -336.198699) (xy 335.38376 -336.160265) (xy 335.461628 -336.129092) (xy 335.542106 -336.105461)
			(xy 335.624466 -336.089588) (xy 335.707962 -336.081615) (xy 335.7499 -336.081116) (xy 335.78709 -336.081504)
			(xy 335.861203 -336.087794) (xy 335.934522 -336.100304) (xy 336.006528 -336.118945) (xy 336.041746 -336.1309)
			(xy 336.049943 -336.133414) (xy 336.067077 -336.133414) (xy 336.075274 -336.1309) (xy 336.110487 -336.118927)
			(xy 336.182491 -336.100276) (xy 336.255813 -336.08777) (xy 336.329929 -336.0815) (xy 336.36712 -336.081116)
			(xy 336.407506 -336.082132) (xy 336.417036 -336.036786) (xy 336.444265 -335.948213) (xy 336.461862 -335.905348)
			(xy 336.465474 -335.895775) (xy 336.465619 -335.875336) (xy 336.462116 -335.865724) (xy 336.445083 -335.824351)
			(xy 336.418467 -335.738922) (xy 336.400565 -335.651253) (xy 336.39156 -335.562229) (xy 336.390996 -335.51749)
			(xy 336.390996 -335.517236) (xy 336.3915 -335.474888) (xy 336.399551 -335.390574) (xy 336.41558 -335.307408)
			(xy 336.439441 -335.226141) (xy 336.47092 -335.147511) (xy 336.509731 -335.07223) (xy 336.555521 -335.000978)
			(xy 336.607877 -334.934402) (xy 336.666325 -334.873104) (xy 336.730335 -334.817639) (xy 336.799327 -334.76851)
			(xy 336.872677 -334.726161) (xy 336.94972 -334.690977) (xy 337.029759 -334.663275) (xy 337.112068 -334.643307)
			(xy 337.195903 -334.631254) (xy 337.280504 -334.627224) (xy 337.365105 -334.631254) (xy 337.44894 -334.643307)
			(xy 337.531249 -334.663275) (xy 337.611288 -334.690977) (xy 337.688331 -334.726161) (xy 337.761681 -334.76851)
			(xy 337.830673 -334.817639) (xy 337.894683 -334.873104) (xy 337.953131 -334.934402) (xy 338.005487 -335.000978)
			(xy 338.051277 -335.07223) (xy 338.090088 -335.147511) (xy 338.121567 -335.226141) (xy 338.145428 -335.307408)
			(xy 338.161457 -335.390574) (xy 338.169508 -335.474888) (xy 338.170012 -335.517236) (xy 338.170012 -335.51749)
			(xy 338.169456 -335.562229) (xy 338.160437 -335.651251) (xy 338.142528 -335.738918) (xy 338.115912 -335.824345)
			(xy 338.098892 -335.865724) (xy 338.095386 -335.875335) (xy 338.09553 -335.895777) (xy 338.099146 -335.905348)
			(xy 338.117792 -335.95091) (xy 338.146101 -336.045203) (xy 338.163844 -336.142042) (xy 338.16798 -336.191098)
			(xy 338.168919 -336.199672) (xy 338.175759 -336.215494) (xy 338.187449 -336.228161) (xy 338.194904 -336.2325)
			(xy 338.283042 -336.278728) (xy 338.309204 -336.27822) (xy 338.320634 -336.271616) (xy 338.354723 -336.252133)
			(xy 338.425722 -336.218592) (xy 338.499399 -336.191437) (xy 338.575183 -336.170878) (xy 338.652483 -336.157075)
			(xy 338.730699 -336.150137) (xy 338.76996 -336.149696) (xy 338.81107 -336.150191) (xy 338.89294 -336.157775)
			(xy 338.97376 -336.172882) (xy 339.052841 -336.195384) (xy 339.129508 -336.225088) (xy 339.203107 -336.261741)
			(xy 339.273008 -336.305029) (xy 339.338617 -336.354584) (xy 339.399372 -336.409982) (xy 339.454755 -336.470751)
			(xy 339.504294 -336.536372) (xy 339.547565 -336.606284) (xy 339.5842 -336.679891) (xy 339.613885 -336.756566)
			(xy 339.636368 -336.835652) (xy 339.651455 -336.916476) (xy 339.659019 -336.998348) (xy 339.659177 -337.0128)
			(xy 343.199717 -337.0128) (xy 343.203707 -336.929019) (xy 343.215644 -336.845997) (xy 343.235419 -336.764486)
			(xy 343.262852 -336.685223) (xy 343.297695 -336.608927) (xy 343.339633 -336.536288) (xy 343.388286 -336.467965)
			(xy 343.443213 -336.404576) (xy 343.503917 -336.346695) (xy 343.569847 -336.294846) (xy 343.640408 -336.249499)
			(xy 343.71496 -336.211065) (xy 343.792828 -336.179892) (xy 343.873306 -336.156261) (xy 343.955666 -336.140388)
			(xy 344.039162 -336.132415) (xy 344.0811 -336.131916) (xy 344.11829 -336.132304) (xy 344.192403 -336.138594)
			(xy 344.265722 -336.151104) (xy 344.337728 -336.169745) (xy 344.372946 -336.1817) (xy 344.381143 -336.184214)
			(xy 344.398277 -336.184214) (xy 344.406474 -336.1817) (xy 344.441687 -336.169727) (xy 344.513691 -336.151076)
			(xy 344.587013 -336.13857) (xy 344.661129 -336.1323) (xy 344.69832 -336.131916) (xy 344.712798 -336.13217)
			(xy 344.724169 -336.131792) (xy 344.744841 -336.122355) (xy 344.759419 -336.104924) (xy 344.762836 -336.09407)
			(xy 344.771457 -336.062103) (xy 344.792812 -335.999426) (xy 344.805508 -335.968848) (xy 344.809054 -335.959252)
			(xy 344.809067 -335.938814) (xy 344.805508 -335.929224) (xy 344.788475 -335.887851) (xy 344.761859 -335.802423)
			(xy 344.743957 -335.714753) (xy 344.734952 -335.625729) (xy 344.734388 -335.58099) (xy 344.734388 -335.580736)
			(xy 344.734892 -335.538388) (xy 344.742943 -335.454074) (xy 344.758972 -335.370908) (xy 344.782833 -335.289641)
			(xy 344.814312 -335.211011) (xy 344.853123 -335.13573) (xy 344.898913 -335.064478) (xy 344.951269 -334.997902)
			(xy 345.009717 -334.936604) (xy 345.073727 -334.881139) (xy 345.142719 -334.83201) (xy 345.216069 -334.789661)
			(xy 345.293112 -334.754477) (xy 345.373151 -334.726775) (xy 345.45546 -334.706807) (xy 345.539295 -334.694754)
			(xy 345.623896 -334.690724) (xy 345.708497 -334.694754) (xy 345.792332 -334.706807) (xy 345.874641 -334.726775)
			(xy 345.95468 -334.754477) (xy 346.031723 -334.789661) (xy 346.105073 -334.83201) (xy 346.174065 -334.881139)
			(xy 346.238075 -334.936604) (xy 346.296523 -334.997902) (xy 346.348879 -335.064478) (xy 346.394669 -335.13573)
			(xy 346.43348 -335.211011) (xy 346.464959 -335.289641) (xy 346.48882 -335.370908) (xy 346.504849 -335.454074)
			(xy 346.5129 -335.538388) (xy 346.513404 -335.580736) (xy 346.513404 -335.58099) (xy 346.512849 -335.625729)
			(xy 346.50383 -335.714751) (xy 346.485921 -335.802418) (xy 346.459304 -335.887845) (xy 346.442284 -335.929224)
			(xy 346.438698 -335.938808) (xy 346.438711 -335.959257) (xy 346.442284 -335.968848) (xy 346.459319 -336.010255)
			(xy 346.48595 -336.095744) (xy 346.503854 -336.183477) (xy 346.51285 -336.272565) (xy 346.513404 -336.317336)
			(xy 346.513182 -336.348682) (xy 346.508857 -336.411225) (xy 346.504768 -336.442304) (xy 346.503244 -336.452972)
			(xy 346.508832 -336.473546) (xy 346.56268 -336.539586) (xy 346.569651 -336.547336) (xy 346.588142 -336.55691)
			(xy 346.598494 -336.558128) (xy 346.599002 -336.558128) (xy 346.640786 -336.561293) (xy 346.723543 -336.574476)
			(xy 346.804694 -336.595383) (xy 346.883519 -336.62383) (xy 346.959319 -336.659564) (xy 347.031422 -336.702268)
			(xy 347.09919 -336.751564) (xy 347.162022 -336.807015) (xy 347.21936 -336.868129) (xy 347.270696 -336.934365)
			(xy 347.315576 -337.005135) (xy 347.353601 -337.079812) (xy 347.384434 -337.157734) (xy 347.407802 -337.238211)
			(xy 347.423499 -337.320529) (xy 347.431384 -337.403958) (xy 347.431868 -337.445858) (xy 347.431868 -337.446874)
			(xy 347.431339 -337.489485) (xy 347.423121 -337.57431) (xy 347.406824 -337.657959) (xy 347.382599 -337.739665)
			(xy 347.367098 -337.77936) (xy 347.363634 -337.789438) (xy 347.36443 -337.810709) (xy 347.368622 -337.820508)
			(xy 347.385666 -337.856788) (xy 347.413917 -337.931808) (xy 347.435302 -338.009067) (xy 347.449648 -338.087936)
			(xy 347.456838 -338.167776) (xy 347.457268 -338.207858) (xy 347.456674 -338.254253) (xy 347.447033 -338.346541)
			(xy 347.42784 -338.437325) (xy 347.399305 -338.525619) (xy 347.381068 -338.568284) (xy 347.377284 -338.578233)
			(xy 347.377268 -338.599491) (xy 347.381068 -338.609432) (xy 347.399296 -338.652101) (xy 347.427845 -338.740391)
			(xy 347.447043 -338.831174) (xy 347.456681 -338.923462) (xy 347.457268 -338.969858) (xy 347.456674 -339.016253)
			(xy 347.447033 -339.108541) (xy 347.42784 -339.199325) (xy 347.399305 -339.287619) (xy 347.381068 -339.330284)
			(xy 347.377284 -339.340233) (xy 347.377268 -339.361491) (xy 347.381068 -339.371432) (xy 347.39928 -339.414039)
			(xy 347.427799 -339.502205) (xy 347.446995 -339.592859) (xy 347.456658 -339.685018) (xy 347.457268 -339.73135)
			(xy 347.457268 -339.731858) (xy 347.456747 -339.772964) (xy 347.449167 -339.854825) (xy 347.434067 -339.935639)
			(xy 347.411576 -340.014714) (xy 347.381885 -340.091377) (xy 347.345249 -340.164975) (xy 347.30198 -340.234878)
			(xy 347.252446 -340.300492) (xy 347.19707 -340.361256) (xy 347.136324 -340.416653) (xy 347.070727 -340.466209)
			(xy 347.000838 -340.509502) (xy 346.927254 -340.546163) (xy 346.8506 -340.575879) (xy 346.771533 -340.598397)
			(xy 346.690725 -340.613525) (xy 346.608866 -340.621133) (xy 346.56776 -340.62162) (xy 346.525159 -340.621134)
			(xy 346.440349 -340.612975) (xy 346.356708 -340.596745) (xy 346.275001 -340.572593) (xy 346.195978 -340.540739)
			(xy 346.120362 -340.501477) (xy 346.048846 -340.455165) (xy 345.982085 -340.402229) (xy 345.920691 -340.343152)
			(xy 345.865226 -340.278476) (xy 345.840304 -340.243922) (xy 345.834713 -340.236567) (xy 345.819465 -340.226159)
			(xy 345.810586 -340.223602) (xy 345.769427 -340.213207) (xy 345.689122 -340.185668) (xy 345.611806 -340.150603)
			(xy 345.538183 -340.108332) (xy 345.468921 -340.05924) (xy 345.40465 -340.003772) (xy 345.345957 -339.942434)
			(xy 345.293373 -339.875784) (xy 345.247379 -339.804427) (xy 345.208391 -339.729013) (xy 345.176765 -339.650228)
			(xy 345.152789 -339.568788) (xy 345.136679 -339.485435) (xy 345.128584 -339.400926) (xy 345.128088 -339.358478)
			(xy 345.128088 -339.358224) (xy 345.128648 -339.313485) (xy 345.137666 -339.224464) (xy 345.155574 -339.136796)
			(xy 345.182189 -339.051369) (xy 345.199208 -339.00999) (xy 345.202787 -339.000403) (xy 345.202779 -338.979957)
			(xy 345.199208 -338.970366) (xy 345.182177 -338.928958) (xy 345.155545 -338.843469) (xy 345.13764 -338.755736)
			(xy 345.128642 -338.666649) (xy 345.128088 -338.621878) (xy 345.128637 -338.577108) (xy 345.137642 -338.488021)
			(xy 345.15555 -338.400289) (xy 345.182178 -338.314799) (xy 345.199208 -338.27339) (xy 345.202787 -338.263803)
			(xy 345.202779 -338.243357) (xy 345.199208 -338.233766) (xy 345.182177 -338.192358) (xy 345.155545 -338.106869)
			(xy 345.13764 -338.019136) (xy 345.128642 -337.930049) (xy 345.128088 -337.885278) (xy 345.128088 -337.87334)
			(xy 345.101609 -337.867394) (xy 345.049374 -337.852651) (xy 345.023694 -337.843876) (xy 345.015497 -337.841362)
			(xy 344.998363 -337.841362) (xy 344.990166 -337.843876) (xy 344.95495 -337.855837) (xy 344.882946 -337.874492)
			(xy 344.809626 -337.887) (xy 344.73551 -337.893274) (xy 344.69832 -337.89366) (xy 344.661131 -337.893262)
			(xy 344.587018 -337.886974) (xy 344.513698 -337.874467) (xy 344.441692 -337.855829) (xy 344.406474 -337.843876)
			(xy 344.398277 -337.841362) (xy 344.381143 -337.841362) (xy 344.372946 -337.843876) (xy 344.337731 -337.855842)
			(xy 344.265728 -337.874496) (xy 344.192406 -337.887003) (xy 344.11829 -337.893275) (xy 344.0811 -337.89366)
			(xy 344.039162 -337.893185) (xy 343.955666 -337.885212) (xy 343.873306 -337.869339) (xy 343.792828 -337.845708)
			(xy 343.71496 -337.814535) (xy 343.640408 -337.776101) (xy 343.569847 -337.730754) (xy 343.503917 -337.678905)
			(xy 343.443213 -337.621024) (xy 343.388286 -337.557635) (xy 343.339633 -337.489312) (xy 343.297695 -337.416673)
			(xy 343.262852 -337.340377) (xy 343.235419 -337.261114) (xy 343.215644 -337.179603) (xy 343.203707 -337.096581)
			(xy 343.199717 -337.0128) (xy 339.659177 -337.0128) (xy 339.659468 -337.039458) (xy 339.6589 -337.084228)
			(xy 339.649901 -337.173314) (xy 339.631999 -337.261046) (xy 339.605375 -337.346537) (xy 339.588348 -337.387946)
			(xy 339.584808 -337.397544) (xy 339.584792 -337.41798) (xy 339.588348 -337.42757) (xy 339.605388 -337.468975)
			(xy 339.632018 -337.554465) (xy 339.649921 -337.642198) (xy 339.658915 -337.731287) (xy 339.659468 -337.776058)
			(xy 339.6589 -337.820828) (xy 339.649901 -337.909914) (xy 339.631999 -337.997646) (xy 339.605375 -338.083137)
			(xy 339.588348 -338.124546) (xy 339.584808 -338.134144) (xy 339.584792 -338.15458) (xy 339.588348 -338.16417)
			(xy 339.605377 -338.205545) (xy 339.631995 -338.290972) (xy 339.649897 -338.378641) (xy 339.658904 -338.467665)
			(xy 339.659468 -338.512404) (xy 339.659468 -338.512658) (xy 339.658947 -338.553764) (xy 339.651367 -338.635625)
			(xy 339.636267 -338.716439) (xy 339.613776 -338.795514) (xy 339.584085 -338.872177) (xy 339.547449 -338.945775)
			(xy 339.50418 -339.015678) (xy 339.454646 -339.081292) (xy 339.39927 -339.142056) (xy 339.338524 -339.197453)
			(xy 339.272927 -339.247009) (xy 339.203038 -339.290302) (xy 339.129454 -339.326963) (xy 339.0528 -339.356679)
			(xy 338.973733 -339.379197) (xy 338.892925 -339.394325) (xy 338.811066 -339.401933) (xy 338.76996 -339.40242)
			(xy 338.728351 -339.40191) (xy 338.645495 -339.394139) (xy 338.563727 -339.378669) (xy 338.483759 -339.355636)
			(xy 338.40629 -339.325239) (xy 338.331996 -339.287745) (xy 338.296504 -339.266022) (xy 338.287367 -339.260856)
			(xy 338.26665 -339.257639) (xy 338.246374 -339.262975) (xy 338.23783 -339.26907) (xy 338.204174 -339.295024)
			(xy 338.132784 -339.341153) (xy 338.057318 -339.380258) (xy 337.978465 -339.411983) (xy 337.896945 -339.436039)
			(xy 337.8135 -339.452205) (xy 337.728894 -339.460335) (xy 337.686396 -339.46084) (xy 337.645286 -339.460351)
			(xy 337.563418 -339.452764) (xy 337.482599 -339.437653) (xy 337.403519 -339.415149) (xy 337.326853 -339.385443)
			(xy 337.253256 -339.348789) (xy 337.183356 -339.3055) (xy 337.117748 -339.255944) (xy 337.056994 -339.200546)
			(xy 337.001611 -339.139778) (xy 336.952073 -339.074158) (xy 336.908801 -339.004246) (xy 336.872166 -338.93064)
			(xy 336.842479 -338.853967) (xy 336.819995 -338.774881) (xy 336.804905 -338.694058) (xy 336.797338 -338.612188)
			(xy 336.796888 -338.571078) (xy 336.797437 -338.526308) (xy 336.806442 -338.437221) (xy 336.82435 -338.349489)
			(xy 336.850978 -338.263999) (xy 336.868008 -338.22259) (xy 336.871587 -338.213003) (xy 336.871579 -338.192557)
			(xy 336.868008 -338.182966) (xy 336.850977 -338.141558) (xy 336.824345 -338.056069) (xy 336.80644 -337.968336)
			(xy 336.797442 -337.879249) (xy 336.796888 -337.834478) (xy 336.796888 -337.82254) (xy 336.770409 -337.816594)
			(xy 336.718174 -337.801851) (xy 336.692494 -337.793076) (xy 336.684297 -337.790562) (xy 336.667163 -337.790562)
			(xy 336.658966 -337.793076) (xy 336.62375 -337.805037) (xy 336.551746 -337.823692) (xy 336.478426 -337.8362)
			(xy 336.40431 -337.842474) (xy 336.36712 -337.84286) (xy 336.329931 -337.842462) (xy 336.255818 -337.836174)
			(xy 336.182498 -337.823667) (xy 336.110492 -337.805029) (xy 336.075274 -337.793076) (xy 336.067077 -337.790562)
			(xy 336.049943 -337.790562) (xy 336.041746 -337.793076) (xy 336.006531 -337.805042) (xy 335.934528 -337.823696)
			(xy 335.861206 -337.836203) (xy 335.78709 -337.842475) (xy 335.7499 -337.84286) (xy 335.707962 -337.842385)
			(xy 335.624466 -337.834412) (xy 335.542106 -337.818539) (xy 335.461628 -337.794908) (xy 335.38376 -337.763735)
			(xy 335.309208 -337.725301) (xy 335.238647 -337.679954) (xy 335.172717 -337.628105) (xy 335.112013 -337.570224)
			(xy 335.057086 -337.506835) (xy 335.008433 -337.438512) (xy 334.966495 -337.365873) (xy 334.931652 -337.289577)
			(xy 334.904219 -337.210314) (xy 334.884444 -337.128803) (xy 334.872507 -337.045781) (xy 334.868517 -336.962)
			(xy 331.296671 -336.962) (xy 331.301379 -337.012832) (xy 331.301852 -337.053936) (xy 331.301852 -337.05419)
			(xy 331.301293 -337.098929) (xy 331.292274 -337.18795) (xy 331.274367 -337.275618) (xy 331.247751 -337.361045)
			(xy 331.230732 -337.402424) (xy 331.227148 -337.412009) (xy 331.227161 -337.432457) (xy 331.230732 -337.442048)
			(xy 331.247764 -337.483456) (xy 331.274397 -337.568945) (xy 331.292302 -337.656677) (xy 331.301298 -337.745765)
			(xy 331.301852 -337.790536) (xy 331.301312 -337.835307) (xy 331.292305 -337.924394) (xy 331.274395 -338.012126)
			(xy 331.247763 -338.097615) (xy 331.230732 -338.139024) (xy 331.227148 -338.148609) (xy 331.227161 -338.169057)
			(xy 331.230732 -338.178648) (xy 331.247759 -338.220024) (xy 331.274376 -338.305451) (xy 331.292279 -338.39312)
			(xy 331.301287 -338.482143) (xy 331.301852 -338.526882) (xy 331.301852 -338.527136) (xy 331.301368 -338.568238)
			(xy 331.29378 -338.65009) (xy 331.278673 -338.730894) (xy 331.256175 -338.809959) (xy 331.226478 -338.886611)
			(xy 331.189836 -338.960196) (xy 331.14656 -339.030087) (xy 331.097021 -339.095686) (xy 331.041641 -339.156436)
			(xy 330.980892 -339.211816) (xy 330.915293 -339.261356) (xy 330.845403 -339.304632) (xy 330.771818 -339.341275)
			(xy 330.695167 -339.370972) (xy 330.616102 -339.393471) (xy 330.535298 -339.408579) (xy 330.453446 -339.416167)
			(xy 330.412344 -339.416644) (xy 330.411582 -339.416644) (xy 330.370042 -339.416142) (xy 330.287326 -339.408361)
			(xy 330.205695 -339.392907) (xy 330.125859 -339.369913) (xy 330.048513 -339.339581) (xy 329.97433 -339.302172)
			(xy 329.938888 -339.2805) (xy 329.929757 -339.275322) (xy 329.909036 -339.272112) (xy 329.888759 -339.277452)
			(xy 329.880214 -339.283548) (xy 329.846565 -339.30947) (xy 329.775191 -339.355528) (xy 329.699752 -339.394575)
			(xy 329.620935 -339.426254) (xy 329.539458 -339.450278) (xy 329.456062 -339.466427) (xy 329.371506 -339.474554)
			(xy 329.329034 -339.475064) (xy 329.32878 -339.475064) (xy 329.287675 -339.474667) (xy 329.205817 -339.46708)
			(xy 329.125007 -339.451972) (xy 329.045936 -339.429472) (xy 328.969279 -339.399772) (xy 328.895689 -339.363126)
			(xy 328.825795 -339.319846) (xy 328.760192 -339.270301) (xy 328.69944 -339.214915) (xy 328.644058 -339.154159)
			(xy 328.594518 -339.088553) (xy 328.551243 -339.018655) (xy 328.514602 -338.945062) (xy 328.484908 -338.868403)
			(xy 328.462414 -338.789331) (xy 328.447312 -338.70852) (xy 328.43973 -338.626661) (xy 328.439272 -338.585556)
			(xy 328.439272 -338.585302) (xy 328.43986 -338.540564) (xy 328.44887 -338.451543) (xy 328.466769 -338.363876)
			(xy 328.493377 -338.278448) (xy 328.510392 -338.237068) (xy 328.513984 -338.227485) (xy 328.513968 -338.207035)
			(xy 328.510392 -338.197444) (xy 328.493353 -338.156039) (xy 328.466723 -338.070549) (xy 328.44882 -337.982815)
			(xy 328.439825 -337.893727) (xy 328.439272 -337.848956) (xy 328.439272 -337.837018) (xy 328.412793 -337.831074)
			(xy 328.360558 -337.81633) (xy 328.334878 -337.807554) (xy 328.326681 -337.80504) (xy 328.309547 -337.80504)
			(xy 328.30135 -337.807554) (xy 328.266125 -337.819474) (xy 328.194118 -337.838068) (xy 328.120798 -337.850516)
			(xy 328.046689 -337.856728) (xy 328.009504 -337.857084) (xy 327.97232 -337.856715) (xy 327.898212 -337.850493)
			(xy 327.824892 -337.838051) (xy 327.752881 -337.819476) (xy 327.717658 -337.807554) (xy 327.709461 -337.80504)
			(xy 327.692327 -337.80504) (xy 327.68413 -337.807554) (xy 327.649029 -337.819442) (xy 327.577272 -337.837992)
			(xy 327.504209 -337.850438) (xy 327.430358 -337.856691) (xy 327.3933 -337.857084) (xy 327.392284 -337.857084)
			(xy 327.350358 -337.856653) (xy 327.266885 -337.848681) (xy 327.184547 -337.83281) (xy 327.104092 -337.809185)
			(xy 327.026246 -337.778019) (xy 326.951715 -337.739594) (xy 326.881174 -337.694259) (xy 326.815262 -337.642424)
			(xy 326.754575 -337.584559) (xy 326.699664 -337.521186) (xy 326.651025 -337.452882) (xy 326.609099 -337.380263)
			(xy 326.574266 -337.303987) (xy 326.546841 -337.224746) (xy 326.527072 -337.143257) (xy 326.515138 -337.060258)
			(xy 326.511148 -336.9765) (xy 322.941787 -336.9765) (xy 322.94581 -337.019944) (xy 322.946268 -337.061048)
			(xy 322.946268 -337.061302) (xy 322.945685 -337.10604) (xy 322.936674 -337.195061) (xy 322.918774 -337.282729)
			(xy 322.892164 -337.368156) (xy 322.875148 -337.409536) (xy 322.871556 -337.419119) (xy 322.871574 -337.439569)
			(xy 322.875148 -337.44916) (xy 322.892185 -337.490566) (xy 322.918816 -337.576056) (xy 322.93672 -337.663789)
			(xy 322.945715 -337.752877) (xy 322.946268 -337.797648) (xy 322.945697 -337.842418) (xy 322.936698 -337.931504)
			(xy 322.918797 -338.019236) (xy 322.892175 -338.104727) (xy 322.875148 -338.146136) (xy 322.871556 -338.155719)
			(xy 322.871574 -338.176169) (xy 322.875148 -338.18576) (xy 322.892174 -338.227136) (xy 322.918792 -338.312563)
			(xy 322.936696 -338.400232) (xy 322.945704 -338.489255) (xy 322.946268 -338.533994) (xy 322.946268 -338.534248)
			(xy 322.945879 -338.575352) (xy 322.938289 -338.65721) (xy 322.923179 -338.738019) (xy 322.900678 -338.817088)
			(xy 322.870976 -338.893744) (xy 322.834329 -338.967333) (xy 322.791048 -339.037226) (xy 322.741503 -339.102828)
			(xy 322.686116 -339.163578) (xy 322.62536 -339.218959) (xy 322.559753 -339.268498) (xy 322.489856 -339.311772)
			(xy 322.416264 -339.348412) (xy 322.339605 -339.378106) (xy 322.260533 -339.400599) (xy 322.179723 -339.415702)
			(xy 322.097864 -339.423283) (xy 322.05676 -339.423756) (xy 322.055998 -339.423756) (xy 322.014458 -339.423244)
			(xy 321.931742 -339.415465) (xy 321.850112 -339.400013) (xy 321.770276 -339.377021) (xy 321.69293 -339.34669)
			(xy 321.618746 -339.309284) (xy 321.583304 -339.287612) (xy 321.574167 -339.282447) (xy 321.55345 -339.279232)
			(xy 321.533175 -339.284566) (xy 321.52463 -339.29066) (xy 321.491012 -339.316622) (xy 321.419631 -339.362677)
			(xy 321.344187 -339.401718) (xy 321.265365 -339.433392) (xy 321.183883 -339.457409) (xy 321.100483 -339.47355)
			(xy 321.015924 -339.48167) (xy 320.97345 -339.482176) (xy 320.973196 -339.482176) (xy 320.932092 -339.481752)
			(xy 320.850234 -339.474166) (xy 320.769426 -339.459059) (xy 320.690356 -339.436561) (xy 320.613699 -339.406863)
			(xy 320.54011 -339.370219) (xy 320.470216 -339.326941) (xy 320.404613 -339.277398) (xy 320.343861 -339.222013)
			(xy 320.288479 -339.161259) (xy 320.238939 -339.095655) (xy 320.195664 -339.025759) (xy 320.159022 -338.952168)
			(xy 320.129327 -338.87551) (xy 320.106832 -338.796439) (xy 320.091729 -338.71563) (xy 320.084147 -338.633772)
			(xy 320.083688 -338.592668) (xy 320.083688 -338.592414) (xy 320.084245 -338.547675) (xy 320.093264 -338.458653)
			(xy 320.111172 -338.370986) (xy 320.137789 -338.285559) (xy 320.154808 -338.24418) (xy 320.158393 -338.234595)
			(xy 320.158381 -338.214147) (xy 320.154808 -338.204556) (xy 320.137774 -338.163149) (xy 320.111142 -338.07766)
			(xy 320.093238 -337.989927) (xy 320.084242 -337.900839) (xy 320.083688 -337.856068) (xy 320.083688 -337.84413)
			(xy 320.057209 -337.838184) (xy 320.004974 -337.823441) (xy 319.979294 -337.814666) (xy 319.971097 -337.812152)
			(xy 319.953963 -337.812152) (xy 319.945766 -337.814666) (xy 319.910549 -337.82661) (xy 319.838539 -337.845197)
			(xy 319.765217 -337.857638) (xy 319.691106 -337.863844) (xy 319.65392 -337.864196) (xy 319.616736 -337.863827)
			(xy 319.542628 -337.857606) (xy 319.469308 -337.845164) (xy 319.397297 -337.826589) (xy 319.362074 -337.814666)
			(xy 319.353877 -337.812152) (xy 319.336743 -337.812152) (xy 319.328546 -337.814666) (xy 319.293452 -337.826578)
			(xy 319.221693 -337.845121) (xy 319.148627 -337.85756) (xy 319.074774 -337.863807) (xy 319.037716 -337.864196)
			(xy 319.0367 -337.864196) (xy 318.994774 -337.863741) (xy 318.911301 -337.855771) (xy 318.828963 -337.839902)
			(xy 318.748507 -337.816278) (xy 318.670661 -337.785113) (xy 318.59613 -337.746689) (xy 318.525589 -337.701355)
			(xy 318.459676 -337.649521) (xy 318.398989 -337.591656) (xy 318.344078 -337.528284) (xy 318.295438 -337.45998)
			(xy 318.253512 -337.387361) (xy 318.218678 -337.311086) (xy 318.191253 -337.231846) (xy 318.171484 -337.150357)
			(xy 318.15955 -337.067358) (xy 318.155561 -336.9836) (xy 99.362614 -336.9836) (xy 99.373171 -336.999727)
			(xy 99.41309 -337.075842) (xy 99.445481 -337.155452) (xy 99.470043 -337.237815) (xy 99.486546 -337.322163)
			(xy 99.494837 -337.40771) (xy 99.495356 -337.450684) (xy 99.494854 -337.493421) (xy 99.48668 -337.578504)
			(xy 99.470386 -337.662411) (xy 99.446122 -337.744369) (xy 99.430586 -337.784186) (xy 99.426944 -337.794219)
			(xy 99.427619 -337.815536) (xy 99.431856 -337.825334) (xy 99.448914 -337.861614) (xy 99.477225 -337.936624)
			(xy 99.498666 -338.013878) (xy 99.513065 -338.092749) (xy 99.520304 -338.172597) (xy 99.520756 -338.212684)
			(xy 99.520272 -338.252763) (xy 99.512982 -338.33259) (xy 99.498549 -338.411439) (xy 99.488244 -338.450174)
			(xy 99.485843 -338.460698) (xy 99.489132 -338.482012) (xy 99.494594 -338.491322) (xy 99.517345 -338.52734)
			(xy 99.556637 -338.602937) (xy 99.588514 -338.681946) (xy 99.612684 -338.763644) (xy 99.628925 -338.847279)
			(xy 99.637089 -338.932085) (xy 99.637596 -338.974684) (xy 99.637001 -339.021087) (xy 99.627302 -339.113385)
			(xy 99.608039 -339.204171) (xy 99.579422 -339.292455) (xy 99.561142 -339.33511) (xy 99.557344 -339.345055)
			(xy 99.557338 -339.366316) (xy 99.561142 -339.376258) (xy 99.579397 -339.418922) (xy 99.607993 -339.507209)
			(xy 99.627252 -339.597991) (xy 99.636966 -339.690283) (xy 99.637596 -339.736684) (xy 99.637118 -339.777779)
			(xy 99.629538 -339.859619) (xy 99.614439 -339.94041) (xy 99.591952 -340.019465) (xy 99.562267 -340.096107)
			(xy 99.525639 -340.169684) (xy 99.482378 -340.239568) (xy 99.432856 -340.305164) (xy 99.377493 -340.36591)
			(xy 99.316762 -340.421291) (xy 99.251181 -340.470833) (xy 99.18131 -340.514113) (xy 99.107743 -340.550763)
			(xy 99.031109 -340.58047) (xy 98.952062 -340.60298) (xy 98.871275 -340.618102) (xy 98.789437 -340.625707)
			(xy 98.748342 -340.626192) (xy 98.747834 -340.626192) (xy 98.704859 -340.625663) (xy 98.619309 -340.617375)
			(xy 98.534957 -340.600874) (xy 98.45259 -340.576313) (xy 98.372977 -340.543922) (xy 98.296859 -340.504001)
			(xy 98.224947 -340.456925) (xy 98.157912 -340.403131) (xy 98.096378 -340.343122) (xy 98.040919 -340.277458)
			(xy 98.01606 -340.242398) (xy 98.010455 -340.235056) (xy 97.995216 -340.224641) (xy 97.986342 -340.222078)
			(xy 97.94544 -340.211492) (xy 97.865683 -340.183605) (xy 97.788928 -340.148281) (xy 97.715869 -340.105839)
			(xy 97.647164 -340.05666) (xy 97.583432 -340.001188) (xy 97.525246 -339.939922) (xy 97.473132 -339.873416)
			(xy 97.427559 -339.802268) (xy 97.388937 -339.727119) (xy 97.357615 -339.648646) (xy 97.333875 -339.567557)
			(xy 97.317931 -339.484583) (xy 97.309927 -339.40047) (xy 97.309432 -339.358224) (xy 97.309829 -339.321956)
			(xy 97.315809 -339.249667) (xy 97.327648 -339.178103) (xy 97.336102 -339.142832) (xy 97.338115 -339.132729)
			(xy 97.334853 -339.112411) (xy 97.329752 -339.103462) (xy 97.30766 -339.067807) (xy 97.269551 -338.993079)
			(xy 97.238646 -338.915096) (xy 97.215218 -338.83455) (xy 97.199477 -338.752156) (xy 97.191562 -338.668646)
			(xy 97.191068 -338.626704) (xy 97.191648 -338.581935) (xy 97.200654 -338.49285) (xy 97.218554 -338.405119)
			(xy 97.245168 -338.319627) (xy 97.262188 -338.278216) (xy 97.265753 -338.268625) (xy 97.265754 -338.248182)
			(xy 97.262188 -338.238592) (xy 97.245172 -338.197246) (xy 97.218563 -338.111882) (xy 97.20066 -338.024278)
			(xy 97.191642 -337.935319) (xy 97.191068 -337.890612) (xy 97.191068 -337.889596) (xy 97.191322 -337.878166)
			(xy 97.164844 -337.872216) (xy 97.112609 -337.857476) (xy 97.086928 -337.848702) (xy 97.078731 -337.846188)
			(xy 97.061597 -337.846188) (xy 97.0534 -337.848702) (xy 97.01818 -337.860638) (xy 96.946171 -337.879227)
			(xy 96.87285 -337.89167) (xy 96.798739 -337.897878) (xy 96.761554 -337.898232) (xy 96.724369 -337.89788)
			(xy 96.650261 -337.891654) (xy 96.576941 -337.879206) (xy 96.504931 -337.860627) (xy 96.469708 -337.848702)
			(xy 96.461511 -337.846188) (xy 96.444377 -337.846188) (xy 96.43618 -337.848702) (xy 96.401082 -337.860602)
			(xy 96.329324 -337.879149) (xy 96.25626 -337.891592) (xy 96.182408 -337.897841) (xy 96.14535 -337.898232)
			(xy 96.144334 -337.898232) (xy 96.102408 -337.897723) (xy 96.018934 -337.889755) (xy 95.936596 -337.873888)
			(xy 95.85614 -337.850267) (xy 95.778292 -337.819104) (xy 95.70376 -337.780683) (xy 95.633218 -337.73535)
			(xy 95.567304 -337.683517) (xy 95.506616 -337.625654) (xy 95.451703 -337.562283) (xy 95.403062 -337.493979)
			(xy 95.361135 -337.421361) (xy 95.3263 -337.345087) (xy 95.298874 -337.265846) (xy 95.279105 -337.184357)
			(xy 95.267171 -337.101358) (xy 95.263181 -337.0176) (xy 91.722641 -337.0176) (xy 91.722956 -337.044284)
			(xy 91.722404 -337.089054) (xy 91.71339 -337.178139) (xy 91.695482 -337.26587) (xy 91.668861 -337.351361)
			(xy 91.651836 -337.392772) (xy 91.648282 -337.402366) (xy 91.648276 -337.422805) (xy 91.651836 -337.432396)
			(xy 91.668872 -337.473803) (xy 91.695506 -337.559291) (xy 91.71341 -337.647024) (xy 91.722404 -337.736113)
			(xy 91.722956 -337.780884) (xy 91.722404 -337.825654) (xy 91.71339 -337.914739) (xy 91.695482 -338.00247)
			(xy 91.668861 -338.087961) (xy 91.651836 -338.129372) (xy 91.648282 -338.138966) (xy 91.648276 -338.159405)
			(xy 91.651836 -338.168996) (xy 91.668872 -338.210403) (xy 91.695506 -338.295891) (xy 91.71341 -338.383624)
			(xy 91.722404 -338.472713) (xy 91.722956 -338.517484) (xy 91.722432 -338.558593) (xy 91.714846 -338.64046)
			(xy 91.699738 -338.721278) (xy 91.677236 -338.800357) (xy 91.647532 -338.877021) (xy 91.610881 -338.950618)
			(xy 91.567594 -339.020518) (xy 91.518041 -339.086125) (xy 91.462645 -339.146879) (xy 91.401879 -339.202262)
			(xy 91.336261 -339.251801) (xy 91.266352 -339.295073) (xy 91.192747 -339.331709) (xy 91.116076 -339.361396)
			(xy 91.036993 -339.383882) (xy 90.956172 -339.398973) (xy 90.874303 -339.406541) (xy 90.833194 -339.406992)
			(xy 90.791589 -339.406554) (xy 90.70874 -339.398816) (xy 90.626975 -339.383379) (xy 90.547007 -339.360379)
			(xy 90.469535 -339.330016) (xy 90.395235 -339.292555) (xy 90.359738 -339.270848) (xy 90.350631 -339.26562)
			(xy 90.329893 -339.262421) (xy 90.309608 -339.267785) (xy 90.301064 -339.273896) (xy 90.267427 -339.299833)
			(xy 90.196051 -339.345891) (xy 90.12061 -339.384937) (xy 90.041791 -339.416615) (xy 89.960312 -339.440636)
			(xy 89.876914 -339.456781) (xy 89.792357 -339.464905) (xy 89.749884 -339.465412) (xy 89.74963 -339.465412)
			(xy 89.708522 -339.464959) (xy 89.626657 -339.457377) (xy 89.545841 -339.442274) (xy 89.466762 -339.41978)
			(xy 89.390096 -339.390087) (xy 89.316497 -339.353447) (xy 89.246591 -339.310173) (xy 89.180976 -339.260635)
			(xy 89.120211 -339.205254) (xy 89.064815 -339.144504) (xy 89.015259 -339.078902) (xy 88.971967 -339.009008)
			(xy 88.935308 -338.935418) (xy 88.905594 -338.85876) (xy 88.883079 -338.779687) (xy 88.867956 -338.698875)
			(xy 88.860352 -338.617012) (xy 88.859868 -338.575904) (xy 88.860448 -338.531135) (xy 88.869454 -338.44205)
			(xy 88.887354 -338.354319) (xy 88.913968 -338.268827) (xy 88.930988 -338.227416) (xy 88.934553 -338.217825)
			(xy 88.934554 -338.197382) (xy 88.930988 -338.187792) (xy 88.913972 -338.146446) (xy 88.887363 -338.061082)
			(xy 88.86946 -337.973478) (xy 88.860442 -337.884519) (xy 88.859868 -337.839812) (xy 88.859868 -337.838796)
			(xy 88.860122 -337.827366) (xy 88.833644 -337.821416) (xy 88.781409 -337.806676) (xy 88.755728 -337.797902)
			(xy 88.747531 -337.795388) (xy 88.730397 -337.795388) (xy 88.7222 -337.797902) (xy 88.68698 -337.809838)
			(xy 88.614971 -337.828427) (xy 88.54165 -337.84087) (xy 88.467539 -337.847078) (xy 88.430354 -337.847432)
			(xy 88.393169 -337.84708) (xy 88.319061 -337.840854) (xy 88.245741 -337.828406) (xy 88.173731 -337.809827)
			(xy 88.138508 -337.797902) (xy 88.130311 -337.795388) (xy 88.113177 -337.795388) (xy 88.10498 -337.797902)
			(xy 88.069882 -337.809802) (xy 87.998124 -337.828349) (xy 87.92506 -337.840792) (xy 87.851208 -337.847041)
			(xy 87.81415 -337.847432) (xy 87.813134 -337.847432) (xy 87.771208 -337.846923) (xy 87.687734 -337.838955)
			(xy 87.605396 -337.823088) (xy 87.52494 -337.799467) (xy 87.447092 -337.768304) (xy 87.37256 -337.729883)
			(xy 87.302018 -337.68455) (xy 87.236104 -337.632717) (xy 87.175416 -337.574854) (xy 87.120503 -337.511483)
			(xy 87.071862 -337.443179) (xy 87.029935 -337.370561) (xy 86.9951 -337.294287) (xy 86.967674 -337.215046)
			(xy 86.947905 -337.133557) (xy 86.935971 -337.050558) (xy 86.931981 -336.9668) (xy 83.360149 -336.9668)
			(xy 83.364863 -337.017649) (xy 83.36534 -337.058762) (xy 83.364781 -337.103532) (xy 83.35577 -337.192617)
			(xy 83.337863 -337.280348) (xy 83.311243 -337.365839) (xy 83.29422 -337.40725) (xy 83.290679 -337.416847)
			(xy 83.290665 -337.437283) (xy 83.29422 -337.446874) (xy 83.311248 -337.488284) (xy 83.337884 -337.573771)
			(xy 83.355791 -337.661503) (xy 83.364787 -337.750591) (xy 83.36534 -337.795362) (xy 83.364781 -337.840132)
			(xy 83.35577 -337.929217) (xy 83.337863 -338.016948) (xy 83.311243 -338.102439) (xy 83.29422 -338.14385)
			(xy 83.290679 -338.153447) (xy 83.290665 -338.173883) (xy 83.29422 -338.183474) (xy 83.311248 -338.224884)
			(xy 83.337884 -338.310371) (xy 83.355791 -338.398103) (xy 83.364787 -338.487191) (xy 83.36534 -338.531962)
			(xy 83.364865 -338.573077) (xy 83.357281 -338.654956) (xy 83.342174 -338.735786) (xy 83.319674 -338.814878)
			(xy 83.289971 -338.891556) (xy 83.253319 -338.965166) (xy 83.210032 -339.03508) (xy 83.160479 -339.100701)
			(xy 83.105082 -339.16147) (xy 83.044313 -339.216869) (xy 82.978693 -339.266423) (xy 82.90878 -339.309712)
			(xy 82.83517 -339.346364) (xy 82.758493 -339.376068) (xy 82.679402 -339.398571) (xy 82.598572 -339.413679)
			(xy 82.516693 -339.421265) (xy 82.475578 -339.421724) (xy 82.433968 -339.421253) (xy 82.351111 -339.413475)
			(xy 82.269342 -339.397998) (xy 82.189374 -339.374957) (xy 82.111906 -339.344554) (xy 82.037613 -339.307053)
			(xy 82.002122 -339.285326) (xy 81.992978 -339.280175) (xy 81.972265 -339.276953) (xy 81.951992 -339.282282)
			(xy 81.943448 -339.288374) (xy 81.909821 -339.314367) (xy 81.838426 -339.360491) (xy 81.762954 -339.399592)
			(xy 81.684096 -339.431311) (xy 81.602571 -339.455361) (xy 81.519123 -339.471521) (xy 81.434513 -339.479643)
			(xy 81.392014 -339.480144) (xy 81.350899 -339.479688) (xy 81.269019 -339.472102) (xy 81.188189 -339.456993)
			(xy 81.109097 -339.434491) (xy 81.032419 -339.404786) (xy 80.95881 -339.368133) (xy 80.888896 -339.324845)
			(xy 80.823275 -339.27529) (xy 80.762506 -339.219892) (xy 80.707108 -339.159122) (xy 80.657553 -339.093501)
			(xy 80.614265 -339.023587) (xy 80.577612 -338.949977) (xy 80.547908 -338.873299) (xy 80.525406 -338.794207)
			(xy 80.510297 -338.713377) (xy 80.502712 -338.631497) (xy 80.502252 -338.590382) (xy 80.502826 -338.545613)
			(xy 80.511834 -338.456528) (xy 80.529735 -338.368797) (xy 80.556351 -338.283305) (xy 80.573372 -338.241894)
			(xy 80.576945 -338.232306) (xy 80.576939 -338.211861) (xy 80.573372 -338.20227) (xy 80.556348 -338.160927)
			(xy 80.529742 -338.075562) (xy 80.511841 -337.987957) (xy 80.502825 -337.898997) (xy 80.502252 -337.85429)
			(xy 80.502252 -337.853274) (xy 80.502506 -337.841844) (xy 80.476028 -337.835896) (xy 80.423793 -337.821155)
			(xy 80.398112 -337.81238) (xy 80.389915 -337.809866) (xy 80.372781 -337.809866) (xy 80.364584 -337.81238)
			(xy 80.329366 -337.824336) (xy 80.257364 -337.842992) (xy 80.184043 -337.855502) (xy 80.109928 -337.861777)
			(xy 80.072738 -337.862164) (xy 80.035549 -337.861761) (xy 79.961436 -337.855475) (xy 79.888116 -337.842969)
			(xy 79.81611 -337.824332) (xy 79.780892 -337.81238) (xy 79.772695 -337.809866) (xy 79.755561 -337.809866)
			(xy 79.747364 -337.81238) (xy 79.712148 -337.824342) (xy 79.640145 -337.842996) (xy 79.566824 -337.855505)
			(xy 79.492708 -337.861778) (xy 79.455518 -337.862164) (xy 79.413579 -337.861698) (xy 79.330081 -337.853726)
			(xy 79.247718 -337.837853) (xy 79.167237 -337.814224) (xy 79.089367 -337.783051) (xy 79.014813 -337.744616)
			(xy 78.94425 -337.69927) (xy 78.878316 -337.64742) (xy 78.81761 -337.589539) (xy 78.762681 -337.526148)
			(xy 78.714027 -337.457824) (xy 78.672087 -337.385183) (xy 78.637243 -337.308885) (xy 78.609809 -337.229621)
			(xy 78.590033 -337.148107) (xy 78.578096 -337.065083) (xy 78.574105 -336.9813) (xy 75.005252 -336.9813)
			(xy 75.00928 -337.024761) (xy 75.009756 -337.065874) (xy 75.009201 -337.110644) (xy 75.000188 -337.199729)
			(xy 74.982281 -337.28746) (xy 74.95566 -337.372951) (xy 74.938636 -337.414362) (xy 74.935088 -337.423957)
			(xy 74.935078 -337.444395) (xy 74.938636 -337.453986) (xy 74.955669 -337.495394) (xy 74.982303 -337.580882)
			(xy 75.000209 -337.668615) (xy 75.009203 -337.757703) (xy 75.009756 -337.802474) (xy 75.009201 -337.847244)
			(xy 75.000188 -337.936329) (xy 74.982281 -338.02406) (xy 74.95566 -338.109551) (xy 74.938636 -338.150962)
			(xy 74.935088 -338.160557) (xy 74.935078 -338.180995) (xy 74.938636 -338.190586) (xy 74.955669 -338.231994)
			(xy 74.982303 -338.317482) (xy 75.000209 -338.405215) (xy 75.009203 -338.494303) (xy 75.009756 -338.539074)
			(xy 75.009277 -338.580189) (xy 75.001692 -338.662067) (xy 74.986584 -338.742897) (xy 74.964083 -338.821988)
			(xy 74.93438 -338.898665) (xy 74.897729 -338.972274) (xy 74.854442 -339.042187) (xy 74.804888 -339.107809)
			(xy 74.749492 -339.168577) (xy 74.688724 -339.223976) (xy 74.623104 -339.27353) (xy 74.553192 -339.316819)
			(xy 74.479583 -339.353472) (xy 74.402907 -339.383177) (xy 74.323816 -339.40568) (xy 74.242987 -339.420789)
			(xy 74.161109 -339.428376) (xy 74.119994 -339.428836) (xy 74.078384 -339.428356) (xy 73.995528 -339.420579)
			(xy 73.913759 -339.405104) (xy 73.833791 -339.382065) (xy 73.756322 -339.351663) (xy 73.682029 -339.314164)
			(xy 73.646538 -339.292438) (xy 73.63743 -339.287211) (xy 73.616693 -339.284013) (xy 73.596408 -339.289376)
			(xy 73.587864 -339.295486) (xy 73.554233 -339.321473) (xy 73.482838 -339.367598) (xy 73.407368 -339.406699)
			(xy 73.32851 -339.438419) (xy 73.246986 -339.46247) (xy 73.163538 -339.47863) (xy 73.078929 -339.486754)
			(xy 73.03643 -339.487256) (xy 72.995315 -339.486773) (xy 72.913437 -339.479188) (xy 72.832607 -339.464081)
			(xy 72.753517 -339.44158) (xy 72.67684 -339.411877) (xy 72.60323 -339.375226) (xy 72.533317 -339.33194)
			(xy 72.467696 -339.282387) (xy 72.406927 -339.22699) (xy 72.351529 -339.166223) (xy 72.301974 -339.100603)
			(xy 72.258685 -339.030691) (xy 72.222032 -338.957082) (xy 72.192327 -338.880406) (xy 72.169824 -338.801316)
			(xy 72.154715 -338.720487) (xy 72.147128 -338.638609) (xy 72.146668 -338.597494) (xy 72.147245 -338.552725)
			(xy 72.156251 -338.46364) (xy 72.174152 -338.375909) (xy 72.200767 -338.290417) (xy 72.217788 -338.249006)
			(xy 72.221359 -338.239417) (xy 72.221356 -338.218972) (xy 72.217788 -338.209382) (xy 72.200768 -338.168037)
			(xy 72.174161 -338.082673) (xy 72.156259 -337.995068) (xy 72.147241 -337.906109) (xy 72.146668 -337.861402)
			(xy 72.146668 -337.860386) (xy 72.146922 -337.848956) (xy 72.120444 -337.843006) (xy 72.068209 -337.828266)
			(xy 72.042528 -337.819492) (xy 72.034331 -337.816978) (xy 72.017197 -337.816978) (xy 72.009 -337.819492)
			(xy 71.973781 -337.831444) (xy 71.901779 -337.850101) (xy 71.828459 -337.862612) (xy 71.754344 -337.868888)
			(xy 71.717154 -337.869276) (xy 71.679965 -337.868873) (xy 71.605852 -337.862587) (xy 71.532532 -337.850082)
			(xy 71.460526 -337.831445) (xy 71.425308 -337.819492) (xy 71.417111 -337.816978) (xy 71.399977 -337.816978)
			(xy 71.39178 -337.819492) (xy 71.356562 -337.83145) (xy 71.28456 -337.850105) (xy 71.211239 -337.862615)
			(xy 71.137124 -337.868889) (xy 71.099934 -337.869276) (xy 71.057995 -337.868786) (xy 70.974497 -337.860816)
			(xy 70.892134 -337.844945) (xy 70.811653 -337.821316) (xy 70.733783 -337.790144) (xy 70.659228 -337.751711)
			(xy 70.588664 -337.706365) (xy 70.522731 -337.654517) (xy 70.462025 -337.596636) (xy 70.407095 -337.533246)
			(xy 70.35844 -337.464922) (xy 70.3165 -337.392282) (xy 70.281655 -337.315985) (xy 70.254221 -337.23672)
			(xy 70.234446 -337.155207) (xy 70.222508 -337.072183) (xy 70.218517 -336.9884) (xy 2.509012 -336.9884)
			(xy 2.509012 -341.9277) (xy 103.538816 -341.9277) (xy 103.542807 -341.843921) (xy 103.554743 -341.760902)
			(xy 103.574517 -341.679392) (xy 103.601948 -341.600131) (xy 103.63679 -341.523837) (xy 103.678726 -341.4512)
			(xy 103.727376 -341.382878) (xy 103.7823 -341.319489) (xy 103.843001 -341.261608) (xy 103.908929 -341.20976)
			(xy 103.979486 -341.164412) (xy 104.054035 -341.125977) (xy 104.131899 -341.094802) (xy 104.212375 -341.071169)
			(xy 104.294732 -341.055293) (xy 104.378225 -341.047317) (xy 104.420162 -341.046816) (xy 104.457351 -341.047215)
			(xy 104.531464 -341.053502) (xy 104.604784 -341.066008) (xy 104.67679 -341.084646) (xy 104.712008 -341.0966)
			(xy 104.720205 -341.099114) (xy 104.737339 -341.099114) (xy 104.745536 -341.0966) (xy 104.780752 -341.084638)
			(xy 104.852755 -341.065983) (xy 104.926076 -341.053475) (xy 105.000192 -341.047202) (xy 105.037382 -341.046816)
			(xy 105.07218 -341.047578) (xy 105.081741 -341.004913) (xy 105.108207 -340.921573) (xy 105.125012 -340.881208)
			(xy 105.128629 -340.871492) (xy 105.128644 -340.850784) (xy 105.125012 -340.841076) (xy 105.107898 -340.799819)
			(xy 105.081109 -340.714608) (xy 105.063074 -340.627124) (xy 105.053979 -340.538265) (xy 105.053384 -340.493604)
			(xy 105.053384 -340.492842) (xy 105.053883 -340.450917) (xy 105.061853 -340.367446) (xy 105.077722 -340.285111)
			(xy 105.101345 -340.204657) (xy 105.132509 -340.126813) (xy 105.170932 -340.052283) (xy 105.216265 -339.981744)
			(xy 105.268098 -339.915833) (xy 105.325961 -339.855147) (xy 105.389331 -339.800237) (xy 105.457634 -339.751599)
			(xy 105.530251 -339.709674) (xy 105.606524 -339.674841) (xy 105.685763 -339.647416) (xy 105.767249 -339.627647)
			(xy 105.850246 -339.615714) (xy 105.934002 -339.611725) (xy 106.017758 -339.615714) (xy 106.100755 -339.627647)
			(xy 106.182241 -339.647416) (xy 106.26148 -339.674841) (xy 106.337753 -339.709674) (xy 106.41037 -339.751599)
			(xy 106.478673 -339.800237) (xy 106.542043 -339.855147) (xy 106.599906 -339.915833) (xy 106.651739 -339.981744)
			(xy 106.697072 -340.052283) (xy 106.735495 -340.126813) (xy 106.766659 -340.204657) (xy 106.790282 -340.285111)
			(xy 106.806151 -340.367446) (xy 106.814121 -340.450917) (xy 106.81462 -340.492842) (xy 106.81462 -340.493604)
			(xy 106.814051 -340.538267) (xy 106.804977 -340.627133) (xy 106.786945 -340.714621) (xy 106.760139 -340.799831)
			(xy 106.742992 -340.841076) (xy 106.739326 -340.850777) (xy 106.739342 -340.871499) (xy 106.742992 -340.881208)
			(xy 106.751628 -340.901528) (xy 106.756582 -340.912278) (xy 106.774248 -340.927996) (xy 106.797062 -340.934212)
			(xy 106.808778 -340.932516) (xy 106.8525 -340.924198) (xy 106.941059 -340.915292) (xy 106.985562 -340.914736)
			(xy 106.98607 -340.914736) (xy 107.027176 -340.915241) (xy 107.109038 -340.922823) (xy 107.189852 -340.937924)
			(xy 107.268928 -340.960416) (xy 107.345591 -340.990108) (xy 107.419189 -341.026745) (xy 107.489092 -341.070016)
			(xy 107.554706 -341.119551) (xy 107.61547 -341.174927) (xy 107.670867 -341.235674) (xy 107.720423 -341.301272)
			(xy 107.763716 -341.371161) (xy 107.800377 -341.444747) (xy 107.830093 -341.521401) (xy 107.85261 -341.60047)
			(xy 107.867738 -341.681278) (xy 107.875346 -341.763138) (xy 107.875832 -341.804244) (xy 107.875268 -341.849014)
			(xy 107.867795 -341.9229) (xy 351.475729 -341.9229) (xy 351.479719 -341.839138) (xy 351.491654 -341.756134)
			(xy 351.511424 -341.674641) (xy 351.538852 -341.595396) (xy 351.573688 -341.519117) (xy 351.615617 -341.446494)
			(xy 351.66426 -341.378187) (xy 351.719176 -341.314813) (xy 351.779867 -341.256945) (xy 351.845785 -341.205109)
			(xy 351.916331 -341.159774) (xy 351.990867 -341.12135) (xy 352.068718 -341.090185) (xy 352.149179 -341.066562)
			(xy 352.231522 -341.050694) (xy 352.314999 -341.042726) (xy 352.356928 -341.042244) (xy 352.357944 -341.042244)
			(xy 352.395001 -341.04264) (xy 352.46885 -341.048907) (xy 352.541913 -341.061352) (xy 352.613673 -341.079887)
			(xy 352.648774 -341.091774) (xy 352.656971 -341.094288) (xy 352.674105 -341.094288) (xy 352.682302 -341.091774)
			(xy 352.717522 -341.079841) (xy 352.789531 -341.06125) (xy 352.862852 -341.048806) (xy 352.936963 -341.042598)
			(xy 352.974148 -341.042244) (xy 352.988626 -341.042244) (xy 352.999994 -341.041829) (xy 353.020668 -341.032414)
			(xy 353.035248 -341.014994) (xy 353.038664 -341.004144) (xy 353.047281 -340.972176) (xy 353.068638 -340.909499)
			(xy 353.081336 -340.878922) (xy 353.084895 -340.86933) (xy 353.084899 -340.848889) (xy 353.081336 -340.839298)
			(xy 353.064328 -340.797915) (xy 353.037705 -340.71249) (xy 353.019796 -340.624824) (xy 353.010783 -340.535802)
			(xy 353.010216 -340.491064) (xy 353.010216 -340.49081) (xy 353.01072 -340.448462) (xy 353.018771 -340.364148)
			(xy 353.0348 -340.280982) (xy 353.058661 -340.199715) (xy 353.09014 -340.121085) (xy 353.128951 -340.045804)
			(xy 353.174741 -339.974552) (xy 353.227097 -339.907976) (xy 353.285545 -339.846678) (xy 353.349555 -339.791213)
			(xy 353.418547 -339.742084) (xy 353.491897 -339.699735) (xy 353.56894 -339.664551) (xy 353.648979 -339.636849)
			(xy 353.731288 -339.616881) (xy 353.815123 -339.604828) (xy 353.899724 -339.600798) (xy 353.984325 -339.604828)
			(xy 354.06816 -339.616881) (xy 354.150469 -339.636849) (xy 354.230508 -339.664551) (xy 354.307551 -339.699735)
			(xy 354.380901 -339.742084) (xy 354.449893 -339.791213) (xy 354.513903 -339.846678) (xy 354.572351 -339.907976)
			(xy 354.624707 -339.974552) (xy 354.670497 -340.045804) (xy 354.709308 -340.121085) (xy 354.740787 -340.199715)
			(xy 354.764648 -340.280982) (xy 354.780677 -340.364148) (xy 354.788728 -340.448462) (xy 354.789232 -340.49081)
			(xy 354.789232 -340.491064) (xy 354.788666 -340.535802) (xy 354.779649 -340.624824) (xy 354.761744 -340.712491)
			(xy 354.73513 -340.797919) (xy 354.718112 -340.839298) (xy 354.714539 -340.848887) (xy 354.714543 -340.869332)
			(xy 354.718112 -340.878922) (xy 354.735129 -340.920302) (xy 354.761749 -341.005728) (xy 354.779655 -341.093395)
			(xy 354.788666 -341.182417) (xy 354.789232 -341.227156) (xy 354.789232 -341.228172) (xy 354.789643 -341.238195)
			(xy 354.79731 -341.256718) (xy 354.811486 -341.270892) (xy 354.830009 -341.278557) (xy 354.840032 -341.278972)
			(xy 354.840286 -341.278972) (xy 354.84794 -341.278603) (xy 354.862532 -341.273956) (xy 354.868988 -341.269828)
			(xy 354.869242 -341.269828) (xy 354.906515 -341.244617) (xy 354.985224 -341.200991) (xy 355.067937 -341.165538)
			(xy 355.153807 -341.13862) (xy 355.241957 -341.120513) (xy 355.331485 -341.111402) (xy 355.37648 -341.110824)
			(xy 355.376988 -341.110824) (xy 355.418092 -341.111264) (xy 355.499949 -341.118848) (xy 355.580757 -341.133953)
			(xy 355.659827 -341.15645) (xy 355.736484 -341.186147) (xy 355.810073 -341.22279) (xy 355.879967 -341.266067)
			(xy 355.94557 -341.315609) (xy 356.006322 -341.370992) (xy 356.061704 -341.431745) (xy 356.111244 -341.497349)
			(xy 356.15452 -341.567245) (xy 356.191162 -341.640835) (xy 356.220857 -341.717492) (xy 356.243352 -341.796562)
			(xy 356.258455 -341.877371) (xy 356.266037 -341.959228) (xy 356.266496 -342.000332) (xy 356.266496 -342.000586)
			(xy 356.26594 -342.045325) (xy 356.256921 -342.134347) (xy 356.239013 -342.222014) (xy 356.212396 -342.307441)
			(xy 356.195376 -342.34882) (xy 356.191792 -342.358405) (xy 356.191804 -342.378853) (xy 356.195376 -342.388444)
			(xy 356.212409 -342.429852) (xy 356.239041 -342.515341) (xy 356.256946 -342.603073) (xy 356.265942 -342.692161)
			(xy 356.266496 -342.736932) (xy 356.265952 -342.781703) (xy 356.256945 -342.87079) (xy 356.239036 -342.958522)
			(xy 356.212407 -343.044011) (xy 356.195376 -343.08542) (xy 356.191792 -343.095005) (xy 356.191804 -343.115453)
			(xy 356.195376 -343.125044) (xy 356.212398 -343.166422) (xy 356.239017 -343.251848) (xy 356.256922 -343.339516)
			(xy 356.265931 -343.428539) (xy 356.266496 -343.473278) (xy 356.266496 -343.473532) (xy 356.266064 -343.514635)
			(xy 356.258476 -343.596491) (xy 356.243368 -343.677298) (xy 356.220868 -343.756366) (xy 356.191169 -343.83302)
			(xy 356.154525 -343.906608) (xy 356.111246 -343.9765) (xy 356.061704 -344.042101) (xy 356.00632 -344.102851)
			(xy 355.945567 -344.158232) (xy 355.879964 -344.207771) (xy 355.810069 -344.251046) (xy 355.73648 -344.287687)
			(xy 355.659824 -344.317382) (xy 355.580755 -344.339878) (xy 355.499948 -344.354982) (xy 355.418091 -344.362566)
			(xy 355.376988 -344.36304) (xy 355.376226 -344.36304) (xy 355.334685 -344.362565) (xy 355.251968 -344.35478)
			(xy 355.170337 -344.33932) (xy 355.090501 -344.316321) (xy 355.013156 -344.285984) (xy 354.938974 -344.248571)
			(xy 354.903532 -344.226896) (xy 354.894382 -344.221758) (xy 354.873674 -344.218535) (xy 354.853403 -344.223857)
			(xy 354.844858 -344.229944) (xy 354.811228 -344.255891) (xy 354.73985 -344.301947) (xy 354.664408 -344.340991)
			(xy 354.585588 -344.372667) (xy 354.504107 -344.396686) (xy 354.420709 -344.412831) (xy 354.336151 -344.420953)
			(xy 354.293678 -344.42146) (xy 354.293424 -344.42146) (xy 354.25232 -344.421025) (xy 354.170462 -344.413441)
			(xy 354.089653 -344.398337) (xy 354.010583 -344.375841) (xy 353.933926 -344.346144) (xy 353.860336 -344.309501)
			(xy 353.790441 -344.266224) (xy 353.724837 -344.216682) (xy 353.664085 -344.161298) (xy 353.608703 -344.100544)
			(xy 353.559163 -344.03494) (xy 353.515887 -343.965043) (xy 353.479246 -343.891453) (xy 353.449552 -343.814794)
			(xy 353.427057 -343.735723) (xy 353.411955 -343.654914) (xy 353.404374 -343.573056) (xy 353.403916 -343.531952)
			(xy 353.403916 -343.531698) (xy 353.4045 -343.48696) (xy 353.413511 -343.397939) (xy 353.431411 -343.310272)
			(xy 353.45802 -343.224844) (xy 353.475036 -343.183464) (xy 353.478628 -343.173881) (xy 353.47861 -343.153431)
			(xy 353.475036 -343.14384) (xy 353.457998 -343.102434) (xy 353.431368 -343.016945) (xy 353.413464 -342.929211)
			(xy 353.404469 -342.840123) (xy 353.403916 -342.795352) (xy 353.403916 -342.783414) (xy 353.377438 -342.777466)
			(xy 353.325203 -342.762725) (xy 353.299522 -342.75395) (xy 353.291325 -342.751436) (xy 353.274191 -342.751436)
			(xy 353.265994 -342.75395) (xy 353.230774 -342.765885) (xy 353.158765 -342.784475) (xy 353.085444 -342.796919)
			(xy 353.011333 -342.803127) (xy 352.974148 -342.80348) (xy 352.936964 -342.803098) (xy 352.862857 -342.79688)
			(xy 352.789537 -342.784441) (xy 352.717525 -342.76587) (xy 352.682302 -342.75395) (xy 352.674105 -342.751436)
			(xy 352.656971 -342.751436) (xy 352.648774 -342.75395) (xy 352.613678 -342.765853) (xy 352.541919 -342.784399)
			(xy 352.468854 -342.796841) (xy 352.395002 -342.80309) (xy 352.357944 -342.80348) (xy 352.356928 -342.80348)
			(xy 352.314999 -342.803074) (xy 352.231522 -342.795106) (xy 352.149179 -342.779238) (xy 352.068718 -342.755615)
			(xy 351.990867 -342.72445) (xy 351.916331 -342.686026) (xy 351.845785 -342.640691) (xy 351.779867 -342.588855)
			(xy 351.719176 -342.530987) (xy 351.66426 -342.467613) (xy 351.615617 -342.399306) (xy 351.573688 -342.326683)
			(xy 351.538852 -342.250404) (xy 351.511424 -342.171159) (xy 351.491654 -342.089666) (xy 351.479719 -342.006662)
			(xy 351.475729 -341.9229) (xy 107.867795 -341.9229) (xy 107.866258 -341.938099) (xy 107.848353 -342.02583)
			(xy 107.821735 -342.111321) (xy 107.804712 -342.152732) (xy 107.80112 -342.162315) (xy 107.801136 -342.182765)
			(xy 107.804712 -342.192356) (xy 107.821734 -342.233768) (xy 107.848372 -342.319255) (xy 107.86628 -342.406986)
			(xy 107.875278 -342.496074) (xy 107.875832 -342.540844) (xy 107.875405 -342.579435) (xy 107.868704 -342.656327)
			(xy 107.855365 -342.732349) (xy 107.835489 -342.806929) (xy 107.822746 -342.843358) (xy 107.81982 -342.852801)
			(xy 107.820595 -342.872535) (xy 107.82427 -342.881712) (xy 107.843314 -342.925129) (xy 107.873091 -343.015145)
			(xy 107.893121 -343.107819) (xy 107.903177 -343.202097) (xy 107.903772 -343.249504) (xy 107.903199 -343.294273)
			(xy 107.894192 -343.383358) (xy 107.87629 -343.471089) (xy 107.849674 -343.556581) (xy 107.832652 -343.597992)
			(xy 107.829086 -343.607582) (xy 107.829087 -343.628025) (xy 107.832652 -343.637616) (xy 107.849695 -343.67902)
			(xy 107.876327 -343.76451) (xy 107.894229 -343.852244) (xy 107.903221 -343.941333) (xy 107.903772 -343.986104)
			(xy 107.903338 -344.0272) (xy 107.895755 -344.109042) (xy 107.880654 -344.189835) (xy 107.858164 -344.268891)
			(xy 107.828477 -344.345534) (xy 107.791846 -344.419112) (xy 107.748583 -344.488997) (xy 107.699057 -344.554593)
			(xy 107.643692 -344.61534) (xy 107.582958 -344.670721) (xy 107.517374 -344.720262) (xy 107.447499 -344.763541)
			(xy 107.37393 -344.80019) (xy 107.297294 -344.829896) (xy 107.218244 -344.852405) (xy 107.137454 -344.867525)
			(xy 107.055614 -344.875128) (xy 107.014518 -344.875612) (xy 107.01401 -344.875612) (xy 106.971454 -344.875048)
			(xy 106.886731 -344.866913) (xy 106.803172 -344.850725) (xy 106.72154 -344.826633) (xy 106.642582 -344.794856)
			(xy 106.567018 -344.755685) (xy 106.49554 -344.709478) (xy 106.428801 -344.656658) (xy 106.36741 -344.597706)
			(xy 106.311928 -344.533162) (xy 106.262863 -344.463615) (xy 106.220663 -344.389701) (xy 106.202734 -344.351102)
			(xy 106.197143 -344.340314) (xy 106.178175 -344.325188) (xy 106.166412 -344.322146) (xy 106.123815 -344.31302)
			(xy 106.04054 -344.287419) (xy 105.960165 -344.253801) (xy 105.883461 -344.212489) (xy 105.811162 -344.163878)
			(xy 105.74396 -344.108434) (xy 105.682498 -344.046687) (xy 105.627365 -343.979229) (xy 105.579089 -343.906705)
			(xy 105.538133 -343.829811) (xy 105.504888 -343.749281) (xy 105.479672 -343.665888) (xy 105.462727 -343.58043)
			(xy 105.454216 -343.493725) (xy 105.453688 -343.450164) (xy 105.454253 -343.405394) (xy 105.463263 -343.316309)
			(xy 105.481167 -343.228578) (xy 105.507785 -343.143087) (xy 105.524808 -343.101676) (xy 105.528395 -343.092092)
			(xy 105.528382 -343.071643) (xy 105.524808 -343.062052) (xy 105.508891 -343.02338) (xy 105.483531 -342.943684)
			(xy 105.46577 -342.861957) (xy 105.460292 -342.820498) (xy 105.458558 -342.81058) (xy 105.448632 -342.793088)
			(xy 105.43277 -342.780723) (xy 105.423208 -342.777572) (xy 105.40795 -342.773353) (xy 105.377717 -342.763951)
			(xy 105.362756 -342.758776) (xy 105.354559 -342.756262) (xy 105.337425 -342.756262) (xy 105.329228 -342.758776)
			(xy 105.294015 -342.770747) (xy 105.222011 -342.789399) (xy 105.148689 -342.801905) (xy 105.074572 -342.808175)
			(xy 105.037382 -342.80856) (xy 105.000192 -342.808173) (xy 104.926079 -342.801882) (xy 104.85276 -342.789372)
			(xy 104.780754 -342.770731) (xy 104.745536 -342.758776) (xy 104.737339 -342.756262) (xy 104.720205 -342.756262)
			(xy 104.712008 -342.758776) (xy 104.676797 -342.770753) (xy 104.604792 -342.789403) (xy 104.531469 -342.801908)
			(xy 104.457353 -342.808176) (xy 104.420162 -342.80856) (xy 104.378225 -342.808083) (xy 104.294732 -342.800107)
			(xy 104.212375 -342.784231) (xy 104.131899 -342.760598) (xy 104.054035 -342.729423) (xy 103.979486 -342.690988)
			(xy 103.908929 -342.64564) (xy 103.843001 -342.593792) (xy 103.7823 -342.535911) (xy 103.727376 -342.472522)
			(xy 103.678726 -342.4042) (xy 103.63679 -342.331563) (xy 103.601948 -342.255269) (xy 103.574517 -342.176008)
			(xy 103.554743 -342.094498) (xy 103.542807 -342.011479) (xy 103.538816 -341.9277) (xy 2.509012 -341.9277)
			(xy 2.509012 -345.238324) (xy 88.42502 -345.238324) (xy 88.42502 -345.237562) (xy 88.425476 -345.196455)
			(xy 88.433064 -345.114592) (xy 88.448171 -345.033778) (xy 88.470668 -344.954703) (xy 88.500364 -344.87804)
			(xy 88.537005 -344.804443) (xy 88.58028 -344.73454) (xy 88.629818 -344.668927) (xy 88.685198 -344.608163)
			(xy 88.745947 -344.552768) (xy 88.811546 -344.503212) (xy 88.881438 -344.459919) (xy 88.955025 -344.423259)
			(xy 89.031681 -344.393542) (xy 89.110751 -344.371024) (xy 89.19156 -344.355896) (xy 89.273421 -344.348287)
			(xy 89.314528 -344.3478) (xy 89.358923 -344.348358) (xy 89.447268 -344.357247) (xy 89.534288 -344.374894)
			(xy 89.619117 -344.401123) (xy 89.660222 -344.417904) (xy 89.668919 -344.421068) (xy 89.687398 -344.421734)
			(xy 89.69629 -344.419174) (xy 89.742575 -344.404089) (xy 89.837607 -344.382956) (xy 89.934379 -344.372329)
			(xy 89.983056 -344.371676) (xy 90.021372 -344.372058) (xy 90.097725 -344.378586) (xy 90.173232 -344.391667)
			(xy 90.247331 -344.411203) (xy 90.283538 -344.423746) (xy 90.291854 -344.426332) (xy 90.309258 -344.426332)
			(xy 90.317574 -344.423746) (xy 90.353782 -344.41121) (xy 90.427885 -344.391692) (xy 90.503391 -344.378612)
			(xy 90.579741 -344.372068) (xy 90.618056 -344.371676) (xy 90.664451 -344.372276) (xy 90.756739 -344.381916)
			(xy 90.847523 -344.401107) (xy 90.935817 -344.429641) (xy 90.978482 -344.447876) (xy 90.988424 -344.451682)
			(xy 91.009688 -344.451682) (xy 91.01963 -344.447876) (xy 91.062298 -344.429645) (xy 91.150588 -344.401097)
			(xy 91.241371 -344.381901) (xy 91.33366 -344.372263) (xy 91.380056 -344.371676) (xy 91.418372 -344.372058)
			(xy 91.494725 -344.378586) (xy 91.570232 -344.391667) (xy 91.644331 -344.411203) (xy 91.680538 -344.423746)
			(xy 91.688854 -344.426332) (xy 91.706258 -344.426332) (xy 91.714574 -344.423746) (xy 91.750782 -344.41121)
			(xy 91.824885 -344.391692) (xy 91.900391 -344.378612) (xy 91.976741 -344.372068) (xy 92.015056 -344.371676)
			(xy 92.053372 -344.372058) (xy 92.129725 -344.378586) (xy 92.205232 -344.391667) (xy 92.279331 -344.411203)
			(xy 92.315538 -344.423746) (xy 92.323854 -344.426332) (xy 92.341258 -344.426332) (xy 92.349574 -344.423746)
			(xy 92.385691 -344.411238) (xy 92.459606 -344.391753) (xy 92.534918 -344.378674) (xy 92.611074 -344.372097)
			(xy 92.649294 -344.371676) (xy 92.650056 -344.371676) (xy 92.691158 -344.372194) (xy 92.773012 -344.379775)
			(xy 92.853817 -344.394876) (xy 92.932883 -344.417369) (xy 93.009537 -344.447061) (xy 93.083125 -344.4837)
			(xy 93.153018 -344.526972) (xy 93.21862 -344.576508) (xy 93.279371 -344.631887) (xy 93.334753 -344.692634)
			(xy 93.384294 -344.758233) (xy 93.427571 -344.828123) (xy 93.464215 -344.901708) (xy 93.493912 -344.97836)
			(xy 93.51641 -345.057425) (xy 93.531517 -345.138229) (xy 93.539103 -345.220082) (xy 93.539564 -345.261184)
			(xy 93.539564 -345.261692) (xy 93.539139 -345.302203) (xy 93.531771 -345.38289) (xy 93.517086 -345.462571)
			(xy 93.495207 -345.540583) (xy 93.466315 -345.616279) (xy 93.448886 -345.652852) (xy 93.444973 -345.661871)
			(xy 93.443532 -345.68146) (xy 93.446092 -345.690952) (xy 93.460285 -345.736019) (xy 93.480192 -345.828387)
			(xy 93.490186 -345.922345) (xy 93.490796 -345.96959) (xy 93.490238 -346.015229) (xy 93.480936 -346.106032)
			(xy 93.462388 -346.195406) (xy 93.44914 -346.239084) (xy 93.446696 -346.248096) (xy 93.447735 -346.266724)
			(xy 93.451172 -346.275406) (xy 93.469867 -346.318487) (xy 93.49915 -346.407722) (xy 93.518862 -346.499547)
			(xy 93.527728 -346.583) (xy 200.85558 -346.583) (xy 200.856207 -346.536598) (xy 200.865897 -346.444301)
			(xy 200.88515 -346.353515) (xy 200.913758 -346.26523) (xy 200.932034 -346.222574) (xy 200.935843 -346.212632)
			(xy 200.935843 -346.191368) (xy 200.932034 -346.181426) (xy 200.913772 -346.138765) (xy 200.885179 -346.050477)
			(xy 200.865922 -345.959694) (xy 200.856209 -345.867401) (xy 200.85558 -345.821) (xy 200.856064 -345.779859)
			(xy 200.863695 -345.69793) (xy 200.878855 -345.617056) (xy 200.901414 -345.537926) (xy 200.931179 -345.461215)
			(xy 200.967897 -345.38758) (xy 200.989184 -345.35237) (xy 200.993752 -345.344157) (xy 200.997195 -345.3257)
			(xy 200.993752 -345.307243) (xy 200.989184 -345.29903) (xy 200.967885 -345.263826) (xy 200.931155 -345.190194)
			(xy 200.901383 -345.113484) (xy 200.878824 -345.034352) (xy 200.86367 -344.953474) (xy 200.856051 -344.871542)
			(xy 200.85558 -344.8304) (xy 200.856207 -344.783998) (xy 200.865897 -344.691701) (xy 200.88515 -344.600915)
			(xy 200.913758 -344.51263) (xy 200.932034 -344.469974) (xy 200.935843 -344.460032) (xy 200.935843 -344.438768)
			(xy 200.932034 -344.428826) (xy 200.913772 -344.386165) (xy 200.885179 -344.297877) (xy 200.865922 -344.207094)
			(xy 200.856209 -344.114801) (xy 200.85558 -344.0684) (xy 200.856084 -344.026039) (xy 200.864137 -343.941702)
			(xy 200.880171 -343.858512) (xy 200.904039 -343.777222) (xy 200.935527 -343.69857) (xy 200.974349 -343.623267)
			(xy 201.020152 -343.551995) (xy 201.072523 -343.485399) (xy 201.130988 -343.424084) (xy 201.195016 -343.368603)
			(xy 201.264028 -343.31946) (xy 201.337398 -343.2771) (xy 201.414463 -343.241905) (xy 201.494525 -343.214196)
			(xy 201.576858 -343.194222) (xy 201.660717 -343.182165) (xy 201.745342 -343.178134) (xy 201.829967 -343.182165)
			(xy 201.913826 -343.194222) (xy 201.996159 -343.214196) (xy 202.076221 -343.241905) (xy 202.153286 -343.2771)
			(xy 202.226656 -343.31946) (xy 202.295668 -343.368603) (xy 202.359696 -343.424084) (xy 202.418161 -343.485399)
			(xy 202.470532 -343.551995) (xy 202.516335 -343.623267) (xy 202.555157 -343.69857) (xy 202.586645 -343.777222)
			(xy 202.610513 -343.858512) (xy 202.626547 -343.941702) (xy 202.6346 -344.026039) (xy 202.635104 -344.0684)
			(xy 202.634479 -344.114802) (xy 202.624789 -344.2071) (xy 202.605534 -344.297885) (xy 202.576926 -344.38617)
			(xy 202.55865 -344.428826) (xy 202.554842 -344.438768) (xy 202.554842 -344.460032) (xy 202.55865 -344.469974)
			(xy 202.576911 -344.512635) (xy 202.605505 -344.600923) (xy 202.624762 -344.691706) (xy 202.634475 -344.783999)
			(xy 202.635104 -344.8304) (xy 202.634622 -344.871541) (xy 202.626991 -344.95347) (xy 202.611831 -345.034344)
			(xy 202.589272 -345.113474) (xy 202.559506 -345.190185) (xy 202.522787 -345.263821) (xy 202.5015 -345.29903)
			(xy 202.496933 -345.307243) (xy 202.493491 -345.3257) (xy 202.496933 -345.344157) (xy 202.5015 -345.35237)
			(xy 202.522797 -345.387575) (xy 202.559528 -345.461207) (xy 202.5893 -345.537917) (xy 202.61186 -345.617049)
			(xy 202.627014 -345.697926) (xy 202.634633 -345.779858) (xy 202.635104 -345.821) (xy 202.634479 -345.867402)
			(xy 202.624789 -345.9597) (xy 202.605534 -346.050485) (xy 202.576926 -346.13877) (xy 202.55865 -346.181426)
			(xy 202.554842 -346.191368) (xy 202.554842 -346.212632) (xy 202.55865 -346.222574) (xy 202.576911 -346.265235)
			(xy 202.605505 -346.353523) (xy 202.624762 -346.444306) (xy 202.634475 -346.536599) (xy 202.635104 -346.583)
			(xy 202.6346 -346.625361) (xy 202.626547 -346.709698) (xy 202.610513 -346.792888) (xy 202.586645 -346.874178)
			(xy 202.555157 -346.95283) (xy 202.516335 -347.028133) (xy 202.470532 -347.099405) (xy 202.418161 -347.166001)
			(xy 202.359696 -347.227316) (xy 202.295668 -347.282797) (xy 202.226656 -347.33194) (xy 202.153286 -347.3743)
			(xy 202.076221 -347.409495) (xy 201.996159 -347.437204) (xy 201.913826 -347.457178) (xy 201.829967 -347.469235)
			(xy 201.745342 -347.473267) (xy 201.660717 -347.469235) (xy 201.576858 -347.457178) (xy 201.494525 -347.437204)
			(xy 201.414463 -347.409495) (xy 201.337398 -347.3743) (xy 201.264028 -347.33194) (xy 201.195016 -347.282797)
			(xy 201.130988 -347.227316) (xy 201.072523 -347.166001) (xy 201.020152 -347.099405) (xy 200.974349 -347.028133)
			(xy 200.935527 -346.95283) (xy 200.904039 -346.874178) (xy 200.880171 -346.792888) (xy 200.864137 -346.709698)
			(xy 200.856084 -346.625361) (xy 200.85558 -346.583) (xy 93.527728 -346.583) (xy 93.528784 -346.592938)
			(xy 93.529404 -346.639896) (xy 93.528944 -346.681007) (xy 93.521356 -346.762877) (xy 93.506246 -346.843698)
			(xy 93.483741 -346.92278) (xy 93.454034 -346.999447) (xy 93.417379 -347.073045) (xy 93.374088 -347.142947)
			(xy 93.324531 -347.208555) (xy 93.269131 -347.26931) (xy 93.20836 -347.324693) (xy 93.142737 -347.374232)
			(xy 93.072823 -347.417503) (xy 92.999214 -347.454137) (xy 92.922539 -347.483822) (xy 92.843451 -347.506304)
			(xy 92.762626 -347.521391) (xy 92.680753 -347.528955) (xy 92.639642 -347.529404) (xy 92.601326 -347.529024)
			(xy 92.524973 -347.522495) (xy 92.449466 -347.509414) (xy 92.375367 -347.489878) (xy 92.33916 -347.477334)
			(xy 92.330844 -347.474748) (xy 92.31344 -347.474748) (xy 92.305124 -347.477334) (xy 92.268906 -347.489842)
			(xy 92.194807 -347.509368) (xy 92.119304 -347.522455) (xy 92.042956 -347.529008) (xy 92.004642 -347.529404)
			(xy 91.961529 -347.52892) (xy 91.875703 -347.520642) (xy 91.791081 -347.504091) (xy 91.70846 -347.479423)
			(xy 91.668346 -347.463618) (xy 91.658977 -347.460281) (xy 91.639107 -347.460281) (xy 91.629738 -347.463618)
			(xy 91.589623 -347.479419) (xy 91.506999 -347.504075) (xy 91.422379 -347.520627) (xy 91.336554 -347.528919)
			(xy 91.293442 -347.529404) (xy 91.255126 -347.529024) (xy 91.178773 -347.522495) (xy 91.103266 -347.509414)
			(xy 91.029167 -347.489878) (xy 90.99296 -347.477334) (xy 90.984644 -347.474748) (xy 90.96724 -347.474748)
			(xy 90.958924 -347.477334) (xy 90.922706 -347.489842) (xy 90.848607 -347.509368) (xy 90.773104 -347.522455)
			(xy 90.696756 -347.529008) (xy 90.658442 -347.529404) (xy 90.620126 -347.529024) (xy 90.543773 -347.522495)
			(xy 90.468266 -347.509414) (xy 90.394167 -347.489878) (xy 90.35796 -347.477334) (xy 90.349644 -347.474748)
			(xy 90.33224 -347.474748) (xy 90.323924 -347.477334) (xy 90.287706 -347.489842) (xy 90.213607 -347.509368)
			(xy 90.138104 -347.522455) (xy 90.061756 -347.529008) (xy 90.023442 -347.529404) (xy 89.985126 -347.529024)
			(xy 89.908773 -347.522495) (xy 89.833266 -347.509414) (xy 89.759167 -347.489878) (xy 89.72296 -347.477334)
			(xy 89.714644 -347.474748) (xy 89.69724 -347.474748) (xy 89.688924 -347.477334) (xy 89.652807 -347.489842)
			(xy 89.578892 -347.509327) (xy 89.50358 -347.522407) (xy 89.427424 -347.528983) (xy 89.389204 -347.529404)
			(xy 89.388442 -347.529404) (xy 89.347337 -347.528847) (xy 89.265478 -347.521267) (xy 89.184667 -347.506168)
			(xy 89.105593 -347.483678) (xy 89.028932 -347.453989) (xy 88.955336 -347.417355) (xy 88.885433 -347.374087)
			(xy 88.81982 -347.324556) (xy 88.759057 -347.269183) (xy 88.70366 -347.20844) (xy 88.654104 -347.142846)
			(xy 88.61081 -347.07296) (xy 88.574148 -346.999378) (xy 88.54443 -346.922728) (xy 88.52191 -346.843663)
			(xy 88.506779 -346.762857) (xy 88.499168 -346.681001) (xy 88.49868 -346.639896) (xy 88.49928 -346.594251)
			(xy 88.508675 -346.503445) (xy 88.527305 -346.414075) (xy 88.54059 -346.370402) (xy 88.543039 -346.361391)
			(xy 88.541996 -346.342762) (xy 88.538558 -346.33408) (xy 88.519895 -346.290993) (xy 88.490688 -346.201748)
			(xy 88.471043 -346.109924) (xy 88.461176 -346.016541) (xy 88.46058 -345.96959) (xy 88.460997 -345.930463)
			(xy 88.467845 -345.852508) (xy 88.481506 -345.775455) (xy 88.501874 -345.699897) (xy 88.514936 -345.663012)
			(xy 88.517951 -345.653293) (xy 88.516917 -345.632991) (xy 88.512904 -345.623642) (xy 88.496039 -345.587523)
			(xy 88.46806 -345.512874) (xy 88.44687 -345.436021) (xy 88.432638 -345.357582) (xy 88.425479 -345.278184)
			(xy 88.42502 -345.238324) (xy 2.509012 -345.238324) (xy 2.509012 -348.70949) (xy 28.410141 -348.70949)
			(xy 28.414132 -348.625708) (xy 28.426069 -348.542686) (xy 28.445844 -348.461173) (xy 28.473277 -348.38191)
			(xy 28.508121 -348.305613) (xy 28.550059 -348.232974) (xy 28.598712 -348.16465) (xy 28.65364 -348.101261)
			(xy 28.714345 -348.043379) (xy 28.780276 -347.99153) (xy 28.850838 -347.946183) (xy 28.92539 -347.907749)
			(xy 29.003259 -347.876576) (xy 29.083738 -347.852945) (xy 29.166099 -347.837072) (xy 29.249596 -347.829099)
			(xy 29.291534 -347.828616) (xy 29.328723 -347.829023) (xy 29.402836 -347.835307) (xy 29.476156 -347.847812)
			(xy 29.548162 -347.866448) (xy 29.58338 -347.8784) (xy 29.591577 -347.880914) (xy 29.608711 -347.880914)
			(xy 29.616908 -347.8784) (xy 29.652035 -347.866473) (xy 29.723849 -347.847849) (xy 29.796976 -347.835339)
			(xy 29.870898 -347.829031) (xy 29.907992 -347.828616) (xy 29.909516 -347.828616) (xy 29.916374 -347.82887)
			(xy 29.922431 -347.792721) (xy 29.939716 -347.721486) (xy 29.962803 -347.651915) (xy 29.976826 -347.61805)
			(xy 29.980289 -347.608427) (xy 29.980173 -347.587996) (xy 29.976572 -347.578426) (xy 29.959544 -347.537016)
			(xy 29.932908 -347.451529) (xy 29.915001 -347.363797) (xy 29.906005 -347.274709) (xy 29.905452 -347.229938)
			(xy 29.905933 -347.189355) (xy 29.913331 -347.108527) (xy 29.928059 -347.028709) (xy 29.949995 -346.950564)
			(xy 29.978957 -346.874741) (xy 30.014703 -346.801871) (xy 30.056938 -346.732559) (xy 30.10531 -346.667382)
			(xy 30.159416 -346.606881) (xy 30.218807 -346.551559) (xy 30.28299 -346.501876) (xy 30.351431 -346.458245)
			(xy 30.38729 -346.439236) (xy 30.395816 -346.434265) (xy 30.408633 -346.419285) (xy 30.414885 -346.400588)
			(xy 30.414722 -346.390722) (xy 30.41396 -346.365322) (xy 30.414481 -346.337437) (xy 30.422793 -346.28229)
			(xy 30.439231 -346.228998) (xy 30.463429 -346.178752) (xy 30.494845 -346.132673) (xy 30.532778 -346.091791)
			(xy 30.57638 -346.057019) (xy 30.624678 -346.029134) (xy 30.676593 -346.008759) (xy 30.730964 -345.996349)
			(xy 30.786578 -345.992182) (xy 30.842192 -345.996349) (xy 30.896563 -346.008759) (xy 30.948478 -346.029134)
			(xy 30.996776 -346.057019) (xy 31.040378 -346.091791) (xy 31.078311 -346.132673) (xy 31.109727 -346.178752)
			(xy 31.133925 -346.228998) (xy 31.150363 -346.28229) (xy 31.158675 -346.337437) (xy 31.159196 -346.365322)
			(xy 31.158688 -346.383356) (xy 31.15866 -346.393249) (xy 31.165282 -346.411875) (xy 31.178455 -346.426614)
			(xy 31.187136 -346.431362) (xy 31.224041 -346.449965) (xy 31.294555 -346.49308) (xy 31.360766 -346.542551)
			(xy 31.4221 -346.597952) (xy 31.47803 -346.658805) (xy 31.528073 -346.724585) (xy 31.571797 -346.794724)
			(xy 31.608825 -346.868616) (xy 31.638837 -346.945626) (xy 31.661575 -347.025088) (xy 31.676842 -347.106317)
			(xy 31.684507 -347.188612) (xy 31.684976 -347.229938) (xy 31.684414 -347.274708) (xy 31.675404 -347.363793)
			(xy 31.657499 -347.451524) (xy 31.630879 -347.537015) (xy 31.613856 -347.578426) (xy 31.61027 -347.58801)
			(xy 31.610284 -347.608459) (xy 31.613856 -347.61805) (xy 31.630031 -347.657368) (xy 31.655701 -347.738424)
			(xy 31.673532 -347.821557) (xy 31.68336 -347.906011) (xy 31.684722 -347.948504) (xy 31.684976 -347.96222)
			(xy 31.6992 -347.985588) (xy 31.788862 -348.034102) (xy 31.796927 -348.038113) (xy 31.814734 -348.040741)
			(xy 31.832352 -348.037052) (xy 31.84017 -348.032578) (xy 31.875522 -348.010993) (xy 31.949529 -347.973778)
			(xy 32.026677 -347.943609) (xy 32.106297 -347.920748) (xy 32.187699 -347.905393) (xy 32.270176 -347.897677)
			(xy 32.311594 -347.897196) (xy 32.352707 -347.897719) (xy 32.434582 -347.905305) (xy 32.515408 -347.920413)
			(xy 32.594495 -347.942914) (xy 32.671169 -347.972616) (xy 32.744775 -348.009266) (xy 32.814686 -348.05255)
			(xy 32.880304 -348.102101) (xy 32.941071 -348.157495) (xy 32.996468 -348.218259) (xy 33.046022 -348.283875)
			(xy 33.089311 -348.353783) (xy 33.125965 -348.427387) (xy 33.155671 -348.504059) (xy 33.178176 -348.583145)
			(xy 33.193289 -348.66397) (xy 33.197509 -348.70949) (xy 36.690541 -348.70949) (xy 36.694532 -348.625708)
			(xy 36.706469 -348.542686) (xy 36.726244 -348.461173) (xy 36.753677 -348.38191) (xy 36.788521 -348.305613)
			(xy 36.830459 -348.232974) (xy 36.879112 -348.16465) (xy 36.93404 -348.101261) (xy 36.994745 -348.043379)
			(xy 37.060676 -347.99153) (xy 37.131238 -347.946183) (xy 37.20579 -347.907749) (xy 37.283659 -347.876576)
			(xy 37.364138 -347.852945) (xy 37.446499 -347.837072) (xy 37.529996 -347.829099) (xy 37.571934 -347.828616)
			(xy 37.609123 -347.829023) (xy 37.683236 -347.835307) (xy 37.756556 -347.847812) (xy 37.828562 -347.866448)
			(xy 37.86378 -347.8784) (xy 37.871977 -347.880914) (xy 37.889111 -347.880914) (xy 37.897308 -347.8784)
			(xy 37.93549 -347.865472) (xy 38.013674 -347.845816) (xy 38.093328 -347.833391) (xy 38.133528 -347.830394)
			(xy 38.144516 -347.829167) (xy 38.163935 -347.818636) (xy 38.177169 -347.800949) (xy 38.18001 -347.790262)
			(xy 38.189419 -347.748079) (xy 38.215379 -347.665637) (xy 38.231826 -347.62567) (xy 38.235335 -347.61606)
			(xy 38.235189 -347.595617) (xy 38.231572 -347.586046) (xy 38.21455 -347.544634) (xy 38.187912 -347.459147)
			(xy 38.170004 -347.371416) (xy 38.161006 -347.282328) (xy 38.160452 -347.237558) (xy 38.160956 -347.195197)
			(xy 38.169009 -347.11086) (xy 38.185043 -347.02767) (xy 38.208911 -346.94638) (xy 38.240399 -346.867728)
			(xy 38.279221 -346.792425) (xy 38.325024 -346.721153) (xy 38.377395 -346.654557) (xy 38.43586 -346.593242)
			(xy 38.499888 -346.537761) (xy 38.5689 -346.488618) (xy 38.64227 -346.446258) (xy 38.719335 -346.411063)
			(xy 38.799397 -346.383354) (xy 38.88173 -346.36338) (xy 38.965589 -346.351323) (xy 39.050214 -346.347292)
			(xy 39.134839 -346.351323) (xy 39.218698 -346.36338) (xy 39.301031 -346.383354) (xy 39.381093 -346.411063)
			(xy 39.458158 -346.446258) (xy 39.531528 -346.488618) (xy 39.60054 -346.537761) (xy 39.664568 -346.593242)
			(xy 39.723033 -346.654557) (xy 39.775404 -346.721153) (xy 39.821207 -346.792425) (xy 39.860029 -346.867728)
			(xy 39.891517 -346.94638) (xy 39.915385 -347.02767) (xy 39.931419 -347.11086) (xy 39.939472 -347.195197)
			(xy 39.939976 -347.237558) (xy 39.939421 -347.282328) (xy 39.930409 -347.371413) (xy 39.912502 -347.459144)
			(xy 39.88588 -347.544635) (xy 39.868856 -347.586046) (xy 39.865251 -347.595621) (xy 39.865104 -347.616057)
			(xy 39.868602 -347.62567) (xy 39.88516 -347.665899) (xy 39.911278 -347.748887) (xy 39.929176 -347.834027)
			(xy 39.938683 -347.920507) (xy 39.939722 -347.963998) (xy 39.939722 -347.964252) (xy 39.94031 -347.973302)
			(xy 39.94696 -347.990157) (xy 39.959055 -348.003648) (xy 39.9669 -348.008194) (xy 40.058086 -348.056454)
			(xy 40.086026 -348.05493) (xy 40.09771 -348.04731) (xy 40.134305 -348.023444) (xy 40.211348 -347.98223)
			(xy 40.292061 -347.948768) (xy 40.375665 -347.923381) (xy 40.461356 -347.906311) (xy 40.548307 -347.897725)
			(xy 40.591994 -347.897196) (xy 40.633107 -347.897719) (xy 40.714982 -347.905305) (xy 40.795808 -347.920413)
			(xy 40.874895 -347.942914) (xy 40.951569 -347.972616) (xy 41.025175 -348.009266) (xy 41.095086 -348.05255)
			(xy 41.160704 -348.102101) (xy 41.221471 -348.157495) (xy 41.276868 -348.218259) (xy 41.326422 -348.283875)
			(xy 41.369711 -348.353783) (xy 41.406365 -348.427387) (xy 41.436071 -348.504059) (xy 41.458576 -348.583145)
			(xy 41.473689 -348.66397) (xy 41.47791 -348.7095) (xy 44.996301 -348.7095) (xy 45.000292 -348.625716)
			(xy 45.01223 -348.54269) (xy 45.032006 -348.461175) (xy 45.05944 -348.381909) (xy 45.094286 -348.30561)
			(xy 45.136227 -348.232969) (xy 45.184883 -348.164644) (xy 45.239813 -348.101253) (xy 45.30052 -348.043371)
			(xy 45.366455 -347.991522) (xy 45.43702 -347.946175) (xy 45.511576 -347.907741) (xy 45.589448 -347.876568)
			(xy 45.66993 -347.852939) (xy 45.752294 -347.837068) (xy 45.835794 -347.829098) (xy 45.877734 -347.828616)
			(xy 45.914923 -347.829023) (xy 45.989036 -347.835307) (xy 46.062356 -347.847812) (xy 46.134362 -347.866448)
			(xy 46.16958 -347.8784) (xy 46.177777 -347.880914) (xy 46.194911 -347.880914) (xy 46.203108 -347.8784)
			(xy 46.238327 -347.866445) (xy 46.310329 -347.847789) (xy 46.383649 -347.835279) (xy 46.457764 -347.829003)
			(xy 46.494954 -347.828616) (xy 46.496732 -347.82887) (xy 46.506097 -347.78788) (xy 46.53154 -347.707736)
			(xy 46.547532 -347.66885) (xy 46.551076 -347.659253) (xy 46.55109 -347.638816) (xy 46.547532 -347.629226)
			(xy 46.530501 -347.587817) (xy 46.503866 -347.502329) (xy 46.485961 -347.414597) (xy 46.476965 -347.325509)
			(xy 46.476412 -347.280738) (xy 46.476916 -347.238377) (xy 46.484969 -347.15404) (xy 46.501003 -347.07085)
			(xy 46.524871 -346.98956) (xy 46.556359 -346.910908) (xy 46.595181 -346.835605) (xy 46.640984 -346.764333)
			(xy 46.693355 -346.697737) (xy 46.75182 -346.636422) (xy 46.815848 -346.580941) (xy 46.88486 -346.531798)
			(xy 46.95823 -346.489438) (xy 47.035295 -346.454243) (xy 47.115357 -346.426534) (xy 47.19769 -346.40656)
			(xy 47.281549 -346.394503) (xy 47.366174 -346.390472) (xy 47.450799 -346.394503) (xy 47.534658 -346.40656)
			(xy 47.616991 -346.426534) (xy 47.697053 -346.454243) (xy 47.774118 -346.489438) (xy 47.847488 -346.531798)
			(xy 47.9165 -346.580941) (xy 47.980528 -346.636422) (xy 48.038993 -346.697737) (xy 48.091364 -346.764333)
			(xy 48.137167 -346.835605) (xy 48.175989 -346.910908) (xy 48.207477 -346.98956) (xy 48.231345 -347.07085)
			(xy 48.247379 -347.15404) (xy 48.255432 -347.238377) (xy 48.255936 -347.280738) (xy 48.25537 -347.325508)
			(xy 48.24636 -347.414592) (xy 48.228456 -347.502324) (xy 48.201838 -347.587815) (xy 48.184816 -347.629226)
			(xy 48.181232 -347.638811) (xy 48.181246 -347.659259) (xy 48.184816 -347.66885) (xy 48.199304 -347.703977)
			(xy 48.222973 -347.776187) (xy 48.2404 -347.850153) (xy 48.251457 -347.925335) (xy 48.254158 -347.963236)
			(xy 48.255104 -347.972078) (xy 48.26215 -347.988388) (xy 48.274337 -348.001315) (xy 48.282098 -348.005654)
			(xy 48.37303 -348.051374) (xy 48.3997 -348.04985) (xy 48.41113 -348.04223) (xy 48.447343 -348.019182)
			(xy 48.523387 -347.979349) (xy 48.602912 -347.947022) (xy 48.685181 -347.922504) (xy 48.769429 -347.90602)
			(xy 48.854872 -347.897725) (xy 48.897794 -347.897196) (xy 48.938907 -347.897719) (xy 49.020782 -347.905305)
			(xy 49.101608 -347.920413) (xy 49.180695 -347.942914) (xy 49.257369 -347.972616) (xy 49.330975 -348.009266)
			(xy 49.400886 -348.05255) (xy 49.466504 -348.102101) (xy 49.527271 -348.157495) (xy 49.582668 -348.218259)
			(xy 49.632222 -348.283875) (xy 49.675511 -348.353783) (xy 49.712165 -348.427387) (xy 49.741871 -348.504059)
			(xy 49.764376 -348.583145) (xy 49.779489 -348.66397) (xy 49.78371 -348.7095) (xy 53.352901 -348.7095)
			(xy 53.356892 -348.625716) (xy 53.36883 -348.54269) (xy 53.388606 -348.461175) (xy 53.41604 -348.381909)
			(xy 53.450886 -348.30561) (xy 53.492827 -348.232969) (xy 53.541483 -348.164644) (xy 53.596413 -348.101253)
			(xy 53.65712 -348.043371) (xy 53.723055 -347.991522) (xy 53.79362 -347.946175) (xy 53.868176 -347.907741)
			(xy 53.946048 -347.876568) (xy 54.02653 -347.852939) (xy 54.108894 -347.837068) (xy 54.192394 -347.829098)
			(xy 54.234334 -347.828616) (xy 54.271523 -347.829023) (xy 54.345636 -347.835307) (xy 54.418956 -347.847812)
			(xy 54.490962 -347.866448) (xy 54.52618 -347.8784) (xy 54.534377 -347.880914) (xy 54.551511 -347.880914)
			(xy 54.559708 -347.8784) (xy 54.594654 -347.86653) (xy 54.66609 -347.847969) (xy 54.738831 -347.835458)
			(xy 54.812365 -347.829087) (xy 54.849268 -347.828616) (xy 54.85384 -347.82887) (xy 54.854348 -347.82887)
			(xy 54.863907 -347.782599) (xy 54.89152 -347.692237) (xy 54.909466 -347.64853) (xy 54.912939 -347.63891)
			(xy 54.912815 -347.618477) (xy 54.909212 -347.608906) (xy 54.892173 -347.5675) (xy 54.865541 -347.482011)
			(xy 54.847637 -347.394278) (xy 54.838644 -347.305189) (xy 54.838092 -347.260418) (xy 54.838596 -347.218057)
			(xy 54.846649 -347.13372) (xy 54.862683 -347.05053) (xy 54.886551 -346.96924) (xy 54.918039 -346.890588)
			(xy 54.956861 -346.815285) (xy 55.002664 -346.744013) (xy 55.055035 -346.677417) (xy 55.1135 -346.616102)
			(xy 55.177528 -346.560621) (xy 55.24654 -346.511478) (xy 55.31991 -346.469118) (xy 55.396975 -346.433923)
			(xy 55.477037 -346.406214) (xy 55.55937 -346.38624) (xy 55.643229 -346.374183) (xy 55.727854 -346.370152)
			(xy 55.812479 -346.374183) (xy 55.896338 -346.38624) (xy 55.978671 -346.406214) (xy 56.058733 -346.433923)
			(xy 56.135798 -346.469118) (xy 56.209168 -346.511478) (xy 56.27818 -346.560621) (xy 56.342208 -346.616102)
			(xy 56.400673 -346.677417) (xy 56.453044 -346.744013) (xy 56.498847 -346.815285) (xy 56.537669 -346.890588)
			(xy 56.569157 -346.96924) (xy 56.593025 -347.05053) (xy 56.609059 -347.13372) (xy 56.617112 -347.218057)
			(xy 56.617616 -347.260418) (xy 56.617044 -347.305187) (xy 56.608037 -347.394272) (xy 56.590134 -347.482003)
			(xy 56.563518 -347.567495) (xy 56.546496 -347.608906) (xy 56.542919 -347.618493) (xy 56.542926 -347.63894)
			(xy 56.546496 -347.64853) (xy 56.561684 -347.685398) (xy 56.586189 -347.761282) (xy 56.603812 -347.839053)
			(xy 56.614411 -347.918088) (xy 56.6166 -347.957902) (xy 56.617108 -347.971364) (xy 56.63184 -347.994224)
			(xy 56.734456 -348.047564) (xy 56.761634 -348.04604) (xy 56.773064 -348.038674) (xy 56.808981 -348.016152)
			(xy 56.88432 -347.977266) (xy 56.963017 -347.945725) (xy 57.044358 -347.921816) (xy 57.127605 -347.905754)
			(xy 57.212003 -347.897686) (xy 57.254394 -347.897196) (xy 57.295507 -347.897719) (xy 57.377382 -347.905305)
			(xy 57.458208 -347.920413) (xy 57.537295 -347.942914) (xy 57.613969 -347.972616) (xy 57.687575 -348.009266)
			(xy 57.757486 -348.05255) (xy 57.823104 -348.102101) (xy 57.883871 -348.157495) (xy 57.939268 -348.218259)
			(xy 57.988822 -348.283875) (xy 58.032111 -348.353783) (xy 58.068765 -348.427387) (xy 58.098471 -348.504059)
			(xy 58.120976 -348.583145) (xy 58.136089 -348.66397) (xy 58.14031 -348.7095) (xy 61.684101 -348.7095)
			(xy 61.688092 -348.625716) (xy 61.70003 -348.54269) (xy 61.719806 -348.461175) (xy 61.74724 -348.381909)
			(xy 61.782086 -348.30561) (xy 61.824027 -348.232969) (xy 61.872683 -348.164644) (xy 61.927613 -348.101253)
			(xy 61.98832 -348.043371) (xy 62.054255 -347.991522) (xy 62.12482 -347.946175) (xy 62.199376 -347.907741)
			(xy 62.277248 -347.876568) (xy 62.35773 -347.852939) (xy 62.440094 -347.837068) (xy 62.523594 -347.829098)
			(xy 62.565534 -347.828616) (xy 62.602723 -347.829023) (xy 62.676836 -347.835307) (xy 62.750156 -347.847812)
			(xy 62.822162 -347.866448) (xy 62.85738 -347.8784) (xy 62.865577 -347.880914) (xy 62.882711 -347.880914)
			(xy 62.890908 -347.8784) (xy 62.926096 -347.866455) (xy 62.998036 -347.847809) (xy 63.071292 -347.835299)
			(xy 63.145342 -347.829013) (xy 63.1825 -347.828616) (xy 63.183008 -347.828616) (xy 63.206122 -347.829124)
			(xy 63.215205 -347.793715) (xy 63.238479 -347.724411) (xy 63.252604 -347.690694) (xy 63.256229 -347.680981)
			(xy 63.25624 -347.66027) (xy 63.252604 -347.650562) (xy 63.235485 -347.609307) (xy 63.208697 -347.524095)
			(xy 63.190664 -347.436611) (xy 63.181571 -347.347751) (xy 63.180976 -347.30309) (xy 63.180976 -347.302328)
			(xy 63.181475 -347.260403) (xy 63.189445 -347.176932) (xy 63.205314 -347.094597) (xy 63.228937 -347.014143)
			(xy 63.260101 -346.936299) (xy 63.298524 -346.861769) (xy 63.343857 -346.79123) (xy 63.39569 -346.725319)
			(xy 63.453553 -346.664633) (xy 63.516923 -346.609723) (xy 63.585226 -346.561085) (xy 63.657843 -346.51916)
			(xy 63.734116 -346.484327) (xy 63.813355 -346.456902) (xy 63.894841 -346.437133) (xy 63.977838 -346.4252)
			(xy 64.061594 -346.421211) (xy 64.14535 -346.4252) (xy 64.228347 -346.437133) (xy 64.309833 -346.456902)
			(xy 64.389072 -346.484327) (xy 64.465345 -346.51916) (xy 64.537962 -346.561085) (xy 64.606265 -346.609723)
			(xy 64.669635 -346.664633) (xy 64.727498 -346.725319) (xy 64.779331 -346.79123) (xy 64.824664 -346.861769)
			(xy 64.863087 -346.936299) (xy 64.894251 -347.014143) (xy 64.917874 -347.094597) (xy 64.933743 -347.176932)
			(xy 64.941713 -347.260403) (xy 64.942212 -347.302328) (xy 64.942212 -347.30309) (xy 64.941639 -347.347753)
			(xy 64.932567 -347.436619) (xy 64.914535 -347.524107) (xy 64.88773 -347.609317) (xy 64.870584 -347.650562)
			(xy 64.866927 -347.660266) (xy 64.866937 -347.680985) (xy 64.870584 -347.690694) (xy 64.888862 -347.734789)
			(xy 64.91689 -347.826038) (xy 64.934892 -347.919782) (xy 64.939418 -347.9673) (xy 64.940434 -347.980508)
			(xy 64.955674 -348.00286) (xy 65.046352 -348.047056) (xy 65.054393 -348.050544) (xy 65.071798 -348.052482)
			(xy 65.088843 -348.048463) (xy 65.09639 -348.044008) (xy 65.096644 -348.043754) (xy 65.132959 -348.020439)
			(xy 65.209305 -347.980191) (xy 65.289189 -347.947525) (xy 65.371861 -347.922748) (xy 65.456544 -347.906093)
			(xy 65.542442 -347.897716) (xy 65.585594 -347.897196) (xy 65.626707 -347.897719) (xy 65.708582 -347.905305)
			(xy 65.789408 -347.920413) (xy 65.868495 -347.942914) (xy 65.945169 -347.972616) (xy 66.018775 -348.009266)
			(xy 66.088686 -348.05255) (xy 66.154304 -348.102101) (xy 66.215071 -348.157495) (xy 66.270468 -348.218259)
			(xy 66.320022 -348.283875) (xy 66.363311 -348.353783) (xy 66.399965 -348.427387) (xy 66.429671 -348.504059)
			(xy 66.452176 -348.583145) (xy 66.467289 -348.66397) (xy 66.474879 -348.745845) (xy 66.475356 -348.786958)
			(xy 66.474795 -348.831728) (xy 66.467942 -348.89948) (xy 81.294224 -348.89948) (xy 81.294687 -348.858913)
			(xy 81.30208 -348.778118) (xy 81.316804 -348.698332) (xy 81.338734 -348.620219) (xy 81.36769 -348.544429)
			(xy 81.385156 -348.507812) (xy 81.389058 -348.498717) (xy 81.390365 -348.478988) (xy 81.387696 -348.469458)
			(xy 81.373498 -348.424437) (xy 81.353605 -348.332151) (xy 81.343609 -348.238277) (xy 81.342992 -348.191074)
			(xy 81.343496 -348.148713) (xy 81.351549 -348.064376) (xy 81.367583 -347.981186) (xy 81.391451 -347.899896)
			(xy 81.422939 -347.821244) (xy 81.461761 -347.745941) (xy 81.507564 -347.674669) (xy 81.559935 -347.608073)
			(xy 81.6184 -347.546758) (xy 81.682428 -347.491277) (xy 81.75144 -347.442134) (xy 81.82481 -347.399774)
			(xy 81.901875 -347.364579) (xy 81.981937 -347.33687) (xy 82.06427 -347.316896) (xy 82.148129 -347.304839)
			(xy 82.232754 -347.300808) (xy 82.317379 -347.304839) (xy 82.401238 -347.316896) (xy 82.483571 -347.33687)
			(xy 82.563633 -347.364579) (xy 82.640698 -347.399774) (xy 82.714068 -347.442134) (xy 82.78308 -347.491277)
			(xy 82.847108 -347.546758) (xy 82.905573 -347.608073) (xy 82.957944 -347.674669) (xy 83.003747 -347.745941)
			(xy 83.042569 -347.821244) (xy 83.074057 -347.899896) (xy 83.097925 -347.981186) (xy 83.113959 -348.064376)
			(xy 83.122012 -348.148713) (xy 83.122516 -348.191074) (xy 83.12207 -348.231641) (xy 83.114672 -348.312437)
			(xy 83.099945 -348.392223) (xy 83.07801 -348.470336) (xy 83.049051 -348.546125) (xy 83.031584 -348.582742)
			(xy 83.027707 -348.591846) (xy 83.026383 -348.611567) (xy 83.029044 -348.621096) (xy 83.043232 -348.66612)
			(xy 83.063129 -348.758404) (xy 83.073129 -348.852278) (xy 83.073245 -348.861126) (xy 83.956144 -348.861126)
			(xy 83.956552 -348.820564) (xy 83.963891 -348.739773) (xy 83.978566 -348.659987) (xy 84.000454 -348.581872)
			(xy 84.029373 -348.506078) (xy 84.046822 -348.469458) (xy 84.05073 -348.460437) (xy 84.052174 -348.440849)
			(xy 84.049616 -348.431358) (xy 84.035467 -348.386455) (xy 84.015597 -348.294425) (xy 84.005567 -348.200811)
			(xy 84.004912 -348.153736) (xy 84.004912 -348.15272) (xy 84.005416 -348.110372) (xy 84.013467 -348.026058)
			(xy 84.029496 -347.942892) (xy 84.053357 -347.861625) (xy 84.084836 -347.782995) (xy 84.123647 -347.707714)
			(xy 84.169437 -347.636462) (xy 84.221793 -347.569886) (xy 84.280241 -347.508588) (xy 84.344251 -347.453123)
			(xy 84.413243 -347.403994) (xy 84.486593 -347.361645) (xy 84.563636 -347.326461) (xy 84.643675 -347.298759)
			(xy 84.725984 -347.278791) (xy 84.809819 -347.266738) (xy 84.89442 -347.262708) (xy 84.979021 -347.266738)
			(xy 85.062856 -347.278791) (xy 85.145165 -347.298759) (xy 85.225204 -347.326461) (xy 85.302247 -347.361645)
			(xy 85.375597 -347.403994) (xy 85.444589 -347.453123) (xy 85.508599 -347.508588) (xy 85.567047 -347.569886)
			(xy 85.619403 -347.636462) (xy 85.665193 -347.707714) (xy 85.704004 -347.782995) (xy 85.735483 -347.861625)
			(xy 85.759344 -347.942892) (xy 85.775373 -348.026058) (xy 85.783424 -348.110372) (xy 85.783928 -348.15272)
			(xy 85.783928 -348.153228) (xy 85.783471 -348.193738) (xy 85.77611 -348.274424) (xy 85.761432 -348.354104)
			(xy 85.73956 -348.432117) (xy 85.710675 -348.507814) (xy 85.69325 -348.544388) (xy 85.689318 -348.553401)
			(xy 85.687887 -348.572996) (xy 85.690456 -348.582488) (xy 85.70466 -348.627551) (xy 85.721282 -348.7047)
			(xy 275.231844 -348.7047) (xy 275.235834 -348.620942) (xy 275.247768 -348.537942) (xy 275.267537 -348.456452)
			(xy 275.294962 -348.377211) (xy 275.329796 -348.300935) (xy 275.371722 -348.228316) (xy 275.420361 -348.16001)
			(xy 275.475273 -348.096638) (xy 275.53596 -348.038772) (xy 275.601873 -347.986937) (xy 275.672414 -347.941602)
			(xy 275.746946 -347.903177) (xy 275.824792 -347.872011) (xy 275.905248 -347.848386) (xy 275.987586 -347.832515)
			(xy 276.071059 -347.824543) (xy 276.112986 -347.824044) (xy 276.114002 -347.824044) (xy 276.151059 -347.824452)
			(xy 276.224908 -347.830716) (xy 276.29797 -347.843157) (xy 276.36973 -347.861689) (xy 276.404832 -347.873574)
			(xy 276.413029 -347.876088) (xy 276.430163 -347.876088) (xy 276.43836 -347.873574) (xy 276.478966 -347.8599)
			(xy 276.562216 -347.839604) (xy 276.647042 -347.827484) (xy 276.68982 -347.82506) (xy 276.700434 -347.823969)
			(xy 276.719453 -347.814348) (xy 276.732947 -347.797851) (xy 276.736302 -347.787722) (xy 276.744404 -347.759433)
			(xy 276.763852 -347.703889) (xy 276.775164 -347.676724) (xy 276.778721 -347.667131) (xy 276.778725 -347.646691)
			(xy 276.775164 -347.6371) (xy 276.758127 -347.595694) (xy 276.731493 -347.510205) (xy 276.713589 -347.422472)
			(xy 276.704596 -347.333383) (xy 276.704044 -347.288612) (xy 276.704548 -347.246251) (xy 276.712601 -347.161914)
			(xy 276.728635 -347.078724) (xy 276.752503 -346.997434) (xy 276.783991 -346.918782) (xy 276.822813 -346.843479)
			(xy 276.868616 -346.772207) (xy 276.920987 -346.705611) (xy 276.979452 -346.644296) (xy 277.04348 -346.588815)
			(xy 277.112492 -346.539672) (xy 277.185862 -346.497312) (xy 277.262927 -346.462117) (xy 277.342989 -346.434408)
			(xy 277.425322 -346.414434) (xy 277.509181 -346.402377) (xy 277.593806 -346.398346) (xy 277.678431 -346.402377)
			(xy 277.76229 -346.414434) (xy 277.844623 -346.434408) (xy 277.924685 -346.462117) (xy 278.00175 -346.497312)
			(xy 278.07512 -346.539672) (xy 278.144132 -346.588815) (xy 278.20816 -346.644296) (xy 278.266625 -346.705611)
			(xy 278.318996 -346.772207) (xy 278.364799 -346.843479) (xy 278.403621 -346.918782) (xy 278.435109 -346.997434)
			(xy 278.458977 -347.078724) (xy 278.475011 -347.161914) (xy 278.483064 -347.246251) (xy 278.483568 -347.288612)
			(xy 278.482998 -347.333381) (xy 278.47399 -347.422466) (xy 278.456088 -347.510198) (xy 278.42947 -347.595689)
			(xy 278.412448 -347.6371) (xy 278.408812 -347.646665) (xy 278.408686 -347.667111) (xy 278.412194 -347.676724)
			(xy 278.426408 -347.711074) (xy 278.449728 -347.781668) (xy 278.467082 -347.85396) (xy 278.478348 -347.927447)
			(xy 278.481282 -347.964506) (xy 278.482267 -347.973327) (xy 278.489457 -347.989544) (xy 278.501708 -348.002373)
			(xy 278.509476 -348.00667) (xy 278.600662 -348.051628) (xy 278.62784 -348.049596) (xy 278.639016 -348.04223)
			(xy 278.675581 -348.018458) (xy 278.752524 -347.977387) (xy 278.833117 -347.944041) (xy 278.916586 -347.91874)
			(xy 279.00213 -347.901729) (xy 279.088929 -347.893169) (xy 279.132538 -347.892624) (xy 279.133046 -347.892624)
			(xy 279.174153 -347.893069) (xy 279.256016 -347.900657) (xy 279.336831 -347.915765) (xy 279.415907 -347.938263)
			(xy 279.49257 -347.96796) (xy 279.566167 -348.004602) (xy 279.63607 -348.047877) (xy 279.701683 -348.097416)
			(xy 279.762447 -348.152796) (xy 279.817842 -348.213546) (xy 279.867398 -348.279147) (xy 279.91069 -348.349039)
			(xy 279.947351 -348.422627) (xy 279.977067 -348.499283) (xy 279.999585 -348.578353) (xy 280.014712 -348.659164)
			(xy 280.018945 -348.7047) (xy 283.512244 -348.7047) (xy 283.516234 -348.620942) (xy 283.528168 -348.537942)
			(xy 283.547937 -348.456452) (xy 283.575362 -348.377211) (xy 283.610196 -348.300935) (xy 283.652122 -348.228316)
			(xy 283.700761 -348.16001) (xy 283.755673 -348.096638) (xy 283.81636 -348.038772) (xy 283.882273 -347.986937)
			(xy 283.952814 -347.941602) (xy 284.027346 -347.903177) (xy 284.105192 -347.872011) (xy 284.185648 -347.848386)
			(xy 284.267986 -347.832515) (xy 284.351459 -347.824543) (xy 284.393386 -347.824044) (xy 284.394402 -347.824044)
			(xy 284.431459 -347.824452) (xy 284.505308 -347.830716) (xy 284.57837 -347.843157) (xy 284.65013 -347.861689)
			(xy 284.685232 -347.873574) (xy 284.693429 -347.876088) (xy 284.710563 -347.876088) (xy 284.71876 -347.873574)
			(xy 284.756938 -347.860634) (xy 284.835124 -347.840982) (xy 284.91478 -347.828562) (xy 284.95498 -347.825568)
			(xy 284.965838 -347.82436) (xy 284.985096 -347.814096) (xy 284.99831 -347.79673) (xy 285.001208 -347.786198)
			(xy 285.010486 -347.747118) (xy 285.035162 -347.670674) (xy 285.050484 -347.633544) (xy 285.054028 -347.623948)
			(xy 285.05404 -347.603511) (xy 285.050484 -347.59392) (xy 285.033454 -347.552511) (xy 285.006819 -347.467023)
			(xy 284.988912 -347.379291) (xy 284.979917 -347.290203) (xy 284.979364 -347.245432) (xy 284.979868 -347.203071)
			(xy 284.987921 -347.118734) (xy 285.003955 -347.035544) (xy 285.027823 -346.954254) (xy 285.059311 -346.875602)
			(xy 285.098133 -346.800299) (xy 285.143936 -346.729027) (xy 285.196307 -346.662431) (xy 285.254772 -346.601116)
			(xy 285.3188 -346.545635) (xy 285.387812 -346.496492) (xy 285.461182 -346.454132) (xy 285.538247 -346.418937)
			(xy 285.618309 -346.391228) (xy 285.700642 -346.371254) (xy 285.784501 -346.359197) (xy 285.869126 -346.355166)
			(xy 285.953751 -346.359197) (xy 286.03761 -346.371254) (xy 286.119943 -346.391228) (xy 286.200005 -346.418937)
			(xy 286.27707 -346.454132) (xy 286.35044 -346.496492) (xy 286.419452 -346.545635) (xy 286.48348 -346.601116)
			(xy 286.541945 -346.662431) (xy 286.594316 -346.729027) (xy 286.640119 -346.800299) (xy 286.678941 -346.875602)
			(xy 286.710429 -346.954254) (xy 286.734297 -347.035544) (xy 286.750331 -347.118734) (xy 286.758384 -347.203071)
			(xy 286.758888 -347.245432) (xy 286.758323 -347.290202) (xy 286.749314 -347.379287) (xy 286.73141 -347.467018)
			(xy 286.704791 -347.552509) (xy 286.687768 -347.59392) (xy 286.684185 -347.603505) (xy 286.684197 -347.623953)
			(xy 286.687768 -347.633544) (xy 286.703871 -347.672618) (xy 286.72945 -347.753174) (xy 286.747275 -347.835792)
			(xy 286.757183 -347.919728) (xy 286.758634 -347.961966) (xy 286.758888 -347.975936) (xy 286.77362 -347.999558)
			(xy 286.86506 -348.047056) (xy 286.873276 -348.050887) (xy 286.891249 -348.053129) (xy 286.908879 -348.048973)
			(xy 286.916622 -348.044262) (xy 286.916876 -348.044008) (xy 286.95358 -348.019938) (xy 287.030887 -347.978361)
			(xy 287.111915 -347.944605) (xy 287.195876 -347.918998) (xy 287.281951 -347.901791) (xy 287.369303 -347.893149)
			(xy 287.413192 -347.892624) (xy 287.413446 -347.892624) (xy 287.454553 -347.893069) (xy 287.536416 -347.900657)
			(xy 287.617231 -347.915765) (xy 287.696307 -347.938263) (xy 287.77297 -347.96796) (xy 287.846567 -348.004602)
			(xy 287.91647 -348.047877) (xy 287.982083 -348.097416) (xy 288.042847 -348.152796) (xy 288.098242 -348.213546)
			(xy 288.147798 -348.279147) (xy 288.19109 -348.349039) (xy 288.227751 -348.422627) (xy 288.257467 -348.499283)
			(xy 288.279985 -348.578353) (xy 288.295112 -348.659164) (xy 288.299345 -348.7047) (xy 291.818044 -348.7047)
			(xy 291.822034 -348.620942) (xy 291.833968 -348.537942) (xy 291.853737 -348.456452) (xy 291.881162 -348.377211)
			(xy 291.915996 -348.300935) (xy 291.957922 -348.228316) (xy 292.006561 -348.16001) (xy 292.061473 -348.096638)
			(xy 292.12216 -348.038772) (xy 292.188073 -347.986937) (xy 292.258614 -347.941602) (xy 292.333146 -347.903177)
			(xy 292.410992 -347.872011) (xy 292.491448 -347.848386) (xy 292.573786 -347.832515) (xy 292.657259 -347.824543)
			(xy 292.699186 -347.824044) (xy 292.700202 -347.824044) (xy 292.737259 -347.824452) (xy 292.811108 -347.830716)
			(xy 292.88417 -347.843157) (xy 292.95593 -347.861689) (xy 292.991032 -347.873574) (xy 292.999229 -347.876088)
			(xy 293.016363 -347.876088) (xy 293.02456 -347.873574) (xy 293.057737 -347.862322) (xy 293.125493 -347.844496)
			(xy 293.194454 -347.832123) (xy 293.229284 -347.828362) (xy 293.240044 -347.82673) (xy 293.258819 -347.815766)
			(xy 293.271409 -347.798041) (xy 293.273988 -347.787468) (xy 293.28351 -347.742121) (xy 293.310744 -347.653548)
			(xy 293.328344 -347.610684) (xy 293.331924 -347.601098) (xy 293.331914 -347.580651) (xy 293.328344 -347.57106)
			(xy 293.311293 -347.529659) (xy 293.284663 -347.444168) (xy 293.266763 -347.356433) (xy 293.257774 -347.267343)
			(xy 293.257224 -347.222572) (xy 293.257728 -347.180211) (xy 293.265781 -347.095874) (xy 293.281815 -347.012684)
			(xy 293.305683 -346.931394) (xy 293.337171 -346.852742) (xy 293.375993 -346.777439) (xy 293.421796 -346.706167)
			(xy 293.474167 -346.639571) (xy 293.532632 -346.578256) (xy 293.59666 -346.522775) (xy 293.665672 -346.473632)
			(xy 293.739042 -346.431272) (xy 293.816107 -346.396077) (xy 293.896169 -346.368368) (xy 293.978502 -346.348394)
			(xy 294.062361 -346.336337) (xy 294.146986 -346.332306) (xy 294.231611 -346.336337) (xy 294.31547 -346.348394)
			(xy 294.397803 -346.368368) (xy 294.477865 -346.396077) (xy 294.55493 -346.431272) (xy 294.6283 -346.473632)
			(xy 294.697312 -346.522775) (xy 294.76134 -346.578256) (xy 294.819805 -346.639571) (xy 294.872176 -346.706167)
			(xy 294.917979 -346.777439) (xy 294.956801 -346.852742) (xy 294.988289 -346.931394) (xy 295.012157 -347.012684)
			(xy 295.028191 -347.095874) (xy 295.036244 -347.180211) (xy 295.036748 -347.222572) (xy 295.036192 -347.267342)
			(xy 295.027179 -347.356427) (xy 295.009272 -347.444158) (xy 294.982652 -347.529649) (xy 294.965628 -347.57106)
			(xy 294.962081 -347.580656) (xy 294.96207 -347.601093) (xy 294.965628 -347.610684) (xy 294.982659 -347.652092)
			(xy 295.009295 -347.73758) (xy 295.0272 -347.825313) (xy 295.036195 -347.914401) (xy 295.036748 -347.959172)
			(xy 295.036494 -347.977206) (xy 295.03624 -347.991684) (xy 295.050718 -348.016576) (xy 295.157144 -348.071948)
			(xy 295.185846 -348.069916) (xy 295.19753 -348.061534) (xy 295.230035 -348.038582) (xy 295.298406 -347.997866)
			(xy 295.370142 -347.963421) (xy 295.444669 -347.935524) (xy 295.521391 -347.914398) (xy 295.599693 -347.900211)
			(xy 295.67895 -347.893078) (xy 295.718738 -347.892624) (xy 295.719246 -347.892624) (xy 295.760353 -347.893069)
			(xy 295.842216 -347.900657) (xy 295.923031 -347.915765) (xy 296.002107 -347.938263) (xy 296.07877 -347.96796)
			(xy 296.152367 -348.004602) (xy 296.22227 -348.047877) (xy 296.287883 -348.097416) (xy 296.348647 -348.152796)
			(xy 296.404042 -348.213546) (xy 296.453598 -348.279147) (xy 296.49689 -348.349039) (xy 296.533551 -348.422627)
			(xy 296.563267 -348.499283) (xy 296.585785 -348.578353) (xy 296.600912 -348.659164) (xy 296.605145 -348.7047)
			(xy 300.174644 -348.7047) (xy 300.178634 -348.620942) (xy 300.190568 -348.537942) (xy 300.210337 -348.456452)
			(xy 300.237762 -348.377211) (xy 300.272596 -348.300935) (xy 300.314522 -348.228316) (xy 300.363161 -348.16001)
			(xy 300.418073 -348.096638) (xy 300.47876 -348.038772) (xy 300.544673 -347.986937) (xy 300.615214 -347.941602)
			(xy 300.689746 -347.903177) (xy 300.767592 -347.872011) (xy 300.848048 -347.848386) (xy 300.930386 -347.832515)
			(xy 301.013859 -347.824543) (xy 301.055786 -347.824044) (xy 301.056802 -347.824044) (xy 301.093859 -347.824452)
			(xy 301.167708 -347.830716) (xy 301.24077 -347.843157) (xy 301.31253 -347.861689) (xy 301.347632 -347.873574)
			(xy 301.355829 -347.876088) (xy 301.372963 -347.876088) (xy 301.38116 -347.873574) (xy 301.419296 -347.860641)
			(xy 301.497398 -347.840993) (xy 301.576968 -347.828568) (xy 301.617126 -347.825568) (xy 301.627844 -347.824451)
			(xy 301.646914 -347.814446) (xy 301.660249 -347.797535) (xy 301.663354 -347.787214) (xy 301.672203 -347.75314)
			(xy 301.694583 -347.686387) (xy 301.708058 -347.653864) (xy 301.711569 -347.644255) (xy 301.711421 -347.623811)
			(xy 301.707804 -347.61424) (xy 301.690776 -347.57283) (xy 301.66414 -347.487343) (xy 301.646234 -347.39961)
			(xy 301.637237 -347.310523) (xy 301.636684 -347.265752) (xy 301.637188 -347.223391) (xy 301.645241 -347.139054)
			(xy 301.661275 -347.055864) (xy 301.685143 -346.974574) (xy 301.716631 -346.895922) (xy 301.755453 -346.820619)
			(xy 301.801256 -346.749347) (xy 301.853627 -346.682751) (xy 301.912092 -346.621436) (xy 301.97612 -346.565955)
			(xy 302.045132 -346.516812) (xy 302.118502 -346.474452) (xy 302.195567 -346.439257) (xy 302.275629 -346.411548)
			(xy 302.357962 -346.391574) (xy 302.441821 -346.379517) (xy 302.526446 -346.375486) (xy 302.611071 -346.379517)
			(xy 302.69493 -346.391574) (xy 302.777263 -346.411548) (xy 302.857325 -346.439257) (xy 302.93439 -346.474452)
			(xy 303.00776 -346.516812) (xy 303.076772 -346.565955) (xy 303.1408 -346.621436) (xy 303.199265 -346.682751)
			(xy 303.251636 -346.749347) (xy 303.297439 -346.820619) (xy 303.336261 -346.895922) (xy 303.367749 -346.974574)
			(xy 303.391617 -347.055864) (xy 303.407651 -347.139054) (xy 303.415704 -347.223391) (xy 303.416208 -347.265752)
			(xy 303.415649 -347.310522) (xy 303.406637 -347.399607) (xy 303.388731 -347.487338) (xy 303.362111 -347.572829)
			(xy 303.345088 -347.61424) (xy 303.341549 -347.623838) (xy 303.341532 -347.644274) (xy 303.345088 -347.653864)
			(xy 303.36051 -347.691224) (xy 303.385289 -347.768163) (xy 303.402976 -347.847034) (xy 303.413426 -347.927187)
			(xy 303.415446 -347.967554) (xy 303.415954 -347.981524) (xy 303.430686 -348.004638) (xy 303.535334 -348.057216)
			(xy 303.562766 -348.055184) (xy 303.574196 -348.04731) (xy 303.611146 -348.022772) (xy 303.689046 -347.980345)
			(xy 303.770779 -347.945874) (xy 303.855535 -347.919702) (xy 303.942473 -347.902087) (xy 304.030732 -347.893205)
			(xy 304.075084 -347.892624) (xy 304.075846 -347.892624) (xy 304.116953 -347.893069) (xy 304.198816 -347.900657)
			(xy 304.279631 -347.915765) (xy 304.358707 -347.938263) (xy 304.43537 -347.96796) (xy 304.508967 -348.004602)
			(xy 304.57887 -348.047877) (xy 304.644483 -348.097416) (xy 304.705247 -348.152796) (xy 304.760642 -348.213546)
			(xy 304.810198 -348.279147) (xy 304.85349 -348.349039) (xy 304.890151 -348.422627) (xy 304.919867 -348.499283)
			(xy 304.942385 -348.578353) (xy 304.957512 -348.659164) (xy 304.961745 -348.7047) (xy 308.505844 -348.7047)
			(xy 308.509834 -348.620942) (xy 308.521768 -348.537942) (xy 308.541537 -348.456452) (xy 308.568962 -348.377211)
			(xy 308.603796 -348.300935) (xy 308.645722 -348.228316) (xy 308.694361 -348.16001) (xy 308.749273 -348.096638)
			(xy 308.80996 -348.038772) (xy 308.875873 -347.986937) (xy 308.946414 -347.941602) (xy 309.020946 -347.903177)
			(xy 309.098792 -347.872011) (xy 309.179248 -347.848386) (xy 309.261586 -347.832515) (xy 309.345059 -347.824543)
			(xy 309.386986 -347.824044) (xy 309.388002 -347.824044) (xy 309.425059 -347.824452) (xy 309.498908 -347.830716)
			(xy 309.57197 -347.843157) (xy 309.64373 -347.861689) (xy 309.678832 -347.873574) (xy 309.687029 -347.876088)
			(xy 309.704163 -347.876088) (xy 309.71236 -347.873574) (xy 309.752087 -347.860214) (xy 309.833476 -347.84017)
			(xy 309.916402 -347.827952) (xy 309.958232 -347.825314) (xy 309.969008 -347.824123) (xy 309.988202 -347.814097)
			(xy 310.001607 -347.79709) (xy 310.004714 -347.786706) (xy 310.013576 -347.75276) (xy 310.035956 -347.686262)
			(xy 310.049418 -347.653864) (xy 310.052931 -347.644255) (xy 310.052783 -347.623811) (xy 310.049164 -347.61424)
			(xy 310.03214 -347.572829) (xy 310.005503 -347.487342) (xy 309.987595 -347.39961) (xy 309.978598 -347.310522)
			(xy 309.978044 -347.265752) (xy 309.978548 -347.223391) (xy 309.986601 -347.139054) (xy 310.002635 -347.055864)
			(xy 310.026503 -346.974574) (xy 310.057991 -346.895922) (xy 310.096813 -346.820619) (xy 310.142616 -346.749347)
			(xy 310.194987 -346.682751) (xy 310.253452 -346.621436) (xy 310.31748 -346.565955) (xy 310.386492 -346.516812)
			(xy 310.459862 -346.474452) (xy 310.536927 -346.439257) (xy 310.616989 -346.411548) (xy 310.699322 -346.391574)
			(xy 310.783181 -346.379517) (xy 310.867806 -346.375486) (xy 310.952431 -346.379517) (xy 311.03629 -346.391574)
			(xy 311.118623 -346.411548) (xy 311.198685 -346.439257) (xy 311.27575 -346.474452) (xy 311.34912 -346.516812)
			(xy 311.418132 -346.565955) (xy 311.48216 -346.621436) (xy 311.540625 -346.682751) (xy 311.592996 -346.749347)
			(xy 311.638799 -346.820619) (xy 311.677621 -346.895922) (xy 311.709109 -346.974574) (xy 311.732977 -347.055864)
			(xy 311.749011 -347.139054) (xy 311.757064 -347.223391) (xy 311.757568 -347.265752) (xy 311.757012 -347.310522)
			(xy 311.748 -347.399607) (xy 311.730093 -347.487338) (xy 311.703472 -347.572829) (xy 311.686448 -347.61424)
			(xy 311.682911 -347.623839) (xy 311.682894 -347.644274) (xy 311.686448 -347.653864) (xy 311.701578 -347.690518)
			(xy 311.725997 -347.765967) (xy 311.743615 -347.843288) (xy 311.754293 -347.921869) (xy 311.756552 -347.961458)
			(xy 311.757251 -347.970429) (xy 311.764179 -347.987026) (xy 311.776392 -348.000229) (xy 311.784238 -348.004638)
			(xy 311.875678 -348.050866) (xy 311.902856 -348.049088) (xy 311.914286 -348.041468) (xy 311.950798 -348.017804)
			(xy 312.027605 -347.976914) (xy 312.10804 -347.943725) (xy 312.191333 -347.918554) (xy 312.276687 -347.901641)
			(xy 312.363285 -347.893148) (xy 312.406792 -347.892624) (xy 312.407046 -347.892624) (xy 312.448153 -347.893069)
			(xy 312.530016 -347.900657) (xy 312.610831 -347.915765) (xy 312.689907 -347.938263) (xy 312.76657 -347.96796)
			(xy 312.840167 -348.004602) (xy 312.91007 -348.047877) (xy 312.975683 -348.097416) (xy 313.036447 -348.152796)
			(xy 313.091842 -348.213546) (xy 313.141398 -348.279147) (xy 313.18469 -348.349039) (xy 313.221351 -348.422627)
			(xy 313.251067 -348.499283) (xy 313.273585 -348.578353) (xy 313.288712 -348.659164) (xy 313.296321 -348.741025)
			(xy 313.296808 -348.782132) (xy 313.296242 -348.826902) (xy 313.287233 -348.915987) (xy 313.269329 -349.003718)
			(xy 313.242711 -349.089209) (xy 313.225688 -349.13062) (xy 313.222104 -349.140205) (xy 313.222115 -349.160653)
			(xy 313.225688 -349.170244) (xy 313.242711 -349.211656) (xy 313.269347 -349.297143) (xy 313.287256 -349.384874)
			(xy 313.291976 -349.43161) (xy 326.552821 -349.43161) (xy 326.556826 -349.325861) (xy 326.568816 -349.220718)
			(xy 326.588725 -349.116783) (xy 326.616436 -349.014651) (xy 326.651793 -348.914907) (xy 326.694591 -348.818123)
			(xy 326.744587 -348.724853) (xy 326.801494 -348.635632) (xy 326.864985 -348.550969) (xy 326.934697 -348.471351)
			(xy 327.010231 -348.397233) (xy 327.091154 -348.32904) (xy 327.177003 -348.267162) (xy 327.267286 -348.211955)
			(xy 327.361485 -348.163733) (xy 327.459062 -348.122773) (xy 327.559457 -348.089311) (xy 327.662095 -348.063537)
			(xy 327.766388 -348.045599) (xy 327.871739 -348.0356) (xy 327.977545 -348.033597) (xy 328.083199 -348.039602)
			(xy 328.188096 -348.053581) (xy 328.291636 -348.075452) (xy 328.393225 -348.105092) (xy 328.492282 -348.14233)
			(xy 328.588239 -348.186952) (xy 328.680546 -348.238704) (xy 328.768675 -348.297289) (xy 328.852121 -348.362371)
			(xy 328.930405 -348.433577) (xy 329.00308 -348.5105) (xy 329.06973 -348.5927) (xy 329.129972 -348.679704)
			(xy 329.183461 -348.771015) (xy 329.229892 -348.86611) (xy 329.268997 -348.964444) (xy 329.300554 -349.065455)
			(xy 329.324381 -349.168562) (xy 329.340342 -349.273176) (xy 329.348346 -349.378698) (xy 329.348846 -349.43161)
			(xy 334.012801 -349.43161) (xy 334.016806 -349.325861) (xy 334.028796 -349.220718) (xy 334.048705 -349.116783)
			(xy 334.076416 -349.014651) (xy 334.111773 -348.914907) (xy 334.154571 -348.818123) (xy 334.204567 -348.724853)
			(xy 334.261474 -348.635632) (xy 334.324965 -348.550969) (xy 334.394677 -348.471351) (xy 334.470211 -348.397233)
			(xy 334.551134 -348.32904) (xy 334.636983 -348.267162) (xy 334.727266 -348.211955) (xy 334.821465 -348.163733)
			(xy 334.919042 -348.122773) (xy 335.019437 -348.089311) (xy 335.122075 -348.063537) (xy 335.226368 -348.045599)
			(xy 335.331719 -348.0356) (xy 335.437525 -348.033597) (xy 335.543179 -348.039602) (xy 335.648076 -348.053581)
			(xy 335.751616 -348.075452) (xy 335.853205 -348.105092) (xy 335.952262 -348.14233) (xy 336.048219 -348.186952)
			(xy 336.140526 -348.238704) (xy 336.228655 -348.297289) (xy 336.312101 -348.362371) (xy 336.390385 -348.433577)
			(xy 336.46306 -348.5105) (xy 336.52971 -348.5927) (xy 336.589952 -348.679704) (xy 336.643441 -348.771015)
			(xy 336.689872 -348.86611) (xy 336.728977 -348.964444) (xy 336.760534 -349.065455) (xy 336.784361 -349.168562)
			(xy 336.800322 -349.273176) (xy 336.808326 -349.378698) (xy 336.808826 -349.43161) (xy 336.808326 -349.484522)
			(xy 336.800322 -349.590044) (xy 336.784361 -349.694658) (xy 336.760534 -349.797765) (xy 336.728977 -349.898776)
			(xy 336.689872 -349.99711) (xy 336.643441 -350.092205) (xy 336.589952 -350.183516) (xy 336.52971 -350.27052)
			(xy 336.46306 -350.35272) (xy 336.390385 -350.429643) (xy 336.312101 -350.500849) (xy 336.228655 -350.565931)
			(xy 336.140526 -350.624516) (xy 336.048219 -350.676268) (xy 335.952262 -350.72089) (xy 335.853205 -350.758128)
			(xy 335.751616 -350.787768) (xy 335.648076 -350.809639) (xy 335.543179 -350.823618) (xy 335.437525 -350.829623)
			(xy 335.331719 -350.82762) (xy 335.226368 -350.817621) (xy 335.122075 -350.799683) (xy 335.019437 -350.773909)
			(xy 334.919042 -350.740447) (xy 334.821465 -350.699487) (xy 334.727266 -350.651265) (xy 334.636983 -350.596058)
			(xy 334.551134 -350.53418) (xy 334.470211 -350.465987) (xy 334.394677 -350.391869) (xy 334.324965 -350.312251)
			(xy 334.261474 -350.227588) (xy 334.204567 -350.138367) (xy 334.154571 -350.045097) (xy 334.111773 -349.948313)
			(xy 334.076416 -349.848569) (xy 334.048705 -349.746437) (xy 334.028796 -349.642502) (xy 334.016806 -349.537359)
			(xy 334.012801 -349.43161) (xy 329.348846 -349.43161) (xy 329.348346 -349.484522) (xy 329.340342 -349.590044)
			(xy 329.324381 -349.694658) (xy 329.300554 -349.797765) (xy 329.268997 -349.898776) (xy 329.229892 -349.99711)
			(xy 329.183461 -350.092205) (xy 329.129972 -350.183516) (xy 329.06973 -350.27052) (xy 329.00308 -350.35272)
			(xy 328.930405 -350.429643) (xy 328.852121 -350.500849) (xy 328.768675 -350.565931) (xy 328.680546 -350.624516)
			(xy 328.588239 -350.676268) (xy 328.492282 -350.72089) (xy 328.393225 -350.758128) (xy 328.291636 -350.787768)
			(xy 328.188096 -350.809639) (xy 328.083199 -350.823618) (xy 327.977545 -350.829623) (xy 327.871739 -350.82762)
			(xy 327.766388 -350.817621) (xy 327.662095 -350.799683) (xy 327.559457 -350.773909) (xy 327.459062 -350.740447)
			(xy 327.361485 -350.699487) (xy 327.267286 -350.651265) (xy 327.177003 -350.596058) (xy 327.091154 -350.53418)
			(xy 327.010231 -350.465987) (xy 326.934697 -350.391869) (xy 326.864985 -350.312251) (xy 326.801494 -350.227588)
			(xy 326.744587 -350.138367) (xy 326.694591 -350.045097) (xy 326.651793 -349.948313) (xy 326.616436 -349.848569)
			(xy 326.588725 -349.746437) (xy 326.568816 -349.642502) (xy 326.556826 -349.537359) (xy 326.552821 -349.43161)
			(xy 313.291976 -349.43161) (xy 313.296254 -349.473962) (xy 313.296808 -349.518732) (xy 313.296242 -349.563502)
			(xy 313.287233 -349.652587) (xy 313.269329 -349.740318) (xy 313.242711 -349.825809) (xy 313.225688 -349.86722)
			(xy 313.222104 -349.876805) (xy 313.222115 -349.897253) (xy 313.225688 -349.906844) (xy 313.242711 -349.948256)
			(xy 313.269347 -350.033743) (xy 313.287256 -350.121474) (xy 313.296254 -350.210562) (xy 313.296808 -350.255332)
			(xy 313.296378 -350.296443) (xy 313.288787 -350.378314) (xy 313.273674 -350.459136) (xy 313.251166 -350.538217)
			(xy 313.221457 -350.614885) (xy 313.184799 -350.688483) (xy 313.141506 -350.758385) (xy 313.091947 -350.823993)
			(xy 313.036545 -350.884747) (xy 312.975772 -350.94013) (xy 312.910148 -350.989668) (xy 312.840233 -351.032938)
			(xy 312.766623 -351.069572) (xy 312.689946 -351.099257) (xy 312.610857 -351.121739) (xy 312.530031 -351.136827)
			(xy 312.448157 -351.144391) (xy 312.407046 -351.14484) (xy 312.365442 -351.14437) (xy 312.282594 -351.136637)
			(xy 312.200829 -351.121206) (xy 312.120862 -351.098211) (xy 312.043389 -351.067854) (xy 311.969088 -351.0304)
			(xy 311.93359 -351.008696) (xy 311.924458 -351.003521) (xy 311.903738 -351.00031) (xy 311.883461 -351.005649)
			(xy 311.874916 -351.011744) (xy 311.841266 -351.037664) (xy 311.769892 -351.083723) (xy 311.694453 -351.12277)
			(xy 311.615637 -351.15445) (xy 311.53416 -351.178473) (xy 311.450764 -351.194623) (xy 311.366208 -351.20275)
			(xy 311.323736 -351.20326) (xy 311.323482 -351.20326) (xy 311.282375 -351.202805) (xy 311.200511 -351.195219)
			(xy 311.119697 -351.180113) (xy 311.04062 -351.157617) (xy 310.963956 -351.127921) (xy 310.890359 -351.09128)
			(xy 310.820455 -351.048006) (xy 310.754841 -350.998468) (xy 310.694077 -350.943088) (xy 310.638682 -350.882339)
			(xy 310.589126 -350.816738) (xy 310.545833 -350.746846) (xy 310.509173 -350.673258) (xy 310.479458 -350.596602)
			(xy 310.456941 -350.517531) (xy 310.441814 -350.43672) (xy 310.434206 -350.354859) (xy 310.43372 -350.313752)
			(xy 310.434279 -350.268982) (xy 310.44329 -350.179897) (xy 310.461196 -350.092166) (xy 310.487816 -350.006675)
			(xy 310.50484 -349.965264) (xy 310.508432 -349.955681) (xy 310.508415 -349.935231) (xy 310.50484 -349.92564)
			(xy 310.487836 -349.884289) (xy 310.461225 -349.798927) (xy 310.443318 -349.711324) (xy 310.434296 -349.622367)
			(xy 310.43372 -349.57766) (xy 310.43372 -349.576644) (xy 310.433974 -349.565214) (xy 310.407495 -349.559269)
			(xy 310.35526 -349.544526) (xy 310.32958 -349.53575) (xy 310.321383 -349.533236) (xy 310.304249 -349.533236)
			(xy 310.296052 -349.53575) (xy 310.260836 -349.547697) (xy 310.188826 -349.566284) (xy 310.115503 -349.578724)
			(xy 310.041392 -349.584928) (xy 310.004206 -349.58528) (xy 309.967022 -349.584911) (xy 309.892914 -349.578689)
			(xy 309.819594 -349.566246) (xy 309.747583 -349.547672) (xy 309.71236 -349.53575) (xy 309.704163 -349.533236)
			(xy 309.687029 -349.533236) (xy 309.678832 -349.53575) (xy 309.64373 -349.547637) (xy 309.571974 -349.566187)
			(xy 309.498911 -349.578634) (xy 309.42506 -349.584887) (xy 309.388002 -349.58528) (xy 309.386986 -349.58528)
			(xy 309.345059 -349.584857) (xy 309.261586 -349.576885) (xy 309.179248 -349.561014) (xy 309.098792 -349.537389)
			(xy 309.020946 -349.506223) (xy 308.946414 -349.467798) (xy 308.875873 -349.422463) (xy 308.80996 -349.370628)
			(xy 308.749273 -349.312762) (xy 308.694361 -349.24939) (xy 308.645722 -349.181084) (xy 308.603796 -349.108465)
			(xy 308.568962 -349.032189) (xy 308.541537 -348.952948) (xy 308.521768 -348.871458) (xy 308.509834 -348.788458)
			(xy 308.505844 -348.7047) (xy 304.961745 -348.7047) (xy 304.965121 -348.741025) (xy 304.965608 -348.782132)
			(xy 304.965042 -348.826902) (xy 304.956033 -348.915987) (xy 304.938129 -349.003718) (xy 304.911511 -349.089209)
			(xy 304.894488 -349.13062) (xy 304.890904 -349.140205) (xy 304.890915 -349.160653) (xy 304.894488 -349.170244)
			(xy 304.911511 -349.211656) (xy 304.938147 -349.297143) (xy 304.956056 -349.384874) (xy 304.965054 -349.473962)
			(xy 304.965608 -349.518732) (xy 304.965042 -349.563502) (xy 304.956033 -349.652587) (xy 304.938129 -349.740318)
			(xy 304.911511 -349.825809) (xy 304.894488 -349.86722) (xy 304.890904 -349.876805) (xy 304.890915 -349.897253)
			(xy 304.894488 -349.906844) (xy 304.911511 -349.948256) (xy 304.938147 -350.033743) (xy 304.956056 -350.121474)
			(xy 304.965054 -350.210562) (xy 304.965608 -350.255332) (xy 304.965178 -350.296443) (xy 304.957587 -350.378314)
			(xy 304.942474 -350.459136) (xy 304.919966 -350.538217) (xy 304.890257 -350.614885) (xy 304.853599 -350.688483)
			(xy 304.810306 -350.758385) (xy 304.760747 -350.823993) (xy 304.705345 -350.884747) (xy 304.644572 -350.94013)
			(xy 304.578948 -350.989668) (xy 304.509033 -351.032938) (xy 304.435423 -351.069572) (xy 304.358746 -351.099257)
			(xy 304.279657 -351.121739) (xy 304.198831 -351.136827) (xy 304.116957 -351.144391) (xy 304.075846 -351.14484)
			(xy 304.034242 -351.14437) (xy 303.951394 -351.136637) (xy 303.869629 -351.121206) (xy 303.789662 -351.098211)
			(xy 303.712189 -351.067854) (xy 303.637888 -351.0304) (xy 303.60239 -351.008696) (xy 303.593258 -351.003521)
			(xy 303.572538 -351.00031) (xy 303.552261 -351.005649) (xy 303.543716 -351.011744) (xy 303.510066 -351.037664)
			(xy 303.438692 -351.083723) (xy 303.363253 -351.12277) (xy 303.284437 -351.15445) (xy 303.20296 -351.178473)
			(xy 303.119564 -351.194623) (xy 303.035008 -351.20275) (xy 302.992536 -351.20326) (xy 302.992282 -351.20326)
			(xy 302.951175 -351.202805) (xy 302.869311 -351.195219) (xy 302.788497 -351.180113) (xy 302.70942 -351.157617)
			(xy 302.632756 -351.127921) (xy 302.559159 -351.09128) (xy 302.489255 -351.048006) (xy 302.423641 -350.998468)
			(xy 302.362877 -350.943088) (xy 302.307482 -350.882339) (xy 302.257926 -350.816738) (xy 302.214633 -350.746846)
			(xy 302.177973 -350.673258) (xy 302.148258 -350.596602) (xy 302.125741 -350.517531) (xy 302.110614 -350.43672)
			(xy 302.103006 -350.354859) (xy 302.10252 -350.313752) (xy 302.103079 -350.268982) (xy 302.11209 -350.179897)
			(xy 302.129996 -350.092166) (xy 302.156616 -350.006675) (xy 302.17364 -349.965264) (xy 302.177232 -349.955681)
			(xy 302.177215 -349.935231) (xy 302.17364 -349.92564) (xy 302.156636 -349.884289) (xy 302.130025 -349.798927)
			(xy 302.112118 -349.711324) (xy 302.103096 -349.622367) (xy 302.10252 -349.57766) (xy 302.10252 -349.576644)
			(xy 302.102774 -349.565214) (xy 302.076295 -349.559269) (xy 302.02406 -349.544526) (xy 301.99838 -349.53575)
			(xy 301.990183 -349.533236) (xy 301.973049 -349.533236) (xy 301.964852 -349.53575) (xy 301.929636 -349.547697)
			(xy 301.857626 -349.566284) (xy 301.784303 -349.578724) (xy 301.710192 -349.584928) (xy 301.673006 -349.58528)
			(xy 301.635822 -349.584911) (xy 301.561714 -349.578689) (xy 301.488394 -349.566246) (xy 301.416383 -349.547672)
			(xy 301.38116 -349.53575) (xy 301.372963 -349.533236) (xy 301.355829 -349.533236) (xy 301.347632 -349.53575)
			(xy 301.31253 -349.547637) (xy 301.240774 -349.566187) (xy 301.167711 -349.578634) (xy 301.09386 -349.584887)
			(xy 301.056802 -349.58528) (xy 301.055786 -349.58528) (xy 301.013859 -349.584857) (xy 300.930386 -349.576885)
			(xy 300.848048 -349.561014) (xy 300.767592 -349.537389) (xy 300.689746 -349.506223) (xy 300.615214 -349.467798)
			(xy 300.544673 -349.422463) (xy 300.47876 -349.370628) (xy 300.418073 -349.312762) (xy 300.363161 -349.24939)
			(xy 300.314522 -349.181084) (xy 300.272596 -349.108465) (xy 300.237762 -349.032189) (xy 300.210337 -348.952948)
			(xy 300.190568 -348.871458) (xy 300.178634 -348.788458) (xy 300.174644 -348.7047) (xy 296.605145 -348.7047)
			(xy 296.608521 -348.741025) (xy 296.609008 -348.782132) (xy 296.608442 -348.826902) (xy 296.599433 -348.915987)
			(xy 296.581529 -349.003718) (xy 296.554911 -349.089209) (xy 296.537888 -349.13062) (xy 296.534304 -349.140205)
			(xy 296.534315 -349.160653) (xy 296.537888 -349.170244) (xy 296.554911 -349.211656) (xy 296.581547 -349.297143)
			(xy 296.599456 -349.384874) (xy 296.608454 -349.473962) (xy 296.609008 -349.518732) (xy 296.608442 -349.563502)
			(xy 296.599433 -349.652587) (xy 296.581529 -349.740318) (xy 296.554911 -349.825809) (xy 296.537888 -349.86722)
			(xy 296.534304 -349.876805) (xy 296.534315 -349.897253) (xy 296.537888 -349.906844) (xy 296.554911 -349.948256)
			(xy 296.581547 -350.033743) (xy 296.599456 -350.121474) (xy 296.608454 -350.210562) (xy 296.609008 -350.255332)
			(xy 296.608578 -350.296443) (xy 296.600987 -350.378314) (xy 296.585874 -350.459136) (xy 296.563366 -350.538217)
			(xy 296.533657 -350.614885) (xy 296.496999 -350.688483) (xy 296.453706 -350.758385) (xy 296.404147 -350.823993)
			(xy 296.348745 -350.884747) (xy 296.287972 -350.94013) (xy 296.222348 -350.989668) (xy 296.152433 -351.032938)
			(xy 296.078823 -351.069572) (xy 296.002146 -351.099257) (xy 295.923057 -351.121739) (xy 295.842231 -351.136827)
			(xy 295.760357 -351.144391) (xy 295.719246 -351.14484) (xy 295.677642 -351.14437) (xy 295.594794 -351.136637)
			(xy 295.513029 -351.121206) (xy 295.433062 -351.098211) (xy 295.355589 -351.067854) (xy 295.281288 -351.0304)
			(xy 295.24579 -351.008696) (xy 295.236658 -351.003521) (xy 295.215938 -351.00031) (xy 295.195661 -351.005649)
			(xy 295.187116 -351.011744) (xy 295.153466 -351.037664) (xy 295.082092 -351.083723) (xy 295.006653 -351.12277)
			(xy 294.927837 -351.15445) (xy 294.84636 -351.178473) (xy 294.762964 -351.194623) (xy 294.678408 -351.20275)
			(xy 294.635936 -351.20326) (xy 294.635682 -351.20326) (xy 294.594575 -351.202805) (xy 294.512711 -351.195219)
			(xy 294.431897 -351.180113) (xy 294.35282 -351.157617) (xy 294.276156 -351.127921) (xy 294.202559 -351.09128)
			(xy 294.132655 -351.048006) (xy 294.067041 -350.998468) (xy 294.006277 -350.943088) (xy 293.950882 -350.882339)
			(xy 293.901326 -350.816738) (xy 293.858033 -350.746846) (xy 293.821373 -350.673258) (xy 293.791658 -350.596602)
			(xy 293.769141 -350.517531) (xy 293.754014 -350.43672) (xy 293.746406 -350.354859) (xy 293.74592 -350.313752)
			(xy 293.746479 -350.268982) (xy 293.75549 -350.179897) (xy 293.773396 -350.092166) (xy 293.800016 -350.006675)
			(xy 293.81704 -349.965264) (xy 293.820632 -349.955681) (xy 293.820615 -349.935231) (xy 293.81704 -349.92564)
			(xy 293.800036 -349.884289) (xy 293.773425 -349.798927) (xy 293.755518 -349.711324) (xy 293.746496 -349.622367)
			(xy 293.74592 -349.57766) (xy 293.74592 -349.576644) (xy 293.746174 -349.565214) (xy 293.719695 -349.559269)
			(xy 293.66746 -349.544526) (xy 293.64178 -349.53575) (xy 293.633583 -349.533236) (xy 293.616449 -349.533236)
			(xy 293.608252 -349.53575) (xy 293.573036 -349.547697) (xy 293.501026 -349.566284) (xy 293.427703 -349.578724)
			(xy 293.353592 -349.584928) (xy 293.316406 -349.58528) (xy 293.279222 -349.584911) (xy 293.205114 -349.578689)
			(xy 293.131794 -349.566246) (xy 293.059783 -349.547672) (xy 293.02456 -349.53575) (xy 293.016363 -349.533236)
			(xy 292.999229 -349.533236) (xy 292.991032 -349.53575) (xy 292.95593 -349.547637) (xy 292.884174 -349.566187)
			(xy 292.811111 -349.578634) (xy 292.73726 -349.584887) (xy 292.700202 -349.58528) (xy 292.699186 -349.58528)
			(xy 292.657259 -349.584857) (xy 292.573786 -349.576885) (xy 292.491448 -349.561014) (xy 292.410992 -349.537389)
			(xy 292.333146 -349.506223) (xy 292.258614 -349.467798) (xy 292.188073 -349.422463) (xy 292.12216 -349.370628)
			(xy 292.061473 -349.312762) (xy 292.006561 -349.24939) (xy 291.957922 -349.181084) (xy 291.915996 -349.108465)
			(xy 291.881162 -349.032189) (xy 291.853737 -348.952948) (xy 291.833968 -348.871458) (xy 291.822034 -348.788458)
			(xy 291.818044 -348.7047) (xy 288.299345 -348.7047) (xy 288.302721 -348.741025) (xy 288.303208 -348.782132)
			(xy 288.302642 -348.826902) (xy 288.293633 -348.915987) (xy 288.275729 -349.003718) (xy 288.249111 -349.089209)
			(xy 288.232088 -349.13062) (xy 288.228504 -349.140205) (xy 288.228515 -349.160653) (xy 288.232088 -349.170244)
			(xy 288.249111 -349.211656) (xy 288.275747 -349.297143) (xy 288.293656 -349.384874) (xy 288.302654 -349.473962)
			(xy 288.303208 -349.518732) (xy 288.302642 -349.563502) (xy 288.293633 -349.652587) (xy 288.275729 -349.740318)
			(xy 288.249111 -349.825809) (xy 288.232088 -349.86722) (xy 288.228504 -349.876805) (xy 288.228515 -349.897253)
			(xy 288.232088 -349.906844) (xy 288.249111 -349.948256) (xy 288.275747 -350.033743) (xy 288.293656 -350.121474)
			(xy 288.302654 -350.210562) (xy 288.303208 -350.255332) (xy 288.302778 -350.296443) (xy 288.295187 -350.378314)
			(xy 288.280074 -350.459136) (xy 288.257566 -350.538217) (xy 288.227857 -350.614885) (xy 288.191199 -350.688483)
			(xy 288.147906 -350.758385) (xy 288.098347 -350.823993) (xy 288.042945 -350.884747) (xy 287.982172 -350.94013)
			(xy 287.916548 -350.989668) (xy 287.846633 -351.032938) (xy 287.773023 -351.069572) (xy 287.696346 -351.099257)
			(xy 287.617257 -351.121739) (xy 287.536431 -351.136827) (xy 287.454557 -351.144391) (xy 287.413446 -351.14484)
			(xy 287.371842 -351.14437) (xy 287.288994 -351.136637) (xy 287.207229 -351.121206) (xy 287.127262 -351.098211)
			(xy 287.049789 -351.067854) (xy 286.975488 -351.0304) (xy 286.93999 -351.008696) (xy 286.930858 -351.003521)
			(xy 286.910138 -351.00031) (xy 286.889861 -351.005649) (xy 286.881316 -351.011744) (xy 286.847666 -351.037664)
			(xy 286.776292 -351.083723) (xy 286.700853 -351.12277) (xy 286.622037 -351.15445) (xy 286.54056 -351.178473)
			(xy 286.457164 -351.194623) (xy 286.372608 -351.20275) (xy 286.330136 -351.20326) (xy 286.329882 -351.20326)
			(xy 286.288775 -351.202805) (xy 286.206911 -351.195219) (xy 286.126097 -351.180113) (xy 286.04702 -351.157617)
			(xy 285.970356 -351.127921) (xy 285.896759 -351.09128) (xy 285.826855 -351.048006) (xy 285.761241 -350.998468)
			(xy 285.700477 -350.943088) (xy 285.645082 -350.882339) (xy 285.595526 -350.816738) (xy 285.552233 -350.746846)
			(xy 285.515573 -350.673258) (xy 285.485858 -350.596602) (xy 285.463341 -350.517531) (xy 285.448214 -350.43672)
			(xy 285.440606 -350.354859) (xy 285.44012 -350.313752) (xy 285.440679 -350.268982) (xy 285.44969 -350.179897)
			(xy 285.467596 -350.092166) (xy 285.494216 -350.006675) (xy 285.51124 -349.965264) (xy 285.514832 -349.955681)
			(xy 285.514815 -349.935231) (xy 285.51124 -349.92564) (xy 285.494236 -349.884289) (xy 285.467625 -349.798927)
			(xy 285.449718 -349.711324) (xy 285.440696 -349.622367) (xy 285.44012 -349.57766) (xy 285.44012 -349.576644)
			(xy 285.440374 -349.565214) (xy 285.413895 -349.559269) (xy 285.36166 -349.544526) (xy 285.33598 -349.53575)
			(xy 285.327783 -349.533236) (xy 285.310649 -349.533236) (xy 285.302452 -349.53575) (xy 285.267236 -349.547697)
			(xy 285.195226 -349.566284) (xy 285.121903 -349.578724) (xy 285.047792 -349.584928) (xy 285.010606 -349.58528)
			(xy 284.973422 -349.584911) (xy 284.899314 -349.578689) (xy 284.825994 -349.566246) (xy 284.753983 -349.547672)
			(xy 284.71876 -349.53575) (xy 284.710563 -349.533236) (xy 284.693429 -349.533236) (xy 284.685232 -349.53575)
			(xy 284.65013 -349.547637) (xy 284.578374 -349.566187) (xy 284.505311 -349.578634) (xy 284.43146 -349.584887)
			(xy 284.394402 -349.58528) (xy 284.393386 -349.58528) (xy 284.351459 -349.584857) (xy 284.267986 -349.576885)
			(xy 284.185648 -349.561014) (xy 284.105192 -349.537389) (xy 284.027346 -349.506223) (xy 283.952814 -349.467798)
			(xy 283.882273 -349.422463) (xy 283.81636 -349.370628) (xy 283.755673 -349.312762) (xy 283.700761 -349.24939)
			(xy 283.652122 -349.181084) (xy 283.610196 -349.108465) (xy 283.575362 -349.032189) (xy 283.547937 -348.952948)
			(xy 283.528168 -348.871458) (xy 283.516234 -348.788458) (xy 283.512244 -348.7047) (xy 280.018945 -348.7047)
			(xy 280.022321 -348.741025) (xy 280.022808 -348.782132) (xy 280.022242 -348.826902) (xy 280.013233 -348.915987)
			(xy 279.995329 -349.003718) (xy 279.968711 -349.089209) (xy 279.951688 -349.13062) (xy 279.948104 -349.140205)
			(xy 279.948115 -349.160653) (xy 279.951688 -349.170244) (xy 279.968711 -349.211656) (xy 279.995347 -349.297143)
			(xy 280.013256 -349.384874) (xy 280.022254 -349.473962) (xy 280.022808 -349.518732) (xy 280.022242 -349.563502)
			(xy 280.013233 -349.652587) (xy 279.995329 -349.740318) (xy 279.968711 -349.825809) (xy 279.951688 -349.86722)
			(xy 279.948104 -349.876805) (xy 279.948115 -349.897253) (xy 279.951688 -349.906844) (xy 279.968711 -349.948256)
			(xy 279.995347 -350.033743) (xy 280.013256 -350.121474) (xy 280.022254 -350.210562) (xy 280.022808 -350.255332)
			(xy 280.022378 -350.296443) (xy 280.014787 -350.378314) (xy 279.999674 -350.459136) (xy 279.977166 -350.538217)
			(xy 279.947457 -350.614885) (xy 279.910799 -350.688483) (xy 279.867506 -350.758385) (xy 279.817947 -350.823993)
			(xy 279.762545 -350.884747) (xy 279.701772 -350.94013) (xy 279.636148 -350.989668) (xy 279.566233 -351.032938)
			(xy 279.492623 -351.069572) (xy 279.415946 -351.099257) (xy 279.336857 -351.121739) (xy 279.256031 -351.136827)
			(xy 279.174157 -351.144391) (xy 279.133046 -351.14484) (xy 279.091442 -351.14437) (xy 279.008594 -351.136637)
			(xy 278.926829 -351.121206) (xy 278.846862 -351.098211) (xy 278.769389 -351.067854) (xy 278.695088 -351.0304)
			(xy 278.65959 -351.008696) (xy 278.650458 -351.003521) (xy 278.629738 -351.00031) (xy 278.609461 -351.005649)
			(xy 278.600916 -351.011744) (xy 278.567266 -351.037664) (xy 278.495892 -351.083723) (xy 278.420453 -351.12277)
			(xy 278.341637 -351.15445) (xy 278.26016 -351.178473) (xy 278.176764 -351.194623) (xy 278.092208 -351.20275)
			(xy 278.049736 -351.20326) (xy 278.049482 -351.20326) (xy 278.008375 -351.202805) (xy 277.926511 -351.195219)
			(xy 277.845697 -351.180113) (xy 277.76662 -351.157617) (xy 277.689956 -351.127921) (xy 277.616359 -351.09128)
			(xy 277.546455 -351.048006) (xy 277.480841 -350.998468) (xy 277.420077 -350.943088) (xy 277.364682 -350.882339)
			(xy 277.315126 -350.816738) (xy 277.271833 -350.746846) (xy 277.235173 -350.673258) (xy 277.205458 -350.596602)
			(xy 277.182941 -350.517531) (xy 277.167814 -350.43672) (xy 277.160206 -350.354859) (xy 277.15972 -350.313752)
			(xy 277.160279 -350.268982) (xy 277.16929 -350.179897) (xy 277.187196 -350.092166) (xy 277.213816 -350.006675)
			(xy 277.23084 -349.965264) (xy 277.234432 -349.955681) (xy 277.234415 -349.935231) (xy 277.23084 -349.92564)
			(xy 277.213836 -349.884289) (xy 277.187225 -349.798927) (xy 277.169318 -349.711324) (xy 277.160296 -349.622367)
			(xy 277.15972 -349.57766) (xy 277.15972 -349.576644) (xy 277.159974 -349.565214) (xy 277.133495 -349.559269)
			(xy 277.08126 -349.544526) (xy 277.05558 -349.53575) (xy 277.047383 -349.533236) (xy 277.030249 -349.533236)
			(xy 277.022052 -349.53575) (xy 276.986836 -349.547697) (xy 276.914826 -349.566284) (xy 276.841503 -349.578724)
			(xy 276.767392 -349.584928) (xy 276.730206 -349.58528) (xy 276.693022 -349.584911) (xy 276.618914 -349.578689)
			(xy 276.545594 -349.566246) (xy 276.473583 -349.547672) (xy 276.43836 -349.53575) (xy 276.430163 -349.533236)
			(xy 276.413029 -349.533236) (xy 276.404832 -349.53575) (xy 276.36973 -349.547637) (xy 276.297974 -349.566187)
			(xy 276.224911 -349.578634) (xy 276.15106 -349.584887) (xy 276.114002 -349.58528) (xy 276.112986 -349.58528)
			(xy 276.071059 -349.584857) (xy 275.987586 -349.576885) (xy 275.905248 -349.561014) (xy 275.824792 -349.537389)
			(xy 275.746946 -349.506223) (xy 275.672414 -349.467798) (xy 275.601873 -349.422463) (xy 275.53596 -349.370628)
			(xy 275.475273 -349.312762) (xy 275.420361 -349.24939) (xy 275.371722 -349.181084) (xy 275.329796 -349.108465)
			(xy 275.294962 -349.032189) (xy 275.267537 -348.952948) (xy 275.247768 -348.871458) (xy 275.235834 -348.788458)
			(xy 275.231844 -348.7047) (xy 85.721282 -348.7047) (xy 85.724562 -348.719921) (xy 85.734552 -348.813881)
			(xy 85.73516 -348.861126) (xy 85.734613 -348.906766) (xy 85.725307 -348.997569) (xy 85.706754 -349.086942)
			(xy 85.693504 -349.13062) (xy 85.691044 -349.139629) (xy 85.692095 -349.15826) (xy 85.695536 -349.166942)
			(xy 85.714247 -349.210016) (xy 85.743525 -349.299254) (xy 85.763232 -349.391081) (xy 85.77315 -349.484473)
			(xy 85.773768 -349.531432) (xy 85.77323 -349.574377) (xy 85.764932 -349.659867) (xy 85.748446 -349.744161)
			(xy 85.723925 -349.826477) (xy 85.708236 -349.866458) (xy 85.704966 -349.875707) (xy 85.704968 -349.895308)
			(xy 85.708236 -349.904558) (xy 85.723959 -349.944561) (xy 85.748521 -350.026936) (xy 85.765013 -350.111298)
			(xy 85.773281 -350.196858) (xy 85.773768 -350.239838) (xy 85.773264 -350.282199) (xy 85.765211 -350.366536)
			(xy 85.749177 -350.449726) (xy 85.725309 -350.531016) (xy 85.693821 -350.609668) (xy 85.654999 -350.684971)
			(xy 85.609196 -350.756243) (xy 85.556825 -350.822839) (xy 85.49836 -350.884154) (xy 85.434332 -350.939635)
			(xy 85.36532 -350.988778) (xy 85.29195 -351.031138) (xy 85.214885 -351.066333) (xy 85.134823 -351.094042)
			(xy 85.05249 -351.114016) (xy 84.968631 -351.126073) (xy 84.884006 -351.130105) (xy 84.799381 -351.126073)
			(xy 84.715522 -351.114016) (xy 84.633189 -351.094042) (xy 84.553127 -351.066333) (xy 84.476062 -351.031138)
			(xy 84.402692 -350.988778) (xy 84.33368 -350.939635) (xy 84.269652 -350.884154) (xy 84.211187 -350.822839)
			(xy 84.158816 -350.756243) (xy 84.113013 -350.684971) (xy 84.074191 -350.609668) (xy 84.042703 -350.531016)
			(xy 84.018835 -350.449726) (xy 84.002801 -350.366536) (xy 83.994748 -350.282199) (xy 83.994244 -350.239838)
			(xy 83.994769 -350.196861) (xy 84.003053 -350.111306) (xy 84.01954 -350.026947) (xy 84.044076 -349.944568)
			(xy 84.059776 -349.904558) (xy 84.063037 -349.895306) (xy 84.06304 -349.875708) (xy 84.059776 -349.866458)
			(xy 84.044053 -349.826489) (xy 84.019511 -349.744174) (xy 84.003027 -349.659876) (xy 83.994754 -349.57438)
			(xy 83.994244 -349.531432) (xy 83.994855 -349.485787) (xy 84.004246 -349.394981) (xy 84.022872 -349.305612)
			(xy 84.036154 -349.261938) (xy 84.038586 -349.252923) (xy 84.037555 -349.234298) (xy 84.034122 -349.225616)
			(xy 84.015469 -349.182525) (xy 83.98626 -349.093282) (xy 83.966612 -349.001459) (xy 83.956742 -348.908077)
			(xy 83.956144 -348.861126) (xy 83.073245 -348.861126) (xy 83.073748 -348.89948) (xy 83.073141 -348.945125)
			(xy 83.063748 -349.035931) (xy 83.045121 -349.1253) (xy 83.031838 -349.168974) (xy 83.0294 -349.177987)
			(xy 83.030435 -349.196614) (xy 83.03387 -349.205296) (xy 83.052527 -349.248385) (xy 83.081735 -349.337629)
			(xy 83.101382 -349.429453) (xy 83.111251 -349.522835) (xy 83.111848 -349.569786) (xy 83.111412 -349.610119)
			(xy 83.104141 -349.690457) (xy 83.08963 -349.769807) (xy 83.067997 -349.847519) (xy 83.039422 -349.922954)
			(xy 83.022186 -349.959422) (xy 83.017653 -349.970011) (xy 83.017661 -349.993024) (xy 83.022186 -350.003618)
			(xy 83.039397 -350.040069) (xy 83.067953 -350.115455) (xy 83.089579 -350.193114) (xy 83.104099 -350.27241)
			(xy 83.111393 -350.352693) (xy 83.111848 -350.393) (xy 83.111344 -350.435361) (xy 83.103291 -350.519698)
			(xy 83.087257 -350.602888) (xy 83.063389 -350.684178) (xy 83.031901 -350.76283) (xy 82.993079 -350.838133)
			(xy 82.947276 -350.909405) (xy 82.894905 -350.976001) (xy 82.83644 -351.037316) (xy 82.772412 -351.092797)
			(xy 82.7034 -351.14194) (xy 82.63003 -351.1843) (xy 82.552965 -351.219495) (xy 82.472903 -351.247204)
			(xy 82.39057 -351.267178) (xy 82.306711 -351.279235) (xy 82.222086 -351.283267) (xy 82.137461 -351.279235)
			(xy 82.053602 -351.267178) (xy 81.971269 -351.247204) (xy 81.891207 -351.219495) (xy 81.814142 -351.1843)
			(xy 81.740772 -351.14194) (xy 81.67176 -351.092797) (xy 81.607732 -351.037316) (xy 81.549267 -350.976001)
			(xy 81.496896 -350.909405) (xy 81.451093 -350.838133) (xy 81.412271 -350.76283) (xy 81.380783 -350.684178)
			(xy 81.356915 -350.602888) (xy 81.340881 -350.519698) (xy 81.332828 -350.435361) (xy 81.332324 -350.393)
			(xy 81.332778 -350.35266) (xy 81.340081 -350.272312) (xy 81.354637 -350.192956) (xy 81.376326 -350.115246)
			(xy 81.404968 -350.039822) (xy 81.42224 -350.003364) (xy 81.426812 -349.992711) (xy 81.426828 -349.969558)
			(xy 81.42224 -349.958914) (xy 81.405059 -349.922483) (xy 81.376548 -349.847143) (xy 81.35497 -349.769534)
			(xy 81.340501 -349.69029) (xy 81.33326 -349.610063) (xy 81.332832 -349.569786) (xy 81.333382 -349.524146)
			(xy 81.342687 -349.433343) (xy 81.361239 -349.34397) (xy 81.374488 -349.300292) (xy 81.376942 -349.291282)
			(xy 81.375896 -349.272652) (xy 81.372456 -349.26397) (xy 81.353748 -349.220894) (xy 81.32447 -349.131657)
			(xy 81.304762 -349.039831) (xy 81.294843 -348.946439) (xy 81.294224 -348.89948) (xy 66.467942 -348.89948)
			(xy 66.465784 -348.920813) (xy 66.447878 -349.008544) (xy 66.421259 -349.094035) (xy 66.404236 -349.135446)
			(xy 66.400697 -349.145044) (xy 66.400681 -349.16548) (xy 66.404236 -349.17507) (xy 66.421263 -349.21648)
			(xy 66.4479 -349.301967) (xy 66.465806 -349.3897) (xy 66.474803 -349.478787) (xy 66.475356 -349.523558)
			(xy 66.474795 -349.568328) (xy 66.465784 -349.657413) (xy 66.447878 -349.745144) (xy 66.421259 -349.830635)
			(xy 66.404236 -349.872046) (xy 66.400697 -349.881644) (xy 66.400681 -349.90208) (xy 66.404236 -349.91167)
			(xy 66.421263 -349.95308) (xy 66.4479 -350.038567) (xy 66.465806 -350.1263) (xy 66.474803 -350.215387)
			(xy 66.475356 -350.260158) (xy 66.474861 -350.301272) (xy 66.467278 -350.383151) (xy 66.452172 -350.46398)
			(xy 66.429672 -350.54307) (xy 66.39997 -350.619748) (xy 66.36332 -350.693357) (xy 66.320034 -350.76327)
			(xy 66.270482 -350.828891) (xy 66.215086 -350.88966) (xy 66.154319 -350.945059) (xy 66.0887 -350.994614)
			(xy 66.018788 -351.037902) (xy 65.94518 -351.074555) (xy 65.868505 -351.10426) (xy 65.789415 -351.126764)
			(xy 65.708586 -351.141873) (xy 65.626708 -351.14946) (xy 65.585594 -351.14992) (xy 65.543984 -351.149442)
			(xy 65.461127 -351.141665) (xy 65.379358 -351.12619) (xy 65.299391 -351.10315) (xy 65.221922 -351.072748)
			(xy 65.147629 -351.035248) (xy 65.112138 -351.013522) (xy 65.10303 -351.008297) (xy 65.082293 -351.005101)
			(xy 65.062008 -351.010462) (xy 65.053464 -351.01657) (xy 65.019831 -351.042555) (xy 64.948437 -351.08868)
			(xy 64.872967 -351.127782) (xy 64.79411 -351.159503) (xy 64.712585 -351.183553) (xy 64.629138 -351.199714)
			(xy 64.544529 -351.207838) (xy 64.50203 -351.20834) (xy 64.460915 -351.207873) (xy 64.379035 -351.200288)
			(xy 64.298205 -351.185181) (xy 64.219114 -351.162679) (xy 64.142436 -351.132976) (xy 64.068826 -351.096324)
			(xy 63.998912 -351.053036) (xy 63.93329 -351.003482) (xy 63.872521 -350.948084) (xy 63.817123 -350.887316)
			(xy 63.767568 -350.821695) (xy 63.72428 -350.751781) (xy 63.687628 -350.678172) (xy 63.657923 -350.601494)
			(xy 63.635421 -350.522403) (xy 63.620313 -350.441573) (xy 63.612727 -350.359693) (xy 63.612268 -350.318578)
			(xy 63.61284 -350.273809) (xy 63.621847 -350.184724) (xy 63.63975 -350.096993) (xy 63.666366 -350.011501)
			(xy 63.683388 -349.97009) (xy 63.686968 -349.960503) (xy 63.68696 -349.940056) (xy 63.683388 -349.930466)
			(xy 63.666363 -349.889123) (xy 63.639757 -349.803758) (xy 63.621856 -349.716153) (xy 63.612841 -349.627193)
			(xy 63.612268 -349.582486) (xy 63.612268 -349.58147) (xy 63.612522 -349.57004) (xy 63.586044 -349.564091)
			(xy 63.533809 -349.54935) (xy 63.508128 -349.540576) (xy 63.499931 -349.538062) (xy 63.482797 -349.538062)
			(xy 63.4746 -349.540576) (xy 63.43938 -349.552528) (xy 63.367379 -349.571185) (xy 63.294059 -349.583696)
			(xy 63.219944 -349.589972) (xy 63.182754 -349.59036) (xy 63.145565 -349.589952) (xy 63.071452 -349.583667)
			(xy 62.998133 -349.571163) (xy 62.926126 -349.552528) (xy 62.890908 -349.540576) (xy 62.882711 -349.538062)
			(xy 62.865577 -349.538062) (xy 62.85738 -349.540576) (xy 62.822162 -349.552533) (xy 62.75016 -349.571189)
			(xy 62.676839 -349.583699) (xy 62.602724 -349.589973) (xy 62.565534 -349.59036) (xy 62.523594 -349.589902)
			(xy 62.440094 -349.581932) (xy 62.35773 -349.566061) (xy 62.277248 -349.542432) (xy 62.199376 -349.511259)
			(xy 62.12482 -349.472825) (xy 62.054255 -349.427478) (xy 61.98832 -349.375629) (xy 61.927613 -349.317747)
			(xy 61.872683 -349.254356) (xy 61.824027 -349.186031) (xy 61.782086 -349.11339) (xy 61.74724 -349.037091)
			(xy 61.719806 -348.957825) (xy 61.70003 -348.87631) (xy 61.688092 -348.793284) (xy 61.684101 -348.7095)
			(xy 58.14031 -348.7095) (xy 58.143679 -348.745845) (xy 58.144156 -348.786958) (xy 58.143595 -348.831728)
			(xy 58.134584 -348.920813) (xy 58.116678 -349.008544) (xy 58.090059 -349.094035) (xy 58.073036 -349.135446)
			(xy 58.069497 -349.145044) (xy 58.069481 -349.16548) (xy 58.073036 -349.17507) (xy 58.090063 -349.21648)
			(xy 58.1167 -349.301967) (xy 58.134606 -349.3897) (xy 58.143603 -349.478787) (xy 58.144156 -349.523558)
			(xy 58.143595 -349.568328) (xy 58.134584 -349.657413) (xy 58.116678 -349.745144) (xy 58.090059 -349.830635)
			(xy 58.073036 -349.872046) (xy 58.069497 -349.881644) (xy 58.069481 -349.90208) (xy 58.073036 -349.91167)
			(xy 58.090063 -349.95308) (xy 58.1167 -350.038567) (xy 58.134606 -350.1263) (xy 58.143603 -350.215387)
			(xy 58.144156 -350.260158) (xy 58.143661 -350.301272) (xy 58.136078 -350.383151) (xy 58.120972 -350.46398)
			(xy 58.098472 -350.54307) (xy 58.06877 -350.619748) (xy 58.03212 -350.693357) (xy 57.988834 -350.76327)
			(xy 57.939282 -350.828891) (xy 57.883886 -350.88966) (xy 57.823119 -350.945059) (xy 57.7575 -350.994614)
			(xy 57.687588 -351.037902) (xy 57.61398 -351.074555) (xy 57.537305 -351.10426) (xy 57.458215 -351.126764)
			(xy 57.377386 -351.141873) (xy 57.295508 -351.14946) (xy 57.254394 -351.14992) (xy 57.212784 -351.149442)
			(xy 57.129927 -351.141665) (xy 57.048158 -351.12619) (xy 56.968191 -351.10315) (xy 56.890722 -351.072748)
			(xy 56.816429 -351.035248) (xy 56.780938 -351.013522) (xy 56.77183 -351.008297) (xy 56.751093 -351.005101)
			(xy 56.730808 -351.010462) (xy 56.722264 -351.01657) (xy 56.688631 -351.042555) (xy 56.617237 -351.08868)
			(xy 56.541767 -351.127782) (xy 56.46291 -351.159503) (xy 56.381385 -351.183553) (xy 56.297938 -351.199714)
			(xy 56.213329 -351.207838) (xy 56.17083 -351.20834) (xy 56.129715 -351.207873) (xy 56.047835 -351.200288)
			(xy 55.967005 -351.185181) (xy 55.887914 -351.162679) (xy 55.811236 -351.132976) (xy 55.737626 -351.096324)
			(xy 55.667712 -351.053036) (xy 55.60209 -351.003482) (xy 55.541321 -350.948084) (xy 55.485923 -350.887316)
			(xy 55.436368 -350.821695) (xy 55.39308 -350.751781) (xy 55.356428 -350.678172) (xy 55.326723 -350.601494)
			(xy 55.304221 -350.522403) (xy 55.289113 -350.441573) (xy 55.281527 -350.359693) (xy 55.281068 -350.318578)
			(xy 55.28164 -350.273809) (xy 55.290647 -350.184724) (xy 55.30855 -350.096993) (xy 55.335166 -350.011501)
			(xy 55.352188 -349.97009) (xy 55.355768 -349.960503) (xy 55.35576 -349.940056) (xy 55.352188 -349.930466)
			(xy 55.335163 -349.889123) (xy 55.308557 -349.803758) (xy 55.290656 -349.716153) (xy 55.281641 -349.627193)
			(xy 55.281068 -349.582486) (xy 55.281068 -349.58147) (xy 55.281322 -349.57004) (xy 55.254844 -349.564091)
			(xy 55.202609 -349.54935) (xy 55.176928 -349.540576) (xy 55.168731 -349.538062) (xy 55.151597 -349.538062)
			(xy 55.1434 -349.540576) (xy 55.10818 -349.552528) (xy 55.036179 -349.571185) (xy 54.962859 -349.583696)
			(xy 54.888744 -349.589972) (xy 54.851554 -349.59036) (xy 54.814365 -349.589952) (xy 54.740252 -349.583667)
			(xy 54.666933 -349.571163) (xy 54.594926 -349.552528) (xy 54.559708 -349.540576) (xy 54.551511 -349.538062)
			(xy 54.534377 -349.538062) (xy 54.52618 -349.540576) (xy 54.490962 -349.552533) (xy 54.41896 -349.571189)
			(xy 54.345639 -349.583699) (xy 54.271524 -349.589973) (xy 54.234334 -349.59036) (xy 54.192394 -349.589902)
			(xy 54.108894 -349.581932) (xy 54.02653 -349.566061) (xy 53.946048 -349.542432) (xy 53.868176 -349.511259)
			(xy 53.79362 -349.472825) (xy 53.723055 -349.427478) (xy 53.65712 -349.375629) (xy 53.596413 -349.317747)
			(xy 53.541483 -349.254356) (xy 53.492827 -349.186031) (xy 53.450886 -349.11339) (xy 53.41604 -349.037091)
			(xy 53.388606 -348.957825) (xy 53.36883 -348.87631) (xy 53.356892 -348.793284) (xy 53.352901 -348.7095)
			(xy 49.78371 -348.7095) (xy 49.787079 -348.745845) (xy 49.787556 -348.786958) (xy 49.786995 -348.831728)
			(xy 49.777984 -348.920813) (xy 49.760078 -349.008544) (xy 49.733459 -349.094035) (xy 49.716436 -349.135446)
			(xy 49.712897 -349.145044) (xy 49.712881 -349.16548) (xy 49.716436 -349.17507) (xy 49.733463 -349.21648)
			(xy 49.7601 -349.301967) (xy 49.778006 -349.3897) (xy 49.787003 -349.478787) (xy 49.787556 -349.523558)
			(xy 49.786995 -349.568328) (xy 49.777984 -349.657413) (xy 49.760078 -349.745144) (xy 49.733459 -349.830635)
			(xy 49.716436 -349.872046) (xy 49.712897 -349.881644) (xy 49.712881 -349.90208) (xy 49.716436 -349.91167)
			(xy 49.733463 -349.95308) (xy 49.7601 -350.038567) (xy 49.778006 -350.1263) (xy 49.787003 -350.215387)
			(xy 49.787556 -350.260158) (xy 49.787061 -350.301272) (xy 49.779478 -350.383151) (xy 49.764372 -350.46398)
			(xy 49.741872 -350.54307) (xy 49.71217 -350.619748) (xy 49.67552 -350.693357) (xy 49.632234 -350.76327)
			(xy 49.582682 -350.828891) (xy 49.527286 -350.88966) (xy 49.466519 -350.945059) (xy 49.4009 -350.994614)
			(xy 49.330988 -351.037902) (xy 49.25738 -351.074555) (xy 49.180705 -351.10426) (xy 49.101615 -351.126764)
			(xy 49.020786 -351.141873) (xy 48.938908 -351.14946) (xy 48.897794 -351.14992) (xy 48.856184 -351.149442)
			(xy 48.773327 -351.141665) (xy 48.691558 -351.12619) (xy 48.611591 -351.10315) (xy 48.534122 -351.072748)
			(xy 48.459829 -351.035248) (xy 48.424338 -351.013522) (xy 48.41523 -351.008297) (xy 48.394493 -351.005101)
			(xy 48.374208 -351.010462) (xy 48.365664 -351.01657) (xy 48.332031 -351.042555) (xy 48.260637 -351.08868)
			(xy 48.185167 -351.127782) (xy 48.10631 -351.159503) (xy 48.024785 -351.183553) (xy 47.941338 -351.199714)
			(xy 47.856729 -351.207838) (xy 47.81423 -351.20834) (xy 47.773115 -351.207873) (xy 47.691235 -351.200288)
			(xy 47.610405 -351.185181) (xy 47.531314 -351.162679) (xy 47.454636 -351.132976) (xy 47.381026 -351.096324)
			(xy 47.311112 -351.053036) (xy 47.24549 -351.003482) (xy 47.184721 -350.948084) (xy 47.129323 -350.887316)
			(xy 47.079768 -350.821695) (xy 47.03648 -350.751781) (xy 46.999828 -350.678172) (xy 46.970123 -350.601494)
			(xy 46.947621 -350.522403) (xy 46.932513 -350.441573) (xy 46.924927 -350.359693) (xy 46.924468 -350.318578)
			(xy 46.92504 -350.273809) (xy 46.934047 -350.184724) (xy 46.95195 -350.096993) (xy 46.978566 -350.011501)
			(xy 46.995588 -349.97009) (xy 46.999168 -349.960503) (xy 46.99916 -349.940056) (xy 46.995588 -349.930466)
			(xy 46.978563 -349.889123) (xy 46.951957 -349.803758) (xy 46.934056 -349.716153) (xy 46.925041 -349.627193)
			(xy 46.924468 -349.582486) (xy 46.924468 -349.58147) (xy 46.924722 -349.57004) (xy 46.898244 -349.564091)
			(xy 46.846009 -349.54935) (xy 46.820328 -349.540576) (xy 46.812131 -349.538062) (xy 46.794997 -349.538062)
			(xy 46.7868 -349.540576) (xy 46.75158 -349.552528) (xy 46.679579 -349.571185) (xy 46.606259 -349.583696)
			(xy 46.532144 -349.589972) (xy 46.494954 -349.59036) (xy 46.457765 -349.589952) (xy 46.383652 -349.583667)
			(xy 46.310333 -349.571163) (xy 46.238326 -349.552528) (xy 46.203108 -349.540576) (xy 46.194911 -349.538062)
			(xy 46.177777 -349.538062) (xy 46.16958 -349.540576) (xy 46.134362 -349.552533) (xy 46.06236 -349.571189)
			(xy 45.989039 -349.583699) (xy 45.914924 -349.589973) (xy 45.877734 -349.59036) (xy 45.835794 -349.589902)
			(xy 45.752294 -349.581932) (xy 45.66993 -349.566061) (xy 45.589448 -349.542432) (xy 45.511576 -349.511259)
			(xy 45.43702 -349.472825) (xy 45.366455 -349.427478) (xy 45.30052 -349.375629) (xy 45.239813 -349.317747)
			(xy 45.184883 -349.254356) (xy 45.136227 -349.186031) (xy 45.094286 -349.11339) (xy 45.05944 -349.037091)
			(xy 45.032006 -348.957825) (xy 45.01223 -348.87631) (xy 45.000292 -348.793284) (xy 44.996301 -348.7095)
			(xy 41.47791 -348.7095) (xy 41.481279 -348.745845) (xy 41.481756 -348.786958) (xy 41.481195 -348.831728)
			(xy 41.472184 -348.920813) (xy 41.454278 -349.008544) (xy 41.427659 -349.094035) (xy 41.410636 -349.135446)
			(xy 41.407097 -349.145044) (xy 41.407081 -349.16548) (xy 41.410636 -349.17507) (xy 41.427663 -349.21648)
			(xy 41.4543 -349.301967) (xy 41.472206 -349.3897) (xy 41.481203 -349.478787) (xy 41.481756 -349.523558)
			(xy 41.481195 -349.568328) (xy 41.472184 -349.657413) (xy 41.454278 -349.745144) (xy 41.427659 -349.830635)
			(xy 41.410636 -349.872046) (xy 41.407097 -349.881644) (xy 41.407081 -349.90208) (xy 41.410636 -349.91167)
			(xy 41.427663 -349.95308) (xy 41.4543 -350.038567) (xy 41.472206 -350.1263) (xy 41.481203 -350.215387)
			(xy 41.481756 -350.260158) (xy 41.481261 -350.301272) (xy 41.473678 -350.383151) (xy 41.458572 -350.46398)
			(xy 41.436072 -350.54307) (xy 41.40637 -350.619748) (xy 41.36972 -350.693357) (xy 41.326434 -350.76327)
			(xy 41.276882 -350.828891) (xy 41.221486 -350.88966) (xy 41.160719 -350.945059) (xy 41.0951 -350.994614)
			(xy 41.025188 -351.037902) (xy 40.95158 -351.074555) (xy 40.874905 -351.10426) (xy 40.795815 -351.126764)
			(xy 40.714986 -351.141873) (xy 40.633108 -351.14946) (xy 40.591994 -351.14992) (xy 40.550384 -351.149442)
			(xy 40.467527 -351.141665) (xy 40.385758 -351.12619) (xy 40.305791 -351.10315) (xy 40.228322 -351.072748)
			(xy 40.154029 -351.035248) (xy 40.118538 -351.013522) (xy 40.10943 -351.008297) (xy 40.088693 -351.005101)
			(xy 40.068408 -351.010462) (xy 40.059864 -351.01657) (xy 40.026231 -351.042555) (xy 39.954837 -351.08868)
			(xy 39.879367 -351.127782) (xy 39.80051 -351.159503) (xy 39.718985 -351.183553) (xy 39.635538 -351.199714)
			(xy 39.550929 -351.207838) (xy 39.50843 -351.20834) (xy 39.467315 -351.207873) (xy 39.385435 -351.200288)
			(xy 39.304605 -351.185181) (xy 39.225514 -351.162679) (xy 39.148836 -351.132976) (xy 39.075226 -351.096324)
			(xy 39.005312 -351.053036) (xy 38.93969 -351.003482) (xy 38.878921 -350.948084) (xy 38.823523 -350.887316)
			(xy 38.773968 -350.821695) (xy 38.73068 -350.751781) (xy 38.694028 -350.678172) (xy 38.664323 -350.601494)
			(xy 38.641821 -350.522403) (xy 38.626713 -350.441573) (xy 38.619127 -350.359693) (xy 38.618668 -350.318578)
			(xy 38.61924 -350.273809) (xy 38.628247 -350.184724) (xy 38.64615 -350.096993) (xy 38.672766 -350.011501)
			(xy 38.689788 -349.97009) (xy 38.693368 -349.960503) (xy 38.69336 -349.940056) (xy 38.689788 -349.930466)
			(xy 38.672763 -349.889123) (xy 38.646157 -349.803758) (xy 38.628256 -349.716153) (xy 38.619241 -349.627193)
			(xy 38.618668 -349.582486) (xy 38.618668 -349.58147) (xy 38.618922 -349.57004) (xy 38.592444 -349.564091)
			(xy 38.540209 -349.54935) (xy 38.514528 -349.540576) (xy 38.506331 -349.538062) (xy 38.489197 -349.538062)
			(xy 38.481 -349.540576) (xy 38.44578 -349.552528) (xy 38.373779 -349.571185) (xy 38.300459 -349.583696)
			(xy 38.226344 -349.589972) (xy 38.189154 -349.59036) (xy 38.151965 -349.589952) (xy 38.077852 -349.583667)
			(xy 38.004533 -349.571163) (xy 37.932526 -349.552528) (xy 37.897308 -349.540576) (xy 37.889111 -349.538062)
			(xy 37.871977 -349.538062) (xy 37.86378 -349.540576) (xy 37.828562 -349.552533) (xy 37.75656 -349.571189)
			(xy 37.683239 -349.583699) (xy 37.609124 -349.589973) (xy 37.571934 -349.59036) (xy 37.529996 -349.589881)
			(xy 37.446499 -349.581908) (xy 37.364138 -349.566035) (xy 37.283659 -349.542404) (xy 37.20579 -349.511231)
			(xy 37.131238 -349.472797) (xy 37.060676 -349.42745) (xy 36.994745 -349.375601) (xy 36.93404 -349.317719)
			(xy 36.879112 -349.25433) (xy 36.830459 -349.186006) (xy 36.788521 -349.113367) (xy 36.753677 -349.03707)
			(xy 36.726244 -348.957807) (xy 36.706469 -348.876294) (xy 36.694532 -348.793272) (xy 36.690541 -348.70949)
			(xy 33.197509 -348.70949) (xy 33.200879 -348.745845) (xy 33.201356 -348.786958) (xy 33.200795 -348.831728)
			(xy 33.191784 -348.920813) (xy 33.173878 -349.008544) (xy 33.147259 -349.094035) (xy 33.130236 -349.135446)
			(xy 33.126697 -349.145044) (xy 33.126681 -349.16548) (xy 33.130236 -349.17507) (xy 33.147263 -349.21648)
			(xy 33.1739 -349.301967) (xy 33.191806 -349.3897) (xy 33.200803 -349.478787) (xy 33.201356 -349.523558)
			(xy 33.200795 -349.568328) (xy 33.191784 -349.657413) (xy 33.173878 -349.745144) (xy 33.147259 -349.830635)
			(xy 33.130236 -349.872046) (xy 33.126697 -349.881644) (xy 33.126681 -349.90208) (xy 33.130236 -349.91167)
			(xy 33.147263 -349.95308) (xy 33.1739 -350.038567) (xy 33.191806 -350.1263) (xy 33.200803 -350.215387)
			(xy 33.201356 -350.260158) (xy 33.200861 -350.301272) (xy 33.193278 -350.383151) (xy 33.178172 -350.46398)
			(xy 33.155672 -350.54307) (xy 33.12597 -350.619748) (xy 33.08932 -350.693357) (xy 33.046034 -350.76327)
			(xy 32.996482 -350.828891) (xy 32.941086 -350.88966) (xy 32.880319 -350.945059) (xy 32.8147 -350.994614)
			(xy 32.744788 -351.037902) (xy 32.67118 -351.074555) (xy 32.594505 -351.10426) (xy 32.515415 -351.126764)
			(xy 32.434586 -351.141873) (xy 32.352708 -351.14946) (xy 32.311594 -351.14992) (xy 32.269984 -351.149442)
			(xy 32.187127 -351.141665) (xy 32.105358 -351.12619) (xy 32.025391 -351.10315) (xy 31.947922 -351.072748)
			(xy 31.873629 -351.035248) (xy 31.838138 -351.013522) (xy 31.82903 -351.008297) (xy 31.808293 -351.005101)
			(xy 31.788008 -351.010462) (xy 31.779464 -351.01657) (xy 31.745831 -351.042555) (xy 31.674437 -351.08868)
			(xy 31.598967 -351.127782) (xy 31.52011 -351.159503) (xy 31.438585 -351.183553) (xy 31.355138 -351.199714)
			(xy 31.270529 -351.207838) (xy 31.22803 -351.20834) (xy 31.186915 -351.207873) (xy 31.105035 -351.200288)
			(xy 31.024205 -351.185181) (xy 30.945114 -351.162679) (xy 30.868436 -351.132976) (xy 30.794826 -351.096324)
			(xy 30.724912 -351.053036) (xy 30.65929 -351.003482) (xy 30.598521 -350.948084) (xy 30.543123 -350.887316)
			(xy 30.493568 -350.821695) (xy 30.45028 -350.751781) (xy 30.413628 -350.678172) (xy 30.383923 -350.601494)
			(xy 30.361421 -350.522403) (xy 30.346313 -350.441573) (xy 30.338727 -350.359693) (xy 30.338268 -350.318578)
			(xy 30.33884 -350.273809) (xy 30.347847 -350.184724) (xy 30.36575 -350.096993) (xy 30.392366 -350.011501)
			(xy 30.409388 -349.97009) (xy 30.412968 -349.960503) (xy 30.41296 -349.940056) (xy 30.409388 -349.930466)
			(xy 30.392363 -349.889123) (xy 30.365757 -349.803758) (xy 30.347856 -349.716153) (xy 30.338841 -349.627193)
			(xy 30.338268 -349.582486) (xy 30.338268 -349.58147) (xy 30.338522 -349.57004) (xy 30.312044 -349.564091)
			(xy 30.259809 -349.54935) (xy 30.234128 -349.540576) (xy 30.225931 -349.538062) (xy 30.208797 -349.538062)
			(xy 30.2006 -349.540576) (xy 30.16538 -349.552528) (xy 30.093379 -349.571185) (xy 30.020059 -349.583696)
			(xy 29.945944 -349.589972) (xy 29.908754 -349.59036) (xy 29.871565 -349.589952) (xy 29.797452 -349.583667)
			(xy 29.724133 -349.571163) (xy 29.652126 -349.552528) (xy 29.616908 -349.540576) (xy 29.608711 -349.538062)
			(xy 29.591577 -349.538062) (xy 29.58338 -349.540576) (xy 29.548162 -349.552533) (xy 29.47616 -349.571189)
			(xy 29.402839 -349.583699) (xy 29.328724 -349.589973) (xy 29.291534 -349.59036) (xy 29.249596 -349.589881)
			(xy 29.166099 -349.581908) (xy 29.083738 -349.566035) (xy 29.003259 -349.542404) (xy 28.92539 -349.511231)
			(xy 28.850838 -349.472797) (xy 28.780276 -349.42745) (xy 28.714345 -349.375601) (xy 28.65364 -349.317719)
			(xy 28.598712 -349.25433) (xy 28.550059 -349.186006) (xy 28.508121 -349.113367) (xy 28.473277 -349.03707)
			(xy 28.445844 -348.957807) (xy 28.426069 -348.876294) (xy 28.414132 -348.793272) (xy 28.410141 -348.70949)
			(xy 2.509012 -348.70949) (xy 2.509012 -351.637854) (xy 73.92162 -351.637854) (xy 73.922073 -351.597287)
			(xy 73.929469 -351.516491) (xy 73.944194 -351.436705) (xy 73.966127 -351.358593) (xy 73.995085 -351.282803)
			(xy 74.012552 -351.246186) (xy 74.016468 -351.237096) (xy 74.017766 -351.217362) (xy 74.015092 -351.207832)
			(xy 74.000912 -351.162806) (xy 73.981012 -351.070523) (xy 73.971009 -350.97665) (xy 73.970388 -350.929448)
			(xy 73.970892 -350.887087) (xy 73.978945 -350.80275) (xy 73.994979 -350.71956) (xy 74.018847 -350.63827)
			(xy 74.050335 -350.559618) (xy 74.089157 -350.484315) (xy 74.13496 -350.413043) (xy 74.187331 -350.346447)
			(xy 74.245796 -350.285132) (xy 74.309824 -350.229651) (xy 74.378836 -350.180508) (xy 74.452206 -350.138148)
			(xy 74.529271 -350.102953) (xy 74.609333 -350.075244) (xy 74.691666 -350.05527) (xy 74.775525 -350.043213)
			(xy 74.86015 -350.039182) (xy 74.944775 -350.043213) (xy 75.028634 -350.05527) (xy 75.110967 -350.075244)
			(xy 75.191029 -350.102953) (xy 75.268094 -350.138148) (xy 75.341464 -350.180508) (xy 75.410476 -350.229651)
			(xy 75.474504 -350.285132) (xy 75.532969 -350.346447) (xy 75.58534 -350.413043) (xy 75.631143 -350.484315)
			(xy 75.669965 -350.559618) (xy 75.701453 -350.63827) (xy 75.725321 -350.71956) (xy 75.741355 -350.80275)
			(xy 75.749408 -350.887087) (xy 75.749912 -350.929448) (xy 75.749456 -350.970015) (xy 75.742061 -351.05081)
			(xy 75.727336 -351.130596) (xy 75.705403 -351.208709) (xy 75.676446 -351.284499) (xy 75.65898 -351.321116)
			(xy 75.655063 -351.330206) (xy 75.653765 -351.34994) (xy 75.65644 -351.35947) (xy 75.670621 -351.404496)
			(xy 75.69052 -351.496779) (xy 75.700524 -351.590652) (xy 75.70064 -351.5995) (xy 76.58354 -351.5995)
			(xy 76.583977 -351.558938) (xy 76.59131 -351.478148) (xy 76.605978 -351.398363) (xy 76.62786 -351.320247)
			(xy 76.656772 -351.244452) (xy 76.674218 -351.207832) (xy 76.67814 -351.198816) (xy 76.679575 -351.179224)
			(xy 76.677012 -351.169732) (xy 76.662856 -351.124831) (xy 76.642989 -351.0328) (xy 76.632962 -350.939185)
			(xy 76.632308 -350.89211) (xy 76.632308 -350.891094) (xy 76.632812 -350.848746) (xy 76.640863 -350.764432)
			(xy 76.656892 -350.681266) (xy 76.680753 -350.599999) (xy 76.712232 -350.521369) (xy 76.751043 -350.446088)
			(xy 76.796833 -350.374836) (xy 76.849189 -350.30826) (xy 76.907637 -350.246962) (xy 76.971647 -350.191497)
			(xy 77.040639 -350.142368) (xy 77.113989 -350.100019) (xy 77.191032 -350.064835) (xy 77.271071 -350.037133)
			(xy 77.35338 -350.017165) (xy 77.437215 -350.005112) (xy 77.521816 -350.001082) (xy 77.606417 -350.005112)
			(xy 77.690252 -350.017165) (xy 77.772561 -350.037133) (xy 77.8526 -350.064835) (xy 77.929643 -350.100019)
			(xy 78.002993 -350.142368) (xy 78.071985 -350.191497) (xy 78.135995 -350.246962) (xy 78.194443 -350.30826)
			(xy 78.246799 -350.374836) (xy 78.292589 -350.446088) (xy 78.3314 -350.521369) (xy 78.362879 -350.599999)
			(xy 78.38674 -350.681266) (xy 78.402769 -350.764432) (xy 78.41082 -350.848746) (xy 78.411324 -350.891094)
			(xy 78.411324 -350.891602) (xy 78.410897 -350.932113) (xy 78.403528 -351.0128) (xy 78.388844 -351.09248)
			(xy 78.366965 -351.170492) (xy 78.338074 -351.246189) (xy 78.320646 -351.282762) (xy 78.316728 -351.291779)
			(xy 78.315288 -351.31137) (xy 78.317852 -351.320862) (xy 78.33205 -351.365927) (xy 78.351954 -351.458296)
			(xy 78.361947 -351.552255) (xy 78.362556 -351.5995) (xy 78.362003 -351.645139) (xy 78.352699 -351.735943)
			(xy 78.334149 -351.825316) (xy 78.3209 -351.868994) (xy 78.318454 -351.878006) (xy 78.319496 -351.896634)
			(xy 78.322932 -351.905316) (xy 78.341634 -351.948394) (xy 78.370914 -352.03763) (xy 78.390624 -352.129456)
			(xy 78.400545 -352.222848) (xy 78.401164 -352.269806) (xy 78.400653 -352.312784) (xy 78.392364 -352.398339)
			(xy 78.375873 -352.482698) (xy 78.351334 -352.565076) (xy 78.335632 -352.605086) (xy 78.332346 -352.614331)
			(xy 78.332359 -352.633935) (xy 78.335632 -352.643186) (xy 78.351338 -352.683162) (xy 78.375884 -352.765474)
			(xy 78.392373 -352.84977) (xy 78.400651 -352.935265) (xy 78.401164 -352.978212) (xy 78.40066 -353.020573)
			(xy 78.392607 -353.10491) (xy 78.376573 -353.1881) (xy 78.352705 -353.26939) (xy 78.346936 -353.2838)
			(xy 182.729656 -353.2838) (xy 182.733646 -353.200045) (xy 182.745579 -353.117047) (xy 182.765347 -353.035561)
			(xy 182.792771 -352.956321) (xy 182.827603 -352.880048) (xy 182.869527 -352.807431) (xy 182.918163 -352.739127)
			(xy 182.973072 -352.675756) (xy 183.033756 -352.617891) (xy 183.099666 -352.566056) (xy 183.170204 -352.520721)
			(xy 183.244732 -352.482296) (xy 183.322575 -352.451129) (xy 183.403028 -352.427503) (xy 183.485362 -352.411631)
			(xy 183.568833 -352.403656) (xy 183.610758 -352.403156) (xy 183.611774 -352.403156) (xy 183.648831 -352.403571)
			(xy 183.72268 -352.409833) (xy 183.795742 -352.422272) (xy 183.867502 -352.440802) (xy 183.902604 -352.452686)
			(xy 183.910801 -352.4552) (xy 183.927935 -352.4552) (xy 183.936132 -352.452686) (xy 183.964337 -352.443048)
			(xy 184.021791 -352.42716) (xy 184.05094 -352.420936) (xy 184.060579 -352.41851) (xy 184.077071 -352.407448)
			(xy 184.088123 -352.390948) (xy 184.090564 -352.381312) (xy 184.100088 -352.337416) (xy 184.126813 -352.251655)
			(xy 184.143904 -352.210116) (xy 184.147468 -352.200525) (xy 184.147469 -352.180082) (xy 184.143904 -352.170492)
			(xy 184.126892 -352.12911) (xy 184.100271 -352.043685) (xy 184.082363 -351.956018) (xy 184.073351 -351.866996)
			(xy 184.072784 -351.822258) (xy 184.072784 -351.822004) (xy 184.073288 -351.779656) (xy 184.081339 -351.695342)
			(xy 184.097368 -351.612176) (xy 184.121229 -351.530909) (xy 184.152708 -351.452279) (xy 184.191519 -351.376998)
			(xy 184.237309 -351.305746) (xy 184.289665 -351.23917) (xy 184.348113 -351.177872) (xy 184.412123 -351.122407)
			(xy 184.481115 -351.073278) (xy 184.554465 -351.030929) (xy 184.631508 -350.995745) (xy 184.711547 -350.968043)
			(xy 184.793856 -350.948075) (xy 184.877691 -350.936022) (xy 184.962292 -350.931992) (xy 185.046893 -350.936022)
			(xy 185.130728 -350.948075) (xy 185.213037 -350.968043) (xy 185.293076 -350.995745) (xy 185.370119 -351.030929)
			(xy 185.443469 -351.073278) (xy 185.512461 -351.122407) (xy 185.576471 -351.177872) (xy 185.634919 -351.23917)
			(xy 185.687275 -351.305746) (xy 185.733065 -351.376998) (xy 185.771876 -351.452279) (xy 185.803355 -351.530909)
			(xy 185.827216 -351.612176) (xy 185.843245 -351.695342) (xy 185.851296 -351.779656) (xy 185.8518 -351.822004)
			(xy 185.8518 -351.822258) (xy 185.851234 -351.866996) (xy 185.842218 -351.956018) (xy 185.824312 -352.043685)
			(xy 185.797698 -352.129113) (xy 185.78068 -352.170492) (xy 185.777112 -352.180082) (xy 185.777113 -352.200525)
			(xy 185.78068 -352.210116) (xy 185.797704 -352.251527) (xy 185.824339 -352.337015) (xy 185.842246 -352.424746)
			(xy 185.851245 -352.513834) (xy 185.8518 -352.558604) (xy 185.85116 -352.609084) (xy 185.839825 -352.709404)
			(xy 185.829194 -352.758756) (xy 185.826997 -352.771225) (xy 185.833664 -352.795617) (xy 185.841894 -352.805238)
			(xy 185.882534 -352.847656) (xy 185.889646 -352.846132) (xy 185.898412 -352.843862) (xy 185.913646 -352.834103)
			(xy 185.919364 -352.827082) (xy 185.944527 -352.794419) (xy 185.999939 -352.733355) (xy 186.060764 -352.67768)
			(xy 186.126478 -352.627872) (xy 186.196519 -352.584357) (xy 186.270286 -352.547509) (xy 186.347146 -352.517645)
			(xy 186.426439 -352.49502) (xy 186.507485 -352.479828) (xy 186.589589 -352.472201) (xy 186.630818 -352.471736)
			(xy 186.671925 -352.472195) (xy 186.753788 -352.479781) (xy 186.834603 -352.494887) (xy 186.913679 -352.517383)
			(xy 186.990343 -352.547078) (xy 187.06394 -352.583719) (xy 187.133844 -352.626993) (xy 187.199457 -352.676531)
			(xy 187.260221 -352.73191) (xy 187.315617 -352.792659) (xy 187.365173 -352.85826) (xy 187.408465 -352.928152)
			(xy 187.445126 -353.001739) (xy 187.474841 -353.078395) (xy 187.497359 -353.157466) (xy 187.512486 -353.238276)
			(xy 187.519078 -353.3092) (xy 191.056256 -353.3092) (xy 191.060246 -353.225443) (xy 191.07218 -353.142444)
			(xy 191.091948 -353.060956) (xy 191.119373 -352.981715) (xy 191.154206 -352.90544) (xy 191.196132 -352.832822)
			(xy 191.244771 -352.764518) (xy 191.299682 -352.701146) (xy 191.360368 -352.643281) (xy 191.42628 -352.591447)
			(xy 191.49682 -352.546112) (xy 191.57135 -352.507688) (xy 191.649196 -352.476522) (xy 191.729651 -352.452897)
			(xy 191.811988 -352.437027) (xy 191.89546 -352.429055) (xy 191.937386 -352.428556) (xy 191.938402 -352.428556)
			(xy 191.975459 -352.428963) (xy 192.049308 -352.435227) (xy 192.12237 -352.447669) (xy 192.194131 -352.466201)
			(xy 192.229232 -352.478086) (xy 192.237429 -352.4806) (xy 192.254563 -352.4806) (xy 192.26276 -352.478086)
			(xy 192.290041 -352.468747) (xy 192.345585 -352.453243) (xy 192.373758 -352.447098) (xy 192.383527 -352.444576)
			(xy 192.400163 -352.433196) (xy 192.411142 -352.416293) (xy 192.413382 -352.406458) (xy 192.422838 -352.357349)
			(xy 192.451357 -352.261489) (xy 192.470278 -352.215196) (xy 192.473919 -352.205632) (xy 192.474045 -352.185185)
			(xy 192.470532 -352.175572) (xy 192.453515 -352.134192) (xy 192.426895 -352.048766) (xy 192.408989 -351.961099)
			(xy 192.399978 -351.872077) (xy 192.399412 -351.827338) (xy 192.399412 -351.827084) (xy 192.399916 -351.784736)
			(xy 192.407967 -351.700422) (xy 192.423996 -351.617256) (xy 192.447857 -351.535989) (xy 192.479336 -351.457359)
			(xy 192.518147 -351.382078) (xy 192.563937 -351.310826) (xy 192.616293 -351.24425) (xy 192.674741 -351.182952)
			(xy 192.738751 -351.127487) (xy 192.807743 -351.078358) (xy 192.881093 -351.036009) (xy 192.958136 -351.000825)
			(xy 193.038175 -350.973123) (xy 193.120484 -350.953155) (xy 193.204319 -350.941102) (xy 193.28892 -350.937072)
			(xy 193.373521 -350.941102) (xy 193.457356 -350.953155) (xy 193.539665 -350.973123) (xy 193.619704 -351.000825)
			(xy 193.696747 -351.036009) (xy 193.770097 -351.078358) (xy 193.839089 -351.127487) (xy 193.903099 -351.182952)
			(xy 193.961547 -351.24425) (xy 194.013903 -351.310826) (xy 194.059693 -351.382078) (xy 194.098504 -351.457359)
			(xy 194.129983 -351.535989) (xy 194.153844 -351.617256) (xy 194.169873 -351.700422) (xy 194.177924 -351.784736)
			(xy 194.178428 -351.827084) (xy 194.178428 -351.827338) (xy 194.177853 -351.872076) (xy 194.168839 -351.961098)
			(xy 194.150936 -352.048765) (xy 194.124325 -352.134193) (xy 194.107308 -352.175572) (xy 194.10375 -352.185165)
			(xy 194.103744 -352.205606) (xy 194.107308 -352.215196) (xy 194.12436 -352.256596) (xy 194.150986 -352.342088)
			(xy 194.165052 -352.41103) (xy 206.449676 -352.41103) (xy 206.449676 -351.54743) (xy 206.450162 -351.520179)
			(xy 206.457918 -351.466231) (xy 206.473273 -351.413936) (xy 206.495915 -351.364359) (xy 206.525381 -351.318509)
			(xy 206.561072 -351.277318) (xy 206.602263 -351.241627) (xy 206.648113 -351.212161) (xy 206.69769 -351.189519)
			(xy 206.749985 -351.174164) (xy 206.803933 -351.166408) (xy 206.858435 -351.166408) (xy 206.912383 -351.174164)
			(xy 206.964678 -351.189519) (xy 207.014255 -351.212161) (xy 207.060105 -351.241627) (xy 207.101296 -351.277318)
			(xy 207.136987 -351.318509) (xy 207.166453 -351.364359) (xy 207.189095 -351.413936) (xy 207.20445 -351.466231)
			(xy 207.212206 -351.520179) (xy 207.212692 -351.54743) (xy 207.212692 -352.41103) (xy 207.212206 -352.438281)
			(xy 207.20445 -352.492229) (xy 207.189095 -352.544524) (xy 207.166453 -352.594101) (xy 207.136987 -352.639951)
			(xy 207.101296 -352.681142) (xy 207.060105 -352.716833) (xy 207.014255 -352.746299) (xy 206.964678 -352.768941)
			(xy 206.912383 -352.784296) (xy 206.858435 -352.792052) (xy 206.803933 -352.792052) (xy 206.749985 -352.784296)
			(xy 206.69769 -352.768941) (xy 206.648113 -352.746299) (xy 206.602263 -352.716833) (xy 206.561072 -352.681142)
			(xy 206.525381 -352.639951) (xy 206.495915 -352.594101) (xy 206.473273 -352.544524) (xy 206.457918 -352.492229)
			(xy 206.450162 -352.438281) (xy 206.449676 -352.41103) (xy 194.165052 -352.41103) (xy 194.168886 -352.429823)
			(xy 194.177877 -352.518913) (xy 194.178428 -352.563684) (xy 194.178055 -352.600778) (xy 194.171875 -352.674709)
			(xy 194.159556 -352.747868) (xy 194.150742 -352.783902) (xy 194.149 -352.792252) (xy 194.15051 -352.809229)
			(xy 194.157543 -352.824754) (xy 194.163188 -352.831146) (xy 194.203574 -352.874326) (xy 194.216274 -352.871532)
			(xy 194.225043 -352.869274) (xy 194.240276 -352.859506) (xy 194.245992 -352.852482) (xy 194.271138 -352.819805)
			(xy 194.326552 -352.758742) (xy 194.387379 -352.703068) (xy 194.453095 -352.65326) (xy 194.523138 -352.609746)
			(xy 194.596907 -352.5729) (xy 194.673768 -352.543037) (xy 194.753063 -352.520414) (xy 194.834111 -352.505225)
			(xy 194.916217 -352.4976) (xy 194.957446 -352.497136) (xy 194.998553 -352.497569) (xy 195.080417 -352.505157)
			(xy 195.161232 -352.520265) (xy 195.240309 -352.542764) (xy 195.316973 -352.572461) (xy 195.390571 -352.609104)
			(xy 195.460474 -352.652379) (xy 195.526087 -352.701919) (xy 195.586851 -352.757301) (xy 195.642247 -352.818051)
			(xy 195.691802 -352.883653) (xy 195.735094 -352.953546) (xy 195.744851 -352.973132) (xy 338.849208 -352.973132)
			(xy 338.849825 -352.926972) (xy 338.859426 -352.835153) (xy 338.878488 -352.744823) (xy 338.906804 -352.656953)
			(xy 338.9249 -352.614484) (xy 338.928699 -352.60454) (xy 338.928703 -352.583278) (xy 338.9249 -352.573336)
			(xy 338.90688 -352.530918) (xy 338.878719 -352.443158) (xy 338.859786 -352.352956) (xy 338.850284 -352.26128)
			(xy 338.849716 -352.215196) (xy 338.850295 -352.1688) (xy 338.859941 -352.076512) (xy 338.879138 -351.985728)
			(xy 338.907678 -351.897435) (xy 338.925916 -351.85477) (xy 338.929722 -351.844828) (xy 338.929721 -351.823565)
			(xy 338.925916 -351.813622) (xy 338.907694 -351.771019) (xy 338.879176 -351.682852) (xy 338.859983 -351.592196)
			(xy 338.850324 -351.500036) (xy 338.849716 -351.453704) (xy 338.849716 -351.453196) (xy 338.850148 -351.412092)
			(xy 338.857734 -351.330235) (xy 338.87284 -351.249427) (xy 338.895338 -351.170357) (xy 338.925036 -351.093701)
			(xy 338.96168 -351.020112) (xy 339.004958 -350.950218) (xy 339.0545 -350.884616) (xy 339.109884 -350.823864)
			(xy 339.170637 -350.768482) (xy 339.236241 -350.718942) (xy 339.306137 -350.675666) (xy 339.379727 -350.639025)
			(xy 339.456384 -350.609329) (xy 339.535454 -350.586834) (xy 339.616263 -350.57173) (xy 339.69812 -350.564147)
			(xy 339.739224 -350.563688) (xy 339.739732 -350.563688) (xy 339.786063 -350.564321) (xy 339.87822 -350.573985)
			(xy 339.968874 -350.593172) (xy 340.057044 -350.621677) (xy 340.09965 -350.639888) (xy 340.109592 -350.643694)
			(xy 340.130856 -350.643694) (xy 340.140798 -350.639888) (xy 340.183457 -350.621635) (xy 340.27175 -350.593093)
			(xy 340.362537 -350.573902) (xy 340.454828 -350.564272) (xy 340.501224 -350.563688) (xy 340.547619 -350.564298)
			(xy 340.639906 -350.573935) (xy 340.73069 -350.593123) (xy 340.818984 -350.621654) (xy 340.86165 -350.639888)
			(xy 340.871592 -350.643694) (xy 340.892856 -350.643694) (xy 340.902798 -350.639888) (xy 340.945457 -350.621635)
			(xy 341.03375 -350.593093) (xy 341.124537 -350.573902) (xy 341.216828 -350.564272) (xy 341.263224 -350.563688)
			(xy 341.309619 -350.564298) (xy 341.401906 -350.573935) (xy 341.49269 -350.593123) (xy 341.580984 -350.621654)
			(xy 341.62365 -350.639888) (xy 341.633592 -350.643694) (xy 341.654856 -350.643694) (xy 341.664798 -350.639888)
			(xy 341.707457 -350.621635) (xy 341.79575 -350.593093) (xy 341.886537 -350.573902) (xy 341.978828 -350.564272)
			(xy 342.025224 -350.563688) (xy 342.071619 -350.564298) (xy 342.163906 -350.573935) (xy 342.25469 -350.593123)
			(xy 342.342984 -350.621654) (xy 342.38565 -350.639888) (xy 342.395592 -350.643694) (xy 342.416856 -350.643694)
			(xy 342.426798 -350.639888) (xy 342.469457 -350.621635) (xy 342.55775 -350.593093) (xy 342.648537 -350.573902)
			(xy 342.740828 -350.564272) (xy 342.787224 -350.563688) (xy 342.833689 -350.564308) (xy 342.926112 -350.573988)
			(xy 343.017025 -350.593241) (xy 343.105438 -350.621857) (xy 343.148158 -350.640142) (xy 343.156911 -350.643584)
			(xy 343.175683 -350.644482) (xy 343.184734 -350.64192) (xy 343.230109 -350.62753) (xy 343.323147 -350.607378)
			(xy 343.417806 -350.597287) (xy 343.465404 -350.596708) (xy 343.506508 -350.597148) (xy 343.588364 -350.604734)
			(xy 343.669172 -350.61984) (xy 343.748241 -350.642338) (xy 343.824897 -350.672035) (xy 343.898486 -350.708679)
			(xy 343.968379 -350.751956) (xy 344.033982 -350.801498) (xy 344.094733 -350.856881) (xy 344.150115 -350.917634)
			(xy 344.199655 -350.983237) (xy 344.242931 -351.053132) (xy 344.279573 -351.126721) (xy 344.309269 -351.203378)
			(xy 344.331765 -351.282448) (xy 344.346869 -351.363255) (xy 344.354453 -351.445112) (xy 344.354912 -351.486216)
			(xy 344.354912 -351.486724) (xy 344.354311 -351.533056) (xy 344.344638 -351.625214) (xy 344.325441 -351.715868)
			(xy 344.296928 -351.804037) (xy 344.278712 -351.846642) (xy 344.274897 -351.856581) (xy 344.274903 -351.877848)
			(xy 344.278712 -351.88779) (xy 344.296962 -351.93045) (xy 344.325505 -352.018743) (xy 344.344696 -352.109529)
			(xy 344.354328 -352.20182) (xy 344.354912 -352.248216) (xy 344.354328 -352.294369) (xy 344.344776 -352.386179)
			(xy 344.325776 -352.476508) (xy 344.297531 -352.564386) (xy 344.279474 -352.606864) (xy 344.275648 -352.6168)
			(xy 344.275662 -352.638069) (xy 344.279474 -352.648012) (xy 344.29749 -352.690438) (xy 344.325707 -352.77819)
			(xy 344.344711 -352.868387) (xy 344.354297 -352.960064) (xy 344.354912 -353.006152) (xy 344.354402 -353.047262)
			(xy 344.34922 -353.1032) (xy 423.453493 -353.1032) (xy 423.457484 -353.019415) (xy 423.469422 -352.936388)
			(xy 423.489198 -352.854872) (xy 423.516634 -352.775605) (xy 423.55148 -352.699305) (xy 423.593421 -352.626663)
			(xy 423.642078 -352.558337) (xy 423.697009 -352.494945) (xy 423.757718 -352.437063) (xy 423.823654 -352.385213)
			(xy 423.89422 -352.339866) (xy 423.968777 -352.301432) (xy 424.04665 -352.270259) (xy 424.127133 -352.24663)
			(xy 424.209499 -352.230759) (xy 424.293 -352.222789) (xy 424.33494 -352.222308) (xy 424.372129 -352.222714)
			(xy 424.446242 -352.228999) (xy 424.519562 -352.241503) (xy 424.591568 -352.260139) (xy 424.626786 -352.272092)
			(xy 424.634983 -352.274606) (xy 424.652117 -352.274606) (xy 424.660314 -352.272092) (xy 424.687596 -352.262757)
			(xy 424.74314 -352.24725) (xy 424.771312 -352.241104) (xy 424.781089 -352.238609) (xy 424.797722 -352.227214)
			(xy 424.808697 -352.210302) (xy 424.810936 -352.200464) (xy 424.820391 -352.151355) (xy 424.84891 -352.055495)
			(xy 424.867832 -352.009202) (xy 424.871403 -351.999613) (xy 424.871399 -351.979169) (xy 424.867832 -351.969578)
			(xy 424.850786 -351.928175) (xy 424.824155 -351.842685) (xy 424.806254 -351.754951) (xy 424.797263 -351.665861)
			(xy 424.796712 -351.62109) (xy 424.797216 -351.578729) (xy 424.805269 -351.494392) (xy 424.821303 -351.411202)
			(xy 424.845171 -351.329912) (xy 424.876659 -351.25126) (xy 424.915481 -351.175957) (xy 424.961284 -351.104685)
			(xy 425.013655 -351.038089) (xy 425.07212 -350.976774) (xy 425.136148 -350.921293) (xy 425.20516 -350.87215)
			(xy 425.27853 -350.82979) (xy 425.355595 -350.794595) (xy 425.435657 -350.766886) (xy 425.51799 -350.746912)
			(xy 425.601849 -350.734855) (xy 425.686474 -350.730824) (xy 425.771099 -350.734855) (xy 425.854958 -350.746912)
			(xy 425.937291 -350.766886) (xy 426.017353 -350.794595) (xy 426.094418 -350.82979) (xy 426.167788 -350.87215)
			(xy 426.2368 -350.921293) (xy 426.300828 -350.976774) (xy 426.359293 -351.038089) (xy 426.411664 -351.104685)
			(xy 426.457467 -351.175957) (xy 426.496289 -351.25126) (xy 426.527777 -351.329912) (xy 426.551645 -351.411202)
			(xy 426.567679 -351.494392) (xy 426.575732 -351.578729) (xy 426.576236 -351.62109) (xy 426.575653 -351.665859)
			(xy 426.566649 -351.754944) (xy 426.548749 -351.842675) (xy 426.522136 -351.928167) (xy 426.505116 -351.969578)
			(xy 426.501559 -351.979171) (xy 426.501555 -351.999611) (xy 426.505116 -352.009202) (xy 426.522153 -352.050608)
			(xy 426.548787 -352.136097) (xy 426.566691 -352.22383) (xy 426.575684 -352.312919) (xy 426.576236 -352.35769)
			(xy 426.575843 -352.394784) (xy 426.569667 -352.468714) (xy 426.557358 -352.541873) (xy 426.54855 -352.577908)
			(xy 426.5467 -352.586267) (xy 426.54815 -352.603318) (xy 426.55512 -352.618947) (xy 426.560742 -352.625406)
			(xy 426.601128 -352.668332) (xy 426.613574 -352.665538) (xy 426.622391 -352.663274) (xy 426.637739 -352.653501)
			(xy 426.643546 -352.646488) (xy 426.66867 -352.613784) (xy 426.724067 -352.552685) (xy 426.784882 -352.496976)
			(xy 426.850593 -352.447136) (xy 426.920635 -352.403592) (xy 426.994408 -352.366719) (xy 427.071277 -352.336834)
			(xy 427.150582 -352.314192) (xy 427.231643 -352.298989) (xy 427.313763 -352.291354) (xy 427.355 -352.290888)
			(xy 427.396111 -352.291352) (xy 427.477981 -352.29894) (xy 427.558801 -352.314051) (xy 427.637882 -352.336556)
			(xy 427.714549 -352.366262) (xy 427.788147 -352.402918) (xy 427.858049 -352.446208) (xy 427.923657 -352.495765)
			(xy 427.984412 -352.551165) (xy 428.039795 -352.611935) (xy 428.089333 -352.677557) (xy 428.132604 -352.747471)
			(xy 428.169239 -352.82108) (xy 428.198924 -352.897755) (xy 428.221406 -352.976842) (xy 428.236494 -353.057667)
			(xy 428.243048 -353.1286) (xy 431.780208 -353.1286) (xy 431.784199 -353.04482) (xy 431.796136 -352.961799)
			(xy 431.815909 -352.880289) (xy 431.843342 -352.801027) (xy 431.878184 -352.724732) (xy 431.92012 -352.652094)
			(xy 431.968771 -352.583771) (xy 432.023696 -352.520381) (xy 432.084398 -352.4625) (xy 432.150327 -352.410651)
			(xy 432.220886 -352.365303) (xy 432.295436 -352.326868) (xy 432.373301 -352.295693) (xy 432.453778 -352.27206)
			(xy 432.536136 -352.256184) (xy 432.619631 -352.248208) (xy 432.661568 -352.247708) (xy 432.698757 -352.248106)
			(xy 432.77287 -352.254393) (xy 432.84619 -352.2669) (xy 432.918196 -352.285538) (xy 432.953414 -352.297492)
			(xy 432.961611 -352.300006) (xy 432.978745 -352.300006) (xy 432.986942 -352.297492) (xy 433.014223 -352.288155)
			(xy 433.069768 -352.27265) (xy 433.09794 -352.266504) (xy 433.107722 -352.264025) (xy 433.124353 -352.252622)
			(xy 433.135327 -352.235704) (xy 433.137564 -352.225864) (xy 433.147017 -352.176755) (xy 433.175537 -352.080895)
			(xy 433.19446 -352.034602) (xy 433.19803 -352.025013) (xy 433.198026 -352.004569) (xy 433.19446 -351.994978)
			(xy 433.177416 -351.953575) (xy 433.150784 -351.868085) (xy 433.132882 -351.780351) (xy 433.123891 -351.691261)
			(xy 433.12334 -351.64649) (xy 433.123844 -351.604129) (xy 433.131897 -351.519792) (xy 433.147931 -351.436602)
			(xy 433.171799 -351.355312) (xy 433.203287 -351.27666) (xy 433.242109 -351.201357) (xy 433.287912 -351.130085)
			(xy 433.340283 -351.063489) (xy 433.398748 -351.002174) (xy 433.462776 -350.946693) (xy 433.531788 -350.89755)
			(xy 433.605158 -350.85519) (xy 433.682223 -350.819995) (xy 433.762285 -350.792286) (xy 433.844618 -350.772312)
			(xy 433.928477 -350.760255) (xy 434.013102 -350.756224) (xy 434.097727 -350.760255) (xy 434.181586 -350.772312)
			(xy 434.263919 -350.792286) (xy 434.343981 -350.819995) (xy 434.421046 -350.85519) (xy 434.494416 -350.89755)
			(xy 434.563428 -350.946693) (xy 434.627456 -351.002174) (xy 434.685921 -351.063489) (xy 434.738292 -351.130085)
			(xy 434.784095 -351.201357) (xy 434.822917 -351.27666) (xy 434.854405 -351.355312) (xy 434.878273 -351.436602)
			(xy 434.894307 -351.519792) (xy 434.90236 -351.604129) (xy 434.902864 -351.64649) (xy 434.902279 -351.691259)
			(xy 434.893275 -351.780343) (xy 434.875376 -351.868074) (xy 434.848764 -351.953566) (xy 434.831744 -351.994978)
			(xy 434.828186 -352.00457) (xy 434.828182 -352.025011) (xy 434.831744 -352.034602) (xy 434.848782 -352.076008)
			(xy 434.875415 -352.161497) (xy 434.893319 -352.24923) (xy 434.902312 -352.338319) (xy 434.902864 -352.38309)
			(xy 434.90247 -352.420184) (xy 434.896295 -352.494114) (xy 434.883986 -352.567273) (xy 434.875178 -352.603308)
			(xy 434.873347 -352.611669) (xy 434.874795 -352.628716) (xy 434.881755 -352.644345) (xy 434.88737 -352.650806)
			(xy 434.927756 -352.693732) (xy 434.940202 -352.690938) (xy 434.94901 -352.688645) (xy 434.964363 -352.678893)
			(xy 434.970174 -352.671888) (xy 434.995281 -352.639171) (xy 435.05068 -352.578072) (xy 435.111497 -352.522364)
			(xy 435.17721 -352.472524) (xy 435.247255 -352.428982) (xy 435.321029 -352.39211) (xy 435.3979 -352.362226)
			(xy 435.477207 -352.339586) (xy 435.558269 -352.324385) (xy 435.64039 -352.316753) (xy 435.681628 -352.316288)
			(xy 435.722739 -352.316726) (xy 435.80461 -352.324316) (xy 435.885431 -352.339429) (xy 435.964512 -352.361936)
			(xy 436.041179 -352.391645) (xy 436.114778 -352.428302) (xy 436.184679 -352.471595) (xy 436.250287 -352.521154)
			(xy 436.311041 -352.576555) (xy 436.366424 -352.637327) (xy 436.415962 -352.70295) (xy 436.459233 -352.772865)
			(xy 436.495867 -352.846475) (xy 436.525552 -352.923151) (xy 436.548034 -353.00224) (xy 436.563122 -353.083066)
			(xy 436.570687 -353.164939) (xy 436.571136 -353.20605) (xy 436.570568 -353.25082) (xy 436.561569 -353.339906)
			(xy 436.543667 -353.427639) (xy 436.517044 -353.513129) (xy 436.500016 -353.554538) (xy 436.496425 -353.564121)
			(xy 436.496444 -353.58457) (xy 436.500016 -353.594162) (xy 436.517052 -353.635569) (xy 436.543684 -353.721058)
			(xy 436.561588 -353.808791) (xy 436.570583 -353.897879) (xy 436.571136 -353.94265) (xy 436.570568 -353.98742)
			(xy 436.561569 -354.076506) (xy 436.543667 -354.164239) (xy 436.517044 -354.249729) (xy 436.500016 -354.291138)
			(xy 436.496425 -354.300721) (xy 436.496444 -354.32117) (xy 436.500016 -354.330762) (xy 436.517046 -354.372136)
			(xy 436.543663 -354.457564) (xy 436.561565 -354.545233) (xy 436.570572 -354.634257) (xy 436.571136 -354.678996)
			(xy 436.571136 -354.67925) (xy 436.57064 -354.720357) (xy 436.56306 -354.80222) (xy 436.547959 -354.883035)
			(xy 436.525468 -354.962112) (xy 436.495777 -355.038776) (xy 436.45914 -355.112375) (xy 436.415869 -355.18228)
			(xy 436.366333 -355.247894) (xy 436.310956 -355.308659) (xy 436.250208 -355.364056) (xy 436.184609 -355.413612)
			(xy 436.114718 -355.456904) (xy 436.041131 -355.493565) (xy 435.964475 -355.523279) (xy 435.885405 -355.545796)
			(xy 435.804595 -355.560921) (xy 435.722735 -355.568527) (xy 435.681628 -355.569012) (xy 435.640018 -355.568519)
			(xy 435.557162 -355.560745) (xy 435.475393 -355.545272) (xy 435.395426 -355.522236) (xy 435.317957 -355.491836)
			(xy 435.243663 -355.454339) (xy 435.208172 -355.432614) (xy 435.199049 -355.42742) (xy 435.178322 -355.424214)
			(xy 435.158043 -355.429561) (xy 435.149498 -355.435662) (xy 435.115852 -355.46163) (xy 435.044461 -355.507757)
			(xy 434.968993 -355.546861) (xy 434.890138 -355.578584) (xy 434.808616 -355.602638) (xy 434.72517 -355.618802)
			(xy 434.640562 -355.626929) (xy 434.598064 -355.627432) (xy 434.556953 -355.626982) (xy 434.475084 -355.619391)
			(xy 434.394263 -355.604278) (xy 434.315183 -355.581771) (xy 434.238517 -355.552062) (xy 434.164919 -355.515405)
			(xy 434.095019 -355.472113) (xy 434.029411 -355.422555) (xy 433.968657 -355.367155) (xy 433.913275 -355.306384)
			(xy 433.863736 -355.240762) (xy 433.820465 -355.170848) (xy 433.783831 -355.09724) (xy 433.754145 -355.020565)
			(xy 433.731661 -354.941477) (xy 433.716572 -354.860653) (xy 433.709006 -354.778781) (xy 433.708556 -354.73767)
			(xy 433.709098 -354.692899) (xy 433.718104 -354.603812) (xy 433.736014 -354.51608) (xy 433.762645 -354.430591)
			(xy 433.779676 -354.389182) (xy 433.783256 -354.379596) (xy 433.783245 -354.359149) (xy 433.779676 -354.349558)
			(xy 433.762646 -354.308149) (xy 433.736013 -354.222661) (xy 433.718107 -354.134928) (xy 433.70911 -354.045841)
			(xy 433.708556 -354.00107) (xy 433.708556 -353.989132) (xy 433.682076 -353.983189) (xy 433.629842 -353.968444)
			(xy 433.604162 -353.959668) (xy 433.595965 -353.957154) (xy 433.578831 -353.957154) (xy 433.570634 -353.959668)
			(xy 433.535422 -353.971642) (xy 433.463417 -353.990292) (xy 433.390095 -354.002797) (xy 433.315979 -354.009067)
			(xy 433.278788 -354.009452) (xy 433.241598 -354.009064) (xy 433.167486 -354.002773) (xy 433.094166 -353.990263)
			(xy 433.02216 -353.971623) (xy 432.986942 -353.959668) (xy 432.978745 -353.957154) (xy 432.961611 -353.957154)
			(xy 432.953414 -353.959668) (xy 432.918203 -353.971647) (xy 432.846198 -353.990296) (xy 432.772875 -354.0028)
			(xy 432.698759 -354.009068) (xy 432.661568 -354.009452) (xy 432.619631 -354.008992) (xy 432.536136 -354.001016)
			(xy 432.453778 -353.98514) (xy 432.373301 -353.961507) (xy 432.295436 -353.930332) (xy 432.220886 -353.891897)
			(xy 432.150327 -353.846549) (xy 432.084398 -353.7947) (xy 432.023696 -353.736819) (xy 431.968771 -353.673429)
			(xy 431.92012 -353.605106) (xy 431.878184 -353.532468) (xy 431.843342 -353.456173) (xy 431.815909 -353.376911)
			(xy 431.796136 -353.295401) (xy 431.784199 -353.21238) (xy 431.780208 -353.1286) (xy 428.243048 -353.1286)
			(xy 428.244059 -353.139539) (xy 428.244508 -353.18065) (xy 428.243935 -353.22542) (xy 428.234936 -353.314506)
			(xy 428.217036 -353.402238) (xy 428.190415 -353.487729) (xy 428.173388 -353.529138) (xy 428.169793 -353.53872)
			(xy 428.169812 -353.559171) (xy 428.173388 -353.568762) (xy 428.190428 -353.610167) (xy 428.217058 -353.695657)
			(xy 428.23496 -353.783391) (xy 428.243955 -353.872479) (xy 428.244508 -353.91725) (xy 428.243935 -353.96202)
			(xy 428.234936 -354.051106) (xy 428.217036 -354.138838) (xy 428.190415 -354.224329) (xy 428.173388 -354.265738)
			(xy 428.169793 -354.27532) (xy 428.169812 -354.295771) (xy 428.173388 -354.305362) (xy 428.190417 -354.346737)
			(xy 428.217034 -354.432165) (xy 428.234937 -354.519833) (xy 428.243944 -354.608857) (xy 428.244508 -354.653596)
			(xy 428.244508 -354.65385) (xy 428.24394 -354.694955) (xy 428.23636 -354.776814) (xy 428.221262 -354.857624)
			(xy 428.198773 -354.936698) (xy 428.169085 -355.013359) (xy 428.132451 -355.086955) (xy 428.089184 -355.156857)
			(xy 428.039654 -355.22247) (xy 427.984281 -355.283233) (xy 427.923539 -355.33863) (xy 427.857946 -355.388186)
			(xy 427.788061 -355.431481) (xy 427.714479 -355.468143) (xy 427.63783 -355.497861) (xy 427.558765 -355.520382)
			(xy 427.47796 -355.535512) (xy 427.396104 -355.543124) (xy 427.355 -355.543612) (xy 427.31339 -355.543132)
			(xy 427.230533 -355.535356) (xy 427.148764 -355.519881) (xy 427.068797 -355.496842) (xy 426.991328 -355.46644)
			(xy 426.917035 -355.42894) (xy 426.881544 -355.407214) (xy 426.872433 -355.401996) (xy 426.851698 -355.398798)
			(xy 426.831415 -355.404156) (xy 426.82287 -355.410262) (xy 426.789234 -355.436243) (xy 426.717841 -355.482369)
			(xy 426.642371 -355.521471) (xy 426.563514 -355.553192) (xy 426.481991 -355.577244) (xy 426.398543 -355.593405)
			(xy 426.313935 -355.60153) (xy 426.271436 -355.602032) (xy 426.230327 -355.601513) (xy 426.148459 -355.593929)
			(xy 426.06764 -355.578822) (xy 425.98856 -355.556321) (xy 425.911894 -355.526617) (xy 425.838297 -355.489966)
			(xy 425.768396 -355.446679) (xy 425.702788 -355.397126) (xy 425.642034 -355.341729) (xy 425.58665 -355.280962)
			(xy 425.537111 -355.215344) (xy 425.49384 -355.145433) (xy 425.457204 -355.071828) (xy 425.427518 -354.995156)
			(xy 425.405034 -354.916071) (xy 425.389944 -354.835249) (xy 425.382378 -354.753379) (xy 425.381928 -354.71227)
			(xy 425.382471 -354.667499) (xy 425.391478 -354.578412) (xy 425.409387 -354.49068) (xy 425.436017 -354.40519)
			(xy 425.453048 -354.363782) (xy 425.45663 -354.354196) (xy 425.456619 -354.333749) (xy 425.453048 -354.324158)
			(xy 425.436017 -354.28275) (xy 425.409384 -354.197261) (xy 425.391479 -354.109528) (xy 425.382482 -354.020441)
			(xy 425.381928 -353.97567) (xy 425.381928 -353.963732) (xy 425.35545 -353.957782) (xy 425.303215 -353.943042)
			(xy 425.277534 -353.934268) (xy 425.269337 -353.931754) (xy 425.252203 -353.931754) (xy 425.244006 -353.934268)
			(xy 425.208787 -353.946222) (xy 425.136785 -353.964878) (xy 425.063465 -353.977388) (xy 424.98935 -353.983664)
			(xy 424.95216 -353.984052) (xy 424.914971 -353.983643) (xy 424.840858 -353.977359) (xy 424.767539 -353.964855)
			(xy 424.695532 -353.94622) (xy 424.660314 -353.934268) (xy 424.652117 -353.931754) (xy 424.634983 -353.931754)
			(xy 424.626786 -353.934268) (xy 424.591569 -353.946227) (xy 424.519566 -353.964882) (xy 424.446245 -353.977391)
			(xy 424.37213 -353.983665) (xy 424.33494 -353.984052) (xy 424.293 -353.983611) (xy 424.209499 -353.975641)
			(xy 424.127133 -353.95977) (xy 424.04665 -353.936141) (xy 423.968777 -353.904968) (xy 423.89422 -353.866534)
			(xy 423.823654 -353.821187) (xy 423.757718 -353.769337) (xy 423.697009 -353.711455) (xy 423.642078 -353.648063)
			(xy 423.593421 -353.579737) (xy 423.55148 -353.507095) (xy 423.516634 -353.430795) (xy 423.489198 -353.351528)
			(xy 423.469422 -353.270012) (xy 423.457484 -353.186985) (xy 423.453493 -353.1032) (xy 344.34922 -353.1032)
			(xy 344.346818 -353.129131) (xy 344.331712 -353.20995) (xy 344.309211 -353.289031) (xy 344.279508 -353.365698)
			(xy 344.242856 -353.439296) (xy 344.199569 -353.509197) (xy 344.150015 -353.574806) (xy 344.094618 -353.635561)
			(xy 344.03385 -353.690944) (xy 343.968231 -353.740483) (xy 343.898319 -353.783755) (xy 343.824713 -353.82039)
			(xy 343.748039 -353.850075) (xy 343.668954 -353.872558) (xy 343.58813 -353.887646) (xy 343.50626 -353.895211)
			(xy 343.46515 -353.89566) (xy 343.421566 -353.895134) (xy 343.334811 -353.886653) (xy 343.249302 -353.869729)
			(xy 343.165858 -353.844524) (xy 343.085279 -353.81128) (xy 343.046558 -353.791266) (xy 343.035092 -353.785848)
			(xy 343.009764 -353.785848) (xy 342.998298 -353.791266) (xy 342.959077 -353.812027) (xy 342.877306 -353.846516)
			(xy 342.792508 -353.872694) (xy 342.705525 -353.890299) (xy 342.617221 -353.899159) (xy 342.572848 -353.899724)
			(xy 342.534532 -353.899341) (xy 342.458179 -353.892813) (xy 342.382672 -353.879733) (xy 342.308573 -353.860197)
			(xy 342.272366 -353.847654) (xy 342.26405 -353.845068) (xy 342.246646 -353.845068) (xy 342.23833 -353.847654)
			(xy 342.202121 -353.860189) (xy 342.128019 -353.879707) (xy 342.052513 -353.892787) (xy 341.976163 -353.899332)
			(xy 341.937848 -353.899724) (xy 341.899532 -353.899341) (xy 341.823179 -353.892813) (xy 341.747672 -353.879733)
			(xy 341.673573 -353.860197) (xy 341.637366 -353.847654) (xy 341.62905 -353.845068) (xy 341.611646 -353.845068)
			(xy 341.60333 -353.847654) (xy 341.567121 -353.860189) (xy 341.493019 -353.879707) (xy 341.417513 -353.892787)
			(xy 341.341163 -353.899332) (xy 341.302848 -353.899724) (xy 341.264532 -353.899341) (xy 341.188179 -353.892813)
			(xy 341.112672 -353.879733) (xy 341.038573 -353.860197) (xy 341.002366 -353.847654) (xy 340.99405 -353.845068)
			(xy 340.976646 -353.845068) (xy 340.96833 -353.847654) (xy 340.932121 -353.860189) (xy 340.858019 -353.879707)
			(xy 340.782513 -353.892787) (xy 340.706163 -353.899332) (xy 340.667848 -353.899724) (xy 340.626539 -353.899263)
			(xy 340.544274 -353.89164) (xy 340.463071 -353.876418) (xy 340.38363 -353.853729) (xy 340.306637 -353.823768)
			(xy 340.232755 -353.786793) (xy 340.19744 -353.765358) (xy 340.189803 -353.761082) (xy 340.172701 -353.75742)
			(xy 340.155358 -353.759679) (xy 340.147402 -353.763326) (xy 340.109501 -353.782381) (xy 340.030769 -353.813979)
			(xy 339.949386 -353.837938) (xy 339.866091 -353.85404) (xy 339.781642 -353.862138) (xy 339.739224 -353.86264)
			(xy 339.73897 -353.86264) (xy 339.697862 -353.862216) (xy 339.615997 -353.854629) (xy 339.535181 -353.839522)
			(xy 339.456103 -353.817024) (xy 339.379438 -353.787327) (xy 339.30584 -353.750684) (xy 339.235936 -353.707408)
			(xy 339.170322 -353.657867) (xy 339.109558 -353.602485) (xy 339.054162 -353.541734) (xy 339.004606 -353.476131)
			(xy 338.961314 -353.406237) (xy 338.924655 -353.332646) (xy 338.89494 -353.255988) (xy 338.872425 -353.176916)
			(xy 338.857299 -353.096103) (xy 338.849693 -353.01424) (xy 338.849208 -352.973132) (xy 195.744851 -352.973132)
			(xy 195.771754 -353.027135) (xy 195.80147 -353.103792) (xy 195.823987 -353.182863) (xy 195.839114 -353.263674)
			(xy 195.846722 -353.345537) (xy 195.847208 -353.386644) (xy 195.846646 -353.431414) (xy 195.837635 -353.520499)
			(xy 195.81973 -353.60823) (xy 195.793111 -353.693721) (xy 195.776088 -353.735132) (xy 195.772497 -353.744715)
			(xy 195.772513 -353.765165) (xy 195.776088 -353.774756) (xy 195.793114 -353.816166) (xy 195.81975 -353.901654)
			(xy 195.837657 -353.989386) (xy 195.846654 -354.078474) (xy 195.847208 -354.123244) (xy 195.846646 -354.168014)
			(xy 195.837635 -354.257099) (xy 195.81973 -354.34483) (xy 195.793111 -354.430321) (xy 195.776088 -354.471732)
			(xy 195.772497 -354.481315) (xy 195.772513 -354.501765) (xy 195.776088 -354.511356) (xy 195.793114 -354.552766)
			(xy 195.81975 -354.638254) (xy 195.837657 -354.725986) (xy 195.846654 -354.815074) (xy 195.847208 -354.859844)
			(xy 195.84679 -354.900955) (xy 195.839198 -354.982827) (xy 195.824083 -355.063648) (xy 195.801575 -355.14273)
			(xy 195.771864 -355.219398) (xy 195.742079 -355.279198) (xy 285.476188 -355.279198) (xy 285.476597 -355.238082)
			(xy 285.484185 -355.1562) (xy 285.499295 -355.075367) (xy 285.5218 -354.996274) (xy 285.551507 -354.919594)
			(xy 285.588163 -354.845983) (xy 285.631455 -354.776069) (xy 285.681013 -354.710447) (xy 285.736414 -354.649677)
			(xy 285.797187 -354.594279) (xy 285.862811 -354.544725) (xy 285.932729 -354.501438) (xy 286.006342 -354.464786)
			(xy 286.083023 -354.435084) (xy 286.162118 -354.412584) (xy 286.242951 -354.397477) (xy 286.324834 -354.389894)
			(xy 286.36595 -354.389436) (xy 286.404239 -354.389856) (xy 286.480533 -354.39646) (xy 286.555976 -354.409605)
			(xy 286.630007 -354.429194) (xy 286.666178 -354.44176) (xy 286.674615 -354.444411) (xy 286.692285 -354.444411)
			(xy 286.700722 -354.44176) (xy 286.736903 -354.429226) (xy 286.810935 -354.409651) (xy 286.886373 -354.396501)
			(xy 286.962662 -354.389874) (xy 287.00095 -354.389436) (xy 287.039239 -354.389856) (xy 287.115533 -354.39646)
			(xy 287.190976 -354.409605) (xy 287.265007 -354.429194) (xy 287.301178 -354.44176) (xy 287.309615 -354.444411)
			(xy 287.327285 -354.444411) (xy 287.335722 -354.44176) (xy 287.371903 -354.429226) (xy 287.445935 -354.409651)
			(xy 287.521373 -354.396501) (xy 287.597662 -354.389874) (xy 287.63595 -354.389436) (xy 287.674239 -354.389856)
			(xy 287.750533 -354.39646) (xy 287.825976 -354.409605) (xy 287.900007 -354.429194) (xy 287.936178 -354.44176)
			(xy 287.944615 -354.444411) (xy 287.962285 -354.444411) (xy 287.970722 -354.44176) (xy 288.006903 -354.429226)
			(xy 288.080935 -354.409651) (xy 288.156373 -354.396501) (xy 288.232662 -354.389874) (xy 288.27095 -354.389436)
			(xy 288.309239 -354.389856) (xy 288.385533 -354.39646) (xy 288.460976 -354.409605) (xy 288.535007 -354.429194)
			(xy 288.571178 -354.44176) (xy 288.579615 -354.444411) (xy 288.597285 -354.444411) (xy 288.605722 -354.44176)
			(xy 288.641903 -354.429226) (xy 288.715935 -354.409651) (xy 288.791373 -354.396501) (xy 288.867662 -354.389874)
			(xy 288.90595 -354.389436) (xy 288.947064 -354.389946) (xy 289.028942 -354.397529) (xy 289.10977 -354.412634)
			(xy 289.18886 -354.435133) (xy 289.265537 -354.464834) (xy 289.339146 -354.501483) (xy 289.409059 -354.544768)
			(xy 289.47468 -354.594319) (xy 289.535449 -354.649714) (xy 289.590847 -354.71048) (xy 289.640402 -354.776098)
			(xy 289.683691 -354.846009) (xy 289.720345 -354.919615) (xy 289.75005 -354.99629) (xy 289.772554 -355.075379)
			(xy 289.787664 -355.156207) (xy 289.795251 -355.238084) (xy 289.795712 -355.279198) (xy 289.795298 -355.318061)
			(xy 289.788487 -355.395488) (xy 289.77495 -355.472025) (xy 289.75479 -355.547092) (xy 289.741864 -355.583744)
			(xy 289.739034 -355.592628) (xy 289.739308 -355.611259) (xy 289.742372 -355.620066) (xy 289.757559 -355.659473)
			(xy 289.781314 -355.740522) (xy 289.797291 -355.823456) (xy 289.805346 -355.907529) (xy 289.805872 -355.949758)
			(xy 289.805454 -355.988048) (xy 289.79885 -356.064341) (xy 289.785704 -356.139784) (xy 289.766114 -356.213815)
			(xy 289.753548 -356.249986) (xy 289.750918 -356.258428) (xy 289.750905 -356.276094) (xy 289.753548 -356.28453)
			(xy 289.766084 -356.32071) (xy 289.785659 -356.394742) (xy 289.798808 -356.470181) (xy 289.805435 -356.54647)
			(xy 289.805872 -356.584758) (xy 289.805362 -356.625872) (xy 289.797778 -356.707749) (xy 289.782672 -356.788578)
			(xy 289.760173 -356.867667) (xy 289.730472 -356.944344) (xy 289.693822 -357.017952) (xy 289.650537 -357.087865)
			(xy 289.600986 -357.153486) (xy 289.545592 -357.214255) (xy 289.484826 -357.269653) (xy 289.419208 -357.319208)
			(xy 289.349298 -357.362497) (xy 289.275691 -357.399151) (xy 289.199017 -357.428856) (xy 289.119928 -357.45136)
			(xy 289.039101 -357.466471) (xy 288.957224 -357.474059) (xy 288.91611 -357.47452) (xy 288.87782 -357.474114)
			(xy 288.801526 -357.467506) (xy 288.726084 -357.454357) (xy 288.652053 -357.434764) (xy 288.615882 -357.422196)
			(xy 288.607445 -357.419545) (xy 288.589775 -357.419545) (xy 288.581338 -357.422196) (xy 288.54516 -357.434739)
			(xy 288.471127 -357.454312) (xy 288.395688 -357.46746) (xy 288.319398 -357.474084) (xy 288.28111 -357.47452)
			(xy 288.24282 -357.474114) (xy 288.166526 -357.467506) (xy 288.091084 -357.454357) (xy 288.017053 -357.434764)
			(xy 287.980882 -357.422196) (xy 287.972445 -357.419545) (xy 287.954775 -357.419545) (xy 287.946338 -357.422196)
			(xy 287.91016 -357.434739) (xy 287.836127 -357.454312) (xy 287.760688 -357.46746) (xy 287.684398 -357.474084)
			(xy 287.64611 -357.47452) (xy 287.60782 -357.474114) (xy 287.531526 -357.467506) (xy 287.456084 -357.454357)
			(xy 287.382053 -357.434764) (xy 287.345882 -357.422196) (xy 287.337445 -357.419545) (xy 287.319775 -357.419545)
			(xy 287.311338 -357.422196) (xy 287.27516 -357.434739) (xy 287.201127 -357.454312) (xy 287.125688 -357.46746)
			(xy 287.049398 -357.474084) (xy 287.01111 -357.47452) (xy 286.97282 -357.474114) (xy 286.896526 -357.467506)
			(xy 286.821084 -357.454357) (xy 286.747053 -357.434764) (xy 286.710882 -357.422196) (xy 286.702445 -357.419545)
			(xy 286.684775 -357.419545) (xy 286.676338 -357.422196) (xy 286.64016 -357.434739) (xy 286.566127 -357.454312)
			(xy 286.490688 -357.46746) (xy 286.414398 -357.474084) (xy 286.37611 -357.47452) (xy 286.334994 -357.474092)
			(xy 286.253113 -357.466505) (xy 286.172281 -357.451395) (xy 286.093188 -357.428892) (xy 286.016509 -357.399186)
			(xy 285.942899 -357.362532) (xy 285.872984 -357.319241) (xy 285.807362 -357.269685) (xy 285.746593 -357.214284)
			(xy 285.691195 -357.153513) (xy 285.641641 -357.08789) (xy 285.598353 -357.017973) (xy 285.561701 -356.944361)
			(xy 285.531998 -356.867681) (xy 285.509497 -356.788588) (xy 285.49439 -356.707755) (xy 285.486807 -356.625874)
			(xy 285.486348 -356.584758) (xy 285.48677 -356.546469) (xy 285.493373 -356.470175) (xy 285.506518 -356.394732)
			(xy 285.526107 -356.320701) (xy 285.538672 -356.28453) (xy 285.541343 -356.276098) (xy 285.541329 -356.258423)
			(xy 285.538672 -356.249986) (xy 285.526141 -356.213804) (xy 285.506565 -356.139773) (xy 285.493414 -356.064334)
			(xy 285.486786 -355.988046) (xy 285.486348 -355.949758) (xy 285.486781 -355.910896) (xy 285.493587 -355.833469)
			(xy 285.507119 -355.756932) (xy 285.527272 -355.681865) (xy 285.540196 -355.645212) (xy 285.542998 -355.636321)
			(xy 285.542744 -355.617697) (xy 285.539688 -355.60889) (xy 285.524486 -355.569489) (xy 285.500735 -355.488437)
			(xy 285.484763 -355.405502) (xy 285.476712 -355.321427) (xy 285.476188 -355.279198) (xy 195.742079 -355.279198)
			(xy 195.735206 -355.292996) (xy 195.691912 -355.362897) (xy 195.642352 -355.428505) (xy 195.586949 -355.48926)
			(xy 195.526176 -355.544642) (xy 195.460551 -355.59418) (xy 195.390636 -355.637451) (xy 195.317025 -355.674085)
			(xy 195.240348 -355.703769) (xy 195.161258 -355.726251) (xy 195.080432 -355.741339) (xy 194.998557 -355.748903)
			(xy 194.957446 -355.749352) (xy 194.915842 -355.74888) (xy 194.832994 -355.741147) (xy 194.75123 -355.725716)
			(xy 194.671262 -355.702722) (xy 194.593789 -355.672366) (xy 194.519488 -355.634911) (xy 194.48399 -355.613208)
			(xy 194.474858 -355.608031) (xy 194.454138 -355.60482) (xy 194.433861 -355.61016) (xy 194.425316 -355.616256)
			(xy 194.391667 -355.642178) (xy 194.320293 -355.688236) (xy 194.244854 -355.727283) (xy 194.166037 -355.758962)
			(xy 194.08456 -355.782986) (xy 194.001164 -355.799135) (xy 193.916608 -355.807262) (xy 193.874136 -355.807772)
			(xy 193.873882 -355.807772) (xy 193.832775 -355.807305) (xy 193.750912 -355.799719) (xy 193.670098 -355.784614)
			(xy 193.591023 -355.762118) (xy 193.514359 -355.732423) (xy 193.440762 -355.695782) (xy 193.370859 -355.652509)
			(xy 193.305245 -355.602971) (xy 193.244482 -355.547592) (xy 193.189086 -355.486844) (xy 193.13953 -355.421244)
			(xy 193.096237 -355.351353) (xy 193.059577 -355.277766) (xy 193.029861 -355.201111) (xy 193.007343 -355.122041)
			(xy 192.992215 -355.041231) (xy 192.984607 -354.959371) (xy 192.98412 -354.918264) (xy 192.984683 -354.873494)
			(xy 192.993693 -354.784409) (xy 193.011598 -354.696678) (xy 193.038217 -354.611187) (xy 193.05524 -354.569776)
			(xy 193.058825 -354.560191) (xy 193.058812 -354.539743) (xy 193.05524 -354.530152) (xy 193.03824 -354.4888)
			(xy 193.011628 -354.403438) (xy 192.99372 -354.315836) (xy 192.984697 -354.226879) (xy 192.98412 -354.182172)
			(xy 192.98412 -354.181156) (xy 192.984374 -354.169726) (xy 192.957895 -354.163781) (xy 192.90566 -354.149038)
			(xy 192.87998 -354.140262) (xy 192.871783 -354.137748) (xy 192.854649 -354.137748) (xy 192.846452 -354.140262)
			(xy 192.811236 -354.152209) (xy 192.739226 -354.170796) (xy 192.665903 -354.183236) (xy 192.591792 -354.18944)
			(xy 192.554606 -354.189792) (xy 192.517422 -354.189422) (xy 192.443314 -354.1832) (xy 192.369994 -354.170758)
			(xy 192.297983 -354.152184) (xy 192.26276 -354.140262) (xy 192.254563 -354.137748) (xy 192.237429 -354.137748)
			(xy 192.229232 -354.140262) (xy 192.19413 -354.15215) (xy 192.122374 -354.1707) (xy 192.049311 -354.183146)
			(xy 191.97546 -354.189399) (xy 191.938402 -354.189792) (xy 191.937386 -354.189792) (xy 191.89546 -354.189345)
			(xy 191.811988 -354.181373) (xy 191.729651 -354.165503) (xy 191.649196 -354.141878) (xy 191.57135 -354.110712)
			(xy 191.49682 -354.072288) (xy 191.42628 -354.026953) (xy 191.360368 -353.975119) (xy 191.299682 -353.917254)
			(xy 191.244771 -353.853882) (xy 191.196132 -353.785578) (xy 191.154206 -353.71296) (xy 191.119373 -353.636685)
			(xy 191.091948 -353.557444) (xy 191.07218 -353.475956) (xy 191.060246 -353.392957) (xy 191.056256 -353.3092)
			(xy 187.519078 -353.3092) (xy 187.520094 -353.320137) (xy 187.52058 -353.361244) (xy 187.52002 -353.406014)
			(xy 187.511009 -353.495099) (xy 187.493104 -353.58283) (xy 187.466484 -353.668321) (xy 187.44946 -353.709732)
			(xy 187.44587 -353.719315) (xy 187.445886 -353.739765) (xy 187.44946 -353.749356) (xy 187.466484 -353.790767)
			(xy 187.493121 -353.876254) (xy 187.511029 -353.963986) (xy 187.520026 -354.053074) (xy 187.52058 -354.097844)
			(xy 187.52002 -354.142614) (xy 187.511009 -354.231699) (xy 187.493104 -354.31943) (xy 187.466484 -354.404921)
			(xy 187.44946 -354.446332) (xy 187.44587 -354.455915) (xy 187.445886 -354.476365) (xy 187.44946 -354.485956)
			(xy 187.466484 -354.527367) (xy 187.493121 -354.612854) (xy 187.511029 -354.700586) (xy 187.520026 -354.789674)
			(xy 187.52058 -354.834444) (xy 187.520189 -354.875556) (xy 187.512597 -354.957429) (xy 187.497482 -355.038252)
			(xy 187.474973 -355.117336) (xy 187.445261 -355.194004) (xy 187.408601 -355.267604) (xy 187.365306 -355.337506)
			(xy 187.315744 -355.403115) (xy 187.260339 -355.46387) (xy 187.199564 -355.519252) (xy 187.133937 -355.56879)
			(xy 187.064019 -355.61206) (xy 186.990406 -355.648693) (xy 186.913727 -355.678376) (xy 186.834635 -355.700857)
			(xy 186.753806 -355.715942) (xy 186.67193 -355.723505) (xy 186.630818 -355.723952) (xy 186.589214 -355.723494)
			(xy 186.506365 -355.715758) (xy 186.424601 -355.700325) (xy 186.344633 -355.677328) (xy 186.267161 -355.646969)
			(xy 186.192859 -355.609513) (xy 186.157362 -355.587808) (xy 186.148243 -355.582606) (xy 186.127514 -355.579404)
			(xy 186.107233 -355.584754) (xy 186.098688 -355.590856) (xy 186.065049 -355.616791) (xy 185.993673 -355.662848)
			(xy 185.918232 -355.701893) (xy 185.839413 -355.73357) (xy 185.757935 -355.757592) (xy 185.674537 -355.773739)
			(xy 185.589981 -355.781864) (xy 185.547508 -355.782372) (xy 185.547254 -355.782372) (xy 185.506147 -355.781931)
			(xy 185.424283 -355.774343) (xy 185.343469 -355.759235) (xy 185.264393 -355.736737) (xy 185.187729 -355.70704)
			(xy 185.114132 -355.670398) (xy 185.044229 -355.627122) (xy 184.978615 -355.577583) (xy 184.917852 -355.522202)
			(xy 184.862456 -355.461452) (xy 184.812901 -355.395851) (xy 184.769609 -355.325959) (xy 184.732948 -355.252371)
			(xy 184.703232 -355.175714) (xy 184.680715 -355.096644) (xy 184.665587 -355.015833) (xy 184.657979 -354.933971)
			(xy 184.657492 -354.892864) (xy 184.658057 -354.848094) (xy 184.667066 -354.759009) (xy 184.684971 -354.671278)
			(xy 184.711589 -354.585787) (xy 184.728612 -354.544376) (xy 184.732199 -354.534792) (xy 184.732185 -354.514343)
			(xy 184.728612 -354.504752) (xy 184.711616 -354.463398) (xy 184.685002 -354.378037) (xy 184.667093 -354.290435)
			(xy 184.658069 -354.201478) (xy 184.657492 -354.156772) (xy 184.657492 -354.155756) (xy 184.657746 -354.144326)
			(xy 184.631266 -354.138384) (xy 184.579032 -354.123639) (xy 184.553352 -354.114862) (xy 184.545155 -354.112348)
			(xy 184.528021 -354.112348) (xy 184.519824 -354.114862) (xy 184.484602 -354.126789) (xy 184.412594 -354.145381)
			(xy 184.339273 -354.157827) (xy 184.265163 -354.164037) (xy 184.227978 -354.164392) (xy 184.190794 -354.16403)
			(xy 184.116686 -354.157806) (xy 184.043366 -354.145361) (xy 183.971355 -354.126785) (xy 183.936132 -354.114862)
			(xy 183.927935 -354.112348) (xy 183.910801 -354.112348) (xy 183.902604 -354.114862) (xy 183.867505 -354.126757)
			(xy 183.795747 -354.145305) (xy 183.722684 -354.157749) (xy 183.648832 -354.164001) (xy 183.611774 -354.164392)
			(xy 183.610758 -354.164392) (xy 183.568833 -354.163944) (xy 183.485362 -354.155969) (xy 183.403028 -354.140097)
			(xy 183.322575 -354.11647) (xy 183.244732 -354.085304) (xy 183.170204 -354.046879) (xy 183.099666 -354.001544)
			(xy 183.033756 -353.949709) (xy 182.973072 -353.891844) (xy 182.918163 -353.828473) (xy 182.869527 -353.760169)
			(xy 182.827603 -353.687552) (xy 182.792771 -353.611278) (xy 182.765347 -353.532039) (xy 182.745579 -353.450553)
			(xy 182.733646 -353.367555) (xy 182.729656 -353.2838) (xy 78.346936 -353.2838) (xy 78.321217 -353.348042)
			(xy 78.282395 -353.423345) (xy 78.236592 -353.494617) (xy 78.184221 -353.561213) (xy 78.125756 -353.622528)
			(xy 78.061728 -353.678009) (xy 77.992716 -353.727152) (xy 77.919346 -353.769512) (xy 77.842281 -353.804707)
			(xy 77.762219 -353.832416) (xy 77.679886 -353.85239) (xy 77.596027 -353.864447) (xy 77.511402 -353.868479)
			(xy 77.426777 -353.864447) (xy 77.342918 -353.85239) (xy 77.260585 -353.832416) (xy 77.180523 -353.804707)
			(xy 77.103458 -353.769512) (xy 77.030088 -353.727152) (xy 76.961076 -353.678009) (xy 76.897048 -353.622528)
			(xy 76.838583 -353.561213) (xy 76.786212 -353.494617) (xy 76.740409 -353.423345) (xy 76.701587 -353.348042)
			(xy 76.670099 -353.26939) (xy 76.646231 -353.1881) (xy 76.630197 -353.10491) (xy 76.622144 -353.020573)
			(xy 76.62164 -352.978212) (xy 76.622159 -352.935266) (xy 76.630462 -352.849776) (xy 76.646954 -352.765482)
			(xy 76.671481 -352.683166) (xy 76.687172 -352.643186) (xy 76.690418 -352.63393) (xy 76.690431 -352.614336)
			(xy 76.687172 -352.605086) (xy 76.671432 -352.565089) (xy 76.646875 -352.482712) (xy 76.630388 -352.398348)
			(xy 76.622124 -352.312786) (xy 76.62164 -352.269806) (xy 76.622244 -352.224161) (xy 76.631638 -352.133355)
			(xy 76.650266 -352.043985) (xy 76.66355 -352.000312) (xy 76.665996 -351.9913) (xy 76.664956 -351.972672)
			(xy 76.661518 -351.96399) (xy 76.642856 -351.920903) (xy 76.61365 -351.831658) (xy 76.594004 -351.739834)
			(xy 76.584137 -351.646451) (xy 76.58354 -351.5995) (xy 75.70064 -351.5995) (xy 75.701144 -351.637854)
			(xy 75.70053 -351.683499) (xy 75.691141 -351.774304) (xy 75.672516 -351.863674) (xy 75.659234 -351.907348)
			(xy 75.65681 -351.916364) (xy 75.657836 -351.934988) (xy 75.661266 -351.94367) (xy 75.679947 -351.986749)
			(xy 75.709149 -352.075997) (xy 75.728789 -352.167824) (xy 75.738651 -352.261208) (xy 75.739244 -352.30816)
			(xy 75.738798 -352.348493) (xy 75.731529 -352.428831) (xy 75.71702 -352.508181) (xy 75.69539 -352.585893)
			(xy 75.666817 -352.661328) (xy 75.649582 -352.697796) (xy 75.645066 -352.708391) (xy 75.645063 -352.731399)
			(xy 75.649582 -352.741992) (xy 75.666819 -352.778431) (xy 75.69537 -352.853821) (xy 75.716991 -352.931483)
			(xy 75.731505 -353.010781) (xy 75.738793 -353.091066) (xy 75.739244 -353.131374) (xy 75.73874 -353.173735)
			(xy 75.730687 -353.258072) (xy 75.714653 -353.341262) (xy 75.690785 -353.422552) (xy 75.659297 -353.501204)
			(xy 75.620475 -353.576507) (xy 75.574672 -353.647779) (xy 75.522301 -353.714375) (xy 75.463836 -353.77569)
			(xy 75.399808 -353.831171) (xy 75.330796 -353.880314) (xy 75.257426 -353.922674) (xy 75.180361 -353.957869)
			(xy 75.100299 -353.985578) (xy 75.017966 -354.005552) (xy 74.934107 -354.017609) (xy 74.849482 -354.021641)
			(xy 74.764857 -354.017609) (xy 74.680998 -354.005552) (xy 74.598665 -353.985578) (xy 74.518603 -353.957869)
			(xy 74.441538 -353.922674) (xy 74.368168 -353.880314) (xy 74.299156 -353.831171) (xy 74.235128 -353.77569)
			(xy 74.176663 -353.714375) (xy 74.124292 -353.647779) (xy 74.078489 -353.576507) (xy 74.039667 -353.501204)
			(xy 74.008179 -353.422552) (xy 73.984311 -353.341262) (xy 73.968277 -353.258072) (xy 73.960224 -353.173735)
			(xy 73.95972 -353.131374) (xy 73.960164 -353.091034) (xy 73.96747 -353.010685) (xy 73.982028 -352.931329)
			(xy 74.003719 -352.85362) (xy 74.032363 -352.778196) (xy 74.049636 -352.741738) (xy 74.054225 -352.731091)
			(xy 74.054231 -352.707932) (xy 74.049636 -352.697288) (xy 74.032445 -352.660861) (xy 74.003936 -352.58552)
			(xy 73.98236 -352.50791) (xy 73.967893 -352.428665) (xy 73.960655 -352.348437) (xy 73.960228 -352.30816)
			(xy 73.960797 -352.262521) (xy 73.970094 -352.171718) (xy 73.988639 -352.082344) (xy 74.001884 -352.038666)
			(xy 74.004352 -352.029659) (xy 74.003297 -352.011026) (xy 73.999852 -352.002344) (xy 73.981136 -351.959272)
			(xy 73.95186 -351.870033) (xy 73.932154 -351.778206) (xy 73.922237 -351.684813) (xy 73.92162 -351.637854)
			(xy 2.509012 -351.637854) (xy 2.509012 -358.071674) (xy 14.438884 -358.071674) (xy 14.438884 -357.208074)
			(xy 14.43937 -357.180805) (xy 14.447132 -357.126821) (xy 14.462497 -357.074491) (xy 14.485154 -357.024881)
			(xy 14.51464 -356.979) (xy 14.550355 -356.937783) (xy 14.591572 -356.902068) (xy 14.637453 -356.872582)
			(xy 14.687063 -356.849925) (xy 14.739393 -356.83456) (xy 14.793377 -356.826798) (xy 14.847915 -356.826798)
			(xy 14.901899 -356.83456) (xy 14.954229 -356.849925) (xy 15.003839 -356.872582) (xy 15.04972 -356.902068)
			(xy 15.090937 -356.937783) (xy 15.126652 -356.979) (xy 15.156138 -357.024881) (xy 15.178795 -357.074491)
			(xy 15.19416 -357.126821) (xy 15.201922 -357.180805) (xy 15.202408 -357.208074) (xy 15.202408 -358.071674)
			(xy 15.201922 -358.098943) (xy 15.19416 -358.152927) (xy 15.178795 -358.205257) (xy 15.156138 -358.254867)
			(xy 15.126652 -358.300748) (xy 15.090937 -358.341965) (xy 15.04972 -358.37768) (xy 15.003839 -358.407166)
			(xy 14.954229 -358.429823) (xy 14.901899 -358.445188) (xy 14.847915 -358.45295) (xy 14.793377 -358.45295)
			(xy 14.739393 -358.445188) (xy 14.687063 -358.429823) (xy 14.637453 -358.407166) (xy 14.591572 -358.37768)
			(xy 14.550355 -358.341965) (xy 14.51464 -358.300748) (xy 14.485154 -358.254867) (xy 14.462497 -358.205257)
			(xy 14.447132 -358.152927) (xy 14.43937 -358.098943) (xy 14.438884 -358.071674) (xy 2.509012 -358.071674)
			(xy 2.509012 -358.549194) (xy 40.47998 -358.549194) (xy 40.480352 -358.511134) (xy 40.486825 -358.435291)
			(xy 40.499758 -358.360279) (xy 40.519056 -358.286646) (xy 40.544577 -358.214933) (xy 40.55999 -358.180132)
			(xy 40.563435 -358.171803) (xy 40.56487 -358.153848) (xy 40.562784 -358.14508) (xy 40.551663 -358.104882)
			(xy 40.536092 -358.022938) (xy 40.528245 -357.939897) (xy 40.527732 -357.898192) (xy 40.528135 -357.859902)
			(xy 40.534744 -357.783608) (xy 40.547894 -357.708165) (xy 40.567488 -357.634135) (xy 40.580056 -357.597964)
			(xy 40.58271 -357.589528) (xy 40.582708 -357.571857) (xy 40.580056 -357.56342) (xy 40.567506 -357.527245)
			(xy 40.547935 -357.453211) (xy 40.53479 -357.37777) (xy 40.528167 -357.30148) (xy 40.527732 -357.263192)
			(xy 40.528236 -357.220831) (xy 40.536289 -357.136494) (xy 40.552323 -357.053304) (xy 40.576191 -356.972014)
			(xy 40.607679 -356.893362) (xy 40.646501 -356.818059) (xy 40.692304 -356.746787) (xy 40.744675 -356.680191)
			(xy 40.80314 -356.618876) (xy 40.867168 -356.563395) (xy 40.93618 -356.514252) (xy 41.00955 -356.471892)
			(xy 41.086615 -356.436697) (xy 41.166677 -356.408988) (xy 41.24901 -356.389014) (xy 41.332869 -356.376957)
			(xy 41.417494 -356.372926) (xy 41.502119 -356.376957) (xy 41.585978 -356.389014) (xy 41.668311 -356.408988)
			(xy 41.748373 -356.436697) (xy 41.825438 -356.471892) (xy 41.898808 -356.514252) (xy 41.96782 -356.563395)
			(xy 42.031848 -356.618876) (xy 42.090313 -356.680191) (xy 42.142684 -356.746787) (xy 42.188487 -356.818059)
			(xy 42.227309 -356.893362) (xy 42.258797 -356.972014) (xy 42.282665 -357.053304) (xy 42.298699 -357.136494)
			(xy 42.306752 -357.220831) (xy 42.307256 -357.263192) (xy 42.306849 -357.301482) (xy 42.300241 -357.377776)
			(xy 42.287093 -357.453218) (xy 42.2675 -357.527249) (xy 42.254932 -357.56342) (xy 42.252286 -357.571858)
			(xy 42.252283 -357.589527) (xy 42.254932 -357.597964) (xy 42.267477 -357.634141) (xy 42.28705 -357.708174)
			(xy 42.300196 -357.783614) (xy 42.30682 -357.859904) (xy 42.307256 -357.898192) (xy 42.306876 -357.936251)
			(xy 42.300404 -358.012094) (xy 42.287473 -358.087107) (xy 42.268177 -358.160739) (xy 42.242658 -358.232452)
			(xy 42.227246 -358.267254) (xy 42.223809 -358.275586) (xy 42.222368 -358.293538) (xy 42.224452 -358.302306)
			(xy 42.23557 -358.342505) (xy 42.251142 -358.424449) (xy 42.258991 -358.507489) (xy 42.259032 -358.51084)
			(xy 43.046396 -358.51084) (xy 43.046759 -358.47278) (xy 43.053225 -358.396935) (xy 43.066156 -358.321921)
			(xy 43.085458 -358.248289) (xy 43.110988 -358.176577) (xy 43.126406 -358.141778) (xy 43.129746 -358.133421)
			(xy 43.131033 -358.115482) (xy 43.128946 -358.106726) (xy 43.117873 -358.066521) (xy 43.102375 -357.984574)
			(xy 43.094614 -357.901538) (xy 43.094148 -357.859838) (xy 43.094524 -357.821522) (xy 43.101053 -357.745169)
			(xy 43.114136 -357.669662) (xy 43.133673 -357.595562) (xy 43.146218 -357.559356) (xy 43.148787 -357.551035)
			(xy 43.148799 -357.533636) (xy 43.146218 -357.52532) (xy 43.13374 -357.489193) (xy 43.114246 -357.415282)
			(xy 43.101158 -357.339973) (xy 43.094573 -357.263819) (xy 43.094148 -357.2256) (xy 43.094148 -357.224838)
			(xy 43.094652 -357.18249) (xy 43.102703 -357.098176) (xy 43.118732 -357.01501) (xy 43.142593 -356.933743)
			(xy 43.174072 -356.855113) (xy 43.212883 -356.779832) (xy 43.258673 -356.70858) (xy 43.311029 -356.642004)
			(xy 43.369477 -356.580706) (xy 43.433487 -356.525241) (xy 43.502479 -356.476112) (xy 43.575829 -356.433763)
			(xy 43.652872 -356.398579) (xy 43.732911 -356.370877) (xy 43.81522 -356.350909) (xy 43.899055 -356.338856)
			(xy 43.983656 -356.334826) (xy 44.068257 -356.338856) (xy 44.152092 -356.350909) (xy 44.234401 -356.370877)
			(xy 44.31444 -356.398579) (xy 44.391483 -356.433763) (xy 44.464833 -356.476112) (xy 44.533825 -356.525241)
			(xy 44.597835 -356.580706) (xy 44.656283 -356.642004) (xy 44.708639 -356.70858) (xy 44.754429 -356.779832)
			(xy 44.79324 -356.855113) (xy 44.824719 -356.933743) (xy 44.84858 -357.01501) (xy 44.864609 -357.098176)
			(xy 44.87266 -357.18249) (xy 44.873164 -357.224838) (xy 44.873164 -357.2256) (xy 44.87277 -357.263821)
			(xy 44.866201 -357.339979) (xy 44.853113 -357.415292) (xy 44.833602 -357.489202) (xy 44.821094 -357.52532)
			(xy 44.818487 -357.533631) (xy 44.818499 -357.55104) (xy 44.821094 -357.559356) (xy 44.833623 -357.595567)
			(xy 44.853143 -357.669669) (xy 44.866225 -357.745173) (xy 44.872771 -357.821523) (xy 44.873164 -357.859838)
			(xy 44.872788 -357.897898) (xy 44.866324 -357.973742) (xy 44.853395 -358.048756) (xy 44.837736 -358.108504)
			(xy 46.991016 -358.108504) (xy 46.991397 -358.070445) (xy 46.997869 -357.994602) (xy 47.0108 -357.919589)
			(xy 47.030096 -357.845957) (xy 47.055615 -357.774244) (xy 47.071026 -357.739442) (xy 47.074466 -357.731111)
			(xy 47.075906 -357.713158) (xy 47.07382 -357.70439) (xy 47.0627 -357.664192) (xy 47.047129 -357.582247)
			(xy 47.039281 -357.499207) (xy 47.038768 -357.457502) (xy 47.039173 -357.419212) (xy 47.045781 -357.342918)
			(xy 47.05893 -357.267476) (xy 47.078524 -357.193445) (xy 47.091092 -357.157274) (xy 47.09374 -357.148837)
			(xy 47.093741 -357.131167) (xy 47.091092 -357.12273) (xy 47.078546 -357.086553) (xy 47.058974 -357.01252)
			(xy 47.045827 -356.93708) (xy 47.039204 -356.86079) (xy 47.038768 -356.822502) (xy 47.0392 -356.781386)
			(xy 47.046788 -356.699506) (xy 47.061898 -356.618674) (xy 47.084402 -356.539582) (xy 47.114108 -356.462904)
			(xy 47.150762 -356.389293) (xy 47.194052 -356.319379) (xy 47.243609 -356.253758) (xy 47.299008 -356.192989)
			(xy 47.359779 -356.137591) (xy 47.425402 -356.088036) (xy 47.495318 -356.044749) (xy 47.568929 -356.008097)
			(xy 47.645609 -355.978393) (xy 47.724702 -355.955891) (xy 47.805533 -355.940784) (xy 47.887414 -355.933199)
			(xy 47.92853 -355.93274) (xy 47.969637 -355.933252) (xy 48.051499 -355.940877) (xy 48.132307 -355.956023)
			(xy 48.211373 -355.97856) (xy 48.288023 -356.008296) (xy 48.325024 -356.026212) (xy 48.335846 -356.030917)
			(xy 48.359414 -356.030917) (xy 48.370236 -356.026212) (xy 48.407247 -356.008316) (xy 48.483894 -355.978575)
			(xy 48.562957 -355.956031) (xy 48.643763 -355.940876) (xy 48.725623 -355.93324) (xy 48.76673 -355.93274)
			(xy 48.80502 -355.933136) (xy 48.881314 -355.939747) (xy 48.956757 -355.952899) (xy 49.030787 -355.972495)
			(xy 49.066958 -355.985064) (xy 49.075395 -355.987715) (xy 49.093065 -355.987715) (xy 49.101502 -355.985064)
			(xy 49.137675 -355.972508) (xy 49.21171 -355.952938) (xy 49.287151 -355.939795) (xy 49.363442 -355.933174)
			(xy 49.40173 -355.93274) (xy 49.44002 -355.933136) (xy 49.516314 -355.939747) (xy 49.591757 -355.952899)
			(xy 49.665787 -355.972495) (xy 49.701958 -355.985064) (xy 49.710395 -355.987715) (xy 49.728065 -355.987715)
			(xy 49.736502 -355.985064) (xy 49.772675 -355.972508) (xy 49.84671 -355.952938) (xy 49.922151 -355.939795)
			(xy 49.998442 -355.933174) (xy 50.03673 -355.93274) (xy 50.07502 -355.933136) (xy 50.151314 -355.939747)
			(xy 50.226757 -355.952899) (xy 50.300787 -355.972495) (xy 50.336958 -355.985064) (xy 50.345395 -355.987715)
			(xy 50.363065 -355.987715) (xy 50.371502 -355.985064) (xy 50.407675 -355.972508) (xy 50.48171 -355.952938)
			(xy 50.557151 -355.939795) (xy 50.633442 -355.933174) (xy 50.67173 -355.93274) (xy 50.712845 -355.933184)
			(xy 50.794723 -355.940774) (xy 50.875552 -355.955886) (xy 50.954642 -355.978392) (xy 51.031318 -356.008098)
			(xy 51.104926 -356.044753) (xy 51.174838 -356.088043) (xy 51.240458 -356.137599) (xy 51.301225 -356.192997)
			(xy 51.356622 -356.253767) (xy 51.406175 -356.319388) (xy 51.449463 -356.389302) (xy 51.486115 -356.462911)
			(xy 51.515819 -356.539588) (xy 51.538321 -356.618679) (xy 51.55343 -356.699508) (xy 51.561017 -356.781387)
			(xy 51.561492 -356.822502) (xy 51.561091 -356.860792) (xy 51.554482 -356.937086) (xy 51.541332 -357.012529)
			(xy 51.521737 -357.086559) (xy 51.509168 -357.12273) (xy 51.506515 -357.131166) (xy 51.506516 -357.148837)
			(xy 51.509168 -357.157274) (xy 51.521713 -357.193451) (xy 51.541286 -357.267484) (xy 51.554433 -357.342924)
			(xy 51.561057 -357.419214) (xy 51.561492 -357.457502) (xy 51.561112 -357.495561) (xy 51.55464 -357.571404)
			(xy 51.541708 -357.646417) (xy 51.522413 -357.720049) (xy 51.496894 -357.791762) (xy 51.481482 -357.826564)
			(xy 51.478039 -357.834894) (xy 51.476603 -357.852848) (xy 51.478688 -357.861616) (xy 51.48981 -357.901814)
			(xy 51.50538 -357.983758) (xy 51.513227 -358.066799) (xy 51.51374 -358.108504) (xy 51.513251 -358.149614)
			(xy 51.505664 -358.231482) (xy 51.490553 -358.312301) (xy 51.468049 -358.391381) (xy 51.438343 -358.468047)
			(xy 51.401689 -358.541644) (xy 51.3584 -358.611544) (xy 51.308844 -358.677152) (xy 51.253446 -358.737906)
			(xy 51.192678 -358.793289) (xy 51.127058 -358.842827) (xy 51.057146 -358.886099) (xy 50.98354 -358.922734)
			(xy 50.906867 -358.952421) (xy 50.827781 -358.974905) (xy 50.746958 -358.989995) (xy 50.665088 -358.997562)
			(xy 50.623978 -358.998012) (xy 50.585661 -358.99765) (xy 50.509308 -358.991116) (xy 50.433801 -358.97803)
			(xy 50.359702 -358.958488) (xy 50.323496 -358.945942) (xy 50.31518 -358.943356) (xy 50.297776 -358.943356)
			(xy 50.28946 -358.945942) (xy 50.253248 -358.958468) (xy 50.179147 -358.977989) (xy 50.103642 -358.991071)
			(xy 50.027293 -358.997619) (xy 49.988978 -358.998012) (xy 49.950661 -358.99765) (xy 49.874308 -358.991116)
			(xy 49.798801 -358.97803) (xy 49.724702 -358.958488) (xy 49.688496 -358.945942) (xy 49.68018 -358.943356)
			(xy 49.662776 -358.943356) (xy 49.65446 -358.945942) (xy 49.618248 -358.958468) (xy 49.544147 -358.977989)
			(xy 49.468642 -358.991071) (xy 49.392293 -358.997619) (xy 49.353978 -358.998012) (xy 49.315661 -358.99765)
			(xy 49.239308 -358.991116) (xy 49.163801 -358.97803) (xy 49.089702 -358.958488) (xy 49.053496 -358.945942)
			(xy 49.04518 -358.943356) (xy 49.027776 -358.943356) (xy 49.01946 -358.945942) (xy 48.983339 -358.95844)
			(xy 48.909426 -358.977928) (xy 48.834115 -358.99101) (xy 48.757959 -358.99759) (xy 48.71974 -358.998012)
			(xy 48.718978 -358.998012) (xy 48.677876 -358.99753) (xy 48.596022 -358.989953) (xy 48.515216 -358.974857)
			(xy 48.436148 -358.95237) (xy 48.359491 -358.922685) (xy 48.322484 -358.904794) (xy 48.311662 -358.900089)
			(xy 48.288094 -358.900089) (xy 48.277272 -358.904794) (xy 48.240271 -358.922698) (xy 48.163612 -358.952379)
			(xy 48.084542 -358.974864) (xy 48.003735 -358.98996) (xy 47.92188 -358.997539) (xy 47.880778 -358.998012)
			(xy 47.839669 -358.997608) (xy 47.757803 -358.990022) (xy 47.676986 -358.974915) (xy 47.597907 -358.952416)
			(xy 47.52124 -358.922719) (xy 47.447641 -358.886075) (xy 47.377735 -358.842798) (xy 47.312121 -358.793256)
			(xy 47.251356 -358.737873) (xy 47.19596 -358.677119) (xy 47.146405 -358.611515) (xy 47.103114 -358.541618)
			(xy 47.066455 -358.468026) (xy 47.036742 -358.391366) (xy 47.014227 -358.312292) (xy 46.999104 -358.231477)
			(xy 46.9915 -358.149612) (xy 46.991016 -358.108504) (xy 44.837736 -358.108504) (xy 44.834097 -358.122388)
			(xy 44.808571 -358.1941) (xy 44.793154 -358.2289) (xy 44.789778 -358.237249) (xy 44.788481 -358.255202)
			(xy 44.790614 -358.263952) (xy 44.801704 -358.304153) (xy 44.817195 -358.386101) (xy 44.82495 -358.46914)
			(xy 44.825412 -358.51084) (xy 44.824852 -358.556303) (xy 44.815599 -358.646758) (xy 44.797171 -358.735798)
			(xy 44.78401 -358.779318) (xy 44.78146 -358.788893) (xy 44.783017 -358.808626) (xy 44.787058 -358.817672)
			(xy 44.805431 -358.855048) (xy 44.835897 -358.932566) (xy 44.858991 -359.012591) (xy 44.87451 -359.094423)
			(xy 44.882318 -359.177347) (xy 44.882816 -359.218992) (xy 44.882816 -359.219246) (xy 44.882312 -359.261594)
			(xy 44.874261 -359.345908) (xy 44.858232 -359.429074) (xy 44.834371 -359.510341) (xy 44.802892 -359.588971)
			(xy 44.764081 -359.664252) (xy 44.718291 -359.735504) (xy 44.665935 -359.80208) (xy 44.607487 -359.863378)
			(xy 44.543477 -359.918843) (xy 44.474485 -359.967972) (xy 44.401135 -360.010321) (xy 44.324092 -360.045505)
			(xy 44.244053 -360.073207) (xy 44.161744 -360.093175) (xy 44.077909 -360.105228) (xy 43.993308 -360.109259)
			(xy 43.908707 -360.105228) (xy 43.824872 -360.093175) (xy 43.742563 -360.073207) (xy 43.662524 -360.045505)
			(xy 43.585481 -360.010321) (xy 43.512131 -359.967972) (xy 43.443139 -359.918843) (xy 43.379129 -359.863378)
			(xy 43.320681 -359.80208) (xy 43.268325 -359.735504) (xy 43.222535 -359.664252) (xy 43.183724 -359.588971)
			(xy 43.152245 -359.510341) (xy 43.128384 -359.429074) (xy 43.112355 -359.345908) (xy 43.104304 -359.261594)
			(xy 43.1038 -359.219246) (xy 43.104356 -359.173782) (xy 43.113611 -359.083328) (xy 43.13204 -358.994288)
			(xy 43.145202 -358.950768) (xy 43.147759 -358.941194) (xy 43.146197 -358.921461) (xy 43.142154 -358.912414)
			(xy 43.123767 -358.875016) (xy 43.093286 -358.797449) (xy 43.070189 -358.717372) (xy 43.054676 -358.635487)
			(xy 43.046883 -358.552511) (xy 43.046396 -358.51084) (xy 42.259032 -358.51084) (xy 42.259504 -358.549194)
			(xy 42.258889 -358.594663) (xy 42.249552 -358.685121) (xy 42.231047 -358.774157) (xy 42.217848 -358.817672)
			(xy 42.215273 -358.827242) (xy 42.216849 -358.846979) (xy 42.220896 -358.856026) (xy 42.239309 -358.893418)
			(xy 42.269845 -358.970977) (xy 42.292996 -359.051051) (xy 42.308559 -359.132939) (xy 42.316398 -359.215923)
			(xy 42.316908 -359.2576) (xy 42.316404 -359.299961) (xy 42.308351 -359.384298) (xy 42.292317 -359.467488)
			(xy 42.268449 -359.548778) (xy 42.236961 -359.62743) (xy 42.198139 -359.702733) (xy 42.152336 -359.774005)
			(xy 42.099965 -359.840601) (xy 42.0415 -359.901916) (xy 41.977472 -359.957397) (xy 41.90846 -360.00654)
			(xy 41.83509 -360.0489) (xy 41.758025 -360.084095) (xy 41.677963 -360.111804) (xy 41.59563 -360.131778)
			(xy 41.511771 -360.143835) (xy 41.427146 -360.147867) (xy 41.342521 -360.143835) (xy 41.258662 -360.131778)
			(xy 41.176329 -360.111804) (xy 41.096267 -360.084095) (xy 41.019202 -360.0489) (xy 40.945832 -360.00654)
			(xy 40.87682 -359.957397) (xy 40.812792 -359.901916) (xy 40.754327 -359.840601) (xy 40.701956 -359.774005)
			(xy 40.656153 -359.702733) (xy 40.617331 -359.62743) (xy 40.585843 -359.548778) (xy 40.561975 -359.467488)
			(xy 40.545941 -359.384298) (xy 40.537888 -359.299961) (xy 40.537384 -359.2576) (xy 40.537998 -359.212131)
			(xy 40.547335 -359.121673) (xy 40.565841 -359.032637) (xy 40.57904 -358.989122) (xy 40.581619 -358.979553)
			(xy 40.580041 -358.959815) (xy 40.575992 -358.950768) (xy 40.557613 -358.91336) (xy 40.527071 -358.835806)
			(xy 40.503913 -358.755736) (xy 40.488342 -358.673851) (xy 40.480494 -358.59087) (xy 40.47998 -358.549194)
			(xy 2.509012 -358.549194) (xy 2.509012 -361.825848) (xy 5.986007 -361.825848) (xy 5.986007 -361.696708)
			(xy 5.993957 -361.567813) (xy 6.009827 -361.439653) (xy 6.033556 -361.312712) (xy 6.065055 -361.187473)
			(xy 6.104204 -361.06441) (xy 6.150855 -360.943991) (xy 6.20483 -360.826672) (xy 6.265925 -360.712898)
			(xy 6.333908 -360.603101) (xy 6.408522 -360.497698) (xy 6.489483 -360.397088) (xy 6.576483 -360.301653)
			(xy 6.669194 -360.211754) (xy 6.767264 -360.127733) (xy 6.870319 -360.049909) (xy 6.97797 -359.978577)
			(xy 7.089809 -359.914007) (xy 7.20541 -359.856445) (xy 7.324335 -359.806108) (xy 7.446134 -359.763188)
			(xy 7.570344 -359.727847) (xy 7.696493 -359.70022) (xy 7.824105 -359.680411) (xy 7.952694 -359.668495)
			(xy 8.081772 -359.664519) (xy 8.21085 -359.668495) (xy 8.339439 -359.680411) (xy 8.467051 -359.70022)
			(xy 8.5932 -359.727847) (xy 8.71741 -359.763188) (xy 8.839209 -359.806108) (xy 8.958134 -359.856445)
			(xy 9.073735 -359.914007) (xy 9.185574 -359.978577) (xy 9.293225 -360.049909) (xy 9.39628 -360.127733)
			(xy 9.49435 -360.211754) (xy 9.587061 -360.301653) (xy 9.674061 -360.397088) (xy 9.689764 -360.416602)
			(xy 12.542012 -360.416602) (xy 12.542012 -359.553002) (xy 12.542498 -359.525751) (xy 12.550254 -359.471803)
			(xy 12.565609 -359.419508) (xy 12.588251 -359.369931) (xy 12.617717 -359.324081) (xy 12.653408 -359.28289)
			(xy 12.694599 -359.247199) (xy 12.740449 -359.217733) (xy 12.790026 -359.195091) (xy 12.842321 -359.179736)
			(xy 12.896269 -359.17198) (xy 12.950771 -359.17198) (xy 13.004719 -359.179736) (xy 13.057014 -359.195091)
			(xy 13.106591 -359.217733) (xy 13.152441 -359.247199) (xy 13.193632 -359.28289) (xy 13.229323 -359.324081)
			(xy 13.258789 -359.369931) (xy 13.281431 -359.419508) (xy 13.296786 -359.471803) (xy 13.304542 -359.525751)
			(xy 13.305028 -359.553002) (xy 13.305028 -360.416602) (xy 13.304542 -360.443853) (xy 13.296786 -360.497801)
			(xy 13.281431 -360.550096) (xy 13.258789 -360.599673) (xy 13.229323 -360.645523) (xy 13.193632 -360.686714)
			(xy 13.152441 -360.722405) (xy 13.106591 -360.751871) (xy 13.057014 -360.774513) (xy 13.004719 -360.789868)
			(xy 12.950771 -360.797624) (xy 12.896269 -360.797624) (xy 12.842321 -360.789868) (xy 12.790026 -360.774513)
			(xy 12.740449 -360.751871) (xy 12.694599 -360.722405) (xy 12.653408 -360.686714) (xy 12.617717 -360.645523)
			(xy 12.588251 -360.599673) (xy 12.565609 -360.550096) (xy 12.550254 -360.497801) (xy 12.542498 -360.443853)
			(xy 12.542012 -360.416602) (xy 9.689764 -360.416602) (xy 9.755022 -360.497698) (xy 9.829636 -360.603101)
			(xy 9.897619 -360.712898) (xy 9.958714 -360.826672) (xy 10.012689 -360.943991) (xy 10.05934 -361.06441)
			(xy 10.098489 -361.187473) (xy 10.129988 -361.312712) (xy 10.153717 -361.439653) (xy 10.169587 -361.567813)
			(xy 10.177537 -361.696708) (xy 10.178034 -361.761278) (xy 10.177537 -361.825848) (xy 10.169587 -361.954743)
			(xy 10.153717 -362.082903) (xy 10.129988 -362.209844) (xy 10.098489 -362.335083) (xy 10.079022 -362.396278)
			(xy 165.733984 -362.396278) (xy 165.733984 -361.532678) (xy 165.73447 -361.505409) (xy 165.742232 -361.451425)
			(xy 165.757597 -361.399095) (xy 165.780254 -361.349485) (xy 165.80974 -361.303604) (xy 165.845455 -361.262387)
			(xy 165.886672 -361.226672) (xy 165.932553 -361.197186) (xy 165.982163 -361.174529) (xy 166.034493 -361.159164)
			(xy 166.088477 -361.151402) (xy 166.143015 -361.151402) (xy 166.196999 -361.159164) (xy 166.249329 -361.174529)
			(xy 166.298939 -361.197186) (xy 166.34482 -361.226672) (xy 166.386037 -361.262387) (xy 166.421752 -361.303604)
			(xy 166.451238 -361.349485) (xy 166.473895 -361.399095) (xy 166.48926 -361.451425) (xy 166.497022 -361.505409)
			(xy 166.497508 -361.532678) (xy 166.497508 -362.234988) (xy 185.144664 -362.234988) (xy 185.144664 -362.23448)
			(xy 185.145268 -362.188148) (xy 185.154941 -362.09599) (xy 185.174137 -362.005336) (xy 185.202649 -361.917167)
			(xy 185.220864 -361.874562) (xy 185.224678 -361.864622) (xy 185.224673 -361.843356) (xy 185.220864 -361.833414)
			(xy 185.202614 -361.790754) (xy 185.174071 -361.702461) (xy 185.15488 -361.611675) (xy 185.145248 -361.519384)
			(xy 185.144664 -361.472988) (xy 185.145245 -361.426592) (xy 185.154891 -361.334304) (xy 185.174088 -361.24352)
			(xy 185.202626 -361.155227) (xy 185.220864 -361.112562) (xy 185.224678 -361.102622) (xy 185.224673 -361.081356)
			(xy 185.220864 -361.071414) (xy 185.202636 -361.028813) (xy 185.17412 -360.940645) (xy 185.154929 -360.849989)
			(xy 185.145271 -360.757828) (xy 185.144664 -360.711496) (xy 185.144664 -360.710988) (xy 185.145155 -360.669886)
			(xy 185.152741 -360.588033) (xy 185.167846 -360.507229) (xy 185.190343 -360.428164) (xy 185.220039 -360.351511)
			(xy 185.25668 -360.277925) (xy 185.299955 -360.208034) (xy 185.349493 -360.142434) (xy 185.404873 -360.081684)
			(xy 185.465622 -360.026303) (xy 185.531221 -359.976764) (xy 185.601111 -359.933488) (xy 185.674696 -359.896845)
			(xy 185.751348 -359.867148) (xy 185.830414 -359.84465) (xy 185.911217 -359.829543) (xy 185.99307 -359.821956)
			(xy 186.034172 -359.82148) (xy 186.03468 -359.82148) (xy 186.081011 -359.822097) (xy 186.173169 -359.831765)
			(xy 186.263823 -359.850958) (xy 186.351992 -359.879466) (xy 186.394598 -359.89768) (xy 186.40454 -359.901486)
			(xy 186.425804 -359.901486) (xy 186.435746 -359.89768) (xy 186.478352 -359.879466) (xy 186.566519 -359.850947)
			(xy 186.657173 -359.831752) (xy 186.749332 -359.822089) (xy 186.795664 -359.82148) (xy 186.796172 -359.82148)
			(xy 186.837274 -359.821979) (xy 186.919129 -359.829561) (xy 186.999934 -359.844664) (xy 187.079001 -359.867158)
			(xy 187.155656 -359.896852) (xy 187.229243 -359.933492) (xy 187.299136 -359.976765) (xy 187.364738 -360.026303)
			(xy 187.425489 -360.081682) (xy 187.480872 -360.142431) (xy 187.530412 -360.208031) (xy 187.573689 -360.277922)
			(xy 187.610332 -360.351508) (xy 187.640029 -360.428161) (xy 187.662527 -360.507227) (xy 187.677633 -360.588032)
			(xy 187.685219 -360.669886) (xy 187.68568 -360.710988) (xy 187.68568 -360.711496) (xy 187.685072 -360.757828)
			(xy 187.684417 -360.764074) (xy 211.161635 -360.764074) (xy 211.16566 -360.621882) (xy 211.177723 -360.480146)
			(xy 211.197786 -360.33932) (xy 211.225784 -360.199854) (xy 211.261628 -360.062195) (xy 211.305202 -359.926785)
			(xy 211.356367 -359.794057) (xy 211.41496 -359.664436) (xy 211.480791 -359.538338) (xy 211.553652 -359.416166)
			(xy 211.633307 -359.298312) (xy 211.719503 -359.185153) (xy 211.811962 -359.077051) (xy 211.91039 -358.974354)
			(xy 212.014469 -358.87739) (xy 212.123868 -358.78647) (xy 212.238236 -358.701884) (xy 212.357205 -358.623904)
			(xy 212.480396 -358.55278) (xy 212.607413 -358.488739) (xy 212.73785 -358.431987) (xy 212.871289 -358.382705)
			(xy 213.007302 -358.341051) (xy 213.145454 -358.307159) (xy 213.285303 -358.281138) (xy 213.426399 -358.26307)
			(xy 213.568291 -358.253013) (xy 213.710526 -358.251) (xy 213.852646 -358.257037) (xy 213.994197 -358.271105)
			(xy 214.134726 -358.293159) (xy 214.273781 -358.323128) (xy 214.410919 -358.360916) (xy 214.545699 -358.406402)
			(xy 214.67769 -358.45944) (xy 214.806469 -358.519861) (xy 214.931623 -358.58747) (xy 215.052751 -358.662052)
			(xy 215.169467 -358.743368) (xy 215.281395 -358.831156) (xy 215.388177 -358.925136) (xy 215.489471 -359.025006)
			(xy 215.584952 -359.130448) (xy 215.674316 -359.241122) (xy 215.757274 -359.356675) (xy 215.833563 -359.476736)
			(xy 215.902937 -359.600921) (xy 215.965174 -359.728832) (xy 216.020075 -359.860059) (xy 216.067463 -359.994182)
			(xy 216.107188 -360.130771) (xy 216.139121 -360.269389) (xy 216.163162 -360.409591) (xy 216.179231 -360.550929)
			(xy 216.187279 -360.69295) (xy 216.187782 -360.764074) (xy 255.611635 -360.764074) (xy 255.61566 -360.621882)
			(xy 255.627723 -360.480146) (xy 255.647786 -360.33932) (xy 255.675784 -360.199854) (xy 255.711628 -360.062195)
			(xy 255.755202 -359.926785) (xy 255.806367 -359.794057) (xy 255.86496 -359.664436) (xy 255.930791 -359.538338)
			(xy 256.003652 -359.416166) (xy 256.083307 -359.298312) (xy 256.169503 -359.185153) (xy 256.261962 -359.077051)
			(xy 256.36039 -358.974354) (xy 256.464469 -358.87739) (xy 256.573868 -358.78647) (xy 256.688236 -358.701884)
			(xy 256.807205 -358.623904) (xy 256.930396 -358.55278) (xy 257.057413 -358.488739) (xy 257.18785 -358.431987)
			(xy 257.321289 -358.382705) (xy 257.457302 -358.341051) (xy 257.595454 -358.307159) (xy 257.735303 -358.281138)
			(xy 257.876399 -358.26307) (xy 258.018291 -358.253013) (xy 258.160526 -358.251) (xy 258.302646 -358.257037)
			(xy 258.444197 -358.271105) (xy 258.584726 -358.293159) (xy 258.723781 -358.323128) (xy 258.860919 -358.360916)
			(xy 258.995699 -358.406402) (xy 259.12769 -358.45944) (xy 259.256469 -358.519861) (xy 259.381623 -358.58747)
			(xy 259.502751 -358.662052) (xy 259.619467 -358.743368) (xy 259.652996 -358.769666) (xy 294.901627 -358.769666)
			(xy 294.905632 -358.663917) (xy 294.917622 -358.558774) (xy 294.937531 -358.454839) (xy 294.965242 -358.352707)
			(xy 295.000599 -358.252963) (xy 295.043397 -358.156179) (xy 295.093393 -358.062909) (xy 295.1503 -357.973688)
			(xy 295.213791 -357.889025) (xy 295.283503 -357.809407) (xy 295.359037 -357.735289) (xy 295.43996 -357.667096)
			(xy 295.525809 -357.605218) (xy 295.616092 -357.550011) (xy 295.710291 -357.501789) (xy 295.807868 -357.460829)
			(xy 295.908263 -357.427367) (xy 296.010901 -357.401593) (xy 296.115194 -357.383655) (xy 296.220545 -357.373656)
			(xy 296.326351 -357.371653) (xy 296.432005 -357.377658) (xy 296.536902 -357.391637) (xy 296.640442 -357.413508)
			(xy 296.742031 -357.443148) (xy 296.841088 -357.480386) (xy 296.937045 -357.525008) (xy 297.029352 -357.57676)
			(xy 297.117481 -357.635345) (xy 297.200927 -357.700427) (xy 297.279211 -357.771633) (xy 297.351886 -357.848556)
			(xy 297.418536 -357.930756) (xy 297.478778 -358.01776) (xy 297.532267 -358.109071) (xy 297.578698 -358.204166)
			(xy 297.617803 -358.3025) (xy 297.64936 -358.403511) (xy 297.673187 -358.506618) (xy 297.689148 -358.611232)
			(xy 297.697152 -358.716754) (xy 297.697652 -358.769666) (xy 297.697152 -358.822578) (xy 297.689148 -358.9281)
			(xy 297.673187 -359.032714) (xy 297.64936 -359.135821) (xy 297.617803 -359.236832) (xy 297.578698 -359.335166)
			(xy 297.532267 -359.430261) (xy 297.478778 -359.521572) (xy 297.418536 -359.608576) (xy 297.351886 -359.690776)
			(xy 297.279211 -359.767699) (xy 297.200927 -359.838905) (xy 297.117481 -359.903987) (xy 297.029352 -359.962572)
			(xy 296.937045 -360.014324) (xy 296.841088 -360.058946) (xy 296.742031 -360.096184) (xy 296.640442 -360.125824)
			(xy 296.536902 -360.147695) (xy 296.432005 -360.161674) (xy 296.326351 -360.167679) (xy 296.220545 -360.165676)
			(xy 296.115194 -360.155677) (xy 296.010901 -360.137739) (xy 295.908263 -360.111965) (xy 295.807868 -360.078503)
			(xy 295.710291 -360.037543) (xy 295.616092 -359.989321) (xy 295.525809 -359.934114) (xy 295.43996 -359.872236)
			(xy 295.359037 -359.804043) (xy 295.283503 -359.729925) (xy 295.213791 -359.650307) (xy 295.1503 -359.565644)
			(xy 295.093393 -359.476423) (xy 295.043397 -359.383153) (xy 295.000599 -359.286369) (xy 294.965242 -359.186625)
			(xy 294.937531 -359.084493) (xy 294.917622 -358.980558) (xy 294.905632 -358.875415) (xy 294.901627 -358.769666)
			(xy 259.652996 -358.769666) (xy 259.731395 -358.831156) (xy 259.838177 -358.925136) (xy 259.939471 -359.025006)
			(xy 260.034952 -359.130448) (xy 260.124316 -359.241122) (xy 260.207274 -359.356675) (xy 260.283563 -359.476736)
			(xy 260.352937 -359.600921) (xy 260.415174 -359.728832) (xy 260.470075 -359.860059) (xy 260.517463 -359.994182)
			(xy 260.557188 -360.130771) (xy 260.589121 -360.269389) (xy 260.613162 -360.409591) (xy 260.629231 -360.550929)
			(xy 260.637279 -360.69295) (xy 260.637782 -360.764074) (xy 260.637279 -360.835198) (xy 260.629231 -360.977219)
			(xy 260.613162 -361.118557) (xy 260.589121 -361.258759) (xy 260.557188 -361.397377) (xy 260.517463 -361.533966)
			(xy 260.470075 -361.668089) (xy 260.415174 -361.799316) (xy 260.401302 -361.827826) (xy 430.615097 -361.827826)
			(xy 430.619102 -361.722077) (xy 430.631092 -361.616934) (xy 430.651001 -361.512999) (xy 430.678712 -361.410867)
			(xy 430.714069 -361.311123) (xy 430.756867 -361.214339) (xy 430.806863 -361.121069) (xy 430.86377 -361.031848)
			(xy 430.927261 -360.947185) (xy 430.996973 -360.867567) (xy 431.072507 -360.793449) (xy 431.15343 -360.725256)
			(xy 431.239279 -360.663378) (xy 431.329562 -360.608171) (xy 431.423761 -360.559949) (xy 431.521338 -360.518989)
			(xy 431.621733 -360.485527) (xy 431.724371 -360.459753) (xy 431.828664 -360.441815) (xy 431.934015 -360.431816)
			(xy 432.039821 -360.429813) (xy 432.145475 -360.435818) (xy 432.250372 -360.449797) (xy 432.353912 -360.471668)
			(xy 432.455501 -360.501308) (xy 432.554558 -360.538546) (xy 432.650515 -360.583168) (xy 432.742822 -360.63492)
			(xy 432.830951 -360.693505) (xy 432.914397 -360.758587) (xy 432.992681 -360.829793) (xy 433.065356 -360.906716)
			(xy 433.132006 -360.988916) (xy 433.192248 -361.07592) (xy 433.245737 -361.167231) (xy 433.292168 -361.262326)
			(xy 433.331273 -361.36066) (xy 433.36283 -361.461671) (xy 433.370787 -361.496102) (xy 434.579776 -361.496102)
			(xy 434.580404 -361.4497) (xy 434.590093 -361.357403) (xy 434.609347 -361.266617) (xy 434.637954 -361.178332)
			(xy 434.65623 -361.135676) (xy 434.660038 -361.125734) (xy 434.660039 -361.10447) (xy 434.65623 -361.094528)
			(xy 434.637968 -361.051867) (xy 434.609375 -360.963579) (xy 434.590118 -360.872796) (xy 434.580405 -360.780503)
			(xy 434.579776 -360.734102) (xy 434.580404 -360.6877) (xy 434.590093 -360.595403) (xy 434.609347 -360.504617)
			(xy 434.637954 -360.416332) (xy 434.65623 -360.373676) (xy 434.660038 -360.363734) (xy 434.660039 -360.34247)
			(xy 434.65623 -360.332528) (xy 434.637968 -360.289867) (xy 434.609375 -360.201579) (xy 434.590118 -360.110796)
			(xy 434.580405 -360.018503) (xy 434.579776 -359.972102) (xy 434.5802 -359.930986) (xy 434.587788 -359.849105)
			(xy 434.602898 -359.768273) (xy 434.625402 -359.68918) (xy 434.655109 -359.612502) (xy 434.691763 -359.538891)
			(xy 434.735054 -359.468977) (xy 434.784611 -359.403355) (xy 434.840011 -359.342586) (xy 434.900783 -359.287188)
			(xy 434.966406 -359.237634) (xy 435.036323 -359.194346) (xy 435.109935 -359.157694) (xy 435.186615 -359.127991)
			(xy 435.265708 -359.10549) (xy 435.346541 -359.090383) (xy 435.428422 -359.082799) (xy 435.469538 -359.08234)
			(xy 435.51594 -359.082957) (xy 435.608238 -359.09265) (xy 435.699023 -359.111907) (xy 435.787308 -359.140517)
			(xy 435.829964 -359.158794) (xy 435.839906 -359.1626) (xy 435.86117 -359.1626) (xy 435.871112 -359.158794)
			(xy 435.913767 -359.140517) (xy 436.002057 -359.111928) (xy 436.092842 -359.092675) (xy 436.185137 -359.082967)
			(xy 436.231538 -359.08234) (xy 436.272653 -359.082777) (xy 436.354532 -359.090367) (xy 436.435361 -359.10548)
			(xy 436.514451 -359.127986) (xy 436.591127 -359.157693) (xy 436.664735 -359.194349) (xy 436.734647 -359.237639)
			(xy 436.800266 -359.287195) (xy 436.861034 -359.342595) (xy 436.91643 -359.403364) (xy 436.965984 -359.468986)
			(xy 437.009271 -359.5389) (xy 437.045923 -359.61251) (xy 437.075627 -359.689187) (xy 437.098129 -359.768278)
			(xy 437.113238 -359.849108) (xy 437.120825 -359.930987) (xy 437.1213 -359.972102) (xy 437.120676 -360.018504)
			(xy 437.110985 -360.110802) (xy 437.091731 -360.201587) (xy 437.063122 -360.289872) (xy 437.044846 -360.332528)
			(xy 437.041037 -360.34247) (xy 437.041038 -360.363734) (xy 437.044846 -360.373676) (xy 437.063108 -360.416337)
			(xy 437.091701 -360.504625) (xy 437.110959 -360.595408) (xy 437.120671 -360.687701) (xy 437.1213 -360.734102)
			(xy 437.120676 -360.780504) (xy 437.110985 -360.872802) (xy 437.091731 -360.963587) (xy 437.063122 -361.051872)
			(xy 437.044846 -361.094528) (xy 437.041037 -361.10447) (xy 437.041038 -361.125734) (xy 437.044846 -361.135676)
			(xy 437.063108 -361.178337) (xy 437.091701 -361.266625) (xy 437.110959 -361.357408) (xy 437.120671 -361.449701)
			(xy 437.1213 -361.496102) (xy 437.120789 -361.537215) (xy 437.113202 -361.619091) (xy 437.098093 -361.699917)
			(xy 437.075592 -361.779004) (xy 437.045889 -361.855678) (xy 437.009238 -361.929285) (xy 436.965952 -361.999196)
			(xy 436.916401 -362.064814) (xy 436.861007 -362.125581) (xy 436.800242 -362.180978) (xy 436.734625 -362.230532)
			(xy 436.664716 -362.273821) (xy 436.591111 -362.310474) (xy 436.514439 -362.34018) (xy 436.435352 -362.362685)
			(xy 436.354526 -362.377797) (xy 436.272651 -362.385387) (xy 436.231538 -362.385864) (xy 436.185135 -362.385256)
			(xy 436.092838 -362.37556) (xy 436.002052 -362.356301) (xy 435.913768 -362.327688) (xy 435.871112 -362.30941)
			(xy 435.86117 -362.305604) (xy 435.839906 -362.305604) (xy 435.829964 -362.30941) (xy 435.787299 -362.327662)
			(xy 435.699012 -362.356257) (xy 435.608231 -362.375517) (xy 435.515939 -362.385233) (xy 435.469538 -362.385864)
			(xy 435.428424 -362.385365) (xy 435.346546 -362.377782) (xy 435.265717 -362.362675) (xy 435.186627 -362.340175)
			(xy 435.10995 -362.310473) (xy 435.036341 -362.273823) (xy 434.966428 -362.230538) (xy 434.900807 -362.180986)
			(xy 434.840038 -362.12559) (xy 434.78464 -362.064824) (xy 434.735085 -361.999205) (xy 434.691796 -361.929294)
			(xy 434.655143 -361.855686) (xy 434.625438 -361.779011) (xy 434.602934 -361.699922) (xy 434.587824 -361.619094)
			(xy 434.580237 -361.537216) (xy 434.579776 -361.496102) (xy 433.370787 -361.496102) (xy 433.386657 -361.564778)
			(xy 433.402618 -361.669392) (xy 433.410622 -361.774914) (xy 433.411122 -361.827826) (xy 433.410622 -361.880738)
			(xy 433.402618 -361.98626) (xy 433.386657 -362.090874) (xy 433.36283 -362.193981) (xy 433.331273 -362.294992)
			(xy 433.292168 -362.393326) (xy 433.245737 -362.488421) (xy 433.192248 -362.579732) (xy 433.132006 -362.666736)
			(xy 433.065356 -362.748936) (xy 432.992681 -362.825859) (xy 432.914397 -362.897065) (xy 432.830951 -362.962147)
			(xy 432.742822 -363.020732) (xy 432.650515 -363.072484) (xy 432.554558 -363.117106) (xy 432.455501 -363.154344)
			(xy 432.353912 -363.183984) (xy 432.250372 -363.205855) (xy 432.145475 -363.219834) (xy 432.039821 -363.225839)
			(xy 431.934015 -363.223836) (xy 431.828664 -363.213837) (xy 431.724371 -363.195899) (xy 431.621733 -363.170125)
			(xy 431.521338 -363.136663) (xy 431.423761 -363.095703) (xy 431.329562 -363.047481) (xy 431.239279 -362.992274)
			(xy 431.15343 -362.930396) (xy 431.072507 -362.862203) (xy 430.996973 -362.788085) (xy 430.927261 -362.708467)
			(xy 430.86377 -362.623804) (xy 430.806863 -362.534583) (xy 430.756867 -362.441313) (xy 430.714069 -362.344529)
			(xy 430.678712 -362.244785) (xy 430.651001 -362.142653) (xy 430.631092 -362.038718) (xy 430.619102 -361.933575)
			(xy 430.615097 -361.827826) (xy 260.401302 -361.827826) (xy 260.352937 -361.927227) (xy 260.283563 -362.051412)
			(xy 260.207274 -362.171473) (xy 260.124316 -362.287026) (xy 260.034952 -362.3977) (xy 259.939471 -362.503142)
			(xy 259.838177 -362.603012) (xy 259.731395 -362.696992) (xy 259.619467 -362.78478) (xy 259.502751 -362.866096)
			(xy 259.381623 -362.940678) (xy 259.256469 -363.008287) (xy 259.12769 -363.068708) (xy 258.995699 -363.121746)
			(xy 258.860919 -363.167232) (xy 258.723781 -363.20502) (xy 258.584726 -363.234989) (xy 258.444197 -363.257043)
			(xy 258.302646 -363.271111) (xy 258.160526 -363.277148) (xy 258.018291 -363.275135) (xy 257.876399 -363.265078)
			(xy 257.735303 -363.24701) (xy 257.595454 -363.220989) (xy 257.457302 -363.187097) (xy 257.321289 -363.145443)
			(xy 257.18785 -363.096161) (xy 257.057413 -363.039409) (xy 256.930396 -362.975368) (xy 256.807205 -362.904244)
			(xy 256.688236 -362.826264) (xy 256.573868 -362.741678) (xy 256.464469 -362.650758) (xy 256.36039 -362.553794)
			(xy 256.261962 -362.451097) (xy 256.169503 -362.342995) (xy 256.083307 -362.229836) (xy 256.003652 -362.111982)
			(xy 255.930791 -361.98981) (xy 255.86496 -361.863712) (xy 255.806367 -361.734091) (xy 255.755202 -361.601363)
			(xy 255.711628 -361.465953) (xy 255.675784 -361.328294) (xy 255.647786 -361.188828) (xy 255.627723 -361.048002)
			(xy 255.61566 -360.906266) (xy 255.611635 -360.764074) (xy 216.187782 -360.764074) (xy 216.187279 -360.835198)
			(xy 216.179231 -360.977219) (xy 216.163162 -361.118557) (xy 216.139121 -361.258759) (xy 216.107188 -361.397377)
			(xy 216.067463 -361.533966) (xy 216.020075 -361.668089) (xy 215.965174 -361.799316) (xy 215.902937 -361.927227)
			(xy 215.833563 -362.051412) (xy 215.757274 -362.171473) (xy 215.674316 -362.287026) (xy 215.584952 -362.3977)
			(xy 215.489471 -362.503142) (xy 215.388177 -362.603012) (xy 215.281395 -362.696992) (xy 215.169467 -362.78478)
			(xy 215.052751 -362.866096) (xy 214.931623 -362.940678) (xy 214.806469 -363.008287) (xy 214.67769 -363.068708)
			(xy 214.545699 -363.121746) (xy 214.410919 -363.167232) (xy 214.273781 -363.20502) (xy 214.134726 -363.234989)
			(xy 213.994197 -363.257043) (xy 213.852646 -363.271111) (xy 213.710526 -363.277148) (xy 213.568291 -363.275135)
			(xy 213.426399 -363.265078) (xy 213.285303 -363.24701) (xy 213.145454 -363.220989) (xy 213.007302 -363.187097)
			(xy 212.871289 -363.145443) (xy 212.73785 -363.096161) (xy 212.607413 -363.039409) (xy 212.480396 -362.975368)
			(xy 212.357205 -362.904244) (xy 212.238236 -362.826264) (xy 212.123868 -362.741678) (xy 212.014469 -362.650758)
			(xy 211.91039 -362.553794) (xy 211.811962 -362.451097) (xy 211.719503 -362.342995) (xy 211.633307 -362.229836)
			(xy 211.553652 -362.111982) (xy 211.480791 -361.98981) (xy 211.41496 -361.863712) (xy 211.356367 -361.734091)
			(xy 211.305202 -361.601363) (xy 211.261628 -361.465953) (xy 211.225784 -361.328294) (xy 211.197786 -361.188828)
			(xy 211.177723 -361.048002) (xy 211.16566 -360.906266) (xy 211.161635 -360.764074) (xy 187.684417 -360.764074)
			(xy 187.675402 -360.849986) (xy 187.656207 -360.94064) (xy 187.627695 -361.028809) (xy 187.60948 -361.071414)
			(xy 187.605683 -361.081359) (xy 187.605679 -361.10262) (xy 187.60948 -361.112562) (xy 187.627719 -361.155227)
			(xy 187.656265 -361.243518) (xy 187.67546 -361.334302) (xy 187.685094 -361.426592) (xy 187.68568 -361.472988)
			(xy 187.685095 -361.519384) (xy 187.675451 -361.611672) (xy 187.656256 -361.702456) (xy 187.627718 -361.790749)
			(xy 187.60948 -361.833414) (xy 187.605683 -361.843359) (xy 187.605679 -361.86462) (xy 187.60948 -361.874562)
			(xy 187.627696 -361.917167) (xy 187.656216 -362.005334) (xy 187.67541 -362.095988) (xy 187.685071 -362.188148)
			(xy 187.68568 -362.23448) (xy 187.68568 -362.234988) (xy 187.685236 -362.276092) (xy 187.677652 -362.357949)
			(xy 187.664078 -362.430568) (xy 190.281567 -362.430568) (xy 190.285572 -362.324819) (xy 190.297562 -362.219676)
			(xy 190.317471 -362.115741) (xy 190.345182 -362.013609) (xy 190.380539 -361.913865) (xy 190.423337 -361.817081)
			(xy 190.473333 -361.723811) (xy 190.53024 -361.63459) (xy 190.593731 -361.549927) (xy 190.663443 -361.470309)
			(xy 190.738977 -361.396191) (xy 190.8199 -361.327998) (xy 190.905749 -361.26612) (xy 190.996032 -361.210913)
			(xy 191.090231 -361.162691) (xy 191.187808 -361.121731) (xy 191.288203 -361.088269) (xy 191.390841 -361.062495)
			(xy 191.495134 -361.044557) (xy 191.600485 -361.034558) (xy 191.706291 -361.032555) (xy 191.811945 -361.03856)
			(xy 191.916842 -361.052539) (xy 192.020382 -361.07441) (xy 192.121971 -361.10405) (xy 192.221028 -361.141288)
			(xy 192.316985 -361.18591) (xy 192.409292 -361.237662) (xy 192.497421 -361.296247) (xy 192.580867 -361.361329)
			(xy 192.659151 -361.432535) (xy 192.731826 -361.509458) (xy 192.798476 -361.591658) (xy 192.858718 -361.678662)
			(xy 192.912207 -361.769973) (xy 192.958638 -361.865068) (xy 192.997743 -361.963402) (xy 193.0293 -362.064413)
			(xy 193.053127 -362.16752) (xy 193.069088 -362.272134) (xy 193.077092 -362.377656) (xy 193.077592 -362.430568)
			(xy 193.077092 -362.48348) (xy 193.069088 -362.589002) (xy 193.053127 -362.693616) (xy 193.0293 -362.796723)
			(xy 192.997743 -362.897734) (xy 192.958638 -362.996068) (xy 192.912207 -363.091163) (xy 192.858718 -363.182474)
			(xy 192.798476 -363.269478) (xy 192.731826 -363.351678) (xy 192.659151 -363.428601) (xy 192.580867 -363.499807)
			(xy 192.497421 -363.564889) (xy 192.409292 -363.623474) (xy 192.316985 -363.675226) (xy 192.221028 -363.719848)
			(xy 192.121971 -363.757086) (xy 192.020382 -363.786726) (xy 191.916842 -363.808597) (xy 191.811945 -363.822576)
			(xy 191.706291 -363.828581) (xy 191.600485 -363.826578) (xy 191.495134 -363.816579) (xy 191.390841 -363.798641)
			(xy 191.288203 -363.772867) (xy 191.187808 -363.739405) (xy 191.090231 -363.698445) (xy 190.996032 -363.650223)
			(xy 190.905749 -363.595016) (xy 190.8199 -363.533138) (xy 190.738977 -363.464945) (xy 190.663443 -363.390827)
			(xy 190.593731 -363.311209) (xy 190.53024 -363.226546) (xy 190.473333 -363.137325) (xy 190.423337 -363.044055)
			(xy 190.380539 -362.947271) (xy 190.345182 -362.847527) (xy 190.317471 -362.745395) (xy 190.297562 -362.64146)
			(xy 190.285572 -362.536317) (xy 190.281567 -362.430568) (xy 187.664078 -362.430568) (xy 187.662547 -362.438757)
			(xy 187.64005 -362.517826) (xy 187.610354 -362.594483) (xy 187.573711 -362.668072) (xy 187.530434 -362.737966)
			(xy 187.480892 -362.803569) (xy 187.425509 -362.86432) (xy 187.364756 -362.919703) (xy 187.299153 -362.969243)
			(xy 187.229258 -363.012519) (xy 187.155668 -363.04916) (xy 187.079011 -363.078856) (xy 186.999941 -363.101351)
			(xy 186.919133 -363.116454) (xy 186.837276 -363.124037) (xy 186.796172 -363.124496) (xy 186.795664 -363.124496)
			(xy 186.749333 -363.123866) (xy 186.657176 -363.114202) (xy 186.566521 -363.095013) (xy 186.478352 -363.066508)
			(xy 186.435746 -363.048296) (xy 186.425804 -363.04449) (xy 186.40454 -363.04449) (xy 186.394598 -363.048296)
			(xy 186.351999 -363.066527) (xy 186.26383 -363.095042) (xy 186.173173 -363.114232) (xy 186.081013 -363.123889)
			(xy 186.03468 -363.124496) (xy 186.034172 -363.124496) (xy 185.993069 -363.12406) (xy 185.911213 -363.116473)
			(xy 185.830407 -363.101365) (xy 185.751339 -363.078866) (xy 185.674684 -363.049167) (xy 185.601097 -363.012522)
			(xy 185.531204 -362.969244) (xy 185.465603 -362.919702) (xy 185.404853 -362.864319) (xy 185.349472 -362.803566)
			(xy 185.299933 -362.737963) (xy 185.256658 -362.668068) (xy 185.220017 -362.594479) (xy 185.190322 -362.517823)
			(xy 185.167826 -362.438755) (xy 185.152722 -362.357947) (xy 185.145138 -362.276091) (xy 185.144664 -362.234988)
			(xy 166.497508 -362.234988) (xy 166.497508 -362.396278) (xy 166.497022 -362.423547) (xy 166.48926 -362.477531)
			(xy 166.473895 -362.529861) (xy 166.451238 -362.579471) (xy 166.421752 -362.625352) (xy 166.386037 -362.666569)
			(xy 166.34482 -362.702284) (xy 166.298939 -362.73177) (xy 166.249329 -362.754427) (xy 166.196999 -362.769792)
			(xy 166.143015 -362.777554) (xy 166.088477 -362.777554) (xy 166.034493 -362.769792) (xy 165.982163 -362.754427)
			(xy 165.932553 -362.73177) (xy 165.886672 -362.702284) (xy 165.845455 -362.666569) (xy 165.80974 -362.625352)
			(xy 165.780254 -362.579471) (xy 165.757597 -362.529861) (xy 165.742232 -362.477531) (xy 165.73447 -362.423547)
			(xy 165.733984 -362.396278) (xy 10.079022 -362.396278) (xy 10.05934 -362.458146) (xy 10.012689 -362.578565)
			(xy 9.958714 -362.695884) (xy 9.897619 -362.809658) (xy 9.829636 -362.919455) (xy 9.755022 -363.024858)
			(xy 9.674061 -363.125468) (xy 9.587061 -363.220903) (xy 9.49435 -363.310802) (xy 9.39628 -363.394823)
			(xy 9.293225 -363.472647) (xy 9.185574 -363.543979) (xy 9.073735 -363.608549) (xy 8.958134 -363.666111)
			(xy 8.839209 -363.716448) (xy 8.71741 -363.759368) (xy 8.5932 -363.794709) (xy 8.467051 -363.822336)
			(xy 8.339439 -363.842145) (xy 8.21085 -363.854061) (xy 8.081772 -363.858038) (xy 7.952694 -363.854061)
			(xy 7.824105 -363.842145) (xy 7.696493 -363.822336) (xy 7.570344 -363.794709) (xy 7.446134 -363.759368)
			(xy 7.324335 -363.716448) (xy 7.20541 -363.666111) (xy 7.089809 -363.608549) (xy 6.97797 -363.543979)
			(xy 6.870319 -363.472647) (xy 6.767264 -363.394823) (xy 6.669194 -363.310802) (xy 6.576483 -363.220903)
			(xy 6.489483 -363.125468) (xy 6.408522 -363.024858) (xy 6.333908 -362.919455) (xy 6.265925 -362.809658)
			(xy 6.20483 -362.695884) (xy 6.150855 -362.578565) (xy 6.104204 -362.458146) (xy 6.065055 -362.335083)
			(xy 6.033556 -362.209844) (xy 6.009827 -362.082903) (xy 5.993957 -361.954743) (xy 5.986007 -361.825848)
			(xy 2.509012 -361.825848) (xy 2.509012 -369.062565) (xy 44.335754 -369.062565) (xy 44.335754 -369.008035)
			(xy 44.343514 -368.95406) (xy 44.358876 -368.901738) (xy 44.381527 -368.852135) (xy 44.411006 -368.806259)
			(xy 44.446714 -368.765046) (xy 44.487923 -368.729334) (xy 44.533794 -368.699849) (xy 44.583395 -368.677192)
			(xy 44.635715 -368.661824) (xy 44.689689 -368.654057) (xy 44.716954 -368.653568) (xy 45.580554 -368.653568)
			(xy 45.607829 -368.653968) (xy 45.661825 -368.661726) (xy 45.714168 -368.677089) (xy 45.763791 -368.699746)
			(xy 45.809684 -368.729235) (xy 45.850912 -368.764955) (xy 45.886638 -368.80618) (xy 45.916132 -368.852069)
			(xy 45.938795 -368.901689) (xy 45.954164 -368.95403) (xy 45.961928 -369.008025) (xy 45.961928 -369.062565)
			(xy 51.142954 -369.062565) (xy 51.142954 -369.008035) (xy 51.150714 -368.95406) (xy 51.166076 -368.901738)
			(xy 51.188727 -368.852135) (xy 51.218206 -368.806259) (xy 51.253914 -368.765046) (xy 51.295123 -368.729334)
			(xy 51.340994 -368.699849) (xy 51.390595 -368.677192) (xy 51.442915 -368.661824) (xy 51.496889 -368.654057)
			(xy 51.524154 -368.653568) (xy 52.387754 -368.653568) (xy 52.415029 -368.653968) (xy 52.469025 -368.661726)
			(xy 52.521368 -368.677089) (xy 52.570991 -368.699746) (xy 52.616884 -368.729235) (xy 52.658112 -368.764955)
			(xy 52.693838 -368.80618) (xy 52.723332 -368.852069) (xy 52.745995 -368.901689) (xy 52.761364 -368.95403)
			(xy 52.769128 -369.008025) (xy 52.769128 -369.062565) (xy 57.950154 -369.062565) (xy 57.950154 -369.008035)
			(xy 57.957914 -368.95406) (xy 57.973276 -368.901738) (xy 57.995927 -368.852135) (xy 58.025406 -368.806259)
			(xy 58.061114 -368.765046) (xy 58.102323 -368.729334) (xy 58.148194 -368.699849) (xy 58.197795 -368.677192)
			(xy 58.250115 -368.661824) (xy 58.304089 -368.654057) (xy 58.331354 -368.653568) (xy 59.194954 -368.653568)
			(xy 59.222229 -368.653968) (xy 59.276225 -368.661726) (xy 59.328568 -368.677089) (xy 59.378191 -368.699746)
			(xy 59.424084 -368.729235) (xy 59.465312 -368.764955) (xy 59.501038 -368.80618) (xy 59.530532 -368.852069)
			(xy 59.553195 -368.901689) (xy 59.568564 -368.95403) (xy 59.576328 -369.008025) (xy 59.576328 -369.062565)
			(xy 64.757354 -369.062565) (xy 64.757354 -369.008035) (xy 64.765114 -368.95406) (xy 64.780476 -368.901738)
			(xy 64.803127 -368.852135) (xy 64.832606 -368.806259) (xy 64.868314 -368.765046) (xy 64.909523 -368.729334)
			(xy 64.955394 -368.699849) (xy 65.004995 -368.677192) (xy 65.057315 -368.661824) (xy 65.111289 -368.654057)
			(xy 65.138554 -368.653568) (xy 66.002154 -368.653568) (xy 66.029429 -368.653968) (xy 66.083425 -368.661726)
			(xy 66.135768 -368.677089) (xy 66.185391 -368.699746) (xy 66.231284 -368.729235) (xy 66.272512 -368.764955)
			(xy 66.308238 -368.80618) (xy 66.337732 -368.852069) (xy 66.360395 -368.901689) (xy 66.375764 -368.95403)
			(xy 66.383528 -369.008025) (xy 66.383528 -369.062565) (xy 68.160954 -369.062565) (xy 68.160954 -369.008035)
			(xy 68.168714 -368.95406) (xy 68.184076 -368.901738) (xy 68.206727 -368.852135) (xy 68.236206 -368.806259)
			(xy 68.271914 -368.765046) (xy 68.313123 -368.729334) (xy 68.358994 -368.699849) (xy 68.408595 -368.677192)
			(xy 68.460915 -368.661824) (xy 68.514889 -368.654057) (xy 68.542154 -368.653568) (xy 69.405754 -368.653568)
			(xy 69.433029 -368.653968) (xy 69.487025 -368.661726) (xy 69.539368 -368.677089) (xy 69.588991 -368.699746)
			(xy 69.634884 -368.729235) (xy 69.676112 -368.764955) (xy 69.711838 -368.80618) (xy 69.741332 -368.852069)
			(xy 69.763995 -368.901689) (xy 69.779364 -368.95403) (xy 69.787128 -369.008025) (xy 69.787128 -369.062569)
			(xy 76.863431 -369.062569) (xy 76.863431 -369.008031) (xy 76.871193 -368.954048) (xy 76.886558 -368.90172)
			(xy 76.909214 -368.85211) (xy 76.9387 -368.80623) (xy 76.974414 -368.765013) (xy 77.015632 -368.729298)
			(xy 77.061512 -368.699813) (xy 77.111121 -368.677157) (xy 77.16345 -368.661793) (xy 77.217433 -368.654031)
			(xy 77.244702 -368.653568) (xy 78.108302 -368.653568) (xy 78.135573 -368.653995) (xy 78.189561 -368.661757)
			(xy 78.241894 -368.677124) (xy 78.291508 -368.699782) (xy 78.337393 -368.72927) (xy 78.378613 -368.764988)
			(xy 78.414331 -368.806209) (xy 78.443819 -368.852093) (xy 78.466477 -368.901707) (xy 78.481843 -368.954041)
			(xy 78.489606 -369.008029) (xy 78.489606 -369.062569) (xy 83.670631 -369.062569) (xy 83.670631 -369.008031)
			(xy 83.678393 -368.954048) (xy 83.693758 -368.90172) (xy 83.716414 -368.85211) (xy 83.7459 -368.80623)
			(xy 83.781614 -368.765013) (xy 83.822832 -368.729298) (xy 83.868712 -368.699813) (xy 83.918321 -368.677157)
			(xy 83.97065 -368.661793) (xy 84.024633 -368.654031) (xy 84.051902 -368.653568) (xy 84.915502 -368.653568)
			(xy 84.942773 -368.653995) (xy 84.996761 -368.661757) (xy 85.049094 -368.677124) (xy 85.098708 -368.699782)
			(xy 85.144593 -368.72927) (xy 85.185813 -368.764988) (xy 85.221531 -368.806209) (xy 85.251019 -368.852093)
			(xy 85.273677 -368.901707) (xy 85.289043 -368.954041) (xy 85.296806 -369.008029) (xy 85.296806 -369.062569)
			(xy 90.477831 -369.062569) (xy 90.477831 -369.008031) (xy 90.485593 -368.954048) (xy 90.500958 -368.90172)
			(xy 90.523614 -368.85211) (xy 90.5531 -368.80623) (xy 90.588814 -368.765013) (xy 90.630032 -368.729298)
			(xy 90.675912 -368.699813) (xy 90.725521 -368.677157) (xy 90.77785 -368.661793) (xy 90.831833 -368.654031)
			(xy 90.859102 -368.653568) (xy 91.722702 -368.653568) (xy 91.749973 -368.653995) (xy 91.803961 -368.661757)
			(xy 91.856294 -368.677124) (xy 91.905908 -368.699782) (xy 91.951793 -368.72927) (xy 91.993013 -368.764988)
			(xy 92.028731 -368.806209) (xy 92.058219 -368.852093) (xy 92.080877 -368.901707) (xy 92.096243 -368.954041)
			(xy 92.104006 -369.008029) (xy 92.104006 -369.062569) (xy 97.285031 -369.062569) (xy 97.285031 -369.008031)
			(xy 97.292793 -368.954048) (xy 97.308158 -368.90172) (xy 97.330814 -368.85211) (xy 97.3603 -368.80623)
			(xy 97.396014 -368.765013) (xy 97.437232 -368.729298) (xy 97.483112 -368.699813) (xy 97.532721 -368.677157)
			(xy 97.58505 -368.661793) (xy 97.639033 -368.654031) (xy 97.666302 -368.653568) (xy 98.529902 -368.653568)
			(xy 98.557173 -368.653995) (xy 98.611161 -368.661757) (xy 98.663494 -368.677124) (xy 98.713108 -368.699782)
			(xy 98.758993 -368.72927) (xy 98.800213 -368.764988) (xy 98.835931 -368.806209) (xy 98.865419 -368.852093)
			(xy 98.888077 -368.901707) (xy 98.903443 -368.954041) (xy 98.911206 -369.008029) (xy 98.911206 -369.062569)
			(xy 100.688631 -369.062569) (xy 100.688631 -369.008031) (xy 100.696393 -368.954048) (xy 100.711758 -368.90172)
			(xy 100.734414 -368.85211) (xy 100.7639 -368.80623) (xy 100.799614 -368.765013) (xy 100.840832 -368.729298)
			(xy 100.886712 -368.699813) (xy 100.936321 -368.677157) (xy 100.98865 -368.661793) (xy 101.042633 -368.654031)
			(xy 101.069902 -368.653568) (xy 101.933502 -368.653568) (xy 101.960773 -368.653995) (xy 102.014761 -368.661757)
			(xy 102.067094 -368.677124) (xy 102.116708 -368.699782) (xy 102.162593 -368.72927) (xy 102.203813 -368.764988)
			(xy 102.239531 -368.806209) (xy 102.269019 -368.852093) (xy 102.291677 -368.901707) (xy 102.307043 -368.954041)
			(xy 102.314806 -369.008029) (xy 102.314806 -369.062567) (xy 111.435654 -369.062567) (xy 111.435654 -369.008033)
			(xy 111.443415 -368.954054) (xy 111.458779 -368.901729) (xy 111.481433 -368.852123) (xy 111.510917 -368.806246)
			(xy 111.546629 -368.765031) (xy 111.587842 -368.729319) (xy 111.633719 -368.699835) (xy 111.683325 -368.677181)
			(xy 111.73565 -368.661816) (xy 111.789629 -368.654055) (xy 111.816896 -368.653568) (xy 112.680496 -368.653568)
			(xy 112.707769 -368.653971) (xy 112.761761 -368.661734) (xy 112.814098 -368.677101) (xy 112.863716 -368.69976)
			(xy 112.909603 -368.72925) (xy 112.950827 -368.76497) (xy 112.986548 -368.806193) (xy 113.016038 -368.852081)
			(xy 113.038698 -368.901698) (xy 113.054066 -368.954035) (xy 113.061828 -369.008027) (xy 113.061828 -369.062567)
			(xy 118.242854 -369.062567) (xy 118.242854 -369.008033) (xy 118.250615 -368.954054) (xy 118.265979 -368.901729)
			(xy 118.288633 -368.852123) (xy 118.318117 -368.806246) (xy 118.353829 -368.765031) (xy 118.395042 -368.729319)
			(xy 118.440919 -368.699835) (xy 118.490525 -368.677181) (xy 118.54285 -368.661816) (xy 118.596829 -368.654055)
			(xy 118.624096 -368.653568) (xy 119.487696 -368.653568) (xy 119.514969 -368.653971) (xy 119.568961 -368.661734)
			(xy 119.621298 -368.677101) (xy 119.670916 -368.69976) (xy 119.716803 -368.72925) (xy 119.758027 -368.76497)
			(xy 119.793748 -368.806193) (xy 119.823238 -368.852081) (xy 119.845898 -368.901698) (xy 119.861266 -368.954035)
			(xy 119.869028 -369.008027) (xy 119.869028 -369.062567) (xy 125.050054 -369.062567) (xy 125.050054 -369.008033)
			(xy 125.057815 -368.954054) (xy 125.073179 -368.901729) (xy 125.095833 -368.852123) (xy 125.125317 -368.806246)
			(xy 125.161029 -368.765031) (xy 125.202242 -368.729319) (xy 125.248119 -368.699835) (xy 125.297725 -368.677181)
			(xy 125.35005 -368.661816) (xy 125.404029 -368.654055) (xy 125.431296 -368.653568) (xy 126.294896 -368.653568)
			(xy 126.322169 -368.653971) (xy 126.376161 -368.661734) (xy 126.428498 -368.677101) (xy 126.478116 -368.69976)
			(xy 126.524003 -368.72925) (xy 126.565227 -368.76497) (xy 126.600948 -368.806193) (xy 126.630438 -368.852081)
			(xy 126.653098 -368.901698) (xy 126.668466 -368.954035) (xy 126.676228 -369.008027) (xy 126.676228 -369.062567)
			(xy 131.857254 -369.062567) (xy 131.857254 -369.008033) (xy 131.865015 -368.954054) (xy 131.880379 -368.901729)
			(xy 131.903033 -368.852123) (xy 131.932517 -368.806246) (xy 131.968229 -368.765031) (xy 132.009442 -368.729319)
			(xy 132.055319 -368.699835) (xy 132.104925 -368.677181) (xy 132.15725 -368.661816) (xy 132.211229 -368.654055)
			(xy 132.238496 -368.653568) (xy 133.102096 -368.653568) (xy 133.129369 -368.653971) (xy 133.183361 -368.661734)
			(xy 133.235698 -368.677101) (xy 133.285316 -368.69976) (xy 133.331203 -368.72925) (xy 133.372427 -368.76497)
			(xy 133.408148 -368.806193) (xy 133.437638 -368.852081) (xy 133.460298 -368.901698) (xy 133.475666 -368.954035)
			(xy 133.483428 -369.008027) (xy 133.483428 -369.062567) (xy 135.260854 -369.062567) (xy 135.260854 -369.008033)
			(xy 135.268615 -368.954054) (xy 135.283979 -368.901729) (xy 135.306633 -368.852123) (xy 135.336117 -368.806246)
			(xy 135.371829 -368.765031) (xy 135.413042 -368.729319) (xy 135.458919 -368.699835) (xy 135.508525 -368.677181)
			(xy 135.56085 -368.661816) (xy 135.614829 -368.654055) (xy 135.642096 -368.653568) (xy 136.505696 -368.653568)
			(xy 136.532969 -368.653971) (xy 136.586961 -368.661734) (xy 136.639298 -368.677101) (xy 136.688916 -368.69976)
			(xy 136.734803 -368.72925) (xy 136.776027 -368.76497) (xy 136.811748 -368.806193) (xy 136.841238 -368.852081)
			(xy 136.863898 -368.901698) (xy 136.879266 -368.954035) (xy 136.887028 -369.008027) (xy 136.887028 -369.062573)
			(xy 136.879266 -369.116565) (xy 136.863898 -369.168902) (xy 136.841238 -369.218519) (xy 136.811748 -369.264407)
			(xy 136.776027 -369.30563) (xy 136.734803 -369.34135) (xy 136.688916 -369.37084) (xy 136.639298 -369.393499)
			(xy 136.586961 -369.408866) (xy 136.532969 -369.416629) (xy 136.505696 -369.417092) (xy 135.642096 -369.417092)
			(xy 135.614829 -369.416545) (xy 135.56085 -369.408784) (xy 135.508525 -369.393419) (xy 135.458919 -369.370765)
			(xy 135.413042 -369.341281) (xy 135.371829 -369.305569) (xy 135.336117 -369.264354) (xy 135.306633 -369.218477)
			(xy 135.283979 -369.168871) (xy 135.268615 -369.116546) (xy 135.260854 -369.062567) (xy 133.483428 -369.062567)
			(xy 133.483428 -369.062573) (xy 133.475666 -369.116565) (xy 133.460298 -369.168902) (xy 133.437638 -369.218519)
			(xy 133.408148 -369.264407) (xy 133.372427 -369.30563) (xy 133.331203 -369.34135) (xy 133.285316 -369.37084)
			(xy 133.235698 -369.393499) (xy 133.183361 -369.408866) (xy 133.129369 -369.416629) (xy 133.102096 -369.417092)
			(xy 132.238496 -369.417092) (xy 132.211229 -369.416545) (xy 132.15725 -369.408784) (xy 132.104925 -369.393419)
			(xy 132.055319 -369.370765) (xy 132.009442 -369.341281) (xy 131.968229 -369.305569) (xy 131.932517 -369.264354)
			(xy 131.903033 -369.218477) (xy 131.880379 -369.168871) (xy 131.865015 -369.116546) (xy 131.857254 -369.062567)
			(xy 126.676228 -369.062567) (xy 126.676228 -369.062573) (xy 126.668466 -369.116565) (xy 126.653098 -369.168902)
			(xy 126.630438 -369.218519) (xy 126.600948 -369.264407) (xy 126.565227 -369.30563) (xy 126.524003 -369.34135)
			(xy 126.478116 -369.37084) (xy 126.428498 -369.393499) (xy 126.376161 -369.408866) (xy 126.322169 -369.416629)
			(xy 126.294896 -369.417092) (xy 125.431296 -369.417092) (xy 125.404029 -369.416545) (xy 125.35005 -369.408784)
			(xy 125.297725 -369.393419) (xy 125.248119 -369.370765) (xy 125.202242 -369.341281) (xy 125.161029 -369.305569)
			(xy 125.125317 -369.264354) (xy 125.095833 -369.218477) (xy 125.073179 -369.168871) (xy 125.057815 -369.116546)
			(xy 125.050054 -369.062567) (xy 119.869028 -369.062567) (xy 119.869028 -369.062573) (xy 119.861266 -369.116565)
			(xy 119.845898 -369.168902) (xy 119.823238 -369.218519) (xy 119.793748 -369.264407) (xy 119.758027 -369.30563)
			(xy 119.716803 -369.34135) (xy 119.670916 -369.37084) (xy 119.621298 -369.393499) (xy 119.568961 -369.408866)
			(xy 119.514969 -369.416629) (xy 119.487696 -369.417092) (xy 118.624096 -369.417092) (xy 118.596829 -369.416545)
			(xy 118.54285 -369.408784) (xy 118.490525 -369.393419) (xy 118.440919 -369.370765) (xy 118.395042 -369.341281)
			(xy 118.353829 -369.305569) (xy 118.318117 -369.264354) (xy 118.288633 -369.218477) (xy 118.265979 -369.168871)
			(xy 118.250615 -369.116546) (xy 118.242854 -369.062567) (xy 113.061828 -369.062567) (xy 113.061828 -369.062573)
			(xy 113.054066 -369.116565) (xy 113.038698 -369.168902) (xy 113.016038 -369.218519) (xy 112.986548 -369.264407)
			(xy 112.950827 -369.30563) (xy 112.909603 -369.34135) (xy 112.863716 -369.37084) (xy 112.814098 -369.393499)
			(xy 112.761761 -369.408866) (xy 112.707769 -369.416629) (xy 112.680496 -369.417092) (xy 111.816896 -369.417092)
			(xy 111.789629 -369.416545) (xy 111.73565 -369.408784) (xy 111.683325 -369.393419) (xy 111.633719 -369.370765)
			(xy 111.587842 -369.341281) (xy 111.546629 -369.305569) (xy 111.510917 -369.264354) (xy 111.481433 -369.218477)
			(xy 111.458779 -369.168871) (xy 111.443415 -369.116546) (xy 111.435654 -369.062567) (xy 102.314806 -369.062567)
			(xy 102.314806 -369.062571) (xy 102.307043 -369.116559) (xy 102.291677 -369.168893) (xy 102.269019 -369.218507)
			(xy 102.239531 -369.264391) (xy 102.203813 -369.305612) (xy 102.162593 -369.34133) (xy 102.116708 -369.370818)
			(xy 102.067094 -369.393476) (xy 102.014761 -369.408843) (xy 101.960773 -369.416605) (xy 101.933502 -369.417092)
			(xy 101.069902 -369.417092) (xy 101.042633 -369.416569) (xy 100.98865 -369.408807) (xy 100.936321 -369.393443)
			(xy 100.886712 -369.370787) (xy 100.840832 -369.341302) (xy 100.799614 -369.305587) (xy 100.7639 -369.26437)
			(xy 100.734414 -369.21849) (xy 100.711758 -369.16888) (xy 100.696393 -369.116552) (xy 100.688631 -369.062569)
			(xy 98.911206 -369.062569) (xy 98.911206 -369.062571) (xy 98.903443 -369.116559) (xy 98.888077 -369.168893)
			(xy 98.865419 -369.218507) (xy 98.835931 -369.264391) (xy 98.800213 -369.305612) (xy 98.758993 -369.34133)
			(xy 98.713108 -369.370818) (xy 98.663494 -369.393476) (xy 98.611161 -369.408843) (xy 98.557173 -369.416605)
			(xy 98.529902 -369.417092) (xy 97.666302 -369.417092) (xy 97.639033 -369.416569) (xy 97.58505 -369.408807)
			(xy 97.532721 -369.393443) (xy 97.483112 -369.370787) (xy 97.437232 -369.341302) (xy 97.396014 -369.305587)
			(xy 97.3603 -369.26437) (xy 97.330814 -369.21849) (xy 97.308158 -369.16888) (xy 97.292793 -369.116552)
			(xy 97.285031 -369.062569) (xy 92.104006 -369.062569) (xy 92.104006 -369.062571) (xy 92.096243 -369.116559)
			(xy 92.080877 -369.168893) (xy 92.058219 -369.218507) (xy 92.028731 -369.264391) (xy 91.993013 -369.305612)
			(xy 91.951793 -369.34133) (xy 91.905908 -369.370818) (xy 91.856294 -369.393476) (xy 91.803961 -369.408843)
			(xy 91.749973 -369.416605) (xy 91.722702 -369.417092) (xy 90.859102 -369.417092) (xy 90.831833 -369.416569)
			(xy 90.77785 -369.408807) (xy 90.725521 -369.393443) (xy 90.675912 -369.370787) (xy 90.630032 -369.341302)
			(xy 90.588814 -369.305587) (xy 90.5531 -369.26437) (xy 90.523614 -369.21849) (xy 90.500958 -369.16888)
			(xy 90.485593 -369.116552) (xy 90.477831 -369.062569) (xy 85.296806 -369.062569) (xy 85.296806 -369.062571)
			(xy 85.289043 -369.116559) (xy 85.273677 -369.168893) (xy 85.251019 -369.218507) (xy 85.221531 -369.264391)
			(xy 85.185813 -369.305612) (xy 85.144593 -369.34133) (xy 85.098708 -369.370818) (xy 85.049094 -369.393476)
			(xy 84.996761 -369.408843) (xy 84.942773 -369.416605) (xy 84.915502 -369.417092) (xy 84.051902 -369.417092)
			(xy 84.024633 -369.416569) (xy 83.97065 -369.408807) (xy 83.918321 -369.393443) (xy 83.868712 -369.370787)
			(xy 83.822832 -369.341302) (xy 83.781614 -369.305587) (xy 83.7459 -369.26437) (xy 83.716414 -369.21849)
			(xy 83.693758 -369.16888) (xy 83.678393 -369.116552) (xy 83.670631 -369.062569) (xy 78.489606 -369.062569)
			(xy 78.489606 -369.062571) (xy 78.481843 -369.116559) (xy 78.466477 -369.168893) (xy 78.443819 -369.218507)
			(xy 78.414331 -369.264391) (xy 78.378613 -369.305612) (xy 78.337393 -369.34133) (xy 78.291508 -369.370818)
			(xy 78.241894 -369.393476) (xy 78.189561 -369.408843) (xy 78.135573 -369.416605) (xy 78.108302 -369.417092)
			(xy 77.244702 -369.417092) (xy 77.217433 -369.416569) (xy 77.16345 -369.408807) (xy 77.111121 -369.393443)
			(xy 77.061512 -369.370787) (xy 77.015632 -369.341302) (xy 76.974414 -369.305587) (xy 76.9387 -369.26437)
			(xy 76.909214 -369.21849) (xy 76.886558 -369.16888) (xy 76.871193 -369.116552) (xy 76.863431 -369.062569)
			(xy 69.787128 -369.062569) (xy 69.787128 -369.062575) (xy 69.779364 -369.11657) (xy 69.763995 -369.168911)
			(xy 69.741332 -369.218531) (xy 69.711838 -369.26442) (xy 69.676112 -369.305645) (xy 69.634884 -369.341365)
			(xy 69.588991 -369.370854) (xy 69.539368 -369.393511) (xy 69.487025 -369.408874) (xy 69.433029 -369.416632)
			(xy 69.405754 -369.417092) (xy 68.542154 -369.417092) (xy 68.514889 -369.416543) (xy 68.460915 -369.408776)
			(xy 68.408595 -369.393408) (xy 68.358994 -369.370751) (xy 68.313123 -369.341266) (xy 68.271914 -369.305554)
			(xy 68.236206 -369.264341) (xy 68.206727 -369.218465) (xy 68.184076 -369.168862) (xy 68.168714 -369.11654)
			(xy 68.160954 -369.062565) (xy 66.383528 -369.062565) (xy 66.383528 -369.062575) (xy 66.375764 -369.11657)
			(xy 66.360395 -369.168911) (xy 66.337732 -369.218531) (xy 66.308238 -369.26442) (xy 66.272512 -369.305645)
			(xy 66.231284 -369.341365) (xy 66.185391 -369.370854) (xy 66.135768 -369.393511) (xy 66.083425 -369.408874)
			(xy 66.029429 -369.416632) (xy 66.002154 -369.417092) (xy 65.138554 -369.417092) (xy 65.111289 -369.416543)
			(xy 65.057315 -369.408776) (xy 65.004995 -369.393408) (xy 64.955394 -369.370751) (xy 64.909523 -369.341266)
			(xy 64.868314 -369.305554) (xy 64.832606 -369.264341) (xy 64.803127 -369.218465) (xy 64.780476 -369.168862)
			(xy 64.765114 -369.11654) (xy 64.757354 -369.062565) (xy 59.576328 -369.062565) (xy 59.576328 -369.062575)
			(xy 59.568564 -369.11657) (xy 59.553195 -369.168911) (xy 59.530532 -369.218531) (xy 59.501038 -369.26442)
			(xy 59.465312 -369.305645) (xy 59.424084 -369.341365) (xy 59.378191 -369.370854) (xy 59.328568 -369.393511)
			(xy 59.276225 -369.408874) (xy 59.222229 -369.416632) (xy 59.194954 -369.417092) (xy 58.331354 -369.417092)
			(xy 58.304089 -369.416543) (xy 58.250115 -369.408776) (xy 58.197795 -369.393408) (xy 58.148194 -369.370751)
			(xy 58.102323 -369.341266) (xy 58.061114 -369.305554) (xy 58.025406 -369.264341) (xy 57.995927 -369.218465)
			(xy 57.973276 -369.168862) (xy 57.957914 -369.11654) (xy 57.950154 -369.062565) (xy 52.769128 -369.062565)
			(xy 52.769128 -369.062575) (xy 52.761364 -369.11657) (xy 52.745995 -369.168911) (xy 52.723332 -369.218531)
			(xy 52.693838 -369.26442) (xy 52.658112 -369.305645) (xy 52.616884 -369.341365) (xy 52.570991 -369.370854)
			(xy 52.521368 -369.393511) (xy 52.469025 -369.408874) (xy 52.415029 -369.416632) (xy 52.387754 -369.417092)
			(xy 51.524154 -369.417092) (xy 51.496889 -369.416543) (xy 51.442915 -369.408776) (xy 51.390595 -369.393408)
			(xy 51.340994 -369.370751) (xy 51.295123 -369.341266) (xy 51.253914 -369.305554) (xy 51.218206 -369.264341)
			(xy 51.188727 -369.218465) (xy 51.166076 -369.168862) (xy 51.150714 -369.11654) (xy 51.142954 -369.062565)
			(xy 45.961928 -369.062565) (xy 45.961928 -369.062575) (xy 45.954164 -369.11657) (xy 45.938795 -369.168911)
			(xy 45.916132 -369.218531) (xy 45.886638 -369.26442) (xy 45.850912 -369.305645) (xy 45.809684 -369.341365)
			(xy 45.763791 -369.370854) (xy 45.714168 -369.393511) (xy 45.661825 -369.408874) (xy 45.607829 -369.416632)
			(xy 45.580554 -369.417092) (xy 44.716954 -369.417092) (xy 44.689689 -369.416543) (xy 44.635715 -369.408776)
			(xy 44.583395 -369.393408) (xy 44.533794 -369.370751) (xy 44.487923 -369.341266) (xy 44.446714 -369.305554)
			(xy 44.411006 -369.264341) (xy 44.381527 -369.218465) (xy 44.358876 -369.168862) (xy 44.343514 -369.11654)
			(xy 44.335754 -369.062565) (xy 2.509012 -369.062565) (xy 2.509012 -370.206778) (xy 138.3665 -370.206778)
			(xy 138.3665 -369.343178) (xy 138.366986 -369.315909) (xy 138.374748 -369.261925) (xy 138.390113 -369.209595)
			(xy 138.41277 -369.159985) (xy 138.442256 -369.114104) (xy 138.477971 -369.072887) (xy 138.519188 -369.037172)
			(xy 138.565069 -369.007686) (xy 138.614679 -368.985029) (xy 138.667009 -368.969664) (xy 138.720993 -368.961902)
			(xy 138.775531 -368.961902) (xy 138.829515 -368.969664) (xy 138.881845 -368.985029) (xy 138.931455 -369.007686)
			(xy 138.977336 -369.037172) (xy 139.006648 -369.062571) (xy 143.963332 -369.062571) (xy 143.963332 -369.008029)
			(xy 143.971094 -368.954043) (xy 143.986461 -368.901711) (xy 144.009121 -368.852098) (xy 144.03861 -368.806216)
			(xy 144.074329 -368.764998) (xy 144.115551 -368.729284) (xy 144.161437 -368.699799) (xy 144.211052 -368.677146)
			(xy 144.263386 -368.661785) (xy 144.317373 -368.654028) (xy 144.344644 -368.653568) (xy 145.208244 -368.653568)
			(xy 145.235513 -368.653998) (xy 145.289497 -368.661765) (xy 145.341825 -368.677135) (xy 145.391433 -368.699796)
			(xy 145.437312 -368.729285) (xy 145.478528 -368.765003) (xy 145.514241 -368.806223) (xy 145.543725 -368.852105)
			(xy 145.56638 -368.901716) (xy 145.581744 -368.954047) (xy 145.589506 -369.00803) (xy 145.589506 -369.06257)
			(xy 145.589506 -369.062571) (xy 150.770532 -369.062571) (xy 150.770532 -369.008029) (xy 150.778294 -368.954043)
			(xy 150.793661 -368.901711) (xy 150.816321 -368.852098) (xy 150.84581 -368.806216) (xy 150.881529 -368.764998)
			(xy 150.922751 -368.729284) (xy 150.968637 -368.699799) (xy 151.018252 -368.677146) (xy 151.070586 -368.661785)
			(xy 151.124573 -368.654028) (xy 151.151844 -368.653568) (xy 152.015444 -368.653568) (xy 152.042713 -368.653998)
			(xy 152.096697 -368.661765) (xy 152.149025 -368.677135) (xy 152.198633 -368.699796) (xy 152.244512 -368.729285)
			(xy 152.285728 -368.765003) (xy 152.321441 -368.806223) (xy 152.350925 -368.852105) (xy 152.37358 -368.901716)
			(xy 152.388944 -368.954047) (xy 152.396706 -369.00803) (xy 152.396706 -369.06257) (xy 152.396706 -369.062571)
			(xy 157.577732 -369.062571) (xy 157.577732 -369.008029) (xy 157.585494 -368.954043) (xy 157.600861 -368.901711)
			(xy 157.623521 -368.852098) (xy 157.65301 -368.806216) (xy 157.688729 -368.764998) (xy 157.729951 -368.729284)
			(xy 157.775837 -368.699799) (xy 157.825452 -368.677146) (xy 157.877786 -368.661785) (xy 157.931773 -368.654028)
			(xy 157.959044 -368.653568) (xy 158.822644 -368.653568) (xy 158.849913 -368.653998) (xy 158.903897 -368.661765)
			(xy 158.956225 -368.677135) (xy 159.005833 -368.699796) (xy 159.051712 -368.729285) (xy 159.092928 -368.765003)
			(xy 159.128641 -368.806223) (xy 159.158125 -368.852105) (xy 159.18078 -368.901716) (xy 159.196144 -368.954047)
			(xy 159.203906 -369.00803) (xy 159.203906 -369.06257) (xy 159.203906 -369.062571) (xy 164.384932 -369.062571)
			(xy 164.384932 -369.008029) (xy 164.392694 -368.954043) (xy 164.408061 -368.901711) (xy 164.430721 -368.852098)
			(xy 164.46021 -368.806216) (xy 164.495929 -368.764998) (xy 164.537151 -368.729284) (xy 164.583037 -368.699799)
			(xy 164.632652 -368.677146) (xy 164.684986 -368.661785) (xy 164.738973 -368.654028) (xy 164.766244 -368.653568)
			(xy 165.629844 -368.653568) (xy 165.657113 -368.653998) (xy 165.711097 -368.661765) (xy 165.763425 -368.677135)
			(xy 165.813033 -368.699796) (xy 165.858912 -368.729285) (xy 165.900128 -368.765003) (xy 165.935841 -368.806223)
			(xy 165.965325 -368.852105) (xy 165.98798 -368.901716) (xy 166.003344 -368.954047) (xy 166.011106 -369.00803)
			(xy 166.011106 -369.06257) (xy 166.011106 -369.062571) (xy 167.788532 -369.062571) (xy 167.788532 -369.008029)
			(xy 167.796294 -368.954043) (xy 167.811661 -368.901711) (xy 167.834321 -368.852098) (xy 167.86381 -368.806216)
			(xy 167.899529 -368.764998) (xy 167.940751 -368.729284) (xy 167.986637 -368.699799) (xy 168.036252 -368.677146)
			(xy 168.088586 -368.661785) (xy 168.142573 -368.654028) (xy 168.169844 -368.653568) (xy 169.033444 -368.653568)
			(xy 169.060713 -368.653998) (xy 169.114697 -368.661765) (xy 169.167025 -368.677135) (xy 169.216633 -368.699796)
			(xy 169.262512 -368.729285) (xy 169.303728 -368.765003) (xy 169.339441 -368.806223) (xy 169.368925 -368.852105)
			(xy 169.39158 -368.901716) (xy 169.406944 -368.954047) (xy 169.414706 -369.00803) (xy 169.414706 -369.06257)
			(xy 169.406944 -369.116553) (xy 169.39158 -369.168884) (xy 169.368925 -369.218495) (xy 169.339441 -369.264377)
			(xy 169.303728 -369.305597) (xy 169.262512 -369.341315) (xy 169.216633 -369.370804) (xy 169.167025 -369.393465)
			(xy 169.114697 -369.408835) (xy 169.060713 -369.416602) (xy 169.033444 -369.417092) (xy 168.169844 -369.417092)
			(xy 168.142573 -369.416572) (xy 168.088586 -369.408815) (xy 168.036252 -369.393454) (xy 167.986637 -369.370801)
			(xy 167.940751 -369.341316) (xy 167.899529 -369.305602) (xy 167.86381 -369.264384) (xy 167.834321 -369.218502)
			(xy 167.811661 -369.168889) (xy 167.796294 -369.116557) (xy 167.788532 -369.062571) (xy 166.011106 -369.062571)
			(xy 166.003344 -369.116553) (xy 165.98798 -369.168884) (xy 165.965325 -369.218495) (xy 165.935841 -369.264377)
			(xy 165.900128 -369.305597) (xy 165.858912 -369.341315) (xy 165.813033 -369.370804) (xy 165.763425 -369.393465)
			(xy 165.711097 -369.408835) (xy 165.657113 -369.416602) (xy 165.629844 -369.417092) (xy 164.766244 -369.417092)
			(xy 164.738973 -369.416572) (xy 164.684986 -369.408815) (xy 164.632652 -369.393454) (xy 164.583037 -369.370801)
			(xy 164.537151 -369.341316) (xy 164.495929 -369.305602) (xy 164.46021 -369.264384) (xy 164.430721 -369.218502)
			(xy 164.408061 -369.168889) (xy 164.392694 -369.116557) (xy 164.384932 -369.062571) (xy 159.203906 -369.062571)
			(xy 159.196144 -369.116553) (xy 159.18078 -369.168884) (xy 159.158125 -369.218495) (xy 159.128641 -369.264377)
			(xy 159.092928 -369.305597) (xy 159.051712 -369.341315) (xy 159.005833 -369.370804) (xy 158.956225 -369.393465)
			(xy 158.903897 -369.408835) (xy 158.849913 -369.416602) (xy 158.822644 -369.417092) (xy 157.959044 -369.417092)
			(xy 157.931773 -369.416572) (xy 157.877786 -369.408815) (xy 157.825452 -369.393454) (xy 157.775837 -369.370801)
			(xy 157.729951 -369.341316) (xy 157.688729 -369.305602) (xy 157.65301 -369.264384) (xy 157.623521 -369.218502)
			(xy 157.600861 -369.168889) (xy 157.585494 -369.116557) (xy 157.577732 -369.062571) (xy 152.396706 -369.062571)
			(xy 152.388944 -369.116553) (xy 152.37358 -369.168884) (xy 152.350925 -369.218495) (xy 152.321441 -369.264377)
			(xy 152.285728 -369.305597) (xy 152.244512 -369.341315) (xy 152.198633 -369.370804) (xy 152.149025 -369.393465)
			(xy 152.096697 -369.408835) (xy 152.042713 -369.416602) (xy 152.015444 -369.417092) (xy 151.151844 -369.417092)
			(xy 151.124573 -369.416572) (xy 151.070586 -369.408815) (xy 151.018252 -369.393454) (xy 150.968637 -369.370801)
			(xy 150.922751 -369.341316) (xy 150.881529 -369.305602) (xy 150.84581 -369.264384) (xy 150.816321 -369.218502)
			(xy 150.793661 -369.168889) (xy 150.778294 -369.116557) (xy 150.770532 -369.062571) (xy 145.589506 -369.062571)
			(xy 145.581744 -369.116553) (xy 145.56638 -369.168884) (xy 145.543725 -369.218495) (xy 145.514241 -369.264377)
			(xy 145.478528 -369.305597) (xy 145.437312 -369.341315) (xy 145.391433 -369.370804) (xy 145.341825 -369.393465)
			(xy 145.289497 -369.408835) (xy 145.235513 -369.416602) (xy 145.208244 -369.417092) (xy 144.344644 -369.417092)
			(xy 144.317373 -369.416572) (xy 144.263386 -369.408815) (xy 144.211052 -369.393454) (xy 144.161437 -369.370801)
			(xy 144.115551 -369.341316) (xy 144.074329 -369.305602) (xy 144.03861 -369.264384) (xy 144.009121 -369.218502)
			(xy 143.986461 -369.168889) (xy 143.971094 -369.116557) (xy 143.963332 -369.062571) (xy 139.006648 -369.062571)
			(xy 139.018553 -369.072887) (xy 139.054268 -369.114104) (xy 139.083754 -369.159985) (xy 139.106411 -369.209595)
			(xy 139.121776 -369.261925) (xy 139.129538 -369.315909) (xy 139.130024 -369.343178) (xy 139.130024 -370.206778)
			(xy 139.129538 -370.234047) (xy 139.121776 -370.288031) (xy 139.106411 -370.340361) (xy 139.083754 -370.389971)
			(xy 139.071223 -370.40947) (xy 141.572996 -370.40947) (xy 141.572996 -369.54587) (xy 141.573482 -369.518619)
			(xy 141.581238 -369.464671) (xy 141.596593 -369.412376) (xy 141.619235 -369.362799) (xy 141.648701 -369.316949)
			(xy 141.684392 -369.275758) (xy 141.725583 -369.240067) (xy 141.771433 -369.210601) (xy 141.82101 -369.187959)
			(xy 141.873305 -369.172604) (xy 141.927253 -369.164848) (xy 141.981755 -369.164848) (xy 142.035703 -369.172604)
			(xy 142.087998 -369.187959) (xy 142.137575 -369.210601) (xy 142.183425 -369.240067) (xy 142.224616 -369.275758)
			(xy 142.260307 -369.316949) (xy 142.289773 -369.362799) (xy 142.312415 -369.412376) (xy 142.32777 -369.464671)
			(xy 142.335526 -369.518619) (xy 142.336012 -369.54587) (xy 142.336012 -369.62565) (xy 175.203103 -369.62565)
			(xy 175.203103 -369.57115) (xy 175.210859 -369.517206) (xy 175.226214 -369.464914) (xy 175.248854 -369.41534)
			(xy 175.278318 -369.369493) (xy 175.314008 -369.328305) (xy 175.355196 -369.292616) (xy 175.401044 -369.263152)
			(xy 175.450618 -369.240512) (xy 175.50291 -369.225158) (xy 175.556854 -369.217403) (xy 175.584104 -369.21694)
			(xy 176.447704 -369.21694) (xy 176.474958 -369.21733) (xy 176.528913 -369.225088) (xy 176.581213 -369.240446)
			(xy 176.630796 -369.26309) (xy 176.676652 -369.29256) (xy 176.717847 -369.328256) (xy 176.753543 -369.369451)
			(xy 176.783012 -369.415307) (xy 176.805656 -369.46489) (xy 176.821013 -369.517191) (xy 176.82877 -369.571146)
			(xy 176.82877 -369.625654) (xy 176.821013 -369.679609) (xy 176.805656 -369.73191) (xy 176.783012 -369.781493)
			(xy 176.753543 -369.827349) (xy 176.717847 -369.868544) (xy 176.676652 -369.90424) (xy 176.630796 -369.93371)
			(xy 176.581213 -369.956354) (xy 176.528913 -369.971712) (xy 176.474958 -369.97947) (xy 176.447704 -369.979956)
			(xy 175.584104 -369.979956) (xy 175.556854 -369.979397) (xy 175.50291 -369.971642) (xy 175.450618 -369.956288)
			(xy 175.401044 -369.933648) (xy 175.355196 -369.904184) (xy 175.314008 -369.868495) (xy 175.278318 -369.827307)
			(xy 175.248854 -369.78146) (xy 175.226214 -369.731886) (xy 175.210859 -369.679594) (xy 175.203103 -369.62565)
			(xy 142.336012 -369.62565) (xy 142.336012 -370.40947) (xy 142.335526 -370.436721) (xy 142.32777 -370.490669)
			(xy 142.312415 -370.542964) (xy 142.289773 -370.592541) (xy 142.260307 -370.638391) (xy 142.224616 -370.679582)
			(xy 142.183425 -370.715273) (xy 142.137575 -370.744739) (xy 142.087998 -370.767381) (xy 142.035703 -370.782736)
			(xy 141.981755 -370.790492) (xy 141.927253 -370.790492) (xy 141.873305 -370.782736) (xy 141.82101 -370.767381)
			(xy 141.771433 -370.744739) (xy 141.725583 -370.715273) (xy 141.684392 -370.679582) (xy 141.648701 -370.638391)
			(xy 141.619235 -370.592541) (xy 141.596593 -370.542964) (xy 141.581238 -370.490669) (xy 141.573482 -370.436721)
			(xy 141.572996 -370.40947) (xy 139.071223 -370.40947) (xy 139.054268 -370.435852) (xy 139.018553 -370.477069)
			(xy 138.977336 -370.512784) (xy 138.931455 -370.54227) (xy 138.881845 -370.564927) (xy 138.829515 -370.580292)
			(xy 138.775531 -370.588054) (xy 138.720993 -370.588054) (xy 138.667009 -370.580292) (xy 138.614679 -370.564927)
			(xy 138.565069 -370.54227) (xy 138.519188 -370.512784) (xy 138.477971 -370.477069) (xy 138.442256 -370.435852)
			(xy 138.41277 -370.389971) (xy 138.390113 -370.340361) (xy 138.374748 -370.288031) (xy 138.366986 -370.234047)
			(xy 138.3665 -370.206778) (xy 2.509012 -370.206778) (xy 2.509012 -371.526365) (xy 42.633954 -371.526365)
			(xy 42.633954 -371.471835) (xy 42.641714 -371.41786) (xy 42.657076 -371.365538) (xy 42.679727 -371.315935)
			(xy 42.709206 -371.270059) (xy 42.744914 -371.228846) (xy 42.786123 -371.193134) (xy 42.831994 -371.163649)
			(xy 42.881595 -371.140992) (xy 42.933915 -371.125624) (xy 42.987889 -371.117857) (xy 43.015154 -371.117368)
			(xy 43.878754 -371.117368) (xy 43.906029 -371.117768) (xy 43.960025 -371.125526) (xy 44.012368 -371.140889)
			(xy 44.061991 -371.163546) (xy 44.107884 -371.193035) (xy 44.149112 -371.228755) (xy 44.184838 -371.26998)
			(xy 44.214332 -371.315869) (xy 44.236995 -371.365489) (xy 44.252364 -371.41783) (xy 44.260128 -371.471825)
			(xy 44.260128 -371.526365) (xy 49.441154 -371.526365) (xy 49.441154 -371.471835) (xy 49.448914 -371.41786)
			(xy 49.464276 -371.365538) (xy 49.486927 -371.315935) (xy 49.516406 -371.270059) (xy 49.552114 -371.228846)
			(xy 49.593323 -371.193134) (xy 49.639194 -371.163649) (xy 49.688795 -371.140992) (xy 49.741115 -371.125624)
			(xy 49.795089 -371.117857) (xy 49.822354 -371.117368) (xy 50.685954 -371.117368) (xy 50.713229 -371.117768)
			(xy 50.767225 -371.125526) (xy 50.819568 -371.140889) (xy 50.869191 -371.163546) (xy 50.915084 -371.193035)
			(xy 50.956312 -371.228755) (xy 50.992038 -371.26998) (xy 51.021532 -371.315869) (xy 51.044195 -371.365489)
			(xy 51.059564 -371.41783) (xy 51.067328 -371.471825) (xy 51.067328 -371.526365) (xy 56.248354 -371.526365)
			(xy 56.248354 -371.471835) (xy 56.256114 -371.41786) (xy 56.271476 -371.365538) (xy 56.294127 -371.315935)
			(xy 56.323606 -371.270059) (xy 56.359314 -371.228846) (xy 56.400523 -371.193134) (xy 56.446394 -371.163649)
			(xy 56.495995 -371.140992) (xy 56.548315 -371.125624) (xy 56.602289 -371.117857) (xy 56.629554 -371.117368)
			(xy 57.493154 -371.117368) (xy 57.520429 -371.117768) (xy 57.574425 -371.125526) (xy 57.626768 -371.140889)
			(xy 57.676391 -371.163546) (xy 57.722284 -371.193035) (xy 57.763512 -371.228755) (xy 57.799238 -371.26998)
			(xy 57.828732 -371.315869) (xy 57.851395 -371.365489) (xy 57.866764 -371.41783) (xy 57.874528 -371.471825)
			(xy 57.874528 -371.526365) (xy 63.055554 -371.526365) (xy 63.055554 -371.471835) (xy 63.063314 -371.41786)
			(xy 63.078676 -371.365538) (xy 63.101327 -371.315935) (xy 63.130806 -371.270059) (xy 63.166514 -371.228846)
			(xy 63.207723 -371.193134) (xy 63.253594 -371.163649) (xy 63.303195 -371.140992) (xy 63.355515 -371.125624)
			(xy 63.409489 -371.117857) (xy 63.436754 -371.117368) (xy 64.300354 -371.117368) (xy 64.327629 -371.117768)
			(xy 64.381625 -371.125526) (xy 64.433968 -371.140889) (xy 64.483591 -371.163546) (xy 64.529484 -371.193035)
			(xy 64.570712 -371.228755) (xy 64.606438 -371.26998) (xy 64.635932 -371.315869) (xy 64.658595 -371.365489)
			(xy 64.673964 -371.41783) (xy 64.681728 -371.471825) (xy 64.681728 -371.526369) (xy 75.161631 -371.526369)
			(xy 75.161631 -371.471831) (xy 75.169393 -371.417848) (xy 75.184758 -371.36552) (xy 75.207414 -371.31591)
			(xy 75.2369 -371.27003) (xy 75.272614 -371.228813) (xy 75.313832 -371.193098) (xy 75.359712 -371.163613)
			(xy 75.409321 -371.140957) (xy 75.46165 -371.125593) (xy 75.515633 -371.117831) (xy 75.542902 -371.117368)
			(xy 76.406502 -371.117368) (xy 76.433773 -371.117795) (xy 76.487761 -371.125557) (xy 76.540094 -371.140924)
			(xy 76.589708 -371.163582) (xy 76.635593 -371.19307) (xy 76.676813 -371.228788) (xy 76.712531 -371.270009)
			(xy 76.742019 -371.315893) (xy 76.764677 -371.365507) (xy 76.780043 -371.417841) (xy 76.787806 -371.471829)
			(xy 76.787806 -371.526369) (xy 81.968831 -371.526369) (xy 81.968831 -371.471831) (xy 81.976593 -371.417848)
			(xy 81.991958 -371.36552) (xy 82.014614 -371.31591) (xy 82.0441 -371.27003) (xy 82.079814 -371.228813)
			(xy 82.121032 -371.193098) (xy 82.166912 -371.163613) (xy 82.216521 -371.140957) (xy 82.26885 -371.125593)
			(xy 82.322833 -371.117831) (xy 82.350102 -371.117368) (xy 83.213702 -371.117368) (xy 83.240973 -371.117795)
			(xy 83.294961 -371.125557) (xy 83.347294 -371.140924) (xy 83.396908 -371.163582) (xy 83.442793 -371.19307)
			(xy 83.484013 -371.228788) (xy 83.519731 -371.270009) (xy 83.549219 -371.315893) (xy 83.571877 -371.365507)
			(xy 83.587243 -371.417841) (xy 83.595006 -371.471829) (xy 83.595006 -371.526369) (xy 88.776031 -371.526369)
			(xy 88.776031 -371.471831) (xy 88.783793 -371.417848) (xy 88.799158 -371.36552) (xy 88.821814 -371.31591)
			(xy 88.8513 -371.27003) (xy 88.887014 -371.228813) (xy 88.928232 -371.193098) (xy 88.974112 -371.163613)
			(xy 89.023721 -371.140957) (xy 89.07605 -371.125593) (xy 89.130033 -371.117831) (xy 89.157302 -371.117368)
			(xy 90.020902 -371.117368) (xy 90.048173 -371.117795) (xy 90.102161 -371.125557) (xy 90.154494 -371.140924)
			(xy 90.204108 -371.163582) (xy 90.249993 -371.19307) (xy 90.291213 -371.228788) (xy 90.326931 -371.270009)
			(xy 90.356419 -371.315893) (xy 90.379077 -371.365507) (xy 90.394443 -371.417841) (xy 90.402206 -371.471829)
			(xy 90.402206 -371.526369) (xy 95.583231 -371.526369) (xy 95.583231 -371.471831) (xy 95.590993 -371.417848)
			(xy 95.606358 -371.36552) (xy 95.629014 -371.31591) (xy 95.6585 -371.27003) (xy 95.694214 -371.228813)
			(xy 95.735432 -371.193098) (xy 95.781312 -371.163613) (xy 95.830921 -371.140957) (xy 95.88325 -371.125593)
			(xy 95.937233 -371.117831) (xy 95.964502 -371.117368) (xy 96.828102 -371.117368) (xy 96.855373 -371.117795)
			(xy 96.909361 -371.125557) (xy 96.961694 -371.140924) (xy 97.011308 -371.163582) (xy 97.057193 -371.19307)
			(xy 97.098413 -371.228788) (xy 97.134131 -371.270009) (xy 97.163619 -371.315893) (xy 97.186277 -371.365507)
			(xy 97.201643 -371.417841) (xy 97.209406 -371.471829) (xy 97.209406 -371.526367) (xy 109.733854 -371.526367)
			(xy 109.733854 -371.471833) (xy 109.741615 -371.417854) (xy 109.756979 -371.365529) (xy 109.779633 -371.315923)
			(xy 109.809117 -371.270046) (xy 109.844829 -371.228831) (xy 109.886042 -371.193119) (xy 109.931919 -371.163635)
			(xy 109.981525 -371.140981) (xy 110.03385 -371.125616) (xy 110.087829 -371.117855) (xy 110.115096 -371.117368)
			(xy 110.978696 -371.117368) (xy 111.005969 -371.117771) (xy 111.059961 -371.125534) (xy 111.112298 -371.140901)
			(xy 111.161916 -371.16356) (xy 111.207803 -371.19305) (xy 111.249027 -371.22877) (xy 111.284748 -371.269993)
			(xy 111.314238 -371.315881) (xy 111.336898 -371.365498) (xy 111.352266 -371.417835) (xy 111.360028 -371.471827)
			(xy 111.360028 -371.526367) (xy 116.541054 -371.526367) (xy 116.541054 -371.471833) (xy 116.548815 -371.417854)
			(xy 116.564179 -371.365529) (xy 116.586833 -371.315923) (xy 116.616317 -371.270046) (xy 116.652029 -371.228831)
			(xy 116.693242 -371.193119) (xy 116.739119 -371.163635) (xy 116.788725 -371.140981) (xy 116.84105 -371.125616)
			(xy 116.895029 -371.117855) (xy 116.922296 -371.117368) (xy 117.785896 -371.117368) (xy 117.813169 -371.117771)
			(xy 117.867161 -371.125534) (xy 117.919498 -371.140901) (xy 117.969116 -371.16356) (xy 118.015003 -371.19305)
			(xy 118.056227 -371.22877) (xy 118.091948 -371.269993) (xy 118.121438 -371.315881) (xy 118.144098 -371.365498)
			(xy 118.159466 -371.417835) (xy 118.167228 -371.471827) (xy 118.167228 -371.526367) (xy 123.348254 -371.526367)
			(xy 123.348254 -371.471833) (xy 123.356015 -371.417854) (xy 123.371379 -371.365529) (xy 123.394033 -371.315923)
			(xy 123.423517 -371.270046) (xy 123.459229 -371.228831) (xy 123.500442 -371.193119) (xy 123.546319 -371.163635)
			(xy 123.595925 -371.140981) (xy 123.64825 -371.125616) (xy 123.702229 -371.117855) (xy 123.729496 -371.117368)
			(xy 124.593096 -371.117368) (xy 124.620369 -371.117771) (xy 124.674361 -371.125534) (xy 124.726698 -371.140901)
			(xy 124.776316 -371.16356) (xy 124.822203 -371.19305) (xy 124.863427 -371.22877) (xy 124.899148 -371.269993)
			(xy 124.928638 -371.315881) (xy 124.951298 -371.365498) (xy 124.966666 -371.417835) (xy 124.974428 -371.471827)
			(xy 124.974428 -371.526367) (xy 130.155454 -371.526367) (xy 130.155454 -371.471833) (xy 130.163215 -371.417854)
			(xy 130.178579 -371.365529) (xy 130.201233 -371.315923) (xy 130.230717 -371.270046) (xy 130.266429 -371.228831)
			(xy 130.307642 -371.193119) (xy 130.353519 -371.163635) (xy 130.403125 -371.140981) (xy 130.45545 -371.125616)
			(xy 130.509429 -371.117855) (xy 130.536696 -371.117368) (xy 131.400296 -371.117368) (xy 131.427569 -371.117771)
			(xy 131.481561 -371.125534) (xy 131.533898 -371.140901) (xy 131.583516 -371.16356) (xy 131.629403 -371.19305)
			(xy 131.670627 -371.22877) (xy 131.706348 -371.269993) (xy 131.735838 -371.315881) (xy 131.758498 -371.365498)
			(xy 131.773866 -371.417835) (xy 131.781628 -371.471827) (xy 131.781628 -371.526371) (xy 142.261532 -371.526371)
			(xy 142.261532 -371.471829) (xy 142.269294 -371.417843) (xy 142.284661 -371.365511) (xy 142.307321 -371.315898)
			(xy 142.33681 -371.270016) (xy 142.372529 -371.228798) (xy 142.413751 -371.193084) (xy 142.459637 -371.163599)
			(xy 142.509252 -371.140946) (xy 142.561586 -371.125585) (xy 142.615573 -371.117828) (xy 142.642844 -371.117368)
			(xy 143.506444 -371.117368) (xy 143.533713 -371.117798) (xy 143.587697 -371.125565) (xy 143.640025 -371.140935)
			(xy 143.689633 -371.163596) (xy 143.735512 -371.193085) (xy 143.776728 -371.228803) (xy 143.812441 -371.270023)
			(xy 143.841925 -371.315905) (xy 143.86458 -371.365516) (xy 143.879944 -371.417847) (xy 143.887706 -371.47183)
			(xy 143.887706 -371.52637) (xy 143.887706 -371.526371) (xy 149.068732 -371.526371) (xy 149.068732 -371.471829)
			(xy 149.076494 -371.417843) (xy 149.091861 -371.365511) (xy 149.114521 -371.315898) (xy 149.14401 -371.270016)
			(xy 149.179729 -371.228798) (xy 149.220951 -371.193084) (xy 149.266837 -371.163599) (xy 149.316452 -371.140946)
			(xy 149.368786 -371.125585) (xy 149.422773 -371.117828) (xy 149.450044 -371.117368) (xy 150.313644 -371.117368)
			(xy 150.340913 -371.117798) (xy 150.394897 -371.125565) (xy 150.447225 -371.140935) (xy 150.496833 -371.163596)
			(xy 150.542712 -371.193085) (xy 150.583928 -371.228803) (xy 150.619641 -371.270023) (xy 150.649125 -371.315905)
			(xy 150.67178 -371.365516) (xy 150.687144 -371.417847) (xy 150.694906 -371.47183) (xy 150.694906 -371.52637)
			(xy 150.694906 -371.526371) (xy 155.875932 -371.526371) (xy 155.875932 -371.471829) (xy 155.883694 -371.417843)
			(xy 155.899061 -371.365511) (xy 155.921721 -371.315898) (xy 155.95121 -371.270016) (xy 155.986929 -371.228798)
			(xy 156.028151 -371.193084) (xy 156.074037 -371.163599) (xy 156.123652 -371.140946) (xy 156.175986 -371.125585)
			(xy 156.229973 -371.117828) (xy 156.257244 -371.117368) (xy 157.120844 -371.117368) (xy 157.148113 -371.117798)
			(xy 157.202097 -371.125565) (xy 157.254425 -371.140935) (xy 157.304033 -371.163596) (xy 157.349912 -371.193085)
			(xy 157.391128 -371.228803) (xy 157.426841 -371.270023) (xy 157.456325 -371.315905) (xy 157.47898 -371.365516)
			(xy 157.494344 -371.417847) (xy 157.502106 -371.47183) (xy 157.502106 -371.52637) (xy 157.502106 -371.526371)
			(xy 162.683132 -371.526371) (xy 162.683132 -371.471829) (xy 162.690894 -371.417843) (xy 162.706261 -371.365511)
			(xy 162.728921 -371.315898) (xy 162.75841 -371.270016) (xy 162.794129 -371.228798) (xy 162.835351 -371.193084)
			(xy 162.881237 -371.163599) (xy 162.930852 -371.140946) (xy 162.983186 -371.125585) (xy 163.037173 -371.117828)
			(xy 163.064444 -371.117368) (xy 163.928044 -371.117368) (xy 163.955313 -371.117798) (xy 164.009297 -371.125565)
			(xy 164.061625 -371.140935) (xy 164.111233 -371.163596) (xy 164.157112 -371.193085) (xy 164.198328 -371.228803)
			(xy 164.234041 -371.270023) (xy 164.263525 -371.315905) (xy 164.28618 -371.365516) (xy 164.301544 -371.417847)
			(xy 164.309306 -371.47183) (xy 164.309306 -371.52637) (xy 164.301544 -371.580353) (xy 164.28618 -371.632684)
			(xy 164.263525 -371.682295) (xy 164.234041 -371.728177) (xy 164.198328 -371.769397) (xy 164.157112 -371.805115)
			(xy 164.111233 -371.834604) (xy 164.061625 -371.857265) (xy 164.009297 -371.872635) (xy 163.955313 -371.880402)
			(xy 163.928044 -371.880892) (xy 163.064444 -371.880892) (xy 163.037173 -371.880372) (xy 162.983186 -371.872615)
			(xy 162.930852 -371.857254) (xy 162.881237 -371.834601) (xy 162.835351 -371.805116) (xy 162.794129 -371.769402)
			(xy 162.75841 -371.728184) (xy 162.728921 -371.682302) (xy 162.706261 -371.632689) (xy 162.690894 -371.580357)
			(xy 162.683132 -371.526371) (xy 157.502106 -371.526371) (xy 157.494344 -371.580353) (xy 157.47898 -371.632684)
			(xy 157.456325 -371.682295) (xy 157.426841 -371.728177) (xy 157.391128 -371.769397) (xy 157.349912 -371.805115)
			(xy 157.304033 -371.834604) (xy 157.254425 -371.857265) (xy 157.202097 -371.872635) (xy 157.148113 -371.880402)
			(xy 157.120844 -371.880892) (xy 156.257244 -371.880892) (xy 156.229973 -371.880372) (xy 156.175986 -371.872615)
			(xy 156.123652 -371.857254) (xy 156.074037 -371.834601) (xy 156.028151 -371.805116) (xy 155.986929 -371.769402)
			(xy 155.95121 -371.728184) (xy 155.921721 -371.682302) (xy 155.899061 -371.632689) (xy 155.883694 -371.580357)
			(xy 155.875932 -371.526371) (xy 150.694906 -371.526371) (xy 150.687144 -371.580353) (xy 150.67178 -371.632684)
			(xy 150.649125 -371.682295) (xy 150.619641 -371.728177) (xy 150.583928 -371.769397) (xy 150.542712 -371.805115)
			(xy 150.496833 -371.834604) (xy 150.447225 -371.857265) (xy 150.394897 -371.872635) (xy 150.340913 -371.880402)
			(xy 150.313644 -371.880892) (xy 149.450044 -371.880892) (xy 149.422773 -371.880372) (xy 149.368786 -371.872615)
			(xy 149.316452 -371.857254) (xy 149.266837 -371.834601) (xy 149.220951 -371.805116) (xy 149.179729 -371.769402)
			(xy 149.14401 -371.728184) (xy 149.114521 -371.682302) (xy 149.091861 -371.632689) (xy 149.076494 -371.580357)
			(xy 149.068732 -371.526371) (xy 143.887706 -371.526371) (xy 143.879944 -371.580353) (xy 143.86458 -371.632684)
			(xy 143.841925 -371.682295) (xy 143.812441 -371.728177) (xy 143.776728 -371.769397) (xy 143.735512 -371.805115)
			(xy 143.689633 -371.834604) (xy 143.640025 -371.857265) (xy 143.587697 -371.872635) (xy 143.533713 -371.880402)
			(xy 143.506444 -371.880892) (xy 142.642844 -371.880892) (xy 142.615573 -371.880372) (xy 142.561586 -371.872615)
			(xy 142.509252 -371.857254) (xy 142.459637 -371.834601) (xy 142.413751 -371.805116) (xy 142.372529 -371.769402)
			(xy 142.33681 -371.728184) (xy 142.307321 -371.682302) (xy 142.284661 -371.632689) (xy 142.269294 -371.580357)
			(xy 142.261532 -371.526371) (xy 131.781628 -371.526371) (xy 131.781628 -371.526373) (xy 131.773866 -371.580365)
			(xy 131.758498 -371.632702) (xy 131.735838 -371.682319) (xy 131.706348 -371.728207) (xy 131.670627 -371.76943)
			(xy 131.629403 -371.80515) (xy 131.583516 -371.83464) (xy 131.533898 -371.857299) (xy 131.481561 -371.872666)
			(xy 131.427569 -371.880429) (xy 131.400296 -371.880892) (xy 130.536696 -371.880892) (xy 130.509429 -371.880345)
			(xy 130.45545 -371.872584) (xy 130.403125 -371.857219) (xy 130.353519 -371.834565) (xy 130.307642 -371.805081)
			(xy 130.266429 -371.769369) (xy 130.230717 -371.728154) (xy 130.201233 -371.682277) (xy 130.178579 -371.632671)
			(xy 130.163215 -371.580346) (xy 130.155454 -371.526367) (xy 124.974428 -371.526367) (xy 124.974428 -371.526373)
			(xy 124.966666 -371.580365) (xy 124.951298 -371.632702) (xy 124.928638 -371.682319) (xy 124.899148 -371.728207)
			(xy 124.863427 -371.76943) (xy 124.822203 -371.80515) (xy 124.776316 -371.83464) (xy 124.726698 -371.857299)
			(xy 124.674361 -371.872666) (xy 124.620369 -371.880429) (xy 124.593096 -371.880892) (xy 123.729496 -371.880892)
			(xy 123.702229 -371.880345) (xy 123.64825 -371.872584) (xy 123.595925 -371.857219) (xy 123.546319 -371.834565)
			(xy 123.500442 -371.805081) (xy 123.459229 -371.769369) (xy 123.423517 -371.728154) (xy 123.394033 -371.682277)
			(xy 123.371379 -371.632671) (xy 123.356015 -371.580346) (xy 123.348254 -371.526367) (xy 118.167228 -371.526367)
			(xy 118.167228 -371.526373) (xy 118.159466 -371.580365) (xy 118.144098 -371.632702) (xy 118.121438 -371.682319)
			(xy 118.091948 -371.728207) (xy 118.056227 -371.76943) (xy 118.015003 -371.80515) (xy 117.969116 -371.83464)
			(xy 117.919498 -371.857299) (xy 117.867161 -371.872666) (xy 117.813169 -371.880429) (xy 117.785896 -371.880892)
			(xy 116.922296 -371.880892) (xy 116.895029 -371.880345) (xy 116.84105 -371.872584) (xy 116.788725 -371.857219)
			(xy 116.739119 -371.834565) (xy 116.693242 -371.805081) (xy 116.652029 -371.769369) (xy 116.616317 -371.728154)
			(xy 116.586833 -371.682277) (xy 116.564179 -371.632671) (xy 116.548815 -371.580346) (xy 116.541054 -371.526367)
			(xy 111.360028 -371.526367) (xy 111.360028 -371.526373) (xy 111.352266 -371.580365) (xy 111.336898 -371.632702)
			(xy 111.314238 -371.682319) (xy 111.284748 -371.728207) (xy 111.249027 -371.76943) (xy 111.207803 -371.80515)
			(xy 111.161916 -371.83464) (xy 111.112298 -371.857299) (xy 111.059961 -371.872666) (xy 111.005969 -371.880429)
			(xy 110.978696 -371.880892) (xy 110.115096 -371.880892) (xy 110.087829 -371.880345) (xy 110.03385 -371.872584)
			(xy 109.981525 -371.857219) (xy 109.931919 -371.834565) (xy 109.886042 -371.805081) (xy 109.844829 -371.769369)
			(xy 109.809117 -371.728154) (xy 109.779633 -371.682277) (xy 109.756979 -371.632671) (xy 109.741615 -371.580346)
			(xy 109.733854 -371.526367) (xy 97.209406 -371.526367) (xy 97.209406 -371.526371) (xy 97.201643 -371.580359)
			(xy 97.186277 -371.632693) (xy 97.163619 -371.682307) (xy 97.134131 -371.728191) (xy 97.098413 -371.769412)
			(xy 97.057193 -371.80513) (xy 97.011308 -371.834618) (xy 96.961694 -371.857276) (xy 96.909361 -371.872643)
			(xy 96.855373 -371.880405) (xy 96.828102 -371.880892) (xy 95.964502 -371.880892) (xy 95.937233 -371.880369)
			(xy 95.88325 -371.872607) (xy 95.830921 -371.857243) (xy 95.781312 -371.834587) (xy 95.735432 -371.805102)
			(xy 95.694214 -371.769387) (xy 95.6585 -371.72817) (xy 95.629014 -371.68229) (xy 95.606358 -371.63268)
			(xy 95.590993 -371.580352) (xy 95.583231 -371.526369) (xy 90.402206 -371.526369) (xy 90.402206 -371.526371)
			(xy 90.394443 -371.580359) (xy 90.379077 -371.632693) (xy 90.356419 -371.682307) (xy 90.326931 -371.728191)
			(xy 90.291213 -371.769412) (xy 90.249993 -371.80513) (xy 90.204108 -371.834618) (xy 90.154494 -371.857276)
			(xy 90.102161 -371.872643) (xy 90.048173 -371.880405) (xy 90.020902 -371.880892) (xy 89.157302 -371.880892)
			(xy 89.130033 -371.880369) (xy 89.07605 -371.872607) (xy 89.023721 -371.857243) (xy 88.974112 -371.834587)
			(xy 88.928232 -371.805102) (xy 88.887014 -371.769387) (xy 88.8513 -371.72817) (xy 88.821814 -371.68229)
			(xy 88.799158 -371.63268) (xy 88.783793 -371.580352) (xy 88.776031 -371.526369) (xy 83.595006 -371.526369)
			(xy 83.595006 -371.526371) (xy 83.587243 -371.580359) (xy 83.571877 -371.632693) (xy 83.549219 -371.682307)
			(xy 83.519731 -371.728191) (xy 83.484013 -371.769412) (xy 83.442793 -371.80513) (xy 83.396908 -371.834618)
			(xy 83.347294 -371.857276) (xy 83.294961 -371.872643) (xy 83.240973 -371.880405) (xy 83.213702 -371.880892)
			(xy 82.350102 -371.880892) (xy 82.322833 -371.880369) (xy 82.26885 -371.872607) (xy 82.216521 -371.857243)
			(xy 82.166912 -371.834587) (xy 82.121032 -371.805102) (xy 82.079814 -371.769387) (xy 82.0441 -371.72817)
			(xy 82.014614 -371.68229) (xy 81.991958 -371.63268) (xy 81.976593 -371.580352) (xy 81.968831 -371.526369)
			(xy 76.787806 -371.526369) (xy 76.787806 -371.526371) (xy 76.780043 -371.580359) (xy 76.764677 -371.632693)
			(xy 76.742019 -371.682307) (xy 76.712531 -371.728191) (xy 76.676813 -371.769412) (xy 76.635593 -371.80513)
			(xy 76.589708 -371.834618) (xy 76.540094 -371.857276) (xy 76.487761 -371.872643) (xy 76.433773 -371.880405)
			(xy 76.406502 -371.880892) (xy 75.542902 -371.880892) (xy 75.515633 -371.880369) (xy 75.46165 -371.872607)
			(xy 75.409321 -371.857243) (xy 75.359712 -371.834587) (xy 75.313832 -371.805102) (xy 75.272614 -371.769387)
			(xy 75.2369 -371.72817) (xy 75.207414 -371.68229) (xy 75.184758 -371.63268) (xy 75.169393 -371.580352)
			(xy 75.161631 -371.526369) (xy 64.681728 -371.526369) (xy 64.681728 -371.526375) (xy 64.673964 -371.58037)
			(xy 64.658595 -371.632711) (xy 64.635932 -371.682331) (xy 64.606438 -371.72822) (xy 64.570712 -371.769445)
			(xy 64.529484 -371.805165) (xy 64.483591 -371.834654) (xy 64.433968 -371.857311) (xy 64.381625 -371.872674)
			(xy 64.327629 -371.880432) (xy 64.300354 -371.880892) (xy 63.436754 -371.880892) (xy 63.409489 -371.880343)
			(xy 63.355515 -371.872576) (xy 63.303195 -371.857208) (xy 63.253594 -371.834551) (xy 63.207723 -371.805066)
			(xy 63.166514 -371.769354) (xy 63.130806 -371.728141) (xy 63.101327 -371.682265) (xy 63.078676 -371.632662)
			(xy 63.063314 -371.58034) (xy 63.055554 -371.526365) (xy 57.874528 -371.526365) (xy 57.874528 -371.526375)
			(xy 57.866764 -371.58037) (xy 57.851395 -371.632711) (xy 57.828732 -371.682331) (xy 57.799238 -371.72822)
			(xy 57.763512 -371.769445) (xy 57.722284 -371.805165) (xy 57.676391 -371.834654) (xy 57.626768 -371.857311)
			(xy 57.574425 -371.872674) (xy 57.520429 -371.880432) (xy 57.493154 -371.880892) (xy 56.629554 -371.880892)
			(xy 56.602289 -371.880343) (xy 56.548315 -371.872576) (xy 56.495995 -371.857208) (xy 56.446394 -371.834551)
			(xy 56.400523 -371.805066) (xy 56.359314 -371.769354) (xy 56.323606 -371.728141) (xy 56.294127 -371.682265)
			(xy 56.271476 -371.632662) (xy 56.256114 -371.58034) (xy 56.248354 -371.526365) (xy 51.067328 -371.526365)
			(xy 51.067328 -371.526375) (xy 51.059564 -371.58037) (xy 51.044195 -371.632711) (xy 51.021532 -371.682331)
			(xy 50.992038 -371.72822) (xy 50.956312 -371.769445) (xy 50.915084 -371.805165) (xy 50.869191 -371.834654)
			(xy 50.819568 -371.857311) (xy 50.767225 -371.872674) (xy 50.713229 -371.880432) (xy 50.685954 -371.880892)
			(xy 49.822354 -371.880892) (xy 49.795089 -371.880343) (xy 49.741115 -371.872576) (xy 49.688795 -371.857208)
			(xy 49.639194 -371.834551) (xy 49.593323 -371.805066) (xy 49.552114 -371.769354) (xy 49.516406 -371.728141)
			(xy 49.486927 -371.682265) (xy 49.464276 -371.632662) (xy 49.448914 -371.58034) (xy 49.441154 -371.526365)
			(xy 44.260128 -371.526365) (xy 44.260128 -371.526375) (xy 44.252364 -371.58037) (xy 44.236995 -371.632711)
			(xy 44.214332 -371.682331) (xy 44.184838 -371.72822) (xy 44.149112 -371.769445) (xy 44.107884 -371.805165)
			(xy 44.061991 -371.834654) (xy 44.012368 -371.857311) (xy 43.960025 -371.872674) (xy 43.906029 -371.880432)
			(xy 43.878754 -371.880892) (xy 43.015154 -371.880892) (xy 42.987889 -371.880343) (xy 42.933915 -371.872576)
			(xy 42.881595 -371.857208) (xy 42.831994 -371.834551) (xy 42.786123 -371.805066) (xy 42.744914 -371.769354)
			(xy 42.709206 -371.728141) (xy 42.679727 -371.682265) (xy 42.657076 -371.632662) (xy 42.641714 -371.58034)
			(xy 42.633954 -371.526365) (xy 2.509012 -371.526365) (xy 2.509012 -376.489976) (xy 31.068784 -376.489976)
			(xy 31.072756 -376.311733) (xy 31.084664 -376.133844) (xy 31.104485 -375.956662) (xy 31.132179 -375.780538)
			(xy 31.167691 -375.605823) (xy 31.210951 -375.432864) (xy 31.261873 -375.262003) (xy 31.320356 -375.093581)
			(xy 31.386283 -374.927931) (xy 31.459524 -374.765382) (xy 31.539934 -374.606257) (xy 31.627352 -374.450872)
			(xy 31.721605 -374.299536) (xy 31.822506 -374.152548) (xy 31.929855 -374.010201) (xy 32.043438 -373.872778)
			(xy 32.163031 -373.740551) (xy 32.288395 -373.613782) (xy 32.419282 -373.492724) (xy 32.555431 -373.377617)
			(xy 32.696573 -373.268689) (xy 32.842428 -373.166157) (xy 32.992705 -373.070223) (xy 33.147106 -372.98108)
			(xy 33.305325 -372.898903) (xy 33.467048 -372.823855) (xy 33.631953 -372.756087) (xy 33.799714 -372.695731)
			(xy 33.969997 -372.642909) (xy 34.142464 -372.597725) (xy 34.316772 -372.560268) (xy 34.492576 -372.530614)
			(xy 34.669526 -372.508821) (xy 34.847272 -372.494931) (xy 35.025459 -372.488974) (xy 35.203736 -372.49096)
			(xy 35.381747 -372.500886) (xy 35.559139 -372.518732) (xy 35.735559 -372.544462) (xy 35.910659 -372.578026)
			(xy 36.08409 -372.619356) (xy 36.255507 -372.668372) (xy 36.42457 -372.724974) (xy 36.590945 -372.789052)
			(xy 36.754299 -372.860478) (xy 36.91431 -372.93911) (xy 37.070659 -373.024791) (xy 37.223036 -373.117353)
			(xy 37.371139 -373.21661) (xy 37.514673 -373.322367) (xy 37.653353 -373.434412) (xy 37.786904 -373.552524)
			(xy 37.915061 -373.676468) (xy 38.03757 -373.805998) (xy 38.154187 -373.940857) (xy 38.193125 -373.990165)
			(xy 47.739354 -373.990165) (xy 47.739354 -373.935635) (xy 47.747114 -373.88166) (xy 47.762476 -373.829338)
			(xy 47.785127 -373.779735) (xy 47.814606 -373.733859) (xy 47.850314 -373.692646) (xy 47.891523 -373.656934)
			(xy 47.937394 -373.627449) (xy 47.986995 -373.604792) (xy 48.039315 -373.589424) (xy 48.093289 -373.581657)
			(xy 48.120554 -373.581168) (xy 48.984154 -373.581168) (xy 49.011429 -373.581568) (xy 49.065425 -373.589326)
			(xy 49.117768 -373.604689) (xy 49.167391 -373.627346) (xy 49.213284 -373.656835) (xy 49.254512 -373.692555)
			(xy 49.290238 -373.73378) (xy 49.319732 -373.779669) (xy 49.342395 -373.829289) (xy 49.357764 -373.88163)
			(xy 49.365528 -373.935625) (xy 49.365528 -373.990165) (xy 54.546554 -373.990165) (xy 54.546554 -373.935635)
			(xy 54.554314 -373.88166) (xy 54.569676 -373.829338) (xy 54.592327 -373.779735) (xy 54.621806 -373.733859)
			(xy 54.657514 -373.692646) (xy 54.698723 -373.656934) (xy 54.744594 -373.627449) (xy 54.794195 -373.604792)
			(xy 54.846515 -373.589424) (xy 54.900489 -373.581657) (xy 54.927754 -373.581168) (xy 55.791354 -373.581168)
			(xy 55.818629 -373.581568) (xy 55.872625 -373.589326) (xy 55.924968 -373.604689) (xy 55.974591 -373.627346)
			(xy 56.020484 -373.656835) (xy 56.061712 -373.692555) (xy 56.097438 -373.73378) (xy 56.126932 -373.779669)
			(xy 56.149595 -373.829289) (xy 56.164964 -373.88163) (xy 56.172728 -373.935625) (xy 56.172728 -373.990165)
			(xy 61.353754 -373.990165) (xy 61.353754 -373.935635) (xy 61.361514 -373.88166) (xy 61.376876 -373.829338)
			(xy 61.399527 -373.779735) (xy 61.429006 -373.733859) (xy 61.464714 -373.692646) (xy 61.505923 -373.656934)
			(xy 61.551794 -373.627449) (xy 61.601395 -373.604792) (xy 61.653715 -373.589424) (xy 61.707689 -373.581657)
			(xy 61.734954 -373.581168) (xy 62.598554 -373.581168) (xy 62.625829 -373.581568) (xy 62.679825 -373.589326)
			(xy 62.732168 -373.604689) (xy 62.781791 -373.627346) (xy 62.827684 -373.656835) (xy 62.868912 -373.692555)
			(xy 62.904638 -373.73378) (xy 62.934132 -373.779669) (xy 62.956795 -373.829289) (xy 62.972164 -373.88163)
			(xy 62.979928 -373.935625) (xy 62.979928 -373.990169) (xy 80.267031 -373.990169) (xy 80.267031 -373.935631)
			(xy 80.274793 -373.881648) (xy 80.290158 -373.82932) (xy 80.312814 -373.77971) (xy 80.3423 -373.73383)
			(xy 80.378014 -373.692613) (xy 80.419232 -373.656898) (xy 80.465112 -373.627413) (xy 80.514721 -373.604757)
			(xy 80.56705 -373.589393) (xy 80.621033 -373.581631) (xy 80.648302 -373.581168) (xy 81.511902 -373.581168)
			(xy 81.539173 -373.581595) (xy 81.593161 -373.589357) (xy 81.645494 -373.604724) (xy 81.695108 -373.627382)
			(xy 81.740993 -373.65687) (xy 81.782213 -373.692588) (xy 81.817931 -373.733809) (xy 81.847419 -373.779693)
			(xy 81.870077 -373.829307) (xy 81.885443 -373.881641) (xy 81.893206 -373.935629) (xy 81.893206 -373.990169)
			(xy 87.074231 -373.990169) (xy 87.074231 -373.935631) (xy 87.081993 -373.881648) (xy 87.097358 -373.82932)
			(xy 87.120014 -373.77971) (xy 87.1495 -373.73383) (xy 87.185214 -373.692613) (xy 87.226432 -373.656898)
			(xy 87.272312 -373.627413) (xy 87.321921 -373.604757) (xy 87.37425 -373.589393) (xy 87.428233 -373.581631)
			(xy 87.455502 -373.581168) (xy 88.319102 -373.581168) (xy 88.346373 -373.581595) (xy 88.400361 -373.589357)
			(xy 88.452694 -373.604724) (xy 88.502308 -373.627382) (xy 88.548193 -373.65687) (xy 88.589413 -373.692588)
			(xy 88.625131 -373.733809) (xy 88.654619 -373.779693) (xy 88.677277 -373.829307) (xy 88.692643 -373.881641)
			(xy 88.700406 -373.935629) (xy 88.700406 -373.990169) (xy 93.881431 -373.990169) (xy 93.881431 -373.935631)
			(xy 93.889193 -373.881648) (xy 93.904558 -373.82932) (xy 93.927214 -373.77971) (xy 93.9567 -373.73383)
			(xy 93.992414 -373.692613) (xy 94.033632 -373.656898) (xy 94.079512 -373.627413) (xy 94.129121 -373.604757)
			(xy 94.18145 -373.589393) (xy 94.235433 -373.581631) (xy 94.262702 -373.581168) (xy 95.126302 -373.581168)
			(xy 95.153573 -373.581595) (xy 95.207561 -373.589357) (xy 95.259894 -373.604724) (xy 95.309508 -373.627382)
			(xy 95.355393 -373.65687) (xy 95.396613 -373.692588) (xy 95.432331 -373.733809) (xy 95.461819 -373.779693)
			(xy 95.484477 -373.829307) (xy 95.499843 -373.881641) (xy 95.507606 -373.935629) (xy 95.507606 -373.990167)
			(xy 114.839254 -373.990167) (xy 114.839254 -373.935633) (xy 114.847015 -373.881654) (xy 114.862379 -373.829329)
			(xy 114.885033 -373.779723) (xy 114.914517 -373.733846) (xy 114.950229 -373.692631) (xy 114.991442 -373.656919)
			(xy 115.037319 -373.627435) (xy 115.086925 -373.604781) (xy 115.13925 -373.589416) (xy 115.193229 -373.581655)
			(xy 115.220496 -373.581168) (xy 116.084096 -373.581168) (xy 116.111369 -373.581571) (xy 116.165361 -373.589334)
			(xy 116.217698 -373.604701) (xy 116.267316 -373.62736) (xy 116.313203 -373.65685) (xy 116.354427 -373.69257)
			(xy 116.390148 -373.733793) (xy 116.419638 -373.779681) (xy 116.442298 -373.829298) (xy 116.457666 -373.881635)
			(xy 116.465428 -373.935627) (xy 116.465428 -373.990167) (xy 121.646454 -373.990167) (xy 121.646454 -373.935633)
			(xy 121.654215 -373.881654) (xy 121.669579 -373.829329) (xy 121.692233 -373.779723) (xy 121.721717 -373.733846)
			(xy 121.757429 -373.692631) (xy 121.798642 -373.656919) (xy 121.844519 -373.627435) (xy 121.894125 -373.604781)
			(xy 121.94645 -373.589416) (xy 122.000429 -373.581655) (xy 122.027696 -373.581168) (xy 122.891296 -373.581168)
			(xy 122.918569 -373.581571) (xy 122.972561 -373.589334) (xy 123.024898 -373.604701) (xy 123.074516 -373.62736)
			(xy 123.120403 -373.65685) (xy 123.161627 -373.69257) (xy 123.197348 -373.733793) (xy 123.226838 -373.779681)
			(xy 123.249498 -373.829298) (xy 123.264866 -373.881635) (xy 123.272628 -373.935627) (xy 123.272628 -373.990167)
			(xy 128.453654 -373.990167) (xy 128.453654 -373.935633) (xy 128.461415 -373.881654) (xy 128.476779 -373.829329)
			(xy 128.499433 -373.779723) (xy 128.528917 -373.733846) (xy 128.564629 -373.692631) (xy 128.605842 -373.656919)
			(xy 128.651719 -373.627435) (xy 128.701325 -373.604781) (xy 128.75365 -373.589416) (xy 128.807629 -373.581655)
			(xy 128.834896 -373.581168) (xy 129.698496 -373.581168) (xy 129.725769 -373.581571) (xy 129.779761 -373.589334)
			(xy 129.832098 -373.604701) (xy 129.881716 -373.62736) (xy 129.927603 -373.65685) (xy 129.968827 -373.69257)
			(xy 130.004548 -373.733793) (xy 130.034038 -373.779681) (xy 130.056698 -373.829298) (xy 130.072066 -373.881635)
			(xy 130.079828 -373.935627) (xy 130.079828 -373.990171) (xy 147.366932 -373.990171) (xy 147.366932 -373.935629)
			(xy 147.374694 -373.881643) (xy 147.390061 -373.829311) (xy 147.412721 -373.779698) (xy 147.44221 -373.733816)
			(xy 147.477929 -373.692598) (xy 147.519151 -373.656884) (xy 147.565037 -373.627399) (xy 147.614652 -373.604746)
			(xy 147.666986 -373.589385) (xy 147.720973 -373.581628) (xy 147.748244 -373.581168) (xy 148.611844 -373.581168)
			(xy 148.639113 -373.581598) (xy 148.693097 -373.589365) (xy 148.745425 -373.604735) (xy 148.795033 -373.627396)
			(xy 148.840912 -373.656885) (xy 148.882128 -373.692603) (xy 148.917841 -373.733823) (xy 148.947325 -373.779705)
			(xy 148.96998 -373.829316) (xy 148.985344 -373.881647) (xy 148.993106 -373.93563) (xy 148.993106 -373.99017)
			(xy 148.993106 -373.990171) (xy 154.174132 -373.990171) (xy 154.174132 -373.935629) (xy 154.181894 -373.881643)
			(xy 154.197261 -373.829311) (xy 154.219921 -373.779698) (xy 154.24941 -373.733816) (xy 154.285129 -373.692598)
			(xy 154.326351 -373.656884) (xy 154.372237 -373.627399) (xy 154.421852 -373.604746) (xy 154.474186 -373.589385)
			(xy 154.528173 -373.581628) (xy 154.555444 -373.581168) (xy 155.419044 -373.581168) (xy 155.446313 -373.581598)
			(xy 155.500297 -373.589365) (xy 155.552625 -373.604735) (xy 155.602233 -373.627396) (xy 155.648112 -373.656885)
			(xy 155.689328 -373.692603) (xy 155.725041 -373.733823) (xy 155.754525 -373.779705) (xy 155.77718 -373.829316)
			(xy 155.792544 -373.881647) (xy 155.800306 -373.93563) (xy 155.800306 -373.99017) (xy 155.800306 -373.990171)
			(xy 160.981332 -373.990171) (xy 160.981332 -373.935629) (xy 160.989094 -373.881643) (xy 161.004461 -373.829311)
			(xy 161.027121 -373.779698) (xy 161.05661 -373.733816) (xy 161.092329 -373.692598) (xy 161.133551 -373.656884)
			(xy 161.179437 -373.627399) (xy 161.229052 -373.604746) (xy 161.281386 -373.589385) (xy 161.335373 -373.581628)
			(xy 161.362644 -373.581168) (xy 162.226244 -373.581168) (xy 162.253513 -373.581598) (xy 162.307497 -373.589365)
			(xy 162.359825 -373.604735) (xy 162.409433 -373.627396) (xy 162.455312 -373.656885) (xy 162.496528 -373.692603)
			(xy 162.532241 -373.733823) (xy 162.561725 -373.779705) (xy 162.58438 -373.829316) (xy 162.599744 -373.881647)
			(xy 162.607506 -373.93563) (xy 162.607506 -373.99017) (xy 162.599744 -374.044153) (xy 162.58438 -374.096484)
			(xy 162.561725 -374.146095) (xy 162.532241 -374.191977) (xy 162.496528 -374.233197) (xy 162.455312 -374.268915)
			(xy 162.409433 -374.298404) (xy 162.359825 -374.321065) (xy 162.307497 -374.336435) (xy 162.253513 -374.344202)
			(xy 162.226244 -374.344692) (xy 161.362644 -374.344692) (xy 161.335373 -374.344172) (xy 161.281386 -374.336415)
			(xy 161.229052 -374.321054) (xy 161.179437 -374.298401) (xy 161.133551 -374.268916) (xy 161.092329 -374.233202)
			(xy 161.05661 -374.191984) (xy 161.027121 -374.146102) (xy 161.004461 -374.096489) (xy 160.989094 -374.044157)
			(xy 160.981332 -373.990171) (xy 155.800306 -373.990171) (xy 155.792544 -374.044153) (xy 155.77718 -374.096484)
			(xy 155.754525 -374.146095) (xy 155.725041 -374.191977) (xy 155.689328 -374.233197) (xy 155.648112 -374.268915)
			(xy 155.602233 -374.298404) (xy 155.552625 -374.321065) (xy 155.500297 -374.336435) (xy 155.446313 -374.344202)
			(xy 155.419044 -374.344692) (xy 154.555444 -374.344692) (xy 154.528173 -374.344172) (xy 154.474186 -374.336415)
			(xy 154.421852 -374.321054) (xy 154.372237 -374.298401) (xy 154.326351 -374.268916) (xy 154.285129 -374.233202)
			(xy 154.24941 -374.191984) (xy 154.219921 -374.146102) (xy 154.197261 -374.096489) (xy 154.181894 -374.044157)
			(xy 154.174132 -373.990171) (xy 148.993106 -373.990171) (xy 148.985344 -374.044153) (xy 148.96998 -374.096484)
			(xy 148.947325 -374.146095) (xy 148.917841 -374.191977) (xy 148.882128 -374.233197) (xy 148.840912 -374.268915)
			(xy 148.795033 -374.298404) (xy 148.745425 -374.321065) (xy 148.693097 -374.336435) (xy 148.639113 -374.344202)
			(xy 148.611844 -374.344692) (xy 147.748244 -374.344692) (xy 147.720973 -374.344172) (xy 147.666986 -374.336415)
			(xy 147.614652 -374.321054) (xy 147.565037 -374.298401) (xy 147.519151 -374.268916) (xy 147.477929 -374.233202)
			(xy 147.44221 -374.191984) (xy 147.412721 -374.146102) (xy 147.390061 -374.096489) (xy 147.374694 -374.044157)
			(xy 147.366932 -373.990171) (xy 130.079828 -373.990171) (xy 130.079828 -373.990173) (xy 130.072066 -374.044165)
			(xy 130.056698 -374.096502) (xy 130.034038 -374.146119) (xy 130.004548 -374.192007) (xy 129.968827 -374.23323)
			(xy 129.927603 -374.26895) (xy 129.881716 -374.29844) (xy 129.832098 -374.321099) (xy 129.779761 -374.336466)
			(xy 129.725769 -374.344229) (xy 129.698496 -374.344692) (xy 128.834896 -374.344692) (xy 128.807629 -374.344145)
			(xy 128.75365 -374.336384) (xy 128.701325 -374.321019) (xy 128.651719 -374.298365) (xy 128.605842 -374.268881)
			(xy 128.564629 -374.233169) (xy 128.528917 -374.191954) (xy 128.499433 -374.146077) (xy 128.476779 -374.096471)
			(xy 128.461415 -374.044146) (xy 128.453654 -373.990167) (xy 123.272628 -373.990167) (xy 123.272628 -373.990173)
			(xy 123.264866 -374.044165) (xy 123.249498 -374.096502) (xy 123.226838 -374.146119) (xy 123.197348 -374.192007)
			(xy 123.161627 -374.23323) (xy 123.120403 -374.26895) (xy 123.074516 -374.29844) (xy 123.024898 -374.321099)
			(xy 122.972561 -374.336466) (xy 122.918569 -374.344229) (xy 122.891296 -374.344692) (xy 122.027696 -374.344692)
			(xy 122.000429 -374.344145) (xy 121.94645 -374.336384) (xy 121.894125 -374.321019) (xy 121.844519 -374.298365)
			(xy 121.798642 -374.268881) (xy 121.757429 -374.233169) (xy 121.721717 -374.191954) (xy 121.692233 -374.146077)
			(xy 121.669579 -374.096471) (xy 121.654215 -374.044146) (xy 121.646454 -373.990167) (xy 116.465428 -373.990167)
			(xy 116.465428 -373.990173) (xy 116.457666 -374.044165) (xy 116.442298 -374.096502) (xy 116.419638 -374.146119)
			(xy 116.390148 -374.192007) (xy 116.354427 -374.23323) (xy 116.313203 -374.26895) (xy 116.267316 -374.29844)
			(xy 116.217698 -374.321099) (xy 116.165361 -374.336466) (xy 116.111369 -374.344229) (xy 116.084096 -374.344692)
			(xy 115.220496 -374.344692) (xy 115.193229 -374.344145) (xy 115.13925 -374.336384) (xy 115.086925 -374.321019)
			(xy 115.037319 -374.298365) (xy 114.991442 -374.268881) (xy 114.950229 -374.233169) (xy 114.914517 -374.191954)
			(xy 114.885033 -374.146077) (xy 114.862379 -374.096471) (xy 114.847015 -374.044146) (xy 114.839254 -373.990167)
			(xy 95.507606 -373.990167) (xy 95.507606 -373.990171) (xy 95.499843 -374.044159) (xy 95.484477 -374.096493)
			(xy 95.461819 -374.146107) (xy 95.432331 -374.191991) (xy 95.396613 -374.233212) (xy 95.355393 -374.26893)
			(xy 95.309508 -374.298418) (xy 95.259894 -374.321076) (xy 95.207561 -374.336443) (xy 95.153573 -374.344205)
			(xy 95.126302 -374.344692) (xy 94.262702 -374.344692) (xy 94.235433 -374.344169) (xy 94.18145 -374.336407)
			(xy 94.129121 -374.321043) (xy 94.079512 -374.298387) (xy 94.033632 -374.268902) (xy 93.992414 -374.233187)
			(xy 93.9567 -374.19197) (xy 93.927214 -374.14609) (xy 93.904558 -374.09648) (xy 93.889193 -374.044152)
			(xy 93.881431 -373.990169) (xy 88.700406 -373.990169) (xy 88.700406 -373.990171) (xy 88.692643 -374.044159)
			(xy 88.677277 -374.096493) (xy 88.654619 -374.146107) (xy 88.625131 -374.191991) (xy 88.589413 -374.233212)
			(xy 88.548193 -374.26893) (xy 88.502308 -374.298418) (xy 88.452694 -374.321076) (xy 88.400361 -374.336443)
			(xy 88.346373 -374.344205) (xy 88.319102 -374.344692) (xy 87.455502 -374.344692) (xy 87.428233 -374.344169)
			(xy 87.37425 -374.336407) (xy 87.321921 -374.321043) (xy 87.272312 -374.298387) (xy 87.226432 -374.268902)
			(xy 87.185214 -374.233187) (xy 87.1495 -374.19197) (xy 87.120014 -374.14609) (xy 87.097358 -374.09648)
			(xy 87.081993 -374.044152) (xy 87.074231 -373.990169) (xy 81.893206 -373.990169) (xy 81.893206 -373.990171)
			(xy 81.885443 -374.044159) (xy 81.870077 -374.096493) (xy 81.847419 -374.146107) (xy 81.817931 -374.191991)
			(xy 81.782213 -374.233212) (xy 81.740993 -374.26893) (xy 81.695108 -374.298418) (xy 81.645494 -374.321076)
			(xy 81.593161 -374.336443) (xy 81.539173 -374.344205) (xy 81.511902 -374.344692) (xy 80.648302 -374.344692)
			(xy 80.621033 -374.344169) (xy 80.56705 -374.336407) (xy 80.514721 -374.321043) (xy 80.465112 -374.298387)
			(xy 80.419232 -374.268902) (xy 80.378014 -374.233187) (xy 80.3423 -374.19197) (xy 80.312814 -374.14609)
			(xy 80.290158 -374.09648) (xy 80.274793 -374.044152) (xy 80.267031 -373.990169) (xy 62.979928 -373.990169)
			(xy 62.979928 -373.990175) (xy 62.972164 -374.04417) (xy 62.956795 -374.096511) (xy 62.934132 -374.146131)
			(xy 62.904638 -374.19202) (xy 62.868912 -374.233245) (xy 62.827684 -374.268965) (xy 62.781791 -374.298454)
			(xy 62.732168 -374.321111) (xy 62.679825 -374.336474) (xy 62.625829 -374.344232) (xy 62.598554 -374.344692)
			(xy 61.734954 -374.344692) (xy 61.707689 -374.344143) (xy 61.653715 -374.336376) (xy 61.601395 -374.321008)
			(xy 61.551794 -374.298351) (xy 61.505923 -374.268866) (xy 61.464714 -374.233154) (xy 61.429006 -374.191941)
			(xy 61.399527 -374.146065) (xy 61.376876 -374.096462) (xy 61.361514 -374.04414) (xy 61.353754 -373.990165)
			(xy 56.172728 -373.990165) (xy 56.172728 -373.990175) (xy 56.164964 -374.04417) (xy 56.149595 -374.096511)
			(xy 56.126932 -374.146131) (xy 56.097438 -374.19202) (xy 56.061712 -374.233245) (xy 56.020484 -374.268965)
			(xy 55.974591 -374.298454) (xy 55.924968 -374.321111) (xy 55.872625 -374.336474) (xy 55.818629 -374.344232)
			(xy 55.791354 -374.344692) (xy 54.927754 -374.344692) (xy 54.900489 -374.344143) (xy 54.846515 -374.336376)
			(xy 54.794195 -374.321008) (xy 54.744594 -374.298351) (xy 54.698723 -374.268866) (xy 54.657514 -374.233154)
			(xy 54.621806 -374.191941) (xy 54.592327 -374.146065) (xy 54.569676 -374.096462) (xy 54.554314 -374.04414)
			(xy 54.546554 -373.990165) (xy 49.365528 -373.990165) (xy 49.365528 -373.990175) (xy 49.357764 -374.04417)
			(xy 49.342395 -374.096511) (xy 49.319732 -374.146131) (xy 49.290238 -374.19202) (xy 49.254512 -374.233245)
			(xy 49.213284 -374.268965) (xy 49.167391 -374.298454) (xy 49.117768 -374.321111) (xy 49.065425 -374.336474)
			(xy 49.011429 -374.344232) (xy 48.984154 -374.344692) (xy 48.120554 -374.344692) (xy 48.093289 -374.344143)
			(xy 48.039315 -374.336376) (xy 47.986995 -374.321008) (xy 47.937394 -374.298351) (xy 47.891523 -374.268866)
			(xy 47.850314 -374.233154) (xy 47.814606 -374.191941) (xy 47.785127 -374.146065) (xy 47.762476 -374.096462)
			(xy 47.747114 -374.04414) (xy 47.739354 -373.990165) (xy 38.193125 -373.990165) (xy 38.26468 -374.080777)
			(xy 38.368831 -374.22548) (xy 38.466433 -374.374679) (xy 38.557291 -374.528078) (xy 38.641225 -374.685372)
			(xy 38.71807 -374.846248) (xy 38.787671 -375.010389) (xy 38.849892 -375.177466) (xy 38.904608 -375.34715)
			(xy 38.95171 -375.519103) (xy 38.991106 -375.692983) (xy 39.022717 -375.868446) (xy 39.046481 -376.045142)
			(xy 39.062349 -376.222722) (xy 39.070291 -376.400832) (xy 39.070788 -376.489976) (xy 39.070291 -376.57912)
			(xy 39.062349 -376.75723) (xy 39.05568 -376.83186) (xy 41.04894 -376.83186) (xy 41.04894 -375.96826)
			(xy 41.049426 -375.940991) (xy 41.057188 -375.887007) (xy 41.072553 -375.834677) (xy 41.09521 -375.785067)
			(xy 41.124696 -375.739186) (xy 41.160411 -375.697969) (xy 41.201628 -375.662254) (xy 41.247509 -375.632768)
			(xy 41.297119 -375.610111) (xy 41.349449 -375.594746) (xy 41.403433 -375.586984) (xy 41.457971 -375.586984)
			(xy 41.511955 -375.594746) (xy 41.564285 -375.610111) (xy 41.613895 -375.632768) (xy 41.659776 -375.662254)
			(xy 41.700993 -375.697969) (xy 41.736708 -375.739186) (xy 41.766194 -375.785067) (xy 41.788851 -375.834677)
			(xy 41.804216 -375.887007) (xy 41.811978 -375.940991) (xy 41.812464 -375.96826) (xy 41.812464 -376.83186)
			(xy 41.811978 -376.859129) (xy 41.804216 -376.913113) (xy 41.791381 -376.956828) (xy 70.895972 -376.956828)
			(xy 70.895972 -376.093228) (xy 70.896458 -376.065959) (xy 70.90422 -376.011975) (xy 70.919585 -375.959645)
			(xy 70.942242 -375.910035) (xy 70.971728 -375.864154) (xy 71.007443 -375.822937) (xy 71.04866 -375.787222)
			(xy 71.094541 -375.757736) (xy 71.144151 -375.735079) (xy 71.196481 -375.719714) (xy 71.250465 -375.711952)
			(xy 71.305003 -375.711952) (xy 71.358987 -375.719714) (xy 71.411317 -375.735079) (xy 71.460927 -375.757736)
			(xy 71.506808 -375.787222) (xy 71.548025 -375.822937) (xy 71.58374 -375.864154) (xy 71.613226 -375.910035)
			(xy 71.635883 -375.959645) (xy 71.651248 -376.011975) (xy 71.65901 -376.065959) (xy 71.659496 -376.093228)
			(xy 71.659496 -376.83186) (xy 73.576688 -376.83186) (xy 73.576688 -375.96826) (xy 73.577174 -375.940991)
			(xy 73.584936 -375.887007) (xy 73.600301 -375.834677) (xy 73.622958 -375.785067) (xy 73.652444 -375.739186)
			(xy 73.688159 -375.697969) (xy 73.729376 -375.662254) (xy 73.775257 -375.632768) (xy 73.824867 -375.610111)
			(xy 73.877197 -375.594746) (xy 73.931181 -375.586984) (xy 73.985719 -375.586984) (xy 74.039703 -375.594746)
			(xy 74.092033 -375.610111) (xy 74.141643 -375.632768) (xy 74.187524 -375.662254) (xy 74.228741 -375.697969)
			(xy 74.264456 -375.739186) (xy 74.293942 -375.785067) (xy 74.316599 -375.834677) (xy 74.331964 -375.887007)
			(xy 74.339726 -375.940991) (xy 74.340212 -375.96826) (xy 74.340212 -376.83186) (xy 74.339726 -376.859129)
			(xy 74.331964 -376.913113) (xy 74.319129 -376.956828) (xy 103.42372 -376.956828) (xy 103.42372 -376.093228)
			(xy 103.424206 -376.065959) (xy 103.431968 -376.011975) (xy 103.447333 -375.959645) (xy 103.46999 -375.910035)
			(xy 103.499476 -375.864154) (xy 103.535191 -375.822937) (xy 103.576408 -375.787222) (xy 103.622289 -375.757736)
			(xy 103.671899 -375.735079) (xy 103.724229 -375.719714) (xy 103.778213 -375.711952) (xy 103.832751 -375.711952)
			(xy 103.886735 -375.719714) (xy 103.939065 -375.735079) (xy 103.988675 -375.757736) (xy 104.034556 -375.787222)
			(xy 104.075773 -375.822937) (xy 104.111488 -375.864154) (xy 104.140974 -375.910035) (xy 104.163631 -375.959645)
			(xy 104.178996 -376.011975) (xy 104.186758 -376.065959) (xy 104.187244 -376.093228) (xy 104.187244 -376.83186)
			(xy 108.149136 -376.83186) (xy 108.149136 -375.96826) (xy 108.149622 -375.941009) (xy 108.157378 -375.887061)
			(xy 108.172733 -375.834766) (xy 108.195375 -375.785189) (xy 108.224841 -375.739339) (xy 108.260532 -375.698148)
			(xy 108.301723 -375.662457) (xy 108.347573 -375.632991) (xy 108.39715 -375.610349) (xy 108.449445 -375.594994)
			(xy 108.503393 -375.587238) (xy 108.557895 -375.587238) (xy 108.611843 -375.594994) (xy 108.664138 -375.610349)
			(xy 108.713715 -375.632991) (xy 108.759565 -375.662457) (xy 108.800756 -375.698148) (xy 108.836447 -375.739339)
			(xy 108.865913 -375.785189) (xy 108.888555 -375.834766) (xy 108.90391 -375.887061) (xy 108.911666 -375.941009)
			(xy 108.912152 -375.96826) (xy 108.912152 -376.83186) (xy 108.911666 -376.859111) (xy 108.90391 -376.913059)
			(xy 108.891058 -376.956828) (xy 137.996168 -376.956828) (xy 137.996168 -376.093228) (xy 137.996654 -376.065977)
			(xy 138.00441 -376.012029) (xy 138.019765 -375.959734) (xy 138.042407 -375.910157) (xy 138.071873 -375.864307)
			(xy 138.107564 -375.823116) (xy 138.148755 -375.787425) (xy 138.194605 -375.757959) (xy 138.244182 -375.735317)
			(xy 138.296477 -375.719962) (xy 138.350425 -375.712206) (xy 138.404927 -375.712206) (xy 138.458875 -375.719962)
			(xy 138.51117 -375.735317) (xy 138.560747 -375.757959) (xy 138.606597 -375.787425) (xy 138.647788 -375.823116)
			(xy 138.683479 -375.864307) (xy 138.712945 -375.910157) (xy 138.735587 -375.959734) (xy 138.750942 -376.012029)
			(xy 138.758698 -376.065977) (xy 138.759184 -376.093228) (xy 138.759184 -376.83186) (xy 140.676884 -376.83186)
			(xy 140.676884 -375.96826) (xy 140.67737 -375.941009) (xy 140.685126 -375.887061) (xy 140.700481 -375.834766)
			(xy 140.723123 -375.785189) (xy 140.752589 -375.739339) (xy 140.78828 -375.698148) (xy 140.829471 -375.662457)
			(xy 140.875321 -375.632991) (xy 140.924898 -375.610349) (xy 140.977193 -375.594994) (xy 141.031141 -375.587238)
			(xy 141.085643 -375.587238) (xy 141.139591 -375.594994) (xy 141.191886 -375.610349) (xy 141.241463 -375.632991)
			(xy 141.287313 -375.662457) (xy 141.328504 -375.698148) (xy 141.364195 -375.739339) (xy 141.393661 -375.785189)
			(xy 141.416303 -375.834766) (xy 141.431658 -375.887061) (xy 141.439414 -375.941009) (xy 141.4399 -375.96826)
			(xy 141.4399 -376.83186) (xy 141.439414 -376.859111) (xy 141.431658 -376.913059) (xy 141.418806 -376.956828)
			(xy 170.523916 -376.956828) (xy 170.523916 -376.093228) (xy 170.524402 -376.065977) (xy 170.532158 -376.012029)
			(xy 170.547513 -375.959734) (xy 170.570155 -375.910157) (xy 170.599621 -375.864307) (xy 170.635312 -375.823116)
			(xy 170.676503 -375.787425) (xy 170.722353 -375.757959) (xy 170.77193 -375.735317) (xy 170.824225 -375.719962)
			(xy 170.878173 -375.712206) (xy 170.932675 -375.712206) (xy 170.986623 -375.719962) (xy 171.038918 -375.735317)
			(xy 171.088495 -375.757959) (xy 171.134345 -375.787425) (xy 171.175536 -375.823116) (xy 171.211227 -375.864307)
			(xy 171.240693 -375.910157) (xy 171.263335 -375.959734) (xy 171.27869 -376.012029) (xy 171.286446 -376.065977)
			(xy 171.286932 -376.093228) (xy 171.286932 -376.489976) (xy 173.498776 -376.489976) (xy 173.502748 -376.311733)
			(xy 173.514656 -376.133844) (xy 173.534477 -375.956662) (xy 173.562171 -375.780538) (xy 173.597683 -375.605823)
			(xy 173.640943 -375.432864) (xy 173.691865 -375.262003) (xy 173.750348 -375.093581) (xy 173.816275 -374.927931)
			(xy 173.889516 -374.765382) (xy 173.969926 -374.606257) (xy 174.057344 -374.450872) (xy 174.151597 -374.299536)
			(xy 174.252498 -374.152548) (xy 174.359847 -374.010201) (xy 174.47343 -373.872778) (xy 174.593023 -373.740551)
			(xy 174.718387 -373.613782) (xy 174.849274 -373.492724) (xy 174.985423 -373.377617) (xy 175.126565 -373.268689)
			(xy 175.27242 -373.166157) (xy 175.422697 -373.070223) (xy 175.577098 -372.98108) (xy 175.735317 -372.898903)
			(xy 175.89704 -372.823855) (xy 176.061945 -372.756087) (xy 176.229706 -372.695731) (xy 176.399989 -372.642909)
			(xy 176.572456 -372.597725) (xy 176.746764 -372.560268) (xy 176.922568 -372.530614) (xy 177.099518 -372.508821)
			(xy 177.277264 -372.494931) (xy 177.455451 -372.488974) (xy 177.633728 -372.49096) (xy 177.811739 -372.500886)
			(xy 177.989131 -372.518732) (xy 178.165551 -372.544462) (xy 178.340651 -372.578026) (xy 178.514082 -372.619356)
			(xy 178.685499 -372.668372) (xy 178.854562 -372.724974) (xy 179.020937 -372.789052) (xy 179.184291 -372.860478)
			(xy 179.344302 -372.93911) (xy 179.500651 -373.024791) (xy 179.653028 -373.117353) (xy 179.801131 -373.21661)
			(xy 179.944665 -373.322367) (xy 180.083345 -373.434412) (xy 180.216896 -373.552524) (xy 180.345053 -373.676468)
			(xy 180.467562 -373.805998) (xy 180.584179 -373.940857) (xy 180.596796 -373.956834) (xy 282.853384 -373.956834)
			(xy 282.853384 -373.093234) (xy 282.85387 -373.065983) (xy 282.861626 -373.012035) (xy 282.876981 -372.95974)
			(xy 282.899623 -372.910163) (xy 282.929089 -372.864313) (xy 282.96478 -372.823122) (xy 283.005971 -372.787431)
			(xy 283.051821 -372.757965) (xy 283.101398 -372.735323) (xy 283.153693 -372.719968) (xy 283.207641 -372.712212)
			(xy 283.262143 -372.712212) (xy 283.316091 -372.719968) (xy 283.368386 -372.735323) (xy 283.417963 -372.757965)
			(xy 283.463813 -372.787431) (xy 283.505004 -372.823122) (xy 283.540695 -372.864313) (xy 283.570161 -372.910163)
			(xy 283.592803 -372.95974) (xy 283.608158 -373.012035) (xy 283.615914 -373.065983) (xy 283.6164 -373.093234)
			(xy 283.6164 -373.956834) (xy 283.615914 -373.984085) (xy 283.608158 -374.038033) (xy 283.592803 -374.090328)
			(xy 283.570161 -374.139905) (xy 283.540695 -374.185755) (xy 283.505004 -374.226946) (xy 283.463813 -374.262637)
			(xy 283.417963 -374.292103) (xy 283.368386 -374.314745) (xy 283.316091 -374.3301) (xy 283.262143 -374.337856)
			(xy 283.207641 -374.337856) (xy 283.153693 -374.3301) (xy 283.101398 -374.314745) (xy 283.051821 -374.292103)
			(xy 283.005971 -374.262637) (xy 282.96478 -374.226946) (xy 282.929089 -374.185755) (xy 282.899623 -374.139905)
			(xy 282.876981 -374.090328) (xy 282.861626 -374.038033) (xy 282.85387 -373.984085) (xy 282.853384 -373.956834)
			(xy 180.596796 -373.956834) (xy 180.694672 -374.080777) (xy 180.798823 -374.22548) (xy 180.896425 -374.374679)
			(xy 180.987283 -374.528078) (xy 181.071217 -374.685372) (xy 181.148062 -374.846248) (xy 181.217663 -375.010389)
			(xy 181.279884 -375.177466) (xy 181.3346 -375.34715) (xy 181.381702 -375.519103) (xy 181.421098 -375.692983)
			(xy 181.452709 -375.868446) (xy 181.476473 -376.045142) (xy 181.492341 -376.222722) (xy 181.500283 -376.400832)
			(xy 181.50078 -376.489976) (xy 181.500283 -376.57912) (xy 181.492341 -376.75723) (xy 181.476473 -376.93481)
			(xy 181.452709 -377.111506) (xy 181.421098 -377.286969) (xy 181.381702 -377.460849) (xy 181.3346 -377.632802)
			(xy 181.319901 -377.678385) (xy 193.900548 -377.678385) (xy 193.900548 -377.593663) (xy 193.908601 -377.509326)
			(xy 193.924635 -377.426136) (xy 193.948503 -377.344846) (xy 193.979991 -377.266194) (xy 194.018813 -377.190891)
			(xy 194.064616 -377.119619) (xy 194.116987 -377.053023) (xy 194.175452 -376.991708) (xy 194.23948 -376.936227)
			(xy 194.308492 -376.887084) (xy 194.381862 -376.844724) (xy 194.458927 -376.809529) (xy 194.538989 -376.78182)
			(xy 194.621322 -376.761846) (xy 194.705181 -376.749789) (xy 194.789806 -376.745758) (xy 194.874431 -376.749789)
			(xy 194.95829 -376.761846) (xy 195.040623 -376.78182) (xy 195.120685 -376.809529) (xy 195.19775 -376.844724)
			(xy 195.27112 -376.887084) (xy 195.340132 -376.936227) (xy 195.40416 -376.991708) (xy 195.462625 -377.053023)
			(xy 195.514996 -377.119619) (xy 195.560799 -377.190891) (xy 195.599621 -377.266194) (xy 195.631109 -377.344846)
			(xy 195.654977 -377.426136) (xy 195.671011 -377.509326) (xy 195.679064 -377.593663) (xy 195.679568 -377.636024)
			(xy 195.679064 -377.678385) (xy 195.671011 -377.762722) (xy 195.654977 -377.845912) (xy 195.631109 -377.927202)
			(xy 195.599621 -378.005854) (xy 195.560799 -378.081157) (xy 195.514996 -378.152429) (xy 195.47531 -378.202895)
			(xy 199.443082 -378.202895) (xy 199.443082 -378.118173) (xy 199.451135 -378.033836) (xy 199.467169 -377.950646)
			(xy 199.491037 -377.869356) (xy 199.522525 -377.790704) (xy 199.561347 -377.715401) (xy 199.60715 -377.644129)
			(xy 199.659521 -377.577533) (xy 199.717986 -377.516218) (xy 199.782014 -377.460737) (xy 199.851026 -377.411594)
			(xy 199.924396 -377.369234) (xy 200.001461 -377.334039) (xy 200.081523 -377.30633) (xy 200.163856 -377.286356)
			(xy 200.247715 -377.274299) (xy 200.33234 -377.270268) (xy 200.416965 -377.274299) (xy 200.500824 -377.286356)
			(xy 200.583157 -377.30633) (xy 200.663219 -377.334039) (xy 200.740284 -377.369234) (xy 200.813654 -377.411594)
			(xy 200.859958 -377.444567) (xy 300.335454 -377.444567) (xy 300.335454 -377.390033) (xy 300.343215 -377.336054)
			(xy 300.358579 -377.283729) (xy 300.381233 -377.234123) (xy 300.410717 -377.188246) (xy 300.446429 -377.147031)
			(xy 300.487642 -377.111319) (xy 300.533519 -377.081835) (xy 300.583125 -377.059181) (xy 300.63545 -377.043816)
			(xy 300.689429 -377.036055) (xy 300.716696 -377.035568) (xy 301.580296 -377.035568) (xy 301.607569 -377.035971)
			(xy 301.661561 -377.043734) (xy 301.713898 -377.059101) (xy 301.763516 -377.08176) (xy 301.809403 -377.11125)
			(xy 301.850627 -377.14697) (xy 301.886348 -377.188193) (xy 301.915838 -377.234081) (xy 301.938498 -377.283698)
			(xy 301.953866 -377.336035) (xy 301.961628 -377.390027) (xy 301.961628 -377.444567) (xy 307.142654 -377.444567)
			(xy 307.142654 -377.390033) (xy 307.150415 -377.336054) (xy 307.165779 -377.283729) (xy 307.188433 -377.234123)
			(xy 307.217917 -377.188246) (xy 307.253629 -377.147031) (xy 307.294842 -377.111319) (xy 307.340719 -377.081835)
			(xy 307.390325 -377.059181) (xy 307.44265 -377.043816) (xy 307.496629 -377.036055) (xy 307.523896 -377.035568)
			(xy 308.387496 -377.035568) (xy 308.414769 -377.035971) (xy 308.468761 -377.043734) (xy 308.521098 -377.059101)
			(xy 308.570716 -377.08176) (xy 308.616603 -377.11125) (xy 308.657827 -377.14697) (xy 308.693548 -377.188193)
			(xy 308.723038 -377.234081) (xy 308.745698 -377.283698) (xy 308.761066 -377.336035) (xy 308.768828 -377.390027)
			(xy 308.768828 -377.444567) (xy 313.949854 -377.444567) (xy 313.949854 -377.390033) (xy 313.957615 -377.336054)
			(xy 313.972979 -377.283729) (xy 313.995633 -377.234123) (xy 314.025117 -377.188246) (xy 314.060829 -377.147031)
			(xy 314.102042 -377.111319) (xy 314.147919 -377.081835) (xy 314.197525 -377.059181) (xy 314.24985 -377.043816)
			(xy 314.303829 -377.036055) (xy 314.331096 -377.035568) (xy 315.194696 -377.035568) (xy 315.221969 -377.035971)
			(xy 315.275961 -377.043734) (xy 315.328298 -377.059101) (xy 315.377916 -377.08176) (xy 315.423803 -377.11125)
			(xy 315.465027 -377.14697) (xy 315.500748 -377.188193) (xy 315.530238 -377.234081) (xy 315.552898 -377.283698)
			(xy 315.568266 -377.336035) (xy 315.576028 -377.390027) (xy 315.576028 -377.444567) (xy 320.757054 -377.444567)
			(xy 320.757054 -377.390033) (xy 320.764815 -377.336054) (xy 320.780179 -377.283729) (xy 320.802833 -377.234123)
			(xy 320.832317 -377.188246) (xy 320.868029 -377.147031) (xy 320.909242 -377.111319) (xy 320.955119 -377.081835)
			(xy 321.004725 -377.059181) (xy 321.05705 -377.043816) (xy 321.111029 -377.036055) (xy 321.138296 -377.035568)
			(xy 322.001896 -377.035568) (xy 322.029169 -377.035971) (xy 322.083161 -377.043734) (xy 322.135498 -377.059101)
			(xy 322.185116 -377.08176) (xy 322.231003 -377.11125) (xy 322.272227 -377.14697) (xy 322.307948 -377.188193)
			(xy 322.337438 -377.234081) (xy 322.360098 -377.283698) (xy 322.375466 -377.336035) (xy 322.383228 -377.390027)
			(xy 322.383228 -377.444567) (xy 324.160654 -377.444567) (xy 324.160654 -377.390033) (xy 324.168415 -377.336054)
			(xy 324.183779 -377.283729) (xy 324.206433 -377.234123) (xy 324.235917 -377.188246) (xy 324.271629 -377.147031)
			(xy 324.312842 -377.111319) (xy 324.358719 -377.081835) (xy 324.408325 -377.059181) (xy 324.46065 -377.043816)
			(xy 324.514629 -377.036055) (xy 324.541896 -377.035568) (xy 325.405496 -377.035568) (xy 325.432769 -377.035971)
			(xy 325.486761 -377.043734) (xy 325.539098 -377.059101) (xy 325.588716 -377.08176) (xy 325.634603 -377.11125)
			(xy 325.675827 -377.14697) (xy 325.711548 -377.188193) (xy 325.741038 -377.234081) (xy 325.763698 -377.283698)
			(xy 325.779066 -377.336035) (xy 325.786828 -377.390027) (xy 325.786828 -377.444571) (xy 332.863132 -377.444571)
			(xy 332.863132 -377.390029) (xy 332.870894 -377.336043) (xy 332.886261 -377.283711) (xy 332.908921 -377.234098)
			(xy 332.93841 -377.188216) (xy 332.974129 -377.146998) (xy 333.015351 -377.111284) (xy 333.061237 -377.081799)
			(xy 333.110852 -377.059146) (xy 333.163186 -377.043785) (xy 333.217173 -377.036028) (xy 333.244444 -377.035568)
			(xy 334.108044 -377.035568) (xy 334.135313 -377.035998) (xy 334.189297 -377.043765) (xy 334.241625 -377.059135)
			(xy 334.291233 -377.081796) (xy 334.337112 -377.111285) (xy 334.378328 -377.147003) (xy 334.414041 -377.188223)
			(xy 334.443525 -377.234105) (xy 334.46618 -377.283716) (xy 334.481544 -377.336047) (xy 334.489306 -377.39003)
			(xy 334.489306 -377.44457) (xy 334.489306 -377.444571) (xy 339.670332 -377.444571) (xy 339.670332 -377.390029)
			(xy 339.678094 -377.336043) (xy 339.693461 -377.283711) (xy 339.716121 -377.234098) (xy 339.74561 -377.188216)
			(xy 339.781329 -377.146998) (xy 339.822551 -377.111284) (xy 339.868437 -377.081799) (xy 339.918052 -377.059146)
			(xy 339.970386 -377.043785) (xy 340.024373 -377.036028) (xy 340.051644 -377.035568) (xy 340.915244 -377.035568)
			(xy 340.942513 -377.035998) (xy 340.996497 -377.043765) (xy 341.048825 -377.059135) (xy 341.098433 -377.081796)
			(xy 341.144312 -377.111285) (xy 341.185528 -377.147003) (xy 341.221241 -377.188223) (xy 341.250725 -377.234105)
			(xy 341.27338 -377.283716) (xy 341.288744 -377.336047) (xy 341.296506 -377.39003) (xy 341.296506 -377.44457)
			(xy 341.296506 -377.444571) (xy 346.477532 -377.444571) (xy 346.477532 -377.390029) (xy 346.485294 -377.336043)
			(xy 346.500661 -377.283711) (xy 346.523321 -377.234098) (xy 346.55281 -377.188216) (xy 346.588529 -377.146998)
			(xy 346.629751 -377.111284) (xy 346.675637 -377.081799) (xy 346.725252 -377.059146) (xy 346.777586 -377.043785)
			(xy 346.831573 -377.036028) (xy 346.858844 -377.035568) (xy 347.722444 -377.035568) (xy 347.749713 -377.035998)
			(xy 347.803697 -377.043765) (xy 347.856025 -377.059135) (xy 347.905633 -377.081796) (xy 347.951512 -377.111285)
			(xy 347.992728 -377.147003) (xy 348.028441 -377.188223) (xy 348.057925 -377.234105) (xy 348.08058 -377.283716)
			(xy 348.095944 -377.336047) (xy 348.103706 -377.39003) (xy 348.103706 -377.44457) (xy 348.103706 -377.444571)
			(xy 353.284732 -377.444571) (xy 353.284732 -377.390029) (xy 353.292494 -377.336043) (xy 353.307861 -377.283711)
			(xy 353.330521 -377.234098) (xy 353.36001 -377.188216) (xy 353.395729 -377.146998) (xy 353.436951 -377.111284)
			(xy 353.482837 -377.081799) (xy 353.532452 -377.059146) (xy 353.584786 -377.043785) (xy 353.638773 -377.036028)
			(xy 353.666044 -377.035568) (xy 354.529644 -377.035568) (xy 354.556913 -377.035998) (xy 354.610897 -377.043765)
			(xy 354.663225 -377.059135) (xy 354.712833 -377.081796) (xy 354.758712 -377.111285) (xy 354.799928 -377.147003)
			(xy 354.835641 -377.188223) (xy 354.865125 -377.234105) (xy 354.88778 -377.283716) (xy 354.903144 -377.336047)
			(xy 354.910906 -377.39003) (xy 354.910906 -377.44457) (xy 354.910906 -377.444571) (xy 356.688332 -377.444571)
			(xy 356.688332 -377.390029) (xy 356.696094 -377.336043) (xy 356.711461 -377.283711) (xy 356.734121 -377.234098)
			(xy 356.76361 -377.188216) (xy 356.799329 -377.146998) (xy 356.840551 -377.111284) (xy 356.886437 -377.081799)
			(xy 356.936052 -377.059146) (xy 356.988386 -377.043785) (xy 357.042373 -377.036028) (xy 357.069644 -377.035568)
			(xy 357.933244 -377.035568) (xy 357.960513 -377.035998) (xy 358.014497 -377.043765) (xy 358.066825 -377.059135)
			(xy 358.116433 -377.081796) (xy 358.162312 -377.111285) (xy 358.203528 -377.147003) (xy 358.239241 -377.188223)
			(xy 358.268725 -377.234105) (xy 358.29138 -377.283716) (xy 358.306744 -377.336047) (xy 358.314506 -377.39003)
			(xy 358.314506 -377.444567) (xy 367.435654 -377.444567) (xy 367.435654 -377.390033) (xy 367.443415 -377.336054)
			(xy 367.458779 -377.28373) (xy 367.481433 -377.234124) (xy 367.510916 -377.188247) (xy 367.546627 -377.147033)
			(xy 367.587841 -377.11132) (xy 367.633717 -377.081837) (xy 367.683322 -377.059182) (xy 367.735647 -377.043817)
			(xy 367.789625 -377.036055) (xy 367.816892 -377.035568) (xy 368.680492 -377.035568) (xy 368.707766 -377.035971)
			(xy 368.761757 -377.043733) (xy 368.814095 -377.0591) (xy 368.863713 -377.081759) (xy 368.909602 -377.111248)
			(xy 368.950826 -377.146968) (xy 368.986547 -377.188192) (xy 369.016038 -377.23408) (xy 369.038698 -377.283697)
			(xy 369.054065 -377.336035) (xy 369.061828 -377.390026) (xy 369.061828 -377.444567) (xy 374.242854 -377.444567)
			(xy 374.242854 -377.390033) (xy 374.250615 -377.336054) (xy 374.265979 -377.28373) (xy 374.288633 -377.234124)
			(xy 374.318116 -377.188247) (xy 374.353827 -377.147033) (xy 374.395041 -377.11132) (xy 374.440917 -377.081837)
			(xy 374.490522 -377.059182) (xy 374.542847 -377.043817) (xy 374.596825 -377.036055) (xy 374.624092 -377.035568)
			(xy 375.487692 -377.035568) (xy 375.514966 -377.035971) (xy 375.568957 -377.043733) (xy 375.621295 -377.0591)
			(xy 375.670913 -377.081759) (xy 375.716802 -377.111248) (xy 375.758026 -377.146968) (xy 375.793747 -377.188192)
			(xy 375.823238 -377.23408) (xy 375.845898 -377.283697) (xy 375.861265 -377.336035) (xy 375.869028 -377.390026)
			(xy 375.869028 -377.444567) (xy 381.050054 -377.444567) (xy 381.050054 -377.390033) (xy 381.057815 -377.336054)
			(xy 381.073179 -377.28373) (xy 381.095833 -377.234124) (xy 381.125316 -377.188247) (xy 381.161027 -377.147033)
			(xy 381.202241 -377.11132) (xy 381.248117 -377.081837) (xy 381.297722 -377.059182) (xy 381.350047 -377.043817)
			(xy 381.404025 -377.036055) (xy 381.431292 -377.035568) (xy 382.294892 -377.035568) (xy 382.322166 -377.035971)
			(xy 382.376157 -377.043733) (xy 382.428495 -377.0591) (xy 382.478113 -377.081759) (xy 382.524002 -377.111248)
			(xy 382.565226 -377.146968) (xy 382.600947 -377.188192) (xy 382.630438 -377.23408) (xy 382.653098 -377.283697)
			(xy 382.668465 -377.336035) (xy 382.676228 -377.390026) (xy 382.676228 -377.444567) (xy 387.857254 -377.444567)
			(xy 387.857254 -377.390033) (xy 387.865015 -377.336054) (xy 387.880379 -377.28373) (xy 387.903033 -377.234124)
			(xy 387.932516 -377.188247) (xy 387.968227 -377.147033) (xy 388.009441 -377.11132) (xy 388.055317 -377.081837)
			(xy 388.104922 -377.059182) (xy 388.157247 -377.043817) (xy 388.211225 -377.036055) (xy 388.238492 -377.035568)
			(xy 389.102092 -377.035568) (xy 389.129366 -377.035971) (xy 389.183357 -377.043733) (xy 389.235695 -377.0591)
			(xy 389.285313 -377.081759) (xy 389.331202 -377.111248) (xy 389.372426 -377.146968) (xy 389.408147 -377.188192)
			(xy 389.437638 -377.23408) (xy 389.460298 -377.283697) (xy 389.475665 -377.336035) (xy 389.483428 -377.390026)
			(xy 389.483428 -377.444567) (xy 391.260854 -377.444567) (xy 391.260854 -377.390033) (xy 391.268615 -377.336054)
			(xy 391.283979 -377.28373) (xy 391.306633 -377.234124) (xy 391.336116 -377.188247) (xy 391.371827 -377.147033)
			(xy 391.413041 -377.11132) (xy 391.458917 -377.081837) (xy 391.508522 -377.059182) (xy 391.560847 -377.043817)
			(xy 391.614825 -377.036055) (xy 391.642092 -377.035568) (xy 392.505692 -377.035568) (xy 392.532966 -377.035971)
			(xy 392.586957 -377.043733) (xy 392.639295 -377.0591) (xy 392.688913 -377.081759) (xy 392.734802 -377.111248)
			(xy 392.776026 -377.146968) (xy 392.811747 -377.188192) (xy 392.841238 -377.23408) (xy 392.863898 -377.283697)
			(xy 392.879265 -377.336035) (xy 392.887028 -377.390026) (xy 392.887028 -377.444571) (xy 399.963332 -377.444571)
			(xy 399.963332 -377.390029) (xy 399.971094 -377.336043) (xy 399.986461 -377.283711) (xy 400.00912 -377.234099)
			(xy 400.038609 -377.188217) (xy 400.074328 -377.147) (xy 400.11555 -377.111285) (xy 400.161435 -377.081801)
			(xy 400.211049 -377.059147) (xy 400.263382 -377.043786) (xy 400.317369 -377.036029) (xy 400.34464 -377.035568)
			(xy 401.20824 -377.035568) (xy 401.23551 -377.035997) (xy 401.289493 -377.043764) (xy 401.341822 -377.059134)
			(xy 401.391431 -377.081794) (xy 401.437311 -377.111284) (xy 401.478527 -377.147002) (xy 401.51424 -377.188222)
			(xy 401.543725 -377.234104) (xy 401.56638 -377.283716) (xy 401.581744 -377.336046) (xy 401.589506 -377.39003)
			(xy 401.589506 -377.44457) (xy 401.589506 -377.444571) (xy 406.770532 -377.444571) (xy 406.770532 -377.390029)
			(xy 406.778294 -377.336043) (xy 406.793661 -377.283711) (xy 406.81632 -377.234099) (xy 406.845809 -377.188217)
			(xy 406.881528 -377.147) (xy 406.92275 -377.111285) (xy 406.968635 -377.081801) (xy 407.018249 -377.059147)
			(xy 407.070582 -377.043786) (xy 407.124569 -377.036029) (xy 407.15184 -377.035568) (xy 408.01544 -377.035568)
			(xy 408.04271 -377.035997) (xy 408.096693 -377.043764) (xy 408.149022 -377.059134) (xy 408.198631 -377.081794)
			(xy 408.244511 -377.111284) (xy 408.285727 -377.147002) (xy 408.32144 -377.188222) (xy 408.350925 -377.234104)
			(xy 408.37358 -377.283716) (xy 408.388944 -377.336046) (xy 408.396706 -377.39003) (xy 408.396706 -377.44457)
			(xy 408.396706 -377.444571) (xy 413.577732 -377.444571) (xy 413.577732 -377.390029) (xy 413.585494 -377.336043)
			(xy 413.600861 -377.283711) (xy 413.62352 -377.234099) (xy 413.653009 -377.188217) (xy 413.688728 -377.147)
			(xy 413.72995 -377.111285) (xy 413.775835 -377.081801) (xy 413.825449 -377.059147) (xy 413.877782 -377.043786)
			(xy 413.931769 -377.036029) (xy 413.95904 -377.035568) (xy 414.82264 -377.035568) (xy 414.84991 -377.035997)
			(xy 414.903893 -377.043764) (xy 414.956222 -377.059134) (xy 415.005831 -377.081794) (xy 415.051711 -377.111284)
			(xy 415.092927 -377.147002) (xy 415.12864 -377.188222) (xy 415.158125 -377.234104) (xy 415.18078 -377.283716)
			(xy 415.196144 -377.336046) (xy 415.203906 -377.39003) (xy 415.203906 -377.44457) (xy 415.203906 -377.444571)
			(xy 420.384932 -377.444571) (xy 420.384932 -377.390029) (xy 420.392694 -377.336043) (xy 420.408061 -377.283711)
			(xy 420.43072 -377.234099) (xy 420.460209 -377.188217) (xy 420.495928 -377.147) (xy 420.53715 -377.111285)
			(xy 420.583035 -377.081801) (xy 420.632649 -377.059147) (xy 420.684982 -377.043786) (xy 420.738969 -377.036029)
			(xy 420.76624 -377.035568) (xy 421.62984 -377.035568) (xy 421.65711 -377.035997) (xy 421.711093 -377.043764)
			(xy 421.763422 -377.059134) (xy 421.813031 -377.081794) (xy 421.858911 -377.111284) (xy 421.900127 -377.147002)
			(xy 421.93584 -377.188222) (xy 421.965325 -377.234104) (xy 421.98798 -377.283716) (xy 422.003344 -377.336046)
			(xy 422.011106 -377.39003) (xy 422.011106 -377.44457) (xy 422.011106 -377.444571) (xy 423.788532 -377.444571)
			(xy 423.788532 -377.390029) (xy 423.796294 -377.336043) (xy 423.811661 -377.283711) (xy 423.83432 -377.234099)
			(xy 423.863809 -377.188217) (xy 423.899528 -377.147) (xy 423.94075 -377.111285) (xy 423.986635 -377.081801)
			(xy 424.036249 -377.059147) (xy 424.088582 -377.043786) (xy 424.142569 -377.036029) (xy 424.16984 -377.035568)
			(xy 425.03344 -377.035568) (xy 425.06071 -377.035997) (xy 425.114693 -377.043764) (xy 425.167022 -377.059134)
			(xy 425.216631 -377.081794) (xy 425.262511 -377.111284) (xy 425.303727 -377.147002) (xy 425.33944 -377.188222)
			(xy 425.368925 -377.234104) (xy 425.39158 -377.283716) (xy 425.406944 -377.336046) (xy 425.414706 -377.39003)
			(xy 425.414706 -377.44457) (xy 425.406944 -377.498554) (xy 425.39158 -377.550884) (xy 425.368925 -377.600496)
			(xy 425.33944 -377.646378) (xy 425.303727 -377.687598) (xy 425.262511 -377.723316) (xy 425.216631 -377.752806)
			(xy 425.167022 -377.775466) (xy 425.114693 -377.790836) (xy 425.06071 -377.798603) (xy 425.03344 -377.799092)
			(xy 424.16984 -377.799092) (xy 424.142569 -377.798571) (xy 424.088582 -377.790814) (xy 424.036249 -377.775453)
			(xy 423.986635 -377.752799) (xy 423.94075 -377.723315) (xy 423.899528 -377.6876) (xy 423.863809 -377.646383)
			(xy 423.83432 -377.600501) (xy 423.811661 -377.550889) (xy 423.796294 -377.498557) (xy 423.788532 -377.444571)
			(xy 422.011106 -377.444571) (xy 422.003344 -377.498554) (xy 421.98798 -377.550884) (xy 421.965325 -377.600496)
			(xy 421.93584 -377.646378) (xy 421.900127 -377.687598) (xy 421.858911 -377.723316) (xy 421.813031 -377.752806)
			(xy 421.763422 -377.775466) (xy 421.711093 -377.790836) (xy 421.65711 -377.798603) (xy 421.62984 -377.799092)
			(xy 420.76624 -377.799092) (xy 420.738969 -377.798571) (xy 420.684982 -377.790814) (xy 420.632649 -377.775453)
			(xy 420.583035 -377.752799) (xy 420.53715 -377.723315) (xy 420.495928 -377.6876) (xy 420.460209 -377.646383)
			(xy 420.43072 -377.600501) (xy 420.408061 -377.550889) (xy 420.392694 -377.498557) (xy 420.384932 -377.444571)
			(xy 415.203906 -377.444571) (xy 415.196144 -377.498554) (xy 415.18078 -377.550884) (xy 415.158125 -377.600496)
			(xy 415.12864 -377.646378) (xy 415.092927 -377.687598) (xy 415.051711 -377.723316) (xy 415.005831 -377.752806)
			(xy 414.956222 -377.775466) (xy 414.903893 -377.790836) (xy 414.84991 -377.798603) (xy 414.82264 -377.799092)
			(xy 413.95904 -377.799092) (xy 413.931769 -377.798571) (xy 413.877782 -377.790814) (xy 413.825449 -377.775453)
			(xy 413.775835 -377.752799) (xy 413.72995 -377.723315) (xy 413.688728 -377.6876) (xy 413.653009 -377.646383)
			(xy 413.62352 -377.600501) (xy 413.600861 -377.550889) (xy 413.585494 -377.498557) (xy 413.577732 -377.444571)
			(xy 408.396706 -377.444571) (xy 408.388944 -377.498554) (xy 408.37358 -377.550884) (xy 408.350925 -377.600496)
			(xy 408.32144 -377.646378) (xy 408.285727 -377.687598) (xy 408.244511 -377.723316) (xy 408.198631 -377.752806)
			(xy 408.149022 -377.775466) (xy 408.096693 -377.790836) (xy 408.04271 -377.798603) (xy 408.01544 -377.799092)
			(xy 407.15184 -377.799092) (xy 407.124569 -377.798571) (xy 407.070582 -377.790814) (xy 407.018249 -377.775453)
			(xy 406.968635 -377.752799) (xy 406.92275 -377.723315) (xy 406.881528 -377.6876) (xy 406.845809 -377.646383)
			(xy 406.81632 -377.600501) (xy 406.793661 -377.550889) (xy 406.778294 -377.498557) (xy 406.770532 -377.444571)
			(xy 401.589506 -377.444571) (xy 401.581744 -377.498554) (xy 401.56638 -377.550884) (xy 401.543725 -377.600496)
			(xy 401.51424 -377.646378) (xy 401.478527 -377.687598) (xy 401.437311 -377.723316) (xy 401.391431 -377.752806)
			(xy 401.341822 -377.775466) (xy 401.289493 -377.790836) (xy 401.23551 -377.798603) (xy 401.20824 -377.799092)
			(xy 400.34464 -377.799092) (xy 400.317369 -377.798571) (xy 400.263382 -377.790814) (xy 400.211049 -377.775453)
			(xy 400.161435 -377.752799) (xy 400.11555 -377.723315) (xy 400.074328 -377.6876) (xy 400.038609 -377.646383)
			(xy 400.00912 -377.600501) (xy 399.986461 -377.550889) (xy 399.971094 -377.498557) (xy 399.963332 -377.444571)
			(xy 392.887028 -377.444571) (xy 392.887028 -377.444574) (xy 392.879265 -377.498565) (xy 392.863898 -377.550903)
			(xy 392.841238 -377.60052) (xy 392.811747 -377.646408) (xy 392.776026 -377.687632) (xy 392.734802 -377.723352)
			(xy 392.688913 -377.752841) (xy 392.639295 -377.7755) (xy 392.586957 -377.790867) (xy 392.532966 -377.798629)
			(xy 392.505692 -377.799092) (xy 391.642092 -377.799092) (xy 391.614825 -377.798545) (xy 391.560847 -377.790783)
			(xy 391.508522 -377.775418) (xy 391.458917 -377.752763) (xy 391.413041 -377.72328) (xy 391.371827 -377.687567)
			(xy 391.336116 -377.646353) (xy 391.306633 -377.600476) (xy 391.283979 -377.55087) (xy 391.268615 -377.498546)
			(xy 391.260854 -377.444567) (xy 389.483428 -377.444567) (xy 389.483428 -377.444574) (xy 389.475665 -377.498565)
			(xy 389.460298 -377.550903) (xy 389.437638 -377.60052) (xy 389.408147 -377.646408) (xy 389.372426 -377.687632)
			(xy 389.331202 -377.723352) (xy 389.285313 -377.752841) (xy 389.235695 -377.7755) (xy 389.183357 -377.790867)
			(xy 389.129366 -377.798629) (xy 389.102092 -377.799092) (xy 388.238492 -377.799092) (xy 388.211225 -377.798545)
			(xy 388.157247 -377.790783) (xy 388.104922 -377.775418) (xy 388.055317 -377.752763) (xy 388.009441 -377.72328)
			(xy 387.968227 -377.687567) (xy 387.932516 -377.646353) (xy 387.903033 -377.600476) (xy 387.880379 -377.55087)
			(xy 387.865015 -377.498546) (xy 387.857254 -377.444567) (xy 382.676228 -377.444567) (xy 382.676228 -377.444574)
			(xy 382.668465 -377.498565) (xy 382.653098 -377.550903) (xy 382.630438 -377.60052) (xy 382.600947 -377.646408)
			(xy 382.565226 -377.687632) (xy 382.524002 -377.723352) (xy 382.478113 -377.752841) (xy 382.428495 -377.7755)
			(xy 382.376157 -377.790867) (xy 382.322166 -377.798629) (xy 382.294892 -377.799092) (xy 381.431292 -377.799092)
			(xy 381.404025 -377.798545) (xy 381.350047 -377.790783) (xy 381.297722 -377.775418) (xy 381.248117 -377.752763)
			(xy 381.202241 -377.72328) (xy 381.161027 -377.687567) (xy 381.125316 -377.646353) (xy 381.095833 -377.600476)
			(xy 381.073179 -377.55087) (xy 381.057815 -377.498546) (xy 381.050054 -377.444567) (xy 375.869028 -377.444567)
			(xy 375.869028 -377.444574) (xy 375.861265 -377.498565) (xy 375.845898 -377.550903) (xy 375.823238 -377.60052)
			(xy 375.793747 -377.646408) (xy 375.758026 -377.687632) (xy 375.716802 -377.723352) (xy 375.670913 -377.752841)
			(xy 375.621295 -377.7755) (xy 375.568957 -377.790867) (xy 375.514966 -377.798629) (xy 375.487692 -377.799092)
			(xy 374.624092 -377.799092) (xy 374.596825 -377.798545) (xy 374.542847 -377.790783) (xy 374.490522 -377.775418)
			(xy 374.440917 -377.752763) (xy 374.395041 -377.72328) (xy 374.353827 -377.687567) (xy 374.318116 -377.646353)
			(xy 374.288633 -377.600476) (xy 374.265979 -377.55087) (xy 374.250615 -377.498546) (xy 374.242854 -377.444567)
			(xy 369.061828 -377.444567) (xy 369.061828 -377.444574) (xy 369.054065 -377.498565) (xy 369.038698 -377.550903)
			(xy 369.016038 -377.60052) (xy 368.986547 -377.646408) (xy 368.950826 -377.687632) (xy 368.909602 -377.723352)
			(xy 368.863713 -377.752841) (xy 368.814095 -377.7755) (xy 368.761757 -377.790867) (xy 368.707766 -377.798629)
			(xy 368.680492 -377.799092) (xy 367.816892 -377.799092) (xy 367.789625 -377.798545) (xy 367.735647 -377.790783)
			(xy 367.683322 -377.775418) (xy 367.633717 -377.752763) (xy 367.587841 -377.72328) (xy 367.546627 -377.687567)
			(xy 367.510916 -377.646353) (xy 367.481433 -377.600476) (xy 367.458779 -377.55087) (xy 367.443415 -377.498546)
			(xy 367.435654 -377.444567) (xy 358.314506 -377.444567) (xy 358.314506 -377.44457) (xy 358.306744 -377.498553)
			(xy 358.29138 -377.550884) (xy 358.268725 -377.600495) (xy 358.239241 -377.646377) (xy 358.203528 -377.687597)
			(xy 358.162312 -377.723315) (xy 358.116433 -377.752804) (xy 358.066825 -377.775465) (xy 358.014497 -377.790835)
			(xy 357.960513 -377.798602) (xy 357.933244 -377.799092) (xy 357.069644 -377.799092) (xy 357.042373 -377.798572)
			(xy 356.988386 -377.790815) (xy 356.936052 -377.775454) (xy 356.886437 -377.752801) (xy 356.840551 -377.723316)
			(xy 356.799329 -377.687602) (xy 356.76361 -377.646384) (xy 356.734121 -377.600502) (xy 356.711461 -377.550889)
			(xy 356.696094 -377.498557) (xy 356.688332 -377.444571) (xy 354.910906 -377.444571) (xy 354.903144 -377.498553)
			(xy 354.88778 -377.550884) (xy 354.865125 -377.600495) (xy 354.835641 -377.646377) (xy 354.799928 -377.687597)
			(xy 354.758712 -377.723315) (xy 354.712833 -377.752804) (xy 354.663225 -377.775465) (xy 354.610897 -377.790835)
			(xy 354.556913 -377.798602) (xy 354.529644 -377.799092) (xy 353.666044 -377.799092) (xy 353.638773 -377.798572)
			(xy 353.584786 -377.790815) (xy 353.532452 -377.775454) (xy 353.482837 -377.752801) (xy 353.436951 -377.723316)
			(xy 353.395729 -377.687602) (xy 353.36001 -377.646384) (xy 353.330521 -377.600502) (xy 353.307861 -377.550889)
			(xy 353.292494 -377.498557) (xy 353.284732 -377.444571) (xy 348.103706 -377.444571) (xy 348.095944 -377.498553)
			(xy 348.08058 -377.550884) (xy 348.057925 -377.600495) (xy 348.028441 -377.646377) (xy 347.992728 -377.687597)
			(xy 347.951512 -377.723315) (xy 347.905633 -377.752804) (xy 347.856025 -377.775465) (xy 347.803697 -377.790835)
			(xy 347.749713 -377.798602) (xy 347.722444 -377.799092) (xy 346.858844 -377.799092) (xy 346.831573 -377.798572)
			(xy 346.777586 -377.790815) (xy 346.725252 -377.775454) (xy 346.675637 -377.752801) (xy 346.629751 -377.723316)
			(xy 346.588529 -377.687602) (xy 346.55281 -377.646384) (xy 346.523321 -377.600502) (xy 346.500661 -377.550889)
			(xy 346.485294 -377.498557) (xy 346.477532 -377.444571) (xy 341.296506 -377.444571) (xy 341.288744 -377.498553)
			(xy 341.27338 -377.550884) (xy 341.250725 -377.600495) (xy 341.221241 -377.646377) (xy 341.185528 -377.687597)
			(xy 341.144312 -377.723315) (xy 341.098433 -377.752804) (xy 341.048825 -377.775465) (xy 340.996497 -377.790835)
			(xy 340.942513 -377.798602) (xy 340.915244 -377.799092) (xy 340.051644 -377.799092) (xy 340.024373 -377.798572)
			(xy 339.970386 -377.790815) (xy 339.918052 -377.775454) (xy 339.868437 -377.752801) (xy 339.822551 -377.723316)
			(xy 339.781329 -377.687602) (xy 339.74561 -377.646384) (xy 339.716121 -377.600502) (xy 339.693461 -377.550889)
			(xy 339.678094 -377.498557) (xy 339.670332 -377.444571) (xy 334.489306 -377.444571) (xy 334.481544 -377.498553)
			(xy 334.46618 -377.550884) (xy 334.443525 -377.600495) (xy 334.414041 -377.646377) (xy 334.378328 -377.687597)
			(xy 334.337112 -377.723315) (xy 334.291233 -377.752804) (xy 334.241625 -377.775465) (xy 334.189297 -377.790835)
			(xy 334.135313 -377.798602) (xy 334.108044 -377.799092) (xy 333.244444 -377.799092) (xy 333.217173 -377.798572)
			(xy 333.163186 -377.790815) (xy 333.110852 -377.775454) (xy 333.061237 -377.752801) (xy 333.015351 -377.723316)
			(xy 332.974129 -377.687602) (xy 332.93841 -377.646384) (xy 332.908921 -377.600502) (xy 332.886261 -377.550889)
			(xy 332.870894 -377.498557) (xy 332.863132 -377.444571) (xy 325.786828 -377.444571) (xy 325.786828 -377.444573)
			(xy 325.779066 -377.498565) (xy 325.763698 -377.550902) (xy 325.741038 -377.600519) (xy 325.711548 -377.646407)
			(xy 325.675827 -377.68763) (xy 325.634603 -377.72335) (xy 325.588716 -377.75284) (xy 325.539098 -377.775499)
			(xy 325.486761 -377.790866) (xy 325.432769 -377.798629) (xy 325.405496 -377.799092) (xy 324.541896 -377.799092)
			(xy 324.514629 -377.798545) (xy 324.46065 -377.790784) (xy 324.408325 -377.775419) (xy 324.358719 -377.752765)
			(xy 324.312842 -377.723281) (xy 324.271629 -377.687569) (xy 324.235917 -377.646354) (xy 324.206433 -377.600477)
			(xy 324.183779 -377.550871) (xy 324.168415 -377.498546) (xy 324.160654 -377.444567) (xy 322.383228 -377.444567)
			(xy 322.383228 -377.444573) (xy 322.375466 -377.498565) (xy 322.360098 -377.550902) (xy 322.337438 -377.600519)
			(xy 322.307948 -377.646407) (xy 322.272227 -377.68763) (xy 322.231003 -377.72335) (xy 322.185116 -377.75284)
			(xy 322.135498 -377.775499) (xy 322.083161 -377.790866) (xy 322.029169 -377.798629) (xy 322.001896 -377.799092)
			(xy 321.138296 -377.799092) (xy 321.111029 -377.798545) (xy 321.05705 -377.790784) (xy 321.004725 -377.775419)
			(xy 320.955119 -377.752765) (xy 320.909242 -377.723281) (xy 320.868029 -377.687569) (xy 320.832317 -377.646354)
			(xy 320.802833 -377.600477) (xy 320.780179 -377.550871) (xy 320.764815 -377.498546) (xy 320.757054 -377.444567)
			(xy 315.576028 -377.444567) (xy 315.576028 -377.444573) (xy 315.568266 -377.498565) (xy 315.552898 -377.550902)
			(xy 315.530238 -377.600519) (xy 315.500748 -377.646407) (xy 315.465027 -377.68763) (xy 315.423803 -377.72335)
			(xy 315.377916 -377.75284) (xy 315.328298 -377.775499) (xy 315.275961 -377.790866) (xy 315.221969 -377.798629)
			(xy 315.194696 -377.799092) (xy 314.331096 -377.799092) (xy 314.303829 -377.798545) (xy 314.24985 -377.790784)
			(xy 314.197525 -377.775419) (xy 314.147919 -377.752765) (xy 314.102042 -377.723281) (xy 314.060829 -377.687569)
			(xy 314.025117 -377.646354) (xy 313.995633 -377.600477) (xy 313.972979 -377.550871) (xy 313.957615 -377.498546)
			(xy 313.949854 -377.444567) (xy 308.768828 -377.444567) (xy 308.768828 -377.444573) (xy 308.761066 -377.498565)
			(xy 308.745698 -377.550902) (xy 308.723038 -377.600519) (xy 308.693548 -377.646407) (xy 308.657827 -377.68763)
			(xy 308.616603 -377.72335) (xy 308.570716 -377.75284) (xy 308.521098 -377.775499) (xy 308.468761 -377.790866)
			(xy 308.414769 -377.798629) (xy 308.387496 -377.799092) (xy 307.523896 -377.799092) (xy 307.496629 -377.798545)
			(xy 307.44265 -377.790784) (xy 307.390325 -377.775419) (xy 307.340719 -377.752765) (xy 307.294842 -377.723281)
			(xy 307.253629 -377.687569) (xy 307.217917 -377.646354) (xy 307.188433 -377.600477) (xy 307.165779 -377.550871)
			(xy 307.150415 -377.498546) (xy 307.142654 -377.444567) (xy 301.961628 -377.444567) (xy 301.961628 -377.444573)
			(xy 301.953866 -377.498565) (xy 301.938498 -377.550902) (xy 301.915838 -377.600519) (xy 301.886348 -377.646407)
			(xy 301.850627 -377.68763) (xy 301.809403 -377.72335) (xy 301.763516 -377.75284) (xy 301.713898 -377.775499)
			(xy 301.661561 -377.790866) (xy 301.607569 -377.798629) (xy 301.580296 -377.799092) (xy 300.716696 -377.799092)
			(xy 300.689429 -377.798545) (xy 300.63545 -377.790784) (xy 300.583125 -377.775419) (xy 300.533519 -377.752765)
			(xy 300.487642 -377.723281) (xy 300.446429 -377.687569) (xy 300.410717 -377.646354) (xy 300.381233 -377.600477)
			(xy 300.358579 -377.550871) (xy 300.343215 -377.498546) (xy 300.335454 -377.444567) (xy 200.859958 -377.444567)
			(xy 200.882666 -377.460737) (xy 200.946694 -377.516218) (xy 201.005159 -377.577533) (xy 201.05753 -377.644129)
			(xy 201.103333 -377.715401) (xy 201.142155 -377.790704) (xy 201.173643 -377.869356) (xy 201.197511 -377.950646)
			(xy 201.213545 -378.033836) (xy 201.221598 -378.118173) (xy 201.222102 -378.160534) (xy 201.221598 -378.202895)
			(xy 201.213545 -378.287232) (xy 201.197511 -378.370422) (xy 201.173643 -378.451712) (xy 201.142155 -378.530364)
			(xy 201.103333 -378.605667) (xy 201.05753 -378.676939) (xy 201.005159 -378.743535) (xy 200.946694 -378.80485)
			(xy 200.882666 -378.860331) (xy 200.813654 -378.909474) (xy 200.740284 -378.951834) (xy 200.663219 -378.987029)
			(xy 200.583157 -379.014738) (xy 200.500824 -379.034712) (xy 200.416965 -379.046769) (xy 200.33234 -379.050801)
			(xy 200.247715 -379.046769) (xy 200.163856 -379.034712) (xy 200.081523 -379.014738) (xy 200.001461 -378.987029)
			(xy 199.924396 -378.951834) (xy 199.851026 -378.909474) (xy 199.782014 -378.860331) (xy 199.717986 -378.80485)
			(xy 199.659521 -378.743535) (xy 199.60715 -378.676939) (xy 199.561347 -378.605667) (xy 199.522525 -378.530364)
			(xy 199.491037 -378.451712) (xy 199.467169 -378.370422) (xy 199.451135 -378.287232) (xy 199.443082 -378.202895)
			(xy 195.47531 -378.202895) (xy 195.462625 -378.219025) (xy 195.40416 -378.28034) (xy 195.340132 -378.335821)
			(xy 195.27112 -378.384964) (xy 195.19775 -378.427324) (xy 195.120685 -378.462519) (xy 195.040623 -378.490228)
			(xy 194.95829 -378.510202) (xy 194.874431 -378.522259) (xy 194.789806 -378.526291) (xy 194.705181 -378.522259)
			(xy 194.621322 -378.510202) (xy 194.538989 -378.490228) (xy 194.458927 -378.462519) (xy 194.381862 -378.427324)
			(xy 194.308492 -378.384964) (xy 194.23948 -378.335821) (xy 194.175452 -378.28034) (xy 194.116987 -378.219025)
			(xy 194.064616 -378.152429) (xy 194.018813 -378.081157) (xy 193.979991 -378.005854) (xy 193.948503 -377.927202)
			(xy 193.924635 -377.845912) (xy 193.908601 -377.762722) (xy 193.900548 -377.678385) (xy 181.319901 -377.678385)
			(xy 181.279884 -377.802486) (xy 181.217663 -377.969563) (xy 181.148062 -378.133704) (xy 181.071217 -378.29458)
			(xy 180.987283 -378.451874) (xy 180.896425 -378.605273) (xy 180.798823 -378.754472) (xy 180.694672 -378.899175)
			(xy 180.584179 -379.039095) (xy 180.467562 -379.173954) (xy 180.345053 -379.303484) (xy 180.216896 -379.427428)
			(xy 180.083345 -379.54554) (xy 179.944665 -379.657585) (xy 179.801131 -379.763342) (xy 179.653028 -379.862599)
			(xy 179.577684 -379.908367) (xy 298.633654 -379.908367) (xy 298.633654 -379.853833) (xy 298.641415 -379.799854)
			(xy 298.656779 -379.747529) (xy 298.679433 -379.697923) (xy 298.708917 -379.652046) (xy 298.744629 -379.610831)
			(xy 298.785842 -379.575119) (xy 298.831719 -379.545635) (xy 298.881325 -379.522981) (xy 298.93365 -379.507616)
			(xy 298.987629 -379.499855) (xy 299.014896 -379.499368) (xy 299.878496 -379.499368) (xy 299.905769 -379.499771)
			(xy 299.959761 -379.507534) (xy 300.012098 -379.522901) (xy 300.061716 -379.54556) (xy 300.107603 -379.57505)
			(xy 300.148827 -379.61077) (xy 300.184548 -379.651993) (xy 300.214038 -379.697881) (xy 300.236698 -379.747498)
			(xy 300.252066 -379.799835) (xy 300.259828 -379.853827) (xy 300.259828 -379.908367) (xy 305.440854 -379.908367)
			(xy 305.440854 -379.853833) (xy 305.448615 -379.799854) (xy 305.463979 -379.747529) (xy 305.486633 -379.697923)
			(xy 305.516117 -379.652046) (xy 305.551829 -379.610831) (xy 305.593042 -379.575119) (xy 305.638919 -379.545635)
			(xy 305.688525 -379.522981) (xy 305.74085 -379.507616) (xy 305.794829 -379.499855) (xy 305.822096 -379.499368)
			(xy 306.685696 -379.499368) (xy 306.712969 -379.499771) (xy 306.766961 -379.507534) (xy 306.819298 -379.522901)
			(xy 306.868916 -379.54556) (xy 306.914803 -379.57505) (xy 306.956027 -379.61077) (xy 306.991748 -379.651993)
			(xy 307.021238 -379.697881) (xy 307.043898 -379.747498) (xy 307.059266 -379.799835) (xy 307.067028 -379.853827)
			(xy 307.067028 -379.908367) (xy 312.248054 -379.908367) (xy 312.248054 -379.853833) (xy 312.255815 -379.799854)
			(xy 312.271179 -379.747529) (xy 312.293833 -379.697923) (xy 312.323317 -379.652046) (xy 312.359029 -379.610831)
			(xy 312.400242 -379.575119) (xy 312.446119 -379.545635) (xy 312.495725 -379.522981) (xy 312.54805 -379.507616)
			(xy 312.602029 -379.499855) (xy 312.629296 -379.499368) (xy 313.492896 -379.499368) (xy 313.520169 -379.499771)
			(xy 313.574161 -379.507534) (xy 313.626498 -379.522901) (xy 313.676116 -379.54556) (xy 313.722003 -379.57505)
			(xy 313.763227 -379.61077) (xy 313.798948 -379.651993) (xy 313.828438 -379.697881) (xy 313.851098 -379.747498)
			(xy 313.866466 -379.799835) (xy 313.874228 -379.853827) (xy 313.874228 -379.908367) (xy 319.055254 -379.908367)
			(xy 319.055254 -379.853833) (xy 319.063015 -379.799854) (xy 319.078379 -379.747529) (xy 319.101033 -379.697923)
			(xy 319.130517 -379.652046) (xy 319.166229 -379.610831) (xy 319.207442 -379.575119) (xy 319.253319 -379.545635)
			(xy 319.302925 -379.522981) (xy 319.35525 -379.507616) (xy 319.409229 -379.499855) (xy 319.436496 -379.499368)
			(xy 320.300096 -379.499368) (xy 320.327369 -379.499771) (xy 320.381361 -379.507534) (xy 320.433698 -379.522901)
			(xy 320.483316 -379.54556) (xy 320.529203 -379.57505) (xy 320.570427 -379.61077) (xy 320.606148 -379.651993)
			(xy 320.635638 -379.697881) (xy 320.658298 -379.747498) (xy 320.673666 -379.799835) (xy 320.681428 -379.853827)
			(xy 320.681428 -379.908371) (xy 331.161332 -379.908371) (xy 331.161332 -379.853829) (xy 331.169094 -379.799843)
			(xy 331.184461 -379.747511) (xy 331.207121 -379.697898) (xy 331.23661 -379.652016) (xy 331.272329 -379.610798)
			(xy 331.313551 -379.575084) (xy 331.359437 -379.545599) (xy 331.409052 -379.522946) (xy 331.461386 -379.507585)
			(xy 331.515373 -379.499828) (xy 331.542644 -379.499368) (xy 332.406244 -379.499368) (xy 332.433513 -379.499798)
			(xy 332.487497 -379.507565) (xy 332.539825 -379.522935) (xy 332.589433 -379.545596) (xy 332.635312 -379.575085)
			(xy 332.676528 -379.610803) (xy 332.712241 -379.652023) (xy 332.741725 -379.697905) (xy 332.76438 -379.747516)
			(xy 332.779744 -379.799847) (xy 332.787506 -379.85383) (xy 332.787506 -379.90837) (xy 332.787506 -379.908371)
			(xy 337.968532 -379.908371) (xy 337.968532 -379.853829) (xy 337.976294 -379.799843) (xy 337.991661 -379.747511)
			(xy 338.014321 -379.697898) (xy 338.04381 -379.652016) (xy 338.079529 -379.610798) (xy 338.120751 -379.575084)
			(xy 338.166637 -379.545599) (xy 338.216252 -379.522946) (xy 338.268586 -379.507585) (xy 338.322573 -379.499828)
			(xy 338.349844 -379.499368) (xy 339.213444 -379.499368) (xy 339.240713 -379.499798) (xy 339.294697 -379.507565)
			(xy 339.347025 -379.522935) (xy 339.396633 -379.545596) (xy 339.442512 -379.575085) (xy 339.483728 -379.610803)
			(xy 339.519441 -379.652023) (xy 339.548925 -379.697905) (xy 339.57158 -379.747516) (xy 339.586944 -379.799847)
			(xy 339.594706 -379.85383) (xy 339.594706 -379.90837) (xy 339.594706 -379.908371) (xy 344.775732 -379.908371)
			(xy 344.775732 -379.853829) (xy 344.783494 -379.799843) (xy 344.798861 -379.747511) (xy 344.821521 -379.697898)
			(xy 344.85101 -379.652016) (xy 344.886729 -379.610798) (xy 344.927951 -379.575084) (xy 344.973837 -379.545599)
			(xy 345.023452 -379.522946) (xy 345.075786 -379.507585) (xy 345.129773 -379.499828) (xy 345.157044 -379.499368)
			(xy 346.020644 -379.499368) (xy 346.047913 -379.499798) (xy 346.101897 -379.507565) (xy 346.154225 -379.522935)
			(xy 346.203833 -379.545596) (xy 346.249712 -379.575085) (xy 346.290928 -379.610803) (xy 346.326641 -379.652023)
			(xy 346.356125 -379.697905) (xy 346.37878 -379.747516) (xy 346.394144 -379.799847) (xy 346.401906 -379.85383)
			(xy 346.401906 -379.90837) (xy 346.401906 -379.908371) (xy 351.582932 -379.908371) (xy 351.582932 -379.853829)
			(xy 351.590694 -379.799843) (xy 351.606061 -379.747511) (xy 351.628721 -379.697898) (xy 351.65821 -379.652016)
			(xy 351.693929 -379.610798) (xy 351.735151 -379.575084) (xy 351.781037 -379.545599) (xy 351.830652 -379.522946)
			(xy 351.882986 -379.507585) (xy 351.936973 -379.499828) (xy 351.964244 -379.499368) (xy 352.827844 -379.499368)
			(xy 352.855113 -379.499798) (xy 352.909097 -379.507565) (xy 352.961425 -379.522935) (xy 353.011033 -379.545596)
			(xy 353.056912 -379.575085) (xy 353.098128 -379.610803) (xy 353.133841 -379.652023) (xy 353.163325 -379.697905)
			(xy 353.18598 -379.747516) (xy 353.201344 -379.799847) (xy 353.209106 -379.85383) (xy 353.209106 -379.908367)
			(xy 365.733854 -379.908367) (xy 365.733854 -379.853833) (xy 365.741615 -379.799854) (xy 365.756979 -379.74753)
			(xy 365.779633 -379.697924) (xy 365.809116 -379.652047) (xy 365.844827 -379.610833) (xy 365.886041 -379.57512)
			(xy 365.931917 -379.545637) (xy 365.981522 -379.522982) (xy 366.033847 -379.507617) (xy 366.087825 -379.499855)
			(xy 366.115092 -379.499368) (xy 366.978692 -379.499368) (xy 367.005966 -379.499771) (xy 367.059957 -379.507533)
			(xy 367.112295 -379.5229) (xy 367.161913 -379.545559) (xy 367.207802 -379.575048) (xy 367.249026 -379.610768)
			(xy 367.284747 -379.651992) (xy 367.314238 -379.69788) (xy 367.336898 -379.747497) (xy 367.352265 -379.799835)
			(xy 367.360028 -379.853826) (xy 367.360028 -379.908367) (xy 372.541054 -379.908367) (xy 372.541054 -379.853833)
			(xy 372.548815 -379.799854) (xy 372.564179 -379.74753) (xy 372.586833 -379.697924) (xy 372.616316 -379.652047)
			(xy 372.652027 -379.610833) (xy 372.693241 -379.57512) (xy 372.739117 -379.545637) (xy 372.788722 -379.522982)
			(xy 372.841047 -379.507617) (xy 372.895025 -379.499855) (xy 372.922292 -379.499368) (xy 373.785892 -379.499368)
			(xy 373.813166 -379.499771) (xy 373.867157 -379.507533) (xy 373.919495 -379.5229) (xy 373.969113 -379.545559)
			(xy 374.015002 -379.575048) (xy 374.056226 -379.610768) (xy 374.091947 -379.651992) (xy 374.121438 -379.69788)
			(xy 374.144098 -379.747497) (xy 374.159465 -379.799835) (xy 374.167228 -379.853826) (xy 374.167228 -379.908367)
			(xy 379.348254 -379.908367) (xy 379.348254 -379.853833) (xy 379.356015 -379.799854) (xy 379.371379 -379.74753)
			(xy 379.394033 -379.697924) (xy 379.423516 -379.652047) (xy 379.459227 -379.610833) (xy 379.500441 -379.57512)
			(xy 379.546317 -379.545637) (xy 379.595922 -379.522982) (xy 379.648247 -379.507617) (xy 379.702225 -379.499855)
			(xy 379.729492 -379.499368) (xy 380.593092 -379.499368) (xy 380.620366 -379.499771) (xy 380.674357 -379.507533)
			(xy 380.726695 -379.5229) (xy 380.776313 -379.545559) (xy 380.822202 -379.575048) (xy 380.863426 -379.610768)
			(xy 380.899147 -379.651992) (xy 380.928638 -379.69788) (xy 380.951298 -379.747497) (xy 380.966665 -379.799835)
			(xy 380.974428 -379.853826) (xy 380.974428 -379.908367) (xy 386.155454 -379.908367) (xy 386.155454 -379.853833)
			(xy 386.163215 -379.799854) (xy 386.178579 -379.74753) (xy 386.201233 -379.697924) (xy 386.230716 -379.652047)
			(xy 386.266427 -379.610833) (xy 386.307641 -379.57512) (xy 386.353517 -379.545637) (xy 386.403122 -379.522982)
			(xy 386.455447 -379.507617) (xy 386.509425 -379.499855) (xy 386.536692 -379.499368) (xy 387.400292 -379.499368)
			(xy 387.427566 -379.499771) (xy 387.481557 -379.507533) (xy 387.533895 -379.5229) (xy 387.583513 -379.545559)
			(xy 387.629402 -379.575048) (xy 387.670626 -379.610768) (xy 387.706347 -379.651992) (xy 387.735838 -379.69788)
			(xy 387.758498 -379.747497) (xy 387.773865 -379.799835) (xy 387.781628 -379.853826) (xy 387.781628 -379.908371)
			(xy 398.261532 -379.908371) (xy 398.261532 -379.853829) (xy 398.269294 -379.799843) (xy 398.284661 -379.747511)
			(xy 398.30732 -379.697899) (xy 398.336809 -379.652017) (xy 398.372528 -379.6108) (xy 398.41375 -379.575085)
			(xy 398.459635 -379.545601) (xy 398.509249 -379.522947) (xy 398.561582 -379.507586) (xy 398.615569 -379.499829)
			(xy 398.64284 -379.499368) (xy 399.50644 -379.499368) (xy 399.53371 -379.499797) (xy 399.587693 -379.507564)
			(xy 399.640022 -379.522934) (xy 399.689631 -379.545594) (xy 399.735511 -379.575084) (xy 399.776727 -379.610802)
			(xy 399.81244 -379.652022) (xy 399.841925 -379.697904) (xy 399.86458 -379.747516) (xy 399.879944 -379.799846)
			(xy 399.887706 -379.85383) (xy 399.887706 -379.90837) (xy 399.887706 -379.908371) (xy 405.068732 -379.908371)
			(xy 405.068732 -379.853829) (xy 405.076494 -379.799843) (xy 405.091861 -379.747511) (xy 405.11452 -379.697899)
			(xy 405.144009 -379.652017) (xy 405.179728 -379.6108) (xy 405.22095 -379.575085) (xy 405.266835 -379.545601)
			(xy 405.316449 -379.522947) (xy 405.368782 -379.507586) (xy 405.422769 -379.499829) (xy 405.45004 -379.499368)
			(xy 406.31364 -379.499368) (xy 406.34091 -379.499797) (xy 406.394893 -379.507564) (xy 406.447222 -379.522934)
			(xy 406.496831 -379.545594) (xy 406.542711 -379.575084) (xy 406.583927 -379.610802) (xy 406.61964 -379.652022)
			(xy 406.649125 -379.697904) (xy 406.67178 -379.747516) (xy 406.687144 -379.799846) (xy 406.694906 -379.85383)
			(xy 406.694906 -379.90837) (xy 406.694906 -379.908371) (xy 411.875932 -379.908371) (xy 411.875932 -379.853829)
			(xy 411.883694 -379.799843) (xy 411.899061 -379.747511) (xy 411.92172 -379.697899) (xy 411.951209 -379.652017)
			(xy 411.986928 -379.6108) (xy 412.02815 -379.575085) (xy 412.074035 -379.545601) (xy 412.123649 -379.522947)
			(xy 412.175982 -379.507586) (xy 412.229969 -379.499829) (xy 412.25724 -379.499368) (xy 413.12084 -379.499368)
			(xy 413.14811 -379.499797) (xy 413.202093 -379.507564) (xy 413.254422 -379.522934) (xy 413.304031 -379.545594)
			(xy 413.349911 -379.575084) (xy 413.391127 -379.610802) (xy 413.42684 -379.652022) (xy 413.456325 -379.697904)
			(xy 413.47898 -379.747516) (xy 413.494344 -379.799846) (xy 413.502106 -379.85383) (xy 413.502106 -379.90837)
			(xy 413.502106 -379.908371) (xy 418.683132 -379.908371) (xy 418.683132 -379.853829) (xy 418.690894 -379.799843)
			(xy 418.706261 -379.747511) (xy 418.72892 -379.697899) (xy 418.758409 -379.652017) (xy 418.794128 -379.6108)
			(xy 418.83535 -379.575085) (xy 418.881235 -379.545601) (xy 418.930849 -379.522947) (xy 418.983182 -379.507586)
			(xy 419.037169 -379.499829) (xy 419.06444 -379.499368) (xy 419.92804 -379.499368) (xy 419.95531 -379.499797)
			(xy 420.009293 -379.507564) (xy 420.061622 -379.522934) (xy 420.111231 -379.545594) (xy 420.157111 -379.575084)
			(xy 420.198327 -379.610802) (xy 420.23404 -379.652022) (xy 420.263525 -379.697904) (xy 420.28618 -379.747516)
			(xy 420.301544 -379.799846) (xy 420.309306 -379.85383) (xy 420.309306 -379.90837) (xy 420.301544 -379.962354)
			(xy 420.28618 -380.014684) (xy 420.263525 -380.064296) (xy 420.23404 -380.110178) (xy 420.198327 -380.151398)
			(xy 420.157111 -380.187116) (xy 420.111231 -380.216606) (xy 420.061622 -380.239266) (xy 420.009293 -380.254636)
			(xy 419.95531 -380.262403) (xy 419.92804 -380.262892) (xy 419.06444 -380.262892) (xy 419.037169 -380.262371)
			(xy 418.983182 -380.254614) (xy 418.930849 -380.239253) (xy 418.881235 -380.216599) (xy 418.83535 -380.187115)
			(xy 418.794128 -380.1514) (xy 418.758409 -380.110183) (xy 418.72892 -380.064301) (xy 418.706261 -380.014689)
			(xy 418.690894 -379.962357) (xy 418.683132 -379.908371) (xy 413.502106 -379.908371) (xy 413.494344 -379.962354)
			(xy 413.47898 -380.014684) (xy 413.456325 -380.064296) (xy 413.42684 -380.110178) (xy 413.391127 -380.151398)
			(xy 413.349911 -380.187116) (xy 413.304031 -380.216606) (xy 413.254422 -380.239266) (xy 413.202093 -380.254636)
			(xy 413.14811 -380.262403) (xy 413.12084 -380.262892) (xy 412.25724 -380.262892) (xy 412.229969 -380.262371)
			(xy 412.175982 -380.254614) (xy 412.123649 -380.239253) (xy 412.074035 -380.216599) (xy 412.02815 -380.187115)
			(xy 411.986928 -380.1514) (xy 411.951209 -380.110183) (xy 411.92172 -380.064301) (xy 411.899061 -380.014689)
			(xy 411.883694 -379.962357) (xy 411.875932 -379.908371) (xy 406.694906 -379.908371) (xy 406.687144 -379.962354)
			(xy 406.67178 -380.014684) (xy 406.649125 -380.064296) (xy 406.61964 -380.110178) (xy 406.583927 -380.151398)
			(xy 406.542711 -380.187116) (xy 406.496831 -380.216606) (xy 406.447222 -380.239266) (xy 406.394893 -380.254636)
			(xy 406.34091 -380.262403) (xy 406.31364 -380.262892) (xy 405.45004 -380.262892) (xy 405.422769 -380.262371)
			(xy 405.368782 -380.254614) (xy 405.316449 -380.239253) (xy 405.266835 -380.216599) (xy 405.22095 -380.187115)
			(xy 405.179728 -380.1514) (xy 405.144009 -380.110183) (xy 405.11452 -380.064301) (xy 405.091861 -380.014689)
			(xy 405.076494 -379.962357) (xy 405.068732 -379.908371) (xy 399.887706 -379.908371) (xy 399.879944 -379.962354)
			(xy 399.86458 -380.014684) (xy 399.841925 -380.064296) (xy 399.81244 -380.110178) (xy 399.776727 -380.151398)
			(xy 399.735511 -380.187116) (xy 399.689631 -380.216606) (xy 399.640022 -380.239266) (xy 399.587693 -380.254636)
			(xy 399.53371 -380.262403) (xy 399.50644 -380.262892) (xy 398.64284 -380.262892) (xy 398.615569 -380.262371)
			(xy 398.561582 -380.254614) (xy 398.509249 -380.239253) (xy 398.459635 -380.216599) (xy 398.41375 -380.187115)
			(xy 398.372528 -380.1514) (xy 398.336809 -380.110183) (xy 398.30732 -380.064301) (xy 398.284661 -380.014689)
			(xy 398.269294 -379.962357) (xy 398.261532 -379.908371) (xy 387.781628 -379.908371) (xy 387.781628 -379.908374)
			(xy 387.773865 -379.962365) (xy 387.758498 -380.014703) (xy 387.735838 -380.06432) (xy 387.706347 -380.110208)
			(xy 387.670626 -380.151432) (xy 387.629402 -380.187152) (xy 387.583513 -380.216641) (xy 387.533895 -380.2393)
			(xy 387.481557 -380.254667) (xy 387.427566 -380.262429) (xy 387.400292 -380.262892) (xy 386.536692 -380.262892)
			(xy 386.509425 -380.262345) (xy 386.455447 -380.254583) (xy 386.403122 -380.239218) (xy 386.353517 -380.216563)
			(xy 386.307641 -380.18708) (xy 386.266427 -380.151367) (xy 386.230716 -380.110153) (xy 386.201233 -380.064276)
			(xy 386.178579 -380.01467) (xy 386.163215 -379.962346) (xy 386.155454 -379.908367) (xy 380.974428 -379.908367)
			(xy 380.974428 -379.908374) (xy 380.966665 -379.962365) (xy 380.951298 -380.014703) (xy 380.928638 -380.06432)
			(xy 380.899147 -380.110208) (xy 380.863426 -380.151432) (xy 380.822202 -380.187152) (xy 380.776313 -380.216641)
			(xy 380.726695 -380.2393) (xy 380.674357 -380.254667) (xy 380.620366 -380.262429) (xy 380.593092 -380.262892)
			(xy 379.729492 -380.262892) (xy 379.702225 -380.262345) (xy 379.648247 -380.254583) (xy 379.595922 -380.239218)
			(xy 379.546317 -380.216563) (xy 379.500441 -380.18708) (xy 379.459227 -380.151367) (xy 379.423516 -380.110153)
			(xy 379.394033 -380.064276) (xy 379.371379 -380.01467) (xy 379.356015 -379.962346) (xy 379.348254 -379.908367)
			(xy 374.167228 -379.908367) (xy 374.167228 -379.908374) (xy 374.159465 -379.962365) (xy 374.144098 -380.014703)
			(xy 374.121438 -380.06432) (xy 374.091947 -380.110208) (xy 374.056226 -380.151432) (xy 374.015002 -380.187152)
			(xy 373.969113 -380.216641) (xy 373.919495 -380.2393) (xy 373.867157 -380.254667) (xy 373.813166 -380.262429)
			(xy 373.785892 -380.262892) (xy 372.922292 -380.262892) (xy 372.895025 -380.262345) (xy 372.841047 -380.254583)
			(xy 372.788722 -380.239218) (xy 372.739117 -380.216563) (xy 372.693241 -380.18708) (xy 372.652027 -380.151367)
			(xy 372.616316 -380.110153) (xy 372.586833 -380.064276) (xy 372.564179 -380.01467) (xy 372.548815 -379.962346)
			(xy 372.541054 -379.908367) (xy 367.360028 -379.908367) (xy 367.360028 -379.908374) (xy 367.352265 -379.962365)
			(xy 367.336898 -380.014703) (xy 367.314238 -380.06432) (xy 367.284747 -380.110208) (xy 367.249026 -380.151432)
			(xy 367.207802 -380.187152) (xy 367.161913 -380.216641) (xy 367.112295 -380.2393) (xy 367.059957 -380.254667)
			(xy 367.005966 -380.262429) (xy 366.978692 -380.262892) (xy 366.115092 -380.262892) (xy 366.087825 -380.262345)
			(xy 366.033847 -380.254583) (xy 365.981522 -380.239218) (xy 365.931917 -380.216563) (xy 365.886041 -380.18708)
			(xy 365.844827 -380.151367) (xy 365.809116 -380.110153) (xy 365.779633 -380.064276) (xy 365.756979 -380.01467)
			(xy 365.741615 -379.962346) (xy 365.733854 -379.908367) (xy 353.209106 -379.908367) (xy 353.209106 -379.90837)
			(xy 353.201344 -379.962353) (xy 353.18598 -380.014684) (xy 353.163325 -380.064295) (xy 353.133841 -380.110177)
			(xy 353.098128 -380.151397) (xy 353.056912 -380.187115) (xy 353.011033 -380.216604) (xy 352.961425 -380.239265)
			(xy 352.909097 -380.254635) (xy 352.855113 -380.262402) (xy 352.827844 -380.262892) (xy 351.964244 -380.262892)
			(xy 351.936973 -380.262372) (xy 351.882986 -380.254615) (xy 351.830652 -380.239254) (xy 351.781037 -380.216601)
			(xy 351.735151 -380.187116) (xy 351.693929 -380.151402) (xy 351.65821 -380.110184) (xy 351.628721 -380.064302)
			(xy 351.606061 -380.014689) (xy 351.590694 -379.962357) (xy 351.582932 -379.908371) (xy 346.401906 -379.908371)
			(xy 346.394144 -379.962353) (xy 346.37878 -380.014684) (xy 346.356125 -380.064295) (xy 346.326641 -380.110177)
			(xy 346.290928 -380.151397) (xy 346.249712 -380.187115) (xy 346.203833 -380.216604) (xy 346.154225 -380.239265)
			(xy 346.101897 -380.254635) (xy 346.047913 -380.262402) (xy 346.020644 -380.262892) (xy 345.157044 -380.262892)
			(xy 345.129773 -380.262372) (xy 345.075786 -380.254615) (xy 345.023452 -380.239254) (xy 344.973837 -380.216601)
			(xy 344.927951 -380.187116) (xy 344.886729 -380.151402) (xy 344.85101 -380.110184) (xy 344.821521 -380.064302)
			(xy 344.798861 -380.014689) (xy 344.783494 -379.962357) (xy 344.775732 -379.908371) (xy 339.594706 -379.908371)
			(xy 339.586944 -379.962353) (xy 339.57158 -380.014684) (xy 339.548925 -380.064295) (xy 339.519441 -380.110177)
			(xy 339.483728 -380.151397) (xy 339.442512 -380.187115) (xy 339.396633 -380.216604) (xy 339.347025 -380.239265)
			(xy 339.294697 -380.254635) (xy 339.240713 -380.262402) (xy 339.213444 -380.262892) (xy 338.349844 -380.262892)
			(xy 338.322573 -380.262372) (xy 338.268586 -380.254615) (xy 338.216252 -380.239254) (xy 338.166637 -380.216601)
			(xy 338.120751 -380.187116) (xy 338.079529 -380.151402) (xy 338.04381 -380.110184) (xy 338.014321 -380.064302)
			(xy 337.991661 -380.014689) (xy 337.976294 -379.962357) (xy 337.968532 -379.908371) (xy 332.787506 -379.908371)
			(xy 332.779744 -379.962353) (xy 332.76438 -380.014684) (xy 332.741725 -380.064295) (xy 332.712241 -380.110177)
			(xy 332.676528 -380.151397) (xy 332.635312 -380.187115) (xy 332.589433 -380.216604) (xy 332.539825 -380.239265)
			(xy 332.487497 -380.254635) (xy 332.433513 -380.262402) (xy 332.406244 -380.262892) (xy 331.542644 -380.262892)
			(xy 331.515373 -380.262372) (xy 331.461386 -380.254615) (xy 331.409052 -380.239254) (xy 331.359437 -380.216601)
			(xy 331.313551 -380.187116) (xy 331.272329 -380.151402) (xy 331.23661 -380.110184) (xy 331.207121 -380.064302)
			(xy 331.184461 -380.014689) (xy 331.169094 -379.962357) (xy 331.161332 -379.908371) (xy 320.681428 -379.908371)
			(xy 320.681428 -379.908373) (xy 320.673666 -379.962365) (xy 320.658298 -380.014702) (xy 320.635638 -380.064319)
			(xy 320.606148 -380.110207) (xy 320.570427 -380.15143) (xy 320.529203 -380.18715) (xy 320.483316 -380.21664)
			(xy 320.433698 -380.239299) (xy 320.381361 -380.254666) (xy 320.327369 -380.262429) (xy 320.300096 -380.262892)
			(xy 319.436496 -380.262892) (xy 319.409229 -380.262345) (xy 319.35525 -380.254584) (xy 319.302925 -380.239219)
			(xy 319.253319 -380.216565) (xy 319.207442 -380.187081) (xy 319.166229 -380.151369) (xy 319.130517 -380.110154)
			(xy 319.101033 -380.064277) (xy 319.078379 -380.014671) (xy 319.063015 -379.962346) (xy 319.055254 -379.908367)
			(xy 313.874228 -379.908367) (xy 313.874228 -379.908373) (xy 313.866466 -379.962365) (xy 313.851098 -380.014702)
			(xy 313.828438 -380.064319) (xy 313.798948 -380.110207) (xy 313.763227 -380.15143) (xy 313.722003 -380.18715)
			(xy 313.676116 -380.21664) (xy 313.626498 -380.239299) (xy 313.574161 -380.254666) (xy 313.520169 -380.262429)
			(xy 313.492896 -380.262892) (xy 312.629296 -380.262892) (xy 312.602029 -380.262345) (xy 312.54805 -380.254584)
			(xy 312.495725 -380.239219) (xy 312.446119 -380.216565) (xy 312.400242 -380.187081) (xy 312.359029 -380.151369)
			(xy 312.323317 -380.110154) (xy 312.293833 -380.064277) (xy 312.271179 -380.014671) (xy 312.255815 -379.962346)
			(xy 312.248054 -379.908367) (xy 307.067028 -379.908367) (xy 307.067028 -379.908373) (xy 307.059266 -379.962365)
			(xy 307.043898 -380.014702) (xy 307.021238 -380.064319) (xy 306.991748 -380.110207) (xy 306.956027 -380.15143)
			(xy 306.914803 -380.18715) (xy 306.868916 -380.21664) (xy 306.819298 -380.239299) (xy 306.766961 -380.254666)
			(xy 306.712969 -380.262429) (xy 306.685696 -380.262892) (xy 305.822096 -380.262892) (xy 305.794829 -380.262345)
			(xy 305.74085 -380.254584) (xy 305.688525 -380.239219) (xy 305.638919 -380.216565) (xy 305.593042 -380.187081)
			(xy 305.551829 -380.151369) (xy 305.516117 -380.110154) (xy 305.486633 -380.064277) (xy 305.463979 -380.014671)
			(xy 305.448615 -379.962346) (xy 305.440854 -379.908367) (xy 300.259828 -379.908367) (xy 300.259828 -379.908373)
			(xy 300.252066 -379.962365) (xy 300.236698 -380.014702) (xy 300.214038 -380.064319) (xy 300.184548 -380.110207)
			(xy 300.148827 -380.15143) (xy 300.107603 -380.18715) (xy 300.061716 -380.21664) (xy 300.012098 -380.239299)
			(xy 299.959761 -380.254666) (xy 299.905769 -380.262429) (xy 299.878496 -380.262892) (xy 299.014896 -380.262892)
			(xy 298.987629 -380.262345) (xy 298.93365 -380.254584) (xy 298.881325 -380.239219) (xy 298.831719 -380.216565)
			(xy 298.785842 -380.187081) (xy 298.744629 -380.151369) (xy 298.708917 -380.110154) (xy 298.679433 -380.064277)
			(xy 298.656779 -380.014671) (xy 298.641415 -379.962346) (xy 298.633654 -379.908367) (xy 179.577684 -379.908367)
			(xy 179.500651 -379.955161) (xy 179.344302 -380.040842) (xy 179.184291 -380.119474) (xy 179.020937 -380.1909)
			(xy 178.854562 -380.254978) (xy 178.685499 -380.31158) (xy 178.514082 -380.360596) (xy 178.340651 -380.401926)
			(xy 178.165551 -380.43549) (xy 177.989131 -380.46122) (xy 177.811739 -380.479066) (xy 177.633728 -380.488992)
			(xy 177.455451 -380.490978) (xy 177.277264 -380.485021) (xy 177.099518 -380.471131) (xy 176.922568 -380.449338)
			(xy 176.746764 -380.419684) (xy 176.572456 -380.382227) (xy 176.399989 -380.337043) (xy 176.229706 -380.284221)
			(xy 176.061945 -380.223865) (xy 175.89704 -380.156097) (xy 175.735317 -380.081049) (xy 175.577098 -379.998872)
			(xy 175.422697 -379.909729) (xy 175.27242 -379.813795) (xy 175.126565 -379.711263) (xy 174.985423 -379.602335)
			(xy 174.849274 -379.487228) (xy 174.718387 -379.36617) (xy 174.593023 -379.239401) (xy 174.47343 -379.107174)
			(xy 174.359847 -378.969751) (xy 174.252498 -378.827404) (xy 174.151597 -378.680416) (xy 174.057344 -378.52908)
			(xy 173.969926 -378.373695) (xy 173.889516 -378.21457) (xy 173.816275 -378.052021) (xy 173.750348 -377.886371)
			(xy 173.691865 -377.717949) (xy 173.640943 -377.547088) (xy 173.597683 -377.374129) (xy 173.562171 -377.199414)
			(xy 173.534477 -377.02329) (xy 173.514656 -376.846108) (xy 173.502748 -376.668219) (xy 173.498776 -376.489976)
			(xy 171.286932 -376.489976) (xy 171.286932 -376.956828) (xy 171.286446 -376.984079) (xy 171.27869 -377.038027)
			(xy 171.263335 -377.090322) (xy 171.240693 -377.139899) (xy 171.211227 -377.185749) (xy 171.175536 -377.22694)
			(xy 171.134345 -377.262631) (xy 171.088495 -377.292097) (xy 171.038918 -377.314739) (xy 170.986623 -377.330094)
			(xy 170.932675 -377.33785) (xy 170.878173 -377.33785) (xy 170.824225 -377.330094) (xy 170.77193 -377.314739)
			(xy 170.722353 -377.292097) (xy 170.676503 -377.262631) (xy 170.635312 -377.22694) (xy 170.599621 -377.185749)
			(xy 170.570155 -377.139899) (xy 170.547513 -377.090322) (xy 170.532158 -377.038027) (xy 170.524402 -376.984079)
			(xy 170.523916 -376.956828) (xy 141.418806 -376.956828) (xy 141.416303 -376.965354) (xy 141.393661 -377.014931)
			(xy 141.364195 -377.060781) (xy 141.328504 -377.101972) (xy 141.287313 -377.137663) (xy 141.241463 -377.167129)
			(xy 141.191886 -377.189771) (xy 141.139591 -377.205126) (xy 141.085643 -377.212882) (xy 141.031141 -377.212882)
			(xy 140.977193 -377.205126) (xy 140.924898 -377.189771) (xy 140.875321 -377.167129) (xy 140.829471 -377.137663)
			(xy 140.78828 -377.101972) (xy 140.752589 -377.060781) (xy 140.723123 -377.014931) (xy 140.700481 -376.965354)
			(xy 140.685126 -376.913059) (xy 140.67737 -376.859111) (xy 140.676884 -376.83186) (xy 138.759184 -376.83186)
			(xy 138.759184 -376.956828) (xy 138.758698 -376.984079) (xy 138.750942 -377.038027) (xy 138.735587 -377.090322)
			(xy 138.712945 -377.139899) (xy 138.683479 -377.185749) (xy 138.647788 -377.22694) (xy 138.606597 -377.262631)
			(xy 138.560747 -377.292097) (xy 138.51117 -377.314739) (xy 138.458875 -377.330094) (xy 138.404927 -377.33785)
			(xy 138.350425 -377.33785) (xy 138.296477 -377.330094) (xy 138.244182 -377.314739) (xy 138.194605 -377.292097)
			(xy 138.148755 -377.262631) (xy 138.107564 -377.22694) (xy 138.071873 -377.185749) (xy 138.042407 -377.139899)
			(xy 138.019765 -377.090322) (xy 138.00441 -377.038027) (xy 137.996654 -376.984079) (xy 137.996168 -376.956828)
			(xy 108.891058 -376.956828) (xy 108.888555 -376.965354) (xy 108.865913 -377.014931) (xy 108.836447 -377.060781)
			(xy 108.800756 -377.101972) (xy 108.759565 -377.137663) (xy 108.713715 -377.167129) (xy 108.664138 -377.189771)
			(xy 108.611843 -377.205126) (xy 108.557895 -377.212882) (xy 108.503393 -377.212882) (xy 108.449445 -377.205126)
			(xy 108.39715 -377.189771) (xy 108.347573 -377.167129) (xy 108.301723 -377.137663) (xy 108.260532 -377.101972)
			(xy 108.224841 -377.060781) (xy 108.195375 -377.014931) (xy 108.172733 -376.965354) (xy 108.157378 -376.913059)
			(xy 108.149622 -376.859111) (xy 108.149136 -376.83186) (xy 104.187244 -376.83186) (xy 104.187244 -376.956828)
			(xy 104.186758 -376.984097) (xy 104.178996 -377.038081) (xy 104.163631 -377.090411) (xy 104.140974 -377.140021)
			(xy 104.111488 -377.185902) (xy 104.075773 -377.227119) (xy 104.034556 -377.262834) (xy 103.988675 -377.29232)
			(xy 103.939065 -377.314977) (xy 103.886735 -377.330342) (xy 103.832751 -377.338104) (xy 103.778213 -377.338104)
			(xy 103.724229 -377.330342) (xy 103.671899 -377.314977) (xy 103.622289 -377.29232) (xy 103.576408 -377.262834)
			(xy 103.535191 -377.227119) (xy 103.499476 -377.185902) (xy 103.46999 -377.140021) (xy 103.447333 -377.090411)
			(xy 103.431968 -377.038081) (xy 103.424206 -376.984097) (xy 103.42372 -376.956828) (xy 74.319129 -376.956828)
			(xy 74.316599 -376.965443) (xy 74.293942 -377.015053) (xy 74.264456 -377.060934) (xy 74.228741 -377.102151)
			(xy 74.187524 -377.137866) (xy 74.141643 -377.167352) (xy 74.092033 -377.190009) (xy 74.039703 -377.205374)
			(xy 73.985719 -377.213136) (xy 73.931181 -377.213136) (xy 73.877197 -377.205374) (xy 73.824867 -377.190009)
			(xy 73.775257 -377.167352) (xy 73.729376 -377.137866) (xy 73.688159 -377.102151) (xy 73.652444 -377.060934)
			(xy 73.622958 -377.015053) (xy 73.600301 -376.965443) (xy 73.584936 -376.913113) (xy 73.577174 -376.859129)
			(xy 73.576688 -376.83186) (xy 71.659496 -376.83186) (xy 71.659496 -376.956828) (xy 71.65901 -376.984097)
			(xy 71.651248 -377.038081) (xy 71.635883 -377.090411) (xy 71.613226 -377.140021) (xy 71.58374 -377.185902)
			(xy 71.548025 -377.227119) (xy 71.506808 -377.262834) (xy 71.460927 -377.29232) (xy 71.411317 -377.314977)
			(xy 71.358987 -377.330342) (xy 71.305003 -377.338104) (xy 71.250465 -377.338104) (xy 71.196481 -377.330342)
			(xy 71.144151 -377.314977) (xy 71.094541 -377.29232) (xy 71.04866 -377.262834) (xy 71.007443 -377.227119)
			(xy 70.971728 -377.185902) (xy 70.942242 -377.140021) (xy 70.919585 -377.090411) (xy 70.90422 -377.038081)
			(xy 70.896458 -376.984097) (xy 70.895972 -376.956828) (xy 41.791381 -376.956828) (xy 41.788851 -376.965443)
			(xy 41.766194 -377.015053) (xy 41.736708 -377.060934) (xy 41.700993 -377.102151) (xy 41.659776 -377.137866)
			(xy 41.613895 -377.167352) (xy 41.564285 -377.190009) (xy 41.511955 -377.205374) (xy 41.457971 -377.213136)
			(xy 41.403433 -377.213136) (xy 41.349449 -377.205374) (xy 41.297119 -377.190009) (xy 41.247509 -377.167352)
			(xy 41.201628 -377.137866) (xy 41.160411 -377.102151) (xy 41.124696 -377.060934) (xy 41.09521 -377.015053)
			(xy 41.072553 -376.965443) (xy 41.057188 -376.913113) (xy 41.049426 -376.859129) (xy 41.04894 -376.83186)
			(xy 39.05568 -376.83186) (xy 39.046481 -376.93481) (xy 39.022717 -377.111506) (xy 38.991106 -377.286969)
			(xy 38.95171 -377.460849) (xy 38.904608 -377.632802) (xy 38.849892 -377.802486) (xy 38.787671 -377.969563)
			(xy 38.71807 -378.133704) (xy 38.641225 -378.29458) (xy 38.557291 -378.451874) (xy 38.466433 -378.605273)
			(xy 38.368831 -378.754472) (xy 38.26468 -378.899175) (xy 38.154187 -379.039095) (xy 38.03757 -379.173954)
			(xy 37.915061 -379.303484) (xy 37.786904 -379.427428) (xy 37.653353 -379.54554) (xy 37.514673 -379.657585)
			(xy 37.371139 -379.763342) (xy 37.223036 -379.862599) (xy 37.070659 -379.955161) (xy 36.91431 -380.040842)
			(xy 36.754299 -380.119474) (xy 36.590945 -380.1909) (xy 36.42457 -380.254978) (xy 36.255507 -380.31158)
			(xy 36.084678 -380.360428) (xy 70.895972 -380.360428) (xy 70.895972 -379.496828) (xy 70.896458 -379.469559)
			(xy 70.90422 -379.415575) (xy 70.919585 -379.363245) (xy 70.942242 -379.313635) (xy 70.971728 -379.267754)
			(xy 71.007443 -379.226537) (xy 71.04866 -379.190822) (xy 71.094541 -379.161336) (xy 71.144151 -379.138679)
			(xy 71.196481 -379.123314) (xy 71.250465 -379.115552) (xy 71.305003 -379.115552) (xy 71.358987 -379.123314)
			(xy 71.411317 -379.138679) (xy 71.460927 -379.161336) (xy 71.506808 -379.190822) (xy 71.548025 -379.226537)
			(xy 71.58374 -379.267754) (xy 71.613226 -379.313635) (xy 71.635883 -379.363245) (xy 71.651248 -379.415575)
			(xy 71.65901 -379.469559) (xy 71.659496 -379.496828) (xy 71.659496 -380.360428) (xy 103.42372 -380.360428)
			(xy 103.42372 -379.496828) (xy 103.424206 -379.469559) (xy 103.431968 -379.415575) (xy 103.447333 -379.363245)
			(xy 103.46999 -379.313635) (xy 103.499476 -379.267754) (xy 103.535191 -379.226537) (xy 103.576408 -379.190822)
			(xy 103.622289 -379.161336) (xy 103.671899 -379.138679) (xy 103.724229 -379.123314) (xy 103.778213 -379.115552)
			(xy 103.832751 -379.115552) (xy 103.886735 -379.123314) (xy 103.939065 -379.138679) (xy 103.988675 -379.161336)
			(xy 104.034556 -379.190822) (xy 104.075773 -379.226537) (xy 104.111488 -379.267754) (xy 104.140974 -379.313635)
			(xy 104.163631 -379.363245) (xy 104.178996 -379.415575) (xy 104.186758 -379.469559) (xy 104.187244 -379.496828)
			(xy 104.187244 -380.360428) (xy 137.996168 -380.360428) (xy 137.996168 -379.496828) (xy 137.996654 -379.469577)
			(xy 138.00441 -379.415629) (xy 138.019765 -379.363334) (xy 138.042407 -379.313757) (xy 138.071873 -379.267907)
			(xy 138.107564 -379.226716) (xy 138.148755 -379.191025) (xy 138.194605 -379.161559) (xy 138.244182 -379.138917)
			(xy 138.296477 -379.123562) (xy 138.350425 -379.115806) (xy 138.404927 -379.115806) (xy 138.458875 -379.123562)
			(xy 138.51117 -379.138917) (xy 138.560747 -379.161559) (xy 138.606597 -379.191025) (xy 138.647788 -379.226716)
			(xy 138.683479 -379.267907) (xy 138.712945 -379.313757) (xy 138.735587 -379.363334) (xy 138.750942 -379.415629)
			(xy 138.758698 -379.469577) (xy 138.759184 -379.496828) (xy 138.759184 -380.360428) (xy 170.523916 -380.360428)
			(xy 170.523916 -379.496828) (xy 170.524402 -379.469577) (xy 170.532158 -379.415629) (xy 170.547513 -379.363334)
			(xy 170.570155 -379.313757) (xy 170.599621 -379.267907) (xy 170.635312 -379.226716) (xy 170.676503 -379.191025)
			(xy 170.722353 -379.161559) (xy 170.77193 -379.138917) (xy 170.824225 -379.123562) (xy 170.878173 -379.115806)
			(xy 170.932675 -379.115806) (xy 170.986623 -379.123562) (xy 171.038918 -379.138917) (xy 171.088495 -379.161559)
			(xy 171.134345 -379.191025) (xy 171.175536 -379.226716) (xy 171.211227 -379.267907) (xy 171.240693 -379.313757)
			(xy 171.263335 -379.363334) (xy 171.27869 -379.415629) (xy 171.286446 -379.469577) (xy 171.286932 -379.496828)
			(xy 171.286932 -380.360428) (xy 171.286446 -380.387679) (xy 171.27869 -380.441627) (xy 171.263335 -380.493922)
			(xy 171.240693 -380.543499) (xy 171.211227 -380.589349) (xy 171.175536 -380.63054) (xy 171.134345 -380.666231)
			(xy 171.088495 -380.695697) (xy 171.038918 -380.718339) (xy 170.986623 -380.733694) (xy 170.932675 -380.74145)
			(xy 170.878173 -380.74145) (xy 170.824225 -380.733694) (xy 170.77193 -380.718339) (xy 170.722353 -380.695697)
			(xy 170.676503 -380.666231) (xy 170.635312 -380.63054) (xy 170.599621 -380.589349) (xy 170.570155 -380.543499)
			(xy 170.547513 -380.493922) (xy 170.532158 -380.441627) (xy 170.524402 -380.387679) (xy 170.523916 -380.360428)
			(xy 138.759184 -380.360428) (xy 138.758698 -380.387679) (xy 138.750942 -380.441627) (xy 138.735587 -380.493922)
			(xy 138.712945 -380.543499) (xy 138.683479 -380.589349) (xy 138.647788 -380.63054) (xy 138.606597 -380.666231)
			(xy 138.560747 -380.695697) (xy 138.51117 -380.718339) (xy 138.458875 -380.733694) (xy 138.404927 -380.74145)
			(xy 138.350425 -380.74145) (xy 138.296477 -380.733694) (xy 138.244182 -380.718339) (xy 138.194605 -380.695697)
			(xy 138.148755 -380.666231) (xy 138.107564 -380.63054) (xy 138.071873 -380.589349) (xy 138.042407 -380.543499)
			(xy 138.019765 -380.493922) (xy 138.00441 -380.441627) (xy 137.996654 -380.387679) (xy 137.996168 -380.360428)
			(xy 104.187244 -380.360428) (xy 104.186758 -380.387697) (xy 104.178996 -380.441681) (xy 104.163631 -380.494011)
			(xy 104.140974 -380.543621) (xy 104.111488 -380.589502) (xy 104.075773 -380.630719) (xy 104.034556 -380.666434)
			(xy 103.988675 -380.69592) (xy 103.939065 -380.718577) (xy 103.886735 -380.733942) (xy 103.832751 -380.741704)
			(xy 103.778213 -380.741704) (xy 103.724229 -380.733942) (xy 103.671899 -380.718577) (xy 103.622289 -380.69592)
			(xy 103.576408 -380.666434) (xy 103.535191 -380.630719) (xy 103.499476 -380.589502) (xy 103.46999 -380.543621)
			(xy 103.447333 -380.494011) (xy 103.431968 -380.441681) (xy 103.424206 -380.387697) (xy 103.42372 -380.360428)
			(xy 71.659496 -380.360428) (xy 71.65901 -380.387697) (xy 71.651248 -380.441681) (xy 71.635883 -380.494011)
			(xy 71.613226 -380.543621) (xy 71.58374 -380.589502) (xy 71.548025 -380.630719) (xy 71.506808 -380.666434)
			(xy 71.460927 -380.69592) (xy 71.411317 -380.718577) (xy 71.358987 -380.733942) (xy 71.305003 -380.741704)
			(xy 71.250465 -380.741704) (xy 71.196481 -380.733942) (xy 71.144151 -380.718577) (xy 71.094541 -380.69592)
			(xy 71.04866 -380.666434) (xy 71.007443 -380.630719) (xy 70.971728 -380.589502) (xy 70.942242 -380.543621)
			(xy 70.919585 -380.494011) (xy 70.90422 -380.441681) (xy 70.896458 -380.387697) (xy 70.895972 -380.360428)
			(xy 36.084678 -380.360428) (xy 36.08409 -380.360596) (xy 35.910659 -380.401926) (xy 35.735559 -380.43549)
			(xy 35.559139 -380.46122) (xy 35.381747 -380.479066) (xy 35.203736 -380.488992) (xy 35.025459 -380.490978)
			(xy 34.847272 -380.485021) (xy 34.669526 -380.471131) (xy 34.492576 -380.449338) (xy 34.316772 -380.419684)
			(xy 34.142464 -380.382227) (xy 33.969997 -380.337043) (xy 33.799714 -380.284221) (xy 33.631953 -380.223865)
			(xy 33.467048 -380.156097) (xy 33.305325 -380.081049) (xy 33.147106 -379.998872) (xy 32.992705 -379.909729)
			(xy 32.842428 -379.813795) (xy 32.696573 -379.711263) (xy 32.555431 -379.602335) (xy 32.419282 -379.487228)
			(xy 32.288395 -379.36617) (xy 32.163031 -379.239401) (xy 32.043438 -379.107174) (xy 31.929855 -378.969751)
			(xy 31.822506 -378.827404) (xy 31.721605 -378.680416) (xy 31.627352 -378.52908) (xy 31.539934 -378.373695)
			(xy 31.459524 -378.21457) (xy 31.386283 -378.052021) (xy 31.320356 -377.886371) (xy 31.261873 -377.717949)
			(xy 31.210951 -377.547088) (xy 31.167691 -377.374129) (xy 31.132179 -377.199414) (xy 31.104485 -377.02329)
			(xy 31.084664 -376.846108) (xy 31.072756 -376.668219) (xy 31.068784 -376.489976) (xy 2.509012 -376.489976)
			(xy 2.509012 -382.36906) (xy 41.04894 -382.36906) (xy 41.04894 -381.50546) (xy 41.049426 -381.478191)
			(xy 41.057188 -381.424207) (xy 41.072553 -381.371877) (xy 41.09521 -381.322267) (xy 41.124696 -381.276386)
			(xy 41.160411 -381.235169) (xy 41.201628 -381.199454) (xy 41.247509 -381.169968) (xy 41.297119 -381.147311)
			(xy 41.349449 -381.131946) (xy 41.403433 -381.124184) (xy 41.457971 -381.124184) (xy 41.511955 -381.131946)
			(xy 41.564285 -381.147311) (xy 41.613895 -381.169968) (xy 41.659776 -381.199454) (xy 41.700993 -381.235169)
			(xy 41.736708 -381.276386) (xy 41.766194 -381.322267) (xy 41.788851 -381.371877) (xy 41.804216 -381.424207)
			(xy 41.811978 -381.478191) (xy 41.812464 -381.50546) (xy 41.812464 -382.36906) (xy 73.576688 -382.36906)
			(xy 73.576688 -381.50546) (xy 73.577174 -381.478191) (xy 73.584936 -381.424207) (xy 73.600301 -381.371877)
			(xy 73.622958 -381.322267) (xy 73.652444 -381.276386) (xy 73.688159 -381.235169) (xy 73.729376 -381.199454)
			(xy 73.775257 -381.169968) (xy 73.824867 -381.147311) (xy 73.877197 -381.131946) (xy 73.931181 -381.124184)
			(xy 73.985719 -381.124184) (xy 74.039703 -381.131946) (xy 74.092033 -381.147311) (xy 74.141643 -381.169968)
			(xy 74.187524 -381.199454) (xy 74.228741 -381.235169) (xy 74.264456 -381.276386) (xy 74.293942 -381.322267)
			(xy 74.316599 -381.371877) (xy 74.331964 -381.424207) (xy 74.339726 -381.478191) (xy 74.340212 -381.50546)
			(xy 74.340212 -382.36906) (xy 108.149136 -382.36906) (xy 108.149136 -381.50546) (xy 108.149622 -381.478209)
			(xy 108.157378 -381.424261) (xy 108.172733 -381.371966) (xy 108.195375 -381.322389) (xy 108.224841 -381.276539)
			(xy 108.260532 -381.235348) (xy 108.301723 -381.199657) (xy 108.347573 -381.170191) (xy 108.39715 -381.147549)
			(xy 108.449445 -381.132194) (xy 108.503393 -381.124438) (xy 108.557895 -381.124438) (xy 108.611843 -381.132194)
			(xy 108.664138 -381.147549) (xy 108.713715 -381.170191) (xy 108.759565 -381.199657) (xy 108.800756 -381.235348)
			(xy 108.836447 -381.276539) (xy 108.865913 -381.322389) (xy 108.888555 -381.371966) (xy 108.90391 -381.424261)
			(xy 108.911666 -381.478209) (xy 108.912152 -381.50546) (xy 108.912152 -382.36906) (xy 140.676884 -382.36906)
			(xy 140.676884 -381.50546) (xy 140.67737 -381.478209) (xy 140.685126 -381.424261) (xy 140.700481 -381.371966)
			(xy 140.723123 -381.322389) (xy 140.752589 -381.276539) (xy 140.78828 -381.235348) (xy 140.829471 -381.199657)
			(xy 140.875321 -381.170191) (xy 140.924898 -381.147549) (xy 140.977193 -381.132194) (xy 141.031141 -381.124438)
			(xy 141.085643 -381.124438) (xy 141.139591 -381.132194) (xy 141.191886 -381.147549) (xy 141.241463 -381.170191)
			(xy 141.287313 -381.199657) (xy 141.328504 -381.235348) (xy 141.364195 -381.276539) (xy 141.393661 -381.322389)
			(xy 141.416303 -381.371966) (xy 141.431658 -381.424261) (xy 141.439414 -381.478209) (xy 141.4399 -381.50546)
			(xy 141.4399 -382.36906) (xy 141.439414 -382.396311) (xy 141.431658 -382.450259) (xy 141.416303 -382.502554)
			(xy 141.393661 -382.552131) (xy 141.364195 -382.597981) (xy 141.328504 -382.639172) (xy 141.287313 -382.674863)
			(xy 141.241463 -382.704329) (xy 141.191886 -382.726971) (xy 141.139591 -382.742326) (xy 141.085643 -382.750082)
			(xy 141.031141 -382.750082) (xy 140.977193 -382.742326) (xy 140.924898 -382.726971) (xy 140.875321 -382.704329)
			(xy 140.829471 -382.674863) (xy 140.78828 -382.639172) (xy 140.752589 -382.597981) (xy 140.723123 -382.552131)
			(xy 140.700481 -382.502554) (xy 140.685126 -382.450259) (xy 140.67737 -382.396311) (xy 140.676884 -382.36906)
			(xy 108.912152 -382.36906) (xy 108.911666 -382.396311) (xy 108.90391 -382.450259) (xy 108.888555 -382.502554)
			(xy 108.865913 -382.552131) (xy 108.836447 -382.597981) (xy 108.800756 -382.639172) (xy 108.759565 -382.674863)
			(xy 108.713715 -382.704329) (xy 108.664138 -382.726971) (xy 108.611843 -382.742326) (xy 108.557895 -382.750082)
			(xy 108.503393 -382.750082) (xy 108.449445 -382.742326) (xy 108.39715 -382.726971) (xy 108.347573 -382.704329)
			(xy 108.301723 -382.674863) (xy 108.260532 -382.639172) (xy 108.224841 -382.597981) (xy 108.195375 -382.552131)
			(xy 108.172733 -382.502554) (xy 108.157378 -382.450259) (xy 108.149622 -382.396311) (xy 108.149136 -382.36906)
			(xy 74.340212 -382.36906) (xy 74.339726 -382.396329) (xy 74.331964 -382.450313) (xy 74.316599 -382.502643)
			(xy 74.293942 -382.552253) (xy 74.264456 -382.598134) (xy 74.228741 -382.639351) (xy 74.187524 -382.675066)
			(xy 74.141643 -382.704552) (xy 74.092033 -382.727209) (xy 74.039703 -382.742574) (xy 73.985719 -382.750336)
			(xy 73.931181 -382.750336) (xy 73.877197 -382.742574) (xy 73.824867 -382.727209) (xy 73.775257 -382.704552)
			(xy 73.729376 -382.675066) (xy 73.688159 -382.639351) (xy 73.652444 -382.598134) (xy 73.622958 -382.552253)
			(xy 73.600301 -382.502643) (xy 73.584936 -382.450313) (xy 73.577174 -382.396329) (xy 73.576688 -382.36906)
			(xy 41.812464 -382.36906) (xy 41.811978 -382.396329) (xy 41.804216 -382.450313) (xy 41.788851 -382.502643)
			(xy 41.766194 -382.552253) (xy 41.736708 -382.598134) (xy 41.700993 -382.639351) (xy 41.659776 -382.675066)
			(xy 41.613895 -382.704552) (xy 41.564285 -382.727209) (xy 41.511955 -382.742574) (xy 41.457971 -382.750336)
			(xy 41.403433 -382.750336) (xy 41.349449 -382.742574) (xy 41.297119 -382.727209) (xy 41.247509 -382.704552)
			(xy 41.201628 -382.675066) (xy 41.160411 -382.639351) (xy 41.124696 -382.598134) (xy 41.09521 -382.552253)
			(xy 41.072553 -382.502643) (xy 41.057188 -382.450313) (xy 41.049426 -382.396329) (xy 41.04894 -382.36906)
			(xy 2.509012 -382.36906) (xy 2.509012 -384.869944) (xy 287.06878 -384.869944) (xy 287.072752 -384.691701)
			(xy 287.08466 -384.513812) (xy 287.104481 -384.33663) (xy 287.132175 -384.160506) (xy 287.167687 -383.985791)
			(xy 287.210947 -383.812832) (xy 287.261869 -383.641971) (xy 287.320352 -383.473549) (xy 287.386279 -383.307899)
			(xy 287.45952 -383.14535) (xy 287.53993 -382.986225) (xy 287.627348 -382.83084) (xy 287.721601 -382.679504)
			(xy 287.822502 -382.532516) (xy 287.929851 -382.390169) (xy 288.043434 -382.252746) (xy 288.163027 -382.120519)
			(xy 288.288391 -381.99375) (xy 288.419278 -381.872692) (xy 288.555427 -381.757585) (xy 288.696569 -381.648657)
			(xy 288.842424 -381.546125) (xy 288.992701 -381.450191) (xy 289.147102 -381.361048) (xy 289.305321 -381.278871)
			(xy 289.467044 -381.203823) (xy 289.631949 -381.136055) (xy 289.79971 -381.075699) (xy 289.969993 -381.022877)
			(xy 290.14246 -380.977693) (xy 290.316768 -380.940236) (xy 290.492572 -380.910582) (xy 290.669522 -380.888789)
			(xy 290.847268 -380.874899) (xy 291.025455 -380.868942) (xy 291.203732 -380.870928) (xy 291.381743 -380.880854)
			(xy 291.559135 -380.8987) (xy 291.735555 -380.92443) (xy 291.910655 -380.957994) (xy 292.084086 -380.999324)
			(xy 292.255503 -381.04834) (xy 292.424566 -381.104942) (xy 292.590941 -381.16902) (xy 292.754295 -381.240446)
			(xy 292.914306 -381.319078) (xy 293.070655 -381.404759) (xy 293.223032 -381.497321) (xy 293.371135 -381.596578)
			(xy 293.514669 -381.702335) (xy 293.653349 -381.81438) (xy 293.7869 -381.932492) (xy 293.915057 -382.056436)
			(xy 294.037566 -382.185966) (xy 294.154183 -382.320825) (xy 294.194727 -382.372167) (xy 303.739054 -382.372167)
			(xy 303.739054 -382.317633) (xy 303.746815 -382.263654) (xy 303.762179 -382.211329) (xy 303.784833 -382.161723)
			(xy 303.814317 -382.115846) (xy 303.850029 -382.074631) (xy 303.891242 -382.038919) (xy 303.937119 -382.009435)
			(xy 303.986725 -381.986781) (xy 304.03905 -381.971416) (xy 304.093029 -381.963655) (xy 304.120296 -381.963168)
			(xy 304.983896 -381.963168) (xy 305.011169 -381.963571) (xy 305.065161 -381.971334) (xy 305.117498 -381.986701)
			(xy 305.167116 -382.00936) (xy 305.213003 -382.03885) (xy 305.254227 -382.07457) (xy 305.289948 -382.115793)
			(xy 305.319438 -382.161681) (xy 305.342098 -382.211298) (xy 305.357466 -382.263635) (xy 305.365228 -382.317627)
			(xy 305.365228 -382.372167) (xy 310.546254 -382.372167) (xy 310.546254 -382.317633) (xy 310.554015 -382.263654)
			(xy 310.569379 -382.211329) (xy 310.592033 -382.161723) (xy 310.621517 -382.115846) (xy 310.657229 -382.074631)
			(xy 310.698442 -382.038919) (xy 310.744319 -382.009435) (xy 310.793925 -381.986781) (xy 310.84625 -381.971416)
			(xy 310.900229 -381.963655) (xy 310.927496 -381.963168) (xy 311.791096 -381.963168) (xy 311.818369 -381.963571)
			(xy 311.872361 -381.971334) (xy 311.924698 -381.986701) (xy 311.974316 -382.00936) (xy 312.020203 -382.03885)
			(xy 312.061427 -382.07457) (xy 312.097148 -382.115793) (xy 312.126638 -382.161681) (xy 312.149298 -382.211298)
			(xy 312.164666 -382.263635) (xy 312.172428 -382.317627) (xy 312.172428 -382.372167) (xy 317.353454 -382.372167)
			(xy 317.353454 -382.317633) (xy 317.361215 -382.263654) (xy 317.376579 -382.211329) (xy 317.399233 -382.161723)
			(xy 317.428717 -382.115846) (xy 317.464429 -382.074631) (xy 317.505642 -382.038919) (xy 317.551519 -382.009435)
			(xy 317.601125 -381.986781) (xy 317.65345 -381.971416) (xy 317.707429 -381.963655) (xy 317.734696 -381.963168)
			(xy 318.598296 -381.963168) (xy 318.625569 -381.963571) (xy 318.679561 -381.971334) (xy 318.731898 -381.986701)
			(xy 318.781516 -382.00936) (xy 318.827403 -382.03885) (xy 318.868627 -382.07457) (xy 318.904348 -382.115793)
			(xy 318.933838 -382.161681) (xy 318.956498 -382.211298) (xy 318.971866 -382.263635) (xy 318.979628 -382.317627)
			(xy 318.979628 -382.372171) (xy 336.266732 -382.372171) (xy 336.266732 -382.317629) (xy 336.274494 -382.263643)
			(xy 336.289861 -382.211311) (xy 336.312521 -382.161698) (xy 336.34201 -382.115816) (xy 336.377729 -382.074598)
			(xy 336.418951 -382.038884) (xy 336.464837 -382.009399) (xy 336.514452 -381.986746) (xy 336.566786 -381.971385)
			(xy 336.620773 -381.963628) (xy 336.648044 -381.963168) (xy 337.511644 -381.963168) (xy 337.538913 -381.963598)
			(xy 337.592897 -381.971365) (xy 337.645225 -381.986735) (xy 337.694833 -382.009396) (xy 337.740712 -382.038885)
			(xy 337.781928 -382.074603) (xy 337.817641 -382.115823) (xy 337.847125 -382.161705) (xy 337.86978 -382.211316)
			(xy 337.885144 -382.263647) (xy 337.892906 -382.31763) (xy 337.892906 -382.37217) (xy 337.892906 -382.372171)
			(xy 343.073932 -382.372171) (xy 343.073932 -382.317629) (xy 343.081694 -382.263643) (xy 343.097061 -382.211311)
			(xy 343.119721 -382.161698) (xy 343.14921 -382.115816) (xy 343.184929 -382.074598) (xy 343.226151 -382.038884)
			(xy 343.272037 -382.009399) (xy 343.321652 -381.986746) (xy 343.373986 -381.971385) (xy 343.427973 -381.963628)
			(xy 343.455244 -381.963168) (xy 344.318844 -381.963168) (xy 344.346113 -381.963598) (xy 344.400097 -381.971365)
			(xy 344.452425 -381.986735) (xy 344.502033 -382.009396) (xy 344.547912 -382.038885) (xy 344.589128 -382.074603)
			(xy 344.624841 -382.115823) (xy 344.654325 -382.161705) (xy 344.67698 -382.211316) (xy 344.692344 -382.263647)
			(xy 344.700106 -382.31763) (xy 344.700106 -382.37217) (xy 344.700106 -382.372171) (xy 349.881132 -382.372171)
			(xy 349.881132 -382.317629) (xy 349.888894 -382.263643) (xy 349.904261 -382.211311) (xy 349.926921 -382.161698)
			(xy 349.95641 -382.115816) (xy 349.992129 -382.074598) (xy 350.033351 -382.038884) (xy 350.079237 -382.009399)
			(xy 350.128852 -381.986746) (xy 350.181186 -381.971385) (xy 350.235173 -381.963628) (xy 350.262444 -381.963168)
			(xy 351.126044 -381.963168) (xy 351.153313 -381.963598) (xy 351.207297 -381.971365) (xy 351.259625 -381.986735)
			(xy 351.309233 -382.009396) (xy 351.355112 -382.038885) (xy 351.396328 -382.074603) (xy 351.432041 -382.115823)
			(xy 351.461525 -382.161705) (xy 351.48418 -382.211316) (xy 351.499544 -382.263647) (xy 351.507306 -382.31763)
			(xy 351.507306 -382.372167) (xy 370.839254 -382.372167) (xy 370.839254 -382.317633) (xy 370.847015 -382.263654)
			(xy 370.862379 -382.21133) (xy 370.885033 -382.161724) (xy 370.914516 -382.115847) (xy 370.950227 -382.074633)
			(xy 370.991441 -382.03892) (xy 371.037317 -382.009437) (xy 371.086922 -381.986782) (xy 371.139247 -381.971417)
			(xy 371.193225 -381.963655) (xy 371.220492 -381.963168) (xy 372.084092 -381.963168) (xy 372.111366 -381.963571)
			(xy 372.165357 -381.971333) (xy 372.217695 -381.9867) (xy 372.267313 -382.009359) (xy 372.313202 -382.038848)
			(xy 372.354426 -382.074568) (xy 372.390147 -382.115792) (xy 372.419638 -382.16168) (xy 372.442298 -382.211297)
			(xy 372.457665 -382.263635) (xy 372.465428 -382.317626) (xy 372.465428 -382.372167) (xy 377.646454 -382.372167)
			(xy 377.646454 -382.317633) (xy 377.654215 -382.263654) (xy 377.669579 -382.21133) (xy 377.692233 -382.161724)
			(xy 377.721716 -382.115847) (xy 377.757427 -382.074633) (xy 377.798641 -382.03892) (xy 377.844517 -382.009437)
			(xy 377.894122 -381.986782) (xy 377.946447 -381.971417) (xy 378.000425 -381.963655) (xy 378.027692 -381.963168)
			(xy 378.891292 -381.963168) (xy 378.918566 -381.963571) (xy 378.972557 -381.971333) (xy 379.024895 -381.9867)
			(xy 379.074513 -382.009359) (xy 379.120402 -382.038848) (xy 379.161626 -382.074568) (xy 379.197347 -382.115792)
			(xy 379.226838 -382.16168) (xy 379.249498 -382.211297) (xy 379.264865 -382.263635) (xy 379.272628 -382.317626)
			(xy 379.272628 -382.372167) (xy 384.453654 -382.372167) (xy 384.453654 -382.317633) (xy 384.461415 -382.263654)
			(xy 384.476779 -382.21133) (xy 384.499433 -382.161724) (xy 384.528916 -382.115847) (xy 384.564627 -382.074633)
			(xy 384.605841 -382.03892) (xy 384.651717 -382.009437) (xy 384.701322 -381.986782) (xy 384.753647 -381.971417)
			(xy 384.807625 -381.963655) (xy 384.834892 -381.963168) (xy 385.698492 -381.963168) (xy 385.725766 -381.963571)
			(xy 385.779757 -381.971333) (xy 385.832095 -381.9867) (xy 385.881713 -382.009359) (xy 385.927602 -382.038848)
			(xy 385.968826 -382.074568) (xy 386.004547 -382.115792) (xy 386.034038 -382.16168) (xy 386.056698 -382.211297)
			(xy 386.072065 -382.263635) (xy 386.079828 -382.317626) (xy 386.079828 -382.372171) (xy 403.366932 -382.372171)
			(xy 403.366932 -382.317629) (xy 403.374694 -382.263643) (xy 403.390061 -382.211311) (xy 403.41272 -382.161699)
			(xy 403.442209 -382.115817) (xy 403.477928 -382.0746) (xy 403.51915 -382.038885) (xy 403.565035 -382.009401)
			(xy 403.614649 -381.986747) (xy 403.666982 -381.971386) (xy 403.720969 -381.963629) (xy 403.74824 -381.963168)
			(xy 404.61184 -381.963168) (xy 404.63911 -381.963597) (xy 404.693093 -381.971364) (xy 404.745422 -381.986734)
			(xy 404.795031 -382.009394) (xy 404.840911 -382.038884) (xy 404.882127 -382.074602) (xy 404.91784 -382.115822)
			(xy 404.947325 -382.161704) (xy 404.96998 -382.211316) (xy 404.985344 -382.263646) (xy 404.993106 -382.31763)
			(xy 404.993106 -382.37217) (xy 404.993106 -382.372171) (xy 410.174132 -382.372171) (xy 410.174132 -382.317629)
			(xy 410.181894 -382.263643) (xy 410.197261 -382.211311) (xy 410.21992 -382.161699) (xy 410.249409 -382.115817)
			(xy 410.285128 -382.0746) (xy 410.32635 -382.038885) (xy 410.372235 -382.009401) (xy 410.421849 -381.986747)
			(xy 410.474182 -381.971386) (xy 410.528169 -381.963629) (xy 410.55544 -381.963168) (xy 411.41904 -381.963168)
			(xy 411.44631 -381.963597) (xy 411.500293 -381.971364) (xy 411.552622 -381.986734) (xy 411.602231 -382.009394)
			(xy 411.648111 -382.038884) (xy 411.689327 -382.074602) (xy 411.72504 -382.115822) (xy 411.754525 -382.161704)
			(xy 411.77718 -382.211316) (xy 411.792544 -382.263646) (xy 411.800306 -382.31763) (xy 411.800306 -382.37217)
			(xy 411.800306 -382.372171) (xy 416.981332 -382.372171) (xy 416.981332 -382.317629) (xy 416.989094 -382.263643)
			(xy 417.004461 -382.211311) (xy 417.02712 -382.161699) (xy 417.056609 -382.115817) (xy 417.092328 -382.0746)
			(xy 417.13355 -382.038885) (xy 417.179435 -382.009401) (xy 417.229049 -381.986747) (xy 417.281382 -381.971386)
			(xy 417.335369 -381.963629) (xy 417.36264 -381.963168) (xy 418.22624 -381.963168) (xy 418.25351 -381.963597)
			(xy 418.307493 -381.971364) (xy 418.359822 -381.986734) (xy 418.409431 -382.009394) (xy 418.455311 -382.038884)
			(xy 418.496527 -382.074602) (xy 418.53224 -382.115822) (xy 418.561725 -382.161704) (xy 418.58438 -382.211316)
			(xy 418.599744 -382.263646) (xy 418.607506 -382.31763) (xy 418.607506 -382.37217) (xy 418.599744 -382.426154)
			(xy 418.58438 -382.478484) (xy 418.561725 -382.528096) (xy 418.53224 -382.573978) (xy 418.496527 -382.615198)
			(xy 418.455311 -382.650916) (xy 418.409431 -382.680406) (xy 418.359822 -382.703066) (xy 418.307493 -382.718436)
			(xy 418.25351 -382.726203) (xy 418.22624 -382.726692) (xy 417.36264 -382.726692) (xy 417.335369 -382.726171)
			(xy 417.281382 -382.718414) (xy 417.229049 -382.703053) (xy 417.179435 -382.680399) (xy 417.13355 -382.650915)
			(xy 417.092328 -382.6152) (xy 417.056609 -382.573983) (xy 417.02712 -382.528101) (xy 417.004461 -382.478489)
			(xy 416.989094 -382.426157) (xy 416.981332 -382.372171) (xy 411.800306 -382.372171) (xy 411.792544 -382.426154)
			(xy 411.77718 -382.478484) (xy 411.754525 -382.528096) (xy 411.72504 -382.573978) (xy 411.689327 -382.615198)
			(xy 411.648111 -382.650916) (xy 411.602231 -382.680406) (xy 411.552622 -382.703066) (xy 411.500293 -382.718436)
			(xy 411.44631 -382.726203) (xy 411.41904 -382.726692) (xy 410.55544 -382.726692) (xy 410.528169 -382.726171)
			(xy 410.474182 -382.718414) (xy 410.421849 -382.703053) (xy 410.372235 -382.680399) (xy 410.32635 -382.650915)
			(xy 410.285128 -382.6152) (xy 410.249409 -382.573983) (xy 410.21992 -382.528101) (xy 410.197261 -382.478489)
			(xy 410.181894 -382.426157) (xy 410.174132 -382.372171) (xy 404.993106 -382.372171) (xy 404.985344 -382.426154)
			(xy 404.96998 -382.478484) (xy 404.947325 -382.528096) (xy 404.91784 -382.573978) (xy 404.882127 -382.615198)
			(xy 404.840911 -382.650916) (xy 404.795031 -382.680406) (xy 404.745422 -382.703066) (xy 404.693093 -382.718436)
			(xy 404.63911 -382.726203) (xy 404.61184 -382.726692) (xy 403.74824 -382.726692) (xy 403.720969 -382.726171)
			(xy 403.666982 -382.718414) (xy 403.614649 -382.703053) (xy 403.565035 -382.680399) (xy 403.51915 -382.650915)
			(xy 403.477928 -382.6152) (xy 403.442209 -382.573983) (xy 403.41272 -382.528101) (xy 403.390061 -382.478489)
			(xy 403.374694 -382.426157) (xy 403.366932 -382.372171) (xy 386.079828 -382.372171) (xy 386.079828 -382.372174)
			(xy 386.072065 -382.426165) (xy 386.056698 -382.478503) (xy 386.034038 -382.52812) (xy 386.004547 -382.574008)
			(xy 385.968826 -382.615232) (xy 385.927602 -382.650952) (xy 385.881713 -382.680441) (xy 385.832095 -382.7031)
			(xy 385.779757 -382.718467) (xy 385.725766 -382.726229) (xy 385.698492 -382.726692) (xy 384.834892 -382.726692)
			(xy 384.807625 -382.726145) (xy 384.753647 -382.718383) (xy 384.701322 -382.703018) (xy 384.651717 -382.680363)
			(xy 384.605841 -382.65088) (xy 384.564627 -382.615167) (xy 384.528916 -382.573953) (xy 384.499433 -382.528076)
			(xy 384.476779 -382.47847) (xy 384.461415 -382.426146) (xy 384.453654 -382.372167) (xy 379.272628 -382.372167)
			(xy 379.272628 -382.372174) (xy 379.264865 -382.426165) (xy 379.249498 -382.478503) (xy 379.226838 -382.52812)
			(xy 379.197347 -382.574008) (xy 379.161626 -382.615232) (xy 379.120402 -382.650952) (xy 379.074513 -382.680441)
			(xy 379.024895 -382.7031) (xy 378.972557 -382.718467) (xy 378.918566 -382.726229) (xy 378.891292 -382.726692)
			(xy 378.027692 -382.726692) (xy 378.000425 -382.726145) (xy 377.946447 -382.718383) (xy 377.894122 -382.703018)
			(xy 377.844517 -382.680363) (xy 377.798641 -382.65088) (xy 377.757427 -382.615167) (xy 377.721716 -382.573953)
			(xy 377.692233 -382.528076) (xy 377.669579 -382.47847) (xy 377.654215 -382.426146) (xy 377.646454 -382.372167)
			(xy 372.465428 -382.372167) (xy 372.465428 -382.372174) (xy 372.457665 -382.426165) (xy 372.442298 -382.478503)
			(xy 372.419638 -382.52812) (xy 372.390147 -382.574008) (xy 372.354426 -382.615232) (xy 372.313202 -382.650952)
			(xy 372.267313 -382.680441) (xy 372.217695 -382.7031) (xy 372.165357 -382.718467) (xy 372.111366 -382.726229)
			(xy 372.084092 -382.726692) (xy 371.220492 -382.726692) (xy 371.193225 -382.726145) (xy 371.139247 -382.718383)
			(xy 371.086922 -382.703018) (xy 371.037317 -382.680363) (xy 370.991441 -382.65088) (xy 370.950227 -382.615167)
			(xy 370.914516 -382.573953) (xy 370.885033 -382.528076) (xy 370.862379 -382.47847) (xy 370.847015 -382.426146)
			(xy 370.839254 -382.372167) (xy 351.507306 -382.372167) (xy 351.507306 -382.37217) (xy 351.499544 -382.426153)
			(xy 351.48418 -382.478484) (xy 351.461525 -382.528095) (xy 351.432041 -382.573977) (xy 351.396328 -382.615197)
			(xy 351.355112 -382.650915) (xy 351.309233 -382.680404) (xy 351.259625 -382.703065) (xy 351.207297 -382.718435)
			(xy 351.153313 -382.726202) (xy 351.126044 -382.726692) (xy 350.262444 -382.726692) (xy 350.235173 -382.726172)
			(xy 350.181186 -382.718415) (xy 350.128852 -382.703054) (xy 350.079237 -382.680401) (xy 350.033351 -382.650916)
			(xy 349.992129 -382.615202) (xy 349.95641 -382.573984) (xy 349.926921 -382.528102) (xy 349.904261 -382.478489)
			(xy 349.888894 -382.426157) (xy 349.881132 -382.372171) (xy 344.700106 -382.372171) (xy 344.692344 -382.426153)
			(xy 344.67698 -382.478484) (xy 344.654325 -382.528095) (xy 344.624841 -382.573977) (xy 344.589128 -382.615197)
			(xy 344.547912 -382.650915) (xy 344.502033 -382.680404) (xy 344.452425 -382.703065) (xy 344.400097 -382.718435)
			(xy 344.346113 -382.726202) (xy 344.318844 -382.726692) (xy 343.455244 -382.726692) (xy 343.427973 -382.726172)
			(xy 343.373986 -382.718415) (xy 343.321652 -382.703054) (xy 343.272037 -382.680401) (xy 343.226151 -382.650916)
			(xy 343.184929 -382.615202) (xy 343.14921 -382.573984) (xy 343.119721 -382.528102) (xy 343.097061 -382.478489)
			(xy 343.081694 -382.426157) (xy 343.073932 -382.372171) (xy 337.892906 -382.372171) (xy 337.885144 -382.426153)
			(xy 337.86978 -382.478484) (xy 337.847125 -382.528095) (xy 337.817641 -382.573977) (xy 337.781928 -382.615197)
			(xy 337.740712 -382.650915) (xy 337.694833 -382.680404) (xy 337.645225 -382.703065) (xy 337.592897 -382.718435)
			(xy 337.538913 -382.726202) (xy 337.511644 -382.726692) (xy 336.648044 -382.726692) (xy 336.620773 -382.726172)
			(xy 336.566786 -382.718415) (xy 336.514452 -382.703054) (xy 336.464837 -382.680401) (xy 336.418951 -382.650916)
			(xy 336.377729 -382.615202) (xy 336.34201 -382.573984) (xy 336.312521 -382.528102) (xy 336.289861 -382.478489)
			(xy 336.274494 -382.426157) (xy 336.266732 -382.372171) (xy 318.979628 -382.372171) (xy 318.979628 -382.372173)
			(xy 318.971866 -382.426165) (xy 318.956498 -382.478502) (xy 318.933838 -382.528119) (xy 318.904348 -382.574007)
			(xy 318.868627 -382.61523) (xy 318.827403 -382.65095) (xy 318.781516 -382.68044) (xy 318.731898 -382.703099)
			(xy 318.679561 -382.718466) (xy 318.625569 -382.726229) (xy 318.598296 -382.726692) (xy 317.734696 -382.726692)
			(xy 317.707429 -382.726145) (xy 317.65345 -382.718384) (xy 317.601125 -382.703019) (xy 317.551519 -382.680365)
			(xy 317.505642 -382.650881) (xy 317.464429 -382.615169) (xy 317.428717 -382.573954) (xy 317.399233 -382.528077)
			(xy 317.376579 -382.478471) (xy 317.361215 -382.426146) (xy 317.353454 -382.372167) (xy 312.172428 -382.372167)
			(xy 312.172428 -382.372173) (xy 312.164666 -382.426165) (xy 312.149298 -382.478502) (xy 312.126638 -382.528119)
			(xy 312.097148 -382.574007) (xy 312.061427 -382.61523) (xy 312.020203 -382.65095) (xy 311.974316 -382.68044)
			(xy 311.924698 -382.703099) (xy 311.872361 -382.718466) (xy 311.818369 -382.726229) (xy 311.791096 -382.726692)
			(xy 310.927496 -382.726692) (xy 310.900229 -382.726145) (xy 310.84625 -382.718384) (xy 310.793925 -382.703019)
			(xy 310.744319 -382.680365) (xy 310.698442 -382.650881) (xy 310.657229 -382.615169) (xy 310.621517 -382.573954)
			(xy 310.592033 -382.528077) (xy 310.569379 -382.478471) (xy 310.554015 -382.426146) (xy 310.546254 -382.372167)
			(xy 305.365228 -382.372167) (xy 305.365228 -382.372173) (xy 305.357466 -382.426165) (xy 305.342098 -382.478502)
			(xy 305.319438 -382.528119) (xy 305.289948 -382.574007) (xy 305.254227 -382.61523) (xy 305.213003 -382.65095)
			(xy 305.167116 -382.68044) (xy 305.117498 -382.703099) (xy 305.065161 -382.718466) (xy 305.011169 -382.726229)
			(xy 304.983896 -382.726692) (xy 304.120296 -382.726692) (xy 304.093029 -382.726145) (xy 304.03905 -382.718384)
			(xy 303.986725 -382.703019) (xy 303.937119 -382.680365) (xy 303.891242 -382.650881) (xy 303.850029 -382.615169)
			(xy 303.814317 -382.573954) (xy 303.784833 -382.528077) (xy 303.762179 -382.478471) (xy 303.746815 -382.426146)
			(xy 303.739054 -382.372167) (xy 294.194727 -382.372167) (xy 294.264676 -382.460745) (xy 294.368827 -382.605448)
			(xy 294.466429 -382.754647) (xy 294.557287 -382.908046) (xy 294.641221 -383.06534) (xy 294.718066 -383.226216)
			(xy 294.787667 -383.390357) (xy 294.849888 -383.557434) (xy 294.904604 -383.727118) (xy 294.951706 -383.899071)
			(xy 294.991102 -384.072951) (xy 295.022713 -384.248414) (xy 295.046477 -384.42511) (xy 295.062345 -384.60269)
			(xy 295.070287 -384.7808) (xy 295.070784 -384.869944) (xy 295.070287 -384.959088) (xy 295.062345 -385.137198)
			(xy 295.055495 -385.21386) (xy 297.048936 -385.21386) (xy 297.048936 -384.35026) (xy 297.049422 -384.323009)
			(xy 297.057178 -384.269061) (xy 297.072533 -384.216766) (xy 297.095175 -384.167189) (xy 297.124641 -384.121339)
			(xy 297.160332 -384.080148) (xy 297.201523 -384.044457) (xy 297.247373 -384.014991) (xy 297.29695 -383.992349)
			(xy 297.349245 -383.976994) (xy 297.403193 -383.969238) (xy 297.457695 -383.969238) (xy 297.511643 -383.976994)
			(xy 297.563938 -383.992349) (xy 297.613515 -384.014991) (xy 297.659365 -384.044457) (xy 297.700556 -384.080148)
			(xy 297.736247 -384.121339) (xy 297.765713 -384.167189) (xy 297.788355 -384.216766) (xy 297.80371 -384.269061)
			(xy 297.811466 -384.323009) (xy 297.811952 -384.35026) (xy 297.811952 -385.21386) (xy 297.811466 -385.241111)
			(xy 297.80371 -385.295059) (xy 297.790858 -385.338828) (xy 326.895968 -385.338828) (xy 326.895968 -384.475228)
			(xy 326.896454 -384.447977) (xy 326.90421 -384.394029) (xy 326.919565 -384.341734) (xy 326.942207 -384.292157)
			(xy 326.971673 -384.246307) (xy 327.007364 -384.205116) (xy 327.048555 -384.169425) (xy 327.094405 -384.139959)
			(xy 327.143982 -384.117317) (xy 327.196277 -384.101962) (xy 327.250225 -384.094206) (xy 327.304727 -384.094206)
			(xy 327.358675 -384.101962) (xy 327.41097 -384.117317) (xy 327.460547 -384.139959) (xy 327.506397 -384.169425)
			(xy 327.547588 -384.205116) (xy 327.583279 -384.246307) (xy 327.612745 -384.292157) (xy 327.635387 -384.341734)
			(xy 327.650742 -384.394029) (xy 327.658498 -384.447977) (xy 327.658984 -384.475228) (xy 327.658984 -385.21386)
			(xy 329.576684 -385.21386) (xy 329.576684 -384.35026) (xy 329.57717 -384.323009) (xy 329.584926 -384.269061)
			(xy 329.600281 -384.216766) (xy 329.622923 -384.167189) (xy 329.652389 -384.121339) (xy 329.68808 -384.080148)
			(xy 329.729271 -384.044457) (xy 329.775121 -384.014991) (xy 329.824698 -383.992349) (xy 329.876993 -383.976994)
			(xy 329.930941 -383.969238) (xy 329.985443 -383.969238) (xy 330.039391 -383.976994) (xy 330.091686 -383.992349)
			(xy 330.141263 -384.014991) (xy 330.187113 -384.044457) (xy 330.228304 -384.080148) (xy 330.263995 -384.121339)
			(xy 330.293461 -384.167189) (xy 330.316103 -384.216766) (xy 330.331458 -384.269061) (xy 330.339214 -384.323009)
			(xy 330.3397 -384.35026) (xy 330.3397 -385.21386) (xy 330.339214 -385.241111) (xy 330.331458 -385.295059)
			(xy 330.318606 -385.338828) (xy 359.423716 -385.338828) (xy 359.423716 -384.475228) (xy 359.424202 -384.447977)
			(xy 359.431958 -384.394029) (xy 359.447313 -384.341734) (xy 359.469955 -384.292157) (xy 359.499421 -384.246307)
			(xy 359.535112 -384.205116) (xy 359.576303 -384.169425) (xy 359.622153 -384.139959) (xy 359.67173 -384.117317)
			(xy 359.724025 -384.101962) (xy 359.777973 -384.094206) (xy 359.832475 -384.094206) (xy 359.886423 -384.101962)
			(xy 359.938718 -384.117317) (xy 359.988295 -384.139959) (xy 360.034145 -384.169425) (xy 360.075336 -384.205116)
			(xy 360.111027 -384.246307) (xy 360.140493 -384.292157) (xy 360.163135 -384.341734) (xy 360.17849 -384.394029)
			(xy 360.186246 -384.447977) (xy 360.186732 -384.475228) (xy 360.186732 -385.21386) (xy 364.149132 -385.21386)
			(xy 364.149132 -384.35026) (xy 364.149618 -384.323009) (xy 364.157374 -384.269061) (xy 364.172729 -384.216766)
			(xy 364.195371 -384.167189) (xy 364.224837 -384.121339) (xy 364.260528 -384.080148) (xy 364.301719 -384.044457)
			(xy 364.347569 -384.014991) (xy 364.397146 -383.992349) (xy 364.449441 -383.976994) (xy 364.503389 -383.969238)
			(xy 364.557891 -383.969238) (xy 364.611839 -383.976994) (xy 364.664134 -383.992349) (xy 364.713711 -384.014991)
			(xy 364.759561 -384.044457) (xy 364.800752 -384.080148) (xy 364.836443 -384.121339) (xy 364.865909 -384.167189)
			(xy 364.888551 -384.216766) (xy 364.903906 -384.269061) (xy 364.911662 -384.323009) (xy 364.912148 -384.35026)
			(xy 364.912148 -385.21386) (xy 364.911662 -385.241111) (xy 364.903906 -385.295059) (xy 364.891054 -385.338828)
			(xy 393.996164 -385.338828) (xy 393.996164 -384.475228) (xy 393.99665 -384.447977) (xy 394.004406 -384.394029)
			(xy 394.019761 -384.341734) (xy 394.042403 -384.292157) (xy 394.071869 -384.246307) (xy 394.10756 -384.205116)
			(xy 394.148751 -384.169425) (xy 394.194601 -384.139959) (xy 394.244178 -384.117317) (xy 394.296473 -384.101962)
			(xy 394.350421 -384.094206) (xy 394.404923 -384.094206) (xy 394.458871 -384.101962) (xy 394.511166 -384.117317)
			(xy 394.560743 -384.139959) (xy 394.606593 -384.169425) (xy 394.647784 -384.205116) (xy 394.683475 -384.246307)
			(xy 394.712941 -384.292157) (xy 394.735583 -384.341734) (xy 394.750938 -384.394029) (xy 394.758694 -384.447977)
			(xy 394.75918 -384.475228) (xy 394.75918 -385.21386) (xy 396.67688 -385.21386) (xy 396.67688 -384.35026)
			(xy 396.677366 -384.323009) (xy 396.685122 -384.269061) (xy 396.700477 -384.216766) (xy 396.723119 -384.167189)
			(xy 396.752585 -384.121339) (xy 396.788276 -384.080148) (xy 396.829467 -384.044457) (xy 396.875317 -384.014991)
			(xy 396.924894 -383.992349) (xy 396.977189 -383.976994) (xy 397.031137 -383.969238) (xy 397.085639 -383.969238)
			(xy 397.139587 -383.976994) (xy 397.191882 -383.992349) (xy 397.241459 -384.014991) (xy 397.287309 -384.044457)
			(xy 397.3285 -384.080148) (xy 397.364191 -384.121339) (xy 397.393657 -384.167189) (xy 397.416299 -384.216766)
			(xy 397.431654 -384.269061) (xy 397.43941 -384.323009) (xy 397.439896 -384.35026) (xy 397.439896 -385.21386)
			(xy 397.43941 -385.241111) (xy 397.431654 -385.295059) (xy 397.418802 -385.338828) (xy 426.523912 -385.338828)
			(xy 426.523912 -384.475228) (xy 426.524398 -384.447977) (xy 426.532154 -384.394029) (xy 426.547509 -384.341734)
			(xy 426.570151 -384.292157) (xy 426.599617 -384.246307) (xy 426.635308 -384.205116) (xy 426.676499 -384.169425)
			(xy 426.722349 -384.139959) (xy 426.771926 -384.117317) (xy 426.824221 -384.101962) (xy 426.878169 -384.094206)
			(xy 426.932671 -384.094206) (xy 426.986619 -384.101962) (xy 427.038914 -384.117317) (xy 427.088491 -384.139959)
			(xy 427.134341 -384.169425) (xy 427.175532 -384.205116) (xy 427.211223 -384.246307) (xy 427.240689 -384.292157)
			(xy 427.263331 -384.341734) (xy 427.278686 -384.394029) (xy 427.286442 -384.447977) (xy 427.286928 -384.475228)
			(xy 427.286928 -384.869944) (xy 429.498772 -384.869944) (xy 429.502744 -384.691701) (xy 429.514652 -384.513812)
			(xy 429.534473 -384.33663) (xy 429.562167 -384.160506) (xy 429.597679 -383.985791) (xy 429.640939 -383.812832)
			(xy 429.691861 -383.641971) (xy 429.750344 -383.473549) (xy 429.816271 -383.307899) (xy 429.889512 -383.14535)
			(xy 429.969922 -382.986225) (xy 430.05734 -382.83084) (xy 430.151593 -382.679504) (xy 430.252494 -382.532516)
			(xy 430.359843 -382.390169) (xy 430.473426 -382.252746) (xy 430.593019 -382.120519) (xy 430.718383 -381.99375)
			(xy 430.84927 -381.872692) (xy 430.985419 -381.757585) (xy 431.126561 -381.648657) (xy 431.272416 -381.546125)
			(xy 431.422693 -381.450191) (xy 431.577094 -381.361048) (xy 431.735313 -381.278871) (xy 431.897036 -381.203823)
			(xy 432.061941 -381.136055) (xy 432.229702 -381.075699) (xy 432.399985 -381.022877) (xy 432.572452 -380.977693)
			(xy 432.74676 -380.940236) (xy 432.922564 -380.910582) (xy 433.099514 -380.888789) (xy 433.27726 -380.874899)
			(xy 433.455447 -380.868942) (xy 433.633724 -380.870928) (xy 433.811735 -380.880854) (xy 433.989127 -380.8987)
			(xy 434.165547 -380.92443) (xy 434.340647 -380.957994) (xy 434.514078 -380.999324) (xy 434.685495 -381.04834)
			(xy 434.854558 -381.104942) (xy 435.020933 -381.16902) (xy 435.184287 -381.240446) (xy 435.344298 -381.319078)
			(xy 435.500647 -381.404759) (xy 435.653024 -381.497321) (xy 435.801127 -381.596578) (xy 435.944661 -381.702335)
			(xy 436.083341 -381.81438) (xy 436.216892 -381.932492) (xy 436.345049 -382.056436) (xy 436.467558 -382.185966)
			(xy 436.584175 -382.320825) (xy 436.694668 -382.460745) (xy 436.798819 -382.605448) (xy 436.896421 -382.754647)
			(xy 436.987279 -382.908046) (xy 437.071213 -383.06534) (xy 437.148058 -383.226216) (xy 437.217659 -383.390357)
			(xy 437.27988 -383.557434) (xy 437.334596 -383.727118) (xy 437.381698 -383.899071) (xy 437.421094 -384.072951)
			(xy 437.452705 -384.248414) (xy 437.476469 -384.42511) (xy 437.492337 -384.60269) (xy 437.500279 -384.7808)
			(xy 437.500776 -384.869944) (xy 437.500279 -384.959088) (xy 437.492337 -385.137198) (xy 437.476469 -385.314778)
			(xy 437.452705 -385.491474) (xy 437.421094 -385.666937) (xy 437.381698 -385.840817) (xy 437.334596 -386.01277)
			(xy 437.27988 -386.182454) (xy 437.217659 -386.349531) (xy 437.148058 -386.513672) (xy 437.071213 -386.674548)
			(xy 436.987279 -386.831842) (xy 436.896421 -386.985241) (xy 436.798819 -387.13444) (xy 436.694668 -387.279143)
			(xy 436.584175 -387.419063) (xy 436.467558 -387.553922) (xy 436.345049 -387.683452) (xy 436.216892 -387.807396)
			(xy 436.083341 -387.925508) (xy 435.944661 -388.037553) (xy 435.801127 -388.14331) (xy 435.653024 -388.242567)
			(xy 435.500647 -388.335129) (xy 435.344298 -388.42081) (xy 435.184287 -388.499442) (xy 435.020933 -388.570868)
			(xy 434.854558 -388.634946) (xy 434.685495 -388.691548) (xy 434.514078 -388.740564) (xy 434.340647 -388.781894)
			(xy 434.165547 -388.815458) (xy 433.989127 -388.841188) (xy 433.811735 -388.859034) (xy 433.633724 -388.86896)
			(xy 433.455447 -388.870946) (xy 433.27726 -388.864989) (xy 433.099514 -388.851099) (xy 432.922564 -388.829306)
			(xy 432.74676 -388.799652) (xy 432.572452 -388.762195) (xy 432.399985 -388.717011) (xy 432.229702 -388.664189)
			(xy 432.061941 -388.603833) (xy 431.897036 -388.536065) (xy 431.735313 -388.461017) (xy 431.577094 -388.37884)
			(xy 431.422693 -388.289697) (xy 431.272416 -388.193763) (xy 431.126561 -388.091231) (xy 430.985419 -387.982303)
			(xy 430.84927 -387.867196) (xy 430.718383 -387.746138) (xy 430.593019 -387.619369) (xy 430.473426 -387.487142)
			(xy 430.359843 -387.349719) (xy 430.252494 -387.207372) (xy 430.151593 -387.060384) (xy 430.05734 -386.909048)
			(xy 429.969922 -386.753663) (xy 429.889512 -386.594538) (xy 429.816271 -386.431989) (xy 429.750344 -386.266339)
			(xy 429.691861 -386.097917) (xy 429.640939 -385.927056) (xy 429.597679 -385.754097) (xy 429.562167 -385.579382)
			(xy 429.534473 -385.403258) (xy 429.514652 -385.226076) (xy 429.502744 -385.048187) (xy 429.498772 -384.869944)
			(xy 427.286928 -384.869944) (xy 427.286928 -385.338828) (xy 427.286442 -385.366079) (xy 427.278686 -385.420027)
			(xy 427.263331 -385.472322) (xy 427.240689 -385.521899) (xy 427.211223 -385.567749) (xy 427.175532 -385.60894)
			(xy 427.134341 -385.644631) (xy 427.088491 -385.674097) (xy 427.038914 -385.696739) (xy 426.986619 -385.712094)
			(xy 426.932671 -385.71985) (xy 426.878169 -385.71985) (xy 426.824221 -385.712094) (xy 426.771926 -385.696739)
			(xy 426.722349 -385.674097) (xy 426.676499 -385.644631) (xy 426.635308 -385.60894) (xy 426.599617 -385.567749)
			(xy 426.570151 -385.521899) (xy 426.547509 -385.472322) (xy 426.532154 -385.420027) (xy 426.524398 -385.366079)
			(xy 426.523912 -385.338828) (xy 397.418802 -385.338828) (xy 397.416299 -385.347354) (xy 397.393657 -385.396931)
			(xy 397.364191 -385.442781) (xy 397.3285 -385.483972) (xy 397.287309 -385.519663) (xy 397.241459 -385.549129)
			(xy 397.191882 -385.571771) (xy 397.139587 -385.587126) (xy 397.085639 -385.594882) (xy 397.031137 -385.594882)
			(xy 396.977189 -385.587126) (xy 396.924894 -385.571771) (xy 396.875317 -385.549129) (xy 396.829467 -385.519663)
			(xy 396.788276 -385.483972) (xy 396.752585 -385.442781) (xy 396.723119 -385.396931) (xy 396.700477 -385.347354)
			(xy 396.685122 -385.295059) (xy 396.677366 -385.241111) (xy 396.67688 -385.21386) (xy 394.75918 -385.21386)
			(xy 394.75918 -385.338828) (xy 394.758694 -385.366079) (xy 394.750938 -385.420027) (xy 394.735583 -385.472322)
			(xy 394.712941 -385.521899) (xy 394.683475 -385.567749) (xy 394.647784 -385.60894) (xy 394.606593 -385.644631)
			(xy 394.560743 -385.674097) (xy 394.511166 -385.696739) (xy 394.458871 -385.712094) (xy 394.404923 -385.71985)
			(xy 394.350421 -385.71985) (xy 394.296473 -385.712094) (xy 394.244178 -385.696739) (xy 394.194601 -385.674097)
			(xy 394.148751 -385.644631) (xy 394.10756 -385.60894) (xy 394.071869 -385.567749) (xy 394.042403 -385.521899)
			(xy 394.019761 -385.472322) (xy 394.004406 -385.420027) (xy 393.99665 -385.366079) (xy 393.996164 -385.338828)
			(xy 364.891054 -385.338828) (xy 364.888551 -385.347354) (xy 364.865909 -385.396931) (xy 364.836443 -385.442781)
			(xy 364.800752 -385.483972) (xy 364.759561 -385.519663) (xy 364.713711 -385.549129) (xy 364.664134 -385.571771)
			(xy 364.611839 -385.587126) (xy 364.557891 -385.594882) (xy 364.503389 -385.594882) (xy 364.449441 -385.587126)
			(xy 364.397146 -385.571771) (xy 364.347569 -385.549129) (xy 364.301719 -385.519663) (xy 364.260528 -385.483972)
			(xy 364.224837 -385.442781) (xy 364.195371 -385.396931) (xy 364.172729 -385.347354) (xy 364.157374 -385.295059)
			(xy 364.149618 -385.241111) (xy 364.149132 -385.21386) (xy 360.186732 -385.21386) (xy 360.186732 -385.338828)
			(xy 360.186246 -385.366079) (xy 360.17849 -385.420027) (xy 360.163135 -385.472322) (xy 360.140493 -385.521899)
			(xy 360.111027 -385.567749) (xy 360.075336 -385.60894) (xy 360.034145 -385.644631) (xy 359.988295 -385.674097)
			(xy 359.938718 -385.696739) (xy 359.886423 -385.712094) (xy 359.832475 -385.71985) (xy 359.777973 -385.71985)
			(xy 359.724025 -385.712094) (xy 359.67173 -385.696739) (xy 359.622153 -385.674097) (xy 359.576303 -385.644631)
			(xy 359.535112 -385.60894) (xy 359.499421 -385.567749) (xy 359.469955 -385.521899) (xy 359.447313 -385.472322)
			(xy 359.431958 -385.420027) (xy 359.424202 -385.366079) (xy 359.423716 -385.338828) (xy 330.318606 -385.338828)
			(xy 330.316103 -385.347354) (xy 330.293461 -385.396931) (xy 330.263995 -385.442781) (xy 330.228304 -385.483972)
			(xy 330.187113 -385.519663) (xy 330.141263 -385.549129) (xy 330.091686 -385.571771) (xy 330.039391 -385.587126)
			(xy 329.985443 -385.594882) (xy 329.930941 -385.594882) (xy 329.876993 -385.587126) (xy 329.824698 -385.571771)
			(xy 329.775121 -385.549129) (xy 329.729271 -385.519663) (xy 329.68808 -385.483972) (xy 329.652389 -385.442781)
			(xy 329.622923 -385.396931) (xy 329.600281 -385.347354) (xy 329.584926 -385.295059) (xy 329.57717 -385.241111)
			(xy 329.576684 -385.21386) (xy 327.658984 -385.21386) (xy 327.658984 -385.338828) (xy 327.658498 -385.366079)
			(xy 327.650742 -385.420027) (xy 327.635387 -385.472322) (xy 327.612745 -385.521899) (xy 327.583279 -385.567749)
			(xy 327.547588 -385.60894) (xy 327.506397 -385.644631) (xy 327.460547 -385.674097) (xy 327.41097 -385.696739)
			(xy 327.358675 -385.712094) (xy 327.304727 -385.71985) (xy 327.250225 -385.71985) (xy 327.196277 -385.712094)
			(xy 327.143982 -385.696739) (xy 327.094405 -385.674097) (xy 327.048555 -385.644631) (xy 327.007364 -385.60894)
			(xy 326.971673 -385.567749) (xy 326.942207 -385.521899) (xy 326.919565 -385.472322) (xy 326.90421 -385.420027)
			(xy 326.896454 -385.366079) (xy 326.895968 -385.338828) (xy 297.790858 -385.338828) (xy 297.788355 -385.347354)
			(xy 297.765713 -385.396931) (xy 297.736247 -385.442781) (xy 297.700556 -385.483972) (xy 297.659365 -385.519663)
			(xy 297.613515 -385.549129) (xy 297.563938 -385.571771) (xy 297.511643 -385.587126) (xy 297.457695 -385.594882)
			(xy 297.403193 -385.594882) (xy 297.349245 -385.587126) (xy 297.29695 -385.571771) (xy 297.247373 -385.549129)
			(xy 297.201523 -385.519663) (xy 297.160332 -385.483972) (xy 297.124641 -385.442781) (xy 297.095175 -385.396931)
			(xy 297.072533 -385.347354) (xy 297.057178 -385.295059) (xy 297.049422 -385.241111) (xy 297.048936 -385.21386)
			(xy 295.055495 -385.21386) (xy 295.046477 -385.314778) (xy 295.022713 -385.491474) (xy 294.991102 -385.666937)
			(xy 294.951706 -385.840817) (xy 294.904604 -386.01277) (xy 294.849888 -386.182454) (xy 294.787667 -386.349531)
			(xy 294.718066 -386.513672) (xy 294.641221 -386.674548) (xy 294.557287 -386.831842) (xy 294.466429 -386.985241)
			(xy 294.368827 -387.13444) (xy 294.264676 -387.279143) (xy 294.154183 -387.419063) (xy 294.037566 -387.553922)
			(xy 293.915057 -387.683452) (xy 293.7869 -387.807396) (xy 293.653349 -387.925508) (xy 293.514669 -388.037553)
			(xy 293.371135 -388.14331) (xy 293.223032 -388.242567) (xy 293.070655 -388.335129) (xy 292.914306 -388.42081)
			(xy 292.754295 -388.499442) (xy 292.590941 -388.570868) (xy 292.424566 -388.634946) (xy 292.255503 -388.691548)
			(xy 292.084086 -388.740564) (xy 292.076264 -388.742428) (xy 326.895968 -388.742428) (xy 326.895968 -387.878828)
			(xy 326.896454 -387.851577) (xy 326.90421 -387.797629) (xy 326.919565 -387.745334) (xy 326.942207 -387.695757)
			(xy 326.971673 -387.649907) (xy 327.007364 -387.608716) (xy 327.048555 -387.573025) (xy 327.094405 -387.543559)
			(xy 327.143982 -387.520917) (xy 327.196277 -387.505562) (xy 327.250225 -387.497806) (xy 327.304727 -387.497806)
			(xy 327.358675 -387.505562) (xy 327.41097 -387.520917) (xy 327.460547 -387.543559) (xy 327.506397 -387.573025)
			(xy 327.547588 -387.608716) (xy 327.583279 -387.649907) (xy 327.612745 -387.695757) (xy 327.635387 -387.745334)
			(xy 327.650742 -387.797629) (xy 327.658498 -387.851577) (xy 327.658984 -387.878828) (xy 327.658984 -388.742428)
			(xy 359.423716 -388.742428) (xy 359.423716 -387.878828) (xy 359.424202 -387.851577) (xy 359.431958 -387.797629)
			(xy 359.447313 -387.745334) (xy 359.469955 -387.695757) (xy 359.499421 -387.649907) (xy 359.535112 -387.608716)
			(xy 359.576303 -387.573025) (xy 359.622153 -387.543559) (xy 359.67173 -387.520917) (xy 359.724025 -387.505562)
			(xy 359.777973 -387.497806) (xy 359.832475 -387.497806) (xy 359.886423 -387.505562) (xy 359.938718 -387.520917)
			(xy 359.988295 -387.543559) (xy 360.034145 -387.573025) (xy 360.075336 -387.608716) (xy 360.111027 -387.649907)
			(xy 360.140493 -387.695757) (xy 360.163135 -387.745334) (xy 360.17849 -387.797629) (xy 360.186246 -387.851577)
			(xy 360.186732 -387.878828) (xy 360.186732 -388.742428) (xy 393.996164 -388.742428) (xy 393.996164 -387.878828)
			(xy 393.99665 -387.851577) (xy 394.004406 -387.797629) (xy 394.019761 -387.745334) (xy 394.042403 -387.695757)
			(xy 394.071869 -387.649907) (xy 394.10756 -387.608716) (xy 394.148751 -387.573025) (xy 394.194601 -387.543559)
			(xy 394.244178 -387.520917) (xy 394.296473 -387.505562) (xy 394.350421 -387.497806) (xy 394.404923 -387.497806)
			(xy 394.458871 -387.505562) (xy 394.511166 -387.520917) (xy 394.560743 -387.543559) (xy 394.606593 -387.573025)
			(xy 394.647784 -387.608716) (xy 394.683475 -387.649907) (xy 394.712941 -387.695757) (xy 394.735583 -387.745334)
			(xy 394.750938 -387.797629) (xy 394.758694 -387.851577) (xy 394.75918 -387.878828) (xy 394.75918 -388.742428)
			(xy 426.523912 -388.742428) (xy 426.523912 -387.878828) (xy 426.524398 -387.851577) (xy 426.532154 -387.797629)
			(xy 426.547509 -387.745334) (xy 426.570151 -387.695757) (xy 426.599617 -387.649907) (xy 426.635308 -387.608716)
			(xy 426.676499 -387.573025) (xy 426.722349 -387.543559) (xy 426.771926 -387.520917) (xy 426.824221 -387.505562)
			(xy 426.878169 -387.497806) (xy 426.932671 -387.497806) (xy 426.986619 -387.505562) (xy 427.038914 -387.520917)
			(xy 427.088491 -387.543559) (xy 427.134341 -387.573025) (xy 427.175532 -387.608716) (xy 427.211223 -387.649907)
			(xy 427.240689 -387.695757) (xy 427.263331 -387.745334) (xy 427.278686 -387.797629) (xy 427.286442 -387.851577)
			(xy 427.286928 -387.878828) (xy 427.286928 -388.742428) (xy 427.286442 -388.769679) (xy 427.278686 -388.823627)
			(xy 427.263331 -388.875922) (xy 427.240689 -388.925499) (xy 427.211223 -388.971349) (xy 427.175532 -389.01254)
			(xy 427.134341 -389.048231) (xy 427.088491 -389.077697) (xy 427.038914 -389.100339) (xy 426.986619 -389.115694)
			(xy 426.932671 -389.12345) (xy 426.878169 -389.12345) (xy 426.824221 -389.115694) (xy 426.771926 -389.100339)
			(xy 426.722349 -389.077697) (xy 426.676499 -389.048231) (xy 426.635308 -389.01254) (xy 426.599617 -388.971349)
			(xy 426.570151 -388.925499) (xy 426.547509 -388.875922) (xy 426.532154 -388.823627) (xy 426.524398 -388.769679)
			(xy 426.523912 -388.742428) (xy 394.75918 -388.742428) (xy 394.758694 -388.769679) (xy 394.750938 -388.823627)
			(xy 394.735583 -388.875922) (xy 394.712941 -388.925499) (xy 394.683475 -388.971349) (xy 394.647784 -389.01254)
			(xy 394.606593 -389.048231) (xy 394.560743 -389.077697) (xy 394.511166 -389.100339) (xy 394.458871 -389.115694)
			(xy 394.404923 -389.12345) (xy 394.350421 -389.12345) (xy 394.296473 -389.115694) (xy 394.244178 -389.100339)
			(xy 394.194601 -389.077697) (xy 394.148751 -389.048231) (xy 394.10756 -389.01254) (xy 394.071869 -388.971349)
			(xy 394.042403 -388.925499) (xy 394.019761 -388.875922) (xy 394.004406 -388.823627) (xy 393.99665 -388.769679)
			(xy 393.996164 -388.742428) (xy 360.186732 -388.742428) (xy 360.186246 -388.769679) (xy 360.17849 -388.823627)
			(xy 360.163135 -388.875922) (xy 360.140493 -388.925499) (xy 360.111027 -388.971349) (xy 360.075336 -389.01254)
			(xy 360.034145 -389.048231) (xy 359.988295 -389.077697) (xy 359.938718 -389.100339) (xy 359.886423 -389.115694)
			(xy 359.832475 -389.12345) (xy 359.777973 -389.12345) (xy 359.724025 -389.115694) (xy 359.67173 -389.100339)
			(xy 359.622153 -389.077697) (xy 359.576303 -389.048231) (xy 359.535112 -389.01254) (xy 359.499421 -388.971349)
			(xy 359.469955 -388.925499) (xy 359.447313 -388.875922) (xy 359.431958 -388.823627) (xy 359.424202 -388.769679)
			(xy 359.423716 -388.742428) (xy 327.658984 -388.742428) (xy 327.658498 -388.769679) (xy 327.650742 -388.823627)
			(xy 327.635387 -388.875922) (xy 327.612745 -388.925499) (xy 327.583279 -388.971349) (xy 327.547588 -389.01254)
			(xy 327.506397 -389.048231) (xy 327.460547 -389.077697) (xy 327.41097 -389.100339) (xy 327.358675 -389.115694)
			(xy 327.304727 -389.12345) (xy 327.250225 -389.12345) (xy 327.196277 -389.115694) (xy 327.143982 -389.100339)
			(xy 327.094405 -389.077697) (xy 327.048555 -389.048231) (xy 327.007364 -389.01254) (xy 326.971673 -388.971349)
			(xy 326.942207 -388.925499) (xy 326.919565 -388.875922) (xy 326.90421 -388.823627) (xy 326.896454 -388.769679)
			(xy 326.895968 -388.742428) (xy 292.076264 -388.742428) (xy 291.910655 -388.781894) (xy 291.735555 -388.815458)
			(xy 291.559135 -388.841188) (xy 291.381743 -388.859034) (xy 291.203732 -388.86896) (xy 291.025455 -388.870946)
			(xy 290.847268 -388.864989) (xy 290.669522 -388.851099) (xy 290.492572 -388.829306) (xy 290.316768 -388.799652)
			(xy 290.14246 -388.762195) (xy 289.969993 -388.717011) (xy 289.79971 -388.664189) (xy 289.631949 -388.603833)
			(xy 289.467044 -388.536065) (xy 289.305321 -388.461017) (xy 289.147102 -388.37884) (xy 288.992701 -388.289697)
			(xy 288.842424 -388.193763) (xy 288.696569 -388.091231) (xy 288.555427 -387.982303) (xy 288.419278 -387.867196)
			(xy 288.288391 -387.746138) (xy 288.163027 -387.619369) (xy 288.043434 -387.487142) (xy 287.929851 -387.349719)
			(xy 287.822502 -387.207372) (xy 287.721601 -387.060384) (xy 287.627348 -386.909048) (xy 287.53993 -386.753663)
			(xy 287.45952 -386.594538) (xy 287.386279 -386.431989) (xy 287.320352 -386.266339) (xy 287.261869 -386.097917)
			(xy 287.210947 -385.927056) (xy 287.167687 -385.754097) (xy 287.132175 -385.579382) (xy 287.104481 -385.403258)
			(xy 287.08466 -385.226076) (xy 287.072752 -385.048187) (xy 287.06878 -384.869944) (xy 2.509012 -384.869944)
			(xy 2.509012 -385.310888) (xy 47.485808 -385.310888) (xy 47.485808 -385.31038) (xy 47.486221 -385.286373)
			(xy 47.493739 -385.238951) (xy 47.508587 -385.19329) (xy 47.530398 -385.150515) (xy 47.558635 -385.111682)
			(xy 47.592603 -385.077747) (xy 47.631463 -385.049546) (xy 47.674258 -385.027775) (xy 47.719933 -385.012971)
			(xy 47.767362 -385.005498) (xy 47.79137 -385.005072) (xy 47.815305 -385.005523) (xy 47.862591 -385.012984)
			(xy 47.908134 -385.027728) (xy 47.950821 -385.049394) (xy 47.989606 -385.077452) (xy 48.023541 -385.111216)
			(xy 48.051795 -385.149858) (xy 48.06315 -385.170934) (xy 48.063658 -385.17195) (xy 48.143964 -385.310888)
			(xy 48.685704 -385.310888) (xy 48.685704 -385.31038) (xy 48.686121 -385.286373) (xy 48.693639 -385.238951)
			(xy 48.708486 -385.193291) (xy 48.730297 -385.150516) (xy 48.758534 -385.111683) (xy 48.792501 -385.077748)
			(xy 48.831361 -385.049548) (xy 48.874155 -385.027777) (xy 48.91983 -385.012972) (xy 48.967259 -385.005498)
			(xy 48.991266 -385.005072) (xy 49.015201 -385.005526) (xy 49.062486 -385.012986) (xy 49.10803 -385.02773)
			(xy 49.150716 -385.049395) (xy 49.189502 -385.077453) (xy 49.223437 -385.111216) (xy 49.251691 -385.149859)
			(xy 49.263046 -385.170934) (xy 49.263554 -385.17195) (xy 49.34386 -385.310888) (xy 49.8856 -385.310888)
			(xy 49.8856 -385.31038) (xy 49.886021 -385.286373) (xy 49.893539 -385.238952) (xy 49.908386 -385.193291)
			(xy 49.930196 -385.150518) (xy 49.958433 -385.111685) (xy 49.992399 -385.07775) (xy 50.031259 -385.049549)
			(xy 50.074052 -385.027778) (xy 50.119727 -385.012973) (xy 50.167155 -385.005499) (xy 50.191162 -385.005072)
			(xy 50.215097 -385.005529) (xy 50.262382 -385.012989) (xy 50.307925 -385.027732) (xy 50.350612 -385.049397)
			(xy 50.389397 -385.077454) (xy 50.423333 -385.111217) (xy 50.451587 -385.149859) (xy 50.462942 -385.170934)
			(xy 50.46345 -385.17195) (xy 50.543756 -385.310888) (xy 51.086004 -385.310888) (xy 51.086004 -385.31038)
			(xy 51.086444 -385.286388) (xy 51.093954 -385.238994) (xy 51.108785 -385.193359) (xy 51.130572 -385.150605)
			(xy 51.158779 -385.111786) (xy 51.192711 -385.077858) (xy 51.231533 -385.049655) (xy 51.274288 -385.027872)
			(xy 51.319925 -385.013046) (xy 51.36732 -385.005542) (xy 51.391312 -385.005072) (xy 51.415246 -385.00557)
			(xy 51.462529 -385.013022) (xy 51.508071 -385.027757) (xy 51.550758 -385.049416) (xy 51.589544 -385.077467)
			(xy 51.62348 -385.111224) (xy 51.651736 -385.149861) (xy 51.663092 -385.170934) (xy 51.6636 -385.17195)
			(xy 51.743906 -385.310888) (xy 52.2859 -385.310888) (xy 52.2859 -385.31038) (xy 52.286344 -385.286388)
			(xy 52.293854 -385.238995) (xy 52.308684 -385.19336) (xy 52.330471 -385.150606) (xy 52.358677 -385.111788)
			(xy 52.392609 -385.077859) (xy 52.43143 -385.049656) (xy 52.474186 -385.027873) (xy 52.519822 -385.013047)
			(xy 52.567216 -385.005542) (xy 52.591208 -385.005072) (xy 52.615141 -385.005573) (xy 52.662424 -385.013024)
			(xy 52.707967 -385.027759) (xy 52.750653 -385.049417) (xy 52.789439 -385.077468) (xy 52.823376 -385.111224)
			(xy 52.851632 -385.149861) (xy 52.862988 -385.170934) (xy 52.863496 -385.17195) (xy 52.943802 -385.310888)
			(xy 53.485796 -385.310888) (xy 53.485796 -385.31038) (xy 53.486221 -385.286373) (xy 53.493738 -385.238952)
			(xy 53.508585 -385.193292) (xy 53.530396 -385.150519) (xy 53.558632 -385.111686) (xy 53.592598 -385.077751)
			(xy 53.631456 -385.04955) (xy 53.67425 -385.027779) (xy 53.719923 -385.012973) (xy 53.767351 -385.005499)
			(xy 53.791358 -385.005072) (xy 53.815293 -385.005532) (xy 53.862578 -385.012992) (xy 53.908121 -385.027734)
			(xy 53.950807 -385.049398) (xy 53.989593 -385.077455) (xy 54.023528 -385.111217) (xy 54.051783 -385.149859)
			(xy 54.063138 -385.170934) (xy 54.063646 -385.17195) (xy 54.143952 -385.310888) (xy 54.685692 -385.310888)
			(xy 54.685692 -385.31038) (xy 54.686121 -385.286374) (xy 54.693638 -385.238953) (xy 54.708485 -385.193293)
			(xy 54.730295 -385.15052) (xy 54.758531 -385.111687) (xy 54.792496 -385.077752) (xy 54.831354 -385.049552)
			(xy 54.874147 -385.02778) (xy 54.91982 -385.012974) (xy 54.967247 -385.005499) (xy 54.991254 -385.005072)
			(xy 55.015189 -385.005536) (xy 55.062474 -385.012994) (xy 55.108017 -385.027736) (xy 55.150703 -385.0494)
			(xy 55.189489 -385.077456) (xy 55.223424 -385.111218) (xy 55.251679 -385.149859) (xy 55.263034 -385.170934)
			(xy 55.263542 -385.17195) (xy 55.343848 -385.310888) (xy 55.885588 -385.310888) (xy 55.885588 -385.31038)
			(xy 55.886021 -385.286374) (xy 55.893538 -385.238954) (xy 55.908385 -385.193294) (xy 55.930194 -385.150521)
			(xy 55.95843 -385.111689) (xy 55.992394 -385.077754) (xy 56.031252 -385.049553) (xy 56.074044 -385.027781)
			(xy 56.119717 -385.012975) (xy 56.167143 -385.0055) (xy 56.19115 -385.005072) (xy 56.215085 -385.005539)
			(xy 56.262369 -385.012997) (xy 56.307912 -385.027738) (xy 56.350599 -385.049401) (xy 56.389384 -385.077457)
			(xy 56.42332 -385.111218) (xy 56.451575 -385.149859) (xy 56.46293 -385.170934) (xy 56.463438 -385.17195)
			(xy 56.543744 -385.310888) (xy 57.085992 -385.310888) (xy 57.085992 -385.31038) (xy 57.086444 -385.286388)
			(xy 57.093953 -385.238996) (xy 57.108783 -385.193362) (xy 57.130569 -385.150609) (xy 57.158775 -385.11179)
			(xy 57.192706 -385.077862) (xy 57.231526 -385.049659) (xy 57.27428 -385.027876) (xy 57.319915 -385.013049)
			(xy 57.367308 -385.005543) (xy 57.3913 -385.005072) (xy 57.415233 -385.00558) (xy 57.462516 -385.01303)
			(xy 57.508058 -385.027764) (xy 57.550744 -385.04942) (xy 57.589531 -385.07747) (xy 57.623468 -385.111226)
			(xy 57.651724 -385.149862) (xy 57.66308 -385.170934) (xy 57.663588 -385.17195) (xy 57.743894 -385.310888)
			(xy 58.285888 -385.310888) (xy 58.285888 -385.31038) (xy 58.286344 -385.286388) (xy 58.293853 -385.238996)
			(xy 58.308683 -385.193362) (xy 58.330469 -385.15061) (xy 58.358674 -385.111792) (xy 58.392604 -385.077863)
			(xy 58.431424 -385.04966) (xy 58.474177 -385.027877) (xy 58.519812 -385.013049) (xy 58.567204 -385.005543)
			(xy 58.591196 -385.005072) (xy 58.615132 -385.005502) (xy 58.662418 -385.012966) (xy 58.707962 -385.027714)
			(xy 58.750649 -385.049384) (xy 58.789434 -385.077445) (xy 58.823368 -385.111212) (xy 58.851622 -385.149857)
			(xy 58.862976 -385.170934) (xy 58.863484 -385.17195) (xy 58.94379 -385.310888) (xy 59.485784 -385.310888)
			(xy 59.485784 -385.31038) (xy 59.486221 -385.286374) (xy 59.493738 -385.238954) (xy 59.508584 -385.193295)
			(xy 59.530394 -385.150522) (xy 59.558628 -385.11169) (xy 59.592593 -385.077755) (xy 59.63145 -385.049554)
			(xy 59.674241 -385.027782) (xy 59.719913 -385.012976) (xy 59.76734 -385.0055) (xy 59.791346 -385.005072)
			(xy 59.815281 -385.005542) (xy 59.862565 -385.012999) (xy 59.908108 -385.02774) (xy 59.950794 -385.049403)
			(xy 59.98958 -385.077458) (xy 60.023516 -385.111219) (xy 60.051771 -385.149859) (xy 60.063126 -385.170934)
			(xy 60.063634 -385.17195) (xy 60.14394 -385.310888) (xy 60.68568 -385.310888) (xy 60.68568 -385.31038)
			(xy 60.686121 -385.286374) (xy 60.693638 -385.238955) (xy 60.708484 -385.193296) (xy 60.730293 -385.150524)
			(xy 60.758527 -385.111692) (xy 60.792491 -385.077757) (xy 60.831347 -385.049556) (xy 60.874139 -385.027783)
			(xy 60.91981 -385.012977) (xy 60.967236 -385.0055) (xy 60.991242 -385.005072) (xy 61.015176 -385.005545)
			(xy 61.062461 -385.013002) (xy 61.108003 -385.027742) (xy 61.15069 -385.049404) (xy 61.189476 -385.077459)
			(xy 61.223412 -385.11122) (xy 61.251667 -385.14986) (xy 61.263022 -385.170934) (xy 61.26353 -385.17195)
			(xy 61.343836 -385.310888) (xy 61.885576 -385.310888) (xy 61.885576 -385.31038) (xy 61.886021 -385.286374)
			(xy 61.893538 -385.238955) (xy 61.908383 -385.193297) (xy 61.930192 -385.150525) (xy 61.958426 -385.111693)
			(xy 61.992389 -385.077758) (xy 62.031245 -385.049557) (xy 62.074036 -385.027785) (xy 62.119707 -385.012977)
			(xy 62.167132 -385.0055) (xy 62.191138 -385.005072) (xy 62.215072 -385.005549) (xy 62.262356 -385.013005)
			(xy 62.307899 -385.027744) (xy 62.350586 -385.049406) (xy 62.389372 -385.07746) (xy 62.423307 -385.11122)
			(xy 62.451563 -385.14986) (xy 62.462918 -385.170934) (xy 62.463426 -385.17195) (xy 62.543732 -385.310888)
			(xy 63.08598 -385.310888) (xy 63.08598 -385.31038) (xy 63.086444 -385.286389) (xy 63.093953 -385.238998)
			(xy 63.108782 -385.193364) (xy 63.130567 -385.150612) (xy 63.158771 -385.111795) (xy 63.192701 -385.077866)
			(xy 63.231519 -385.049663) (xy 63.274272 -385.027879) (xy 63.319905 -385.013051) (xy 63.367297 -385.005543)
			(xy 63.391288 -385.005072) (xy 63.415224 -385.005508) (xy 63.46251 -385.012972) (xy 63.508053 -385.027718)
			(xy 63.55074 -385.049387) (xy 63.589525 -385.077447) (xy 63.62346 -385.111213) (xy 63.651714 -385.149858)
			(xy 63.663068 -385.170934) (xy 63.663576 -385.17195) (xy 63.743882 -385.310888) (xy 64.285876 -385.310888)
			(xy 64.285876 -385.31038) (xy 64.286344 -385.286389) (xy 64.293853 -385.238998) (xy 64.308682 -385.193365)
			(xy 64.330467 -385.150614) (xy 64.35867 -385.111796) (xy 64.392599 -385.077868) (xy 64.431417 -385.049664)
			(xy 64.474169 -385.02788) (xy 64.519802 -385.013052) (xy 64.567193 -385.005544) (xy 64.591184 -385.005072)
			(xy 64.61512 -385.005511) (xy 64.662406 -385.012974) (xy 64.707949 -385.02772) (xy 64.750636 -385.049388)
			(xy 64.789421 -385.077448) (xy 64.823356 -385.111214) (xy 64.85161 -385.149858) (xy 64.862964 -385.170934)
			(xy 64.863472 -385.17195) (xy 64.943778 -385.310888) (xy 65.485772 -385.310888) (xy 65.485772 -385.31038)
			(xy 65.486221 -385.286375) (xy 65.493738 -385.238956) (xy 65.508583 -385.193298) (xy 65.530391 -385.150526)
			(xy 65.558625 -385.111694) (xy 65.592588 -385.07776) (xy 65.631443 -385.049558) (xy 65.674233 -385.027786)
			(xy 65.719903 -385.012978) (xy 65.767328 -385.005501) (xy 65.791334 -385.005072) (xy 65.815268 -385.005552)
			(xy 65.862552 -385.013007) (xy 65.908095 -385.027746) (xy 65.950781 -385.049407) (xy 65.989567 -385.077461)
			(xy 66.023503 -385.111221) (xy 66.051759 -385.14986) (xy 66.063114 -385.170934) (xy 66.063622 -385.17195)
			(xy 66.143928 -385.310888) (xy 80.013556 -385.310888) (xy 80.013556 -385.31038) (xy 80.014021 -385.286375)
			(xy 80.021537 -385.238958) (xy 80.036382 -385.193302) (xy 80.058188 -385.150531) (xy 80.08642 -385.1117)
			(xy 80.120381 -385.077765) (xy 80.159234 -385.049564) (xy 80.202022 -385.02779) (xy 80.24769 -385.012981)
			(xy 80.295113 -385.005502) (xy 80.319118 -385.005072) (xy 80.343052 -385.005565) (xy 80.390335 -385.013018)
			(xy 80.435877 -385.027754) (xy 80.478564 -385.049413) (xy 80.51735 -385.077465) (xy 80.551287 -385.111223)
			(xy 80.579542 -385.149861) (xy 80.590898 -385.170934) (xy 80.591406 -385.17195) (xy 80.671712 -385.310888)
			(xy 81.213452 -385.310888) (xy 81.213452 -385.31038) (xy 81.213921 -385.286376) (xy 81.221437 -385.238959)
			(xy 81.236281 -385.193303) (xy 81.258088 -385.150532) (xy 81.286319 -385.111701) (xy 81.320279 -385.077767)
			(xy 81.359132 -385.049565) (xy 81.401919 -385.027792) (xy 81.447587 -385.012982) (xy 81.495009 -385.005502)
			(xy 81.519014 -385.005072) (xy 81.542948 -385.005568) (xy 81.590231 -385.013021) (xy 81.635773 -385.027756)
			(xy 81.67846 -385.049415) (xy 81.717246 -385.077466) (xy 81.751182 -385.111224) (xy 81.779438 -385.149861)
			(xy 81.790794 -385.170934) (xy 81.791302 -385.17195) (xy 81.871608 -385.310888) (xy 82.413348 -385.310888)
			(xy 82.413348 -385.31038) (xy 82.413821 -385.286376) (xy 82.421337 -385.238959) (xy 82.436181 -385.193304)
			(xy 82.457987 -385.150533) (xy 82.486218 -385.111702) (xy 82.520178 -385.077768) (xy 82.55903 -385.049567)
			(xy 82.601816 -385.027793) (xy 82.647483 -385.012983) (xy 82.694905 -385.005502) (xy 82.71891 -385.005072)
			(xy 82.742843 -385.005571) (xy 82.790127 -385.013023) (xy 82.835669 -385.027758) (xy 82.878355 -385.049416)
			(xy 82.917142 -385.077467) (xy 82.951078 -385.111224) (xy 82.979334 -385.149861) (xy 82.99069 -385.170934)
			(xy 82.991198 -385.17195) (xy 83.071504 -385.310888) (xy 83.613752 -385.310888) (xy 83.613752 -385.31038)
			(xy 83.614244 -385.28639) (xy 83.621752 -385.239002) (xy 83.63658 -385.193371) (xy 83.658362 -385.150621)
			(xy 83.686563 -385.111804) (xy 83.720489 -385.077876) (xy 83.759304 -385.049673) (xy 83.802052 -385.027887)
			(xy 83.847682 -385.013057) (xy 83.89507 -385.005546) (xy 83.91906 -385.005072) (xy 83.942995 -385.005531)
			(xy 83.99028 -385.01299) (xy 84.035823 -385.027733) (xy 84.07851 -385.049398) (xy 84.117295 -385.077455)
			(xy 84.151231 -385.111217) (xy 84.179485 -385.149859) (xy 84.19084 -385.170934) (xy 84.191348 -385.17195)
			(xy 84.271654 -385.310888) (xy 84.813648 -385.310888) (xy 84.813648 -385.31038) (xy 84.814144 -385.28639)
			(xy 84.821652 -385.239002) (xy 84.836479 -385.193372) (xy 84.858261 -385.150622) (xy 84.886462 -385.111805)
			(xy 84.920387 -385.077878) (xy 84.959201 -385.049674) (xy 85.001949 -385.027888) (xy 85.047579 -385.013057)
			(xy 85.094966 -385.005546) (xy 85.118956 -385.005072) (xy 85.142891 -385.005534) (xy 85.190176 -385.012993)
			(xy 85.235719 -385.027735) (xy 85.278405 -385.049399) (xy 85.317191 -385.077456) (xy 85.351126 -385.111218)
			(xy 85.379381 -385.149859) (xy 85.390736 -385.170934) (xy 85.391244 -385.17195) (xy 85.47155 -385.310888)
			(xy 86.013544 -385.310888) (xy 86.013544 -385.31038) (xy 86.01402 -385.286376) (xy 86.021537 -385.23896)
			(xy 86.03638 -385.193304) (xy 86.058186 -385.150534) (xy 86.086417 -385.111704) (xy 86.120376 -385.07777)
			(xy 86.159227 -385.049568) (xy 86.202014 -385.027794) (xy 86.24768 -385.012984) (xy 86.295102 -385.005503)
			(xy 86.319106 -385.005072) (xy 86.343039 -385.005575) (xy 86.390322 -385.013026) (xy 86.435864 -385.02776)
			(xy 86.478551 -385.049418) (xy 86.517337 -385.077468) (xy 86.551274 -385.111225) (xy 86.57953 -385.149861)
			(xy 86.590886 -385.170934) (xy 86.591394 -385.17195) (xy 86.6717 -385.310888) (xy 87.21344 -385.310888)
			(xy 87.21344 -385.31038) (xy 87.213821 -385.286371) (xy 87.22134 -385.238946) (xy 87.23619 -385.193282)
			(xy 87.258004 -385.150506) (xy 87.286245 -385.111671) (xy 87.320216 -385.077735) (xy 87.359081 -385.049535)
			(xy 87.40188 -385.027766) (xy 87.44756 -385.012965) (xy 87.494993 -385.005496) (xy 87.519002 -385.005072)
			(xy 87.542935 -385.005578) (xy 87.590218 -385.013028) (xy 87.63576 -385.027763) (xy 87.678447 -385.04942)
			(xy 87.717233 -385.077469) (xy 87.75117 -385.111225) (xy 87.779426 -385.149861) (xy 87.790782 -385.170934)
			(xy 87.79129 -385.17195) (xy 87.871596 -385.310888) (xy 88.413336 -385.310888) (xy 88.413336 -385.31038)
			(xy 88.413721 -385.286371) (xy 88.42124 -385.238947) (xy 88.436089 -385.193283) (xy 88.457903 -385.150507)
			(xy 88.486144 -385.111672) (xy 88.520115 -385.077737) (xy 88.558979 -385.049537) (xy 88.601777 -385.027767)
			(xy 88.647456 -385.012965) (xy 88.694889 -385.005496) (xy 88.718898 -385.005072) (xy 88.742834 -385.0055)
			(xy 88.790121 -385.012965) (xy 88.835664 -385.027713) (xy 88.878351 -385.049383) (xy 88.917136 -385.077445)
			(xy 88.95107 -385.111212) (xy 88.979324 -385.149857) (xy 88.990678 -385.170934) (xy 88.991186 -385.17195)
			(xy 89.071492 -385.310888) (xy 89.61374 -385.310888) (xy 89.61374 -385.31038) (xy 89.61412 -385.286384)
			(xy 89.621631 -385.238983) (xy 89.636465 -385.193341) (xy 89.658257 -385.150582) (xy 89.68647 -385.111758)
			(xy 89.72041 -385.077826) (xy 89.75924 -385.049622) (xy 89.802004 -385.027839) (xy 89.847649 -385.013015)
			(xy 89.895052 -385.005515) (xy 89.919048 -385.005072) (xy 89.942983 -385.005541) (xy 89.990267 -385.012998)
			(xy 90.03581 -385.027739) (xy 90.078497 -385.049402) (xy 90.117282 -385.077458) (xy 90.151218 -385.111219)
			(xy 90.179473 -385.149859) (xy 90.190828 -385.170934) (xy 90.191336 -385.17195) (xy 90.271642 -385.310888)
			(xy 90.813636 -385.310888) (xy 90.813636 -385.31038) (xy 90.81402 -385.286384) (xy 90.821531 -385.238984)
			(xy 90.836365 -385.193342) (xy 90.858157 -385.150583) (xy 90.886369 -385.111759) (xy 90.920308 -385.077828)
			(xy 90.959138 -385.049623) (xy 91.001901 -385.02784) (xy 91.047546 -385.013016) (xy 91.094948 -385.005515)
			(xy 91.118944 -385.005072) (xy 91.142878 -385.005544) (xy 91.190163 -385.013001) (xy 91.235706 -385.027741)
			(xy 91.278392 -385.049404) (xy 91.317178 -385.077459) (xy 91.351114 -385.111219) (xy 91.379369 -385.14986)
			(xy 91.390724 -385.170934) (xy 91.391232 -385.17195) (xy 91.471538 -385.310888) (xy 92.013532 -385.310888)
			(xy 92.013532 -385.31038) (xy 92.013921 -385.286372) (xy 92.02144 -385.238947) (xy 92.036289 -385.193284)
			(xy 92.058102 -385.150508) (xy 92.086342 -385.111674) (xy 92.120313 -385.077738) (xy 92.159176 -385.049538)
			(xy 92.201975 -385.027769) (xy 92.247653 -385.012966) (xy 92.295085 -385.005496) (xy 92.319094 -385.005072)
			(xy 92.34303 -385.005503) (xy 92.390316 -385.012968) (xy 92.43586 -385.027715) (xy 92.478547 -385.049385)
			(xy 92.517332 -385.077446) (xy 92.551266 -385.111212) (xy 92.57952 -385.149857) (xy 92.590874 -385.170934)
			(xy 92.591382 -385.17195) (xy 92.671688 -385.310888) (xy 93.213428 -385.310888) (xy 93.213428 -385.31038)
			(xy 93.213821 -385.286372) (xy 93.221339 -385.238948) (xy 93.236188 -385.193285) (xy 93.258002 -385.150509)
			(xy 93.286241 -385.111675) (xy 93.320211 -385.07774) (xy 93.359074 -385.049539) (xy 93.401872 -385.02777)
			(xy 93.44755 -385.012967) (xy 93.494981 -385.005497) (xy 93.51899 -385.005072) (xy 93.542926 -385.005506)
			(xy 93.590212 -385.01297) (xy 93.635756 -385.027717) (xy 93.678442 -385.049386) (xy 93.717227 -385.077447)
			(xy 93.751162 -385.111213) (xy 93.779416 -385.149857) (xy 93.79077 -385.170934) (xy 93.791278 -385.17195)
			(xy 93.871584 -385.310888) (xy 94.413324 -385.310888) (xy 94.413324 -385.31038) (xy 94.413721 -385.286372)
			(xy 94.421239 -385.238948) (xy 94.436088 -385.193286) (xy 94.457901 -385.15051) (xy 94.48614 -385.111676)
			(xy 94.520109 -385.077741) (xy 94.558972 -385.049541) (xy 94.601769 -385.027771) (xy 94.647446 -385.012968)
			(xy 94.694878 -385.005497) (xy 94.718886 -385.005072) (xy 94.742822 -385.00551) (xy 94.790108 -385.012973)
			(xy 94.835651 -385.027719) (xy 94.878338 -385.049388) (xy 94.917123 -385.077448) (xy 94.951058 -385.111213)
			(xy 94.979312 -385.149858) (xy 94.990666 -385.170934) (xy 94.991174 -385.17195) (xy 95.07148 -385.310888)
			(xy 95.613728 -385.310888) (xy 95.613728 -385.31038) (xy 95.61412 -385.286385) (xy 95.621631 -385.238985)
			(xy 95.636464 -385.193344) (xy 95.658255 -385.150585) (xy 95.686467 -385.111762) (xy 95.720405 -385.07783)
			(xy 95.759233 -385.049626) (xy 95.801996 -385.027843) (xy 95.847639 -385.013018) (xy 95.89504 -385.005515)
			(xy 95.919036 -385.005072) (xy 95.94297 -385.00555) (xy 95.990254 -385.013006) (xy 96.035797 -385.027745)
			(xy 96.078484 -385.049407) (xy 96.117269 -385.077461) (xy 96.151205 -385.11122) (xy 96.179461 -385.14986)
			(xy 96.190816 -385.170934) (xy 96.191324 -385.17195) (xy 96.27163 -385.310888) (xy 96.813624 -385.310888)
			(xy 96.813624 -385.31038) (xy 96.81402 -385.286385) (xy 96.821531 -385.238985) (xy 96.836364 -385.193345)
			(xy 96.858154 -385.150586) (xy 96.886366 -385.111764) (xy 96.920303 -385.077832) (xy 96.959131 -385.049627)
			(xy 97.001893 -385.027844) (xy 97.047536 -385.013018) (xy 97.094937 -385.005516) (xy 97.118932 -385.005072)
			(xy 97.142866 -385.005554) (xy 97.19015 -385.013009) (xy 97.235693 -385.027747) (xy 97.278379 -385.049408)
			(xy 97.317165 -385.077462) (xy 97.351101 -385.111221) (xy 97.379357 -385.14986) (xy 97.390712 -385.170934)
			(xy 97.39122 -385.17195) (xy 97.471526 -385.310888) (xy 98.01352 -385.310888) (xy 98.01352 -385.31038)
			(xy 98.013921 -385.286372) (xy 98.021439 -385.238949) (xy 98.036288 -385.193287) (xy 98.0581 -385.150512)
			(xy 98.086339 -385.111678) (xy 98.120308 -385.077742) (xy 98.15917 -385.049542) (xy 98.201966 -385.027772)
			(xy 98.247643 -385.012969) (xy 98.295074 -385.005497) (xy 98.319082 -385.005072) (xy 98.343018 -385.005513)
			(xy 98.390303 -385.012976) (xy 98.435847 -385.027721) (xy 98.478534 -385.049389) (xy 98.517319 -385.077449)
			(xy 98.551254 -385.111214) (xy 98.579508 -385.149858) (xy 98.590862 -385.170934) (xy 98.59137 -385.17195)
			(xy 98.671676 -385.310888) (xy 114.586004 -385.310888) (xy 114.586004 -385.31038) (xy 114.586444 -385.286388)
			(xy 114.593954 -385.238994) (xy 114.608785 -385.193359) (xy 114.630572 -385.150605) (xy 114.658779 -385.111786)
			(xy 114.692711 -385.077858) (xy 114.731533 -385.049655) (xy 114.774288 -385.027872) (xy 114.819925 -385.013046)
			(xy 114.86732 -385.005542) (xy 114.891312 -385.005072) (xy 114.915246 -385.00557) (xy 114.962529 -385.013022)
			(xy 115.008071 -385.027757) (xy 115.050758 -385.049416) (xy 115.089544 -385.077467) (xy 115.12348 -385.111224)
			(xy 115.151736 -385.149861) (xy 115.163092 -385.170934) (xy 115.1636 -385.17195) (xy 115.243906 -385.310888)
			(xy 115.7859 -385.310888) (xy 115.7859 -385.31038) (xy 115.786344 -385.286388) (xy 115.793854 -385.238995)
			(xy 115.808684 -385.19336) (xy 115.830471 -385.150606) (xy 115.858677 -385.111788) (xy 115.892609 -385.077859)
			(xy 115.93143 -385.049656) (xy 115.974186 -385.027873) (xy 116.019822 -385.013047) (xy 116.067216 -385.005542)
			(xy 116.091208 -385.005072) (xy 116.115141 -385.005573) (xy 116.162424 -385.013024) (xy 116.207967 -385.027759)
			(xy 116.250653 -385.049417) (xy 116.289439 -385.077468) (xy 116.323376 -385.111224) (xy 116.351632 -385.149861)
			(xy 116.362988 -385.170934) (xy 116.363496 -385.17195) (xy 116.443802 -385.310888) (xy 116.985796 -385.310888)
			(xy 116.985796 -385.31038) (xy 116.986244 -385.286388) (xy 116.993753 -385.238995) (xy 117.008584 -385.193361)
			(xy 117.03037 -385.150608) (xy 117.058576 -385.111789) (xy 117.092507 -385.077861) (xy 117.131328 -385.049658)
			(xy 117.174083 -385.027875) (xy 117.219719 -385.013048) (xy 117.267112 -385.005542) (xy 117.291104 -385.005072)
			(xy 117.315037 -385.005576) (xy 117.36232 -385.013027) (xy 117.407862 -385.027762) (xy 117.450549 -385.049419)
			(xy 117.489335 -385.077469) (xy 117.523272 -385.111225) (xy 117.551528 -385.149861) (xy 117.562884 -385.170934)
			(xy 117.563392 -385.17195) (xy 117.643698 -385.310888) (xy 118.185692 -385.310888) (xy 118.185692 -385.31038)
			(xy 118.186121 -385.286374) (xy 118.193638 -385.238953) (xy 118.208485 -385.193293) (xy 118.230295 -385.15052)
			(xy 118.258531 -385.111687) (xy 118.292496 -385.077752) (xy 118.331354 -385.049552) (xy 118.374147 -385.02778)
			(xy 118.41982 -385.012974) (xy 118.467247 -385.005499) (xy 118.491254 -385.005072) (xy 118.515189 -385.005536)
			(xy 118.562474 -385.012994) (xy 118.608017 -385.027736) (xy 118.650703 -385.0494) (xy 118.689489 -385.077456)
			(xy 118.723424 -385.111218) (xy 118.751679 -385.149859) (xy 118.763034 -385.170934) (xy 118.763542 -385.17195)
			(xy 118.843848 -385.310888) (xy 119.385588 -385.310888) (xy 119.385588 -385.31038) (xy 119.386021 -385.286374)
			(xy 119.393538 -385.238954) (xy 119.408385 -385.193294) (xy 119.430194 -385.150521) (xy 119.45843 -385.111689)
			(xy 119.492394 -385.077754) (xy 119.531252 -385.049553) (xy 119.574044 -385.027781) (xy 119.619717 -385.012975)
			(xy 119.667143 -385.0055) (xy 119.69115 -385.005072) (xy 119.715085 -385.005539) (xy 119.762369 -385.012997)
			(xy 119.807912 -385.027738) (xy 119.850599 -385.049401) (xy 119.889384 -385.077457) (xy 119.92332 -385.111218)
			(xy 119.951575 -385.149859) (xy 119.96293 -385.170934) (xy 119.963438 -385.17195) (xy 120.043744 -385.310888)
			(xy 120.585992 -385.310888) (xy 120.585992 -385.31038) (xy 120.586444 -385.286388) (xy 120.593953 -385.238996)
			(xy 120.608783 -385.193362) (xy 120.630569 -385.150609) (xy 120.658775 -385.11179) (xy 120.692706 -385.077862)
			(xy 120.731526 -385.049659) (xy 120.77428 -385.027876) (xy 120.819915 -385.013049) (xy 120.867308 -385.005543)
			(xy 120.8913 -385.005072) (xy 120.915233 -385.00558) (xy 120.962516 -385.01303) (xy 121.008058 -385.027764)
			(xy 121.050744 -385.04942) (xy 121.089531 -385.07747) (xy 121.123468 -385.111226) (xy 121.151724 -385.149862)
			(xy 121.16308 -385.170934) (xy 121.163588 -385.17195) (xy 121.243894 -385.310888) (xy 121.785888 -385.310888)
			(xy 121.785888 -385.31038) (xy 121.786344 -385.286388) (xy 121.793853 -385.238996) (xy 121.808683 -385.193362)
			(xy 121.830469 -385.15061) (xy 121.858674 -385.111792) (xy 121.892604 -385.077863) (xy 121.931424 -385.04966)
			(xy 121.974177 -385.027877) (xy 122.019812 -385.013049) (xy 122.067204 -385.005543) (xy 122.091196 -385.005072)
			(xy 122.115132 -385.005502) (xy 122.162418 -385.012966) (xy 122.207962 -385.027714) (xy 122.250649 -385.049384)
			(xy 122.289434 -385.077445) (xy 122.323368 -385.111212) (xy 122.351622 -385.149857) (xy 122.362976 -385.170934)
			(xy 122.363484 -385.17195) (xy 122.44379 -385.310888) (xy 122.985784 -385.310888) (xy 122.985784 -385.31038)
			(xy 122.986244 -385.286389) (xy 122.993753 -385.238997) (xy 123.008583 -385.193363) (xy 123.030368 -385.150611)
			(xy 123.058573 -385.111793) (xy 123.092502 -385.077865) (xy 123.131321 -385.049662) (xy 123.174074 -385.027878)
			(xy 123.219709 -385.01305) (xy 123.267101 -385.005543) (xy 123.291092 -385.005072) (xy 123.315028 -385.005505)
			(xy 123.362314 -385.012969) (xy 123.407858 -385.027716) (xy 123.450544 -385.049385) (xy 123.48933 -385.077446)
			(xy 123.523264 -385.111212) (xy 123.551518 -385.149857) (xy 123.562872 -385.170934) (xy 123.56338 -385.17195)
			(xy 123.643686 -385.310888) (xy 124.18568 -385.310888) (xy 124.18568 -385.31038) (xy 124.186121 -385.286374)
			(xy 124.193638 -385.238955) (xy 124.208484 -385.193296) (xy 124.230293 -385.150524) (xy 124.258527 -385.111692)
			(xy 124.292491 -385.077757) (xy 124.331347 -385.049556) (xy 124.374139 -385.027783) (xy 124.41981 -385.012977)
			(xy 124.467236 -385.0055) (xy 124.491242 -385.005072) (xy 124.515176 -385.005545) (xy 124.562461 -385.013002)
			(xy 124.608003 -385.027742) (xy 124.65069 -385.049404) (xy 124.689476 -385.077459) (xy 124.723412 -385.11122)
			(xy 124.751667 -385.14986) (xy 124.763022 -385.170934) (xy 124.76353 -385.17195) (xy 124.843836 -385.310888)
			(xy 125.385576 -385.310888) (xy 125.385576 -385.31038) (xy 125.386021 -385.286374) (xy 125.393538 -385.238955)
			(xy 125.408383 -385.193297) (xy 125.430192 -385.150525) (xy 125.458426 -385.111693) (xy 125.492389 -385.077758)
			(xy 125.531245 -385.049557) (xy 125.574036 -385.027785) (xy 125.619707 -385.012977) (xy 125.667132 -385.0055)
			(xy 125.691138 -385.005072) (xy 125.715072 -385.005549) (xy 125.762356 -385.013005) (xy 125.807899 -385.027744)
			(xy 125.850586 -385.049406) (xy 125.889372 -385.07746) (xy 125.923307 -385.11122) (xy 125.951563 -385.14986)
			(xy 125.962918 -385.170934) (xy 125.963426 -385.17195) (xy 126.043732 -385.310888) (xy 126.58598 -385.310888)
			(xy 126.58598 -385.31038) (xy 126.586444 -385.286389) (xy 126.593953 -385.238998) (xy 126.608782 -385.193364)
			(xy 126.630567 -385.150612) (xy 126.658771 -385.111795) (xy 126.692701 -385.077866) (xy 126.731519 -385.049663)
			(xy 126.774272 -385.027879) (xy 126.819905 -385.013051) (xy 126.867297 -385.005543) (xy 126.891288 -385.005072)
			(xy 126.915224 -385.005508) (xy 126.96251 -385.012972) (xy 127.008053 -385.027718) (xy 127.05074 -385.049387)
			(xy 127.089525 -385.077447) (xy 127.12346 -385.111213) (xy 127.151714 -385.149858) (xy 127.163068 -385.170934)
			(xy 127.163576 -385.17195) (xy 127.243882 -385.310888) (xy 127.785876 -385.310888) (xy 127.785876 -385.31038)
			(xy 127.786344 -385.286389) (xy 127.793853 -385.238998) (xy 127.808682 -385.193365) (xy 127.830467 -385.150614)
			(xy 127.85867 -385.111796) (xy 127.892599 -385.077868) (xy 127.931417 -385.049664) (xy 127.974169 -385.02788)
			(xy 128.019802 -385.013052) (xy 128.067193 -385.005544) (xy 128.091184 -385.005072) (xy 128.11512 -385.005511)
			(xy 128.162406 -385.012974) (xy 128.207949 -385.02772) (xy 128.250636 -385.049388) (xy 128.289421 -385.077448)
			(xy 128.323356 -385.111214) (xy 128.35161 -385.149858) (xy 128.362964 -385.170934) (xy 128.363472 -385.17195)
			(xy 128.443778 -385.310888) (xy 128.985772 -385.310888) (xy 128.985772 -385.31038) (xy 128.986244 -385.286389)
			(xy 128.993753 -385.238999) (xy 129.008581 -385.193366) (xy 129.030366 -385.150615) (xy 129.058569 -385.111797)
			(xy 129.092497 -385.077869) (xy 129.131315 -385.049666) (xy 129.174066 -385.027881) (xy 129.219699 -385.013053)
			(xy 129.267089 -385.005544) (xy 129.29108 -385.005072) (xy 129.315016 -385.005515) (xy 129.362301 -385.012977)
			(xy 129.407845 -385.027722) (xy 129.450531 -385.04939) (xy 129.489317 -385.077449) (xy 129.523252 -385.111214)
			(xy 129.551506 -385.149858) (xy 129.56286 -385.170934) (xy 129.563368 -385.17195) (xy 129.643674 -385.310888)
			(xy 130.185668 -385.310888) (xy 130.185668 -385.31038) (xy 130.186121 -385.286375) (xy 130.193637 -385.238957)
			(xy 130.208483 -385.193299) (xy 130.230291 -385.150527) (xy 130.258524 -385.111696) (xy 130.292486 -385.077761)
			(xy 130.331341 -385.04956) (xy 130.37413 -385.027787) (xy 130.4198 -385.012979) (xy 130.467224 -385.005501)
			(xy 130.49123 -385.005072) (xy 130.515164 -385.005555) (xy 130.562448 -385.01301) (xy 130.60799 -385.027748)
			(xy 130.650677 -385.049409) (xy 130.689463 -385.077462) (xy 130.723399 -385.111221) (xy 130.751655 -385.14986)
			(xy 130.76301 -385.170934) (xy 130.763518 -385.17195) (xy 130.843824 -385.310888) (xy 131.385564 -385.310888)
			(xy 131.385564 -385.31038) (xy 131.386021 -385.286375) (xy 131.393537 -385.238957) (xy 131.408382 -385.1933)
			(xy 131.43019 -385.150528) (xy 131.458422 -385.111697) (xy 131.492384 -385.077762) (xy 131.531239 -385.049561)
			(xy 131.574027 -385.027788) (xy 131.619697 -385.01298) (xy 131.667121 -385.005501) (xy 131.691126 -385.005072)
			(xy 131.71506 -385.005558) (xy 131.762344 -385.013013) (xy 131.807886 -385.02775) (xy 131.850573 -385.04941)
			(xy 131.889359 -385.077463) (xy 131.923295 -385.111222) (xy 131.951551 -385.14986) (xy 131.962906 -385.170934)
			(xy 131.963414 -385.17195) (xy 132.04372 -385.310888) (xy 132.585968 -385.310888) (xy 132.585968 -385.31038)
			(xy 132.586444 -385.286389) (xy 132.593952 -385.238999) (xy 132.608781 -385.193367) (xy 132.630565 -385.150616)
			(xy 132.658768 -385.111799) (xy 132.692696 -385.077871) (xy 132.731513 -385.049667) (xy 132.774263 -385.027883)
			(xy 132.819895 -385.013053) (xy 132.867285 -385.005544) (xy 132.891276 -385.005072) (xy 132.915211 -385.005518)
			(xy 132.962497 -385.01298) (xy 133.00804 -385.027724) (xy 133.050727 -385.049391) (xy 133.089512 -385.07745)
			(xy 133.123447 -385.111215) (xy 133.151701 -385.149858) (xy 133.163056 -385.170934) (xy 133.163564 -385.17195)
			(xy 133.24387 -385.310888) (xy 147.113752 -385.310888) (xy 147.113752 -385.31038) (xy 147.114244 -385.28639)
			(xy 147.121752 -385.239002) (xy 147.13658 -385.193371) (xy 147.158362 -385.150621) (xy 147.186563 -385.111804)
			(xy 147.220489 -385.077876) (xy 147.259304 -385.049673) (xy 147.302052 -385.027887) (xy 147.347682 -385.013057)
			(xy 147.39507 -385.005546) (xy 147.41906 -385.005072) (xy 147.442995 -385.005531) (xy 147.49028 -385.01299)
			(xy 147.535823 -385.027733) (xy 147.57851 -385.049398) (xy 147.617295 -385.077455) (xy 147.651231 -385.111217)
			(xy 147.679485 -385.149859) (xy 147.69084 -385.170934) (xy 147.691348 -385.17195) (xy 147.771654 -385.310888)
			(xy 148.313648 -385.310888) (xy 148.313648 -385.31038) (xy 148.314144 -385.28639) (xy 148.321652 -385.239002)
			(xy 148.336479 -385.193372) (xy 148.358261 -385.150622) (xy 148.386462 -385.111805) (xy 148.420387 -385.077878)
			(xy 148.459201 -385.049674) (xy 148.501949 -385.027888) (xy 148.547579 -385.013057) (xy 148.594966 -385.005546)
			(xy 148.618956 -385.005072) (xy 148.642891 -385.005534) (xy 148.690176 -385.012993) (xy 148.735719 -385.027735)
			(xy 148.778405 -385.049399) (xy 148.817191 -385.077456) (xy 148.851126 -385.111218) (xy 148.879381 -385.149859)
			(xy 148.890736 -385.170934) (xy 148.891244 -385.17195) (xy 148.97155 -385.310888) (xy 149.513544 -385.310888)
			(xy 149.513544 -385.31038) (xy 149.514044 -385.286391) (xy 149.521552 -385.239003) (xy 149.536379 -385.193373)
			(xy 149.558161 -385.150623) (xy 149.586361 -385.111807) (xy 149.620286 -385.077879) (xy 149.659099 -385.049675)
			(xy 149.701847 -385.02789) (xy 149.747476 -385.013058) (xy 149.794863 -385.005546) (xy 149.818852 -385.005072)
			(xy 149.842787 -385.005537) (xy 149.890071 -385.012995) (xy 149.935614 -385.027737) (xy 149.978301 -385.049401)
			(xy 150.017087 -385.077457) (xy 150.051022 -385.111218) (xy 150.079277 -385.149859) (xy 150.090632 -385.170934)
			(xy 150.09114 -385.17195) (xy 150.171446 -385.310888) (xy 150.71344 -385.310888) (xy 150.71344 -385.31038)
			(xy 150.713821 -385.286371) (xy 150.72134 -385.238946) (xy 150.73619 -385.193282) (xy 150.758004 -385.150506)
			(xy 150.786245 -385.111671) (xy 150.820216 -385.077735) (xy 150.859081 -385.049535) (xy 150.90188 -385.027766)
			(xy 150.94756 -385.012965) (xy 150.994993 -385.005496) (xy 151.019002 -385.005072) (xy 151.042935 -385.005578)
			(xy 151.090218 -385.013028) (xy 151.13576 -385.027763) (xy 151.178447 -385.04942) (xy 151.217233 -385.077469)
			(xy 151.25117 -385.111225) (xy 151.279426 -385.149861) (xy 151.290782 -385.170934) (xy 151.29129 -385.17195)
			(xy 151.371596 -385.310888) (xy 151.913336 -385.310888) (xy 151.913336 -385.31038) (xy 151.913721 -385.286371)
			(xy 151.92124 -385.238947) (xy 151.936089 -385.193283) (xy 151.957903 -385.150507) (xy 151.986144 -385.111672)
			(xy 152.020115 -385.077737) (xy 152.058979 -385.049537) (xy 152.101777 -385.027767) (xy 152.147456 -385.012965)
			(xy 152.194889 -385.005496) (xy 152.218898 -385.005072) (xy 152.242834 -385.0055) (xy 152.290121 -385.012965)
			(xy 152.335664 -385.027713) (xy 152.378351 -385.049383) (xy 152.417136 -385.077445) (xy 152.45107 -385.111212)
			(xy 152.479324 -385.149857) (xy 152.490678 -385.170934) (xy 152.491186 -385.17195) (xy 152.571492 -385.310888)
			(xy 153.11374 -385.310888) (xy 153.11374 -385.31038) (xy 153.11412 -385.286384) (xy 153.121631 -385.238983)
			(xy 153.136465 -385.193341) (xy 153.158257 -385.150582) (xy 153.18647 -385.111758) (xy 153.22041 -385.077826)
			(xy 153.25924 -385.049622) (xy 153.302004 -385.027839) (xy 153.347649 -385.013015) (xy 153.395052 -385.005515)
			(xy 153.419048 -385.005072) (xy 153.442983 -385.005541) (xy 153.490267 -385.012998) (xy 153.53581 -385.027739)
			(xy 153.578497 -385.049402) (xy 153.617282 -385.077458) (xy 153.651218 -385.111219) (xy 153.679473 -385.149859)
			(xy 153.690828 -385.170934) (xy 153.691336 -385.17195) (xy 153.771642 -385.310888) (xy 154.313636 -385.310888)
			(xy 154.313636 -385.31038) (xy 154.31402 -385.286384) (xy 154.321531 -385.238984) (xy 154.336365 -385.193342)
			(xy 154.358157 -385.150583) (xy 154.386369 -385.111759) (xy 154.420308 -385.077828) (xy 154.459138 -385.049623)
			(xy 154.501901 -385.02784) (xy 154.547546 -385.013016) (xy 154.594948 -385.005515) (xy 154.618944 -385.005072)
			(xy 154.642878 -385.005544) (xy 154.690163 -385.013001) (xy 154.735706 -385.027741) (xy 154.778392 -385.049404)
			(xy 154.817178 -385.077459) (xy 154.851114 -385.111219) (xy 154.879369 -385.14986) (xy 154.890724 -385.170934)
			(xy 154.891232 -385.17195) (xy 154.971538 -385.310888) (xy 155.513532 -385.310888) (xy 155.513532 -385.31038)
			(xy 155.51392 -385.286384) (xy 155.521431 -385.238984) (xy 155.536265 -385.193343) (xy 155.558056 -385.150584)
			(xy 155.586268 -385.111761) (xy 155.620206 -385.077829) (xy 155.659035 -385.049624) (xy 155.701798 -385.027842)
			(xy 155.747443 -385.013017) (xy 155.794844 -385.005515) (xy 155.81884 -385.005072) (xy 155.842774 -385.005547)
			(xy 155.890059 -385.013003) (xy 155.935601 -385.027743) (xy 155.978288 -385.049405) (xy 156.017074 -385.07746)
			(xy 156.05101 -385.11122) (xy 156.079265 -385.14986) (xy 156.09062 -385.170934) (xy 156.091128 -385.17195)
			(xy 156.171434 -385.310888) (xy 156.713428 -385.310888) (xy 156.713428 -385.31038) (xy 156.713821 -385.286372)
			(xy 156.721339 -385.238948) (xy 156.736188 -385.193285) (xy 156.758002 -385.150509) (xy 156.786241 -385.111675)
			(xy 156.820211 -385.07774) (xy 156.859074 -385.049539) (xy 156.901872 -385.02777) (xy 156.94755 -385.012967)
			(xy 156.994981 -385.005497) (xy 157.01899 -385.005072) (xy 157.042926 -385.005506) (xy 157.090212 -385.01297)
			(xy 157.135756 -385.027717) (xy 157.178442 -385.049386) (xy 157.217227 -385.077447) (xy 157.251162 -385.111213)
			(xy 157.279416 -385.149857) (xy 157.29077 -385.170934) (xy 157.291278 -385.17195) (xy 157.371584 -385.310888)
			(xy 157.913324 -385.310888) (xy 157.913324 -385.31038) (xy 157.913721 -385.286372) (xy 157.921239 -385.238948)
			(xy 157.936088 -385.193286) (xy 157.957901 -385.15051) (xy 157.98614 -385.111676) (xy 158.020109 -385.077741)
			(xy 158.058972 -385.049541) (xy 158.101769 -385.027771) (xy 158.147446 -385.012968) (xy 158.194878 -385.005497)
			(xy 158.218886 -385.005072) (xy 158.242822 -385.00551) (xy 158.290108 -385.012973) (xy 158.335651 -385.027719)
			(xy 158.378338 -385.049388) (xy 158.417123 -385.077448) (xy 158.451058 -385.111213) (xy 158.479312 -385.149858)
			(xy 158.490666 -385.170934) (xy 158.491174 -385.17195) (xy 158.57148 -385.310888) (xy 159.113728 -385.310888)
			(xy 159.113728 -385.31038) (xy 159.11412 -385.286385) (xy 159.121631 -385.238985) (xy 159.136464 -385.193344)
			(xy 159.158255 -385.150585) (xy 159.186467 -385.111762) (xy 159.220405 -385.07783) (xy 159.259233 -385.049626)
			(xy 159.301996 -385.027843) (xy 159.347639 -385.013018) (xy 159.39504 -385.005515) (xy 159.419036 -385.005072)
			(xy 159.44297 -385.00555) (xy 159.490254 -385.013006) (xy 159.535797 -385.027745) (xy 159.578484 -385.049407)
			(xy 159.617269 -385.077461) (xy 159.651205 -385.11122) (xy 159.679461 -385.14986) (xy 159.690816 -385.170934)
			(xy 159.691324 -385.17195) (xy 159.77163 -385.310888) (xy 160.313624 -385.310888) (xy 160.313624 -385.31038)
			(xy 160.31402 -385.286385) (xy 160.321531 -385.238985) (xy 160.336364 -385.193345) (xy 160.358154 -385.150586)
			(xy 160.386366 -385.111764) (xy 160.420303 -385.077832) (xy 160.459131 -385.049627) (xy 160.501893 -385.027844)
			(xy 160.547536 -385.013018) (xy 160.594937 -385.005516) (xy 160.618932 -385.005072) (xy 160.642866 -385.005554)
			(xy 160.69015 -385.013009) (xy 160.735693 -385.027747) (xy 160.778379 -385.049408) (xy 160.817165 -385.077462)
			(xy 160.851101 -385.111221) (xy 160.879357 -385.14986) (xy 160.890712 -385.170934) (xy 160.89122 -385.17195)
			(xy 160.971526 -385.310888) (xy 161.51352 -385.310888) (xy 161.51352 -385.31038) (xy 161.51392 -385.286385)
			(xy 161.52143 -385.238986) (xy 161.536263 -385.193346) (xy 161.558054 -385.150588) (xy 161.586265 -385.111765)
			(xy 161.620201 -385.077833) (xy 161.659029 -385.049629) (xy 161.70179 -385.027845) (xy 161.747433 -385.013019)
			(xy 161.794833 -385.005516) (xy 161.818828 -385.005072) (xy 161.842762 -385.005557) (xy 161.890046 -385.013011)
			(xy 161.935588 -385.027749) (xy 161.978275 -385.04941) (xy 162.017061 -385.077463) (xy 162.050997 -385.111222)
			(xy 162.079253 -385.14986) (xy 162.090608 -385.170934) (xy 162.091116 -385.17195) (xy 162.171422 -385.310888)
			(xy 162.713416 -385.310888) (xy 162.713416 -385.31038) (xy 162.713821 -385.286372) (xy 162.721339 -385.238949)
			(xy 162.736187 -385.193288) (xy 162.757999 -385.150513) (xy 162.786238 -385.111679) (xy 162.820206 -385.077744)
			(xy 162.859067 -385.049543) (xy 162.901864 -385.027773) (xy 162.94754 -385.012969) (xy 162.99497 -385.005497)
			(xy 163.018978 -385.005072) (xy 163.042913 -385.005516) (xy 163.090199 -385.012978) (xy 163.135743 -385.027723)
			(xy 163.178429 -385.049391) (xy 163.217215 -385.07745) (xy 163.251149 -385.111214) (xy 163.279404 -385.149858)
			(xy 163.290758 -385.170934) (xy 163.291266 -385.17195) (xy 163.371572 -385.310888) (xy 163.913312 -385.310888)
			(xy 163.913312 -385.31038) (xy 163.913721 -385.286373) (xy 163.921239 -385.23895) (xy 163.936087 -385.193289)
			(xy 163.957899 -385.150514) (xy 163.986137 -385.111681) (xy 164.020104 -385.077745) (xy 164.058965 -385.049545)
			(xy 164.101761 -385.027774) (xy 164.147436 -385.01297) (xy 164.194866 -385.005498) (xy 164.218874 -385.005072)
			(xy 164.242809 -385.005519) (xy 164.290095 -385.012981) (xy 164.335638 -385.027726) (xy 164.378325 -385.049392)
			(xy 164.41711 -385.077451) (xy 164.451045 -385.111215) (xy 164.479299 -385.149858) (xy 164.490654 -385.170934)
			(xy 164.491162 -385.17195) (xy 164.571468 -385.310888) (xy 165.113716 -385.310888) (xy 165.113716 -385.31038)
			(xy 165.11412 -385.286385) (xy 165.12163 -385.238987) (xy 165.136463 -385.193347) (xy 165.158253 -385.150589)
			(xy 165.186463 -385.111766) (xy 165.2204 -385.077835) (xy 165.259226 -385.04963) (xy 165.301987 -385.027846)
			(xy 165.347629 -385.01302) (xy 165.395029 -385.005516) (xy 165.419024 -385.005072) (xy 165.442958 -385.00556)
			(xy 165.490242 -385.013014) (xy 165.535784 -385.027751) (xy 165.578471 -385.049411) (xy 165.617257 -385.077464)
			(xy 165.651193 -385.111222) (xy 165.679449 -385.14986) (xy 165.690804 -385.170934) (xy 165.691312 -385.17195)
			(xy 166.083742 -385.850892) (xy 166.096567 -385.874224) (xy 166.114787 -385.924247) (xy 166.124047 -385.976673)
			(xy 166.124636 -386.003292) (xy 166.124154 -386.027296) (xy 166.116641 -386.074713) (xy 166.1018 -386.12037)
			(xy 166.079996 -386.163141) (xy 166.051766 -386.201973) (xy 166.017807 -386.235908) (xy 165.978955 -386.26411)
			(xy 165.936168 -386.285883) (xy 165.890501 -386.300692) (xy 165.843079 -386.308171) (xy 165.819074 -386.3086)
			(xy 165.795499 -386.308227) (xy 165.74891 -386.300982) (xy 165.703991 -386.286652) (xy 165.661813 -386.26558)
			(xy 165.62338 -386.238267) (xy 165.589609 -386.205365) (xy 165.561304 -386.167657) (xy 165.549834 -386.147056)
			(xy 165.549326 -386.146294) (xy 165.151562 -385.457954) (xy 165.139704 -385.435268) (xy 165.122846 -385.38694)
			(xy 165.114266 -385.33648) (xy 165.113716 -385.310888) (xy 164.571468 -385.310888) (xy 164.883592 -385.850892)
			(xy 164.896342 -385.874249) (xy 164.914451 -385.924281) (xy 164.923654 -385.976688) (xy 164.924232 -386.003292)
			(xy 164.92373 -386.027282) (xy 164.916226 -386.074671) (xy 164.901401 -386.120303) (xy 164.879621 -386.163054)
			(xy 164.851421 -386.201871) (xy 164.817496 -386.2358) (xy 164.778681 -386.264004) (xy 164.735932 -386.285789)
			(xy 164.690302 -386.300618) (xy 164.642914 -386.308128) (xy 164.618924 -386.3086) (xy 164.595351 -386.308187)
			(xy 164.548763 -386.300949) (xy 164.503845 -386.286627) (xy 164.461667 -386.265561) (xy 164.423233 -386.238255)
			(xy 164.389461 -386.205358) (xy 164.361155 -386.167655) (xy 164.349684 -386.147056) (xy 164.349176 -386.146294)
			(xy 163.951412 -385.457954) (xy 163.939479 -385.435295) (xy 163.922547 -385.386965) (xy 163.913895 -385.336491)
			(xy 163.913312 -385.310888) (xy 163.371572 -385.310888) (xy 163.683696 -385.850892) (xy 163.696446 -385.874249)
			(xy 163.714555 -385.924281) (xy 163.723758 -385.976688) (xy 163.724336 -386.003292) (xy 163.72383 -386.027282)
			(xy 163.716326 -386.07467) (xy 163.701501 -386.120302) (xy 163.679721 -386.163053) (xy 163.651522 -386.20187)
			(xy 163.617597 -386.235798) (xy 163.578783 -386.264002) (xy 163.536035 -386.285788) (xy 163.490405 -386.300618)
			(xy 163.443018 -386.308127) (xy 163.419028 -386.3086) (xy 163.395455 -386.308184) (xy 163.348868 -386.300946)
			(xy 163.30395 -386.286625) (xy 163.261771 -386.26556) (xy 163.223338 -386.238254) (xy 163.189565 -386.205357)
			(xy 163.161259 -386.167654) (xy 163.149788 -386.147056) (xy 163.14928 -386.146294) (xy 162.751516 -385.457954)
			(xy 162.739583 -385.435294) (xy 162.722652 -385.386965) (xy 162.713999 -385.336491) (xy 162.713416 -385.310888)
			(xy 162.171422 -385.310888) (xy 162.483546 -385.850892) (xy 162.496371 -385.874224) (xy 162.514591 -385.924247)
			(xy 162.523851 -385.976673) (xy 162.52444 -386.003292) (xy 162.523954 -386.027296) (xy 162.516441 -386.074713)
			(xy 162.5016 -386.120369) (xy 162.479796 -386.16314) (xy 162.451567 -386.201972) (xy 162.417609 -386.235907)
			(xy 162.378757 -386.264108) (xy 162.335971 -386.285882) (xy 162.290304 -386.300691) (xy 162.242882 -386.30817)
			(xy 162.218878 -386.3086) (xy 162.195303 -386.308224) (xy 162.148714 -386.300979) (xy 162.103795 -386.28665)
			(xy 162.061617 -386.265579) (xy 162.023184 -386.238266) (xy 161.989413 -386.205364) (xy 161.961108 -386.167657)
			(xy 161.949638 -386.147056) (xy 161.94913 -386.146294) (xy 161.551366 -385.457954) (xy 161.539508 -385.435268)
			(xy 161.52265 -385.38694) (xy 161.51407 -385.33648) (xy 161.51352 -385.310888) (xy 160.971526 -385.310888)
			(xy 161.28365 -385.850892) (xy 161.296476 -385.874224) (xy 161.314695 -385.924247) (xy 161.323955 -385.976673)
			(xy 161.324544 -386.003292) (xy 161.324054 -386.027296) (xy 161.316541 -386.074712) (xy 161.301701 -386.120368)
			(xy 161.279897 -386.163139) (xy 161.251669 -386.20197) (xy 161.21771 -386.235905) (xy 161.17886 -386.264107)
			(xy 161.136074 -386.285881) (xy 161.090407 -386.30069) (xy 161.042986 -386.30817) (xy 161.018982 -386.3086)
			(xy 160.995407 -386.308221) (xy 160.948819 -386.300977) (xy 160.9039 -386.286648) (xy 160.861721 -386.265577)
			(xy 160.823288 -386.238265) (xy 160.789517 -386.205364) (xy 160.761212 -386.167657) (xy 160.749742 -386.147056)
			(xy 160.749234 -386.146294) (xy 160.35147 -385.457954) (xy 160.339612 -385.435268) (xy 160.322755 -385.386939)
			(xy 160.314174 -385.33648) (xy 160.313624 -385.310888) (xy 159.77163 -385.310888) (xy 160.083754 -385.850892)
			(xy 160.09658 -385.874224) (xy 160.114799 -385.924247) (xy 160.124059 -385.976673) (xy 160.124648 -386.003292)
			(xy 160.124154 -386.027296) (xy 160.116641 -386.074711) (xy 160.101801 -386.120367) (xy 160.079998 -386.163138)
			(xy 160.05177 -386.201969) (xy 160.017812 -386.235904) (xy 159.978962 -386.264106) (xy 159.936177 -386.28588)
			(xy 159.890511 -386.30069) (xy 159.84309 -386.30817) (xy 159.819086 -386.3086) (xy 159.795512 -386.308217)
			(xy 159.748923 -386.300974) (xy 159.704004 -386.286646) (xy 159.661826 -386.265576) (xy 159.623393 -386.238264)
			(xy 159.589621 -386.205363) (xy 159.561316 -386.167656) (xy 159.549846 -386.147056) (xy 159.549338 -386.146294)
			(xy 159.151574 -385.457954) (xy 159.139717 -385.435268) (xy 159.122859 -385.386939) (xy 159.114278 -385.336479)
			(xy 159.113728 -385.310888) (xy 158.57148 -385.310888) (xy 158.883604 -385.850892) (xy 158.896355 -385.874249)
			(xy 158.914464 -385.924281) (xy 158.923666 -385.976688) (xy 158.924244 -386.003292) (xy 158.92373 -386.027281)
			(xy 158.916226 -386.074669) (xy 158.901402 -386.1203) (xy 158.879623 -386.16305) (xy 158.851424 -386.201867)
			(xy 158.817501 -386.235796) (xy 158.778688 -386.264) (xy 158.735941 -386.285785) (xy 158.690312 -386.300616)
			(xy 158.642925 -386.308127) (xy 158.618936 -386.3086) (xy 158.595363 -386.308177) (xy 158.548776 -386.300941)
			(xy 158.503858 -386.286621) (xy 158.46168 -386.265557) (xy 158.423246 -386.238252) (xy 158.389474 -386.205356)
			(xy 158.361167 -386.167654) (xy 158.349696 -386.147056) (xy 158.349188 -386.146294) (xy 157.951424 -385.457954)
			(xy 157.939492 -385.435294) (xy 157.92256 -385.386965) (xy 157.913907 -385.336491) (xy 157.913324 -385.310888)
			(xy 157.371584 -385.310888) (xy 157.683708 -385.850892) (xy 157.696459 -385.874248) (xy 157.714568 -385.924281)
			(xy 157.72377 -385.976688) (xy 157.724348 -386.003292) (xy 157.72383 -386.027281) (xy 157.716326 -386.074669)
			(xy 157.701503 -386.120299) (xy 157.679724 -386.163049) (xy 157.651525 -386.201866) (xy 157.617603 -386.235794)
			(xy 157.57879 -386.263998) (xy 157.536043 -386.285784) (xy 157.490415 -386.300615) (xy 157.443029 -386.308126)
			(xy 157.41904 -386.3086) (xy 157.395467 -386.308174) (xy 157.34888 -386.300939) (xy 157.303963 -386.286618)
			(xy 157.261784 -386.265555) (xy 157.223351 -386.238251) (xy 157.189578 -386.205355) (xy 157.161271 -386.167654)
			(xy 157.1498 -386.147056) (xy 157.149292 -386.146294) (xy 156.751528 -385.457954) (xy 156.739596 -385.435294)
			(xy 156.722664 -385.386965) (xy 156.714011 -385.336491) (xy 156.713428 -385.310888) (xy 156.171434 -385.310888)
			(xy 156.483558 -385.850892) (xy 156.496384 -385.874224) (xy 156.514604 -385.924247) (xy 156.523863 -385.976673)
			(xy 156.524452 -386.003292) (xy 156.523954 -386.027295) (xy 156.516442 -386.074711) (xy 156.501601 -386.120366)
			(xy 156.479799 -386.163137) (xy 156.451571 -386.201968) (xy 156.417614 -386.235902) (xy 156.378764 -386.264104)
			(xy 156.335979 -386.285879) (xy 156.290314 -386.300689) (xy 156.242894 -386.308169) (xy 156.21889 -386.3086)
			(xy 156.195316 -386.308214) (xy 156.148727 -386.300971) (xy 156.103808 -386.286644) (xy 156.06163 -386.265574)
			(xy 156.023197 -386.238263) (xy 155.989426 -386.205363) (xy 155.96112 -386.167656) (xy 155.94965 -386.147056)
			(xy 155.949142 -386.146294) (xy 155.551378 -385.457954) (xy 155.539521 -385.435268) (xy 155.522663 -385.386939)
			(xy 155.514082 -385.336479) (xy 155.513532 -385.310888) (xy 154.971538 -385.310888) (xy 155.283662 -385.850892)
			(xy 155.296489 -385.874224) (xy 155.314708 -385.924247) (xy 155.323967 -385.976673) (xy 155.324556 -386.003292)
			(xy 155.324054 -386.027295) (xy 155.316542 -386.07471) (xy 155.301702 -386.120365) (xy 155.279899 -386.163135)
			(xy 155.251672 -386.201966) (xy 155.217715 -386.235901) (xy 155.178866 -386.264103) (xy 155.136082 -386.285878)
			(xy 155.090417 -386.300688) (xy 155.042998 -386.308169) (xy 155.018994 -386.3086) (xy 154.99542 -386.308211)
			(xy 154.948831 -386.300969) (xy 154.903913 -386.286642) (xy 154.861734 -386.265573) (xy 154.823301 -386.238262)
			(xy 154.78953 -386.205362) (xy 154.761224 -386.167656) (xy 154.749754 -386.147056) (xy 154.749246 -386.146294)
			(xy 154.351482 -385.457954) (xy 154.339625 -385.435268) (xy 154.322767 -385.386939) (xy 154.314186 -385.336479)
			(xy 154.313636 -385.310888) (xy 153.771642 -385.310888) (xy 154.083766 -385.850892) (xy 154.096593 -385.874223)
			(xy 154.114812 -385.924247) (xy 154.124071 -385.976673) (xy 154.12466 -386.003292) (xy 154.124253 -386.0273)
			(xy 154.116738 -386.074724) (xy 154.101893 -386.120388) (xy 154.080082 -386.163164) (xy 154.051844 -386.201999)
			(xy 154.017875 -386.235935) (xy 153.979013 -386.264136) (xy 153.936216 -386.285905) (xy 153.890538 -386.300707)
			(xy 153.843106 -386.308176) (xy 153.819098 -386.3086) (xy 153.795524 -386.308208) (xy 153.748936 -386.300966)
			(xy 153.704017 -386.28664) (xy 153.661839 -386.265571) (xy 153.623406 -386.238261) (xy 153.589634 -386.205361)
			(xy 153.561328 -386.167656) (xy 153.549858 -386.147056) (xy 153.54935 -386.146294) (xy 153.151586 -385.457954)
			(xy 153.13973 -385.435267) (xy 153.122871 -385.386939) (xy 153.11429 -385.336479) (xy 153.11374 -385.310888)
			(xy 152.571492 -385.310888) (xy 152.883616 -385.850892) (xy 152.896368 -385.874248) (xy 152.914476 -385.924281)
			(xy 152.923678 -385.976688) (xy 152.924256 -386.003292) (xy 152.92373 -386.027281) (xy 152.916227 -386.074667)
			(xy 152.901403 -386.120297) (xy 152.879625 -386.163047) (xy 152.851428 -386.201863) (xy 152.817506 -386.235791)
			(xy 152.778694 -386.263996) (xy 152.735949 -386.285782) (xy 152.690322 -386.300614) (xy 152.642937 -386.308126)
			(xy 152.618948 -386.3086) (xy 152.595375 -386.308168) (xy 152.548789 -386.300933) (xy 152.503871 -386.286614)
			(xy 152.461693 -386.265552) (xy 152.423259 -386.238248) (xy 152.389486 -386.205354) (xy 152.361179 -386.167654)
			(xy 152.349708 -386.147056) (xy 152.3492 -386.146294) (xy 151.951436 -385.457954) (xy 151.939505 -385.435294)
			(xy 151.922572 -385.386964) (xy 151.913919 -385.336491) (xy 151.913336 -385.310888) (xy 151.371596 -385.310888)
			(xy 151.68372 -385.850892) (xy 151.696472 -385.874248) (xy 151.71458 -385.924281) (xy 151.723782 -385.976688)
			(xy 151.72436 -386.003292) (xy 151.723954 -386.027287) (xy 151.716447 -386.074687) (xy 151.701617 -386.120329)
			(xy 151.679828 -386.163088) (xy 151.651618 -386.201912) (xy 151.617682 -386.235844) (xy 151.578854 -386.264049)
			(xy 151.536092 -386.285832) (xy 151.490448 -386.300657) (xy 151.443047 -386.308157) (xy 151.419052 -386.3086)
			(xy 151.395479 -386.308164) (xy 151.348893 -386.300931) (xy 151.303976 -386.286612) (xy 151.261797 -386.265551)
			(xy 151.223364 -386.238247) (xy 151.189591 -386.205354) (xy 151.161283 -386.167653) (xy 151.149812 -386.147056)
			(xy 151.149304 -386.146294) (xy 150.75154 -385.457954) (xy 150.739609 -385.435293) (xy 150.722676 -385.386964)
			(xy 150.714023 -385.336491) (xy 150.71344 -385.310888) (xy 150.171446 -385.310888) (xy 150.48357 -385.850892)
			(xy 150.496397 -385.874223) (xy 150.514616 -385.924247) (xy 150.523875 -385.976673) (xy 150.524464 -386.003292)
			(xy 150.524053 -386.0273) (xy 150.516539 -386.074724) (xy 150.501693 -386.120387) (xy 150.479883 -386.163163)
			(xy 150.451645 -386.201998) (xy 150.417677 -386.235934) (xy 150.378815 -386.264134) (xy 150.336018 -386.285904)
			(xy 150.290341 -386.300706) (xy 150.24291 -386.308176) (xy 150.218902 -386.3086) (xy 150.195328 -386.308205)
			(xy 150.14874 -386.300963) (xy 150.103821 -386.286638) (xy 150.061643 -386.26557) (xy 150.02321 -386.23826)
			(xy 149.989438 -386.205361) (xy 149.961133 -386.167656) (xy 149.949662 -386.147056) (xy 149.949154 -386.146294)
			(xy 149.55139 -385.457954) (xy 149.539534 -385.435267) (xy 149.522675 -385.386939) (xy 149.514094 -385.336479)
			(xy 149.513544 -385.310888) (xy 148.97155 -385.310888) (xy 149.283674 -385.850892) (xy 149.296501 -385.874223)
			(xy 149.31472 -385.924247) (xy 149.323979 -385.976673) (xy 149.324568 -386.003292) (xy 149.324153 -386.0273)
			(xy 149.316639 -386.074723) (xy 149.301793 -386.120386) (xy 149.279983 -386.163162) (xy 149.251746 -386.201996)
			(xy 149.217779 -386.235932) (xy 149.178917 -386.264133) (xy 149.136121 -386.285903) (xy 149.090445 -386.300706)
			(xy 149.043014 -386.308176) (xy 149.019006 -386.3086) (xy 148.995432 -386.308201) (xy 148.948844 -386.300961)
			(xy 148.903926 -386.286636) (xy 148.861747 -386.265568) (xy 148.823314 -386.238259) (xy 148.789542 -386.20536)
			(xy 148.761237 -386.167655) (xy 148.749766 -386.147056) (xy 148.749258 -386.146294) (xy 148.351494 -385.457954)
			(xy 148.339638 -385.435267) (xy 148.322779 -385.386939) (xy 148.314198 -385.336479) (xy 148.313648 -385.310888)
			(xy 147.771654 -385.310888) (xy 148.083778 -385.850892) (xy 148.096606 -385.874223) (xy 148.114824 -385.924247)
			(xy 148.124083 -385.976673) (xy 148.124672 -386.003292) (xy 148.124253 -386.027299) (xy 148.116739 -386.074723)
			(xy 148.101894 -386.120385) (xy 148.080084 -386.163161) (xy 148.051848 -386.201995) (xy 148.01788 -386.235931)
			(xy 147.97902 -386.264132) (xy 147.936224 -386.285902) (xy 147.890548 -386.300705) (xy 147.843118 -386.308175)
			(xy 147.81911 -386.3086) (xy 147.795536 -386.308198) (xy 147.748948 -386.300958) (xy 147.70403 -386.286634)
			(xy 147.661852 -386.265566) (xy 147.623418 -386.238258) (xy 147.589647 -386.20536) (xy 147.561341 -386.167655)
			(xy 147.54987 -386.147056) (xy 147.549362 -386.146294) (xy 147.151598 -385.457954) (xy 147.139742 -385.435267)
			(xy 147.122883 -385.386939) (xy 147.114302 -385.336479) (xy 147.113752 -385.310888) (xy 133.24387 -385.310888)
			(xy 133.555994 -385.850892) (xy 133.568823 -385.874222) (xy 133.587041 -385.924246) (xy 133.596299 -385.976673)
			(xy 133.596888 -386.003292) (xy 133.596453 -386.027299) (xy 133.588939 -386.07472) (xy 133.574095 -386.120381)
			(xy 133.552287 -386.163156) (xy 133.524052 -386.20199) (xy 133.490087 -386.235925) (xy 133.451229 -386.264126)
			(xy 133.408435 -386.285897) (xy 133.362761 -386.300702) (xy 133.315333 -386.308174) (xy 133.291326 -386.3086)
			(xy 133.267753 -386.308185) (xy 133.221165 -386.300948) (xy 133.176247 -386.286626) (xy 133.134069 -386.26556)
			(xy 133.095636 -386.238254) (xy 133.061863 -386.205357) (xy 133.033557 -386.167655) (xy 133.022086 -386.147056)
			(xy 133.021578 -386.146294) (xy 132.623814 -385.457954) (xy 132.611952 -385.43527) (xy 132.595097 -385.38694)
			(xy 132.586517 -385.33648) (xy 132.585968 -385.310888) (xy 132.04372 -385.310888) (xy 132.355844 -385.850892)
			(xy 132.368598 -385.874247) (xy 132.386705 -385.92428) (xy 132.395906 -385.976688) (xy 132.396484 -386.003292)
			(xy 132.396054 -386.027286) (xy 132.388548 -386.074684) (xy 132.373719 -386.120323) (xy 132.351933 -386.163081)
			(xy 132.323725 -386.201904) (xy 132.289792 -386.235836) (xy 132.250967 -386.264041) (xy 132.208208 -386.285825)
			(xy 132.162568 -386.300652) (xy 132.11517 -386.308156) (xy 132.091176 -386.3086) (xy 132.067601 -386.308226)
			(xy 132.021012 -386.30098) (xy 131.976093 -386.286651) (xy 131.933915 -386.265579) (xy 131.895482 -386.238267)
			(xy 131.861711 -386.205365) (xy 131.833406 -386.167657) (xy 131.821936 -386.147056) (xy 131.821428 -386.146294)
			(xy 131.423664 -385.457954) (xy 131.411735 -385.435292) (xy 131.394801 -385.386964) (xy 131.386148 -385.336491)
			(xy 131.385564 -385.310888) (xy 130.843824 -385.310888) (xy 131.155948 -385.850892) (xy 131.168702 -385.874247)
			(xy 131.186809 -385.92428) (xy 131.19601 -385.976688) (xy 131.196588 -386.003292) (xy 131.196154 -386.027286)
			(xy 131.188648 -386.074683) (xy 131.17382 -386.120322) (xy 131.152033 -386.16308) (xy 131.123826 -386.201902)
			(xy 131.089893 -386.235834) (xy 131.05107 -386.26404) (xy 131.008311 -386.285824) (xy 130.962671 -386.300651)
			(xy 130.915274 -386.308155) (xy 130.89128 -386.3086) (xy 130.867705 -386.308222) (xy 130.821116 -386.300978)
			(xy 130.776197 -386.286649) (xy 130.734019 -386.265578) (xy 130.695586 -386.238266) (xy 130.661815 -386.205364)
			(xy 130.63351 -386.167657) (xy 130.62204 -386.147056) (xy 130.621532 -386.146294) (xy 130.223768 -385.457954)
			(xy 130.211839 -385.435292) (xy 130.194906 -385.386964) (xy 130.186252 -385.336491) (xy 130.185668 -385.310888)
			(xy 129.643674 -385.310888) (xy 129.955798 -385.850892) (xy 129.968619 -385.874226) (xy 129.986842 -385.924248)
			(xy 129.996103 -385.976674) (xy 129.996692 -386.003292) (xy 129.996253 -386.027298) (xy 129.98874 -386.07472)
			(xy 129.973896 -386.12038) (xy 129.952088 -386.163155) (xy 129.923853 -386.201988) (xy 129.889889 -386.235924)
			(xy 129.851031 -386.264125) (xy 129.808238 -386.285896) (xy 129.762564 -386.300701) (xy 129.715137 -386.308174)
			(xy 129.69113 -386.3086) (xy 129.667557 -386.308182) (xy 129.62097 -386.300945) (xy 129.576052 -386.286624)
			(xy 129.533873 -386.265559) (xy 129.49544 -386.238253) (xy 129.461668 -386.205357) (xy 129.433361 -386.167654)
			(xy 129.42189 -386.147056) (xy 129.421382 -386.146294) (xy 129.023618 -385.457954) (xy 129.011756 -385.43527)
			(xy 128.994901 -385.38694) (xy 128.986321 -385.33648) (xy 128.985772 -385.310888) (xy 128.443778 -385.310888)
			(xy 128.755902 -385.850892) (xy 128.768724 -385.874226) (xy 128.786946 -385.924248) (xy 128.796207 -385.976674)
			(xy 128.796796 -386.003292) (xy 128.796353 -386.027298) (xy 128.78884 -386.074719) (xy 128.773996 -386.120379)
			(xy 128.752188 -386.163153) (xy 128.723955 -386.201987) (xy 128.68999 -386.235922) (xy 128.651133 -386.264123)
			(xy 128.608341 -386.285895) (xy 128.562668 -386.3007) (xy 128.515241 -386.308174) (xy 128.491234 -386.3086)
			(xy 128.467661 -386.308179) (xy 128.421074 -386.300942) (xy 128.376156 -386.286622) (xy 128.333978 -386.265557)
			(xy 128.295544 -386.238252) (xy 128.261772 -386.205356) (xy 128.233465 -386.167654) (xy 128.221994 -386.147056)
			(xy 128.221486 -386.146294) (xy 127.823722 -385.457954) (xy 127.811861 -385.43527) (xy 127.795005 -385.38694)
			(xy 127.786426 -385.33648) (xy 127.785876 -385.310888) (xy 127.243882 -385.310888) (xy 127.556006 -385.850892)
			(xy 127.568828 -385.874226) (xy 127.58705 -385.924248) (xy 127.596311 -385.976674) (xy 127.5969 -386.003292)
			(xy 127.596454 -386.027298) (xy 127.58894 -386.074718) (xy 127.574096 -386.120378) (xy 127.552289 -386.163152)
			(xy 127.524056 -386.201985) (xy 127.490092 -386.235921) (xy 127.451235 -386.264122) (xy 127.408443 -386.285894)
			(xy 127.362771 -386.300699) (xy 127.315344 -386.308173) (xy 127.291338 -386.3086) (xy 127.267765 -386.308176)
			(xy 127.221178 -386.30094) (xy 127.17626 -386.28662) (xy 127.134082 -386.265556) (xy 127.095648 -386.238251)
			(xy 127.061876 -386.205356) (xy 127.033569 -386.167654) (xy 127.022098 -386.147056) (xy 127.02159 -386.146294)
			(xy 126.623826 -385.457954) (xy 126.611965 -385.43527) (xy 126.595109 -385.38694) (xy 126.58653 -385.33648)
			(xy 126.58598 -385.310888) (xy 126.043732 -385.310888) (xy 126.355856 -385.850892) (xy 126.368611 -385.874246)
			(xy 126.386717 -385.92428) (xy 126.395918 -385.976688) (xy 126.396496 -386.003292) (xy 126.396054 -386.027286)
			(xy 126.388548 -386.074682) (xy 126.37372 -386.12032) (xy 126.351935 -386.163077) (xy 126.323729 -386.2019)
			(xy 126.289797 -386.235831) (xy 126.250974 -386.264037) (xy 126.208217 -386.285822) (xy 126.162578 -386.300649)
			(xy 126.115182 -386.308155) (xy 126.091188 -386.3086) (xy 126.067614 -386.308216) (xy 126.021025 -386.300973)
			(xy 125.976106 -386.286645) (xy 125.933928 -386.265575) (xy 125.895495 -386.238264) (xy 125.861723 -386.205363)
			(xy 125.833418 -386.167656) (xy 125.821948 -386.147056) (xy 125.82144 -386.146294) (xy 125.423676 -385.457954)
			(xy 125.41174 -385.435296) (xy 125.39481 -385.386965) (xy 125.386159 -385.336492) (xy 125.385576 -385.310888)
			(xy 124.843836 -385.310888) (xy 125.15596 -385.850892) (xy 125.168715 -385.874246) (xy 125.186821 -385.92428)
			(xy 125.196022 -385.976688) (xy 125.1966 -386.003292) (xy 125.196154 -386.027285) (xy 125.188649 -386.074681)
			(xy 125.173821 -386.12032) (xy 125.152036 -386.163076) (xy 125.12383 -386.201898) (xy 125.089898 -386.23583)
			(xy 125.051076 -386.264036) (xy 125.00832 -386.285821) (xy 124.962681 -386.300649) (xy 124.915285 -386.308154)
			(xy 124.891292 -386.3086) (xy 124.867718 -386.308213) (xy 124.821129 -386.30097) (xy 124.77621 -386.286643)
			(xy 124.734032 -386.265573) (xy 124.695599 -386.238263) (xy 124.661828 -386.205362) (xy 124.633522 -386.167656)
			(xy 124.622052 -386.147056) (xy 124.621544 -386.146294) (xy 124.22378 -385.457954) (xy 124.211844 -385.435296)
			(xy 124.194915 -385.386965) (xy 124.186263 -385.336492) (xy 124.18568 -385.310888) (xy 123.643686 -385.310888)
			(xy 123.95581 -385.850892) (xy 123.968632 -385.874226) (xy 123.986854 -385.924248) (xy 123.996115 -385.976673)
			(xy 123.996704 -386.003292) (xy 123.996254 -386.027298) (xy 123.98874 -386.074718) (xy 123.973897 -386.120377)
			(xy 123.95209 -386.163151) (xy 123.923857 -386.201984) (xy 123.889894 -386.23592) (xy 123.851037 -386.264121)
			(xy 123.808246 -386.285893) (xy 123.762574 -386.300698) (xy 123.715148 -386.308173) (xy 123.691142 -386.3086)
			(xy 123.667569 -386.308172) (xy 123.620983 -386.300937) (xy 123.576065 -386.286617) (xy 123.533886 -386.265554)
			(xy 123.495453 -386.23825) (xy 123.46168 -386.205355) (xy 123.433373 -386.167654) (xy 123.421902 -386.147056)
			(xy 123.421394 -386.146294) (xy 123.02363 -385.457954) (xy 123.011769 -385.43527) (xy 122.994913 -385.38694)
			(xy 122.986334 -385.33648) (xy 122.985784 -385.310888) (xy 122.44379 -385.310888) (xy 122.755914 -385.850892)
			(xy 122.768737 -385.874226) (xy 122.786958 -385.924248) (xy 122.796219 -385.976673) (xy 122.796808 -386.003292)
			(xy 122.796354 -386.027298) (xy 122.78884 -386.074717) (xy 122.773997 -386.120377) (xy 122.752191 -386.16315)
			(xy 122.723958 -386.201983) (xy 122.689995 -386.235918) (xy 122.65114 -386.264119) (xy 122.608349 -386.285891)
			(xy 122.562678 -386.300698) (xy 122.515252 -386.308173) (xy 122.491246 -386.3086) (xy 122.467673 -386.308169)
			(xy 122.421087 -386.300935) (xy 122.376169 -386.286615) (xy 122.333991 -386.265553) (xy 122.295557 -386.238249)
			(xy 122.261784 -386.205355) (xy 122.233477 -386.167654) (xy 122.222006 -386.147056) (xy 122.221498 -386.146294)
			(xy 121.823734 -385.457954) (xy 121.811874 -385.43527) (xy 121.795018 -385.38694) (xy 121.786438 -385.33648)
			(xy 121.785888 -385.310888) (xy 121.243894 -385.310888) (xy 121.556018 -385.850892) (xy 121.568841 -385.874226)
			(xy 121.587062 -385.924248) (xy 121.596323 -385.976673) (xy 121.596912 -386.003292) (xy 121.596454 -386.027297)
			(xy 121.58894 -386.074717) (xy 121.574098 -386.120376) (xy 121.552291 -386.163149) (xy 121.524059 -386.201981)
			(xy 121.490097 -386.235917) (xy 121.451242 -386.264118) (xy 121.408452 -386.28589) (xy 121.362781 -386.300697)
			(xy 121.315356 -386.308172) (xy 121.29135 -386.3086) (xy 121.267777 -386.308166) (xy 121.221191 -386.300932)
			(xy 121.176273 -386.286613) (xy 121.134095 -386.265551) (xy 121.095661 -386.238248) (xy 121.061888 -386.205354)
			(xy 121.033581 -386.167653) (xy 121.02211 -386.147056) (xy 121.021602 -386.146294) (xy 120.623838 -385.457954)
			(xy 120.611978 -385.435269) (xy 120.595122 -385.38694) (xy 120.586542 -385.33648) (xy 120.585992 -385.310888)
			(xy 120.043744 -385.310888) (xy 120.355868 -385.850892) (xy 120.368624 -385.874246) (xy 120.38673 -385.92428)
			(xy 120.39593 -385.976688) (xy 120.396508 -386.003292) (xy 120.396054 -386.027285) (xy 120.388549 -386.07468)
			(xy 120.373721 -386.120318) (xy 120.351937 -386.163074) (xy 120.323732 -386.201896) (xy 120.289802 -386.235827)
			(xy 120.250981 -386.264033) (xy 120.208225 -386.285818) (xy 120.162588 -386.300647) (xy 120.115193 -386.308154)
			(xy 120.0912 -386.3086) (xy 120.067626 -386.308206) (xy 120.021038 -386.300965) (xy 119.976119 -386.286639)
			(xy 119.933941 -386.26557) (xy 119.895508 -386.238261) (xy 119.861736 -386.205361) (xy 119.83343 -386.167656)
			(xy 119.82196 -386.147056) (xy 119.821452 -386.146294) (xy 119.423688 -385.457954) (xy 119.411753 -385.435296)
			(xy 119.394823 -385.386965) (xy 119.386171 -385.336491) (xy 119.385588 -385.310888) (xy 118.843848 -385.310888)
			(xy 119.155972 -385.850892) (xy 119.168728 -385.874246) (xy 119.186834 -385.92428) (xy 119.196034 -385.976688)
			(xy 119.196612 -386.003292) (xy 119.196154 -386.027285) (xy 119.188649 -386.07468) (xy 119.173822 -386.120317)
			(xy 119.152038 -386.163073) (xy 119.123834 -386.201894) (xy 119.089903 -386.235826) (xy 119.051083 -386.264032)
			(xy 119.008328 -386.285817) (xy 118.962691 -386.300646) (xy 118.915297 -386.308154) (xy 118.891304 -386.3086)
			(xy 118.86773 -386.308203) (xy 118.821142 -386.300962) (xy 118.776223 -386.286637) (xy 118.734045 -386.265569)
			(xy 118.695612 -386.23826) (xy 118.66184 -386.205361) (xy 118.633535 -386.167656) (xy 118.622064 -386.147056)
			(xy 118.621556 -386.146294) (xy 118.223792 -385.457954) (xy 118.211857 -385.435295) (xy 118.194927 -385.386965)
			(xy 118.186275 -385.336491) (xy 118.185692 -385.310888) (xy 117.643698 -385.310888) (xy 117.955822 -385.850892)
			(xy 117.968645 -385.874225) (xy 117.986866 -385.924248) (xy 117.996127 -385.976673) (xy 117.996716 -386.003292)
			(xy 117.996254 -386.027297) (xy 117.98874 -386.074716) (xy 117.973898 -386.120375) (xy 117.952092 -386.163147)
			(xy 117.92386 -386.20198) (xy 117.889899 -386.235915) (xy 117.851044 -386.264117) (xy 117.808254 -386.285889)
			(xy 117.762584 -386.300696) (xy 117.71516 -386.308172) (xy 117.691154 -386.3086) (xy 117.667582 -386.308163)
			(xy 117.620995 -386.300929) (xy 117.576078 -386.286611) (xy 117.533899 -386.26555) (xy 117.495466 -386.238247)
			(xy 117.461693 -386.205353) (xy 117.433385 -386.167653) (xy 117.421914 -386.147056) (xy 117.421406 -386.146294)
			(xy 117.023642 -385.457954) (xy 117.011782 -385.435269) (xy 116.994926 -385.38694) (xy 116.986346 -385.33648)
			(xy 116.985796 -385.310888) (xy 116.443802 -385.310888) (xy 116.755926 -385.850892) (xy 116.76875 -385.874225)
			(xy 116.786971 -385.924247) (xy 116.796231 -385.976673) (xy 116.79682 -386.003292) (xy 116.796354 -386.027297)
			(xy 116.788841 -386.074716) (xy 116.773998 -386.120374) (xy 116.752193 -386.163146) (xy 116.723962 -386.201979)
			(xy 116.69 -386.235914) (xy 116.651146 -386.264115) (xy 116.608357 -386.285888) (xy 116.562688 -386.300695)
			(xy 116.515263 -386.308172) (xy 116.491258 -386.3086) (xy 116.467686 -386.308159) (xy 116.4211 -386.300927)
			(xy 116.376182 -386.286609) (xy 116.334004 -386.265548) (xy 116.29557 -386.238246) (xy 116.261797 -386.205353)
			(xy 116.23349 -386.167653) (xy 116.222018 -386.147056) (xy 116.22151 -386.146294) (xy 115.823746 -385.457954)
			(xy 115.811886 -385.435269) (xy 115.79503 -385.38694) (xy 115.78645 -385.33648) (xy 115.7859 -385.310888)
			(xy 115.243906 -385.310888) (xy 115.55603 -385.850892) (xy 115.568854 -385.874225) (xy 115.587075 -385.924247)
			(xy 115.596335 -385.976673) (xy 115.596924 -386.003292) (xy 115.596454 -386.027297) (xy 115.588941 -386.074715)
			(xy 115.574099 -386.120373) (xy 115.552294 -386.163145) (xy 115.524063 -386.201977) (xy 115.490102 -386.235912)
			(xy 115.451249 -386.264114) (xy 115.40846 -386.285887) (xy 115.362791 -386.300694) (xy 115.315367 -386.308172)
			(xy 115.291362 -386.3086) (xy 115.26779 -386.308156) (xy 115.221204 -386.300924) (xy 115.176286 -386.286607)
			(xy 115.134108 -386.265547) (xy 115.095674 -386.238245) (xy 115.061901 -386.205352) (xy 115.033594 -386.167653)
			(xy 115.022122 -386.147056) (xy 115.021614 -386.146294) (xy 114.62385 -385.457954) (xy 114.611991 -385.435269)
			(xy 114.595134 -385.38694) (xy 114.586554 -385.33648) (xy 114.586004 -385.310888) (xy 98.671676 -385.310888)
			(xy 98.9838 -385.850892) (xy 98.99655 -385.874249) (xy 99.01466 -385.924281) (xy 99.023862 -385.976688)
			(xy 99.02444 -386.003292) (xy 99.02393 -386.027281) (xy 99.016426 -386.07467) (xy 99.001602 -386.120301)
			(xy 98.979822 -386.163051) (xy 98.951623 -386.201869) (xy 98.917699 -386.235797) (xy 98.878886 -386.264001)
			(xy 98.836138 -386.285787) (xy 98.790509 -386.300617) (xy 98.743121 -386.308127) (xy 98.719132 -386.3086)
			(xy 98.695559 -386.30818) (xy 98.648972 -386.300944) (xy 98.604054 -386.286623) (xy 98.561875 -386.265558)
			(xy 98.523442 -386.238253) (xy 98.48967 -386.205357) (xy 98.461363 -386.167654) (xy 98.449892 -386.147056)
			(xy 98.449384 -386.146294) (xy 98.05162 -385.457954) (xy 98.039687 -385.435294) (xy 98.022756 -385.386965)
			(xy 98.014103 -385.336491) (xy 98.01352 -385.310888) (xy 97.471526 -385.310888) (xy 97.78365 -385.850892)
			(xy 97.796476 -385.874224) (xy 97.814695 -385.924247) (xy 97.823955 -385.976673) (xy 97.824544 -386.003292)
			(xy 97.824054 -386.027296) (xy 97.816541 -386.074712) (xy 97.801701 -386.120368) (xy 97.779897 -386.163139)
			(xy 97.751669 -386.20197) (xy 97.71771 -386.235905) (xy 97.67886 -386.264107) (xy 97.636074 -386.285881)
			(xy 97.590407 -386.30069) (xy 97.542986 -386.30817) (xy 97.518982 -386.3086) (xy 97.495407 -386.308221)
			(xy 97.448819 -386.300977) (xy 97.4039 -386.286648) (xy 97.361721 -386.265577) (xy 97.323288 -386.238265)
			(xy 97.289517 -386.205364) (xy 97.261212 -386.167657) (xy 97.249742 -386.147056) (xy 97.249234 -386.146294)
			(xy 96.85147 -385.457954) (xy 96.839612 -385.435268) (xy 96.822755 -385.386939) (xy 96.814174 -385.33648)
			(xy 96.813624 -385.310888) (xy 96.27163 -385.310888) (xy 96.583754 -385.850892) (xy 96.59658 -385.874224)
			(xy 96.614799 -385.924247) (xy 96.624059 -385.976673) (xy 96.624648 -386.003292) (xy 96.624154 -386.027296)
			(xy 96.616641 -386.074711) (xy 96.601801 -386.120367) (xy 96.579998 -386.163138) (xy 96.55177 -386.201969)
			(xy 96.517812 -386.235904) (xy 96.478962 -386.264106) (xy 96.436177 -386.28588) (xy 96.390511 -386.30069)
			(xy 96.34309 -386.30817) (xy 96.319086 -386.3086) (xy 96.295512 -386.308217) (xy 96.248923 -386.300974)
			(xy 96.204004 -386.286646) (xy 96.161826 -386.265576) (xy 96.123393 -386.238264) (xy 96.089621 -386.205363)
			(xy 96.061316 -386.167656) (xy 96.049846 -386.147056) (xy 96.049338 -386.146294) (xy 95.651574 -385.457954)
			(xy 95.639717 -385.435268) (xy 95.622859 -385.386939) (xy 95.614278 -385.336479) (xy 95.613728 -385.310888)
			(xy 95.07148 -385.310888) (xy 95.383604 -385.850892) (xy 95.396355 -385.874249) (xy 95.414464 -385.924281)
			(xy 95.423666 -385.976688) (xy 95.424244 -386.003292) (xy 95.42373 -386.027281) (xy 95.416226 -386.074669)
			(xy 95.401402 -386.1203) (xy 95.379623 -386.16305) (xy 95.351424 -386.201867) (xy 95.317501 -386.235796)
			(xy 95.278688 -386.264) (xy 95.235941 -386.285785) (xy 95.190312 -386.300616) (xy 95.142925 -386.308127)
			(xy 95.118936 -386.3086) (xy 95.095363 -386.308177) (xy 95.048776 -386.300941) (xy 95.003858 -386.286621)
			(xy 94.96168 -386.265557) (xy 94.923246 -386.238252) (xy 94.889474 -386.205356) (xy 94.861167 -386.167654)
			(xy 94.849696 -386.147056) (xy 94.849188 -386.146294) (xy 94.451424 -385.457954) (xy 94.439492 -385.435294)
			(xy 94.42256 -385.386965) (xy 94.413907 -385.336491) (xy 94.413324 -385.310888) (xy 93.871584 -385.310888)
			(xy 94.183708 -385.850892) (xy 94.196459 -385.874248) (xy 94.214568 -385.924281) (xy 94.22377 -385.976688)
			(xy 94.224348 -386.003292) (xy 94.22383 -386.027281) (xy 94.216326 -386.074669) (xy 94.201503 -386.120299)
			(xy 94.179724 -386.163049) (xy 94.151525 -386.201866) (xy 94.117603 -386.235794) (xy 94.07879 -386.263998)
			(xy 94.036043 -386.285784) (xy 93.990415 -386.300615) (xy 93.943029 -386.308126) (xy 93.91904 -386.3086)
			(xy 93.895467 -386.308174) (xy 93.84888 -386.300939) (xy 93.803963 -386.286618) (xy 93.761784 -386.265555)
			(xy 93.723351 -386.238251) (xy 93.689578 -386.205355) (xy 93.661271 -386.167654) (xy 93.6498 -386.147056)
			(xy 93.649292 -386.146294) (xy 93.251528 -385.457954) (xy 93.239596 -385.435294) (xy 93.222664 -385.386965)
			(xy 93.214011 -385.336491) (xy 93.213428 -385.310888) (xy 92.671688 -385.310888) (xy 92.983812 -385.850892)
			(xy 92.996563 -385.874248) (xy 93.014672 -385.924281) (xy 93.023874 -385.976688) (xy 93.024452 -386.003292)
			(xy 93.02393 -386.027281) (xy 93.016427 -386.074668) (xy 93.001603 -386.120298) (xy 92.979824 -386.163048)
			(xy 92.951627 -386.201865) (xy 92.917704 -386.235793) (xy 92.878892 -386.263997) (xy 92.836146 -386.285783)
			(xy 92.790519 -386.300614) (xy 92.743133 -386.308126) (xy 92.719144 -386.3086) (xy 92.695571 -386.308171)
			(xy 92.648985 -386.300936) (xy 92.604067 -386.286616) (xy 92.561889 -386.265554) (xy 92.523455 -386.238249)
			(xy 92.489682 -386.205355) (xy 92.461375 -386.167654) (xy 92.449904 -386.147056) (xy 92.449396 -386.146294)
			(xy 92.051632 -385.457954) (xy 92.0397 -385.435294) (xy 92.022768 -385.386965) (xy 92.014115 -385.336491)
			(xy 92.013532 -385.310888) (xy 91.471538 -385.310888) (xy 91.783662 -385.850892) (xy 91.796489 -385.874224)
			(xy 91.814708 -385.924247) (xy 91.823967 -385.976673) (xy 91.824556 -386.003292) (xy 91.824054 -386.027295)
			(xy 91.816542 -386.07471) (xy 91.801702 -386.120365) (xy 91.779899 -386.163135) (xy 91.751672 -386.201966)
			(xy 91.717715 -386.235901) (xy 91.678866 -386.264103) (xy 91.636082 -386.285878) (xy 91.590417 -386.300688)
			(xy 91.542998 -386.308169) (xy 91.518994 -386.3086) (xy 91.49542 -386.308211) (xy 91.448831 -386.300969)
			(xy 91.403913 -386.286642) (xy 91.361734 -386.265573) (xy 91.323301 -386.238262) (xy 91.28953 -386.205362)
			(xy 91.261224 -386.167656) (xy 91.249754 -386.147056) (xy 91.249246 -386.146294) (xy 90.851482 -385.457954)
			(xy 90.839625 -385.435268) (xy 90.822767 -385.386939) (xy 90.814186 -385.336479) (xy 90.813636 -385.310888)
			(xy 90.271642 -385.310888) (xy 90.583766 -385.850892) (xy 90.596593 -385.874223) (xy 90.614812 -385.924247)
			(xy 90.624071 -385.976673) (xy 90.62466 -386.003292) (xy 90.624253 -386.0273) (xy 90.616738 -386.074724)
			(xy 90.601893 -386.120388) (xy 90.580082 -386.163164) (xy 90.551844 -386.201999) (xy 90.517875 -386.235935)
			(xy 90.479013 -386.264136) (xy 90.436216 -386.285905) (xy 90.390538 -386.300707) (xy 90.343106 -386.308176)
			(xy 90.319098 -386.3086) (xy 90.295524 -386.308208) (xy 90.248936 -386.300966) (xy 90.204017 -386.28664)
			(xy 90.161839 -386.265571) (xy 90.123406 -386.238261) (xy 90.089634 -386.205361) (xy 90.061328 -386.167656)
			(xy 90.049858 -386.147056) (xy 90.04935 -386.146294) (xy 89.651586 -385.457954) (xy 89.63973 -385.435267)
			(xy 89.622871 -385.386939) (xy 89.61429 -385.336479) (xy 89.61374 -385.310888) (xy 89.071492 -385.310888)
			(xy 89.383616 -385.850892) (xy 89.396368 -385.874248) (xy 89.414476 -385.924281) (xy 89.423678 -385.976688)
			(xy 89.424256 -386.003292) (xy 89.42373 -386.027281) (xy 89.416227 -386.074667) (xy 89.401403 -386.120297)
			(xy 89.379625 -386.163047) (xy 89.351428 -386.201863) (xy 89.317506 -386.235791) (xy 89.278694 -386.263996)
			(xy 89.235949 -386.285782) (xy 89.190322 -386.300614) (xy 89.142937 -386.308126) (xy 89.118948 -386.3086)
			(xy 89.095375 -386.308168) (xy 89.048789 -386.300933) (xy 89.003871 -386.286614) (xy 88.961693 -386.265552)
			(xy 88.923259 -386.238248) (xy 88.889486 -386.205354) (xy 88.861179 -386.167654) (xy 88.849708 -386.147056)
			(xy 88.8492 -386.146294) (xy 88.451436 -385.457954) (xy 88.439505 -385.435294) (xy 88.422572 -385.386964)
			(xy 88.413919 -385.336491) (xy 88.413336 -385.310888) (xy 87.871596 -385.310888) (xy 88.18372 -385.850892)
			(xy 88.196472 -385.874248) (xy 88.21458 -385.924281) (xy 88.223782 -385.976688) (xy 88.22436 -386.003292)
			(xy 88.223954 -386.027287) (xy 88.216447 -386.074687) (xy 88.201617 -386.120329) (xy 88.179828 -386.163088)
			(xy 88.151618 -386.201912) (xy 88.117682 -386.235844) (xy 88.078854 -386.264049) (xy 88.036092 -386.285832)
			(xy 87.990448 -386.300657) (xy 87.943047 -386.308157) (xy 87.919052 -386.3086) (xy 87.895479 -386.308164)
			(xy 87.848893 -386.300931) (xy 87.803976 -386.286612) (xy 87.761797 -386.265551) (xy 87.723364 -386.238247)
			(xy 87.689591 -386.205354) (xy 87.661283 -386.167653) (xy 87.649812 -386.147056) (xy 87.649304 -386.146294)
			(xy 87.25154 -385.457954) (xy 87.239609 -385.435293) (xy 87.222676 -385.386964) (xy 87.214023 -385.336491)
			(xy 87.21344 -385.310888) (xy 86.6717 -385.310888) (xy 86.983824 -385.850892) (xy 86.996576 -385.874248)
			(xy 87.014684 -385.92428) (xy 87.023886 -385.976688) (xy 87.024464 -386.003292) (xy 87.024054 -386.027287)
			(xy 87.016547 -386.074687) (xy 87.001717 -386.120328) (xy 86.979929 -386.163087) (xy 86.951719 -386.201911)
			(xy 86.917783 -386.235843) (xy 86.878956 -386.264048) (xy 86.836195 -386.285831) (xy 86.790552 -386.300656)
			(xy 86.743151 -386.308157) (xy 86.719156 -386.3086) (xy 86.695584 -386.308161) (xy 86.648997 -386.300928)
			(xy 86.60408 -386.28661) (xy 86.561902 -386.265549) (xy 86.523468 -386.238246) (xy 86.489695 -386.205353)
			(xy 86.461387 -386.167653) (xy 86.449916 -386.147056) (xy 86.449408 -386.146294) (xy 86.051644 -385.457954)
			(xy 86.039713 -385.435293) (xy 86.02278 -385.386964) (xy 86.014127 -385.336491) (xy 86.013544 -385.310888)
			(xy 85.47155 -385.310888) (xy 85.783674 -385.850892) (xy 85.796501 -385.874223) (xy 85.81472 -385.924247)
			(xy 85.823979 -385.976673) (xy 85.824568 -386.003292) (xy 85.824153 -386.0273) (xy 85.816639 -386.074723)
			(xy 85.801793 -386.120386) (xy 85.779983 -386.163162) (xy 85.751746 -386.201996) (xy 85.717779 -386.235932)
			(xy 85.678917 -386.264133) (xy 85.636121 -386.285903) (xy 85.590445 -386.300706) (xy 85.543014 -386.308176)
			(xy 85.519006 -386.3086) (xy 85.495432 -386.308201) (xy 85.448844 -386.300961) (xy 85.403926 -386.286636)
			(xy 85.361747 -386.265568) (xy 85.323314 -386.238259) (xy 85.289542 -386.20536) (xy 85.261237 -386.167655)
			(xy 85.249766 -386.147056) (xy 85.249258 -386.146294) (xy 84.851494 -385.457954) (xy 84.839638 -385.435267)
			(xy 84.822779 -385.386939) (xy 84.814198 -385.336479) (xy 84.813648 -385.310888) (xy 84.271654 -385.310888)
			(xy 84.583778 -385.850892) (xy 84.596606 -385.874223) (xy 84.614824 -385.924247) (xy 84.624083 -385.976673)
			(xy 84.624672 -386.003292) (xy 84.624253 -386.027299) (xy 84.616739 -386.074723) (xy 84.601894 -386.120385)
			(xy 84.580084 -386.163161) (xy 84.551848 -386.201995) (xy 84.51788 -386.235931) (xy 84.47902 -386.264132)
			(xy 84.436224 -386.285902) (xy 84.390548 -386.300705) (xy 84.343118 -386.308175) (xy 84.31911 -386.3086)
			(xy 84.295536 -386.308198) (xy 84.248948 -386.300958) (xy 84.20403 -386.286634) (xy 84.161852 -386.265566)
			(xy 84.123418 -386.238258) (xy 84.089647 -386.20536) (xy 84.061341 -386.167655) (xy 84.04987 -386.147056)
			(xy 84.049362 -386.146294) (xy 83.651598 -385.457954) (xy 83.639742 -385.435267) (xy 83.622883 -385.386939)
			(xy 83.614302 -385.336479) (xy 83.613752 -385.310888) (xy 83.071504 -385.310888) (xy 83.383628 -385.850892)
			(xy 83.396381 -385.874247) (xy 83.414488 -385.92428) (xy 83.42369 -385.976688) (xy 83.424268 -386.003292)
			(xy 83.423854 -386.027287) (xy 83.416348 -386.074686) (xy 83.401518 -386.120327) (xy 83.37973 -386.163086)
			(xy 83.351521 -386.201909) (xy 83.317585 -386.235841) (xy 83.278758 -386.264047) (xy 83.235997 -386.28583)
			(xy 83.190355 -386.300655) (xy 83.142955 -386.308157) (xy 83.11896 -386.3086) (xy 83.095388 -386.308158)
			(xy 83.048802 -386.300925) (xy 83.003884 -386.286608) (xy 82.961706 -386.265548) (xy 82.923272 -386.238245)
			(xy 82.889499 -386.205353) (xy 82.861192 -386.167653) (xy 82.84972 -386.147056) (xy 82.849212 -386.146294)
			(xy 82.451448 -385.457954) (xy 82.439517 -385.435293) (xy 82.422585 -385.386964) (xy 82.413931 -385.336491)
			(xy 82.413348 -385.310888) (xy 81.871608 -385.310888) (xy 82.183732 -385.850892) (xy 82.196485 -385.874247)
			(xy 82.214593 -385.92428) (xy 82.223794 -385.976688) (xy 82.224372 -386.003292) (xy 82.223954 -386.027287)
			(xy 82.216448 -386.074685) (xy 82.201618 -386.120326) (xy 82.179831 -386.163085) (xy 82.151622 -386.201908)
			(xy 82.117687 -386.23584) (xy 82.078861 -386.264045) (xy 82.0361 -386.285829) (xy 81.990458 -386.300654)
			(xy 81.943059 -386.308156) (xy 81.919064 -386.3086) (xy 81.895492 -386.308155) (xy 81.848906 -386.300923)
			(xy 81.803989 -386.286606) (xy 81.76181 -386.265546) (xy 81.723376 -386.238244) (xy 81.689603 -386.205352)
			(xy 81.661296 -386.167653) (xy 81.649824 -386.147056) (xy 81.649316 -386.146294) (xy 81.251552 -385.457954)
			(xy 81.239622 -385.435293) (xy 81.222689 -385.386964) (xy 81.214035 -385.336491) (xy 81.213452 -385.310888)
			(xy 80.671712 -385.310888) (xy 80.983836 -385.850892) (xy 80.996589 -385.874247) (xy 81.014697 -385.92428)
			(xy 81.023898 -385.976688) (xy 81.024476 -386.003292) (xy 81.024054 -386.027287) (xy 81.016548 -386.074685)
			(xy 81.001718 -386.120325) (xy 80.979931 -386.163083) (xy 80.951723 -386.201907) (xy 80.917788 -386.235839)
			(xy 80.878963 -386.264044) (xy 80.836203 -386.285828) (xy 80.790561 -386.300653) (xy 80.743163 -386.308156)
			(xy 80.719168 -386.3086) (xy 80.695596 -386.308151) (xy 80.64901 -386.30092) (xy 80.604093 -386.286604)
			(xy 80.561915 -386.265545) (xy 80.523481 -386.238243) (xy 80.489707 -386.205351) (xy 80.4614 -386.167653)
			(xy 80.449928 -386.147056) (xy 80.44942 -386.146294) (xy 80.051656 -385.457954) (xy 80.039726 -385.435293)
			(xy 80.022793 -385.386964) (xy 80.014139 -385.336491) (xy 80.013556 -385.310888) (xy 66.143928 -385.310888)
			(xy 66.456052 -385.850892) (xy 66.468807 -385.874246) (xy 66.486913 -385.92428) (xy 66.496114 -385.976688)
			(xy 66.496692 -386.003292) (xy 66.496254 -386.027286) (xy 66.488748 -386.074682) (xy 66.47392 -386.120321)
			(xy 66.452134 -386.163079) (xy 66.423928 -386.201901) (xy 66.389995 -386.235833) (xy 66.351172 -386.264038)
			(xy 66.308414 -386.285823) (xy 66.262775 -386.30065) (xy 66.215378 -386.308155) (xy 66.191384 -386.3086)
			(xy 66.16781 -386.308219) (xy 66.121221 -386.300975) (xy 66.076302 -386.286647) (xy 66.034123 -386.265576)
			(xy 65.995691 -386.238265) (xy 65.961919 -386.205363) (xy 65.933614 -386.167656) (xy 65.922144 -386.147056)
			(xy 65.921636 -386.146294) (xy 65.523872 -385.457954) (xy 65.511936 -385.435296) (xy 65.495006 -385.386965)
			(xy 65.486355 -385.336492) (xy 65.485772 -385.310888) (xy 64.943778 -385.310888) (xy 65.255902 -385.850892)
			(xy 65.268724 -385.874226) (xy 65.286946 -385.924248) (xy 65.296207 -385.976674) (xy 65.296796 -386.003292)
			(xy 65.296353 -386.027298) (xy 65.28884 -386.074719) (xy 65.273996 -386.120379) (xy 65.252188 -386.163153)
			(xy 65.223955 -386.201987) (xy 65.18999 -386.235922) (xy 65.151133 -386.264123) (xy 65.108341 -386.285895)
			(xy 65.062668 -386.3007) (xy 65.015241 -386.308174) (xy 64.991234 -386.3086) (xy 64.967661 -386.308179)
			(xy 64.921074 -386.300942) (xy 64.876156 -386.286622) (xy 64.833978 -386.265557) (xy 64.795544 -386.238252)
			(xy 64.761772 -386.205356) (xy 64.733465 -386.167654) (xy 64.721994 -386.147056) (xy 64.721486 -386.146294)
			(xy 64.323722 -385.457954) (xy 64.311861 -385.43527) (xy 64.295005 -385.38694) (xy 64.286426 -385.33648)
			(xy 64.285876 -385.310888) (xy 63.743882 -385.310888) (xy 64.056006 -385.850892) (xy 64.068828 -385.874226)
			(xy 64.08705 -385.924248) (xy 64.096311 -385.976674) (xy 64.0969 -386.003292) (xy 64.096454 -386.027298)
			(xy 64.08894 -386.074718) (xy 64.074096 -386.120378) (xy 64.052289 -386.163152) (xy 64.024056 -386.201985)
			(xy 63.990092 -386.235921) (xy 63.951235 -386.264122) (xy 63.908443 -386.285894) (xy 63.862771 -386.300699)
			(xy 63.815344 -386.308173) (xy 63.791338 -386.3086) (xy 63.767765 -386.308176) (xy 63.721178 -386.30094)
			(xy 63.67626 -386.28662) (xy 63.634082 -386.265556) (xy 63.595648 -386.238251) (xy 63.561876 -386.205356)
			(xy 63.533569 -386.167654) (xy 63.522098 -386.147056) (xy 63.52159 -386.146294) (xy 63.123826 -385.457954)
			(xy 63.111965 -385.43527) (xy 63.095109 -385.38694) (xy 63.08653 -385.33648) (xy 63.08598 -385.310888)
			(xy 62.543732 -385.310888) (xy 62.855856 -385.850892) (xy 62.868611 -385.874246) (xy 62.886717 -385.92428)
			(xy 62.895918 -385.976688) (xy 62.896496 -386.003292) (xy 62.896054 -386.027286) (xy 62.888548 -386.074682)
			(xy 62.87372 -386.12032) (xy 62.851935 -386.163077) (xy 62.823729 -386.2019) (xy 62.789797 -386.235831)
			(xy 62.750974 -386.264037) (xy 62.708217 -386.285822) (xy 62.662578 -386.300649) (xy 62.615182 -386.308155)
			(xy 62.591188 -386.3086) (xy 62.567614 -386.308216) (xy 62.521025 -386.300973) (xy 62.476106 -386.286645)
			(xy 62.433928 -386.265575) (xy 62.395495 -386.238264) (xy 62.361723 -386.205363) (xy 62.333418 -386.167656)
			(xy 62.321948 -386.147056) (xy 62.32144 -386.146294) (xy 61.923676 -385.457954) (xy 61.91174 -385.435296)
			(xy 61.89481 -385.386965) (xy 61.886159 -385.336492) (xy 61.885576 -385.310888) (xy 61.343836 -385.310888)
			(xy 61.65596 -385.850892) (xy 61.668715 -385.874246) (xy 61.686821 -385.92428) (xy 61.696022 -385.976688)
			(xy 61.6966 -386.003292) (xy 61.696154 -386.027285) (xy 61.688649 -386.074681) (xy 61.673821 -386.12032)
			(xy 61.652036 -386.163076) (xy 61.62383 -386.201898) (xy 61.589898 -386.23583) (xy 61.551076 -386.264036)
			(xy 61.50832 -386.285821) (xy 61.462681 -386.300649) (xy 61.415285 -386.308154) (xy 61.391292 -386.3086)
			(xy 61.367718 -386.308213) (xy 61.321129 -386.30097) (xy 61.27621 -386.286643) (xy 61.234032 -386.265573)
			(xy 61.195599 -386.238263) (xy 61.161828 -386.205362) (xy 61.133522 -386.167656) (xy 61.122052 -386.147056)
			(xy 61.121544 -386.146294) (xy 60.72378 -385.457954) (xy 60.711844 -385.435296) (xy 60.694915 -385.386965)
			(xy 60.686263 -385.336492) (xy 60.68568 -385.310888) (xy 60.14394 -385.310888) (xy 60.456064 -385.850892)
			(xy 60.46882 -385.874246) (xy 60.486926 -385.92428) (xy 60.496126 -385.976688) (xy 60.496704 -386.003292)
			(xy 60.496254 -386.027285) (xy 60.488749 -386.074681) (xy 60.473921 -386.120319) (xy 60.452136 -386.163075)
			(xy 60.423931 -386.201897) (xy 60.39 -386.235829) (xy 60.351178 -386.264034) (xy 60.308422 -386.28582)
			(xy 60.262785 -386.300648) (xy 60.215389 -386.308154) (xy 60.191396 -386.3086) (xy 60.167822 -386.308209)
			(xy 60.121233 -386.300967) (xy 60.076315 -386.286641) (xy 60.034136 -386.265572) (xy 59.995703 -386.238262)
			(xy 59.961932 -386.205362) (xy 59.933626 -386.167656) (xy 59.922156 -386.147056) (xy 59.921648 -386.146294)
			(xy 59.523884 -385.457954) (xy 59.511948 -385.435296) (xy 59.495019 -385.386965) (xy 59.486367 -385.336492)
			(xy 59.485784 -385.310888) (xy 58.94379 -385.310888) (xy 59.255914 -385.850892) (xy 59.268737 -385.874226)
			(xy 59.286958 -385.924248) (xy 59.296219 -385.976673) (xy 59.296808 -386.003292) (xy 59.296354 -386.027298)
			(xy 59.28884 -386.074717) (xy 59.273997 -386.120377) (xy 59.252191 -386.16315) (xy 59.223958 -386.201983)
			(xy 59.189995 -386.235918) (xy 59.15114 -386.264119) (xy 59.108349 -386.285891) (xy 59.062678 -386.300698)
			(xy 59.015252 -386.308173) (xy 58.991246 -386.3086) (xy 58.967673 -386.308169) (xy 58.921087 -386.300935)
			(xy 58.876169 -386.286615) (xy 58.833991 -386.265553) (xy 58.795557 -386.238249) (xy 58.761784 -386.205355)
			(xy 58.733477 -386.167654) (xy 58.722006 -386.147056) (xy 58.721498 -386.146294) (xy 58.323734 -385.457954)
			(xy 58.311874 -385.43527) (xy 58.295018 -385.38694) (xy 58.286438 -385.33648) (xy 58.285888 -385.310888)
			(xy 57.743894 -385.310888) (xy 58.056018 -385.850892) (xy 58.068841 -385.874226) (xy 58.087062 -385.924248)
			(xy 58.096323 -385.976673) (xy 58.096912 -386.003292) (xy 58.096454 -386.027297) (xy 58.08894 -386.074717)
			(xy 58.074098 -386.120376) (xy 58.052291 -386.163149) (xy 58.024059 -386.201981) (xy 57.990097 -386.235917)
			(xy 57.951242 -386.264118) (xy 57.908452 -386.28589) (xy 57.862781 -386.300697) (xy 57.815356 -386.308172)
			(xy 57.79135 -386.3086) (xy 57.767777 -386.308166) (xy 57.721191 -386.300932) (xy 57.676273 -386.286613)
			(xy 57.634095 -386.265551) (xy 57.595661 -386.238248) (xy 57.561888 -386.205354) (xy 57.533581 -386.167653)
			(xy 57.52211 -386.147056) (xy 57.521602 -386.146294) (xy 57.123838 -385.457954) (xy 57.111978 -385.435269)
			(xy 57.095122 -385.38694) (xy 57.086542 -385.33648) (xy 57.085992 -385.310888) (xy 56.543744 -385.310888)
			(xy 56.855868 -385.850892) (xy 56.868624 -385.874246) (xy 56.88673 -385.92428) (xy 56.89593 -385.976688)
			(xy 56.896508 -386.003292) (xy 56.896054 -386.027285) (xy 56.888549 -386.07468) (xy 56.873721 -386.120318)
			(xy 56.851937 -386.163074) (xy 56.823732 -386.201896) (xy 56.789802 -386.235827) (xy 56.750981 -386.264033)
			(xy 56.708225 -386.285818) (xy 56.662588 -386.300647) (xy 56.615193 -386.308154) (xy 56.5912 -386.3086)
			(xy 56.567626 -386.308206) (xy 56.521038 -386.300965) (xy 56.476119 -386.286639) (xy 56.433941 -386.26557)
			(xy 56.395508 -386.238261) (xy 56.361736 -386.205361) (xy 56.33343 -386.167656) (xy 56.32196 -386.147056)
			(xy 56.321452 -386.146294) (xy 55.923688 -385.457954) (xy 55.911753 -385.435296) (xy 55.894823 -385.386965)
			(xy 55.886171 -385.336491) (xy 55.885588 -385.310888) (xy 55.343848 -385.310888) (xy 55.655972 -385.850892)
			(xy 55.668728 -385.874246) (xy 55.686834 -385.92428) (xy 55.696034 -385.976688) (xy 55.696612 -386.003292)
			(xy 55.696154 -386.027285) (xy 55.688649 -386.07468) (xy 55.673822 -386.120317) (xy 55.652038 -386.163073)
			(xy 55.623834 -386.201894) (xy 55.589903 -386.235826) (xy 55.551083 -386.264032) (xy 55.508328 -386.285817)
			(xy 55.462691 -386.300646) (xy 55.415297 -386.308154) (xy 55.391304 -386.3086) (xy 55.36773 -386.308203)
			(xy 55.321142 -386.300962) (xy 55.276223 -386.286637) (xy 55.234045 -386.265569) (xy 55.195612 -386.23826)
			(xy 55.16184 -386.205361) (xy 55.133535 -386.167656) (xy 55.122064 -386.147056) (xy 55.121556 -386.146294)
			(xy 54.723792 -385.457954) (xy 54.711857 -385.435295) (xy 54.694927 -385.386965) (xy 54.686275 -385.336491)
			(xy 54.685692 -385.310888) (xy 54.143952 -385.310888) (xy 54.456076 -385.850892) (xy 54.468824 -385.87425)
			(xy 54.486935 -385.924281) (xy 54.496138 -385.976688) (xy 54.496716 -386.003292) (xy 54.49623 -386.027283)
			(xy 54.488725 -386.074673) (xy 54.4739 -386.120306) (xy 54.452118 -386.163059) (xy 54.423916 -386.201877)
			(xy 54.389989 -386.235806) (xy 54.351172 -386.264009) (xy 54.308421 -386.285793) (xy 54.262789 -386.300622)
			(xy 54.215399 -386.308129) (xy 54.191408 -386.3086) (xy 54.167834 -386.3082) (xy 54.121246 -386.30096)
			(xy 54.076328 -386.286635) (xy 54.034149 -386.265567) (xy 53.995716 -386.238259) (xy 53.961944 -386.20536)
			(xy 53.933639 -386.167655) (xy 53.922168 -386.147056) (xy 53.92166 -386.146294) (xy 53.523896 -385.457954)
			(xy 53.511961 -385.435295) (xy 53.495031 -385.386965) (xy 53.486379 -385.336491) (xy 53.485796 -385.310888)
			(xy 52.943802 -385.310888) (xy 53.255926 -385.850892) (xy 53.26875 -385.874225) (xy 53.286971 -385.924247)
			(xy 53.296231 -385.976673) (xy 53.29682 -386.003292) (xy 53.296354 -386.027297) (xy 53.288841 -386.074716)
			(xy 53.273998 -386.120374) (xy 53.252193 -386.163146) (xy 53.223962 -386.201979) (xy 53.19 -386.235914)
			(xy 53.151146 -386.264115) (xy 53.108357 -386.285888) (xy 53.062688 -386.300695) (xy 53.015263 -386.308172)
			(xy 52.991258 -386.3086) (xy 52.967686 -386.308159) (xy 52.9211 -386.300927) (xy 52.876182 -386.286609)
			(xy 52.834004 -386.265548) (xy 52.79557 -386.238246) (xy 52.761797 -386.205353) (xy 52.73349 -386.167653)
			(xy 52.722018 -386.147056) (xy 52.72151 -386.146294) (xy 52.323746 -385.457954) (xy 52.311886 -385.435269)
			(xy 52.29503 -385.38694) (xy 52.28645 -385.33648) (xy 52.2859 -385.310888) (xy 51.743906 -385.310888)
			(xy 52.05603 -385.850892) (xy 52.068854 -385.874225) (xy 52.087075 -385.924247) (xy 52.096335 -385.976673)
			(xy 52.096924 -386.003292) (xy 52.096454 -386.027297) (xy 52.088941 -386.074715) (xy 52.074099 -386.120373)
			(xy 52.052294 -386.163145) (xy 52.024063 -386.201977) (xy 51.990102 -386.235912) (xy 51.951249 -386.264114)
			(xy 51.90846 -386.285887) (xy 51.862791 -386.300694) (xy 51.815367 -386.308172) (xy 51.791362 -386.3086)
			(xy 51.76779 -386.308156) (xy 51.721204 -386.300924) (xy 51.676286 -386.286607) (xy 51.634108 -386.265547)
			(xy 51.595674 -386.238245) (xy 51.561901 -386.205352) (xy 51.533594 -386.167653) (xy 51.522122 -386.147056)
			(xy 51.521614 -386.146294) (xy 51.12385 -385.457954) (xy 51.111991 -385.435269) (xy 51.095134 -385.38694)
			(xy 51.086554 -385.33648) (xy 51.086004 -385.310888) (xy 50.543756 -385.310888) (xy 50.85588 -385.850892)
			(xy 50.868629 -385.87425) (xy 50.886739 -385.924281) (xy 50.895942 -385.976688) (xy 50.89652 -386.003292)
			(xy 50.89603 -386.027282) (xy 50.888526 -386.074673) (xy 50.8737 -386.120306) (xy 50.851918 -386.163057)
			(xy 50.823717 -386.201876) (xy 50.789791 -386.235804) (xy 50.750974 -386.264008) (xy 50.708224 -386.285792)
			(xy 50.662592 -386.300621) (xy 50.615202 -386.308128) (xy 50.591212 -386.3086) (xy 50.567638 -386.308197)
			(xy 50.521051 -386.300957) (xy 50.476132 -386.286633) (xy 50.433954 -386.265566) (xy 50.395521 -386.238258)
			(xy 50.361749 -386.205359) (xy 50.333443 -386.167655) (xy 50.321972 -386.147056) (xy 50.321464 -386.146294)
			(xy 49.9237 -385.457954) (xy 49.911766 -385.435295) (xy 49.894835 -385.386965) (xy 49.886183 -385.336491)
			(xy 49.8856 -385.310888) (xy 49.34386 -385.310888) (xy 49.655984 -385.850892) (xy 49.668733 -385.874249)
			(xy 49.686843 -385.924281) (xy 49.696046 -385.976688) (xy 49.696624 -386.003292) (xy 49.69613 -386.027282)
			(xy 49.688626 -386.074672) (xy 49.6738 -386.120305) (xy 49.652019 -386.163056) (xy 49.623818 -386.201874)
			(xy 49.589892 -386.235803) (xy 49.551077 -386.264007) (xy 49.508327 -386.285791) (xy 49.462695 -386.30062)
			(xy 49.415306 -386.308128) (xy 49.391316 -386.3086) (xy 49.367742 -386.308193) (xy 49.321155 -386.300954)
			(xy 49.276236 -386.286631) (xy 49.234058 -386.265564) (xy 49.195625 -386.238257) (xy 49.161853 -386.205359)
			(xy 49.133547 -386.167655) (xy 49.122076 -386.147056) (xy 49.121568 -386.146294) (xy 48.723804 -385.457954)
			(xy 48.71187 -385.435295) (xy 48.694939 -385.386965) (xy 48.686287 -385.336491) (xy 48.685704 -385.310888)
			(xy 48.143964 -385.310888) (xy 48.456088 -385.850892) (xy 48.468837 -385.874249) (xy 48.486947 -385.924281)
			(xy 48.49615 -385.976688) (xy 48.496728 -386.003292) (xy 48.49623 -386.027282) (xy 48.488726 -386.074672)
			(xy 48.473901 -386.120304) (xy 48.45212 -386.163055) (xy 48.42392 -386.201873) (xy 48.389994 -386.235801)
			(xy 48.351179 -386.264005) (xy 48.30843 -386.28579) (xy 48.262799 -386.300619) (xy 48.21541 -386.308128)
			(xy 48.19142 -386.3086) (xy 48.167847 -386.30819) (xy 48.121259 -386.300952) (xy 48.076341 -386.286629)
			(xy 48.034162 -386.265563) (xy 47.995729 -386.238256) (xy 47.961957 -386.205358) (xy 47.933651 -386.167655)
			(xy 47.92218 -386.147056) (xy 47.921672 -386.146294) (xy 47.523908 -385.457954) (xy 47.511974 -385.435295)
			(xy 47.495043 -385.386965) (xy 47.486391 -385.336491) (xy 47.485808 -385.310888) (xy 2.509012 -385.310888)
			(xy 2.509012 -387.789674) (xy 40.901112 -387.789674) (xy 40.901112 -386.926074) (xy 40.901598 -386.898805)
			(xy 40.90936 -386.844821) (xy 40.924725 -386.792491) (xy 40.947382 -386.742881) (xy 40.976868 -386.697)
			(xy 41.012583 -386.655783) (xy 41.0538 -386.620068) (xy 41.099681 -386.590582) (xy 41.149291 -386.567925)
			(xy 41.201621 -386.55256) (xy 41.255605 -386.544798) (xy 41.310143 -386.544798) (xy 41.364127 -386.55256)
			(xy 41.416457 -386.567925) (xy 41.466067 -386.590582) (xy 41.511948 -386.620068) (xy 41.553165 -386.655783)
			(xy 41.58888 -386.697) (xy 41.618366 -386.742881) (xy 41.641023 -386.792491) (xy 41.656388 -386.844821)
			(xy 41.66415 -386.898805) (xy 41.664636 -386.926074) (xy 41.664636 -387.789674) (xy 73.42886 -387.789674)
			(xy 73.42886 -386.926074) (xy 73.429346 -386.898805) (xy 73.437108 -386.844821) (xy 73.452473 -386.792491)
			(xy 73.47513 -386.742881) (xy 73.504616 -386.697) (xy 73.540331 -386.655783) (xy 73.581548 -386.620068)
			(xy 73.627429 -386.590582) (xy 73.677039 -386.567925) (xy 73.729369 -386.55256) (xy 73.783353 -386.544798)
			(xy 73.837891 -386.544798) (xy 73.891875 -386.55256) (xy 73.944205 -386.567925) (xy 73.993815 -386.590582)
			(xy 74.039696 -386.620068) (xy 74.080913 -386.655783) (xy 74.116628 -386.697) (xy 74.146114 -386.742881)
			(xy 74.168771 -386.792491) (xy 74.184136 -386.844821) (xy 74.191898 -386.898805) (xy 74.192384 -386.926074)
			(xy 74.192384 -387.789674) (xy 108.001308 -387.789674) (xy 108.001308 -386.926074) (xy 108.001794 -386.898823)
			(xy 108.00955 -386.844875) (xy 108.024905 -386.79258) (xy 108.047547 -386.743003) (xy 108.077013 -386.697153)
			(xy 108.112704 -386.655962) (xy 108.153895 -386.620271) (xy 108.199745 -386.590805) (xy 108.249322 -386.568163)
			(xy 108.301617 -386.552808) (xy 108.355565 -386.545052) (xy 108.410067 -386.545052) (xy 108.464015 -386.552808)
			(xy 108.51631 -386.568163) (xy 108.565887 -386.590805) (xy 108.611737 -386.620271) (xy 108.652928 -386.655962)
			(xy 108.688619 -386.697153) (xy 108.718085 -386.743003) (xy 108.740727 -386.79258) (xy 108.756082 -386.844875)
			(xy 108.763838 -386.898823) (xy 108.764324 -386.926074) (xy 108.764324 -387.789674) (xy 140.529056 -387.789674)
			(xy 140.529056 -386.926074) (xy 140.529542 -386.898823) (xy 140.537298 -386.844875) (xy 140.552653 -386.79258)
			(xy 140.575295 -386.743003) (xy 140.604761 -386.697153) (xy 140.640452 -386.655962) (xy 140.681643 -386.620271)
			(xy 140.727493 -386.590805) (xy 140.77707 -386.568163) (xy 140.829365 -386.552808) (xy 140.883313 -386.545052)
			(xy 140.937815 -386.545052) (xy 140.991763 -386.552808) (xy 141.044058 -386.568163) (xy 141.093635 -386.590805)
			(xy 141.139485 -386.620271) (xy 141.180676 -386.655962) (xy 141.216367 -386.697153) (xy 141.245833 -386.743003)
			(xy 141.268475 -386.79258) (xy 141.28383 -386.844875) (xy 141.291586 -386.898823) (xy 141.292072 -386.926074)
			(xy 141.292072 -387.789674) (xy 141.291586 -387.816925) (xy 141.28383 -387.870873) (xy 141.268475 -387.923168)
			(xy 141.245833 -387.972745) (xy 141.216367 -388.018595) (xy 141.180676 -388.059786) (xy 141.139485 -388.095477)
			(xy 141.093635 -388.124943) (xy 141.044058 -388.147585) (xy 140.991763 -388.16294) (xy 140.937815 -388.170696)
			(xy 140.883313 -388.170696) (xy 140.829365 -388.16294) (xy 140.77707 -388.147585) (xy 140.727493 -388.124943)
			(xy 140.681643 -388.095477) (xy 140.640452 -388.059786) (xy 140.604761 -388.018595) (xy 140.575295 -387.972745)
			(xy 140.552653 -387.923168) (xy 140.537298 -387.870873) (xy 140.529542 -387.816925) (xy 140.529056 -387.789674)
			(xy 108.764324 -387.789674) (xy 108.763838 -387.816925) (xy 108.756082 -387.870873) (xy 108.740727 -387.923168)
			(xy 108.718085 -387.972745) (xy 108.688619 -388.018595) (xy 108.652928 -388.059786) (xy 108.611737 -388.095477)
			(xy 108.565887 -388.124943) (xy 108.51631 -388.147585) (xy 108.464015 -388.16294) (xy 108.410067 -388.170696)
			(xy 108.355565 -388.170696) (xy 108.301617 -388.16294) (xy 108.249322 -388.147585) (xy 108.199745 -388.124943)
			(xy 108.153895 -388.095477) (xy 108.112704 -388.059786) (xy 108.077013 -388.018595) (xy 108.047547 -387.972745)
			(xy 108.024905 -387.923168) (xy 108.00955 -387.870873) (xy 108.001794 -387.816925) (xy 108.001308 -387.789674)
			(xy 74.192384 -387.789674) (xy 74.191898 -387.816943) (xy 74.184136 -387.870927) (xy 74.168771 -387.923257)
			(xy 74.146114 -387.972867) (xy 74.116628 -388.018748) (xy 74.080913 -388.059965) (xy 74.039696 -388.09568)
			(xy 73.993815 -388.125166) (xy 73.944205 -388.147823) (xy 73.891875 -388.163188) (xy 73.837891 -388.17095)
			(xy 73.783353 -388.17095) (xy 73.729369 -388.163188) (xy 73.677039 -388.147823) (xy 73.627429 -388.125166)
			(xy 73.581548 -388.09568) (xy 73.540331 -388.059965) (xy 73.504616 -388.018748) (xy 73.47513 -387.972867)
			(xy 73.452473 -387.923257) (xy 73.437108 -387.870927) (xy 73.429346 -387.816943) (xy 73.42886 -387.789674)
			(xy 41.664636 -387.789674) (xy 41.66415 -387.816943) (xy 41.656388 -387.870927) (xy 41.641023 -387.923257)
			(xy 41.618366 -387.972867) (xy 41.58888 -388.018748) (xy 41.553165 -388.059965) (xy 41.511948 -388.09568)
			(xy 41.466067 -388.125166) (xy 41.416457 -388.147823) (xy 41.364127 -388.163188) (xy 41.310143 -388.17095)
			(xy 41.255605 -388.17095) (xy 41.201621 -388.163188) (xy 41.149291 -388.147823) (xy 41.099681 -388.125166)
			(xy 41.0538 -388.09568) (xy 41.012583 -388.059965) (xy 40.976868 -388.018748) (xy 40.947382 -387.972867)
			(xy 40.924725 -387.923257) (xy 40.90936 -387.870927) (xy 40.901598 -387.816943) (xy 40.901112 -387.789674)
			(xy 2.509012 -387.789674) (xy 2.509012 -388.797976) (xy 47.486325 -388.797976) (xy 47.486573 -388.747043)
			(xy 47.495267 -388.696858) (xy 47.512163 -388.648809) (xy 47.536795 -388.604229) (xy 47.56848 -388.564351)
			(xy 47.60634 -388.530281) (xy 47.649327 -388.502963) (xy 47.696249 -388.483153) (xy 47.745807 -388.471399)
			(xy 47.796628 -388.468029) (xy 47.847305 -388.473134) (xy 47.896432 -388.486573) (xy 47.942651 -388.507975)
			(xy 47.984679 -388.536747) (xy 48.021353 -388.57209) (xy 48.051657 -388.613027) (xy 48.063658 -388.635494)
			(xy 48.064166 -388.636764) (xy 48.15733 -388.797975) (xy 48.686228 -388.797975) (xy 48.686477 -388.747043)
			(xy 48.69517 -388.696859) (xy 48.712067 -388.648811) (xy 48.736698 -388.604231) (xy 48.768383 -388.564354)
			(xy 48.806242 -388.530284) (xy 48.849228 -388.502966) (xy 48.89615 -388.483156) (xy 48.945707 -388.471403)
			(xy 48.996528 -388.468032) (xy 49.047203 -388.473137) (xy 49.09633 -388.486576) (xy 49.142548 -388.507978)
			(xy 49.184575 -388.536748) (xy 49.221249 -388.572091) (xy 49.251553 -388.613027) (xy 49.263554 -388.635494)
			(xy 49.264062 -388.636764) (xy 49.330245 -388.751287) (xy 49.885901 -388.751287) (xy 49.893233 -388.703732)
			(xy 49.907928 -388.657914) (xy 49.929622 -388.614966) (xy 49.95778 -388.575949) (xy 49.991706 -388.541827)
			(xy 50.03056 -388.513445) (xy 50.073382 -388.491502) (xy 50.119114 -388.476543) (xy 50.166626 -388.468937)
			(xy 50.214742 -388.468871) (xy 50.262274 -388.476348) (xy 50.308047 -388.491183) (xy 50.350929 -388.513008)
			(xy 50.389861 -388.541284) (xy 50.423879 -388.575313) (xy 50.452143 -388.614254) (xy 50.46345 -388.635494)
			(xy 50.463958 -388.636764) (xy 50.53014 -388.751285) (xy 51.086146 -388.751285) (xy 51.093477 -388.703739)
			(xy 51.10817 -388.657929) (xy 51.129861 -388.614989) (xy 51.158013 -388.575979) (xy 51.191932 -388.541863)
			(xy 51.230779 -388.513485) (xy 51.273593 -388.491546) (xy 51.319317 -388.476589) (xy 51.366819 -388.468982)
			(xy 51.414927 -388.468915) (xy 51.462451 -388.476388) (xy 51.508216 -388.491218) (xy 51.551092 -388.513037)
			(xy 51.590018 -388.541306) (xy 51.624032 -388.575327) (xy 51.652294 -388.614258) (xy 51.6636 -388.635494)
			(xy 51.664108 -388.636764) (xy 51.730289 -388.751284) (xy 52.286049 -388.751284) (xy 52.293381 -388.703739)
			(xy 52.308073 -388.65793) (xy 52.329764 -388.614991) (xy 52.357916 -388.575981) (xy 52.391834 -388.541866)
			(xy 52.43068 -388.513488) (xy 52.473494 -388.49155) (xy 52.519217 -388.476592) (xy 52.566719 -388.468986)
			(xy 52.614826 -388.468918) (xy 52.662349 -388.476392) (xy 52.708114 -388.491221) (xy 52.750989 -388.513039)
			(xy 52.789914 -388.541308) (xy 52.823928 -388.575328) (xy 52.85219 -388.614259) (xy 52.863496 -388.635494)
			(xy 52.864004 -388.636764) (xy 52.930187 -388.751287) (xy 53.486104 -388.751287) (xy 53.493436 -388.703733)
			(xy 53.508131 -388.657915) (xy 53.529825 -388.614968) (xy 53.557983 -388.575951) (xy 53.591908 -388.54183)
			(xy 53.630761 -388.513448) (xy 53.673583 -388.491506) (xy 53.719314 -388.476547) (xy 53.766825 -388.468941)
			(xy 53.814941 -388.468875) (xy 53.862473 -388.476351) (xy 53.908245 -388.491185) (xy 53.951126 -388.51301)
			(xy 53.990057 -388.541286) (xy 54.024075 -388.575314) (xy 54.052339 -388.614254) (xy 54.063646 -388.635494)
			(xy 54.064154 -388.636764) (xy 54.130337 -388.751286) (xy 54.686008 -388.751286) (xy 54.69334 -388.703733)
			(xy 54.708035 -388.657917) (xy 54.729728 -388.61497) (xy 54.757886 -388.575954) (xy 54.79181 -388.541833)
			(xy 54.830663 -388.513451) (xy 54.873484 -388.491509) (xy 54.919215 -388.476551) (xy 54.966725 -388.468944)
			(xy 55.01484 -388.468878) (xy 55.062371 -388.476355) (xy 55.108142 -388.491188) (xy 55.151023 -388.513012)
			(xy 55.189954 -388.541288) (xy 55.223971 -388.575315) (xy 55.252235 -388.614254) (xy 55.263542 -388.635494)
			(xy 55.26405 -388.636764) (xy 55.330233 -388.751286) (xy 55.885912 -388.751286) (xy 55.893244 -388.703734)
			(xy 55.907938 -388.657918) (xy 55.929632 -388.614971) (xy 55.957788 -388.575956) (xy 55.991712 -388.541836)
			(xy 56.030564 -388.513454) (xy 56.073385 -388.491513) (xy 56.119115 -388.476554) (xy 56.166624 -388.468948)
			(xy 56.214739 -388.468882) (xy 56.262269 -388.476358) (xy 56.30804 -388.491191) (xy 56.35092 -388.513015)
			(xy 56.38985 -388.54129) (xy 56.423868 -388.575317) (xy 56.452131 -388.614255) (xy 56.463438 -388.635494)
			(xy 56.463946 -388.636764) (xy 56.530127 -388.751284) (xy 57.086156 -388.751284) (xy 57.093488 -388.70374)
			(xy 57.10818 -388.657933) (xy 57.12987 -388.614994) (xy 57.158021 -388.575986) (xy 57.191939 -388.541872)
			(xy 57.230784 -388.513495) (xy 57.273596 -388.491557) (xy 57.319317 -388.476599) (xy 57.366818 -388.468993)
			(xy 57.414924 -388.468925) (xy 57.462446 -388.476398) (xy 57.508209 -388.491226) (xy 57.551083 -388.513044)
			(xy 57.590007 -388.541311) (xy 57.624021 -388.57533) (xy 57.652282 -388.614259) (xy 57.663588 -388.635494)
			(xy 57.664096 -388.636764) (xy 57.730277 -388.751284) (xy 58.28606 -388.751284) (xy 58.293391 -388.703741)
			(xy 58.308083 -388.657934) (xy 58.329773 -388.614996) (xy 58.357924 -388.575988) (xy 58.391841 -388.541874)
			(xy 58.430685 -388.513498) (xy 58.473497 -388.49156) (xy 58.519217 -388.476603) (xy 58.566717 -388.468997)
			(xy 58.614822 -388.468929) (xy 58.662344 -388.476401) (xy 58.708107 -388.491229) (xy 58.75098 -388.513046)
			(xy 58.789904 -388.541313) (xy 58.823917 -388.575331) (xy 58.852178 -388.61426) (xy 58.863484 -388.635494)
			(xy 58.863992 -388.636764) (xy 58.930175 -388.751286) (xy 59.486115 -388.751286) (xy 59.493447 -388.703734)
			(xy 59.508141 -388.657919) (xy 59.529835 -388.614973) (xy 59.557991 -388.575958) (xy 59.591914 -388.541839)
			(xy 59.630766 -388.513457) (xy 59.673585 -388.491516) (xy 59.719315 -388.476558) (xy 59.766824 -388.468952)
			(xy 59.814937 -388.468885) (xy 59.862467 -388.476361) (xy 59.908237 -388.491194) (xy 59.951117 -388.513017)
			(xy 59.990047 -388.541291) (xy 60.024064 -388.575318) (xy 60.052327 -388.614255) (xy 60.063634 -388.635494)
			(xy 60.064142 -388.636764) (xy 60.130325 -388.751286) (xy 60.686019 -388.751286) (xy 60.693351 -388.703735)
			(xy 60.708045 -388.65792) (xy 60.729738 -388.614975) (xy 60.757893 -388.575961) (xy 60.791816 -388.541841)
			(xy 60.830667 -388.513461) (xy 60.873486 -388.49152) (xy 60.919215 -388.476561) (xy 60.966723 -388.468955)
			(xy 61.014836 -388.468889) (xy 61.062365 -388.476364) (xy 61.108135 -388.491197) (xy 61.151014 -388.513019)
			(xy 61.189943 -388.541293) (xy 61.22396 -388.575319) (xy 61.252223 -388.614255) (xy 61.26353 -388.635494)
			(xy 61.264038 -388.636764) (xy 61.330221 -388.751286) (xy 61.885922 -388.751286) (xy 61.893254 -388.703735)
			(xy 61.907948 -388.657921) (xy 61.929641 -388.614977) (xy 61.957796 -388.575963) (xy 61.991718 -388.541844)
			(xy 62.030569 -388.513464) (xy 62.073387 -388.491523) (xy 62.119115 -388.476565) (xy 62.166623 -388.468959)
			(xy 62.214735 -388.468892) (xy 62.262263 -388.476368) (xy 62.308032 -388.4912) (xy 62.350911 -388.513022)
			(xy 62.38984 -388.541295) (xy 62.423856 -388.57532) (xy 62.452119 -388.614256) (xy 62.463426 -388.635494)
			(xy 62.463934 -388.636764) (xy 62.530115 -388.751284) (xy 63.086167 -388.751284) (xy 63.093498 -388.703742)
			(xy 63.10819 -388.657936) (xy 63.129879 -388.615) (xy 63.158029 -388.575993) (xy 63.191945 -388.54188)
			(xy 63.230788 -388.513504) (xy 63.273598 -388.491567) (xy 63.319318 -388.47661) (xy 63.366816 -388.469004)
			(xy 63.41492 -388.468936) (xy 63.46244 -388.476408) (xy 63.508202 -388.491235) (xy 63.551074 -388.513051)
			(xy 63.589997 -388.541317) (xy 63.624009 -388.575333) (xy 63.65227 -388.61426) (xy 63.663576 -388.635494)
			(xy 63.664084 -388.636764) (xy 63.757251 -388.797979) (xy 64.286112 -388.797979) (xy 64.286361 -388.747044)
			(xy 64.295054 -388.696856) (xy 64.311952 -388.648805) (xy 64.336585 -388.604222) (xy 64.368271 -388.564342)
			(xy 64.406133 -388.530271) (xy 64.449122 -388.502951) (xy 64.496047 -388.48314) (xy 64.545608 -388.471387)
			(xy 64.596432 -388.468016) (xy 64.647111 -388.473122) (xy 64.696241 -388.486563) (xy 64.742461 -388.507967)
			(xy 64.784491 -388.53674) (xy 64.821166 -388.572086) (xy 64.851471 -388.613026) (xy 64.863472 -388.635494)
			(xy 64.86398 -388.636764) (xy 64.930163 -388.751286) (xy 65.486126 -388.751286) (xy 65.493458 -388.703736)
			(xy 65.508151 -388.657923) (xy 65.529844 -388.614979) (xy 65.557999 -388.575966) (xy 65.59192 -388.541847)
			(xy 65.63077 -388.513467) (xy 65.673588 -388.491527) (xy 65.719316 -388.476569) (xy 65.766822 -388.468962)
			(xy 65.814934 -388.468896) (xy 65.862461 -388.476371) (xy 65.90823 -388.491202) (xy 65.951108 -388.513024)
			(xy 65.990037 -388.541297) (xy 66.024053 -388.575321) (xy 66.052315 -388.614256) (xy 66.063622 -388.635494)
			(xy 66.06413 -388.636764) (xy 66.130312 -388.751285) (xy 80.01394 -388.751285) (xy 80.021272 -388.703738)
			(xy 80.035965 -388.657927) (xy 80.057656 -388.614986) (xy 80.085809 -388.575975) (xy 80.119729 -388.541859)
			(xy 80.158577 -388.51348) (xy 80.201392 -388.491541) (xy 80.247116 -388.476583) (xy 80.29462 -388.468977)
			(xy 80.342729 -388.46891) (xy 80.390254 -388.476384) (xy 80.43602 -388.491214) (xy 80.478896 -388.513033)
			(xy 80.517823 -388.541304) (xy 80.551837 -388.575325) (xy 80.5801 -388.614258) (xy 80.591406 -388.635494)
			(xy 80.591914 -388.636764) (xy 80.658096 -388.751285) (xy 81.213844 -388.751285) (xy 81.221175 -388.703738)
			(xy 81.235868 -388.657929) (xy 81.257559 -388.614988) (xy 81.285712 -388.575977) (xy 81.319631 -388.541862)
			(xy 81.358478 -388.513483) (xy 81.401293 -388.491544) (xy 81.447017 -388.476587) (xy 81.49452 -388.46898)
			(xy 81.542628 -388.468913) (xy 81.590152 -388.476387) (xy 81.635918 -388.491217) (xy 81.678793 -388.513036)
			(xy 81.717719 -388.541305) (xy 81.751734 -388.575326) (xy 81.779996 -388.614258) (xy 81.791302 -388.635494)
			(xy 81.79181 -388.636764) (xy 81.857992 -388.751285) (xy 82.413748 -388.751285) (xy 82.421079 -388.703739)
			(xy 82.435771 -388.65793) (xy 82.457462 -388.61499) (xy 82.485615 -388.57598) (xy 82.519533 -388.541864)
			(xy 82.55838 -388.513487) (xy 82.601194 -388.491548) (xy 82.646917 -388.47659) (xy 82.694419 -388.468984)
			(xy 82.742527 -388.468917) (xy 82.79005 -388.47639) (xy 82.835815 -388.491219) (xy 82.87869 -388.513038)
			(xy 82.917616 -388.541307) (xy 82.95163 -388.575327) (xy 82.979892 -388.614258) (xy 82.991198 -388.635494)
			(xy 82.991706 -388.636764) (xy 83.057889 -388.751287) (xy 83.613803 -388.751287) (xy 83.621135 -388.703732)
			(xy 83.635829 -388.657915) (xy 83.657524 -388.614967) (xy 83.685682 -388.57595) (xy 83.719607 -388.541829)
			(xy 83.75846 -388.513446) (xy 83.801282 -388.491504) (xy 83.847014 -388.476545) (xy 83.894525 -388.468939)
			(xy 83.942642 -388.468873) (xy 83.990174 -388.47635) (xy 84.035946 -388.491184) (xy 84.078828 -388.513009)
			(xy 84.117759 -388.541285) (xy 84.151777 -388.575314) (xy 84.180041 -388.614254) (xy 84.191348 -388.635494)
			(xy 84.191856 -388.636764) (xy 84.258039 -388.751287) (xy 84.813706 -388.751287) (xy 84.821038 -388.703733)
			(xy 84.835733 -388.657916) (xy 84.857427 -388.614969) (xy 84.885584 -388.575952) (xy 84.919509 -388.541831)
			(xy 84.958362 -388.513449) (xy 85.001183 -388.491508) (xy 85.046914 -388.476549) (xy 85.094425 -388.468942)
			(xy 85.14254 -388.468877) (xy 85.190072 -388.476353) (xy 85.235844 -388.491187) (xy 85.278725 -388.513011)
			(xy 85.317655 -388.541287) (xy 85.351673 -388.575315) (xy 85.379937 -388.614254) (xy 85.391244 -388.635494)
			(xy 85.391752 -388.636764) (xy 85.457933 -388.751284) (xy 86.013951 -388.751284) (xy 86.021282 -388.703739)
			(xy 86.035975 -388.657931) (xy 86.057665 -388.614992) (xy 86.085817 -388.575982) (xy 86.119735 -388.541867)
			(xy 86.158581 -388.51349) (xy 86.201394 -388.491551) (xy 86.247117 -388.476594) (xy 86.294619 -388.468988)
			(xy 86.342725 -388.46892) (xy 86.390248 -388.476393) (xy 86.436013 -388.491222) (xy 86.478887 -388.513041)
			(xy 86.517813 -388.541309) (xy 86.551826 -388.575329) (xy 86.580088 -388.614259) (xy 86.591394 -388.635494)
			(xy 86.591902 -388.636764) (xy 86.658083 -388.751284) (xy 87.213855 -388.751284) (xy 87.221186 -388.70374)
			(xy 87.235878 -388.657932) (xy 87.257568 -388.614993) (xy 87.28572 -388.575985) (xy 87.319638 -388.54187)
			(xy 87.358483 -388.513493) (xy 87.401295 -388.491555) (xy 87.447017 -388.476598) (xy 87.494518 -388.468991)
			(xy 87.542624 -388.468924) (xy 87.590147 -388.476397) (xy 87.63591 -388.491225) (xy 87.678784 -388.513043)
			(xy 87.717709 -388.541311) (xy 87.751722 -388.57533) (xy 87.779984 -388.614259) (xy 87.79129 -388.635494)
			(xy 87.791798 -388.636764) (xy 87.857979 -388.751284) (xy 88.413758 -388.751284) (xy 88.42109 -388.70374)
			(xy 88.435782 -388.657933) (xy 88.457471 -388.614995) (xy 88.485623 -388.575987) (xy 88.51954 -388.541873)
			(xy 88.558384 -388.513496) (xy 88.601196 -388.491558) (xy 88.646917 -388.476601) (xy 88.694418 -388.468995)
			(xy 88.742523 -388.468927) (xy 88.790045 -388.4764) (xy 88.835808 -388.491228) (xy 88.878681 -388.513045)
			(xy 88.917606 -388.541312) (xy 88.951619 -388.575331) (xy 88.97988 -388.614259) (xy 88.991186 -388.635494)
			(xy 88.991694 -388.636764) (xy 89.057877 -388.751286) (xy 89.613813 -388.751286) (xy 89.621145 -388.703734)
			(xy 89.63584 -388.657918) (xy 89.657533 -388.614972) (xy 89.68569 -388.575957) (xy 89.719613 -388.541837)
			(xy 89.758465 -388.513456) (xy 89.801285 -388.491515) (xy 89.847015 -388.476556) (xy 89.894524 -388.46895)
			(xy 89.942638 -388.468884) (xy 89.990168 -388.476359) (xy 90.035939 -388.491192) (xy 90.078819 -388.513016)
			(xy 90.117749 -388.54129) (xy 90.151766 -388.575317) (xy 90.180029 -388.614255) (xy 90.191336 -388.635494)
			(xy 90.191844 -388.636764) (xy 90.258027 -388.751286) (xy 90.813717 -388.751286) (xy 90.821049 -388.703734)
			(xy 90.835743 -388.65792) (xy 90.857436 -388.614974) (xy 90.885592 -388.57596) (xy 90.919515 -388.54184)
			(xy 90.958366 -388.513459) (xy 91.001186 -388.491518) (xy 91.046915 -388.47656) (xy 91.094423 -388.468953)
			(xy 91.142537 -388.468887) (xy 91.190066 -388.476363) (xy 91.235836 -388.491195) (xy 91.278716 -388.513018)
			(xy 91.317645 -388.541292) (xy 91.351662 -388.575318) (xy 91.379925 -388.614255) (xy 91.391232 -388.635494)
			(xy 91.39174 -388.636764) (xy 91.457921 -388.751284) (xy 92.013962 -388.751284) (xy 92.021293 -388.703741)
			(xy 92.035985 -388.657935) (xy 92.057674 -388.614997) (xy 92.085825 -388.575989) (xy 92.119742 -388.541876)
			(xy 92.158586 -388.5135) (xy 92.201397 -388.491562) (xy 92.247118 -388.476605) (xy 92.294617 -388.468999)
			(xy 92.342722 -388.468931) (xy 92.390243 -388.476403) (xy 92.436005 -388.491231) (xy 92.478878 -388.513048)
			(xy 92.517802 -388.541314) (xy 92.551815 -388.575332) (xy 92.580076 -388.61426) (xy 92.591382 -388.635494)
			(xy 92.59189 -388.636764) (xy 92.658071 -388.751284) (xy 93.213865 -388.751284) (xy 93.221197 -388.703741)
			(xy 93.235888 -388.657936) (xy 93.257577 -388.614999) (xy 93.285728 -388.575992) (xy 93.319644 -388.541879)
			(xy 93.358487 -388.513503) (xy 93.401298 -388.491565) (xy 93.447018 -388.476609) (xy 93.494517 -388.469002)
			(xy 93.542621 -388.468934) (xy 93.590141 -388.476406) (xy 93.635903 -388.491234) (xy 93.678775 -388.51305)
			(xy 93.717699 -388.541316) (xy 93.751711 -388.575333) (xy 93.779972 -388.61426) (xy 93.791278 -388.635494)
			(xy 93.791786 -388.636764) (xy 93.884953 -388.797979) (xy 94.413811 -388.797979) (xy 94.414059 -388.747044)
			(xy 94.422753 -388.696855) (xy 94.43965 -388.648804) (xy 94.464283 -388.604221) (xy 94.49597 -388.564341)
			(xy 94.533833 -388.530269) (xy 94.576822 -388.502949) (xy 94.623747 -388.483138) (xy 94.673308 -388.471385)
			(xy 94.724132 -388.468014) (xy 94.774811 -388.47312) (xy 94.823942 -388.486562) (xy 94.870162 -388.507966)
			(xy 94.912192 -388.536739) (xy 94.948868 -388.572086) (xy 94.979173 -388.613025) (xy 94.991174 -388.635494)
			(xy 94.991682 -388.636764) (xy 95.057865 -388.751286) (xy 95.613824 -388.751286) (xy 95.621156 -388.703735)
			(xy 95.63585 -388.657922) (xy 95.657542 -388.614978) (xy 95.685697 -388.575964) (xy 95.719619 -388.541846)
			(xy 95.75847 -388.513466) (xy 95.801288 -388.491525) (xy 95.847015 -388.476567) (xy 95.894522 -388.468961)
			(xy 95.942634 -388.468894) (xy 95.990162 -388.476369) (xy 96.035931 -388.491201) (xy 96.07881 -388.513023)
			(xy 96.117738 -388.541296) (xy 96.151754 -388.57532) (xy 96.180017 -388.614256) (xy 96.191324 -388.635494)
			(xy 96.191832 -388.636764) (xy 96.258014 -388.751285) (xy 96.813728 -388.751285) (xy 96.821059 -388.703736)
			(xy 96.835753 -388.657923) (xy 96.857445 -388.61498) (xy 96.8856 -388.575967) (xy 96.919522 -388.541849)
			(xy 96.958371 -388.513469) (xy 97.001189 -388.491529) (xy 97.046916 -388.476571) (xy 97.094422 -388.468964)
			(xy 97.142533 -388.468898) (xy 97.19006 -388.476372) (xy 97.235829 -388.491204) (xy 97.278707 -388.513025)
			(xy 97.317635 -388.541297) (xy 97.351651 -388.575321) (xy 97.379913 -388.614256) (xy 97.39122 -388.635494)
			(xy 97.391728 -388.636764) (xy 97.484894 -388.797978) (xy 98.014014 -388.797978) (xy 98.014263 -388.747044)
			(xy 98.022956 -388.696856) (xy 98.039853 -388.648805) (xy 98.064486 -388.604223) (xy 98.096173 -388.564344)
			(xy 98.134034 -388.530272) (xy 98.177023 -388.502953) (xy 98.223948 -388.483142) (xy 98.273508 -388.471388)
			(xy 98.324331 -388.468018) (xy 98.37501 -388.473124) (xy 98.424139 -388.486565) (xy 98.470359 -388.507968)
			(xy 98.512389 -388.536741) (xy 98.549064 -388.572087) (xy 98.579369 -388.613026) (xy 98.59137 -388.635494)
			(xy 98.591878 -388.636764) (xy 98.65806 -388.751285) (xy 114.586146 -388.751285) (xy 114.593477 -388.703739)
			(xy 114.60817 -388.657929) (xy 114.629861 -388.614989) (xy 114.658013 -388.575979) (xy 114.691932 -388.541863)
			(xy 114.730779 -388.513485) (xy 114.773593 -388.491546) (xy 114.819317 -388.476589) (xy 114.866819 -388.468982)
			(xy 114.914927 -388.468915) (xy 114.962451 -388.476388) (xy 115.008216 -388.491218) (xy 115.051092 -388.513037)
			(xy 115.090018 -388.541306) (xy 115.124032 -388.575327) (xy 115.152294 -388.614258) (xy 115.1636 -388.635494)
			(xy 115.164108 -388.636764) (xy 115.230289 -388.751284) (xy 115.786049 -388.751284) (xy 115.793381 -388.703739)
			(xy 115.808073 -388.65793) (xy 115.829764 -388.614991) (xy 115.857916 -388.575981) (xy 115.891834 -388.541866)
			(xy 115.93068 -388.513488) (xy 115.973494 -388.49155) (xy 116.019217 -388.476592) (xy 116.066719 -388.468986)
			(xy 116.114826 -388.468918) (xy 116.162349 -388.476392) (xy 116.208114 -388.491221) (xy 116.250989 -388.513039)
			(xy 116.289914 -388.541308) (xy 116.323928 -388.575328) (xy 116.35219 -388.614259) (xy 116.363496 -388.635494)
			(xy 116.364004 -388.636764) (xy 116.430185 -388.751284) (xy 116.985953 -388.751284) (xy 116.993284 -388.70374)
			(xy 117.007977 -388.657932) (xy 117.029667 -388.614992) (xy 117.057819 -388.575983) (xy 117.091737 -388.541869)
			(xy 117.130582 -388.513491) (xy 117.173395 -388.491553) (xy 117.219117 -388.476596) (xy 117.266618 -388.468989)
			(xy 117.314725 -388.468922) (xy 117.362247 -388.476395) (xy 117.408011 -388.491224) (xy 117.450886 -388.513042)
			(xy 117.489811 -388.54131) (xy 117.523824 -388.575329) (xy 117.552086 -388.614259) (xy 117.563392 -388.635494)
			(xy 117.5639 -388.636764) (xy 117.630083 -388.751286) (xy 118.186008 -388.751286) (xy 118.19334 -388.703733)
			(xy 118.208035 -388.657917) (xy 118.229728 -388.61497) (xy 118.257886 -388.575954) (xy 118.29181 -388.541833)
			(xy 118.330663 -388.513451) (xy 118.373484 -388.491509) (xy 118.419215 -388.476551) (xy 118.466725 -388.468944)
			(xy 118.51484 -388.468878) (xy 118.562371 -388.476355) (xy 118.608142 -388.491188) (xy 118.651023 -388.513012)
			(xy 118.689954 -388.541288) (xy 118.723971 -388.575315) (xy 118.752235 -388.614254) (xy 118.763542 -388.635494)
			(xy 118.76405 -388.636764) (xy 118.830233 -388.751286) (xy 119.385912 -388.751286) (xy 119.393244 -388.703734)
			(xy 119.407938 -388.657918) (xy 119.429632 -388.614971) (xy 119.457788 -388.575956) (xy 119.491712 -388.541836)
			(xy 119.530564 -388.513454) (xy 119.573385 -388.491513) (xy 119.619115 -388.476554) (xy 119.666624 -388.468948)
			(xy 119.714739 -388.468882) (xy 119.762269 -388.476358) (xy 119.80804 -388.491191) (xy 119.85092 -388.513015)
			(xy 119.88985 -388.54129) (xy 119.923868 -388.575317) (xy 119.952131 -388.614255) (xy 119.963438 -388.635494)
			(xy 119.963946 -388.636764) (xy 120.030127 -388.751284) (xy 120.586156 -388.751284) (xy 120.593488 -388.70374)
			(xy 120.60818 -388.657933) (xy 120.62987 -388.614994) (xy 120.658021 -388.575986) (xy 120.691939 -388.541872)
			(xy 120.730784 -388.513495) (xy 120.773596 -388.491557) (xy 120.819317 -388.476599) (xy 120.866818 -388.468993)
			(xy 120.914924 -388.468925) (xy 120.962446 -388.476398) (xy 121.008209 -388.491226) (xy 121.051083 -388.513044)
			(xy 121.090007 -388.541311) (xy 121.124021 -388.57533) (xy 121.152282 -388.614259) (xy 121.163588 -388.635494)
			(xy 121.164096 -388.636764) (xy 121.230277 -388.751284) (xy 121.78606 -388.751284) (xy 121.793391 -388.703741)
			(xy 121.808083 -388.657934) (xy 121.829773 -388.614996) (xy 121.857924 -388.575988) (xy 121.891841 -388.541874)
			(xy 121.930685 -388.513498) (xy 121.973497 -388.49156) (xy 122.019217 -388.476603) (xy 122.066717 -388.468997)
			(xy 122.114822 -388.468929) (xy 122.162344 -388.476401) (xy 122.208107 -388.491229) (xy 122.25098 -388.513046)
			(xy 122.289904 -388.541313) (xy 122.323917 -388.575331) (xy 122.352178 -388.61426) (xy 122.363484 -388.635494)
			(xy 122.363992 -388.636764) (xy 122.430173 -388.751284) (xy 122.985964 -388.751284) (xy 122.993295 -388.703741)
			(xy 123.007987 -388.657935) (xy 123.029676 -388.614998) (xy 123.057827 -388.575991) (xy 123.091743 -388.541877)
			(xy 123.130587 -388.513501) (xy 123.173398 -388.491564) (xy 123.219118 -388.476607) (xy 123.266617 -388.469)
			(xy 123.314721 -388.468932) (xy 123.362242 -388.476405) (xy 123.408004 -388.491232) (xy 123.450877 -388.513049)
			(xy 123.4898 -388.541315) (xy 123.523813 -388.575332) (xy 123.552074 -388.61426) (xy 123.56338 -388.635494)
			(xy 123.563888 -388.636764) (xy 123.630071 -388.751286) (xy 124.186019 -388.751286) (xy 124.193351 -388.703735)
			(xy 124.208045 -388.65792) (xy 124.229738 -388.614975) (xy 124.257893 -388.575961) (xy 124.291816 -388.541841)
			(xy 124.330667 -388.513461) (xy 124.373486 -388.49152) (xy 124.419215 -388.476561) (xy 124.466723 -388.468955)
			(xy 124.514836 -388.468889) (xy 124.562365 -388.476364) (xy 124.608135 -388.491197) (xy 124.651014 -388.513019)
			(xy 124.689943 -388.541293) (xy 124.72396 -388.575319) (xy 124.752223 -388.614255) (xy 124.76353 -388.635494)
			(xy 124.764038 -388.636764) (xy 124.830221 -388.751286) (xy 125.385922 -388.751286) (xy 125.393254 -388.703735)
			(xy 125.407948 -388.657921) (xy 125.429641 -388.614977) (xy 125.457796 -388.575963) (xy 125.491718 -388.541844)
			(xy 125.530569 -388.513464) (xy 125.573387 -388.491523) (xy 125.619115 -388.476565) (xy 125.666623 -388.468959)
			(xy 125.714735 -388.468892) (xy 125.762263 -388.476368) (xy 125.808032 -388.4912) (xy 125.850911 -388.513022)
			(xy 125.88984 -388.541295) (xy 125.923856 -388.57532) (xy 125.952119 -388.614256) (xy 125.963426 -388.635494)
			(xy 125.963934 -388.636764) (xy 126.030115 -388.751284) (xy 126.586167 -388.751284) (xy 126.593498 -388.703742)
			(xy 126.60819 -388.657936) (xy 126.629879 -388.615) (xy 126.658029 -388.575993) (xy 126.691945 -388.54188)
			(xy 126.730788 -388.513504) (xy 126.773598 -388.491567) (xy 126.819318 -388.47661) (xy 126.866816 -388.469004)
			(xy 126.91492 -388.468936) (xy 126.96244 -388.476408) (xy 127.008202 -388.491235) (xy 127.051074 -388.513051)
			(xy 127.089997 -388.541317) (xy 127.124009 -388.575333) (xy 127.15227 -388.61426) (xy 127.163576 -388.635494)
			(xy 127.164084 -388.636764) (xy 127.257251 -388.797979) (xy 127.786112 -388.797979) (xy 127.786361 -388.747044)
			(xy 127.795054 -388.696856) (xy 127.811952 -388.648805) (xy 127.836585 -388.604222) (xy 127.868271 -388.564342)
			(xy 127.906133 -388.530271) (xy 127.949122 -388.502951) (xy 127.996047 -388.48314) (xy 128.045608 -388.471387)
			(xy 128.096432 -388.468016) (xy 128.147111 -388.473122) (xy 128.196241 -388.486563) (xy 128.242461 -388.507967)
			(xy 128.284491 -388.53674) (xy 128.321166 -388.572086) (xy 128.351471 -388.613026) (xy 128.363472 -388.635494)
			(xy 128.36398 -388.636764) (xy 128.457146 -388.797978) (xy 128.986016 -388.797978) (xy 128.986265 -388.747044)
			(xy 128.994958 -388.696856) (xy 129.011855 -388.648806) (xy 129.036488 -388.604224) (xy 129.068174 -388.564345)
			(xy 129.106035 -388.530274) (xy 129.149024 -388.502955) (xy 129.195948 -388.483144) (xy 129.245508 -388.47139)
			(xy 129.296331 -388.46802) (xy 129.347009 -388.473125) (xy 129.396138 -388.486566) (xy 129.442358 -388.507969)
			(xy 129.484387 -388.536742) (xy 129.521062 -388.572087) (xy 129.551367 -388.613026) (xy 129.563368 -388.635494)
			(xy 129.563876 -388.636764) (xy 129.630058 -388.751285) (xy 130.18603 -388.751285) (xy 130.193361 -388.703736)
			(xy 130.208055 -388.657924) (xy 130.229747 -388.614981) (xy 130.257901 -388.575968) (xy 130.291823 -388.54185)
			(xy 130.330672 -388.51347) (xy 130.373489 -388.49153) (xy 130.419216 -388.476572) (xy 130.466722 -388.468966)
			(xy 130.514833 -388.468899) (xy 130.56236 -388.476374) (xy 130.608128 -388.491205) (xy 130.651005 -388.513026)
			(xy 130.689933 -388.541298) (xy 130.723949 -388.575322) (xy 130.752211 -388.614256) (xy 130.763518 -388.635494)
			(xy 130.764026 -388.636764) (xy 130.830208 -388.751285) (xy 131.385933 -388.751285) (xy 131.393265 -388.703737)
			(xy 131.407958 -388.657925) (xy 131.42965 -388.614982) (xy 131.457804 -388.57597) (xy 131.491725 -388.541853)
			(xy 131.530573 -388.513474) (xy 131.57339 -388.491534) (xy 131.619116 -388.476576) (xy 131.666621 -388.46897)
			(xy 131.714731 -388.468903) (xy 131.762258 -388.476377) (xy 131.808025 -388.491208) (xy 131.850902 -388.513029)
			(xy 131.88983 -388.5413) (xy 131.923845 -388.575323) (xy 131.952107 -388.614257) (xy 131.963414 -388.635494)
			(xy 131.963922 -388.636764) (xy 132.057087 -388.797977) (xy 132.586219 -388.797977) (xy 132.586468 -388.747044)
			(xy 132.595161 -388.696857) (xy 132.612058 -388.648807) (xy 132.636691 -388.604226) (xy 132.668376 -388.564348)
			(xy 132.706237 -388.530277) (xy 132.749225 -388.502958) (xy 132.796148 -388.483147) (xy 132.845708 -388.471394)
			(xy 132.89653 -388.468023) (xy 132.947207 -388.473129) (xy 132.996336 -388.486569) (xy 133.042555 -388.507972)
			(xy 133.084584 -388.536744) (xy 133.121258 -388.572088) (xy 133.151563 -388.613026) (xy 133.163564 -388.635494)
			(xy 133.164072 -388.636764) (xy 133.230255 -388.751287) (xy 147.113803 -388.751287) (xy 147.121135 -388.703732)
			(xy 147.135829 -388.657915) (xy 147.157524 -388.614967) (xy 147.185682 -388.57595) (xy 147.219607 -388.541829)
			(xy 147.25846 -388.513446) (xy 147.301282 -388.491504) (xy 147.347014 -388.476545) (xy 147.394525 -388.468939)
			(xy 147.442642 -388.468873) (xy 147.490174 -388.47635) (xy 147.535946 -388.491184) (xy 147.578828 -388.513009)
			(xy 147.617759 -388.541285) (xy 147.651777 -388.575314) (xy 147.680041 -388.614254) (xy 147.691348 -388.635494)
			(xy 147.691856 -388.636764) (xy 147.758039 -388.751287) (xy 148.313706 -388.751287) (xy 148.321038 -388.703733)
			(xy 148.335733 -388.657916) (xy 148.357427 -388.614969) (xy 148.385584 -388.575952) (xy 148.419509 -388.541831)
			(xy 148.458362 -388.513449) (xy 148.501183 -388.491508) (xy 148.546914 -388.476549) (xy 148.594425 -388.468942)
			(xy 148.64254 -388.468877) (xy 148.690072 -388.476353) (xy 148.735844 -388.491187) (xy 148.778725 -388.513011)
			(xy 148.817655 -388.541287) (xy 148.851673 -388.575315) (xy 148.879937 -388.614254) (xy 148.891244 -388.635494)
			(xy 148.891752 -388.636764) (xy 148.971604 -388.77494) (xy 149.513544 -388.77494) (xy 149.513544 -388.774432)
			(xy 149.514057 -388.749519) (xy 149.522145 -388.700354) (xy 149.538096 -388.653149) (xy 149.549358 -388.630922)
			(xy 149.549358 -388.630668) (xy 149.561087 -388.609816) (xy 149.589876 -388.571614) (xy 149.624267 -388.538365)
			(xy 149.663419 -388.510882) (xy 149.706377 -388.489837) (xy 149.752089 -388.475745) (xy 149.79944 -388.468949)
			(xy 149.84727 -388.469617) (xy 149.894413 -388.477731) (xy 149.939714 -388.493093) (xy 149.982068 -388.515327)
			(xy 150.020439 -388.543891) (xy 150.053889 -388.578087) (xy 150.081601 -388.617078) (xy 150.092664 -388.638288)
			(xy 150.093426 -388.639812) (xy 150.157865 -388.751284) (xy 150.713855 -388.751284) (xy 150.721186 -388.70374)
			(xy 150.735878 -388.657932) (xy 150.757568 -388.614993) (xy 150.78572 -388.575985) (xy 150.819638 -388.54187)
			(xy 150.858483 -388.513493) (xy 150.901295 -388.491555) (xy 150.947017 -388.476598) (xy 150.994518 -388.468991)
			(xy 151.042624 -388.468924) (xy 151.090147 -388.476397) (xy 151.13591 -388.491225) (xy 151.178784 -388.513043)
			(xy 151.217709 -388.541311) (xy 151.251722 -388.57533) (xy 151.279984 -388.614259) (xy 151.29129 -388.635494)
			(xy 151.291798 -388.636764) (xy 151.357979 -388.751284) (xy 151.913758 -388.751284) (xy 151.92109 -388.70374)
			(xy 151.935782 -388.657933) (xy 151.957471 -388.614995) (xy 151.985623 -388.575987) (xy 152.01954 -388.541873)
			(xy 152.058384 -388.513496) (xy 152.101196 -388.491558) (xy 152.146917 -388.476601) (xy 152.194418 -388.468995)
			(xy 152.242523 -388.468927) (xy 152.290045 -388.4764) (xy 152.335808 -388.491228) (xy 152.378681 -388.513045)
			(xy 152.417606 -388.541312) (xy 152.451619 -388.575331) (xy 152.47988 -388.614259) (xy 152.491186 -388.635494)
			(xy 152.491694 -388.636764) (xy 152.557877 -388.751286) (xy 153.113813 -388.751286) (xy 153.121145 -388.703734)
			(xy 153.13584 -388.657918) (xy 153.157533 -388.614972) (xy 153.18569 -388.575957) (xy 153.219613 -388.541837)
			(xy 153.258465 -388.513456) (xy 153.301285 -388.491515) (xy 153.347015 -388.476556) (xy 153.394524 -388.46895)
			(xy 153.442638 -388.468884) (xy 153.490168 -388.476359) (xy 153.535939 -388.491192) (xy 153.578819 -388.513016)
			(xy 153.617749 -388.54129) (xy 153.651766 -388.575317) (xy 153.680029 -388.614255) (xy 153.691336 -388.635494)
			(xy 153.691844 -388.636764) (xy 153.758027 -388.751286) (xy 154.313717 -388.751286) (xy 154.321049 -388.703734)
			(xy 154.335743 -388.65792) (xy 154.357436 -388.614974) (xy 154.385592 -388.57596) (xy 154.419515 -388.54184)
			(xy 154.458366 -388.513459) (xy 154.501186 -388.491518) (xy 154.546915 -388.47656) (xy 154.594423 -388.468953)
			(xy 154.642537 -388.468887) (xy 154.690066 -388.476363) (xy 154.735836 -388.491195) (xy 154.778716 -388.513018)
			(xy 154.817645 -388.541292) (xy 154.851662 -388.575318) (xy 154.879925 -388.614255) (xy 154.891232 -388.635494)
			(xy 154.89174 -388.636764) (xy 154.971592 -388.77494) (xy 155.513532 -388.77494) (xy 155.513532 -388.774432)
			(xy 155.514035 -388.749518) (xy 155.522126 -388.700352) (xy 155.538081 -388.653149) (xy 155.549346 -388.630922)
			(xy 155.549346 -388.630668) (xy 155.560943 -388.609739) (xy 155.589744 -388.571531) (xy 155.624148 -388.538278)
			(xy 155.663314 -388.510793) (xy 155.706286 -388.489749) (xy 155.752012 -388.475659) (xy 155.799375 -388.468868)
			(xy 155.847218 -388.469542) (xy 155.894371 -388.477664) (xy 155.939682 -388.493036) (xy 155.982044 -388.515282)
			(xy 156.020421 -388.543858) (xy 156.053875 -388.578067) (xy 156.081588 -388.617071) (xy 156.092652 -388.638288)
			(xy 156.093414 -388.639812) (xy 156.157853 -388.751284) (xy 156.713865 -388.751284) (xy 156.721197 -388.703741)
			(xy 156.735888 -388.657936) (xy 156.757577 -388.614999) (xy 156.785728 -388.575992) (xy 156.819644 -388.541879)
			(xy 156.858487 -388.513503) (xy 156.901298 -388.491565) (xy 156.947018 -388.476609) (xy 156.994517 -388.469002)
			(xy 157.042621 -388.468934) (xy 157.090141 -388.476406) (xy 157.135903 -388.491234) (xy 157.178775 -388.51305)
			(xy 157.217699 -388.541316) (xy 157.251711 -388.575333) (xy 157.279972 -388.61426) (xy 157.291278 -388.635494)
			(xy 157.291786 -388.636764) (xy 157.384953 -388.797979) (xy 157.913811 -388.797979) (xy 157.914059 -388.747044)
			(xy 157.922753 -388.696855) (xy 157.93965 -388.648804) (xy 157.964283 -388.604221) (xy 157.99597 -388.564341)
			(xy 158.033833 -388.530269) (xy 158.076822 -388.502949) (xy 158.123747 -388.483138) (xy 158.173308 -388.471385)
			(xy 158.224132 -388.468014) (xy 158.274811 -388.47312) (xy 158.323942 -388.486562) (xy 158.370162 -388.507966)
			(xy 158.412192 -388.536739) (xy 158.448868 -388.572086) (xy 158.479173 -388.613025) (xy 158.491174 -388.635494)
			(xy 158.491682 -388.636764) (xy 158.557865 -388.751286) (xy 159.113824 -388.751286) (xy 159.121156 -388.703735)
			(xy 159.13585 -388.657922) (xy 159.157542 -388.614978) (xy 159.185697 -388.575964) (xy 159.219619 -388.541846)
			(xy 159.25847 -388.513466) (xy 159.301288 -388.491525) (xy 159.347015 -388.476567) (xy 159.394522 -388.468961)
			(xy 159.442634 -388.468894) (xy 159.490162 -388.476369) (xy 159.535931 -388.491201) (xy 159.57881 -388.513023)
			(xy 159.617738 -388.541296) (xy 159.651754 -388.57532) (xy 159.680017 -388.614256) (xy 159.691324 -388.635494)
			(xy 159.691832 -388.636764) (xy 159.758014 -388.751285) (xy 160.313728 -388.751285) (xy 160.321059 -388.703736)
			(xy 160.335753 -388.657923) (xy 160.357445 -388.61498) (xy 160.3856 -388.575967) (xy 160.419522 -388.541849)
			(xy 160.458371 -388.513469) (xy 160.501189 -388.491529) (xy 160.546916 -388.476571) (xy 160.594422 -388.468964)
			(xy 160.642533 -388.468898) (xy 160.69006 -388.476372) (xy 160.735829 -388.491204) (xy 160.778707 -388.513025)
			(xy 160.817635 -388.541297) (xy 160.851651 -388.575321) (xy 160.879913 -388.614256) (xy 160.89122 -388.635494)
			(xy 160.891728 -388.636764) (xy 160.97158 -388.77494) (xy 161.51352 -388.77494) (xy 161.51352 -388.774432)
			(xy 161.514025 -388.749519) (xy 161.522115 -388.700353) (xy 161.538069 -388.653149) (xy 161.549334 -388.630922)
			(xy 161.549334 -388.630668) (xy 161.560949 -388.60975) (xy 161.589748 -388.571542) (xy 161.624151 -388.53829)
			(xy 161.663315 -388.510806) (xy 161.706285 -388.489761) (xy 161.752009 -388.475671) (xy 161.79937 -388.468879)
			(xy 161.847211 -388.469552) (xy 161.894363 -388.477673) (xy 161.939673 -388.493044) (xy 161.982033 -388.515288)
			(xy 162.020409 -388.543863) (xy 162.053863 -388.578069) (xy 162.081577 -388.617072) (xy 162.09264 -388.638288)
			(xy 162.093402 -388.639812) (xy 162.184833 -388.797977) (xy 162.713918 -388.797977) (xy 162.714166 -388.747044)
			(xy 162.72286 -388.696857) (xy 162.739757 -388.648807) (xy 162.764389 -388.604225) (xy 162.796075 -388.564346)
			(xy 162.833936 -388.530275) (xy 162.876924 -388.502956) (xy 162.923848 -388.483145) (xy 162.973408 -388.471392)
			(xy 163.02423 -388.468021) (xy 163.074908 -388.473127) (xy 163.124037 -388.486568) (xy 163.170256 -388.50797)
			(xy 163.212286 -388.536743) (xy 163.24896 -388.572088) (xy 163.279265 -388.613026) (xy 163.291266 -388.635494)
			(xy 163.291774 -388.636764) (xy 163.371626 -388.77494) (xy 163.913312 -388.77494) (xy 163.913312 -388.774432)
			(xy 163.913822 -388.749504) (xy 163.921966 -388.700319) (xy 163.938039 -388.653126) (xy 163.94938 -388.630922)
			(xy 163.94938 -388.630668) (xy 163.961076 -388.609797) (xy 163.989868 -388.571593) (xy 164.024262 -388.538343)
			(xy 164.063418 -388.51086) (xy 164.106379 -388.489815) (xy 164.152095 -388.475724) (xy 164.199449 -388.468929)
			(xy 164.247282 -388.469598) (xy 164.294427 -388.477714) (xy 164.339731 -388.493078) (xy 164.382087 -388.515316)
			(xy 164.420459 -388.543883) (xy 164.45391 -388.578082) (xy 164.481623 -388.617076) (xy 164.492686 -388.638288)
			(xy 164.493448 -388.639812) (xy 164.557888 -388.751285) (xy 165.113835 -388.751285) (xy 165.121167 -388.703737)
			(xy 165.13586 -388.657926) (xy 165.157551 -388.614983) (xy 165.185705 -388.575971) (xy 165.219626 -388.541854)
			(xy 165.258474 -388.513475) (xy 165.30129 -388.491536) (xy 165.347016 -388.476578) (xy 165.394521 -388.468971)
			(xy 165.442631 -388.468905) (xy 165.490157 -388.476379) (xy 165.535924 -388.491209) (xy 165.578801 -388.51303)
			(xy 165.617728 -388.541301) (xy 165.651743 -388.575324) (xy 165.680005 -388.614257) (xy 165.691312 -388.635494)
			(xy 165.69182 -388.636764) (xy 165.74419 -388.727385) (xy 193.900548 -388.727385) (xy 193.900548 -388.642663)
			(xy 193.908601 -388.558326) (xy 193.924635 -388.475136) (xy 193.948503 -388.393846) (xy 193.979991 -388.315194)
			(xy 194.018813 -388.239891) (xy 194.064616 -388.168619) (xy 194.116987 -388.102023) (xy 194.175452 -388.040708)
			(xy 194.23948 -387.985227) (xy 194.308492 -387.936084) (xy 194.381862 -387.893724) (xy 194.458927 -387.858529)
			(xy 194.538989 -387.83082) (xy 194.621322 -387.810846) (xy 194.705181 -387.798789) (xy 194.789806 -387.794758)
			(xy 194.874431 -387.798789) (xy 194.95829 -387.810846) (xy 195.040623 -387.83082) (xy 195.120685 -387.858529)
			(xy 195.19775 -387.893724) (xy 195.27112 -387.936084) (xy 195.340132 -387.985227) (xy 195.40416 -388.040708)
			(xy 195.462625 -388.102023) (xy 195.514996 -388.168619) (xy 195.560799 -388.239891) (xy 195.599621 -388.315194)
			(xy 195.631109 -388.393846) (xy 195.654977 -388.475136) (xy 195.671011 -388.558326) (xy 195.679064 -388.642663)
			(xy 195.679568 -388.685024) (xy 195.679064 -388.727385) (xy 195.671011 -388.811722) (xy 195.654977 -388.894912)
			(xy 195.631109 -388.976202) (xy 195.599621 -389.054854) (xy 195.560799 -389.130157) (xy 195.514996 -389.201429)
			(xy 195.462625 -389.268025) (xy 195.40416 -389.32934) (xy 195.355765 -389.371275) (xy 238.989866 -389.371275)
			(xy 238.989866 -389.286553) (xy 238.997919 -389.202216) (xy 239.013953 -389.119026) (xy 239.037821 -389.037736)
			(xy 239.069309 -388.959084) (xy 239.108131 -388.883781) (xy 239.153934 -388.812509) (xy 239.206305 -388.745913)
			(xy 239.26477 -388.684598) (xy 239.328798 -388.629117) (xy 239.39781 -388.579974) (xy 239.47118 -388.537614)
			(xy 239.548245 -388.502419) (xy 239.628307 -388.47471) (xy 239.71064 -388.454736) (xy 239.794499 -388.442679)
			(xy 239.879124 -388.438648) (xy 239.963749 -388.442679) (xy 240.047608 -388.454736) (xy 240.129941 -388.47471)
			(xy 240.210003 -388.502419) (xy 240.287068 -388.537614) (xy 240.360438 -388.579974) (xy 240.42945 -388.629117)
			(xy 240.493478 -388.684598) (xy 240.551943 -388.745913) (xy 240.604314 -388.812509) (xy 240.650117 -388.883781)
			(xy 240.688939 -388.959084) (xy 240.720427 -389.037736) (xy 240.744295 -389.119026) (xy 240.760329 -389.202216)
			(xy 240.768382 -389.286553) (xy 240.768792 -389.321) (xy 241.768928 -389.321) (xy 241.772957 -389.236403)
			(xy 241.78501 -389.152572) (xy 241.804978 -389.070266) (xy 241.832678 -388.990231) (xy 241.867861 -388.913191)
			(xy 241.910207 -388.839845) (xy 241.959334 -388.770856) (xy 242.014797 -388.706849) (xy 242.076092 -388.648404)
			(xy 242.142665 -388.59605) (xy 242.213914 -388.550261) (xy 242.289192 -388.511453) (xy 242.367819 -388.479975)
			(xy 242.449081 -388.456114) (xy 242.532244 -388.440086) (xy 242.616553 -388.432036) (xy 242.6589 -388.431532)
			(xy 242.659408 -388.431532) (xy 242.70574 -388.432135) (xy 242.797898 -388.441807) (xy 242.888552 -388.461003)
			(xy 242.976721 -388.489516) (xy 243.019326 -388.507732) (xy 243.029268 -388.511538) (xy 243.050532 -388.511538)
			(xy 243.060474 -388.507732) (xy 243.103108 -388.489501) (xy 243.191337 -388.460969) (xy 243.282057 -388.441775)
			(xy 243.374282 -388.432129) (xy 243.420646 -388.431532) (xy 243.421154 -388.431532) (xy 243.467518 -388.432123)
			(xy 243.559741 -388.441782) (xy 243.65046 -388.460978) (xy 243.738691 -388.489505) (xy 243.781326 -388.507732)
			(xy 243.791268 -388.511538) (xy 243.812532 -388.511538) (xy 243.822474 -388.507732) (xy 243.861902 -388.4908)
			(xy 243.943323 -388.463701) (xy 243.985034 -388.45363) (xy 243.999004 -388.450328) (xy 244.018816 -388.431024)
			(xy 244.049296 -388.31647) (xy 244.041422 -388.289292) (xy 244.031008 -388.279894) (xy 244.001154 -388.251861)
			(xy 243.946161 -388.191171) (xy 243.89698 -388.125683) (xy 243.854027 -388.055951) (xy 243.817668 -387.982565)
			(xy 243.788209 -387.906147) (xy 243.7659 -387.827344) (xy 243.75093 -387.746825) (xy 243.743427 -387.66527)
			(xy 243.742972 -387.62432) (xy 243.743564 -387.577925) (xy 243.753206 -387.485637) (xy 243.7724 -387.394853)
			(xy 243.800936 -387.306559) (xy 243.819172 -387.263894) (xy 243.822967 -387.253948) (xy 243.822974 -387.232688)
			(xy 243.819172 -387.222746) (xy 243.800933 -387.180082) (xy 243.772387 -387.09179) (xy 243.753193 -387.001006)
			(xy 243.743558 -386.908716) (xy 243.742972 -386.86232) (xy 243.743564 -386.815925) (xy 243.753206 -386.723637)
			(xy 243.7724 -386.632853) (xy 243.800936 -386.544559) (xy 243.819172 -386.501894) (xy 243.822967 -386.491948)
			(xy 243.822974 -386.470688) (xy 243.819172 -386.460746) (xy 243.800955 -386.418141) (xy 243.772437 -386.329974)
			(xy 243.753242 -386.239319) (xy 243.743581 -386.14716) (xy 243.742972 -386.100828) (xy 243.742972 -386.10032)
			(xy 243.743476 -386.057972) (xy 243.751527 -385.973658) (xy 243.767556 -385.890492) (xy 243.791417 -385.809225)
			(xy 243.822896 -385.730595) (xy 243.861707 -385.655314) (xy 243.907497 -385.584062) (xy 243.959853 -385.517486)
			(xy 244.018301 -385.456188) (xy 244.082311 -385.400723) (xy 244.151303 -385.351594) (xy 244.224653 -385.309245)
			(xy 244.301696 -385.274061) (xy 244.381735 -385.246359) (xy 244.464044 -385.226391) (xy 244.547879 -385.214338)
			(xy 244.63248 -385.210308) (xy 244.717081 -385.214338) (xy 244.800916 -385.226391) (xy 244.883225 -385.246359)
			(xy 244.963264 -385.274061) (xy 245.040307 -385.309245) (xy 245.113657 -385.351594) (xy 245.182649 -385.400723)
			(xy 245.246659 -385.456188) (xy 245.305107 -385.517486) (xy 245.357463 -385.584062) (xy 245.403253 -385.655314)
			(xy 245.442064 -385.730595) (xy 245.473543 -385.809225) (xy 245.497404 -385.890492) (xy 245.513433 -385.973658)
			(xy 245.521484 -386.057972) (xy 245.521988 -386.10032) (xy 245.521988 -386.100828) (xy 245.521391 -386.14716)
			(xy 245.511717 -386.239318) (xy 245.492519 -386.329972) (xy 245.464005 -386.418141) (xy 245.445788 -386.460746)
			(xy 245.441972 -386.470685) (xy 245.44198 -386.491951) (xy 245.445788 -386.501894) (xy 245.464038 -386.544554)
			(xy 245.492581 -386.632847) (xy 245.511773 -386.723633) (xy 245.521404 -386.815924) (xy 245.521988 -386.86232)
			(xy 245.521379 -386.908715) (xy 245.511742 -387.001003) (xy 245.492553 -387.091786) (xy 245.464022 -387.180081)
			(xy 245.445788 -387.222746) (xy 245.441972 -387.232685) (xy 245.44198 -387.253951) (xy 245.445788 -387.263894)
			(xy 245.464015 -387.306495) (xy 245.492532 -387.394663) (xy 245.511723 -387.485319) (xy 245.521381 -387.57748)
			(xy 245.521988 -387.623812) (xy 245.521988 -387.62432) (xy 249.677936 -387.62432) (xy 249.677936 -387.623812)
			(xy 249.678545 -387.57748) (xy 249.688215 -387.485322) (xy 249.70741 -387.394668) (xy 249.735921 -387.306499)
			(xy 249.754136 -387.263894) (xy 249.757932 -387.253949) (xy 249.75794 -387.232688) (xy 249.754136 -387.222746)
			(xy 249.735901 -387.18008) (xy 249.707353 -387.091789) (xy 249.688158 -387.001005) (xy 249.678522 -386.908716)
			(xy 249.677936 -386.86232) (xy 249.678522 -386.815924) (xy 249.688166 -386.723636) (xy 249.707361 -386.632852)
			(xy 249.735898 -386.544559) (xy 249.754136 -386.501894) (xy 249.757932 -386.491949) (xy 249.75794 -386.470688)
			(xy 249.754136 -386.460746) (xy 249.735917 -386.418142) (xy 249.707399 -386.329975) (xy 249.688206 -386.23932)
			(xy 249.678545 -386.14716) (xy 249.677936 -386.100828) (xy 249.677936 -386.10032) (xy 249.67844 -386.057972)
			(xy 249.686491 -385.973658) (xy 249.70252 -385.890492) (xy 249.726381 -385.809225) (xy 249.75786 -385.730595)
			(xy 249.796671 -385.655314) (xy 249.842461 -385.584062) (xy 249.894817 -385.517486) (xy 249.953265 -385.456188)
			(xy 250.017275 -385.400723) (xy 250.086267 -385.351594) (xy 250.159617 -385.309245) (xy 250.23666 -385.274061)
			(xy 250.316699 -385.246359) (xy 250.399008 -385.226391) (xy 250.482843 -385.214338) (xy 250.567444 -385.210308)
			(xy 250.652045 -385.214338) (xy 250.73588 -385.226391) (xy 250.818189 -385.246359) (xy 250.898228 -385.274061)
			(xy 250.975271 -385.309245) (xy 251.048621 -385.351594) (xy 251.117613 -385.400723) (xy 251.181623 -385.456188)
			(xy 251.240071 -385.517486) (xy 251.292427 -385.584062) (xy 251.338217 -385.655314) (xy 251.377028 -385.730595)
			(xy 251.408507 -385.809225) (xy 251.432368 -385.890492) (xy 251.448397 -385.973658) (xy 251.456448 -386.057972)
			(xy 251.456952 -386.10032) (xy 251.456952 -386.100828) (xy 251.456349 -386.14716) (xy 251.446676 -386.239318)
			(xy 251.42748 -386.329972) (xy 251.398967 -386.418141) (xy 251.380752 -386.460746) (xy 251.376932 -386.470684)
			(xy 251.37694 -386.491952) (xy 251.380752 -386.501894) (xy 251.399 -386.544555) (xy 251.427544 -386.632848)
			(xy 251.446736 -386.723633) (xy 251.456368 -386.815924) (xy 251.456952 -386.86232) (xy 251.456346 -386.908715)
			(xy 251.446708 -387.001003) (xy 251.427519 -387.091787) (xy 251.398987 -387.180081) (xy 251.380752 -387.222746)
			(xy 251.376932 -387.232684) (xy 251.37694 -387.253952) (xy 251.380752 -387.263894) (xy 251.399 -387.306555)
			(xy 251.427544 -387.394848) (xy 251.446736 -387.485633) (xy 251.456368 -387.577924) (xy 251.456952 -387.62432)
			(xy 255.6129 -387.62432) (xy 255.6129 -387.623812) (xy 255.613512 -387.57748) (xy 255.623182 -387.485323)
			(xy 255.642376 -387.394668) (xy 255.670886 -387.3065) (xy 255.6891 -387.263894) (xy 255.692893 -387.253948)
			(xy 255.692901 -387.232688) (xy 255.6891 -387.222746) (xy 255.670862 -387.180081) (xy 255.642316 -387.09179)
			(xy 255.623121 -387.001005) (xy 255.613486 -386.908716) (xy 255.6129 -386.86232) (xy 255.613489 -386.815925)
			(xy 255.623132 -386.723636) (xy 255.642326 -386.632853) (xy 255.670863 -386.544559) (xy 255.6891 -386.501894)
			(xy 255.692893 -386.491948) (xy 255.692901 -386.470688) (xy 255.6891 -386.460746) (xy 255.670885 -386.41814)
			(xy 255.642365 -386.329974) (xy 255.623171 -386.239319) (xy 255.613509 -386.14716) (xy 255.6129 -386.100828)
			(xy 255.6129 -386.10032) (xy 255.613404 -386.057972) (xy 255.621455 -385.973658) (xy 255.637484 -385.890492)
			(xy 255.661345 -385.809225) (xy 255.692824 -385.730595) (xy 255.731635 -385.655314) (xy 255.777425 -385.584062)
			(xy 255.829781 -385.517486) (xy 255.888229 -385.456188) (xy 255.952239 -385.400723) (xy 256.021231 -385.351594)
			(xy 256.094581 -385.309245) (xy 256.171624 -385.274061) (xy 256.251663 -385.246359) (xy 256.333972 -385.226391)
			(xy 256.417807 -385.214338) (xy 256.502408 -385.210308) (xy 256.587009 -385.214338) (xy 256.670844 -385.226391)
			(xy 256.753153 -385.246359) (xy 256.833192 -385.274061) (xy 256.910235 -385.309245) (xy 256.983585 -385.351594)
			(xy 257.052577 -385.400723) (xy 257.116587 -385.456188) (xy 257.175035 -385.517486) (xy 257.227391 -385.584062)
			(xy 257.273181 -385.655314) (xy 257.311992 -385.730595) (xy 257.343471 -385.809225) (xy 257.367332 -385.890492)
			(xy 257.383361 -385.973658) (xy 257.391412 -386.057972) (xy 257.391916 -386.10032) (xy 257.391916 -386.100828)
			(xy 257.391316 -386.14716) (xy 257.381643 -386.239318) (xy 257.362446 -386.329972) (xy 257.333932 -386.418141)
			(xy 257.315716 -386.460746) (xy 257.311898 -386.470685) (xy 257.311906 -386.491952) (xy 257.315716 -386.501894)
			(xy 257.333968 -386.544553) (xy 257.36251 -386.632847) (xy 257.381701 -386.723633) (xy 257.391332 -386.815924)
			(xy 257.391916 -386.86232) (xy 257.391304 -386.908715) (xy 257.381668 -387.001002) (xy 257.36248 -387.091786)
			(xy 257.33395 -387.18008) (xy 257.315716 -387.222746) (xy 257.311898 -387.232685) (xy 257.311906 -387.253952)
			(xy 257.315716 -387.263894) (xy 257.333945 -387.306494) (xy 257.362461 -387.394663) (xy 257.381651 -387.485319)
			(xy 257.391309 -387.57748) (xy 257.391916 -387.623812) (xy 257.391916 -387.62432) (xy 257.391412 -387.666668)
			(xy 257.383361 -387.750982) (xy 257.367332 -387.834148) (xy 257.343471 -387.915415) (xy 257.311992 -387.994045)
			(xy 257.273181 -388.069326) (xy 257.227391 -388.140578) (xy 257.175035 -388.207154) (xy 257.116587 -388.268452)
			(xy 257.052577 -388.323917) (xy 256.983585 -388.373046) (xy 256.910235 -388.415395) (xy 256.833192 -388.450579)
			(xy 256.753153 -388.478281) (xy 256.670844 -388.498249) (xy 256.587009 -388.510302) (xy 256.502408 -388.514333)
			(xy 256.417807 -388.510302) (xy 256.333972 -388.498249) (xy 256.251663 -388.478281) (xy 256.171624 -388.450579)
			(xy 256.094581 -388.415395) (xy 256.021231 -388.373046) (xy 255.952239 -388.323917) (xy 255.888229 -388.268452)
			(xy 255.829781 -388.207154) (xy 255.777425 -388.140578) (xy 255.731635 -388.069326) (xy 255.692824 -387.994045)
			(xy 255.661345 -387.915415) (xy 255.637484 -387.834148) (xy 255.621455 -387.750982) (xy 255.613404 -387.666668)
			(xy 255.6129 -387.62432) (xy 251.456952 -387.62432) (xy 251.456512 -387.665188) (xy 251.449014 -387.746579)
			(xy 251.434085 -387.82694) (xy 251.411848 -387.905592) (xy 251.382493 -387.981875) (xy 251.346266 -388.055144)
			(xy 251.303472 -388.124781) (xy 251.254472 -388.190201) (xy 251.19968 -388.250852) (xy 251.169932 -388.278878)
			(xy 251.159518 -388.28853) (xy 251.151644 -388.315708) (xy 251.182378 -388.430008) (xy 251.202698 -388.449566)
			(xy 251.216668 -388.452614) (xy 251.259507 -388.462746) (xy 251.343101 -388.490352) (xy 251.383546 -388.507732)
			(xy 251.393488 -388.511538) (xy 251.414752 -388.511538) (xy 251.424694 -388.507732) (xy 251.467325 -388.489494)
			(xy 251.555555 -388.460964) (xy 251.646276 -388.441772) (xy 251.738502 -388.432127) (xy 251.784866 -388.431532)
			(xy 251.785374 -388.431532) (xy 251.831737 -388.432151) (xy 251.92396 -388.441802) (xy 252.014679 -388.46099)
			(xy 252.10291 -388.489509) (xy 252.145546 -388.507732) (xy 252.155488 -388.511538) (xy 252.176752 -388.511538)
			(xy 252.186694 -388.507732) (xy 252.229325 -388.489494) (xy 252.317555 -388.460964) (xy 252.408276 -388.441772)
			(xy 252.500502 -388.432127) (xy 252.546866 -388.431532) (xy 252.547374 -388.431532) (xy 252.593737 -388.432151)
			(xy 252.68596 -388.441802) (xy 252.776679 -388.46099) (xy 252.86491 -388.489509) (xy 252.907546 -388.507732)
			(xy 252.917488 -388.511538) (xy 252.938752 -388.511538) (xy 252.948694 -388.507732) (xy 252.991325 -388.489494)
			(xy 253.079555 -388.460964) (xy 253.170276 -388.441772) (xy 253.262502 -388.432127) (xy 253.308866 -388.431532)
			(xy 253.309374 -388.431532) (xy 253.355737 -388.432151) (xy 253.44796 -388.441802) (xy 253.538679 -388.46099)
			(xy 253.62691 -388.489509) (xy 253.669546 -388.507732) (xy 253.679488 -388.511538) (xy 253.700752 -388.511538)
			(xy 253.710694 -388.507732) (xy 253.753293 -388.4895) (xy 253.841462 -388.460986) (xy 253.932119 -388.441796)
			(xy 254.024279 -388.432139) (xy 254.070612 -388.431532) (xy 254.07112 -388.431532) (xy 254.11347 -388.431957)
			(xy 254.197786 -388.44001) (xy 254.280954 -388.456041) (xy 254.362223 -388.479905) (xy 254.440854 -388.511386)
			(xy 254.516138 -388.550199) (xy 254.587391 -388.595992) (xy 254.653969 -388.64835) (xy 254.715268 -388.7068)
			(xy 254.770734 -388.770813) (xy 254.819864 -388.839807) (xy 254.862213 -388.91316) (xy 254.897398 -388.990205)
			(xy 254.9251 -389.070247) (xy 254.945069 -389.152559) (xy 254.957122 -389.236396) (xy 254.961153 -389.321)
			(xy 254.959095 -389.3642) (xy 258.047807 -389.3642) (xy 258.051837 -389.279603) (xy 258.06389 -389.195773)
			(xy 258.083856 -389.113467) (xy 258.111556 -389.033432) (xy 258.146738 -388.956393) (xy 258.189083 -388.883046)
			(xy 258.238208 -388.814056) (xy 258.293669 -388.750049) (xy 258.354962 -388.691603) (xy 258.421534 -388.639248)
			(xy 258.492781 -388.593457) (xy 258.568057 -388.554646) (xy 258.646682 -388.523167) (xy 258.727943 -388.499303)
			(xy 258.811105 -388.483272) (xy 258.895414 -388.475217) (xy 258.93776 -388.474712) (xy 258.938268 -388.474712)
			(xy 258.984599 -388.47533) (xy 259.076757 -388.484998) (xy 259.167411 -388.50419) (xy 259.25558 -388.532698)
			(xy 259.298186 -388.550912) (xy 259.308128 -388.554718) (xy 259.329392 -388.554718) (xy 259.339334 -388.550912)
			(xy 259.381972 -388.532693) (xy 259.4702 -388.504158) (xy 259.560919 -388.484961) (xy 259.653142 -388.475311)
			(xy 259.699506 -388.474712) (xy 259.700014 -388.474712) (xy 259.746377 -388.475319) (xy 259.8386 -388.484973)
			(xy 259.929319 -388.504165) (xy 260.017551 -388.532687) (xy 260.060186 -388.550912) (xy 260.070128 -388.554718)
			(xy 260.091392 -388.554718) (xy 260.101334 -388.550912) (xy 260.143972 -388.532693) (xy 260.2322 -388.504158)
			(xy 260.322919 -388.484961) (xy 260.415142 -388.475311) (xy 260.461506 -388.474712) (xy 260.462014 -388.474712)
			(xy 260.508377 -388.475319) (xy 260.6006 -388.484973) (xy 260.691319 -388.504165) (xy 260.779551 -388.532687)
			(xy 260.822186 -388.550912) (xy 260.832128 -388.554718) (xy 260.853392 -388.554718) (xy 260.863334 -388.550912)
			(xy 260.905972 -388.532693) (xy 260.9942 -388.504158) (xy 261.084919 -388.484961) (xy 261.177142 -388.475311)
			(xy 261.223506 -388.474712) (xy 261.224014 -388.474712) (xy 261.270377 -388.475319) (xy 261.3626 -388.484973)
			(xy 261.453319 -388.504165) (xy 261.541551 -388.532687) (xy 261.584186 -388.550912) (xy 261.594128 -388.554718)
			(xy 261.615392 -388.554718) (xy 261.625334 -388.550912) (xy 261.673582 -388.530355) (xy 261.773794 -388.499416)
			(xy 261.825232 -388.48919) (xy 261.834695 -388.487076) (xy 261.851111 -388.476778) (xy 261.862543 -388.461131)
			(xy 261.865364 -388.451852) (xy 261.892288 -388.348474) (xy 261.883144 -388.32028) (xy 261.87146 -388.310882)
			(xy 261.838207 -388.282721) (xy 261.77672 -388.220971) (xy 261.721566 -388.153504) (xy 261.673272 -388.080968)
			(xy 261.632303 -388.004058) (xy 261.599049 -387.92351) (xy 261.57383 -387.840097) (xy 261.556889 -387.754617)
			(xy 261.548386 -387.667891) (xy 261.547864 -387.62432) (xy 261.548456 -387.577925) (xy 261.558099 -387.485637)
			(xy 261.577292 -387.394853) (xy 261.605828 -387.306559) (xy 261.624064 -387.263894) (xy 261.627859 -387.253948)
			(xy 261.627867 -387.232688) (xy 261.624064 -387.222746) (xy 261.605824 -387.180082) (xy 261.577279 -387.09179)
			(xy 261.558085 -387.001006) (xy 261.54845 -386.908716) (xy 261.547864 -386.86232) (xy 261.548456 -386.815925)
			(xy 261.558099 -386.723637) (xy 261.577292 -386.632853) (xy 261.605828 -386.544559) (xy 261.624064 -386.501894)
			(xy 261.627859 -386.491948) (xy 261.627867 -386.470688) (xy 261.624064 -386.460746) (xy 261.605847 -386.418141)
			(xy 261.577328 -386.329974) (xy 261.558134 -386.23932) (xy 261.548473 -386.14716) (xy 261.547864 -386.100828)
			(xy 261.547864 -386.10032) (xy 261.548368 -386.057972) (xy 261.556419 -385.973658) (xy 261.572448 -385.890492)
			(xy 261.596309 -385.809225) (xy 261.627788 -385.730595) (xy 261.666599 -385.655314) (xy 261.712389 -385.584062)
			(xy 261.764745 -385.517486) (xy 261.823193 -385.456188) (xy 261.887203 -385.400723) (xy 261.956195 -385.351594)
			(xy 262.029545 -385.309245) (xy 262.106588 -385.274061) (xy 262.186627 -385.246359) (xy 262.268936 -385.226391)
			(xy 262.352771 -385.214338) (xy 262.437372 -385.210308) (xy 262.521973 -385.214338) (xy 262.605808 -385.226391)
			(xy 262.688117 -385.246359) (xy 262.768156 -385.274061) (xy 262.845199 -385.309245) (xy 262.918549 -385.351594)
			(xy 262.987541 -385.400723) (xy 263.051551 -385.456188) (xy 263.109999 -385.517486) (xy 263.162355 -385.584062)
			(xy 263.208145 -385.655314) (xy 263.246956 -385.730595) (xy 263.278435 -385.809225) (xy 263.302296 -385.890492)
			(xy 263.318325 -385.973658) (xy 263.326376 -386.057972) (xy 263.32688 -386.10032) (xy 263.32688 -386.100828)
			(xy 263.326283 -386.14716) (xy 263.31661 -386.239318) (xy 263.297411 -386.329973) (xy 263.268897 -386.418141)
			(xy 263.25068 -386.460746) (xy 263.246864 -386.470685) (xy 263.246872 -386.491951) (xy 263.25068 -386.501894)
			(xy 263.26893 -386.544554) (xy 263.297473 -386.632847) (xy 263.316665 -386.723633) (xy 263.326296 -386.815924)
			(xy 263.32688 -386.86232) (xy 263.326271 -386.908715) (xy 263.316634 -387.001003) (xy 263.297446 -387.091786)
			(xy 263.268915 -387.180081) (xy 263.25068 -387.222746) (xy 263.246864 -387.232685) (xy 263.246872 -387.253951)
			(xy 263.25068 -387.263894) (xy 263.268907 -387.306495) (xy 263.297424 -387.394663) (xy 263.316615 -387.485319)
			(xy 263.326273 -387.57748) (xy 263.32688 -387.623812) (xy 263.32688 -387.62432) (xy 263.326348 -387.665522)
			(xy 263.318718 -387.747571) (xy 263.303535 -387.828564) (xy 263.280929 -387.907805) (xy 263.251093 -387.984618)
			(xy 263.214282 -388.058343) (xy 263.170814 -388.128348) (xy 263.121058 -388.194035) (xy 263.065443 -388.25484)
			(xy 263.004444 -388.310243) (xy 262.938584 -388.359768) (xy 262.868427 -388.402993) (xy 262.794575 -388.439545)
			(xy 262.717659 -388.469113) (xy 262.638339 -388.491443) (xy 262.5979 -388.49935) (xy 262.588454 -388.501522)
			(xy 262.57204 -388.511796) (xy 262.560598 -388.527419) (xy 262.557768 -388.536688) (xy 262.530844 -388.640066)
			(xy 262.539988 -388.66826) (xy 262.551672 -388.677658) (xy 262.58493 -388.705769) (xy 262.646379 -388.767481)
			(xy 262.701504 -388.834901) (xy 262.749777 -388.907385) (xy 262.790737 -388.984239) (xy 262.823992 -389.064728)
			(xy 262.849222 -389.148081) (xy 262.866187 -389.2335) (xy 262.874725 -389.320168) (xy 262.875021 -389.3439)
			(xy 266.091872 -389.3439) (xy 266.095902 -389.259295) (xy 266.107957 -389.175456) (xy 266.127926 -389.093143)
			(xy 266.15563 -389.013101) (xy 266.190817 -388.936055) (xy 266.233169 -388.862702) (xy 266.282301 -388.793708)
			(xy 266.33777 -388.729696) (xy 266.399072 -388.671247) (xy 266.465653 -388.618891) (xy 266.536909 -388.5731)
			(xy 266.612195 -388.53429) (xy 266.69083 -388.502812) (xy 266.772101 -388.478952) (xy 266.855272 -388.462926)
			(xy 266.93959 -388.454878) (xy 266.98194 -388.454392) (xy 266.982448 -388.454392) (xy 267.028779 -388.455019)
			(xy 267.120937 -388.464684) (xy 267.211591 -388.483874) (xy 267.29976 -388.51238) (xy 267.342366 -388.530592)
			(xy 267.352308 -388.534398) (xy 267.373572 -388.534398) (xy 267.383514 -388.530592) (xy 267.421715 -388.514199)
			(xy 267.500531 -388.487758) (xy 267.58147 -388.468784) (xy 267.663826 -388.457441) (xy 267.705332 -388.455154)
			(xy 267.705586 -388.455154) (xy 267.715547 -388.454267) (xy 267.733653 -388.445817) (xy 267.747164 -388.431096)
			(xy 267.751052 -388.42188) (xy 267.78839 -388.31901) (xy 267.781278 -388.289292) (xy 267.769848 -388.278878)
			(xy 267.740077 -388.250874) (xy 267.685266 -388.190234) (xy 267.636254 -388.124818) (xy 267.593452 -388.05518)
			(xy 267.557224 -387.981907) (xy 267.527875 -387.905618) (xy 267.505652 -387.826957) (xy 267.490743 -387.746588)
			(xy 267.483275 -387.66519) (xy 267.482828 -387.62432) (xy 267.483415 -387.577925) (xy 267.493058 -387.485636)
			(xy 267.512253 -387.394852) (xy 267.54079 -387.306559) (xy 267.559028 -387.263894) (xy 267.56282 -387.253948)
			(xy 267.562827 -387.232688) (xy 267.559028 -387.222746) (xy 267.540792 -387.18008) (xy 267.512245 -387.091789)
			(xy 267.49305 -387.001005) (xy 267.483414 -386.908716) (xy 267.482828 -386.86232) (xy 267.483415 -386.815925)
			(xy 267.493058 -386.723636) (xy 267.512253 -386.632852) (xy 267.54079 -386.544559) (xy 267.559028 -386.501894)
			(xy 267.56282 -386.491948) (xy 267.562827 -386.470688) (xy 267.559028 -386.460746) (xy 267.540809 -386.418142)
			(xy 267.512291 -386.329975) (xy 267.493098 -386.23932) (xy 267.483437 -386.14716) (xy 267.482828 -386.100828)
			(xy 267.482828 -386.10032) (xy 267.483332 -386.057972) (xy 267.491383 -385.973658) (xy 267.507412 -385.890492)
			(xy 267.531273 -385.809225) (xy 267.562752 -385.730595) (xy 267.601563 -385.655314) (xy 267.647353 -385.584062)
			(xy 267.699709 -385.517486) (xy 267.758157 -385.456188) (xy 267.822167 -385.400723) (xy 267.891159 -385.351594)
			(xy 267.964509 -385.309245) (xy 268.041552 -385.274061) (xy 268.121591 -385.246359) (xy 268.2039 -385.226391)
			(xy 268.287735 -385.214338) (xy 268.372336 -385.210308) (xy 268.456937 -385.214338) (xy 268.540772 -385.226391)
			(xy 268.623081 -385.246359) (xy 268.70312 -385.274061) (xy 268.780163 -385.309245) (xy 268.853513 -385.351594)
			(xy 268.922505 -385.400723) (xy 268.986515 -385.456188) (xy 269.044963 -385.517486) (xy 269.097319 -385.584062)
			(xy 269.143109 -385.655314) (xy 269.18192 -385.730595) (xy 269.213399 -385.809225) (xy 269.23726 -385.890492)
			(xy 269.253289 -385.973658) (xy 269.26134 -386.057972) (xy 269.261844 -386.10032) (xy 269.261844 -386.100828)
			(xy 269.261242 -386.14716) (xy 269.251569 -386.239318) (xy 269.232372 -386.329972) (xy 269.203859 -386.418141)
			(xy 269.185644 -386.460746) (xy 269.181825 -386.470684) (xy 269.181833 -386.491952) (xy 269.185644 -386.501894)
			(xy 269.203898 -386.544553) (xy 269.232439 -386.632846) (xy 269.251629 -386.723633) (xy 269.26126 -386.815924)
			(xy 269.261844 -386.86232) (xy 269.261238 -386.908715) (xy 269.251601 -387.001003) (xy 269.232412 -387.091787)
			(xy 269.203879 -387.180081) (xy 269.185644 -387.222746) (xy 269.181825 -387.232684) (xy 269.181833 -387.253952)
			(xy 269.185644 -387.263894) (xy 269.203875 -387.306493) (xy 269.23239 -387.394662) (xy 269.25158 -387.485319)
			(xy 269.261237 -387.577479) (xy 269.261844 -387.623812) (xy 269.261844 -387.62432) (xy 269.261348 -387.66668)
			(xy 269.253296 -387.751015) (xy 269.237266 -387.834205) (xy 269.213405 -387.915494) (xy 269.181926 -387.994148)
			(xy 269.143116 -388.069455) (xy 269.097326 -388.140734) (xy 269.04497 -388.207339) (xy 268.986522 -388.268667)
			(xy 268.922511 -388.324164) (xy 268.853515 -388.373328) (xy 268.81709 -388.394956) (xy 268.809042 -388.400057)
			(xy 268.797209 -388.414978) (xy 268.791622 -388.433184) (xy 268.791944 -388.442708) (xy 268.793976 -388.470648)
			(xy 268.795065 -388.48018) (xy 268.803481 -388.497409) (xy 268.817662 -388.510315) (xy 268.826488 -388.514082)
			(xy 268.866366 -388.530592) (xy 268.876308 -388.534398) (xy 268.897572 -388.534398) (xy 268.907514 -388.530592)
			(xy 268.950141 -388.512345) (xy 269.038373 -388.483818) (xy 269.129095 -388.464629) (xy 269.221321 -388.454986)
			(xy 269.267686 -388.454392) (xy 269.268194 -388.454392) (xy 269.314557 -388.455008) (xy 269.40678 -388.46466)
			(xy 269.497499 -388.483849) (xy 269.58573 -388.512368) (xy 269.628366 -388.530592) (xy 269.638308 -388.534398)
			(xy 269.659572 -388.534398) (xy 269.669514 -388.530592) (xy 269.712111 -388.512357) (xy 269.800281 -388.483843)
			(xy 269.890938 -388.464654) (xy 269.983099 -388.454998) (xy 270.029432 -388.454392) (xy 270.02994 -388.454392)
			(xy 270.072287 -388.454897) (xy 270.156598 -388.462952) (xy 270.239761 -388.478984) (xy 270.321024 -388.502848)
			(xy 270.399651 -388.534328) (xy 270.474929 -388.57314) (xy 270.546178 -388.618931) (xy 270.612751 -388.671288)
			(xy 270.674046 -388.729735) (xy 270.729508 -388.793744) (xy 270.778634 -388.862735) (xy 270.82098 -388.936083)
			(xy 270.856163 -389.013125) (xy 270.883863 -389.093161) (xy 270.90383 -389.175469) (xy 270.915883 -389.259301)
			(xy 270.917612 -389.2956) (xy 275.284228 -389.2956) (xy 275.288257 -389.211003) (xy 275.30031 -389.127172)
			(xy 275.320278 -389.044866) (xy 275.347978 -388.964831) (xy 275.383161 -388.887791) (xy 275.425507 -388.814445)
			(xy 275.474634 -388.745456) (xy 275.530097 -388.681449) (xy 275.591392 -388.623004) (xy 275.657965 -388.57065)
			(xy 275.729214 -388.524861) (xy 275.804492 -388.486053) (xy 275.883119 -388.454575) (xy 275.964381 -388.430714)
			(xy 276.047544 -388.414686) (xy 276.131853 -388.406636) (xy 276.1742 -388.406132) (xy 276.174708 -388.406132)
			(xy 276.22104 -388.406735) (xy 276.313198 -388.416407) (xy 276.403852 -388.435603) (xy 276.492021 -388.464116)
			(xy 276.534626 -388.482332) (xy 276.544568 -388.486138) (xy 276.565832 -388.486138) (xy 276.575774 -388.482332)
			(xy 276.618408 -388.464101) (xy 276.706637 -388.435569) (xy 276.797357 -388.416375) (xy 276.889582 -388.406729)
			(xy 276.935946 -388.406132) (xy 276.936454 -388.406132) (xy 276.982818 -388.406723) (xy 277.075041 -388.416382)
			(xy 277.16576 -388.435578) (xy 277.253991 -388.464105) (xy 277.296626 -388.482332) (xy 277.306568 -388.486138)
			(xy 277.327832 -388.486138) (xy 277.337774 -388.482332) (xy 277.380408 -388.464101) (xy 277.468637 -388.435569)
			(xy 277.559357 -388.416375) (xy 277.651582 -388.406729) (xy 277.697946 -388.406132) (xy 277.698454 -388.406132)
			(xy 277.744818 -388.406723) (xy 277.837041 -388.416382) (xy 277.92776 -388.435578) (xy 278.015991 -388.464105)
			(xy 278.058626 -388.482332) (xy 278.068568 -388.486138) (xy 278.089832 -388.486138) (xy 278.099774 -388.482332)
			(xy 278.142375 -388.464106) (xy 278.230544 -388.43559) (xy 278.321199 -388.416399) (xy 278.41336 -388.40674)
			(xy 278.459692 -388.406132) (xy 278.4602 -388.406132) (xy 278.50255 -388.406556) (xy 278.586868 -388.414607)
			(xy 278.670038 -388.430637) (xy 278.751308 -388.4545) (xy 278.829941 -388.48598) (xy 278.905226 -388.524792)
			(xy 278.976481 -388.570585) (xy 279.04306 -388.622943) (xy 279.104361 -388.681393) (xy 279.159829 -388.745406)
			(xy 279.20896 -388.814401) (xy 279.25131 -388.887754) (xy 279.286496 -388.964801) (xy 279.314199 -389.044843)
			(xy 279.334168 -389.127156) (xy 279.346222 -389.210995) (xy 279.350253 -389.2956) (xy 279.346222 -389.380205)
			(xy 279.334168 -389.464044) (xy 279.314199 -389.546357) (xy 279.286496 -389.626399) (xy 279.25131 -389.703446)
			(xy 279.20896 -389.776799) (xy 279.159829 -389.845794) (xy 279.104361 -389.909807) (xy 279.04306 -389.968257)
			(xy 278.976481 -390.020615) (xy 278.905226 -390.066408) (xy 278.829941 -390.10522) (xy 278.751308 -390.1367)
			(xy 278.670038 -390.160563) (xy 278.586868 -390.176593) (xy 278.50255 -390.184644) (xy 278.4602 -390.185148)
			(xy 278.459692 -390.185148) (xy 278.41336 -390.184539) (xy 278.321203 -390.174868) (xy 278.230548 -390.155673)
			(xy 278.14238 -390.127162) (xy 278.099774 -390.108948) (xy 278.089832 -390.105142) (xy 278.068568 -390.105142)
			(xy 278.058626 -390.108948) (xy 278.015992 -390.127178) (xy 277.927763 -390.15571) (xy 277.837043 -390.174904)
			(xy 277.744818 -390.184551) (xy 277.698454 -390.185148) (xy 277.697946 -390.185148) (xy 277.651582 -390.184559)
			(xy 277.559359 -390.1749) (xy 277.46864 -390.155703) (xy 277.380409 -390.127176) (xy 277.337774 -390.108948)
			(xy 277.327832 -390.105142) (xy 277.306568 -390.105142) (xy 277.296626 -390.108948) (xy 277.253992 -390.127178)
			(xy 277.165763 -390.15571) (xy 277.075043 -390.174904) (xy 276.982818 -390.184551) (xy 276.936454 -390.185148)
			(xy 276.935946 -390.185148) (xy 276.889582 -390.184559) (xy 276.797359 -390.1749) (xy 276.70664 -390.155703)
			(xy 276.618409 -390.127176) (xy 276.575774 -390.108948) (xy 276.565832 -390.105142) (xy 276.544568 -390.105142)
			(xy 276.534626 -390.108948) (xy 276.492024 -390.127173) (xy 276.403856 -390.155689) (xy 276.3132 -390.174881)
			(xy 276.22104 -390.18454) (xy 276.174708 -390.185148) (xy 276.1742 -390.185148) (xy 276.131853 -390.184564)
			(xy 276.047544 -390.176514) (xy 275.964381 -390.160486) (xy 275.883119 -390.136625) (xy 275.804492 -390.105147)
			(xy 275.729214 -390.066339) (xy 275.657965 -390.02055) (xy 275.591392 -389.968196) (xy 275.530097 -389.909751)
			(xy 275.474634 -389.845744) (xy 275.425507 -389.776755) (xy 275.383161 -389.703409) (xy 275.347978 -389.626369)
			(xy 275.320278 -389.546334) (xy 275.30031 -389.464028) (xy 275.288257 -389.380197) (xy 275.284228 -389.2956)
			(xy 270.917612 -389.2956) (xy 270.919913 -389.3439) (xy 270.915883 -389.428499) (xy 270.90383 -389.512331)
			(xy 270.883863 -389.594639) (xy 270.856163 -389.674675) (xy 270.82098 -389.751717) (xy 270.778634 -389.825065)
			(xy 270.729508 -389.894056) (xy 270.674046 -389.958065) (xy 270.612751 -390.016512) (xy 270.546178 -390.068869)
			(xy 270.474929 -390.11466) (xy 270.399651 -390.153472) (xy 270.321024 -390.184952) (xy 270.239761 -390.208816)
			(xy 270.156598 -390.224848) (xy 270.072287 -390.232903) (xy 270.02994 -390.233408) (xy 270.029432 -390.233408)
			(xy 269.983101 -390.232788) (xy 269.890943 -390.223121) (xy 269.800289 -390.203929) (xy 269.71212 -390.175421)
			(xy 269.669514 -390.157208) (xy 269.659572 -390.153402) (xy 269.638308 -390.153402) (xy 269.628366 -390.157208)
			(xy 269.585728 -390.175428) (xy 269.4975 -390.203962) (xy 269.406782 -390.223159) (xy 269.314558 -390.232809)
			(xy 269.268194 -390.233408) (xy 269.267686 -390.233408) (xy 269.221323 -390.232799) (xy 269.1291 -390.223145)
			(xy 269.038381 -390.203954) (xy 268.950149 -390.175433) (xy 268.907514 -390.157208) (xy 268.897572 -390.153402)
			(xy 268.876308 -390.153402) (xy 268.866366 -390.157208) (xy 268.823728 -390.175428) (xy 268.7355 -390.203962)
			(xy 268.644782 -390.223159) (xy 268.552558 -390.232809) (xy 268.506194 -390.233408) (xy 268.505686 -390.233408)
			(xy 268.459323 -390.232799) (xy 268.3671 -390.223145) (xy 268.276381 -390.203954) (xy 268.188149 -390.175433)
			(xy 268.145514 -390.157208) (xy 268.135572 -390.153402) (xy 268.114308 -390.153402) (xy 268.104366 -390.157208)
			(xy 268.061728 -390.175428) (xy 267.9735 -390.203962) (xy 267.882782 -390.223159) (xy 267.790558 -390.232809)
			(xy 267.744194 -390.233408) (xy 267.743686 -390.233408) (xy 267.697323 -390.232799) (xy 267.6051 -390.223145)
			(xy 267.514381 -390.203954) (xy 267.426149 -390.175433) (xy 267.383514 -390.157208) (xy 267.373572 -390.153402)
			(xy 267.352308 -390.153402) (xy 267.342366 -390.157208) (xy 267.299758 -390.175417) (xy 267.211592 -390.203938)
			(xy 267.120938 -390.223134) (xy 267.02878 -390.232798) (xy 266.982448 -390.233408) (xy 266.98194 -390.233408)
			(xy 266.93959 -390.232922) (xy 266.855272 -390.224874) (xy 266.772101 -390.208848) (xy 266.69083 -390.184988)
			(xy 266.612195 -390.15351) (xy 266.536909 -390.1147) (xy 266.465653 -390.068909) (xy 266.399072 -390.016553)
			(xy 266.33777 -389.958104) (xy 266.282301 -389.894092) (xy 266.233169 -389.825098) (xy 266.190817 -389.751745)
			(xy 266.15563 -389.674699) (xy 266.127926 -389.594657) (xy 266.107957 -389.512344) (xy 266.095902 -389.428505)
			(xy 266.091872 -389.3439) (xy 262.875021 -389.3439) (xy 262.875268 -389.363712) (xy 262.875268 -389.36422)
			(xy 262.874867 -389.405325) (xy 262.86728 -389.487183) (xy 262.852172 -389.567992) (xy 262.829672 -389.647063)
			(xy 262.799972 -389.72372) (xy 262.763326 -389.79731) (xy 262.720047 -389.867204) (xy 262.670502 -389.932807)
			(xy 262.615116 -389.993559) (xy 262.554361 -390.048941) (xy 262.488755 -390.09848) (xy 262.418857 -390.141756)
			(xy 262.345265 -390.178397) (xy 262.268606 -390.208091) (xy 262.189534 -390.230585) (xy 262.108724 -390.245688)
			(xy 262.026865 -390.25327) (xy 261.98576 -390.253728) (xy 261.985252 -390.253728) (xy 261.938921 -390.253099)
			(xy 261.846764 -390.243434) (xy 261.756109 -390.224245) (xy 261.66794 -390.19574) (xy 261.625334 -390.177528)
			(xy 261.615392 -390.173722) (xy 261.594128 -390.173722) (xy 261.584186 -390.177528) (xy 261.541559 -390.195776)
			(xy 261.453327 -390.224303) (xy 261.362605 -390.243491) (xy 261.270379 -390.253134) (xy 261.224014 -390.253728)
			(xy 261.223506 -390.253728) (xy 261.177143 -390.253111) (xy 261.08492 -390.243459) (xy 260.994202 -390.22427)
			(xy 260.90597 -390.195751) (xy 260.863334 -390.177528) (xy 260.853392 -390.173722) (xy 260.832128 -390.173722)
			(xy 260.822186 -390.177528) (xy 260.779559 -390.195776) (xy 260.691327 -390.224303) (xy 260.600605 -390.243491)
			(xy 260.508379 -390.253134) (xy 260.462014 -390.253728) (xy 260.461506 -390.253728) (xy 260.415143 -390.253111)
			(xy 260.32292 -390.243459) (xy 260.232202 -390.22427) (xy 260.14397 -390.195751) (xy 260.101334 -390.177528)
			(xy 260.091392 -390.173722) (xy 260.070128 -390.173722) (xy 260.060186 -390.177528) (xy 260.017559 -390.195776)
			(xy 259.929327 -390.224303) (xy 259.838605 -390.243491) (xy 259.746379 -390.253134) (xy 259.700014 -390.253728)
			(xy 259.699506 -390.253728) (xy 259.653143 -390.253111) (xy 259.56092 -390.243459) (xy 259.470202 -390.22427)
			(xy 259.38197 -390.195751) (xy 259.339334 -390.177528) (xy 259.329392 -390.173722) (xy 259.308128 -390.173722)
			(xy 259.298186 -390.177528) (xy 259.255589 -390.195764) (xy 259.167419 -390.224278) (xy 259.076762 -390.243467)
			(xy 258.984601 -390.253122) (xy 258.938268 -390.253728) (xy 258.93776 -390.253728) (xy 258.895414 -390.253183)
			(xy 258.811105 -390.245128) (xy 258.727943 -390.229097) (xy 258.646682 -390.205233) (xy 258.568057 -390.173754)
			(xy 258.492781 -390.134943) (xy 258.421534 -390.089152) (xy 258.354962 -390.036797) (xy 258.293669 -389.978351)
			(xy 258.238208 -389.914344) (xy 258.189083 -389.845354) (xy 258.146738 -389.772007) (xy 258.111556 -389.694968)
			(xy 258.083856 -389.614933) (xy 258.06389 -389.532627) (xy 258.051837 -389.448797) (xy 258.047807 -389.3642)
			(xy 254.959095 -389.3642) (xy 254.957122 -389.405604) (xy 254.945069 -389.489441) (xy 254.9251 -389.571753)
			(xy 254.897398 -389.651795) (xy 254.862213 -389.72884) (xy 254.819864 -389.802193) (xy 254.770734 -389.871187)
			(xy 254.715268 -389.9352) (xy 254.653969 -389.99365) (xy 254.587391 -390.046008) (xy 254.516138 -390.091801)
			(xy 254.440854 -390.130614) (xy 254.362223 -390.162095) (xy 254.280954 -390.185959) (xy 254.197786 -390.20199)
			(xy 254.11347 -390.210043) (xy 254.07112 -390.210548) (xy 254.070612 -390.210548) (xy 254.024281 -390.209931)
			(xy 253.932123 -390.200263) (xy 253.841469 -390.18107) (xy 253.7533 -390.152561) (xy 253.710694 -390.134348)
			(xy 253.700752 -390.130542) (xy 253.679488 -390.130542) (xy 253.669546 -390.134348) (xy 253.626909 -390.152571)
			(xy 253.538681 -390.181105) (xy 253.447962 -390.200301) (xy 253.355738 -390.20995) (xy 253.309374 -390.210548)
			(xy 253.308866 -390.210548) (xy 253.262502 -390.209952) (xy 253.170279 -390.200295) (xy 253.07956 -390.1811)
			(xy 252.991329 -390.152575) (xy 252.948694 -390.134348) (xy 252.938752 -390.130542) (xy 252.917488 -390.130542)
			(xy 252.907546 -390.134348) (xy 252.864909 -390.152571) (xy 252.776681 -390.181105) (xy 252.685962 -390.200301)
			(xy 252.593738 -390.20995) (xy 252.547374 -390.210548) (xy 252.546866 -390.210548) (xy 252.500502 -390.209952)
			(xy 252.408279 -390.200295) (xy 252.31756 -390.1811) (xy 252.229329 -390.152575) (xy 252.186694 -390.134348)
			(xy 252.176752 -390.130542) (xy 252.155488 -390.130542) (xy 252.145546 -390.134348) (xy 252.102909 -390.152571)
			(xy 252.014681 -390.181105) (xy 251.923962 -390.200301) (xy 251.831738 -390.20995) (xy 251.785374 -390.210548)
			(xy 251.784866 -390.210548) (xy 251.738502 -390.209952) (xy 251.646279 -390.200295) (xy 251.55556 -390.1811)
			(xy 251.467329 -390.152575) (xy 251.424694 -390.134348) (xy 251.414752 -390.130542) (xy 251.393488 -390.130542)
			(xy 251.383546 -390.134348) (xy 251.340941 -390.152566) (xy 251.252774 -390.181084) (xy 251.16212 -390.200278)
			(xy 251.06996 -390.209939) (xy 251.023628 -390.210548) (xy 251.02312 -390.210548) (xy 250.982019 -390.210014)
			(xy 250.900168 -390.202432) (xy 250.819365 -390.187329) (xy 250.7403 -390.164836) (xy 250.663648 -390.135143)
			(xy 250.590063 -390.098504) (xy 250.520172 -390.055233) (xy 250.454572 -390.005697) (xy 250.393822 -389.95032)
			(xy 250.338441 -389.889574) (xy 250.288901 -389.823977) (xy 250.245625 -389.754089) (xy 250.208981 -389.680507)
			(xy 250.179284 -389.603857) (xy 250.156785 -389.524794) (xy 250.141677 -389.443992) (xy 250.134088 -389.362141)
			(xy 250.133612 -389.32104) (xy 250.133612 -389.320786) (xy 250.134084 -389.279933) (xy 250.141595 -389.198572)
			(xy 250.156533 -389.118242) (xy 250.178773 -389.03962) (xy 250.208128 -388.963369) (xy 250.24435 -388.89013)
			(xy 250.287134 -388.82052) (xy 250.336119 -388.755125) (xy 250.390894 -388.694498) (xy 250.420632 -388.666482)
			(xy 250.431046 -388.65683) (xy 250.43892 -388.629652) (xy 250.408186 -388.515352) (xy 250.387866 -388.495794)
			(xy 250.373896 -388.492746) (xy 250.332086 -388.482917) (xy 250.250448 -388.456208) (xy 250.171765 -388.421758)
			(xy 250.096766 -388.379887) (xy 250.026152 -388.330983) (xy 249.960578 -388.275503) (xy 249.900655 -388.213962)
			(xy 249.846941 -388.146934) (xy 249.799936 -388.075042) (xy 249.760077 -387.998955) (xy 249.727734 -387.919382)
			(xy 249.70321 -387.837062) (xy 249.686732 -387.752763) (xy 249.678453 -387.667268) (xy 249.677936 -387.62432)
			(xy 245.521988 -387.62432) (xy 245.521472 -387.667499) (xy 245.513112 -387.753451) (xy 245.496463 -387.838189)
			(xy 245.471682 -387.920915) (xy 245.439002 -388.000851) (xy 245.398731 -388.077244) (xy 245.351247 -388.149375)
			(xy 245.296998 -388.216566) (xy 245.236493 -388.278185) (xy 245.203726 -388.30631) (xy 245.197019 -388.312325)
			(xy 245.188001 -388.32791) (xy 245.184926 -388.345651) (xy 245.1862 -388.35457) (xy 245.204996 -388.455154)
			(xy 245.222776 -388.475728) (xy 245.23573 -388.4803) (xy 245.253374 -388.48652) (xy 245.288184 -388.50024)
			(xy 245.305326 -388.507732) (xy 245.315268 -388.511538) (xy 245.336532 -388.511538) (xy 245.346474 -388.507732)
			(xy 245.389075 -388.489506) (xy 245.477244 -388.46099) (xy 245.567899 -388.441799) (xy 245.66006 -388.43214)
			(xy 245.706392 -388.431532) (xy 245.7069 -388.431532) (xy 245.74925 -388.431956) (xy 245.833568 -388.440007)
			(xy 245.916738 -388.456037) (xy 245.998008 -388.4799) (xy 246.076641 -388.51138) (xy 246.151926 -388.550192)
			(xy 246.223181 -388.595985) (xy 246.28976 -388.648343) (xy 246.351061 -388.706793) (xy 246.406529 -388.770806)
			(xy 246.45566 -388.839801) (xy 246.49801 -388.913154) (xy 246.533196 -388.990201) (xy 246.560899 -389.070243)
			(xy 246.580868 -389.152556) (xy 246.592922 -389.236395) (xy 246.596953 -389.321) (xy 246.592922 -389.405605)
			(xy 246.580868 -389.489444) (xy 246.560899 -389.571757) (xy 246.533196 -389.651799) (xy 246.49801 -389.728846)
			(xy 246.45566 -389.802199) (xy 246.406529 -389.871194) (xy 246.351061 -389.935207) (xy 246.28976 -389.993657)
			(xy 246.223181 -390.046015) (xy 246.151926 -390.091808) (xy 246.076641 -390.13062) (xy 245.998008 -390.1621)
			(xy 245.916738 -390.185963) (xy 245.833568 -390.201993) (xy 245.74925 -390.210044) (xy 245.7069 -390.210548)
			(xy 245.706392 -390.210548) (xy 245.66006 -390.209939) (xy 245.567903 -390.200268) (xy 245.477248 -390.181073)
			(xy 245.38908 -390.152562) (xy 245.346474 -390.134348) (xy 245.336532 -390.130542) (xy 245.315268 -390.130542)
			(xy 245.305326 -390.134348) (xy 245.262692 -390.152578) (xy 245.174463 -390.18111) (xy 245.083743 -390.200304)
			(xy 244.991518 -390.209951) (xy 244.945154 -390.210548) (xy 244.944646 -390.210548) (xy 244.898282 -390.209959)
			(xy 244.806059 -390.2003) (xy 244.71534 -390.181103) (xy 244.627109 -390.152576) (xy 244.584474 -390.134348)
			(xy 244.574532 -390.130542) (xy 244.553268 -390.130542) (xy 244.543326 -390.134348) (xy 244.500692 -390.152578)
			(xy 244.412463 -390.18111) (xy 244.321743 -390.200304) (xy 244.229518 -390.209951) (xy 244.183154 -390.210548)
			(xy 244.182646 -390.210548) (xy 244.136282 -390.209959) (xy 244.044059 -390.2003) (xy 243.95334 -390.181103)
			(xy 243.865109 -390.152576) (xy 243.822474 -390.134348) (xy 243.812532 -390.130542) (xy 243.791268 -390.130542)
			(xy 243.781326 -390.134348) (xy 243.738692 -390.152578) (xy 243.650463 -390.18111) (xy 243.559743 -390.200304)
			(xy 243.467518 -390.209951) (xy 243.421154 -390.210548) (xy 243.420646 -390.210548) (xy 243.374282 -390.209959)
			(xy 243.282059 -390.2003) (xy 243.19134 -390.181103) (xy 243.103109 -390.152576) (xy 243.060474 -390.134348)
			(xy 243.050532 -390.130542) (xy 243.029268 -390.130542) (xy 243.019326 -390.134348) (xy 242.976724 -390.152573)
			(xy 242.888556 -390.181089) (xy 242.7979 -390.200281) (xy 242.70574 -390.20994) (xy 242.659408 -390.210548)
			(xy 242.6589 -390.210548) (xy 242.616553 -390.209964) (xy 242.532244 -390.201914) (xy 242.449081 -390.185886)
			(xy 242.367819 -390.162025) (xy 242.289192 -390.130547) (xy 242.213914 -390.091739) (xy 242.142665 -390.04595)
			(xy 242.076092 -389.993596) (xy 242.014797 -389.935151) (xy 241.959334 -389.871144) (xy 241.910207 -389.802155)
			(xy 241.867861 -389.728809) (xy 241.832678 -389.651769) (xy 241.804978 -389.571734) (xy 241.78501 -389.489428)
			(xy 241.772957 -389.405597) (xy 241.768928 -389.321) (xy 240.768792 -389.321) (xy 240.768886 -389.328914)
			(xy 240.768382 -389.371275) (xy 240.760329 -389.455612) (xy 240.744295 -389.538802) (xy 240.720427 -389.620092)
			(xy 240.688939 -389.698744) (xy 240.650117 -389.774047) (xy 240.604314 -389.845319) (xy 240.551943 -389.911915)
			(xy 240.493478 -389.97323) (xy 240.42945 -390.028711) (xy 240.360438 -390.077854) (xy 240.287068 -390.120214)
			(xy 240.210003 -390.155409) (xy 240.129941 -390.183118) (xy 240.047608 -390.203092) (xy 239.963749 -390.215149)
			(xy 239.879124 -390.219181) (xy 239.794499 -390.215149) (xy 239.71064 -390.203092) (xy 239.628307 -390.183118)
			(xy 239.548245 -390.155409) (xy 239.47118 -390.120214) (xy 239.39781 -390.077854) (xy 239.328798 -390.028711)
			(xy 239.26477 -389.97323) (xy 239.206305 -389.911915) (xy 239.153934 -389.845319) (xy 239.108131 -389.774047)
			(xy 239.069309 -389.698744) (xy 239.037821 -389.620092) (xy 239.013953 -389.538802) (xy 238.997919 -389.455612)
			(xy 238.989866 -389.371275) (xy 195.355765 -389.371275) (xy 195.340132 -389.384821) (xy 195.27112 -389.433964)
			(xy 195.19775 -389.476324) (xy 195.120685 -389.511519) (xy 195.040623 -389.539228) (xy 194.95829 -389.559202)
			(xy 194.874431 -389.571259) (xy 194.789806 -389.575291) (xy 194.705181 -389.571259) (xy 194.621322 -389.559202)
			(xy 194.538989 -389.539228) (xy 194.458927 -389.511519) (xy 194.381862 -389.476324) (xy 194.308492 -389.433964)
			(xy 194.23948 -389.384821) (xy 194.175452 -389.32934) (xy 194.116987 -389.268025) (xy 194.064616 -389.201429)
			(xy 194.018813 -389.130157) (xy 193.979991 -389.054854) (xy 193.948503 -388.976202) (xy 193.924635 -388.894912)
			(xy 193.908601 -388.811722) (xy 193.900548 -388.727385) (xy 165.74419 -388.727385) (xy 166.083742 -389.314944)
			(xy 166.083996 -389.315452) (xy 166.08425 -389.315452) (xy 166.08552 -389.317992) (xy 166.097793 -389.340907)
			(xy 166.115198 -389.389885) (xy 166.124072 -389.441101) (xy 166.124636 -389.46709) (xy 166.124636 -389.467344)
			(xy 166.124202 -389.49135) (xy 166.116681 -389.538768) (xy 166.101833 -389.584426) (xy 166.080022 -389.627197)
			(xy 166.051787 -389.666029) (xy 166.017823 -389.699963) (xy 165.978967 -389.728164) (xy 165.936176 -389.749936)
			(xy 165.890505 -389.764744) (xy 165.84308 -389.772223) (xy 165.819074 -389.772652) (xy 165.795412 -389.772153)
			(xy 165.748653 -389.764854) (xy 165.703579 -389.750433) (xy 165.661267 -389.729237) (xy 165.622728 -389.701771)
			(xy 165.588884 -389.668693) (xy 165.560543 -389.630792) (xy 165.549072 -389.610092) (xy 165.548818 -389.60933)
			(xy 165.151562 -388.922006) (xy 165.139384 -388.898789) (xy 165.122268 -388.849239) (xy 165.117526 -388.823454)
			(xy 165.117526 -388.8232) (xy 165.114046 -388.799395) (xy 165.113835 -388.751285) (xy 164.557888 -388.751285)
			(xy 164.865812 -389.283956) (xy 164.866066 -389.284464) (xy 164.885624 -389.317992) (xy 164.897897 -389.340907)
			(xy 164.915302 -389.389885) (xy 164.924176 -389.441101) (xy 164.92474 -389.46709) (xy 164.92474 -389.467344)
			(xy 164.924302 -389.491349) (xy 164.916781 -389.538768) (xy 164.901933 -389.584425) (xy 164.880123 -389.627196)
			(xy 164.851888 -389.666027) (xy 164.817925 -389.699961) (xy 164.779069 -389.728162) (xy 164.736279 -389.749935)
			(xy 164.690609 -389.764744) (xy 164.643184 -389.772222) (xy 164.619178 -389.772652) (xy 164.618924 -389.772652)
			(xy 164.595352 -389.772211) (xy 164.548767 -389.764975) (xy 164.503851 -389.750656) (xy 164.461674 -389.729594)
			(xy 164.423241 -389.702292) (xy 164.389467 -389.669401) (xy 164.361157 -389.631704) (xy 164.349684 -389.611108)
			(xy 164.349176 -389.610346) (xy 163.951412 -388.922006) (xy 163.939498 -388.899337) (xy 163.92256 -388.851012)
			(xy 163.9139 -388.800542) (xy 163.913312 -388.77494) (xy 163.371626 -388.77494) (xy 163.683696 -389.314944)
			(xy 163.68395 -389.315452) (xy 163.684204 -389.315452) (xy 163.685474 -389.317992) (xy 163.697704 -389.340918)
			(xy 163.715026 -389.389903) (xy 163.723814 -389.441111) (xy 163.724336 -389.46709) (xy 163.724336 -389.467344)
			(xy 163.723878 -389.491335) (xy 163.716366 -389.538726) (xy 163.701535 -389.584358) (xy 163.679748 -389.627109)
			(xy 163.651543 -389.665926) (xy 163.617613 -389.699853) (xy 163.578795 -389.728056) (xy 163.536043 -389.749841)
			(xy 163.49041 -389.76467) (xy 163.443019 -389.772179) (xy 163.419028 -389.772652) (xy 163.395364 -389.77219)
			(xy 163.348604 -389.764884) (xy 163.303529 -389.750457) (xy 163.261217 -389.729254) (xy 163.222679 -389.701783)
			(xy 163.188836 -389.668699) (xy 163.160497 -389.630794) (xy 163.149026 -389.610092) (xy 163.148772 -389.60933)
			(xy 162.751516 -388.922006) (xy 162.739335 -388.89879) (xy 162.722222 -388.849239) (xy 162.71748 -388.823454)
			(xy 162.71748 -388.8232) (xy 162.713918 -388.797977) (xy 162.184833 -388.797977) (xy 162.465766 -389.283956)
			(xy 162.46602 -389.284464) (xy 162.485578 -389.317992) (xy 162.497808 -389.340918) (xy 162.51513 -389.389903)
			(xy 162.523918 -389.441111) (xy 162.52444 -389.46709) (xy 162.52444 -389.467344) (xy 162.523978 -389.491335)
			(xy 162.516466 -389.538725) (xy 162.501635 -389.584357) (xy 162.479849 -389.627107) (xy 162.451644 -389.665924)
			(xy 162.417715 -389.699852) (xy 162.378897 -389.728055) (xy 162.336146 -389.74984) (xy 162.290513 -389.764669)
			(xy 162.243123 -389.772179) (xy 162.219132 -389.772652) (xy 162.218878 -389.772652) (xy 162.195305 -389.772249)
			(xy 162.148718 -389.765005) (xy 162.103801 -389.750679) (xy 162.061624 -389.729611) (xy 162.023191 -389.702304)
			(xy 161.989418 -389.669408) (xy 161.96111 -389.631706) (xy 161.949638 -389.611108) (xy 161.94913 -389.610346)
			(xy 161.551366 -388.922006) (xy 161.539491 -388.899329) (xy 161.522639 -388.850996) (xy 161.514066 -388.800533)
			(xy 161.51352 -388.77494) (xy 160.97158 -388.77494) (xy 161.28365 -389.314944) (xy 161.283904 -389.315452)
			(xy 161.284158 -389.315452) (xy 161.285428 -389.317992) (xy 161.297701 -389.340907) (xy 161.315106 -389.389885)
			(xy 161.32398 -389.441101) (xy 161.324544 -389.46709) (xy 161.324544 -389.467344) (xy 161.324102 -389.491349)
			(xy 161.316582 -389.538767) (xy 161.301734 -389.584424) (xy 161.279924 -389.627195) (xy 161.25169 -389.666026)
			(xy 161.217726 -389.69996) (xy 161.178871 -389.728161) (xy 161.136082 -389.749934) (xy 161.090412 -389.764743)
			(xy 161.042988 -389.772222) (xy 161.018982 -389.772652) (xy 160.995317 -389.772227) (xy 160.948555 -389.764914)
			(xy 160.90348 -389.75048) (xy 160.861167 -389.729272) (xy 160.822629 -389.701795) (xy 160.788787 -389.668706)
			(xy 160.76045 -389.630797) (xy 160.74898 -389.610092) (xy 160.748726 -389.60933) (xy 160.35147 -388.922006)
			(xy 160.339293 -388.898789) (xy 160.322177 -388.849238) (xy 160.317434 -388.823454) (xy 160.317434 -388.8232)
			(xy 160.313939 -388.799396) (xy 160.313728 -388.751285) (xy 159.758014 -388.751285) (xy 160.083754 -389.314944)
			(xy 160.084008 -389.315452) (xy 160.084262 -389.315452) (xy 160.085532 -389.317992) (xy 160.097806 -389.340907)
			(xy 160.115211 -389.389885) (xy 160.124084 -389.441101) (xy 160.124648 -389.46709) (xy 160.124648 -389.467344)
			(xy 160.124202 -389.491349) (xy 160.116682 -389.538767) (xy 160.101834 -389.584423) (xy 160.080025 -389.627194)
			(xy 160.051791 -389.666025) (xy 160.017828 -389.699959) (xy 159.978973 -389.72816) (xy 159.936184 -389.749933)
			(xy 159.890515 -389.764742) (xy 159.843091 -389.772222) (xy 159.819086 -389.772652) (xy 159.795421 -389.772224)
			(xy 159.74866 -389.764911) (xy 159.703584 -389.750478) (xy 159.661272 -389.72927) (xy 159.622734 -389.701794)
			(xy 159.588892 -389.668705) (xy 159.560554 -389.630796) (xy 159.549084 -389.610092) (xy 159.54883 -389.60933)
			(xy 159.151574 -388.922006) (xy 159.139397 -388.898788) (xy 159.122281 -388.849238) (xy 159.117538 -388.823454)
			(xy 159.117538 -388.8232) (xy 159.114036 -388.799397) (xy 159.113824 -388.751286) (xy 158.557865 -388.751286)
			(xy 158.883604 -389.314944) (xy 158.883858 -389.315452) (xy 158.884112 -389.315452) (xy 158.885382 -389.317992)
			(xy 158.897612 -389.340918) (xy 158.914934 -389.389903) (xy 158.923722 -389.441111) (xy 158.924244 -389.46709)
			(xy 158.924244 -389.467344) (xy 158.923778 -389.491335) (xy 158.916267 -389.538724) (xy 158.901435 -389.584356)
			(xy 158.879649 -389.627106) (xy 158.851445 -389.665923) (xy 158.817517 -389.69985) (xy 158.778699 -389.728054)
			(xy 158.735949 -389.749838) (xy 158.690317 -389.764668) (xy 158.642927 -389.772179) (xy 158.618936 -389.772652)
			(xy 158.595273 -389.772184) (xy 158.548513 -389.764878) (xy 158.503438 -389.750453) (xy 158.461126 -389.729251)
			(xy 158.422587 -389.701781) (xy 158.388744 -389.668698) (xy 158.360405 -389.630794) (xy 158.348934 -389.610092)
			(xy 158.34868 -389.60933) (xy 157.951424 -388.922006) (xy 157.939244 -388.89879) (xy 157.92213 -388.849239)
			(xy 157.917388 -388.823454) (xy 157.917388 -388.8232) (xy 157.913811 -388.797979) (xy 157.384953 -388.797979)
			(xy 157.683708 -389.314944) (xy 157.683962 -389.315452) (xy 157.684216 -389.315452) (xy 157.685486 -389.317992)
			(xy 157.697717 -389.340917) (xy 157.715038 -389.389902) (xy 157.723826 -389.441111) (xy 157.724348 -389.46709)
			(xy 157.724348 -389.467344) (xy 157.723878 -389.491334) (xy 157.716367 -389.538724) (xy 157.701536 -389.584355)
			(xy 157.67975 -389.627105) (xy 157.651546 -389.665922) (xy 157.617618 -389.699849) (xy 157.578802 -389.728052)
			(xy 157.536051 -389.749837) (xy 157.49042 -389.764668) (xy 157.44303 -389.772178) (xy 157.41904 -389.772652)
			(xy 157.395377 -389.77218) (xy 157.348617 -389.764876) (xy 157.303542 -389.750451) (xy 157.26123 -389.72925)
			(xy 157.222692 -389.70178) (xy 157.188848 -389.668698) (xy 157.160509 -389.630794) (xy 157.149038 -389.610092)
			(xy 157.148784 -389.60933) (xy 156.751528 -388.922006) (xy 156.739348 -388.89879) (xy 156.722234 -388.849239)
			(xy 156.717492 -388.823454) (xy 156.717492 -388.8232) (xy 156.714076 -388.799387) (xy 156.713865 -388.751284)
			(xy 156.157853 -388.751284) (xy 156.465778 -389.283956) (xy 156.466032 -389.284464) (xy 156.48559 -389.317992)
			(xy 156.497821 -389.340917) (xy 156.515142 -389.389902) (xy 156.52393 -389.441111) (xy 156.524452 -389.46709)
			(xy 156.524452 -389.467344) (xy 156.523978 -389.491334) (xy 156.516467 -389.538723) (xy 156.501636 -389.584354)
			(xy 156.479851 -389.627104) (xy 156.451648 -389.66592) (xy 156.41772 -389.699848) (xy 156.378904 -389.728051)
			(xy 156.336154 -389.749836) (xy 156.290523 -389.764667) (xy 156.243134 -389.772178) (xy 156.219144 -389.772652)
			(xy 156.21889 -389.772652) (xy 156.195317 -389.772239) (xy 156.148731 -389.764997) (xy 156.103814 -389.750673)
			(xy 156.061637 -389.729607) (xy 156.023204 -389.702301) (xy 155.989431 -389.669406) (xy 155.961123 -389.631705)
			(xy 155.94965 -389.611108) (xy 155.949142 -389.610346) (xy 155.551378 -388.922006) (xy 155.539503 -388.899328)
			(xy 155.522652 -388.850996) (xy 155.514078 -388.800533) (xy 155.513532 -388.77494) (xy 154.971592 -388.77494)
			(xy 155.283662 -389.314944) (xy 155.283916 -389.315452) (xy 155.28417 -389.315452) (xy 155.28544 -389.317992)
			(xy 155.297714 -389.340906) (xy 155.315119 -389.389885) (xy 155.323992 -389.441101) (xy 155.324556 -389.46709)
			(xy 155.324556 -389.467344) (xy 155.324102 -389.491349) (xy 155.316582 -389.538765) (xy 155.301735 -389.584421)
			(xy 155.279926 -389.627191) (xy 155.251693 -389.666022) (xy 155.217731 -389.699956) (xy 155.178878 -389.728157)
			(xy 155.13609 -389.749931) (xy 155.090422 -389.76474) (xy 155.042999 -389.772221) (xy 155.018994 -389.772652)
			(xy 154.995329 -389.772217) (xy 154.948568 -389.764906) (xy 154.903493 -389.750474) (xy 154.86118 -389.729267)
			(xy 154.822642 -389.701792) (xy 154.7888 -389.668704) (xy 154.760462 -389.630796) (xy 154.748992 -389.610092)
			(xy 154.748738 -389.60933) (xy 154.351482 -388.922006) (xy 154.339305 -388.898788) (xy 154.322189 -388.849238)
			(xy 154.317446 -388.823454) (xy 154.317446 -388.8232) (xy 154.313929 -388.799399) (xy 154.313717 -388.751286)
			(xy 153.758027 -388.751286) (xy 154.083766 -389.314944) (xy 154.08402 -389.315452) (xy 154.084274 -389.315452)
			(xy 154.085544 -389.317992) (xy 154.097819 -389.340906) (xy 154.115223 -389.389885) (xy 154.124096 -389.441101)
			(xy 154.12466 -389.46709) (xy 154.12466 -389.467344) (xy 154.124301 -389.491353) (xy 154.116779 -389.53878)
			(xy 154.101926 -389.584444) (xy 154.080109 -389.62722) (xy 154.051865 -389.666055) (xy 154.017891 -389.69999)
			(xy 153.979025 -389.72819) (xy 153.936223 -389.749958) (xy 153.890542 -389.764759) (xy 153.843108 -389.772228)
			(xy 153.819098 -389.772652) (xy 153.795434 -389.772214) (xy 153.748672 -389.764903) (xy 153.703597 -389.750472)
			(xy 153.661285 -389.729266) (xy 153.622747 -389.701791) (xy 153.588904 -389.668704) (xy 153.560566 -389.630796)
			(xy 153.549096 -389.610092) (xy 153.548842 -389.60933) (xy 153.151586 -388.922006) (xy 153.13941 -388.898788)
			(xy 153.122293 -388.849238) (xy 153.11755 -388.823454) (xy 153.11755 -388.8232) (xy 153.114025 -388.7994)
			(xy 153.113813 -388.751286) (xy 152.557877 -388.751286) (xy 152.883616 -389.314944) (xy 152.88387 -389.315452)
			(xy 152.884124 -389.315452) (xy 152.885394 -389.317992) (xy 152.897625 -389.340917) (xy 152.914946 -389.389902)
			(xy 152.923734 -389.441111) (xy 152.924256 -389.46709) (xy 152.924256 -389.467344) (xy 152.923778 -389.491334)
			(xy 152.916267 -389.538723) (xy 152.901436 -389.584353) (xy 152.879652 -389.627103) (xy 152.851449 -389.665919)
			(xy 152.817522 -389.699846) (xy 152.778706 -389.72805) (xy 152.735957 -389.749835) (xy 152.690327 -389.764666)
			(xy 152.642938 -389.772178) (xy 152.618948 -389.772652) (xy 152.595285 -389.772174) (xy 152.548526 -389.764871)
			(xy 152.503451 -389.750447) (xy 152.461139 -389.729247) (xy 152.4226 -389.701778) (xy 152.388757 -389.668697)
			(xy 152.360417 -389.630794) (xy 152.348946 -389.610092) (xy 152.348692 -389.60933) (xy 151.951436 -388.922006)
			(xy 151.939256 -388.89879) (xy 151.922142 -388.849239) (xy 151.9174 -388.823454) (xy 151.9174 -388.8232)
			(xy 151.913969 -388.799389) (xy 151.913758 -388.751284) (xy 151.357979 -388.751284) (xy 151.68372 -389.314944)
			(xy 151.683974 -389.315452) (xy 151.684228 -389.315452) (xy 151.685498 -389.317992) (xy 151.697729 -389.340917)
			(xy 151.71505 -389.389902) (xy 151.723838 -389.441111) (xy 151.72436 -389.46709) (xy 151.72436 -389.467344)
			(xy 151.724002 -389.491341) (xy 151.716487 -389.538742) (xy 151.70165 -389.584385) (xy 151.679855 -389.627144)
			(xy 151.651639 -389.665968) (xy 151.617698 -389.699899) (xy 151.578866 -389.728103) (xy 151.5361 -389.749885)
			(xy 151.490453 -389.764709) (xy 151.443049 -389.772209) (xy 151.419052 -389.772652) (xy 151.395389 -389.772171)
			(xy 151.34863 -389.764868) (xy 151.303556 -389.750445) (xy 151.261243 -389.729245) (xy 151.222705 -389.701777)
			(xy 151.188861 -389.668696) (xy 151.160521 -389.630793) (xy 151.14905 -389.610092) (xy 151.148796 -389.60933)
			(xy 150.75154 -388.922006) (xy 150.739361 -388.89879) (xy 150.722246 -388.849239) (xy 150.717504 -388.823454)
			(xy 150.717504 -388.8232) (xy 150.714066 -388.79939) (xy 150.713855 -388.751284) (xy 150.157865 -388.751284)
			(xy 150.46579 -389.283956) (xy 150.466044 -389.284464) (xy 150.485602 -389.317992) (xy 150.497834 -389.340917)
			(xy 150.515155 -389.389902) (xy 150.523942 -389.441111) (xy 150.524464 -389.46709) (xy 150.524464 -389.467344)
			(xy 150.524078 -389.491339) (xy 150.516564 -389.538736) (xy 150.501728 -389.584375) (xy 150.479935 -389.62713)
			(xy 150.451722 -389.66595) (xy 150.417783 -389.699879) (xy 150.378955 -389.728081) (xy 150.336193 -389.749861)
			(xy 150.29055 -389.764684) (xy 150.243151 -389.772185) (xy 150.219156 -389.772652) (xy 150.218902 -389.772652)
			(xy 150.195329 -389.772229) (xy 150.148744 -389.76499) (xy 150.103827 -389.750667) (xy 150.06165 -389.729602)
			(xy 150.023217 -389.702298) (xy 149.989444 -389.669404) (xy 149.961135 -389.631705) (xy 149.949662 -389.611108)
			(xy 149.949154 -389.610346) (xy 149.55139 -388.922006) (xy 149.539516 -388.899328) (xy 149.522664 -388.850995)
			(xy 149.51409 -388.800533) (xy 149.513544 -388.77494) (xy 148.971604 -388.77494) (xy 149.283674 -389.314944)
			(xy 149.283928 -389.315452) (xy 149.284182 -389.315452) (xy 149.285452 -389.317992) (xy 149.297727 -389.340906)
			(xy 149.315131 -389.389885) (xy 149.324004 -389.441101) (xy 149.324568 -389.46709) (xy 149.324568 -389.467344)
			(xy 149.324201 -389.491353) (xy 149.316679 -389.538778) (xy 149.301826 -389.584442) (xy 149.28001 -389.627218)
			(xy 149.251767 -389.666052) (xy 149.217795 -389.699987) (xy 149.178929 -389.728187) (xy 149.136129 -389.749956)
			(xy 149.090449 -389.764758) (xy 149.043016 -389.772228) (xy 149.019006 -389.772652) (xy 148.995342 -389.772208)
			(xy 148.948581 -389.764898) (xy 148.903506 -389.750468) (xy 148.861193 -389.729263) (xy 148.822655 -389.701789)
			(xy 148.788813 -389.668703) (xy 148.760474 -389.630795) (xy 148.749004 -389.610092) (xy 148.74875 -389.60933)
			(xy 148.351494 -388.922006) (xy 148.339312 -388.898791) (xy 148.322199 -388.849239) (xy 148.317458 -388.823454)
			(xy 148.317458 -388.8232) (xy 148.313918 -388.799402) (xy 148.313706 -388.751287) (xy 147.758039 -388.751287)
			(xy 148.083778 -389.314944) (xy 148.084032 -389.315452) (xy 148.084286 -389.315452) (xy 148.085556 -389.317992)
			(xy 148.097831 -389.340906) (xy 148.115235 -389.389885) (xy 148.124108 -389.441101) (xy 148.124672 -389.46709)
			(xy 148.124672 -389.467344) (xy 148.124301 -389.491353) (xy 148.116779 -389.538778) (xy 148.101927 -389.584441)
			(xy 148.080111 -389.627217) (xy 148.051868 -389.666051) (xy 148.017896 -389.699986) (xy 147.979031 -389.728185)
			(xy 147.936232 -389.749955) (xy 147.890552 -389.764757) (xy 147.843119 -389.772228) (xy 147.81911 -389.772652)
			(xy 147.795446 -389.772205) (xy 147.748685 -389.764896) (xy 147.70361 -389.750466) (xy 147.661298 -389.729261)
			(xy 147.622759 -389.701788) (xy 147.588917 -389.668702) (xy 147.560578 -389.630795) (xy 147.549108 -389.610092)
			(xy 147.548854 -389.60933) (xy 147.151598 -388.922006) (xy 147.139416 -388.898791) (xy 147.122303 -388.849239)
			(xy 147.117562 -388.823454) (xy 147.117562 -388.8232) (xy 147.114015 -388.799402) (xy 147.113803 -388.751287)
			(xy 133.230255 -388.751287) (xy 133.555994 -389.314944) (xy 133.556248 -389.315452) (xy 133.556502 -389.315452)
			(xy 133.557772 -389.317992) (xy 133.570041 -389.340909) (xy 133.587449 -389.389886) (xy 133.596324 -389.441102)
			(xy 133.596888 -389.46709) (xy 133.596888 -389.467344) (xy 133.596501 -389.491352) (xy 133.58898 -389.538775)
			(xy 133.574128 -389.584437) (xy 133.552314 -389.627212) (xy 133.524073 -389.666045) (xy 133.490103 -389.69998)
			(xy 133.45124 -389.72818) (xy 133.408443 -389.74995) (xy 133.362766 -389.764754) (xy 133.315334 -389.772226)
			(xy 133.291326 -389.772652) (xy 133.267662 -389.772192) (xy 133.220902 -389.764885) (xy 133.175827 -389.750458)
			(xy 133.133515 -389.729255) (xy 133.094977 -389.701783) (xy 133.061134 -389.6687) (xy 133.032795 -389.630795)
			(xy 133.021324 -389.610092) (xy 133.02107 -389.60933) (xy 132.623814 -388.922006) (xy 132.611633 -388.89879)
			(xy 132.59452 -388.849239) (xy 132.589778 -388.823454) (xy 132.589778 -388.8232) (xy 132.586219 -388.797977)
			(xy 132.057087 -388.797977) (xy 132.355844 -389.314944) (xy 132.356098 -389.315452) (xy 132.356352 -389.315452)
			(xy 132.357622 -389.317992) (xy 132.369855 -389.340916) (xy 132.387175 -389.389902) (xy 132.395962 -389.441111)
			(xy 132.396484 -389.46709) (xy 132.396484 -389.467344) (xy 132.396078 -389.491338) (xy 132.388564 -389.538733)
			(xy 132.37373 -389.58437) (xy 132.351938 -389.627124) (xy 132.323728 -389.665943) (xy 132.289792 -389.699872)
			(xy 132.250966 -389.728074) (xy 132.208207 -389.749856) (xy 132.162567 -389.76468) (xy 132.11517 -389.772183)
			(xy 132.091176 -389.772652) (xy 132.067511 -389.772232) (xy 132.020749 -389.764918) (xy 131.975673 -389.750483)
			(xy 131.933361 -389.729274) (xy 131.894823 -389.701796) (xy 131.860981 -389.668707) (xy 131.832644 -389.630797)
			(xy 131.821174 -389.610092) (xy 131.82092 -389.60933) (xy 131.423664 -388.922006) (xy 131.411486 -388.898789)
			(xy 131.39437 -388.849239) (xy 131.389628 -388.823454) (xy 131.389628 -388.8232) (xy 131.386145 -388.799395)
			(xy 131.385933 -388.751285) (xy 130.830208 -388.751285) (xy 131.155948 -389.314944) (xy 131.156202 -389.315452)
			(xy 131.156456 -389.315452) (xy 131.157726 -389.317992) (xy 131.16996 -389.340916) (xy 131.187279 -389.389902)
			(xy 131.196066 -389.441111) (xy 131.196588 -389.46709) (xy 131.196588 -389.467344) (xy 131.196178 -389.491337)
			(xy 131.188665 -389.538733) (xy 131.17383 -389.584369) (xy 131.152039 -389.627123) (xy 131.123829 -389.665942)
			(xy 131.089893 -389.69987) (xy 131.051068 -389.728073) (xy 131.00831 -389.749854) (xy 130.96267 -389.76468)
			(xy 130.915274 -389.772183) (xy 130.89128 -389.772652) (xy 130.867615 -389.772229) (xy 130.820853 -389.764915)
			(xy 130.775777 -389.750481) (xy 130.733465 -389.729272) (xy 130.694927 -389.701795) (xy 130.661085 -389.668706)
			(xy 130.632748 -389.630797) (xy 130.621278 -389.610092) (xy 130.621024 -389.60933) (xy 130.223768 -388.922006)
			(xy 130.21159 -388.898789) (xy 130.194475 -388.849239) (xy 130.189732 -388.823454) (xy 130.189732 -388.8232)
			(xy 130.186241 -388.799396) (xy 130.18603 -388.751285) (xy 129.630058 -388.751285) (xy 129.955798 -389.314944)
			(xy 129.956052 -389.315452) (xy 129.956306 -389.315452) (xy 129.957576 -389.317992) (xy 129.969845 -389.340909)
			(xy 129.987253 -389.389886) (xy 129.996128 -389.441102) (xy 129.996692 -389.46709) (xy 129.996692 -389.467344)
			(xy 129.996301 -389.491352) (xy 129.98878 -389.538775) (xy 129.973929 -389.584436) (xy 129.952114 -389.627211)
			(xy 129.923874 -389.666044) (xy 129.889905 -389.699979) (xy 129.851042 -389.728179) (xy 129.808246 -389.749949)
			(xy 129.762569 -389.764753) (xy 129.715138 -389.772226) (xy 129.69113 -389.772652) (xy 129.667466 -389.772188)
			(xy 129.620707 -389.764882) (xy 129.575632 -389.750456) (xy 129.533319 -389.729254) (xy 129.494781 -389.701782)
			(xy 129.460938 -389.668699) (xy 129.432599 -389.630794) (xy 129.421128 -389.610092) (xy 129.420874 -389.60933)
			(xy 129.023618 -388.922006) (xy 129.011437 -388.89879) (xy 128.994324 -388.849239) (xy 128.989582 -388.823454)
			(xy 128.989582 -388.8232) (xy 128.986016 -388.797978) (xy 128.457146 -388.797978) (xy 128.755902 -389.314944)
			(xy 128.756156 -389.315452) (xy 128.75641 -389.315452) (xy 128.75768 -389.317992) (xy 128.769949 -389.340909)
			(xy 128.787357 -389.389886) (xy 128.796232 -389.441102) (xy 128.796796 -389.46709) (xy 128.796796 -389.467344)
			(xy 128.796401 -389.491352) (xy 128.78888 -389.538774) (xy 128.774029 -389.584435) (xy 128.752215 -389.627209)
			(xy 128.723975 -389.666042) (xy 128.690006 -389.699977) (xy 128.651145 -389.728177) (xy 128.608348 -389.749948)
			(xy 128.562672 -389.764752) (xy 128.515242 -389.772226) (xy 128.491234 -389.772652) (xy 128.467571 -389.772185)
			(xy 128.420811 -389.76488) (xy 128.375736 -389.750454) (xy 128.333424 -389.729252) (xy 128.294885 -389.701781)
			(xy 128.261042 -389.668699) (xy 128.232703 -389.630794) (xy 128.221232 -389.610092) (xy 128.220978 -389.60933)
			(xy 127.823722 -388.922006) (xy 127.811541 -388.89879) (xy 127.794428 -388.849239) (xy 127.789686 -388.823454)
			(xy 127.789686 -388.8232) (xy 127.786112 -388.797979) (xy 127.257251 -388.797979) (xy 127.556006 -389.314944)
			(xy 127.55626 -389.315452) (xy 127.556514 -389.315452) (xy 127.557784 -389.317992) (xy 127.570054 -389.340909)
			(xy 127.587461 -389.389886) (xy 127.596336 -389.441101) (xy 127.5969 -389.46709) (xy 127.5969 -389.467344)
			(xy 127.596501 -389.491351) (xy 127.58898 -389.538774) (xy 127.57413 -389.584434) (xy 127.552316 -389.627208)
			(xy 127.524077 -389.666041) (xy 127.490108 -389.699976) (xy 127.451247 -389.728176) (xy 127.408451 -389.749947)
			(xy 127.362776 -389.764752) (xy 127.315346 -389.772225) (xy 127.291338 -389.772652) (xy 127.267675 -389.772182)
			(xy 127.220915 -389.764877) (xy 127.17584 -389.750452) (xy 127.133528 -389.729251) (xy 127.094989 -389.70178)
			(xy 127.061146 -389.668698) (xy 127.032807 -389.630794) (xy 127.021336 -389.610092) (xy 127.021082 -389.60933)
			(xy 126.623826 -388.922006) (xy 126.611646 -388.89879) (xy 126.594532 -388.849239) (xy 126.58979 -388.823454)
			(xy 126.58979 -388.8232) (xy 126.586378 -388.799387) (xy 126.586167 -388.751284) (xy 126.030115 -388.751284)
			(xy 126.355856 -389.314944) (xy 126.35611 -389.315452) (xy 126.356364 -389.315452) (xy 126.357634 -389.317992)
			(xy 126.369868 -389.340915) (xy 126.387188 -389.389902) (xy 126.395975 -389.441111) (xy 126.396496 -389.46709)
			(xy 126.396496 -389.467344) (xy 126.396078 -389.491337) (xy 126.388565 -389.538731) (xy 126.373731 -389.584367)
			(xy 126.351941 -389.627121) (xy 126.323731 -389.665939) (xy 126.289797 -389.699868) (xy 126.250973 -389.72807)
			(xy 126.208215 -389.749852) (xy 126.162577 -389.764678) (xy 126.115181 -389.772182) (xy 126.091188 -389.772652)
			(xy 126.067523 -389.772222) (xy 126.020762 -389.76491) (xy 125.975686 -389.750477) (xy 125.933374 -389.729269)
			(xy 125.894836 -389.701793) (xy 125.860994 -389.668705) (xy 125.832656 -389.630796) (xy 125.821186 -389.610092)
			(xy 125.820932 -389.60933) (xy 125.423676 -388.922006) (xy 125.411499 -388.898788) (xy 125.394383 -388.849238)
			(xy 125.38964 -388.823454) (xy 125.38964 -388.8232) (xy 125.386134 -388.799398) (xy 125.385922 -388.751286)
			(xy 124.830221 -388.751286) (xy 125.15596 -389.314944) (xy 125.156214 -389.315452) (xy 125.156468 -389.315452)
			(xy 125.157738 -389.317992) (xy 125.169973 -389.340915) (xy 125.187292 -389.389902) (xy 125.196079 -389.441111)
			(xy 125.1966 -389.46709) (xy 125.1966 -389.467344) (xy 125.196178 -389.491337) (xy 125.188665 -389.538731)
			(xy 125.173831 -389.584366) (xy 125.152041 -389.627119) (xy 125.123832 -389.665938) (xy 125.089898 -389.699866)
			(xy 125.051075 -389.728069) (xy 125.008318 -389.749851) (xy 124.96268 -389.764677) (xy 124.915285 -389.772182)
			(xy 124.891292 -389.772652) (xy 124.867627 -389.772219) (xy 124.820866 -389.764907) (xy 124.77579 -389.750475)
			(xy 124.733478 -389.729268) (xy 124.69494 -389.701792) (xy 124.661098 -389.668705) (xy 124.63276 -389.630796)
			(xy 124.62129 -389.610092) (xy 124.621036 -389.60933) (xy 124.22378 -388.922006) (xy 124.211603 -388.898788)
			(xy 124.194487 -388.849238) (xy 124.189744 -388.823454) (xy 124.189744 -388.8232) (xy 124.186231 -388.799399)
			(xy 124.186019 -388.751286) (xy 123.630071 -388.751286) (xy 123.95581 -389.314944) (xy 123.956064 -389.315452)
			(xy 123.956318 -389.315452) (xy 123.957588 -389.317992) (xy 123.969858 -389.340908) (xy 123.987265 -389.389886)
			(xy 123.99614 -389.441101) (xy 123.996704 -389.46709) (xy 123.996704 -389.467344) (xy 123.996301 -389.491351)
			(xy 123.98878 -389.538773) (xy 123.97393 -389.584433) (xy 123.952117 -389.627207) (xy 123.923878 -389.66604)
			(xy 123.88991 -389.699974) (xy 123.851049 -389.728175) (xy 123.808254 -389.749946) (xy 123.762579 -389.764751)
			(xy 123.71515 -389.772225) (xy 123.691142 -389.772652) (xy 123.667479 -389.772179) (xy 123.620719 -389.764875)
			(xy 123.575645 -389.75045) (xy 123.533332 -389.729249) (xy 123.494794 -389.701779) (xy 123.46095 -389.668697)
			(xy 123.432611 -389.630794) (xy 123.42114 -389.610092) (xy 123.420886 -389.60933) (xy 123.02363 -388.922006)
			(xy 123.01145 -388.89879) (xy 122.994336 -388.849239) (xy 122.989594 -388.823454) (xy 122.989594 -388.8232)
			(xy 122.986174 -388.799388) (xy 122.985964 -388.751284) (xy 122.430173 -388.751284) (xy 122.755914 -389.314944)
			(xy 122.756168 -389.315452) (xy 122.756422 -389.315452) (xy 122.757692 -389.317992) (xy 122.769962 -389.340908)
			(xy 122.787369 -389.389886) (xy 122.796244 -389.441101) (xy 122.796808 -389.46709) (xy 122.796808 -389.467344)
			(xy 122.796401 -389.491351) (xy 122.78888 -389.538772) (xy 122.77403 -389.584432) (xy 122.752217 -389.627206)
			(xy 122.723979 -389.666038) (xy 122.690011 -389.699973) (xy 122.651151 -389.728173) (xy 122.608357 -389.749944)
			(xy 122.562682 -389.76475) (xy 122.515253 -389.772225) (xy 122.491246 -389.772652) (xy 122.467583 -389.772176)
			(xy 122.420824 -389.764872) (xy 122.375749 -389.750448) (xy 122.333437 -389.729248) (xy 122.294898 -389.701778)
			(xy 122.261054 -389.668697) (xy 122.232715 -389.630794) (xy 122.221244 -389.610092) (xy 122.22099 -389.60933)
			(xy 121.823734 -388.922006) (xy 121.811554 -388.89879) (xy 121.79444 -388.849239) (xy 121.789698 -388.823454)
			(xy 121.789698 -388.8232) (xy 121.786271 -388.799389) (xy 121.78606 -388.751284) (xy 121.230277 -388.751284)
			(xy 121.556018 -389.314944) (xy 121.556272 -389.315452) (xy 121.556526 -389.315452) (xy 121.557796 -389.317992)
			(xy 121.570067 -389.340908) (xy 121.587474 -389.389886) (xy 121.596348 -389.441101) (xy 121.596912 -389.46709)
			(xy 121.596912 -389.467344) (xy 121.596502 -389.491351) (xy 121.58898 -389.538772) (xy 121.574131 -389.584432)
			(xy 121.552318 -389.627205) (xy 121.52408 -389.666037) (xy 121.490113 -389.699971) (xy 121.451253 -389.728172)
			(xy 121.408459 -389.749943) (xy 121.362786 -389.764749) (xy 121.315357 -389.772225) (xy 121.29135 -389.772652)
			(xy 121.267687 -389.772172) (xy 121.220928 -389.764869) (xy 121.175853 -389.750446) (xy 121.133541 -389.729246)
			(xy 121.095002 -389.701777) (xy 121.061159 -389.668696) (xy 121.032819 -389.630793) (xy 121.021348 -389.610092)
			(xy 121.021094 -389.60933) (xy 120.623838 -388.922006) (xy 120.611658 -388.89879) (xy 120.594544 -388.849239)
			(xy 120.589802 -388.823454) (xy 120.589802 -388.8232) (xy 120.586367 -388.799389) (xy 120.586156 -388.751284)
			(xy 120.030127 -388.751284) (xy 120.355868 -389.314944) (xy 120.356122 -389.315452) (xy 120.356376 -389.315452)
			(xy 120.357646 -389.317992) (xy 120.369881 -389.340915) (xy 120.3872 -389.389902) (xy 120.395987 -389.441111)
			(xy 120.396508 -389.46709) (xy 120.396508 -389.467344) (xy 120.396078 -389.491336) (xy 120.388565 -389.53873)
			(xy 120.373732 -389.584364) (xy 120.351943 -389.627117) (xy 120.323735 -389.665935) (xy 120.289802 -389.699863)
			(xy 120.250979 -389.728066) (xy 120.208224 -389.749849) (xy 120.162587 -389.764676) (xy 120.115192 -389.772181)
			(xy 120.0912 -389.772652) (xy 120.067536 -389.772213) (xy 120.020775 -389.764902) (xy 119.975699 -389.750471)
			(xy 119.933387 -389.729265) (xy 119.894849 -389.70179) (xy 119.861006 -389.668703) (xy 119.832668 -389.630796)
			(xy 119.821198 -389.610092) (xy 119.820944 -389.60933) (xy 119.423688 -388.922006) (xy 119.411512 -388.898788)
			(xy 119.394395 -388.849238) (xy 119.389652 -388.823454) (xy 119.389652 -388.8232) (xy 119.386123 -388.7994)
			(xy 119.385912 -388.751286) (xy 118.830233 -388.751286) (xy 119.155972 -389.314944) (xy 119.156226 -389.315452)
			(xy 119.15648 -389.315452) (xy 119.15775 -389.317992) (xy 119.169986 -389.340915) (xy 119.187304 -389.389901)
			(xy 119.196091 -389.441111) (xy 119.196612 -389.46709) (xy 119.196612 -389.467344) (xy 119.196178 -389.491336)
			(xy 119.188665 -389.538729) (xy 119.173832 -389.584363) (xy 119.152044 -389.627116) (xy 119.123836 -389.665934)
			(xy 119.089903 -389.699862) (xy 119.051082 -389.728065) (xy 119.008326 -389.749848) (xy 118.96269 -389.764675)
			(xy 118.915296 -389.772181) (xy 118.891304 -389.772652) (xy 118.86764 -389.772209) (xy 118.820879 -389.764899)
			(xy 118.775803 -389.750469) (xy 118.733491 -389.729263) (xy 118.694953 -389.701789) (xy 118.66111 -389.668703)
			(xy 118.632772 -389.630796) (xy 118.621302 -389.610092) (xy 118.621048 -389.60933) (xy 118.223792 -388.922006)
			(xy 118.211609 -388.898791) (xy 118.194497 -388.849239) (xy 118.189756 -388.823454) (xy 118.189756 -388.8232)
			(xy 118.18622 -388.799401) (xy 118.186008 -388.751286) (xy 117.630083 -388.751286) (xy 117.955822 -389.314944)
			(xy 117.956076 -389.315452) (xy 117.95633 -389.315452) (xy 117.9576 -389.317992) (xy 117.969871 -389.340908)
			(xy 117.987278 -389.389886) (xy 117.996152 -389.441101) (xy 117.996716 -389.46709) (xy 117.996716 -389.467344)
			(xy 117.996302 -389.491351) (xy 117.988781 -389.538771) (xy 117.973931 -389.584431) (xy 117.952119 -389.627203)
			(xy 117.923881 -389.666036) (xy 117.889915 -389.69997) (xy 117.851056 -389.728171) (xy 117.808262 -389.749942)
			(xy 117.762589 -389.764748) (xy 117.715161 -389.772224) (xy 117.691154 -389.772652) (xy 117.667491 -389.772169)
			(xy 117.620732 -389.764867) (xy 117.575658 -389.750444) (xy 117.533345 -389.729245) (xy 117.494807 -389.701776)
			(xy 117.460963 -389.668696) (xy 117.432623 -389.630793) (xy 117.421152 -389.610092) (xy 117.420898 -389.60933)
			(xy 117.023642 -388.922006) (xy 117.011463 -388.898789) (xy 116.994348 -388.849239) (xy 116.989606 -388.823454)
			(xy 116.989606 -388.8232) (xy 116.986164 -388.79939) (xy 116.985953 -388.751284) (xy 116.430185 -388.751284)
			(xy 116.755926 -389.314944) (xy 116.75618 -389.315452) (xy 116.756434 -389.315452) (xy 116.757704 -389.317992)
			(xy 116.769975 -389.340908) (xy 116.787382 -389.389886) (xy 116.796256 -389.441101) (xy 116.79682 -389.46709)
			(xy 116.79682 -389.467344) (xy 116.796402 -389.49135) (xy 116.788881 -389.538771) (xy 116.774031 -389.58443)
			(xy 116.752219 -389.627202) (xy 116.723982 -389.666034) (xy 116.690016 -389.699969) (xy 116.651158 -389.728169)
			(xy 116.608365 -389.749941) (xy 116.562692 -389.764748) (xy 116.515265 -389.772224) (xy 116.491258 -389.772652)
			(xy 116.467595 -389.772166) (xy 116.420836 -389.764864) (xy 116.375762 -389.750442) (xy 116.33345 -389.729243)
			(xy 116.294911 -389.701775) (xy 116.261067 -389.668695) (xy 116.232727 -389.630793) (xy 116.221256 -389.610092)
			(xy 116.221002 -389.60933) (xy 115.823746 -388.922006) (xy 115.811567 -388.898789) (xy 115.794452 -388.849239)
			(xy 115.78971 -388.823454) (xy 115.78971 -388.8232) (xy 115.78626 -388.799391) (xy 115.786049 -388.751284)
			(xy 115.230289 -388.751284) (xy 115.55603 -389.314944) (xy 115.556284 -389.315452) (xy 115.556538 -389.315452)
			(xy 115.557808 -389.317992) (xy 115.57008 -389.340908) (xy 115.587486 -389.389886) (xy 115.59636 -389.441101)
			(xy 115.596924 -389.46709) (xy 115.596924 -389.467344) (xy 115.596502 -389.49135) (xy 115.588981 -389.53877)
			(xy 115.574132 -389.584429) (xy 115.55232 -389.627201) (xy 115.524084 -389.666033) (xy 115.490118 -389.699967)
			(xy 115.45126 -389.728168) (xy 115.408468 -389.74994) (xy 115.362795 -389.764747) (xy 115.315369 -389.772224)
			(xy 115.291362 -389.772652) (xy 115.267699 -389.772163) (xy 115.220941 -389.764861) (xy 115.175866 -389.750439)
			(xy 115.133554 -389.729241) (xy 115.095015 -389.701774) (xy 115.061171 -389.668695) (xy 115.032831 -389.630793)
			(xy 115.02136 -389.610092) (xy 115.021106 -389.60933) (xy 114.62385 -388.922006) (xy 114.611671 -388.898789)
			(xy 114.594556 -388.849239) (xy 114.589814 -388.823454) (xy 114.589814 -388.8232) (xy 114.586357 -388.799392)
			(xy 114.586146 -388.751285) (xy 98.65806 -388.751285) (xy 98.9838 -389.314944) (xy 98.984054 -389.315452)
			(xy 98.984308 -389.315452) (xy 98.985578 -389.317992) (xy 98.997808 -389.340918) (xy 99.01513 -389.389903)
			(xy 99.023918 -389.441111) (xy 99.02444 -389.46709) (xy 99.02444 -389.467344) (xy 99.023978 -389.491335)
			(xy 99.016466 -389.538725) (xy 99.001635 -389.584357) (xy 98.979849 -389.627107) (xy 98.951644 -389.665924)
			(xy 98.917715 -389.699852) (xy 98.878897 -389.728055) (xy 98.836146 -389.74984) (xy 98.790513 -389.764669)
			(xy 98.743123 -389.772179) (xy 98.719132 -389.772652) (xy 98.695469 -389.772187) (xy 98.648709 -389.764881)
			(xy 98.603634 -389.750455) (xy 98.561321 -389.729253) (xy 98.522783 -389.701782) (xy 98.48894 -389.668699)
			(xy 98.460601 -389.630794) (xy 98.44913 -389.610092) (xy 98.448876 -389.60933) (xy 98.05162 -388.922006)
			(xy 98.039439 -388.89879) (xy 98.022326 -388.849239) (xy 98.017584 -388.823454) (xy 98.017584 -388.8232)
			(xy 98.014014 -388.797978) (xy 97.484894 -388.797978) (xy 97.78365 -389.314944) (xy 97.783904 -389.315452)
			(xy 97.784158 -389.315452) (xy 97.785428 -389.317992) (xy 97.797701 -389.340907) (xy 97.815106 -389.389885)
			(xy 97.82398 -389.441101) (xy 97.824544 -389.46709) (xy 97.824544 -389.467344) (xy 97.824102 -389.491349)
			(xy 97.816582 -389.538767) (xy 97.801734 -389.584424) (xy 97.779924 -389.627195) (xy 97.75169 -389.666026)
			(xy 97.717726 -389.69996) (xy 97.678871 -389.728161) (xy 97.636082 -389.749934) (xy 97.590412 -389.764743)
			(xy 97.542988 -389.772222) (xy 97.518982 -389.772652) (xy 97.495317 -389.772227) (xy 97.448555 -389.764914)
			(xy 97.40348 -389.75048) (xy 97.361167 -389.729272) (xy 97.322629 -389.701795) (xy 97.288787 -389.668706)
			(xy 97.26045 -389.630797) (xy 97.24898 -389.610092) (xy 97.248726 -389.60933) (xy 96.85147 -388.922006)
			(xy 96.839293 -388.898789) (xy 96.822177 -388.849238) (xy 96.817434 -388.823454) (xy 96.817434 -388.8232)
			(xy 96.813939 -388.799396) (xy 96.813728 -388.751285) (xy 96.258014 -388.751285) (xy 96.583754 -389.314944)
			(xy 96.584008 -389.315452) (xy 96.584262 -389.315452) (xy 96.585532 -389.317992) (xy 96.597806 -389.340907)
			(xy 96.615211 -389.389885) (xy 96.624084 -389.441101) (xy 96.624648 -389.46709) (xy 96.624648 -389.467344)
			(xy 96.624202 -389.491349) (xy 96.616682 -389.538767) (xy 96.601834 -389.584423) (xy 96.580025 -389.627194)
			(xy 96.551791 -389.666025) (xy 96.517828 -389.699959) (xy 96.478973 -389.72816) (xy 96.436184 -389.749933)
			(xy 96.390515 -389.764742) (xy 96.343091 -389.772222) (xy 96.319086 -389.772652) (xy 96.295421 -389.772224)
			(xy 96.24866 -389.764911) (xy 96.203584 -389.750478) (xy 96.161272 -389.72927) (xy 96.122734 -389.701794)
			(xy 96.088892 -389.668705) (xy 96.060554 -389.630796) (xy 96.049084 -389.610092) (xy 96.04883 -389.60933)
			(xy 95.651574 -388.922006) (xy 95.639397 -388.898788) (xy 95.622281 -388.849238) (xy 95.617538 -388.823454)
			(xy 95.617538 -388.8232) (xy 95.614036 -388.799397) (xy 95.613824 -388.751286) (xy 95.057865 -388.751286)
			(xy 95.383604 -389.314944) (xy 95.383858 -389.315452) (xy 95.384112 -389.315452) (xy 95.385382 -389.317992)
			(xy 95.397612 -389.340918) (xy 95.414934 -389.389903) (xy 95.423722 -389.441111) (xy 95.424244 -389.46709)
			(xy 95.424244 -389.467344) (xy 95.423778 -389.491335) (xy 95.416267 -389.538724) (xy 95.401435 -389.584356)
			(xy 95.379649 -389.627106) (xy 95.351445 -389.665923) (xy 95.317517 -389.69985) (xy 95.278699 -389.728054)
			(xy 95.235949 -389.749838) (xy 95.190317 -389.764668) (xy 95.142927 -389.772179) (xy 95.118936 -389.772652)
			(xy 95.095273 -389.772184) (xy 95.048513 -389.764878) (xy 95.003438 -389.750453) (xy 94.961126 -389.729251)
			(xy 94.922587 -389.701781) (xy 94.888744 -389.668698) (xy 94.860405 -389.630794) (xy 94.848934 -389.610092)
			(xy 94.84868 -389.60933) (xy 94.451424 -388.922006) (xy 94.439244 -388.89879) (xy 94.42213 -388.849239)
			(xy 94.417388 -388.823454) (xy 94.417388 -388.8232) (xy 94.413811 -388.797979) (xy 93.884953 -388.797979)
			(xy 94.183708 -389.314944) (xy 94.183962 -389.315452) (xy 94.184216 -389.315452) (xy 94.185486 -389.317992)
			(xy 94.197717 -389.340917) (xy 94.215038 -389.389902) (xy 94.223826 -389.441111) (xy 94.224348 -389.46709)
			(xy 94.224348 -389.467344) (xy 94.223878 -389.491334) (xy 94.216367 -389.538724) (xy 94.201536 -389.584355)
			(xy 94.17975 -389.627105) (xy 94.151546 -389.665922) (xy 94.117618 -389.699849) (xy 94.078802 -389.728052)
			(xy 94.036051 -389.749837) (xy 93.99042 -389.764668) (xy 93.94303 -389.772178) (xy 93.91904 -389.772652)
			(xy 93.895377 -389.77218) (xy 93.848617 -389.764876) (xy 93.803542 -389.750451) (xy 93.76123 -389.72925)
			(xy 93.722692 -389.70178) (xy 93.688848 -389.668698) (xy 93.660509 -389.630794) (xy 93.649038 -389.610092)
			(xy 93.648784 -389.60933) (xy 93.251528 -388.922006) (xy 93.239348 -388.89879) (xy 93.222234 -388.849239)
			(xy 93.217492 -388.823454) (xy 93.217492 -388.8232) (xy 93.214076 -388.799387) (xy 93.213865 -388.751284)
			(xy 92.658071 -388.751284) (xy 92.983812 -389.314944) (xy 92.984066 -389.315452) (xy 92.98432 -389.315452)
			(xy 92.98559 -389.317992) (xy 92.997821 -389.340917) (xy 93.015142 -389.389902) (xy 93.02393 -389.441111)
			(xy 93.024452 -389.46709) (xy 93.024452 -389.467344) (xy 93.023978 -389.491334) (xy 93.016467 -389.538723)
			(xy 93.001636 -389.584354) (xy 92.979851 -389.627104) (xy 92.951648 -389.66592) (xy 92.91772 -389.699848)
			(xy 92.878904 -389.728051) (xy 92.836154 -389.749836) (xy 92.790523 -389.764667) (xy 92.743134 -389.772178)
			(xy 92.719144 -389.772652) (xy 92.695481 -389.772177) (xy 92.648721 -389.764873) (xy 92.603647 -389.750449)
			(xy 92.561334 -389.729248) (xy 92.522796 -389.701779) (xy 92.488952 -389.668697) (xy 92.460613 -389.630794)
			(xy 92.449142 -389.610092) (xy 92.448888 -389.60933) (xy 92.051632 -388.922006) (xy 92.039452 -388.89879)
			(xy 92.022338 -388.849239) (xy 92.017596 -388.823454) (xy 92.017596 -388.8232) (xy 92.014173 -388.799388)
			(xy 92.013962 -388.751284) (xy 91.457921 -388.751284) (xy 91.783662 -389.314944) (xy 91.783916 -389.315452)
			(xy 91.78417 -389.315452) (xy 91.78544 -389.317992) (xy 91.797714 -389.340906) (xy 91.815119 -389.389885)
			(xy 91.823992 -389.441101) (xy 91.824556 -389.46709) (xy 91.824556 -389.467344) (xy 91.824102 -389.491349)
			(xy 91.816582 -389.538765) (xy 91.801735 -389.584421) (xy 91.779926 -389.627191) (xy 91.751693 -389.666022)
			(xy 91.717731 -389.699956) (xy 91.678878 -389.728157) (xy 91.63609 -389.749931) (xy 91.590422 -389.76474)
			(xy 91.542999 -389.772221) (xy 91.518994 -389.772652) (xy 91.495329 -389.772217) (xy 91.448568 -389.764906)
			(xy 91.403493 -389.750474) (xy 91.36118 -389.729267) (xy 91.322642 -389.701792) (xy 91.2888 -389.668704)
			(xy 91.260462 -389.630796) (xy 91.248992 -389.610092) (xy 91.248738 -389.60933) (xy 90.851482 -388.922006)
			(xy 90.839305 -388.898788) (xy 90.822189 -388.849238) (xy 90.817446 -388.823454) (xy 90.817446 -388.8232)
			(xy 90.813929 -388.799399) (xy 90.813717 -388.751286) (xy 90.258027 -388.751286) (xy 90.583766 -389.314944)
			(xy 90.58402 -389.315452) (xy 90.584274 -389.315452) (xy 90.585544 -389.317992) (xy 90.597819 -389.340906)
			(xy 90.615223 -389.389885) (xy 90.624096 -389.441101) (xy 90.62466 -389.46709) (xy 90.62466 -389.467344)
			(xy 90.624301 -389.491353) (xy 90.616779 -389.53878) (xy 90.601926 -389.584444) (xy 90.580109 -389.62722)
			(xy 90.551865 -389.666055) (xy 90.517891 -389.69999) (xy 90.479025 -389.72819) (xy 90.436223 -389.749958)
			(xy 90.390542 -389.764759) (xy 90.343108 -389.772228) (xy 90.319098 -389.772652) (xy 90.295434 -389.772214)
			(xy 90.248672 -389.764903) (xy 90.203597 -389.750472) (xy 90.161285 -389.729266) (xy 90.122747 -389.701791)
			(xy 90.088904 -389.668704) (xy 90.060566 -389.630796) (xy 90.049096 -389.610092) (xy 90.048842 -389.60933)
			(xy 89.651586 -388.922006) (xy 89.63941 -388.898788) (xy 89.622293 -388.849238) (xy 89.61755 -388.823454)
			(xy 89.61755 -388.8232) (xy 89.614025 -388.7994) (xy 89.613813 -388.751286) (xy 89.057877 -388.751286)
			(xy 89.383616 -389.314944) (xy 89.38387 -389.315452) (xy 89.384124 -389.315452) (xy 89.385394 -389.317992)
			(xy 89.397625 -389.340917) (xy 89.414946 -389.389902) (xy 89.423734 -389.441111) (xy 89.424256 -389.46709)
			(xy 89.424256 -389.467344) (xy 89.423778 -389.491334) (xy 89.416267 -389.538723) (xy 89.401436 -389.584353)
			(xy 89.379652 -389.627103) (xy 89.351449 -389.665919) (xy 89.317522 -389.699846) (xy 89.278706 -389.72805)
			(xy 89.235957 -389.749835) (xy 89.190327 -389.764666) (xy 89.142938 -389.772178) (xy 89.118948 -389.772652)
			(xy 89.095285 -389.772174) (xy 89.048526 -389.764871) (xy 89.003451 -389.750447) (xy 88.961139 -389.729247)
			(xy 88.9226 -389.701778) (xy 88.888757 -389.668697) (xy 88.860417 -389.630794) (xy 88.848946 -389.610092)
			(xy 88.848692 -389.60933) (xy 88.451436 -388.922006) (xy 88.439256 -388.89879) (xy 88.422142 -388.849239)
			(xy 88.4174 -388.823454) (xy 88.4174 -388.8232) (xy 88.413969 -388.799389) (xy 88.413758 -388.751284)
			(xy 87.857979 -388.751284) (xy 88.18372 -389.314944) (xy 88.183974 -389.315452) (xy 88.184228 -389.315452)
			(xy 88.185498 -389.317992) (xy 88.197729 -389.340917) (xy 88.21505 -389.389902) (xy 88.223838 -389.441111)
			(xy 88.22436 -389.46709) (xy 88.22436 -389.467344) (xy 88.224002 -389.491341) (xy 88.216487 -389.538742)
			(xy 88.20165 -389.584385) (xy 88.179855 -389.627144) (xy 88.151639 -389.665968) (xy 88.117698 -389.699899)
			(xy 88.078866 -389.728103) (xy 88.0361 -389.749885) (xy 87.990453 -389.764709) (xy 87.943049 -389.772209)
			(xy 87.919052 -389.772652) (xy 87.895389 -389.772171) (xy 87.84863 -389.764868) (xy 87.803556 -389.750445)
			(xy 87.761243 -389.729245) (xy 87.722705 -389.701777) (xy 87.688861 -389.668696) (xy 87.660521 -389.630793)
			(xy 87.64905 -389.610092) (xy 87.648796 -389.60933) (xy 87.25154 -388.922006) (xy 87.239361 -388.89879)
			(xy 87.222246 -388.849239) (xy 87.217504 -388.823454) (xy 87.217504 -388.8232) (xy 87.214066 -388.79939)
			(xy 87.213855 -388.751284) (xy 86.658083 -388.751284) (xy 86.983824 -389.314944) (xy 86.984078 -389.315452)
			(xy 86.984332 -389.315452) (xy 86.985602 -389.317992) (xy 86.997834 -389.340917) (xy 87.015155 -389.389902)
			(xy 87.023942 -389.441111) (xy 87.024464 -389.46709) (xy 87.024464 -389.467344) (xy 87.024078 -389.491339)
			(xy 87.016564 -389.538736) (xy 87.001728 -389.584375) (xy 86.979935 -389.62713) (xy 86.951722 -389.66595)
			(xy 86.917783 -389.699879) (xy 86.878955 -389.728081) (xy 86.836193 -389.749861) (xy 86.79055 -389.764684)
			(xy 86.743151 -389.772185) (xy 86.719156 -389.772652) (xy 86.695493 -389.772167) (xy 86.648734 -389.764865)
			(xy 86.60366 -389.750443) (xy 86.561348 -389.729244) (xy 86.522809 -389.701776) (xy 86.488965 -389.668695)
			(xy 86.460625 -389.630793) (xy 86.449154 -389.610092) (xy 86.4489 -389.60933) (xy 86.051644 -388.922006)
			(xy 86.039465 -388.898789) (xy 86.02235 -388.849239) (xy 86.017608 -388.823454) (xy 86.017608 -388.8232)
			(xy 86.014162 -388.799391) (xy 86.013951 -388.751284) (xy 85.457933 -388.751284) (xy 85.783674 -389.314944)
			(xy 85.783928 -389.315452) (xy 85.784182 -389.315452) (xy 85.785452 -389.317992) (xy 85.797727 -389.340906)
			(xy 85.815131 -389.389885) (xy 85.824004 -389.441101) (xy 85.824568 -389.46709) (xy 85.824568 -389.467344)
			(xy 85.824201 -389.491353) (xy 85.816679 -389.538778) (xy 85.801826 -389.584442) (xy 85.78001 -389.627218)
			(xy 85.751767 -389.666052) (xy 85.717795 -389.699987) (xy 85.678929 -389.728187) (xy 85.636129 -389.749956)
			(xy 85.590449 -389.764758) (xy 85.543016 -389.772228) (xy 85.519006 -389.772652) (xy 85.495342 -389.772208)
			(xy 85.448581 -389.764898) (xy 85.403506 -389.750468) (xy 85.361193 -389.729263) (xy 85.322655 -389.701789)
			(xy 85.288813 -389.668703) (xy 85.260474 -389.630795) (xy 85.249004 -389.610092) (xy 85.24875 -389.60933)
			(xy 84.851494 -388.922006) (xy 84.839312 -388.898791) (xy 84.822199 -388.849239) (xy 84.817458 -388.823454)
			(xy 84.817458 -388.8232) (xy 84.813918 -388.799402) (xy 84.813706 -388.751287) (xy 84.258039 -388.751287)
			(xy 84.583778 -389.314944) (xy 84.584032 -389.315452) (xy 84.584286 -389.315452) (xy 84.585556 -389.317992)
			(xy 84.597831 -389.340906) (xy 84.615235 -389.389885) (xy 84.624108 -389.441101) (xy 84.624672 -389.46709)
			(xy 84.624672 -389.467344) (xy 84.624301 -389.491353) (xy 84.616779 -389.538778) (xy 84.601927 -389.584441)
			(xy 84.580111 -389.627217) (xy 84.551868 -389.666051) (xy 84.517896 -389.699986) (xy 84.479031 -389.728185)
			(xy 84.436232 -389.749955) (xy 84.390552 -389.764757) (xy 84.343119 -389.772228) (xy 84.31911 -389.772652)
			(xy 84.295446 -389.772205) (xy 84.248685 -389.764896) (xy 84.20361 -389.750466) (xy 84.161298 -389.729261)
			(xy 84.122759 -389.701788) (xy 84.088917 -389.668702) (xy 84.060578 -389.630795) (xy 84.049108 -389.610092)
			(xy 84.048854 -389.60933) (xy 83.651598 -388.922006) (xy 83.639416 -388.898791) (xy 83.622303 -388.849239)
			(xy 83.617562 -388.823454) (xy 83.617562 -388.8232) (xy 83.614015 -388.799402) (xy 83.613803 -388.751287)
			(xy 83.057889 -388.751287) (xy 83.383628 -389.314944) (xy 83.383882 -389.315452) (xy 83.384136 -389.315452)
			(xy 83.385406 -389.317992) (xy 83.397638 -389.340917) (xy 83.414959 -389.389902) (xy 83.423746 -389.441111)
			(xy 83.424268 -389.46709) (xy 83.424268 -389.467344) (xy 83.423878 -389.491338) (xy 83.416364 -389.538735)
			(xy 83.401528 -389.584374) (xy 83.379736 -389.627129) (xy 83.351523 -389.665949) (xy 83.317585 -389.699878)
			(xy 83.278757 -389.728079) (xy 83.235996 -389.74986) (xy 83.190354 -389.764684) (xy 83.142955 -389.772184)
			(xy 83.11896 -389.772652) (xy 83.095297 -389.772164) (xy 83.048539 -389.764863) (xy 83.003464 -389.75044)
			(xy 82.961152 -389.729242) (xy 82.922613 -389.701775) (xy 82.888769 -389.668695) (xy 82.860429 -389.630793)
			(xy 82.848958 -389.610092) (xy 82.848704 -389.60933) (xy 82.451448 -388.922006) (xy 82.439269 -388.898789)
			(xy 82.422154 -388.849239) (xy 82.417412 -388.823454) (xy 82.417412 -388.8232) (xy 82.413959 -388.799392)
			(xy 82.413748 -388.751285) (xy 81.857992 -388.751285) (xy 82.183732 -389.314944) (xy 82.183986 -389.315452)
			(xy 82.18424 -389.315452) (xy 82.18551 -389.317992) (xy 82.197742 -389.340916) (xy 82.215063 -389.389902)
			(xy 82.22385 -389.441111) (xy 82.224372 -389.46709) (xy 82.224372 -389.467344) (xy 82.223978 -389.491338)
			(xy 82.216464 -389.538735) (xy 82.201628 -389.584373) (xy 82.179836 -389.627128) (xy 82.151624 -389.665948)
			(xy 82.117687 -389.699876) (xy 82.078859 -389.728078) (xy 82.036099 -389.749859) (xy 81.990457 -389.764683)
			(xy 81.943058 -389.772184) (xy 81.919064 -389.772652) (xy 81.895401 -389.772161) (xy 81.848643 -389.76486)
			(xy 81.803569 -389.750438) (xy 81.761256 -389.729241) (xy 81.722717 -389.701774) (xy 81.688873 -389.668694)
			(xy 81.660533 -389.630793) (xy 81.649062 -389.610092) (xy 81.648808 -389.60933) (xy 81.251552 -388.922006)
			(xy 81.239373 -388.898789) (xy 81.222258 -388.849239) (xy 81.217516 -388.823454) (xy 81.217516 -388.8232)
			(xy 81.214055 -388.799392) (xy 81.213844 -388.751285) (xy 80.658096 -388.751285) (xy 80.983836 -389.314944)
			(xy 80.98409 -389.315452) (xy 80.984344 -389.315452) (xy 80.985614 -389.317992) (xy 80.997847 -389.340916)
			(xy 81.015167 -389.389902) (xy 81.023954 -389.441111) (xy 81.024476 -389.46709) (xy 81.024476 -389.467344)
			(xy 81.024078 -389.491338) (xy 81.016564 -389.538734) (xy 81.001729 -389.584372) (xy 80.979937 -389.627127)
			(xy 80.951725 -389.665946) (xy 80.917788 -389.699875) (xy 80.878962 -389.728077) (xy 80.836201 -389.749858)
			(xy 80.79056 -389.764682) (xy 80.743162 -389.772184) (xy 80.719168 -389.772652) (xy 80.695506 -389.772158)
			(xy 80.648747 -389.764857) (xy 80.603673 -389.750436) (xy 80.561361 -389.729239) (xy 80.522822 -389.701773)
			(xy 80.488978 -389.668694) (xy 80.460637 -389.630793) (xy 80.449166 -389.610092) (xy 80.448912 -389.60933)
			(xy 80.051656 -388.922006) (xy 80.039478 -388.898789) (xy 80.022362 -388.849239) (xy 80.01762 -388.823454)
			(xy 80.01762 -388.8232) (xy 80.014152 -388.799393) (xy 80.01394 -388.751285) (xy 66.130312 -388.751285)
			(xy 66.456052 -389.314944) (xy 66.456306 -389.315452) (xy 66.45656 -389.315452) (xy 66.45783 -389.317992)
			(xy 66.470064 -389.340916) (xy 66.487383 -389.389902) (xy 66.496171 -389.441111) (xy 66.496692 -389.46709)
			(xy 66.496692 -389.467344) (xy 66.496278 -389.491337) (xy 66.488765 -389.538732) (xy 66.47393 -389.584368)
			(xy 66.45214 -389.627122) (xy 66.42393 -389.665941) (xy 66.389995 -389.699869) (xy 66.351171 -389.728071)
			(xy 66.308412 -389.749853) (xy 66.262774 -389.764679) (xy 66.215377 -389.772183) (xy 66.191384 -389.772652)
			(xy 66.167719 -389.772226) (xy 66.120957 -389.764913) (xy 66.075882 -389.750479) (xy 66.033569 -389.729271)
			(xy 65.995032 -389.701794) (xy 65.961189 -389.668706) (xy 65.932852 -389.630796) (xy 65.921382 -389.610092)
			(xy 65.921128 -389.60933) (xy 65.523872 -388.922006) (xy 65.511695 -388.898788) (xy 65.494579 -388.849238)
			(xy 65.489836 -388.823454) (xy 65.489836 -388.8232) (xy 65.486338 -388.799397) (xy 65.486126 -388.751286)
			(xy 64.930163 -388.751286) (xy 65.255902 -389.314944) (xy 65.256156 -389.315452) (xy 65.25641 -389.315452)
			(xy 65.25768 -389.317992) (xy 65.269949 -389.340909) (xy 65.287357 -389.389886) (xy 65.296232 -389.441102)
			(xy 65.296796 -389.46709) (xy 65.296796 -389.467344) (xy 65.296401 -389.491352) (xy 65.28888 -389.538774)
			(xy 65.274029 -389.584435) (xy 65.252215 -389.627209) (xy 65.223975 -389.666042) (xy 65.190006 -389.699977)
			(xy 65.151145 -389.728177) (xy 65.108348 -389.749948) (xy 65.062672 -389.764752) (xy 65.015242 -389.772226)
			(xy 64.991234 -389.772652) (xy 64.967571 -389.772185) (xy 64.920811 -389.76488) (xy 64.875736 -389.750454)
			(xy 64.833424 -389.729252) (xy 64.794885 -389.701781) (xy 64.761042 -389.668699) (xy 64.732703 -389.630794)
			(xy 64.721232 -389.610092) (xy 64.720978 -389.60933) (xy 64.323722 -388.922006) (xy 64.311541 -388.89879)
			(xy 64.294428 -388.849239) (xy 64.289686 -388.823454) (xy 64.289686 -388.8232) (xy 64.286112 -388.797979)
			(xy 63.757251 -388.797979) (xy 64.056006 -389.314944) (xy 64.05626 -389.315452) (xy 64.056514 -389.315452)
			(xy 64.057784 -389.317992) (xy 64.070054 -389.340909) (xy 64.087461 -389.389886) (xy 64.096336 -389.441101)
			(xy 64.0969 -389.46709) (xy 64.0969 -389.467344) (xy 64.096501 -389.491351) (xy 64.08898 -389.538774)
			(xy 64.07413 -389.584434) (xy 64.052316 -389.627208) (xy 64.024077 -389.666041) (xy 63.990108 -389.699976)
			(xy 63.951247 -389.728176) (xy 63.908451 -389.749947) (xy 63.862776 -389.764752) (xy 63.815346 -389.772225)
			(xy 63.791338 -389.772652) (xy 63.767675 -389.772182) (xy 63.720915 -389.764877) (xy 63.67584 -389.750452)
			(xy 63.633528 -389.729251) (xy 63.594989 -389.70178) (xy 63.561146 -389.668698) (xy 63.532807 -389.630794)
			(xy 63.521336 -389.610092) (xy 63.521082 -389.60933) (xy 63.123826 -388.922006) (xy 63.111646 -388.89879)
			(xy 63.094532 -388.849239) (xy 63.08979 -388.823454) (xy 63.08979 -388.8232) (xy 63.086378 -388.799387)
			(xy 63.086167 -388.751284) (xy 62.530115 -388.751284) (xy 62.855856 -389.314944) (xy 62.85611 -389.315452)
			(xy 62.856364 -389.315452) (xy 62.857634 -389.317992) (xy 62.869868 -389.340915) (xy 62.887188 -389.389902)
			(xy 62.895975 -389.441111) (xy 62.896496 -389.46709) (xy 62.896496 -389.467344) (xy 62.896078 -389.491337)
			(xy 62.888565 -389.538731) (xy 62.873731 -389.584367) (xy 62.851941 -389.627121) (xy 62.823731 -389.665939)
			(xy 62.789797 -389.699868) (xy 62.750973 -389.72807) (xy 62.708215 -389.749852) (xy 62.662577 -389.764678)
			(xy 62.615181 -389.772182) (xy 62.591188 -389.772652) (xy 62.567523 -389.772222) (xy 62.520762 -389.76491)
			(xy 62.475686 -389.750477) (xy 62.433374 -389.729269) (xy 62.394836 -389.701793) (xy 62.360994 -389.668705)
			(xy 62.332656 -389.630796) (xy 62.321186 -389.610092) (xy 62.320932 -389.60933) (xy 61.923676 -388.922006)
			(xy 61.911499 -388.898788) (xy 61.894383 -388.849238) (xy 61.88964 -388.823454) (xy 61.88964 -388.8232)
			(xy 61.886134 -388.799398) (xy 61.885922 -388.751286) (xy 61.330221 -388.751286) (xy 61.65596 -389.314944)
			(xy 61.656214 -389.315452) (xy 61.656468 -389.315452) (xy 61.657738 -389.317992) (xy 61.669973 -389.340915)
			(xy 61.687292 -389.389902) (xy 61.696079 -389.441111) (xy 61.6966 -389.46709) (xy 61.6966 -389.467344)
			(xy 61.696178 -389.491337) (xy 61.688665 -389.538731) (xy 61.673831 -389.584366) (xy 61.652041 -389.627119)
			(xy 61.623832 -389.665938) (xy 61.589898 -389.699866) (xy 61.551075 -389.728069) (xy 61.508318 -389.749851)
			(xy 61.46268 -389.764677) (xy 61.415285 -389.772182) (xy 61.391292 -389.772652) (xy 61.367627 -389.772219)
			(xy 61.320866 -389.764907) (xy 61.27579 -389.750475) (xy 61.233478 -389.729268) (xy 61.19494 -389.701792)
			(xy 61.161098 -389.668705) (xy 61.13276 -389.630796) (xy 61.12129 -389.610092) (xy 61.121036 -389.60933)
			(xy 60.72378 -388.922006) (xy 60.711603 -388.898788) (xy 60.694487 -388.849238) (xy 60.689744 -388.823454)
			(xy 60.689744 -388.8232) (xy 60.686231 -388.799399) (xy 60.686019 -388.751286) (xy 60.130325 -388.751286)
			(xy 60.456064 -389.314944) (xy 60.456318 -389.315452) (xy 60.456572 -389.315452) (xy 60.457842 -389.317992)
			(xy 60.470077 -389.340915) (xy 60.487396 -389.389902) (xy 60.496183 -389.441111) (xy 60.496704 -389.46709)
			(xy 60.496704 -389.467344) (xy 60.496278 -389.491337) (xy 60.488765 -389.53873) (xy 60.473931 -389.584365)
			(xy 60.452142 -389.627118) (xy 60.423933 -389.665937) (xy 60.39 -389.699865) (xy 60.351177 -389.728067)
			(xy 60.308421 -389.74985) (xy 60.262783 -389.764676) (xy 60.215389 -389.772182) (xy 60.191396 -389.772652)
			(xy 60.167731 -389.772216) (xy 60.12097 -389.764905) (xy 60.075895 -389.750473) (xy 60.033582 -389.729266)
			(xy 59.995044 -389.701791) (xy 59.961202 -389.668704) (xy 59.932864 -389.630796) (xy 59.921394 -389.610092)
			(xy 59.92114 -389.60933) (xy 59.523884 -388.922006) (xy 59.511708 -388.898788) (xy 59.494591 -388.849238)
			(xy 59.489848 -388.823454) (xy 59.489848 -388.8232) (xy 59.486327 -388.799399) (xy 59.486115 -388.751286)
			(xy 58.930175 -388.751286) (xy 59.255914 -389.314944) (xy 59.256168 -389.315452) (xy 59.256422 -389.315452)
			(xy 59.257692 -389.317992) (xy 59.269962 -389.340908) (xy 59.287369 -389.389886) (xy 59.296244 -389.441101)
			(xy 59.296808 -389.46709) (xy 59.296808 -389.467344) (xy 59.296401 -389.491351) (xy 59.28888 -389.538772)
			(xy 59.27403 -389.584432) (xy 59.252217 -389.627206) (xy 59.223979 -389.666038) (xy 59.190011 -389.699973)
			(xy 59.151151 -389.728173) (xy 59.108357 -389.749944) (xy 59.062682 -389.76475) (xy 59.015253 -389.772225)
			(xy 58.991246 -389.772652) (xy 58.967583 -389.772176) (xy 58.920824 -389.764872) (xy 58.875749 -389.750448)
			(xy 58.833437 -389.729248) (xy 58.794898 -389.701778) (xy 58.761054 -389.668697) (xy 58.732715 -389.630794)
			(xy 58.721244 -389.610092) (xy 58.72099 -389.60933) (xy 58.323734 -388.922006) (xy 58.311554 -388.89879)
			(xy 58.29444 -388.849239) (xy 58.289698 -388.823454) (xy 58.289698 -388.8232) (xy 58.286271 -388.799389)
			(xy 58.28606 -388.751284) (xy 57.730277 -388.751284) (xy 58.056018 -389.314944) (xy 58.056272 -389.315452)
			(xy 58.056526 -389.315452) (xy 58.057796 -389.317992) (xy 58.070067 -389.340908) (xy 58.087474 -389.389886)
			(xy 58.096348 -389.441101) (xy 58.096912 -389.46709) (xy 58.096912 -389.467344) (xy 58.096502 -389.491351)
			(xy 58.08898 -389.538772) (xy 58.074131 -389.584432) (xy 58.052318 -389.627205) (xy 58.02408 -389.666037)
			(xy 57.990113 -389.699971) (xy 57.951253 -389.728172) (xy 57.908459 -389.749943) (xy 57.862786 -389.764749)
			(xy 57.815357 -389.772225) (xy 57.79135 -389.772652) (xy 57.767687 -389.772172) (xy 57.720928 -389.764869)
			(xy 57.675853 -389.750446) (xy 57.633541 -389.729246) (xy 57.595002 -389.701777) (xy 57.561159 -389.668696)
			(xy 57.532819 -389.630793) (xy 57.521348 -389.610092) (xy 57.521094 -389.60933) (xy 57.123838 -388.922006)
			(xy 57.111658 -388.89879) (xy 57.094544 -388.849239) (xy 57.089802 -388.823454) (xy 57.089802 -388.8232)
			(xy 57.086367 -388.799389) (xy 57.086156 -388.751284) (xy 56.530127 -388.751284) (xy 56.855868 -389.314944)
			(xy 56.856122 -389.315452) (xy 56.856376 -389.315452) (xy 56.857646 -389.317992) (xy 56.869881 -389.340915)
			(xy 56.8872 -389.389902) (xy 56.895987 -389.441111) (xy 56.896508 -389.46709) (xy 56.896508 -389.467344)
			(xy 56.896078 -389.491336) (xy 56.888565 -389.53873) (xy 56.873732 -389.584364) (xy 56.851943 -389.627117)
			(xy 56.823735 -389.665935) (xy 56.789802 -389.699863) (xy 56.750979 -389.728066) (xy 56.708224 -389.749849)
			(xy 56.662587 -389.764676) (xy 56.615192 -389.772181) (xy 56.5912 -389.772652) (xy 56.567536 -389.772213)
			(xy 56.520775 -389.764902) (xy 56.475699 -389.750471) (xy 56.433387 -389.729265) (xy 56.394849 -389.70179)
			(xy 56.361006 -389.668703) (xy 56.332668 -389.630796) (xy 56.321198 -389.610092) (xy 56.320944 -389.60933)
			(xy 55.923688 -388.922006) (xy 55.911512 -388.898788) (xy 55.894395 -388.849238) (xy 55.889652 -388.823454)
			(xy 55.889652 -388.8232) (xy 55.886123 -388.7994) (xy 55.885912 -388.751286) (xy 55.330233 -388.751286)
			(xy 55.655972 -389.314944) (xy 55.656226 -389.315452) (xy 55.65648 -389.315452) (xy 55.65775 -389.317992)
			(xy 55.669986 -389.340915) (xy 55.687304 -389.389901) (xy 55.696091 -389.441111) (xy 55.696612 -389.46709)
			(xy 55.696612 -389.467344) (xy 55.696178 -389.491336) (xy 55.688665 -389.538729) (xy 55.673832 -389.584363)
			(xy 55.652044 -389.627116) (xy 55.623836 -389.665934) (xy 55.589903 -389.699862) (xy 55.551082 -389.728065)
			(xy 55.508326 -389.749848) (xy 55.46269 -389.764675) (xy 55.415296 -389.772181) (xy 55.391304 -389.772652)
			(xy 55.36764 -389.772209) (xy 55.320879 -389.764899) (xy 55.275803 -389.750469) (xy 55.233491 -389.729263)
			(xy 55.194953 -389.701789) (xy 55.16111 -389.668703) (xy 55.132772 -389.630796) (xy 55.121302 -389.610092)
			(xy 55.121048 -389.60933) (xy 54.723792 -388.922006) (xy 54.711609 -388.898791) (xy 54.694497 -388.849239)
			(xy 54.689756 -388.823454) (xy 54.689756 -388.8232) (xy 54.68622 -388.799401) (xy 54.686008 -388.751286)
			(xy 54.130337 -388.751286) (xy 54.456076 -389.314944) (xy 54.45633 -389.315452) (xy 54.456584 -389.315452)
			(xy 54.457854 -389.317992) (xy 54.47009 -389.340915) (xy 54.487408 -389.389901) (xy 54.496195 -389.441111)
			(xy 54.496716 -389.46709) (xy 54.496716 -389.467344) (xy 54.496278 -389.491336) (xy 54.488766 -389.538728)
			(xy 54.473933 -389.584362) (xy 54.452144 -389.627115) (xy 54.423937 -389.665932) (xy 54.390005 -389.69986)
			(xy 54.351184 -389.728063) (xy 54.308429 -389.749846) (xy 54.262793 -389.764674) (xy 54.2154 -389.772181)
			(xy 54.191408 -389.772652) (xy 54.167744 -389.772206) (xy 54.120983 -389.764897) (xy 54.075908 -389.750467)
			(xy 54.033595 -389.729262) (xy 53.995057 -389.701788) (xy 53.961215 -389.668702) (xy 53.932876 -389.630795)
			(xy 53.921406 -389.610092) (xy 53.921152 -389.60933) (xy 53.523896 -388.922006) (xy 53.511714 -388.898791)
			(xy 53.494601 -388.849239) (xy 53.48986 -388.823454) (xy 53.48986 -388.8232) (xy 53.486316 -388.799402)
			(xy 53.486104 -388.751287) (xy 52.930187 -388.751287) (xy 53.255926 -389.314944) (xy 53.25618 -389.315452)
			(xy 53.256434 -389.315452) (xy 53.257704 -389.317992) (xy 53.269975 -389.340908) (xy 53.287382 -389.389886)
			(xy 53.296256 -389.441101) (xy 53.29682 -389.46709) (xy 53.29682 -389.467344) (xy 53.296402 -389.49135)
			(xy 53.288881 -389.538771) (xy 53.274031 -389.58443) (xy 53.252219 -389.627202) (xy 53.223982 -389.666034)
			(xy 53.190016 -389.699969) (xy 53.151158 -389.728169) (xy 53.108365 -389.749941) (xy 53.062692 -389.764748)
			(xy 53.015265 -389.772224) (xy 52.991258 -389.772652) (xy 52.967595 -389.772166) (xy 52.920836 -389.764864)
			(xy 52.875762 -389.750442) (xy 52.83345 -389.729243) (xy 52.794911 -389.701775) (xy 52.761067 -389.668695)
			(xy 52.732727 -389.630793) (xy 52.721256 -389.610092) (xy 52.721002 -389.60933) (xy 52.323746 -388.922006)
			(xy 52.311567 -388.898789) (xy 52.294452 -388.849239) (xy 52.28971 -388.823454) (xy 52.28971 -388.8232)
			(xy 52.28626 -388.799391) (xy 52.286049 -388.751284) (xy 51.730289 -388.751284) (xy 52.05603 -389.314944)
			(xy 52.056284 -389.315452) (xy 52.056538 -389.315452) (xy 52.057808 -389.317992) (xy 52.07008 -389.340908)
			(xy 52.087486 -389.389886) (xy 52.09636 -389.441101) (xy 52.096924 -389.46709) (xy 52.096924 -389.467344)
			(xy 52.096502 -389.49135) (xy 52.088981 -389.53877) (xy 52.074132 -389.584429) (xy 52.05232 -389.627201)
			(xy 52.024084 -389.666033) (xy 51.990118 -389.699967) (xy 51.95126 -389.728168) (xy 51.908468 -389.74994)
			(xy 51.862795 -389.764747) (xy 51.815369 -389.772224) (xy 51.791362 -389.772652) (xy 51.767699 -389.772163)
			(xy 51.720941 -389.764861) (xy 51.675866 -389.750439) (xy 51.633554 -389.729241) (xy 51.595015 -389.701774)
			(xy 51.561171 -389.668695) (xy 51.532831 -389.630793) (xy 51.52136 -389.610092) (xy 51.521106 -389.60933)
			(xy 51.12385 -388.922006) (xy 51.111671 -388.898789) (xy 51.094556 -388.849239) (xy 51.089814 -388.823454)
			(xy 51.089814 -388.8232) (xy 51.086357 -388.799392) (xy 51.086146 -388.751285) (xy 50.53014 -388.751285)
			(xy 50.85588 -389.314944) (xy 50.856134 -389.315452) (xy 50.856388 -389.315452) (xy 50.857658 -389.317992)
			(xy 50.869894 -389.340914) (xy 50.887212 -389.389901) (xy 50.895999 -389.441111) (xy 50.89652 -389.46709)
			(xy 50.89652 -389.467344) (xy 50.896078 -389.491336) (xy 50.888566 -389.538728) (xy 50.873733 -389.584362)
			(xy 50.851945 -389.627113) (xy 50.823738 -389.665931) (xy 50.789807 -389.699859) (xy 50.750986 -389.728062)
			(xy 50.708232 -389.749845) (xy 50.662597 -389.764673) (xy 50.615204 -389.772181) (xy 50.591212 -389.772652)
			(xy 50.567548 -389.772203) (xy 50.520787 -389.764894) (xy 50.475712 -389.750465) (xy 50.4334 -389.72926)
			(xy 50.394862 -389.701787) (xy 50.361019 -389.668702) (xy 50.33268 -389.630795) (xy 50.32121 -389.610092)
			(xy 50.320956 -389.60933) (xy 49.9237 -388.922006) (xy 49.911518 -388.898791) (xy 49.894405 -388.849239)
			(xy 49.889664 -388.823454) (xy 49.889664 -388.8232) (xy 49.886113 -388.799403) (xy 49.885901 -388.751287)
			(xy 49.330245 -388.751287) (xy 49.655984 -389.314944) (xy 49.656238 -389.315452) (xy 49.656492 -389.315452)
			(xy 49.657762 -389.317992) (xy 49.669999 -389.340914) (xy 49.687316 -389.389901) (xy 49.696103 -389.441111)
			(xy 49.696624 -389.46709) (xy 49.696624 -389.467344) (xy 49.696178 -389.491336) (xy 49.688666 -389.538727)
			(xy 49.673833 -389.584361) (xy 49.652046 -389.627112) (xy 49.623839 -389.66593) (xy 49.589908 -389.699858)
			(xy 49.551088 -389.72806) (xy 49.508335 -389.749844) (xy 49.4627 -389.764672) (xy 49.415308 -389.77218)
			(xy 49.391316 -389.772652) (xy 49.367652 -389.7722) (xy 49.320892 -389.764892) (xy 49.275816 -389.750463)
			(xy 49.233504 -389.729259) (xy 49.194966 -389.701786) (xy 49.161123 -389.668701) (xy 49.132784 -389.630795)
			(xy 49.121314 -389.610092) (xy 49.12106 -389.60933) (xy 48.723804 -388.922006) (xy 48.711622 -388.898791)
			(xy 48.694509 -388.849239) (xy 48.689768 -388.823454) (xy 48.689768 -388.8232) (xy 48.686228 -388.797975)
			(xy 48.15733 -388.797975) (xy 48.456088 -389.314944) (xy 48.456342 -389.315452) (xy 48.456596 -389.315452)
			(xy 48.457866 -389.317992) (xy 48.470103 -389.340914) (xy 48.48742 -389.389901) (xy 48.496207 -389.441111)
			(xy 48.496728 -389.46709) (xy 48.496728 -389.467344) (xy 48.496278 -389.491335) (xy 48.488766 -389.538727)
			(xy 48.473934 -389.58436) (xy 48.452147 -389.627111) (xy 48.423941 -389.665928) (xy 48.39001 -389.699856)
			(xy 48.351191 -389.728059) (xy 48.308437 -389.749843) (xy 48.262803 -389.764672) (xy 48.215411 -389.77218)
			(xy 48.19142 -389.772652) (xy 48.167756 -389.772196) (xy 48.120996 -389.764889) (xy 48.075921 -389.750461)
			(xy 48.033608 -389.729257) (xy 47.99507 -389.701785) (xy 47.961227 -389.668701) (xy 47.932888 -389.630795)
			(xy 47.921418 -389.610092) (xy 47.921164 -389.60933) (xy 47.523908 -388.922006) (xy 47.511727 -388.898791)
			(xy 47.494614 -388.849239) (xy 47.489872 -388.823454) (xy 47.489872 -388.8232) (xy 47.486325 -388.797976)
			(xy 2.509012 -388.797976) (xy 2.509012 -390.75106) (xy 297.048936 -390.75106) (xy 297.048936 -389.88746)
			(xy 297.049422 -389.860209) (xy 297.057178 -389.806261) (xy 297.072533 -389.753966) (xy 297.095175 -389.704389)
			(xy 297.124641 -389.658539) (xy 297.160332 -389.617348) (xy 297.201523 -389.581657) (xy 297.247373 -389.552191)
			(xy 297.29695 -389.529549) (xy 297.349245 -389.514194) (xy 297.403193 -389.506438) (xy 297.457695 -389.506438)
			(xy 297.511643 -389.514194) (xy 297.563938 -389.529549) (xy 297.613515 -389.552191) (xy 297.659365 -389.581657)
			(xy 297.700556 -389.617348) (xy 297.736247 -389.658539) (xy 297.765713 -389.704389) (xy 297.788355 -389.753966)
			(xy 297.80371 -389.806261) (xy 297.811466 -389.860209) (xy 297.811952 -389.88746) (xy 297.811952 -390.75106)
			(xy 329.576684 -390.75106) (xy 329.576684 -389.88746) (xy 329.57717 -389.860209) (xy 329.584926 -389.806261)
			(xy 329.600281 -389.753966) (xy 329.622923 -389.704389) (xy 329.652389 -389.658539) (xy 329.68808 -389.617348)
			(xy 329.729271 -389.581657) (xy 329.775121 -389.552191) (xy 329.824698 -389.529549) (xy 329.876993 -389.514194)
			(xy 329.930941 -389.506438) (xy 329.985443 -389.506438) (xy 330.039391 -389.514194) (xy 330.091686 -389.529549)
			(xy 330.141263 -389.552191) (xy 330.187113 -389.581657) (xy 330.228304 -389.617348) (xy 330.263995 -389.658539)
			(xy 330.293461 -389.704389) (xy 330.316103 -389.753966) (xy 330.331458 -389.806261) (xy 330.339214 -389.860209)
			(xy 330.3397 -389.88746) (xy 330.3397 -390.75106) (xy 364.149132 -390.75106) (xy 364.149132 -389.88746)
			(xy 364.149618 -389.860209) (xy 364.157374 -389.806261) (xy 364.172729 -389.753966) (xy 364.195371 -389.704389)
			(xy 364.224837 -389.658539) (xy 364.260528 -389.617348) (xy 364.301719 -389.581657) (xy 364.347569 -389.552191)
			(xy 364.397146 -389.529549) (xy 364.449441 -389.514194) (xy 364.503389 -389.506438) (xy 364.557891 -389.506438)
			(xy 364.611839 -389.514194) (xy 364.664134 -389.529549) (xy 364.713711 -389.552191) (xy 364.759561 -389.581657)
			(xy 364.800752 -389.617348) (xy 364.836443 -389.658539) (xy 364.865909 -389.704389) (xy 364.888551 -389.753966)
			(xy 364.903906 -389.806261) (xy 364.911662 -389.860209) (xy 364.912148 -389.88746) (xy 364.912148 -390.75106)
			(xy 396.67688 -390.75106) (xy 396.67688 -389.88746) (xy 396.677366 -389.860209) (xy 396.685122 -389.806261)
			(xy 396.700477 -389.753966) (xy 396.723119 -389.704389) (xy 396.752585 -389.658539) (xy 396.788276 -389.617348)
			(xy 396.829467 -389.581657) (xy 396.875317 -389.552191) (xy 396.924894 -389.529549) (xy 396.977189 -389.514194)
			(xy 397.031137 -389.506438) (xy 397.085639 -389.506438) (xy 397.139587 -389.514194) (xy 397.191882 -389.529549)
			(xy 397.241459 -389.552191) (xy 397.287309 -389.581657) (xy 397.3285 -389.617348) (xy 397.364191 -389.658539)
			(xy 397.393657 -389.704389) (xy 397.416299 -389.753966) (xy 397.431654 -389.806261) (xy 397.43941 -389.860209)
			(xy 397.439896 -389.88746) (xy 397.439896 -390.75106) (xy 397.43941 -390.778311) (xy 397.431654 -390.832259)
			(xy 397.416299 -390.884554) (xy 397.393657 -390.934131) (xy 397.364191 -390.979981) (xy 397.3285 -391.021172)
			(xy 397.287309 -391.056863) (xy 397.241459 -391.086329) (xy 397.191882 -391.108971) (xy 397.139587 -391.124326)
			(xy 397.085639 -391.132082) (xy 397.031137 -391.132082) (xy 396.977189 -391.124326) (xy 396.924894 -391.108971)
			(xy 396.875317 -391.086329) (xy 396.829467 -391.056863) (xy 396.788276 -391.021172) (xy 396.752585 -390.979981)
			(xy 396.723119 -390.934131) (xy 396.700477 -390.884554) (xy 396.685122 -390.832259) (xy 396.677366 -390.778311)
			(xy 396.67688 -390.75106) (xy 364.912148 -390.75106) (xy 364.911662 -390.778311) (xy 364.903906 -390.832259)
			(xy 364.888551 -390.884554) (xy 364.865909 -390.934131) (xy 364.836443 -390.979981) (xy 364.800752 -391.021172)
			(xy 364.759561 -391.056863) (xy 364.713711 -391.086329) (xy 364.664134 -391.108971) (xy 364.611839 -391.124326)
			(xy 364.557891 -391.132082) (xy 364.503389 -391.132082) (xy 364.449441 -391.124326) (xy 364.397146 -391.108971)
			(xy 364.347569 -391.086329) (xy 364.301719 -391.056863) (xy 364.260528 -391.021172) (xy 364.224837 -390.979981)
			(xy 364.195371 -390.934131) (xy 364.172729 -390.884554) (xy 364.157374 -390.832259) (xy 364.149618 -390.778311)
			(xy 364.149132 -390.75106) (xy 330.3397 -390.75106) (xy 330.339214 -390.778311) (xy 330.331458 -390.832259)
			(xy 330.316103 -390.884554) (xy 330.293461 -390.934131) (xy 330.263995 -390.979981) (xy 330.228304 -391.021172)
			(xy 330.187113 -391.056863) (xy 330.141263 -391.086329) (xy 330.091686 -391.108971) (xy 330.039391 -391.124326)
			(xy 329.985443 -391.132082) (xy 329.930941 -391.132082) (xy 329.876993 -391.124326) (xy 329.824698 -391.108971)
			(xy 329.775121 -391.086329) (xy 329.729271 -391.056863) (xy 329.68808 -391.021172) (xy 329.652389 -390.979981)
			(xy 329.622923 -390.934131) (xy 329.600281 -390.884554) (xy 329.584926 -390.832259) (xy 329.57717 -390.778311)
			(xy 329.576684 -390.75106) (xy 297.811952 -390.75106) (xy 297.811466 -390.778311) (xy 297.80371 -390.832259)
			(xy 297.788355 -390.884554) (xy 297.765713 -390.934131) (xy 297.736247 -390.979981) (xy 297.700556 -391.021172)
			(xy 297.659365 -391.056863) (xy 297.613515 -391.086329) (xy 297.563938 -391.108971) (xy 297.511643 -391.124326)
			(xy 297.457695 -391.132082) (xy 297.403193 -391.132082) (xy 297.349245 -391.124326) (xy 297.29695 -391.108971)
			(xy 297.247373 -391.086329) (xy 297.201523 -391.056863) (xy 297.160332 -391.021172) (xy 297.124641 -390.979981)
			(xy 297.095175 -390.934131) (xy 297.072533 -390.884554) (xy 297.057178 -390.832259) (xy 297.049422 -390.778311)
			(xy 297.048936 -390.75106) (xy 2.509012 -390.75106) (xy 2.509012 -393.292838) (xy 47.435008 -393.292838)
			(xy 47.435008 -392.429238) (xy 47.435494 -392.401987) (xy 47.44325 -392.348039) (xy 47.458605 -392.295744)
			(xy 47.481247 -392.246167) (xy 47.510713 -392.200317) (xy 47.546404 -392.159126) (xy 47.587595 -392.123435)
			(xy 47.633445 -392.093969) (xy 47.683022 -392.071327) (xy 47.735317 -392.055972) (xy 47.789265 -392.048216)
			(xy 47.843767 -392.048216) (xy 47.897715 -392.055972) (xy 47.95001 -392.071327) (xy 47.999587 -392.093969)
			(xy 48.045437 -392.123435) (xy 48.086628 -392.159126) (xy 48.122319 -392.200317) (xy 48.151785 -392.246167)
			(xy 48.174427 -392.295744) (xy 48.189782 -392.348039) (xy 48.197538 -392.401987) (xy 48.198024 -392.429238)
			(xy 48.198024 -393.292838) (xy 48.634904 -393.292838) (xy 48.634904 -392.429238) (xy 48.63539 -392.401987)
			(xy 48.643146 -392.348039) (xy 48.658501 -392.295744) (xy 48.681143 -392.246167) (xy 48.710609 -392.200317)
			(xy 48.7463 -392.159126) (xy 48.787491 -392.123435) (xy 48.833341 -392.093969) (xy 48.882918 -392.071327)
			(xy 48.935213 -392.055972) (xy 48.989161 -392.048216) (xy 49.043663 -392.048216) (xy 49.097611 -392.055972)
			(xy 49.149906 -392.071327) (xy 49.199483 -392.093969) (xy 49.245333 -392.123435) (xy 49.286524 -392.159126)
			(xy 49.322215 -392.200317) (xy 49.351681 -392.246167) (xy 49.374323 -392.295744) (xy 49.389678 -392.348039)
			(xy 49.397434 -392.401987) (xy 49.39792 -392.429238) (xy 49.39792 -393.292838) (xy 49.8348 -393.292838)
			(xy 49.8348 -392.429238) (xy 49.835286 -392.401969) (xy 49.843048 -392.347985) (xy 49.858413 -392.295655)
			(xy 49.88107 -392.246045) (xy 49.910556 -392.200164) (xy 49.946271 -392.158947) (xy 49.987488 -392.123232)
			(xy 50.033369 -392.093746) (xy 50.082979 -392.071089) (xy 50.135309 -392.055724) (xy 50.189293 -392.047962)
			(xy 50.243831 -392.047962) (xy 50.297815 -392.055724) (xy 50.350145 -392.071089) (xy 50.399755 -392.093746)
			(xy 50.445636 -392.123232) (xy 50.486853 -392.158947) (xy 50.522568 -392.200164) (xy 50.552054 -392.246045)
			(xy 50.574711 -392.295655) (xy 50.590076 -392.347985) (xy 50.597838 -392.401969) (xy 50.598324 -392.429238)
			(xy 50.598324 -393.292838) (xy 51.034696 -393.292838) (xy 51.034696 -392.429238) (xy 51.035182 -392.401969)
			(xy 51.042944 -392.347985) (xy 51.058309 -392.295655) (xy 51.080966 -392.246045) (xy 51.110452 -392.200164)
			(xy 51.146167 -392.158947) (xy 51.187384 -392.123232) (xy 51.233265 -392.093746) (xy 51.282875 -392.071089)
			(xy 51.335205 -392.055724) (xy 51.389189 -392.047962) (xy 51.443727 -392.047962) (xy 51.497711 -392.055724)
			(xy 51.550041 -392.071089) (xy 51.599651 -392.093746) (xy 51.645532 -392.123232) (xy 51.686749 -392.158947)
			(xy 51.722464 -392.200164) (xy 51.75195 -392.246045) (xy 51.774607 -392.295655) (xy 51.789972 -392.347985)
			(xy 51.797734 -392.401969) (xy 51.79822 -392.429238) (xy 51.79822 -393.292838) (xy 52.2351 -393.292838)
			(xy 52.2351 -392.429238) (xy 52.235586 -392.401987) (xy 52.243342 -392.348039) (xy 52.258697 -392.295744)
			(xy 52.281339 -392.246167) (xy 52.310805 -392.200317) (xy 52.346496 -392.159126) (xy 52.387687 -392.123435)
			(xy 52.433537 -392.093969) (xy 52.483114 -392.071327) (xy 52.535409 -392.055972) (xy 52.589357 -392.048216)
			(xy 52.643859 -392.048216) (xy 52.697807 -392.055972) (xy 52.750102 -392.071327) (xy 52.799679 -392.093969)
			(xy 52.845529 -392.123435) (xy 52.88672 -392.159126) (xy 52.922411 -392.200317) (xy 52.951877 -392.246167)
			(xy 52.974519 -392.295744) (xy 52.989874 -392.348039) (xy 52.99763 -392.401987) (xy 52.998116 -392.429238)
			(xy 52.998116 -393.292838) (xy 53.434996 -393.292838) (xy 53.434996 -392.429238) (xy 53.435482 -392.401987)
			(xy 53.443238 -392.348039) (xy 53.458593 -392.295744) (xy 53.481235 -392.246167) (xy 53.510701 -392.200317)
			(xy 53.546392 -392.159126) (xy 53.587583 -392.123435) (xy 53.633433 -392.093969) (xy 53.68301 -392.071327)
			(xy 53.735305 -392.055972) (xy 53.789253 -392.048216) (xy 53.843755 -392.048216) (xy 53.897703 -392.055972)
			(xy 53.949998 -392.071327) (xy 53.999575 -392.093969) (xy 54.045425 -392.123435) (xy 54.086616 -392.159126)
			(xy 54.122307 -392.200317) (xy 54.151773 -392.246167) (xy 54.174415 -392.295744) (xy 54.18977 -392.348039)
			(xy 54.197526 -392.401987) (xy 54.198012 -392.429238) (xy 54.198012 -393.292838) (xy 54.634892 -393.292838)
			(xy 54.634892 -392.429238) (xy 54.635378 -392.401969) (xy 54.64314 -392.347985) (xy 54.658505 -392.295655)
			(xy 54.681162 -392.246045) (xy 54.710648 -392.200164) (xy 54.746363 -392.158947) (xy 54.78758 -392.123232)
			(xy 54.833461 -392.093746) (xy 54.883071 -392.071089) (xy 54.935401 -392.055724) (xy 54.989385 -392.047962)
			(xy 55.043923 -392.047962) (xy 55.097907 -392.055724) (xy 55.150237 -392.071089) (xy 55.199847 -392.093746)
			(xy 55.245728 -392.123232) (xy 55.286945 -392.158947) (xy 55.32266 -392.200164) (xy 55.352146 -392.246045)
			(xy 55.374803 -392.295655) (xy 55.390168 -392.347985) (xy 55.39793 -392.401969) (xy 55.398416 -392.429238)
			(xy 55.398416 -393.292838) (xy 55.834788 -393.292838) (xy 55.834788 -392.429238) (xy 55.835274 -392.401969)
			(xy 55.843036 -392.347985) (xy 55.858401 -392.295655) (xy 55.881058 -392.246045) (xy 55.910544 -392.200164)
			(xy 55.946259 -392.158947) (xy 55.987476 -392.123232) (xy 56.033357 -392.093746) (xy 56.082967 -392.071089)
			(xy 56.135297 -392.055724) (xy 56.189281 -392.047962) (xy 56.243819 -392.047962) (xy 56.297803 -392.055724)
			(xy 56.350133 -392.071089) (xy 56.399743 -392.093746) (xy 56.445624 -392.123232) (xy 56.486841 -392.158947)
			(xy 56.522556 -392.200164) (xy 56.552042 -392.246045) (xy 56.574699 -392.295655) (xy 56.590064 -392.347985)
			(xy 56.597826 -392.401969) (xy 56.598312 -392.429238) (xy 56.598312 -393.292838) (xy 57.035192 -393.292838)
			(xy 57.035192 -392.429238) (xy 57.035678 -392.401987) (xy 57.043434 -392.348039) (xy 57.058789 -392.295744)
			(xy 57.081431 -392.246167) (xy 57.110897 -392.200317) (xy 57.146588 -392.159126) (xy 57.187779 -392.123435)
			(xy 57.233629 -392.093969) (xy 57.283206 -392.071327) (xy 57.335501 -392.055972) (xy 57.389449 -392.048216)
			(xy 57.443951 -392.048216) (xy 57.497899 -392.055972) (xy 57.550194 -392.071327) (xy 57.599771 -392.093969)
			(xy 57.645621 -392.123435) (xy 57.686812 -392.159126) (xy 57.722503 -392.200317) (xy 57.751969 -392.246167)
			(xy 57.774611 -392.295744) (xy 57.789966 -392.348039) (xy 57.797722 -392.401987) (xy 57.798208 -392.429238)
			(xy 57.798208 -393.292838) (xy 58.235088 -393.292838) (xy 58.235088 -392.429238) (xy 58.235574 -392.401987)
			(xy 58.24333 -392.348039) (xy 58.258685 -392.295744) (xy 58.281327 -392.246167) (xy 58.310793 -392.200317)
			(xy 58.346484 -392.159126) (xy 58.387675 -392.123435) (xy 58.433525 -392.093969) (xy 58.483102 -392.071327)
			(xy 58.535397 -392.055972) (xy 58.589345 -392.048216) (xy 58.643847 -392.048216) (xy 58.697795 -392.055972)
			(xy 58.75009 -392.071327) (xy 58.799667 -392.093969) (xy 58.845517 -392.123435) (xy 58.886708 -392.159126)
			(xy 58.922399 -392.200317) (xy 58.951865 -392.246167) (xy 58.974507 -392.295744) (xy 58.989862 -392.348039)
			(xy 58.997618 -392.401987) (xy 58.998104 -392.429238) (xy 58.998104 -393.292838) (xy 59.434984 -393.292838)
			(xy 59.434984 -392.429238) (xy 59.43547 -392.401969) (xy 59.443232 -392.347985) (xy 59.458597 -392.295655)
			(xy 59.481254 -392.246045) (xy 59.51074 -392.200164) (xy 59.546455 -392.158947) (xy 59.587672 -392.123232)
			(xy 59.633553 -392.093746) (xy 59.683163 -392.071089) (xy 59.735493 -392.055724) (xy 59.789477 -392.047962)
			(xy 59.844015 -392.047962) (xy 59.897999 -392.055724) (xy 59.950329 -392.071089) (xy 59.999939 -392.093746)
			(xy 60.04582 -392.123232) (xy 60.087037 -392.158947) (xy 60.122752 -392.200164) (xy 60.152238 -392.246045)
			(xy 60.174895 -392.295655) (xy 60.19026 -392.347985) (xy 60.198022 -392.401969) (xy 60.198508 -392.429238)
			(xy 60.198508 -393.292838) (xy 60.63488 -393.292838) (xy 60.63488 -392.429238) (xy 60.635366 -392.401969)
			(xy 60.643128 -392.347985) (xy 60.658493 -392.295655) (xy 60.68115 -392.246045) (xy 60.710636 -392.200164)
			(xy 60.746351 -392.158947) (xy 60.787568 -392.123232) (xy 60.833449 -392.093746) (xy 60.883059 -392.071089)
			(xy 60.935389 -392.055724) (xy 60.989373 -392.047962) (xy 61.043911 -392.047962) (xy 61.097895 -392.055724)
			(xy 61.150225 -392.071089) (xy 61.199835 -392.093746) (xy 61.245716 -392.123232) (xy 61.286933 -392.158947)
			(xy 61.322648 -392.200164) (xy 61.352134 -392.246045) (xy 61.374791 -392.295655) (xy 61.390156 -392.347985)
			(xy 61.397918 -392.401969) (xy 61.398404 -392.429238) (xy 61.398404 -393.292838) (xy 61.834776 -393.292838)
			(xy 61.834776 -392.429238) (xy 61.835262 -392.401969) (xy 61.843024 -392.347985) (xy 61.858389 -392.295655)
			(xy 61.881046 -392.246045) (xy 61.910532 -392.200164) (xy 61.946247 -392.158947) (xy 61.987464 -392.123232)
			(xy 62.033345 -392.093746) (xy 62.082955 -392.071089) (xy 62.135285 -392.055724) (xy 62.189269 -392.047962)
			(xy 62.243807 -392.047962) (xy 62.297791 -392.055724) (xy 62.350121 -392.071089) (xy 62.399731 -392.093746)
			(xy 62.445612 -392.123232) (xy 62.486829 -392.158947) (xy 62.522544 -392.200164) (xy 62.55203 -392.246045)
			(xy 62.574687 -392.295655) (xy 62.590052 -392.347985) (xy 62.597814 -392.401969) (xy 62.5983 -392.429238)
			(xy 62.5983 -393.292838) (xy 63.034672 -393.292838) (xy 63.034672 -392.429238) (xy 63.035158 -392.401969)
			(xy 63.04292 -392.347985) (xy 63.058285 -392.295655) (xy 63.080942 -392.246045) (xy 63.110428 -392.200164)
			(xy 63.146143 -392.158947) (xy 63.18736 -392.123232) (xy 63.233241 -392.093746) (xy 63.282851 -392.071089)
			(xy 63.335181 -392.055724) (xy 63.389165 -392.047962) (xy 63.443703 -392.047962) (xy 63.497687 -392.055724)
			(xy 63.550017 -392.071089) (xy 63.599627 -392.093746) (xy 63.645508 -392.123232) (xy 63.686725 -392.158947)
			(xy 63.72244 -392.200164) (xy 63.751926 -392.246045) (xy 63.774583 -392.295655) (xy 63.789948 -392.347985)
			(xy 63.79771 -392.401969) (xy 63.798196 -392.429238) (xy 63.798196 -393.292838) (xy 64.235076 -393.292838)
			(xy 64.235076 -392.429238) (xy 64.235562 -392.401987) (xy 64.243318 -392.348039) (xy 64.258673 -392.295744)
			(xy 64.281315 -392.246167) (xy 64.310781 -392.200317) (xy 64.346472 -392.159126) (xy 64.387663 -392.123435)
			(xy 64.433513 -392.093969) (xy 64.48309 -392.071327) (xy 64.535385 -392.055972) (xy 64.589333 -392.048216)
			(xy 64.643835 -392.048216) (xy 64.697783 -392.055972) (xy 64.750078 -392.071327) (xy 64.799655 -392.093969)
			(xy 64.845505 -392.123435) (xy 64.886696 -392.159126) (xy 64.922387 -392.200317) (xy 64.951853 -392.246167)
			(xy 64.974495 -392.295744) (xy 64.98985 -392.348039) (xy 64.997606 -392.401987) (xy 64.998092 -392.429238)
			(xy 64.998092 -393.292838) (xy 65.434972 -393.292838) (xy 65.434972 -392.429238) (xy 65.435458 -392.401987)
			(xy 65.443214 -392.348039) (xy 65.458569 -392.295744) (xy 65.481211 -392.246167) (xy 65.510677 -392.200317)
			(xy 65.546368 -392.159126) (xy 65.587559 -392.123435) (xy 65.633409 -392.093969) (xy 65.682986 -392.071327)
			(xy 65.735281 -392.055972) (xy 65.789229 -392.048216) (xy 65.843731 -392.048216) (xy 65.897679 -392.055972)
			(xy 65.949974 -392.071327) (xy 65.999551 -392.093969) (xy 66.045401 -392.123435) (xy 66.086592 -392.159126)
			(xy 66.122283 -392.200317) (xy 66.151749 -392.246167) (xy 66.174391 -392.295744) (xy 66.189746 -392.348039)
			(xy 66.197502 -392.401987) (xy 66.197988 -392.429238) (xy 66.197988 -393.292838) (xy 79.962756 -393.292838)
			(xy 79.962756 -392.429238) (xy 79.963242 -392.401987) (xy 79.970998 -392.348039) (xy 79.986353 -392.295744)
			(xy 80.008995 -392.246167) (xy 80.038461 -392.200317) (xy 80.074152 -392.159126) (xy 80.115343 -392.123435)
			(xy 80.161193 -392.093969) (xy 80.21077 -392.071327) (xy 80.263065 -392.055972) (xy 80.317013 -392.048216)
			(xy 80.371515 -392.048216) (xy 80.425463 -392.055972) (xy 80.477758 -392.071327) (xy 80.527335 -392.093969)
			(xy 80.573185 -392.123435) (xy 80.614376 -392.159126) (xy 80.650067 -392.200317) (xy 80.679533 -392.246167)
			(xy 80.702175 -392.295744) (xy 80.71753 -392.348039) (xy 80.725286 -392.401987) (xy 80.725772 -392.429238)
			(xy 80.725772 -393.292838) (xy 81.162652 -393.292838) (xy 81.162652 -392.429238) (xy 81.163138 -392.401987)
			(xy 81.170894 -392.348039) (xy 81.186249 -392.295744) (xy 81.208891 -392.246167) (xy 81.238357 -392.200317)
			(xy 81.274048 -392.159126) (xy 81.315239 -392.123435) (xy 81.361089 -392.093969) (xy 81.410666 -392.071327)
			(xy 81.462961 -392.055972) (xy 81.516909 -392.048216) (xy 81.571411 -392.048216) (xy 81.625359 -392.055972)
			(xy 81.677654 -392.071327) (xy 81.727231 -392.093969) (xy 81.773081 -392.123435) (xy 81.814272 -392.159126)
			(xy 81.849963 -392.200317) (xy 81.879429 -392.246167) (xy 81.902071 -392.295744) (xy 81.917426 -392.348039)
			(xy 81.925182 -392.401987) (xy 81.925668 -392.429238) (xy 81.925668 -393.292838) (xy 82.362548 -393.292838)
			(xy 82.362548 -392.429238) (xy 82.363034 -392.401969) (xy 82.370796 -392.347985) (xy 82.386161 -392.295655)
			(xy 82.408818 -392.246045) (xy 82.438304 -392.200164) (xy 82.474019 -392.158947) (xy 82.515236 -392.123232)
			(xy 82.561117 -392.093746) (xy 82.610727 -392.071089) (xy 82.663057 -392.055724) (xy 82.717041 -392.047962)
			(xy 82.771579 -392.047962) (xy 82.825563 -392.055724) (xy 82.877893 -392.071089) (xy 82.927503 -392.093746)
			(xy 82.973384 -392.123232) (xy 83.014601 -392.158947) (xy 83.050316 -392.200164) (xy 83.079802 -392.246045)
			(xy 83.102459 -392.295655) (xy 83.117824 -392.347985) (xy 83.125586 -392.401969) (xy 83.126072 -392.429238)
			(xy 83.126072 -393.292838) (xy 83.562444 -393.292838) (xy 83.562444 -392.429238) (xy 83.56293 -392.401969)
			(xy 83.570692 -392.347985) (xy 83.586057 -392.295655) (xy 83.608714 -392.246045) (xy 83.6382 -392.200164)
			(xy 83.673915 -392.158947) (xy 83.715132 -392.123232) (xy 83.761013 -392.093746) (xy 83.810623 -392.071089)
			(xy 83.862953 -392.055724) (xy 83.916937 -392.047962) (xy 83.971475 -392.047962) (xy 84.025459 -392.055724)
			(xy 84.077789 -392.071089) (xy 84.127399 -392.093746) (xy 84.17328 -392.123232) (xy 84.214497 -392.158947)
			(xy 84.250212 -392.200164) (xy 84.279698 -392.246045) (xy 84.302355 -392.295655) (xy 84.31772 -392.347985)
			(xy 84.325482 -392.401969) (xy 84.325968 -392.429238) (xy 84.325968 -393.292838) (xy 84.762848 -393.292838)
			(xy 84.762848 -392.429238) (xy 84.763334 -392.401987) (xy 84.77109 -392.348039) (xy 84.786445 -392.295744)
			(xy 84.809087 -392.246167) (xy 84.838553 -392.200317) (xy 84.874244 -392.159126) (xy 84.915435 -392.123435)
			(xy 84.961285 -392.093969) (xy 85.010862 -392.071327) (xy 85.063157 -392.055972) (xy 85.117105 -392.048216)
			(xy 85.171607 -392.048216) (xy 85.225555 -392.055972) (xy 85.27785 -392.071327) (xy 85.327427 -392.093969)
			(xy 85.373277 -392.123435) (xy 85.414468 -392.159126) (xy 85.450159 -392.200317) (xy 85.479625 -392.246167)
			(xy 85.502267 -392.295744) (xy 85.517622 -392.348039) (xy 85.525378 -392.401987) (xy 85.525864 -392.429238)
			(xy 85.525864 -393.292838) (xy 85.962744 -393.292838) (xy 85.962744 -392.429238) (xy 85.96323 -392.401987)
			(xy 85.970986 -392.348039) (xy 85.986341 -392.295744) (xy 86.008983 -392.246167) (xy 86.038449 -392.200317)
			(xy 86.07414 -392.159126) (xy 86.115331 -392.123435) (xy 86.161181 -392.093969) (xy 86.210758 -392.071327)
			(xy 86.263053 -392.055972) (xy 86.317001 -392.048216) (xy 86.371503 -392.048216) (xy 86.425451 -392.055972)
			(xy 86.477746 -392.071327) (xy 86.527323 -392.093969) (xy 86.573173 -392.123435) (xy 86.614364 -392.159126)
			(xy 86.650055 -392.200317) (xy 86.679521 -392.246167) (xy 86.702163 -392.295744) (xy 86.717518 -392.348039)
			(xy 86.725274 -392.401987) (xy 86.72576 -392.429238) (xy 86.72576 -393.292838) (xy 87.16264 -393.292838)
			(xy 87.16264 -392.429238) (xy 87.163126 -392.401969) (xy 87.170888 -392.347985) (xy 87.186253 -392.295655)
			(xy 87.20891 -392.246045) (xy 87.238396 -392.200164) (xy 87.274111 -392.158947) (xy 87.315328 -392.123232)
			(xy 87.361209 -392.093746) (xy 87.410819 -392.071089) (xy 87.463149 -392.055724) (xy 87.517133 -392.047962)
			(xy 87.571671 -392.047962) (xy 87.625655 -392.055724) (xy 87.677985 -392.071089) (xy 87.727595 -392.093746)
			(xy 87.773476 -392.123232) (xy 87.814693 -392.158947) (xy 87.850408 -392.200164) (xy 87.879894 -392.246045)
			(xy 87.902551 -392.295655) (xy 87.917916 -392.347985) (xy 87.925678 -392.401969) (xy 87.926164 -392.429238)
			(xy 87.926164 -393.292838) (xy 88.362536 -393.292838) (xy 88.362536 -392.429238) (xy 88.363022 -392.401969)
			(xy 88.370784 -392.347985) (xy 88.386149 -392.295655) (xy 88.408806 -392.246045) (xy 88.438292 -392.200164)
			(xy 88.474007 -392.158947) (xy 88.515224 -392.123232) (xy 88.561105 -392.093746) (xy 88.610715 -392.071089)
			(xy 88.663045 -392.055724) (xy 88.717029 -392.047962) (xy 88.771567 -392.047962) (xy 88.825551 -392.055724)
			(xy 88.877881 -392.071089) (xy 88.927491 -392.093746) (xy 88.973372 -392.123232) (xy 89.014589 -392.158947)
			(xy 89.050304 -392.200164) (xy 89.07979 -392.246045) (xy 89.102447 -392.295655) (xy 89.117812 -392.347985)
			(xy 89.125574 -392.401969) (xy 89.12606 -392.429238) (xy 89.12606 -393.292838) (xy 89.56294 -393.292838)
			(xy 89.56294 -392.429238) (xy 89.563426 -392.401987) (xy 89.571182 -392.348039) (xy 89.586537 -392.295744)
			(xy 89.609179 -392.246167) (xy 89.638645 -392.200317) (xy 89.674336 -392.159126) (xy 89.715527 -392.123435)
			(xy 89.761377 -392.093969) (xy 89.810954 -392.071327) (xy 89.863249 -392.055972) (xy 89.917197 -392.048216)
			(xy 89.971699 -392.048216) (xy 90.025647 -392.055972) (xy 90.077942 -392.071327) (xy 90.127519 -392.093969)
			(xy 90.173369 -392.123435) (xy 90.21456 -392.159126) (xy 90.250251 -392.200317) (xy 90.279717 -392.246167)
			(xy 90.302359 -392.295744) (xy 90.317714 -392.348039) (xy 90.32547 -392.401987) (xy 90.325956 -392.429238)
			(xy 90.325956 -393.292838) (xy 90.762836 -393.292838) (xy 90.762836 -392.429238) (xy 90.763322 -392.401987)
			(xy 90.771078 -392.348039) (xy 90.786433 -392.295744) (xy 90.809075 -392.246167) (xy 90.838541 -392.200317)
			(xy 90.874232 -392.159126) (xy 90.915423 -392.123435) (xy 90.961273 -392.093969) (xy 91.01085 -392.071327)
			(xy 91.063145 -392.055972) (xy 91.117093 -392.048216) (xy 91.171595 -392.048216) (xy 91.225543 -392.055972)
			(xy 91.277838 -392.071327) (xy 91.327415 -392.093969) (xy 91.373265 -392.123435) (xy 91.414456 -392.159126)
			(xy 91.450147 -392.200317) (xy 91.479613 -392.246167) (xy 91.502255 -392.295744) (xy 91.51761 -392.348039)
			(xy 91.525366 -392.401987) (xy 91.525852 -392.429238) (xy 91.525852 -393.292838) (xy 91.962732 -393.292838)
			(xy 91.962732 -392.429238) (xy 91.963218 -392.401969) (xy 91.97098 -392.347985) (xy 91.986345 -392.295655)
			(xy 92.009002 -392.246045) (xy 92.038488 -392.200164) (xy 92.074203 -392.158947) (xy 92.11542 -392.123232)
			(xy 92.161301 -392.093746) (xy 92.210911 -392.071089) (xy 92.263241 -392.055724) (xy 92.317225 -392.047962)
			(xy 92.371763 -392.047962) (xy 92.425747 -392.055724) (xy 92.478077 -392.071089) (xy 92.527687 -392.093746)
			(xy 92.573568 -392.123232) (xy 92.614785 -392.158947) (xy 92.6505 -392.200164) (xy 92.679986 -392.246045)
			(xy 92.702643 -392.295655) (xy 92.718008 -392.347985) (xy 92.72577 -392.401969) (xy 92.726256 -392.429238)
			(xy 92.726256 -393.292838) (xy 93.162628 -393.292838) (xy 93.162628 -392.429238) (xy 93.163114 -392.401969)
			(xy 93.170876 -392.347985) (xy 93.186241 -392.295655) (xy 93.208898 -392.246045) (xy 93.238384 -392.200164)
			(xy 93.274099 -392.158947) (xy 93.315316 -392.123232) (xy 93.361197 -392.093746) (xy 93.410807 -392.071089)
			(xy 93.463137 -392.055724) (xy 93.517121 -392.047962) (xy 93.571659 -392.047962) (xy 93.625643 -392.055724)
			(xy 93.677973 -392.071089) (xy 93.727583 -392.093746) (xy 93.773464 -392.123232) (xy 93.814681 -392.158947)
			(xy 93.850396 -392.200164) (xy 93.879882 -392.246045) (xy 93.902539 -392.295655) (xy 93.917904 -392.347985)
			(xy 93.925666 -392.401969) (xy 93.926152 -392.429238) (xy 93.926152 -393.292838) (xy 94.362524 -393.292838)
			(xy 94.362524 -392.429238) (xy 94.36301 -392.401969) (xy 94.370772 -392.347985) (xy 94.386137 -392.295655)
			(xy 94.408794 -392.246045) (xy 94.43828 -392.200164) (xy 94.473995 -392.158947) (xy 94.515212 -392.123232)
			(xy 94.561093 -392.093746) (xy 94.610703 -392.071089) (xy 94.663033 -392.055724) (xy 94.717017 -392.047962)
			(xy 94.771555 -392.047962) (xy 94.825539 -392.055724) (xy 94.877869 -392.071089) (xy 94.927479 -392.093746)
			(xy 94.97336 -392.123232) (xy 95.014577 -392.158947) (xy 95.050292 -392.200164) (xy 95.079778 -392.246045)
			(xy 95.102435 -392.295655) (xy 95.1178 -392.347985) (xy 95.125562 -392.401969) (xy 95.126048 -392.429238)
			(xy 95.126048 -393.292838) (xy 95.56242 -393.292838) (xy 95.56242 -392.429238) (xy 95.562906 -392.401969)
			(xy 95.570668 -392.347985) (xy 95.586033 -392.295655) (xy 95.60869 -392.246045) (xy 95.638176 -392.200164)
			(xy 95.673891 -392.158947) (xy 95.715108 -392.123232) (xy 95.760989 -392.093746) (xy 95.810599 -392.071089)
			(xy 95.862929 -392.055724) (xy 95.916913 -392.047962) (xy 95.971451 -392.047962) (xy 96.025435 -392.055724)
			(xy 96.077765 -392.071089) (xy 96.127375 -392.093746) (xy 96.173256 -392.123232) (xy 96.214473 -392.158947)
			(xy 96.250188 -392.200164) (xy 96.279674 -392.246045) (xy 96.302331 -392.295655) (xy 96.317696 -392.347985)
			(xy 96.325458 -392.401969) (xy 96.325944 -392.429238) (xy 96.325944 -393.292838) (xy 96.762824 -393.292838)
			(xy 96.762824 -392.429238) (xy 96.76331 -392.401987) (xy 96.771066 -392.348039) (xy 96.786421 -392.295744)
			(xy 96.809063 -392.246167) (xy 96.838529 -392.200317) (xy 96.87422 -392.159126) (xy 96.915411 -392.123435)
			(xy 96.961261 -392.093969) (xy 97.010838 -392.071327) (xy 97.063133 -392.055972) (xy 97.117081 -392.048216)
			(xy 97.171583 -392.048216) (xy 97.225531 -392.055972) (xy 97.277826 -392.071327) (xy 97.327403 -392.093969)
			(xy 97.373253 -392.123435) (xy 97.414444 -392.159126) (xy 97.450135 -392.200317) (xy 97.479601 -392.246167)
			(xy 97.502243 -392.295744) (xy 97.517598 -392.348039) (xy 97.525354 -392.401987) (xy 97.52584 -392.429238)
			(xy 97.52584 -393.292838) (xy 97.96272 -393.292838) (xy 97.96272 -392.429238) (xy 97.963206 -392.401987)
			(xy 97.970962 -392.348039) (xy 97.986317 -392.295744) (xy 98.008959 -392.246167) (xy 98.038425 -392.200317)
			(xy 98.074116 -392.159126) (xy 98.115307 -392.123435) (xy 98.161157 -392.093969) (xy 98.210734 -392.071327)
			(xy 98.263029 -392.055972) (xy 98.316977 -392.048216) (xy 98.371479 -392.048216) (xy 98.425427 -392.055972)
			(xy 98.477722 -392.071327) (xy 98.527299 -392.093969) (xy 98.573149 -392.123435) (xy 98.61434 -392.159126)
			(xy 98.650031 -392.200317) (xy 98.679497 -392.246167) (xy 98.702139 -392.295744) (xy 98.717494 -392.348039)
			(xy 98.72525 -392.401987) (xy 98.725736 -392.429238) (xy 98.725736 -393.292838) (xy 114.534696 -393.292838)
			(xy 114.534696 -392.429238) (xy 114.535182 -392.401969) (xy 114.542944 -392.347985) (xy 114.558309 -392.295655)
			(xy 114.580966 -392.246045) (xy 114.610452 -392.200164) (xy 114.646167 -392.158947) (xy 114.687384 -392.123232)
			(xy 114.733265 -392.093746) (xy 114.782875 -392.071089) (xy 114.835205 -392.055724) (xy 114.889189 -392.047962)
			(xy 114.943727 -392.047962) (xy 114.997711 -392.055724) (xy 115.050041 -392.071089) (xy 115.099651 -392.093746)
			(xy 115.145532 -392.123232) (xy 115.186749 -392.158947) (xy 115.222464 -392.200164) (xy 115.25195 -392.246045)
			(xy 115.274607 -392.295655) (xy 115.289972 -392.347985) (xy 115.297734 -392.401969) (xy 115.29822 -392.429238)
			(xy 115.29822 -393.292838) (xy 115.734592 -393.292838) (xy 115.734592 -392.429238) (xy 115.735078 -392.401969)
			(xy 115.74284 -392.347985) (xy 115.758205 -392.295655) (xy 115.780862 -392.246045) (xy 115.810348 -392.200164)
			(xy 115.846063 -392.158947) (xy 115.88728 -392.123232) (xy 115.933161 -392.093746) (xy 115.982771 -392.071089)
			(xy 116.035101 -392.055724) (xy 116.089085 -392.047962) (xy 116.143623 -392.047962) (xy 116.197607 -392.055724)
			(xy 116.249937 -392.071089) (xy 116.299547 -392.093746) (xy 116.345428 -392.123232) (xy 116.386645 -392.158947)
			(xy 116.42236 -392.200164) (xy 116.451846 -392.246045) (xy 116.474503 -392.295655) (xy 116.489868 -392.347985)
			(xy 116.49763 -392.401969) (xy 116.498116 -392.429238) (xy 116.498116 -393.292838) (xy 116.934996 -393.292838)
			(xy 116.934996 -392.429238) (xy 116.935482 -392.401987) (xy 116.943238 -392.348039) (xy 116.958593 -392.295744)
			(xy 116.981235 -392.246167) (xy 117.010701 -392.200317) (xy 117.046392 -392.159126) (xy 117.087583 -392.123435)
			(xy 117.133433 -392.093969) (xy 117.18301 -392.071327) (xy 117.235305 -392.055972) (xy 117.289253 -392.048216)
			(xy 117.343755 -392.048216) (xy 117.397703 -392.055972) (xy 117.449998 -392.071327) (xy 117.499575 -392.093969)
			(xy 117.545425 -392.123435) (xy 117.586616 -392.159126) (xy 117.622307 -392.200317) (xy 117.651773 -392.246167)
			(xy 117.674415 -392.295744) (xy 117.68977 -392.348039) (xy 117.697526 -392.401987) (xy 117.698012 -392.429238)
			(xy 117.698012 -393.292838) (xy 118.134892 -393.292838) (xy 118.134892 -392.429238) (xy 118.135378 -392.401987)
			(xy 118.143134 -392.348039) (xy 118.158489 -392.295744) (xy 118.181131 -392.246167) (xy 118.210597 -392.200317)
			(xy 118.246288 -392.159126) (xy 118.287479 -392.123435) (xy 118.333329 -392.093969) (xy 118.382906 -392.071327)
			(xy 118.435201 -392.055972) (xy 118.489149 -392.048216) (xy 118.543651 -392.048216) (xy 118.597599 -392.055972)
			(xy 118.649894 -392.071327) (xy 118.699471 -392.093969) (xy 118.745321 -392.123435) (xy 118.786512 -392.159126)
			(xy 118.822203 -392.200317) (xy 118.851669 -392.246167) (xy 118.874311 -392.295744) (xy 118.889666 -392.348039)
			(xy 118.897422 -392.401987) (xy 118.897908 -392.429238) (xy 118.897908 -393.292838) (xy 119.334788 -393.292838)
			(xy 119.334788 -392.429238) (xy 119.335274 -392.401969) (xy 119.343036 -392.347985) (xy 119.358401 -392.295655)
			(xy 119.381058 -392.246045) (xy 119.410544 -392.200164) (xy 119.446259 -392.158947) (xy 119.487476 -392.123232)
			(xy 119.533357 -392.093746) (xy 119.582967 -392.071089) (xy 119.635297 -392.055724) (xy 119.689281 -392.047962)
			(xy 119.743819 -392.047962) (xy 119.797803 -392.055724) (xy 119.850133 -392.071089) (xy 119.899743 -392.093746)
			(xy 119.945624 -392.123232) (xy 119.986841 -392.158947) (xy 120.022556 -392.200164) (xy 120.052042 -392.246045)
			(xy 120.074699 -392.295655) (xy 120.090064 -392.347985) (xy 120.097826 -392.401969) (xy 120.098312 -392.429238)
			(xy 120.098312 -393.292838) (xy 120.534684 -393.292838) (xy 120.534684 -392.429238) (xy 120.53517 -392.401969)
			(xy 120.542932 -392.347985) (xy 120.558297 -392.295655) (xy 120.580954 -392.246045) (xy 120.61044 -392.200164)
			(xy 120.646155 -392.158947) (xy 120.687372 -392.123232) (xy 120.733253 -392.093746) (xy 120.782863 -392.071089)
			(xy 120.835193 -392.055724) (xy 120.889177 -392.047962) (xy 120.943715 -392.047962) (xy 120.997699 -392.055724)
			(xy 121.050029 -392.071089) (xy 121.099639 -392.093746) (xy 121.14552 -392.123232) (xy 121.186737 -392.158947)
			(xy 121.222452 -392.200164) (xy 121.251938 -392.246045) (xy 121.274595 -392.295655) (xy 121.28996 -392.347985)
			(xy 121.297722 -392.401969) (xy 121.298208 -392.429238) (xy 121.298208 -393.292838) (xy 121.735088 -393.292838)
			(xy 121.735088 -392.429238) (xy 121.735574 -392.401987) (xy 121.74333 -392.348039) (xy 121.758685 -392.295744)
			(xy 121.781327 -392.246167) (xy 121.810793 -392.200317) (xy 121.846484 -392.159126) (xy 121.887675 -392.123435)
			(xy 121.933525 -392.093969) (xy 121.983102 -392.071327) (xy 122.035397 -392.055972) (xy 122.089345 -392.048216)
			(xy 122.143847 -392.048216) (xy 122.197795 -392.055972) (xy 122.25009 -392.071327) (xy 122.299667 -392.093969)
			(xy 122.345517 -392.123435) (xy 122.386708 -392.159126) (xy 122.422399 -392.200317) (xy 122.451865 -392.246167)
			(xy 122.474507 -392.295744) (xy 122.489862 -392.348039) (xy 122.497618 -392.401987) (xy 122.498104 -392.429238)
			(xy 122.498104 -393.292838) (xy 122.934984 -393.292838) (xy 122.934984 -392.429238) (xy 122.93547 -392.401987)
			(xy 122.943226 -392.348039) (xy 122.958581 -392.295744) (xy 122.981223 -392.246167) (xy 123.010689 -392.200317)
			(xy 123.04638 -392.159126) (xy 123.087571 -392.123435) (xy 123.133421 -392.093969) (xy 123.182998 -392.071327)
			(xy 123.235293 -392.055972) (xy 123.289241 -392.048216) (xy 123.343743 -392.048216) (xy 123.397691 -392.055972)
			(xy 123.449986 -392.071327) (xy 123.499563 -392.093969) (xy 123.545413 -392.123435) (xy 123.586604 -392.159126)
			(xy 123.622295 -392.200317) (xy 123.651761 -392.246167) (xy 123.674403 -392.295744) (xy 123.689758 -392.348039)
			(xy 123.697514 -392.401987) (xy 123.698 -392.429238) (xy 123.698 -393.292838) (xy 124.13488 -393.292838)
			(xy 124.13488 -392.429238) (xy 124.135366 -392.401969) (xy 124.143128 -392.347985) (xy 124.158493 -392.295655)
			(xy 124.18115 -392.246045) (xy 124.210636 -392.200164) (xy 124.246351 -392.158947) (xy 124.287568 -392.123232)
			(xy 124.333449 -392.093746) (xy 124.383059 -392.071089) (xy 124.435389 -392.055724) (xy 124.489373 -392.047962)
			(xy 124.543911 -392.047962) (xy 124.597895 -392.055724) (xy 124.650225 -392.071089) (xy 124.699835 -392.093746)
			(xy 124.745716 -392.123232) (xy 124.786933 -392.158947) (xy 124.822648 -392.200164) (xy 124.852134 -392.246045)
			(xy 124.874791 -392.295655) (xy 124.890156 -392.347985) (xy 124.897918 -392.401969) (xy 124.898404 -392.429238)
			(xy 124.898404 -393.292838) (xy 125.334776 -393.292838) (xy 125.334776 -392.429238) (xy 125.335262 -392.401969)
			(xy 125.343024 -392.347985) (xy 125.358389 -392.295655) (xy 125.381046 -392.246045) (xy 125.410532 -392.200164)
			(xy 125.446247 -392.158947) (xy 125.487464 -392.123232) (xy 125.533345 -392.093746) (xy 125.582955 -392.071089)
			(xy 125.635285 -392.055724) (xy 125.689269 -392.047962) (xy 125.743807 -392.047962) (xy 125.797791 -392.055724)
			(xy 125.850121 -392.071089) (xy 125.899731 -392.093746) (xy 125.945612 -392.123232) (xy 125.986829 -392.158947)
			(xy 126.022544 -392.200164) (xy 126.05203 -392.246045) (xy 126.074687 -392.295655) (xy 126.090052 -392.347985)
			(xy 126.097814 -392.401969) (xy 126.0983 -392.429238) (xy 126.0983 -393.292838) (xy 126.53518 -393.292838)
			(xy 126.53518 -392.429238) (xy 126.535666 -392.401987) (xy 126.543422 -392.348039) (xy 126.558777 -392.295744)
			(xy 126.581419 -392.246167) (xy 126.610885 -392.200317) (xy 126.646576 -392.159126) (xy 126.687767 -392.123435)
			(xy 126.733617 -392.093969) (xy 126.783194 -392.071327) (xy 126.835489 -392.055972) (xy 126.889437 -392.048216)
			(xy 126.943939 -392.048216) (xy 126.997887 -392.055972) (xy 127.050182 -392.071327) (xy 127.099759 -392.093969)
			(xy 127.145609 -392.123435) (xy 127.1868 -392.159126) (xy 127.222491 -392.200317) (xy 127.251957 -392.246167)
			(xy 127.274599 -392.295744) (xy 127.289954 -392.348039) (xy 127.29771 -392.401987) (xy 127.298196 -392.429238)
			(xy 127.298196 -393.292838) (xy 127.735076 -393.292838) (xy 127.735076 -392.429238) (xy 127.735562 -392.401987)
			(xy 127.743318 -392.348039) (xy 127.758673 -392.295744) (xy 127.781315 -392.246167) (xy 127.810781 -392.200317)
			(xy 127.846472 -392.159126) (xy 127.887663 -392.123435) (xy 127.933513 -392.093969) (xy 127.98309 -392.071327)
			(xy 128.035385 -392.055972) (xy 128.089333 -392.048216) (xy 128.143835 -392.048216) (xy 128.197783 -392.055972)
			(xy 128.250078 -392.071327) (xy 128.299655 -392.093969) (xy 128.345505 -392.123435) (xy 128.386696 -392.159126)
			(xy 128.422387 -392.200317) (xy 128.451853 -392.246167) (xy 128.474495 -392.295744) (xy 128.48985 -392.348039)
			(xy 128.497606 -392.401987) (xy 128.498092 -392.429238) (xy 128.498092 -393.292838) (xy 128.934972 -393.292838)
			(xy 128.934972 -392.429238) (xy 128.935458 -392.401987) (xy 128.943214 -392.348039) (xy 128.958569 -392.295744)
			(xy 128.981211 -392.246167) (xy 129.010677 -392.200317) (xy 129.046368 -392.159126) (xy 129.087559 -392.123435)
			(xy 129.133409 -392.093969) (xy 129.182986 -392.071327) (xy 129.235281 -392.055972) (xy 129.289229 -392.048216)
			(xy 129.343731 -392.048216) (xy 129.397679 -392.055972) (xy 129.449974 -392.071327) (xy 129.499551 -392.093969)
			(xy 129.545401 -392.123435) (xy 129.586592 -392.159126) (xy 129.622283 -392.200317) (xy 129.651749 -392.246167)
			(xy 129.674391 -392.295744) (xy 129.689746 -392.348039) (xy 129.697502 -392.401987) (xy 129.697988 -392.429238)
			(xy 129.697988 -393.292838) (xy 130.134868 -393.292838) (xy 130.134868 -392.429238) (xy 130.135354 -392.401987)
			(xy 130.14311 -392.348039) (xy 130.158465 -392.295744) (xy 130.181107 -392.246167) (xy 130.210573 -392.200317)
			(xy 130.246264 -392.159126) (xy 130.287455 -392.123435) (xy 130.333305 -392.093969) (xy 130.382882 -392.071327)
			(xy 130.435177 -392.055972) (xy 130.489125 -392.048216) (xy 130.543627 -392.048216) (xy 130.597575 -392.055972)
			(xy 130.64987 -392.071327) (xy 130.699447 -392.093969) (xy 130.745297 -392.123435) (xy 130.786488 -392.159126)
			(xy 130.822179 -392.200317) (xy 130.851645 -392.246167) (xy 130.874287 -392.295744) (xy 130.889642 -392.348039)
			(xy 130.897398 -392.401987) (xy 130.897884 -392.429238) (xy 130.897884 -393.292838) (xy 131.334764 -393.292838)
			(xy 131.334764 -392.429238) (xy 131.33525 -392.401969) (xy 131.343012 -392.347985) (xy 131.358377 -392.295655)
			(xy 131.381034 -392.246045) (xy 131.41052 -392.200164) (xy 131.446235 -392.158947) (xy 131.487452 -392.123232)
			(xy 131.533333 -392.093746) (xy 131.582943 -392.071089) (xy 131.635273 -392.055724) (xy 131.689257 -392.047962)
			(xy 131.743795 -392.047962) (xy 131.797779 -392.055724) (xy 131.850109 -392.071089) (xy 131.899719 -392.093746)
			(xy 131.9456 -392.123232) (xy 131.986817 -392.158947) (xy 132.022532 -392.200164) (xy 132.052018 -392.246045)
			(xy 132.074675 -392.295655) (xy 132.09004 -392.347985) (xy 132.097802 -392.401969) (xy 132.098288 -392.429238)
			(xy 132.098288 -393.292838) (xy 132.53466 -393.292838) (xy 132.53466 -392.429238) (xy 132.535146 -392.401969)
			(xy 132.542908 -392.347985) (xy 132.558273 -392.295655) (xy 132.58093 -392.246045) (xy 132.610416 -392.200164)
			(xy 132.646131 -392.158947) (xy 132.687348 -392.123232) (xy 132.733229 -392.093746) (xy 132.782839 -392.071089)
			(xy 132.835169 -392.055724) (xy 132.889153 -392.047962) (xy 132.943691 -392.047962) (xy 132.997675 -392.055724)
			(xy 133.050005 -392.071089) (xy 133.099615 -392.093746) (xy 133.145496 -392.123232) (xy 133.186713 -392.158947)
			(xy 133.222428 -392.200164) (xy 133.251914 -392.246045) (xy 133.274571 -392.295655) (xy 133.289936 -392.347985)
			(xy 133.297698 -392.401969) (xy 133.298184 -392.429238) (xy 133.298184 -393.292838) (xy 147.062444 -393.292838)
			(xy 147.062444 -392.429238) (xy 147.06293 -392.401969) (xy 147.070692 -392.347985) (xy 147.086057 -392.295655)
			(xy 147.108714 -392.246045) (xy 147.1382 -392.200164) (xy 147.173915 -392.158947) (xy 147.215132 -392.123232)
			(xy 147.261013 -392.093746) (xy 147.310623 -392.071089) (xy 147.362953 -392.055724) (xy 147.416937 -392.047962)
			(xy 147.471475 -392.047962) (xy 147.525459 -392.055724) (xy 147.577789 -392.071089) (xy 147.627399 -392.093746)
			(xy 147.67328 -392.123232) (xy 147.714497 -392.158947) (xy 147.750212 -392.200164) (xy 147.779698 -392.246045)
			(xy 147.802355 -392.295655) (xy 147.81772 -392.347985) (xy 147.825482 -392.401969) (xy 147.825968 -392.429238)
			(xy 147.825968 -393.292838) (xy 148.26234 -393.292838) (xy 148.26234 -392.429238) (xy 148.262826 -392.401969)
			(xy 148.270588 -392.347985) (xy 148.285953 -392.295655) (xy 148.30861 -392.246045) (xy 148.338096 -392.200164)
			(xy 148.373811 -392.158947) (xy 148.415028 -392.123232) (xy 148.460909 -392.093746) (xy 148.510519 -392.071089)
			(xy 148.562849 -392.055724) (xy 148.616833 -392.047962) (xy 148.671371 -392.047962) (xy 148.725355 -392.055724)
			(xy 148.777685 -392.071089) (xy 148.827295 -392.093746) (xy 148.873176 -392.123232) (xy 148.914393 -392.158947)
			(xy 148.950108 -392.200164) (xy 148.979594 -392.246045) (xy 149.002251 -392.295655) (xy 149.017616 -392.347985)
			(xy 149.025378 -392.401969) (xy 149.025864 -392.429238) (xy 149.025864 -393.292838) (xy 149.462744 -393.292838)
			(xy 149.462744 -392.429238) (xy 149.46323 -392.401987) (xy 149.470986 -392.348039) (xy 149.486341 -392.295744)
			(xy 149.508983 -392.246167) (xy 149.538449 -392.200317) (xy 149.57414 -392.159126) (xy 149.615331 -392.123435)
			(xy 149.661181 -392.093969) (xy 149.710758 -392.071327) (xy 149.763053 -392.055972) (xy 149.817001 -392.048216)
			(xy 149.871503 -392.048216) (xy 149.925451 -392.055972) (xy 149.977746 -392.071327) (xy 150.027323 -392.093969)
			(xy 150.073173 -392.123435) (xy 150.114364 -392.159126) (xy 150.150055 -392.200317) (xy 150.179521 -392.246167)
			(xy 150.202163 -392.295744) (xy 150.217518 -392.348039) (xy 150.225274 -392.401987) (xy 150.22576 -392.429238)
			(xy 150.22576 -393.292838) (xy 150.66264 -393.292838) (xy 150.66264 -392.429238) (xy 150.663126 -392.401987)
			(xy 150.670882 -392.348039) (xy 150.686237 -392.295744) (xy 150.708879 -392.246167) (xy 150.738345 -392.200317)
			(xy 150.774036 -392.159126) (xy 150.815227 -392.123435) (xy 150.861077 -392.093969) (xy 150.910654 -392.071327)
			(xy 150.962949 -392.055972) (xy 151.016897 -392.048216) (xy 151.071399 -392.048216) (xy 151.125347 -392.055972)
			(xy 151.177642 -392.071327) (xy 151.227219 -392.093969) (xy 151.273069 -392.123435) (xy 151.31426 -392.159126)
			(xy 151.349951 -392.200317) (xy 151.379417 -392.246167) (xy 151.402059 -392.295744) (xy 151.417414 -392.348039)
			(xy 151.42517 -392.401987) (xy 151.425656 -392.429238) (xy 151.425656 -393.292838) (xy 151.862536 -393.292838)
			(xy 151.862536 -392.429238) (xy 151.863022 -392.401969) (xy 151.870784 -392.347985) (xy 151.886149 -392.295655)
			(xy 151.908806 -392.246045) (xy 151.938292 -392.200164) (xy 151.974007 -392.158947) (xy 152.015224 -392.123232)
			(xy 152.061105 -392.093746) (xy 152.110715 -392.071089) (xy 152.163045 -392.055724) (xy 152.217029 -392.047962)
			(xy 152.271567 -392.047962) (xy 152.325551 -392.055724) (xy 152.377881 -392.071089) (xy 152.427491 -392.093746)
			(xy 152.473372 -392.123232) (xy 152.514589 -392.158947) (xy 152.550304 -392.200164) (xy 152.57979 -392.246045)
			(xy 152.602447 -392.295655) (xy 152.617812 -392.347985) (xy 152.625574 -392.401969) (xy 152.62606 -392.429238)
			(xy 152.62606 -393.292838) (xy 153.062432 -393.292838) (xy 153.062432 -392.429238) (xy 153.062918 -392.401969)
			(xy 153.07068 -392.347985) (xy 153.086045 -392.295655) (xy 153.108702 -392.246045) (xy 153.138188 -392.200164)
			(xy 153.173903 -392.158947) (xy 153.21512 -392.123232) (xy 153.261001 -392.093746) (xy 153.310611 -392.071089)
			(xy 153.362941 -392.055724) (xy 153.416925 -392.047962) (xy 153.471463 -392.047962) (xy 153.525447 -392.055724)
			(xy 153.577777 -392.071089) (xy 153.627387 -392.093746) (xy 153.673268 -392.123232) (xy 153.714485 -392.158947)
			(xy 153.7502 -392.200164) (xy 153.779686 -392.246045) (xy 153.802343 -392.295655) (xy 153.817708 -392.347985)
			(xy 153.82547 -392.401969) (xy 153.825956 -392.429238) (xy 153.825956 -393.292838) (xy 154.262836 -393.292838)
			(xy 154.262836 -392.429238) (xy 154.263322 -392.401987) (xy 154.271078 -392.348039) (xy 154.286433 -392.295744)
			(xy 154.309075 -392.246167) (xy 154.338541 -392.200317) (xy 154.374232 -392.159126) (xy 154.415423 -392.123435)
			(xy 154.461273 -392.093969) (xy 154.51085 -392.071327) (xy 154.563145 -392.055972) (xy 154.617093 -392.048216)
			(xy 154.671595 -392.048216) (xy 154.725543 -392.055972) (xy 154.777838 -392.071327) (xy 154.827415 -392.093969)
			(xy 154.873265 -392.123435) (xy 154.914456 -392.159126) (xy 154.950147 -392.200317) (xy 154.979613 -392.246167)
			(xy 155.002255 -392.295744) (xy 155.01761 -392.348039) (xy 155.025366 -392.401987) (xy 155.025852 -392.429238)
			(xy 155.025852 -393.292838) (xy 155.462732 -393.292838) (xy 155.462732 -392.429238) (xy 155.463218 -392.401987)
			(xy 155.470974 -392.348039) (xy 155.486329 -392.295744) (xy 155.508971 -392.246167) (xy 155.538437 -392.200317)
			(xy 155.574128 -392.159126) (xy 155.615319 -392.123435) (xy 155.661169 -392.093969) (xy 155.710746 -392.071327)
			(xy 155.763041 -392.055972) (xy 155.816989 -392.048216) (xy 155.871491 -392.048216) (xy 155.925439 -392.055972)
			(xy 155.977734 -392.071327) (xy 156.027311 -392.093969) (xy 156.073161 -392.123435) (xy 156.114352 -392.159126)
			(xy 156.150043 -392.200317) (xy 156.179509 -392.246167) (xy 156.202151 -392.295744) (xy 156.217506 -392.348039)
			(xy 156.225262 -392.401987) (xy 156.225748 -392.429238) (xy 156.225748 -393.292838) (xy 156.662628 -393.292838)
			(xy 156.662628 -392.429238) (xy 156.663114 -392.401969) (xy 156.670876 -392.347985) (xy 156.686241 -392.295655)
			(xy 156.708898 -392.246045) (xy 156.738384 -392.200164) (xy 156.774099 -392.158947) (xy 156.815316 -392.123232)
			(xy 156.861197 -392.093746) (xy 156.910807 -392.071089) (xy 156.963137 -392.055724) (xy 157.017121 -392.047962)
			(xy 157.071659 -392.047962) (xy 157.125643 -392.055724) (xy 157.177973 -392.071089) (xy 157.227583 -392.093746)
			(xy 157.273464 -392.123232) (xy 157.314681 -392.158947) (xy 157.350396 -392.200164) (xy 157.379882 -392.246045)
			(xy 157.402539 -392.295655) (xy 157.417904 -392.347985) (xy 157.425666 -392.401969) (xy 157.426152 -392.429238)
			(xy 157.426152 -393.292838) (xy 157.862524 -393.292838) (xy 157.862524 -392.429238) (xy 157.86301 -392.401969)
			(xy 157.870772 -392.347985) (xy 157.886137 -392.295655) (xy 157.908794 -392.246045) (xy 157.93828 -392.200164)
			(xy 157.973995 -392.158947) (xy 158.015212 -392.123232) (xy 158.061093 -392.093746) (xy 158.110703 -392.071089)
			(xy 158.163033 -392.055724) (xy 158.217017 -392.047962) (xy 158.271555 -392.047962) (xy 158.325539 -392.055724)
			(xy 158.377869 -392.071089) (xy 158.427479 -392.093746) (xy 158.47336 -392.123232) (xy 158.514577 -392.158947)
			(xy 158.550292 -392.200164) (xy 158.579778 -392.246045) (xy 158.602435 -392.295655) (xy 158.6178 -392.347985)
			(xy 158.625562 -392.401969) (xy 158.626048 -392.429238) (xy 158.626048 -393.292838) (xy 159.062928 -393.292838)
			(xy 159.062928 -392.429238) (xy 159.063414 -392.401987) (xy 159.07117 -392.348039) (xy 159.086525 -392.295744)
			(xy 159.109167 -392.246167) (xy 159.138633 -392.200317) (xy 159.174324 -392.159126) (xy 159.215515 -392.123435)
			(xy 159.261365 -392.093969) (xy 159.310942 -392.071327) (xy 159.363237 -392.055972) (xy 159.417185 -392.048216)
			(xy 159.471687 -392.048216) (xy 159.525635 -392.055972) (xy 159.57793 -392.071327) (xy 159.627507 -392.093969)
			(xy 159.673357 -392.123435) (xy 159.714548 -392.159126) (xy 159.750239 -392.200317) (xy 159.779705 -392.246167)
			(xy 159.802347 -392.295744) (xy 159.817702 -392.348039) (xy 159.825458 -392.401987) (xy 159.825944 -392.429238)
			(xy 159.825944 -393.292838) (xy 160.262824 -393.292838) (xy 160.262824 -392.429238) (xy 160.26331 -392.401987)
			(xy 160.271066 -392.348039) (xy 160.286421 -392.295744) (xy 160.309063 -392.246167) (xy 160.338529 -392.200317)
			(xy 160.37422 -392.159126) (xy 160.415411 -392.123435) (xy 160.461261 -392.093969) (xy 160.510838 -392.071327)
			(xy 160.563133 -392.055972) (xy 160.617081 -392.048216) (xy 160.671583 -392.048216) (xy 160.725531 -392.055972)
			(xy 160.777826 -392.071327) (xy 160.827403 -392.093969) (xy 160.873253 -392.123435) (xy 160.914444 -392.159126)
			(xy 160.950135 -392.200317) (xy 160.979601 -392.246167) (xy 161.002243 -392.295744) (xy 161.017598 -392.348039)
			(xy 161.025354 -392.401987) (xy 161.02584 -392.429238) (xy 161.02584 -393.292838) (xy 161.46272 -393.292838)
			(xy 161.46272 -392.429238) (xy 161.463206 -392.401987) (xy 161.470962 -392.348039) (xy 161.486317 -392.295744)
			(xy 161.508959 -392.246167) (xy 161.538425 -392.200317) (xy 161.574116 -392.159126) (xy 161.615307 -392.123435)
			(xy 161.661157 -392.093969) (xy 161.710734 -392.071327) (xy 161.763029 -392.055972) (xy 161.816977 -392.048216)
			(xy 161.871479 -392.048216) (xy 161.925427 -392.055972) (xy 161.977722 -392.071327) (xy 162.027299 -392.093969)
			(xy 162.073149 -392.123435) (xy 162.11434 -392.159126) (xy 162.150031 -392.200317) (xy 162.179497 -392.246167)
			(xy 162.202139 -392.295744) (xy 162.217494 -392.348039) (xy 162.22525 -392.401987) (xy 162.225736 -392.429238)
			(xy 162.225736 -393.292838) (xy 162.662616 -393.292838) (xy 162.662616 -392.429238) (xy 162.663102 -392.401987)
			(xy 162.670858 -392.348039) (xy 162.686213 -392.295744) (xy 162.708855 -392.246167) (xy 162.738321 -392.200317)
			(xy 162.774012 -392.159126) (xy 162.815203 -392.123435) (xy 162.861053 -392.093969) (xy 162.91063 -392.071327)
			(xy 162.962925 -392.055972) (xy 163.016873 -392.048216) (xy 163.071375 -392.048216) (xy 163.125323 -392.055972)
			(xy 163.177618 -392.071327) (xy 163.227195 -392.093969) (xy 163.273045 -392.123435) (xy 163.314236 -392.159126)
			(xy 163.349927 -392.200317) (xy 163.379393 -392.246167) (xy 163.402035 -392.295744) (xy 163.41739 -392.348039)
			(xy 163.425146 -392.401987) (xy 163.425632 -392.429238) (xy 163.425632 -393.292838) (xy 163.862512 -393.292838)
			(xy 163.862512 -392.429238) (xy 163.862998 -392.401969) (xy 163.87076 -392.347985) (xy 163.886125 -392.295655)
			(xy 163.908782 -392.246045) (xy 163.938268 -392.200164) (xy 163.973983 -392.158947) (xy 164.0152 -392.123232)
			(xy 164.061081 -392.093746) (xy 164.110691 -392.071089) (xy 164.163021 -392.055724) (xy 164.217005 -392.047962)
			(xy 164.271543 -392.047962) (xy 164.325527 -392.055724) (xy 164.377857 -392.071089) (xy 164.427467 -392.093746)
			(xy 164.473348 -392.123232) (xy 164.514565 -392.158947) (xy 164.55028 -392.200164) (xy 164.579766 -392.246045)
			(xy 164.602423 -392.295655) (xy 164.617788 -392.347985) (xy 164.62555 -392.401969) (xy 164.626036 -392.429238)
			(xy 164.626036 -393.292838) (xy 165.062408 -393.292838) (xy 165.062408 -392.429238) (xy 165.062894 -392.401969)
			(xy 165.070656 -392.347985) (xy 165.086021 -392.295655) (xy 165.108678 -392.246045) (xy 165.138164 -392.200164)
			(xy 165.173879 -392.158947) (xy 165.215096 -392.123232) (xy 165.260977 -392.093746) (xy 165.310587 -392.071089)
			(xy 165.362917 -392.055724) (xy 165.416901 -392.047962) (xy 165.471439 -392.047962) (xy 165.525423 -392.055724)
			(xy 165.577753 -392.071089) (xy 165.627363 -392.093746) (xy 165.673244 -392.123232) (xy 165.714461 -392.158947)
			(xy 165.750176 -392.200164) (xy 165.779662 -392.246045) (xy 165.802319 -392.295655) (xy 165.817684 -392.347985)
			(xy 165.825446 -392.401969) (xy 165.825932 -392.429238) (xy 165.825932 -393.292838) (xy 165.825446 -393.320107)
			(xy 165.817684 -393.374091) (xy 165.802319 -393.426421) (xy 165.779662 -393.476031) (xy 165.750176 -393.521912)
			(xy 165.714461 -393.563129) (xy 165.673244 -393.598844) (xy 165.627363 -393.62833) (xy 165.577753 -393.650987)
			(xy 165.525423 -393.666352) (xy 165.471439 -393.674114) (xy 165.416901 -393.674114) (xy 165.362917 -393.666352)
			(xy 165.310587 -393.650987) (xy 165.260977 -393.62833) (xy 165.215096 -393.598844) (xy 165.173879 -393.563129)
			(xy 165.138164 -393.521912) (xy 165.108678 -393.476031) (xy 165.086021 -393.426421) (xy 165.070656 -393.374091)
			(xy 165.062894 -393.320107) (xy 165.062408 -393.292838) (xy 164.626036 -393.292838) (xy 164.62555 -393.320107)
			(xy 164.617788 -393.374091) (xy 164.602423 -393.426421) (xy 164.579766 -393.476031) (xy 164.55028 -393.521912)
			(xy 164.514565 -393.563129) (xy 164.473348 -393.598844) (xy 164.427467 -393.62833) (xy 164.377857 -393.650987)
			(xy 164.325527 -393.666352) (xy 164.271543 -393.674114) (xy 164.217005 -393.674114) (xy 164.163021 -393.666352)
			(xy 164.110691 -393.650987) (xy 164.061081 -393.62833) (xy 164.0152 -393.598844) (xy 163.973983 -393.563129)
			(xy 163.938268 -393.521912) (xy 163.908782 -393.476031) (xy 163.886125 -393.426421) (xy 163.87076 -393.374091)
			(xy 163.862998 -393.320107) (xy 163.862512 -393.292838) (xy 163.425632 -393.292838) (xy 163.425146 -393.320089)
			(xy 163.41739 -393.374037) (xy 163.402035 -393.426332) (xy 163.379393 -393.475909) (xy 163.349927 -393.521759)
			(xy 163.314236 -393.56295) (xy 163.273045 -393.598641) (xy 163.227195 -393.628107) (xy 163.177618 -393.650749)
			(xy 163.125323 -393.666104) (xy 163.071375 -393.67386) (xy 163.016873 -393.67386) (xy 162.962925 -393.666104)
			(xy 162.91063 -393.650749) (xy 162.861053 -393.628107) (xy 162.815203 -393.598641) (xy 162.774012 -393.56295)
			(xy 162.738321 -393.521759) (xy 162.708855 -393.475909) (xy 162.686213 -393.426332) (xy 162.670858 -393.374037)
			(xy 162.663102 -393.320089) (xy 162.662616 -393.292838) (xy 162.225736 -393.292838) (xy 162.22525 -393.320089)
			(xy 162.217494 -393.374037) (xy 162.202139 -393.426332) (xy 162.179497 -393.475909) (xy 162.150031 -393.521759)
			(xy 162.11434 -393.56295) (xy 162.073149 -393.598641) (xy 162.027299 -393.628107) (xy 161.977722 -393.650749)
			(xy 161.925427 -393.666104) (xy 161.871479 -393.67386) (xy 161.816977 -393.67386) (xy 161.763029 -393.666104)
			(xy 161.710734 -393.650749) (xy 161.661157 -393.628107) (xy 161.615307 -393.598641) (xy 161.574116 -393.56295)
			(xy 161.538425 -393.521759) (xy 161.508959 -393.475909) (xy 161.486317 -393.426332) (xy 161.470962 -393.374037)
			(xy 161.463206 -393.320089) (xy 161.46272 -393.292838) (xy 161.02584 -393.292838) (xy 161.025354 -393.320089)
			(xy 161.017598 -393.374037) (xy 161.002243 -393.426332) (xy 160.979601 -393.475909) (xy 160.950135 -393.521759)
			(xy 160.914444 -393.56295) (xy 160.873253 -393.598641) (xy 160.827403 -393.628107) (xy 160.777826 -393.650749)
			(xy 160.725531 -393.666104) (xy 160.671583 -393.67386) (xy 160.617081 -393.67386) (xy 160.563133 -393.666104)
			(xy 160.510838 -393.650749) (xy 160.461261 -393.628107) (xy 160.415411 -393.598641) (xy 160.37422 -393.56295)
			(xy 160.338529 -393.521759) (xy 160.309063 -393.475909) (xy 160.286421 -393.426332) (xy 160.271066 -393.374037)
			(xy 160.26331 -393.320089) (xy 160.262824 -393.292838) (xy 159.825944 -393.292838) (xy 159.825458 -393.320089)
			(xy 159.817702 -393.374037) (xy 159.802347 -393.426332) (xy 159.779705 -393.475909) (xy 159.750239 -393.521759)
			(xy 159.714548 -393.56295) (xy 159.673357 -393.598641) (xy 159.627507 -393.628107) (xy 159.57793 -393.650749)
			(xy 159.525635 -393.666104) (xy 159.471687 -393.67386) (xy 159.417185 -393.67386) (xy 159.363237 -393.666104)
			(xy 159.310942 -393.650749) (xy 159.261365 -393.628107) (xy 159.215515 -393.598641) (xy 159.174324 -393.56295)
			(xy 159.138633 -393.521759) (xy 159.109167 -393.475909) (xy 159.086525 -393.426332) (xy 159.07117 -393.374037)
			(xy 159.063414 -393.320089) (xy 159.062928 -393.292838) (xy 158.626048 -393.292838) (xy 158.625562 -393.320107)
			(xy 158.6178 -393.374091) (xy 158.602435 -393.426421) (xy 158.579778 -393.476031) (xy 158.550292 -393.521912)
			(xy 158.514577 -393.563129) (xy 158.47336 -393.598844) (xy 158.427479 -393.62833) (xy 158.377869 -393.650987)
			(xy 158.325539 -393.666352) (xy 158.271555 -393.674114) (xy 158.217017 -393.674114) (xy 158.163033 -393.666352)
			(xy 158.110703 -393.650987) (xy 158.061093 -393.62833) (xy 158.015212 -393.598844) (xy 157.973995 -393.563129)
			(xy 157.93828 -393.521912) (xy 157.908794 -393.476031) (xy 157.886137 -393.426421) (xy 157.870772 -393.374091)
			(xy 157.86301 -393.320107) (xy 157.862524 -393.292838) (xy 157.426152 -393.292838) (xy 157.425666 -393.320107)
			(xy 157.417904 -393.374091) (xy 157.402539 -393.426421) (xy 157.379882 -393.476031) (xy 157.350396 -393.521912)
			(xy 157.314681 -393.563129) (xy 157.273464 -393.598844) (xy 157.227583 -393.62833) (xy 157.177973 -393.650987)
			(xy 157.125643 -393.666352) (xy 157.071659 -393.674114) (xy 157.017121 -393.674114) (xy 156.963137 -393.666352)
			(xy 156.910807 -393.650987) (xy 156.861197 -393.62833) (xy 156.815316 -393.598844) (xy 156.774099 -393.563129)
			(xy 156.738384 -393.521912) (xy 156.708898 -393.476031) (xy 156.686241 -393.426421) (xy 156.670876 -393.374091)
			(xy 156.663114 -393.320107) (xy 156.662628 -393.292838) (xy 156.225748 -393.292838) (xy 156.225262 -393.320089)
			(xy 156.217506 -393.374037) (xy 156.202151 -393.426332) (xy 156.179509 -393.475909) (xy 156.150043 -393.521759)
			(xy 156.114352 -393.56295) (xy 156.073161 -393.598641) (xy 156.027311 -393.628107) (xy 155.977734 -393.650749)
			(xy 155.925439 -393.666104) (xy 155.871491 -393.67386) (xy 155.816989 -393.67386) (xy 155.763041 -393.666104)
			(xy 155.710746 -393.650749) (xy 155.661169 -393.628107) (xy 155.615319 -393.598641) (xy 155.574128 -393.56295)
			(xy 155.538437 -393.521759) (xy 155.508971 -393.475909) (xy 155.486329 -393.426332) (xy 155.470974 -393.374037)
			(xy 155.463218 -393.320089) (xy 155.462732 -393.292838) (xy 155.025852 -393.292838) (xy 155.025366 -393.320089)
			(xy 155.01761 -393.374037) (xy 155.002255 -393.426332) (xy 154.979613 -393.475909) (xy 154.950147 -393.521759)
			(xy 154.914456 -393.56295) (xy 154.873265 -393.598641) (xy 154.827415 -393.628107) (xy 154.777838 -393.650749)
			(xy 154.725543 -393.666104) (xy 154.671595 -393.67386) (xy 154.617093 -393.67386) (xy 154.563145 -393.666104)
			(xy 154.51085 -393.650749) (xy 154.461273 -393.628107) (xy 154.415423 -393.598641) (xy 154.374232 -393.56295)
			(xy 154.338541 -393.521759) (xy 154.309075 -393.475909) (xy 154.286433 -393.426332) (xy 154.271078 -393.374037)
			(xy 154.263322 -393.320089) (xy 154.262836 -393.292838) (xy 153.825956 -393.292838) (xy 153.82547 -393.320107)
			(xy 153.817708 -393.374091) (xy 153.802343 -393.426421) (xy 153.779686 -393.476031) (xy 153.7502 -393.521912)
			(xy 153.714485 -393.563129) (xy 153.673268 -393.598844) (xy 153.627387 -393.62833) (xy 153.577777 -393.650987)
			(xy 153.525447 -393.666352) (xy 153.471463 -393.674114) (xy 153.416925 -393.674114) (xy 153.362941 -393.666352)
			(xy 153.310611 -393.650987) (xy 153.261001 -393.62833) (xy 153.21512 -393.598844) (xy 153.173903 -393.563129)
			(xy 153.138188 -393.521912) (xy 153.108702 -393.476031) (xy 153.086045 -393.426421) (xy 153.07068 -393.374091)
			(xy 153.062918 -393.320107) (xy 153.062432 -393.292838) (xy 152.62606 -393.292838) (xy 152.625574 -393.320107)
			(xy 152.617812 -393.374091) (xy 152.602447 -393.426421) (xy 152.57979 -393.476031) (xy 152.550304 -393.521912)
			(xy 152.514589 -393.563129) (xy 152.473372 -393.598844) (xy 152.427491 -393.62833) (xy 152.377881 -393.650987)
			(xy 152.325551 -393.666352) (xy 152.271567 -393.674114) (xy 152.217029 -393.674114) (xy 152.163045 -393.666352)
			(xy 152.110715 -393.650987) (xy 152.061105 -393.62833) (xy 152.015224 -393.598844) (xy 151.974007 -393.563129)
			(xy 151.938292 -393.521912) (xy 151.908806 -393.476031) (xy 151.886149 -393.426421) (xy 151.870784 -393.374091)
			(xy 151.863022 -393.320107) (xy 151.862536 -393.292838) (xy 151.425656 -393.292838) (xy 151.42517 -393.320089)
			(xy 151.417414 -393.374037) (xy 151.402059 -393.426332) (xy 151.379417 -393.475909) (xy 151.349951 -393.521759)
			(xy 151.31426 -393.56295) (xy 151.273069 -393.598641) (xy 151.227219 -393.628107) (xy 151.177642 -393.650749)
			(xy 151.125347 -393.666104) (xy 151.071399 -393.67386) (xy 151.016897 -393.67386) (xy 150.962949 -393.666104)
			(xy 150.910654 -393.650749) (xy 150.861077 -393.628107) (xy 150.815227 -393.598641) (xy 150.774036 -393.56295)
			(xy 150.738345 -393.521759) (xy 150.708879 -393.475909) (xy 150.686237 -393.426332) (xy 150.670882 -393.374037)
			(xy 150.663126 -393.320089) (xy 150.66264 -393.292838) (xy 150.22576 -393.292838) (xy 150.225274 -393.320089)
			(xy 150.217518 -393.374037) (xy 150.202163 -393.426332) (xy 150.179521 -393.475909) (xy 150.150055 -393.521759)
			(xy 150.114364 -393.56295) (xy 150.073173 -393.598641) (xy 150.027323 -393.628107) (xy 149.977746 -393.650749)
			(xy 149.925451 -393.666104) (xy 149.871503 -393.67386) (xy 149.817001 -393.67386) (xy 149.763053 -393.666104)
			(xy 149.710758 -393.650749) (xy 149.661181 -393.628107) (xy 149.615331 -393.598641) (xy 149.57414 -393.56295)
			(xy 149.538449 -393.521759) (xy 149.508983 -393.475909) (xy 149.486341 -393.426332) (xy 149.470986 -393.374037)
			(xy 149.46323 -393.320089) (xy 149.462744 -393.292838) (xy 149.025864 -393.292838) (xy 149.025378 -393.320107)
			(xy 149.017616 -393.374091) (xy 149.002251 -393.426421) (xy 148.979594 -393.476031) (xy 148.950108 -393.521912)
			(xy 148.914393 -393.563129) (xy 148.873176 -393.598844) (xy 148.827295 -393.62833) (xy 148.777685 -393.650987)
			(xy 148.725355 -393.666352) (xy 148.671371 -393.674114) (xy 148.616833 -393.674114) (xy 148.562849 -393.666352)
			(xy 148.510519 -393.650987) (xy 148.460909 -393.62833) (xy 148.415028 -393.598844) (xy 148.373811 -393.563129)
			(xy 148.338096 -393.521912) (xy 148.30861 -393.476031) (xy 148.285953 -393.426421) (xy 148.270588 -393.374091)
			(xy 148.262826 -393.320107) (xy 148.26234 -393.292838) (xy 147.825968 -393.292838) (xy 147.825482 -393.320107)
			(xy 147.81772 -393.374091) (xy 147.802355 -393.426421) (xy 147.779698 -393.476031) (xy 147.750212 -393.521912)
			(xy 147.714497 -393.563129) (xy 147.67328 -393.598844) (xy 147.627399 -393.62833) (xy 147.577789 -393.650987)
			(xy 147.525459 -393.666352) (xy 147.471475 -393.674114) (xy 147.416937 -393.674114) (xy 147.362953 -393.666352)
			(xy 147.310623 -393.650987) (xy 147.261013 -393.62833) (xy 147.215132 -393.598844) (xy 147.173915 -393.563129)
			(xy 147.1382 -393.521912) (xy 147.108714 -393.476031) (xy 147.086057 -393.426421) (xy 147.070692 -393.374091)
			(xy 147.06293 -393.320107) (xy 147.062444 -393.292838) (xy 133.298184 -393.292838) (xy 133.297698 -393.320107)
			(xy 133.289936 -393.374091) (xy 133.274571 -393.426421) (xy 133.251914 -393.476031) (xy 133.222428 -393.521912)
			(xy 133.186713 -393.563129) (xy 133.145496 -393.598844) (xy 133.099615 -393.62833) (xy 133.050005 -393.650987)
			(xy 132.997675 -393.666352) (xy 132.943691 -393.674114) (xy 132.889153 -393.674114) (xy 132.835169 -393.666352)
			(xy 132.782839 -393.650987) (xy 132.733229 -393.62833) (xy 132.687348 -393.598844) (xy 132.646131 -393.563129)
			(xy 132.610416 -393.521912) (xy 132.58093 -393.476031) (xy 132.558273 -393.426421) (xy 132.542908 -393.374091)
			(xy 132.535146 -393.320107) (xy 132.53466 -393.292838) (xy 132.098288 -393.292838) (xy 132.097802 -393.320107)
			(xy 132.09004 -393.374091) (xy 132.074675 -393.426421) (xy 132.052018 -393.476031) (xy 132.022532 -393.521912)
			(xy 131.986817 -393.563129) (xy 131.9456 -393.598844) (xy 131.899719 -393.62833) (xy 131.850109 -393.650987)
			(xy 131.797779 -393.666352) (xy 131.743795 -393.674114) (xy 131.689257 -393.674114) (xy 131.635273 -393.666352)
			(xy 131.582943 -393.650987) (xy 131.533333 -393.62833) (xy 131.487452 -393.598844) (xy 131.446235 -393.563129)
			(xy 131.41052 -393.521912) (xy 131.381034 -393.476031) (xy 131.358377 -393.426421) (xy 131.343012 -393.374091)
			(xy 131.33525 -393.320107) (xy 131.334764 -393.292838) (xy 130.897884 -393.292838) (xy 130.897398 -393.320089)
			(xy 130.889642 -393.374037) (xy 130.874287 -393.426332) (xy 130.851645 -393.475909) (xy 130.822179 -393.521759)
			(xy 130.786488 -393.56295) (xy 130.745297 -393.598641) (xy 130.699447 -393.628107) (xy 130.64987 -393.650749)
			(xy 130.597575 -393.666104) (xy 130.543627 -393.67386) (xy 130.489125 -393.67386) (xy 130.435177 -393.666104)
			(xy 130.382882 -393.650749) (xy 130.333305 -393.628107) (xy 130.287455 -393.598641) (xy 130.246264 -393.56295)
			(xy 130.210573 -393.521759) (xy 130.181107 -393.475909) (xy 130.158465 -393.426332) (xy 130.14311 -393.374037)
			(xy 130.135354 -393.320089) (xy 130.134868 -393.292838) (xy 129.697988 -393.292838) (xy 129.697502 -393.320089)
			(xy 129.689746 -393.374037) (xy 129.674391 -393.426332) (xy 129.651749 -393.475909) (xy 129.622283 -393.521759)
			(xy 129.586592 -393.56295) (xy 129.545401 -393.598641) (xy 129.499551 -393.628107) (xy 129.449974 -393.650749)
			(xy 129.397679 -393.666104) (xy 129.343731 -393.67386) (xy 129.289229 -393.67386) (xy 129.235281 -393.666104)
			(xy 129.182986 -393.650749) (xy 129.133409 -393.628107) (xy 129.087559 -393.598641) (xy 129.046368 -393.56295)
			(xy 129.010677 -393.521759) (xy 128.981211 -393.475909) (xy 128.958569 -393.426332) (xy 128.943214 -393.374037)
			(xy 128.935458 -393.320089) (xy 128.934972 -393.292838) (xy 128.498092 -393.292838) (xy 128.497606 -393.320089)
			(xy 128.48985 -393.374037) (xy 128.474495 -393.426332) (xy 128.451853 -393.475909) (xy 128.422387 -393.521759)
			(xy 128.386696 -393.56295) (xy 128.345505 -393.598641) (xy 128.299655 -393.628107) (xy 128.250078 -393.650749)
			(xy 128.197783 -393.666104) (xy 128.143835 -393.67386) (xy 128.089333 -393.67386) (xy 128.035385 -393.666104)
			(xy 127.98309 -393.650749) (xy 127.933513 -393.628107) (xy 127.887663 -393.598641) (xy 127.846472 -393.56295)
			(xy 127.810781 -393.521759) (xy 127.781315 -393.475909) (xy 127.758673 -393.426332) (xy 127.743318 -393.374037)
			(xy 127.735562 -393.320089) (xy 127.735076 -393.292838) (xy 127.298196 -393.292838) (xy 127.29771 -393.320089)
			(xy 127.289954 -393.374037) (xy 127.274599 -393.426332) (xy 127.251957 -393.475909) (xy 127.222491 -393.521759)
			(xy 127.1868 -393.56295) (xy 127.145609 -393.598641) (xy 127.099759 -393.628107) (xy 127.050182 -393.650749)
			(xy 126.997887 -393.666104) (xy 126.943939 -393.67386) (xy 126.889437 -393.67386) (xy 126.835489 -393.666104)
			(xy 126.783194 -393.650749) (xy 126.733617 -393.628107) (xy 126.687767 -393.598641) (xy 126.646576 -393.56295)
			(xy 126.610885 -393.521759) (xy 126.581419 -393.475909) (xy 126.558777 -393.426332) (xy 126.543422 -393.374037)
			(xy 126.535666 -393.320089) (xy 126.53518 -393.292838) (xy 126.0983 -393.292838) (xy 126.097814 -393.320107)
			(xy 126.090052 -393.374091) (xy 126.074687 -393.426421) (xy 126.05203 -393.476031) (xy 126.022544 -393.521912)
			(xy 125.986829 -393.563129) (xy 125.945612 -393.598844) (xy 125.899731 -393.62833) (xy 125.850121 -393.650987)
			(xy 125.797791 -393.666352) (xy 125.743807 -393.674114) (xy 125.689269 -393.674114) (xy 125.635285 -393.666352)
			(xy 125.582955 -393.650987) (xy 125.533345 -393.62833) (xy 125.487464 -393.598844) (xy 125.446247 -393.563129)
			(xy 125.410532 -393.521912) (xy 125.381046 -393.476031) (xy 125.358389 -393.426421) (xy 125.343024 -393.374091)
			(xy 125.335262 -393.320107) (xy 125.334776 -393.292838) (xy 124.898404 -393.292838) (xy 124.897918 -393.320107)
			(xy 124.890156 -393.374091) (xy 124.874791 -393.426421) (xy 124.852134 -393.476031) (xy 124.822648 -393.521912)
			(xy 124.786933 -393.563129) (xy 124.745716 -393.598844) (xy 124.699835 -393.62833) (xy 124.650225 -393.650987)
			(xy 124.597895 -393.666352) (xy 124.543911 -393.674114) (xy 124.489373 -393.674114) (xy 124.435389 -393.666352)
			(xy 124.383059 -393.650987) (xy 124.333449 -393.62833) (xy 124.287568 -393.598844) (xy 124.246351 -393.563129)
			(xy 124.210636 -393.521912) (xy 124.18115 -393.476031) (xy 124.158493 -393.426421) (xy 124.143128 -393.374091)
			(xy 124.135366 -393.320107) (xy 124.13488 -393.292838) (xy 123.698 -393.292838) (xy 123.697514 -393.320089)
			(xy 123.689758 -393.374037) (xy 123.674403 -393.426332) (xy 123.651761 -393.475909) (xy 123.622295 -393.521759)
			(xy 123.586604 -393.56295) (xy 123.545413 -393.598641) (xy 123.499563 -393.628107) (xy 123.449986 -393.650749)
			(xy 123.397691 -393.666104) (xy 123.343743 -393.67386) (xy 123.289241 -393.67386) (xy 123.235293 -393.666104)
			(xy 123.182998 -393.650749) (xy 123.133421 -393.628107) (xy 123.087571 -393.598641) (xy 123.04638 -393.56295)
			(xy 123.010689 -393.521759) (xy 122.981223 -393.475909) (xy 122.958581 -393.426332) (xy 122.943226 -393.374037)
			(xy 122.93547 -393.320089) (xy 122.934984 -393.292838) (xy 122.498104 -393.292838) (xy 122.497618 -393.320089)
			(xy 122.489862 -393.374037) (xy 122.474507 -393.426332) (xy 122.451865 -393.475909) (xy 122.422399 -393.521759)
			(xy 122.386708 -393.56295) (xy 122.345517 -393.598641) (xy 122.299667 -393.628107) (xy 122.25009 -393.650749)
			(xy 122.197795 -393.666104) (xy 122.143847 -393.67386) (xy 122.089345 -393.67386) (xy 122.035397 -393.666104)
			(xy 121.983102 -393.650749) (xy 121.933525 -393.628107) (xy 121.887675 -393.598641) (xy 121.846484 -393.56295)
			(xy 121.810793 -393.521759) (xy 121.781327 -393.475909) (xy 121.758685 -393.426332) (xy 121.74333 -393.374037)
			(xy 121.735574 -393.320089) (xy 121.735088 -393.292838) (xy 121.298208 -393.292838) (xy 121.297722 -393.320107)
			(xy 121.28996 -393.374091) (xy 121.274595 -393.426421) (xy 121.251938 -393.476031) (xy 121.222452 -393.521912)
			(xy 121.186737 -393.563129) (xy 121.14552 -393.598844) (xy 121.099639 -393.62833) (xy 121.050029 -393.650987)
			(xy 120.997699 -393.666352) (xy 120.943715 -393.674114) (xy 120.889177 -393.674114) (xy 120.835193 -393.666352)
			(xy 120.782863 -393.650987) (xy 120.733253 -393.62833) (xy 120.687372 -393.598844) (xy 120.646155 -393.563129)
			(xy 120.61044 -393.521912) (xy 120.580954 -393.476031) (xy 120.558297 -393.426421) (xy 120.542932 -393.374091)
			(xy 120.53517 -393.320107) (xy 120.534684 -393.292838) (xy 120.098312 -393.292838) (xy 120.097826 -393.320107)
			(xy 120.090064 -393.374091) (xy 120.074699 -393.426421) (xy 120.052042 -393.476031) (xy 120.022556 -393.521912)
			(xy 119.986841 -393.563129) (xy 119.945624 -393.598844) (xy 119.899743 -393.62833) (xy 119.850133 -393.650987)
			(xy 119.797803 -393.666352) (xy 119.743819 -393.674114) (xy 119.689281 -393.674114) (xy 119.635297 -393.666352)
			(xy 119.582967 -393.650987) (xy 119.533357 -393.62833) (xy 119.487476 -393.598844) (xy 119.446259 -393.563129)
			(xy 119.410544 -393.521912) (xy 119.381058 -393.476031) (xy 119.358401 -393.426421) (xy 119.343036 -393.374091)
			(xy 119.335274 -393.320107) (xy 119.334788 -393.292838) (xy 118.897908 -393.292838) (xy 118.897422 -393.320089)
			(xy 118.889666 -393.374037) (xy 118.874311 -393.426332) (xy 118.851669 -393.475909) (xy 118.822203 -393.521759)
			(xy 118.786512 -393.56295) (xy 118.745321 -393.598641) (xy 118.699471 -393.628107) (xy 118.649894 -393.650749)
			(xy 118.597599 -393.666104) (xy 118.543651 -393.67386) (xy 118.489149 -393.67386) (xy 118.435201 -393.666104)
			(xy 118.382906 -393.650749) (xy 118.333329 -393.628107) (xy 118.287479 -393.598641) (xy 118.246288 -393.56295)
			(xy 118.210597 -393.521759) (xy 118.181131 -393.475909) (xy 118.158489 -393.426332) (xy 118.143134 -393.374037)
			(xy 118.135378 -393.320089) (xy 118.134892 -393.292838) (xy 117.698012 -393.292838) (xy 117.697526 -393.320089)
			(xy 117.68977 -393.374037) (xy 117.674415 -393.426332) (xy 117.651773 -393.475909) (xy 117.622307 -393.521759)
			(xy 117.586616 -393.56295) (xy 117.545425 -393.598641) (xy 117.499575 -393.628107) (xy 117.449998 -393.650749)
			(xy 117.397703 -393.666104) (xy 117.343755 -393.67386) (xy 117.289253 -393.67386) (xy 117.235305 -393.666104)
			(xy 117.18301 -393.650749) (xy 117.133433 -393.628107) (xy 117.087583 -393.598641) (xy 117.046392 -393.56295)
			(xy 117.010701 -393.521759) (xy 116.981235 -393.475909) (xy 116.958593 -393.426332) (xy 116.943238 -393.374037)
			(xy 116.935482 -393.320089) (xy 116.934996 -393.292838) (xy 116.498116 -393.292838) (xy 116.49763 -393.320107)
			(xy 116.489868 -393.374091) (xy 116.474503 -393.426421) (xy 116.451846 -393.476031) (xy 116.42236 -393.521912)
			(xy 116.386645 -393.563129) (xy 116.345428 -393.598844) (xy 116.299547 -393.62833) (xy 116.249937 -393.650987)
			(xy 116.197607 -393.666352) (xy 116.143623 -393.674114) (xy 116.089085 -393.674114) (xy 116.035101 -393.666352)
			(xy 115.982771 -393.650987) (xy 115.933161 -393.62833) (xy 115.88728 -393.598844) (xy 115.846063 -393.563129)
			(xy 115.810348 -393.521912) (xy 115.780862 -393.476031) (xy 115.758205 -393.426421) (xy 115.74284 -393.374091)
			(xy 115.735078 -393.320107) (xy 115.734592 -393.292838) (xy 115.29822 -393.292838) (xy 115.297734 -393.320107)
			(xy 115.289972 -393.374091) (xy 115.274607 -393.426421) (xy 115.25195 -393.476031) (xy 115.222464 -393.521912)
			(xy 115.186749 -393.563129) (xy 115.145532 -393.598844) (xy 115.099651 -393.62833) (xy 115.050041 -393.650987)
			(xy 114.997711 -393.666352) (xy 114.943727 -393.674114) (xy 114.889189 -393.674114) (xy 114.835205 -393.666352)
			(xy 114.782875 -393.650987) (xy 114.733265 -393.62833) (xy 114.687384 -393.598844) (xy 114.646167 -393.563129)
			(xy 114.610452 -393.521912) (xy 114.580966 -393.476031) (xy 114.558309 -393.426421) (xy 114.542944 -393.374091)
			(xy 114.535182 -393.320107) (xy 114.534696 -393.292838) (xy 98.725736 -393.292838) (xy 98.72525 -393.320089)
			(xy 98.717494 -393.374037) (xy 98.702139 -393.426332) (xy 98.679497 -393.475909) (xy 98.650031 -393.521759)
			(xy 98.61434 -393.56295) (xy 98.573149 -393.598641) (xy 98.527299 -393.628107) (xy 98.477722 -393.650749)
			(xy 98.425427 -393.666104) (xy 98.371479 -393.67386) (xy 98.316977 -393.67386) (xy 98.263029 -393.666104)
			(xy 98.210734 -393.650749) (xy 98.161157 -393.628107) (xy 98.115307 -393.598641) (xy 98.074116 -393.56295)
			(xy 98.038425 -393.521759) (xy 98.008959 -393.475909) (xy 97.986317 -393.426332) (xy 97.970962 -393.374037)
			(xy 97.963206 -393.320089) (xy 97.96272 -393.292838) (xy 97.52584 -393.292838) (xy 97.525354 -393.320089)
			(xy 97.517598 -393.374037) (xy 97.502243 -393.426332) (xy 97.479601 -393.475909) (xy 97.450135 -393.521759)
			(xy 97.414444 -393.56295) (xy 97.373253 -393.598641) (xy 97.327403 -393.628107) (xy 97.277826 -393.650749)
			(xy 97.225531 -393.666104) (xy 97.171583 -393.67386) (xy 97.117081 -393.67386) (xy 97.063133 -393.666104)
			(xy 97.010838 -393.650749) (xy 96.961261 -393.628107) (xy 96.915411 -393.598641) (xy 96.87422 -393.56295)
			(xy 96.838529 -393.521759) (xy 96.809063 -393.475909) (xy 96.786421 -393.426332) (xy 96.771066 -393.374037)
			(xy 96.76331 -393.320089) (xy 96.762824 -393.292838) (xy 96.325944 -393.292838) (xy 96.325458 -393.320107)
			(xy 96.317696 -393.374091) (xy 96.302331 -393.426421) (xy 96.279674 -393.476031) (xy 96.250188 -393.521912)
			(xy 96.214473 -393.563129) (xy 96.173256 -393.598844) (xy 96.127375 -393.62833) (xy 96.077765 -393.650987)
			(xy 96.025435 -393.666352) (xy 95.971451 -393.674114) (xy 95.916913 -393.674114) (xy 95.862929 -393.666352)
			(xy 95.810599 -393.650987) (xy 95.760989 -393.62833) (xy 95.715108 -393.598844) (xy 95.673891 -393.563129)
			(xy 95.638176 -393.521912) (xy 95.60869 -393.476031) (xy 95.586033 -393.426421) (xy 95.570668 -393.374091)
			(xy 95.562906 -393.320107) (xy 95.56242 -393.292838) (xy 95.126048 -393.292838) (xy 95.125562 -393.320107)
			(xy 95.1178 -393.374091) (xy 95.102435 -393.426421) (xy 95.079778 -393.476031) (xy 95.050292 -393.521912)
			(xy 95.014577 -393.563129) (xy 94.97336 -393.598844) (xy 94.927479 -393.62833) (xy 94.877869 -393.650987)
			(xy 94.825539 -393.666352) (xy 94.771555 -393.674114) (xy 94.717017 -393.674114) (xy 94.663033 -393.666352)
			(xy 94.610703 -393.650987) (xy 94.561093 -393.62833) (xy 94.515212 -393.598844) (xy 94.473995 -393.563129)
			(xy 94.43828 -393.521912) (xy 94.408794 -393.476031) (xy 94.386137 -393.426421) (xy 94.370772 -393.374091)
			(xy 94.36301 -393.320107) (xy 94.362524 -393.292838) (xy 93.926152 -393.292838) (xy 93.925666 -393.320107)
			(xy 93.917904 -393.374091) (xy 93.902539 -393.426421) (xy 93.879882 -393.476031) (xy 93.850396 -393.521912)
			(xy 93.814681 -393.563129) (xy 93.773464 -393.598844) (xy 93.727583 -393.62833) (xy 93.677973 -393.650987)
			(xy 93.625643 -393.666352) (xy 93.571659 -393.674114) (xy 93.517121 -393.674114) (xy 93.463137 -393.666352)
			(xy 93.410807 -393.650987) (xy 93.361197 -393.62833) (xy 93.315316 -393.598844) (xy 93.274099 -393.563129)
			(xy 93.238384 -393.521912) (xy 93.208898 -393.476031) (xy 93.186241 -393.426421) (xy 93.170876 -393.374091)
			(xy 93.163114 -393.320107) (xy 93.162628 -393.292838) (xy 92.726256 -393.292838) (xy 92.72577 -393.320107)
			(xy 92.718008 -393.374091) (xy 92.702643 -393.426421) (xy 92.679986 -393.476031) (xy 92.6505 -393.521912)
			(xy 92.614785 -393.563129) (xy 92.573568 -393.598844) (xy 92.527687 -393.62833) (xy 92.478077 -393.650987)
			(xy 92.425747 -393.666352) (xy 92.371763 -393.674114) (xy 92.317225 -393.674114) (xy 92.263241 -393.666352)
			(xy 92.210911 -393.650987) (xy 92.161301 -393.62833) (xy 92.11542 -393.598844) (xy 92.074203 -393.563129)
			(xy 92.038488 -393.521912) (xy 92.009002 -393.476031) (xy 91.986345 -393.426421) (xy 91.97098 -393.374091)
			(xy 91.963218 -393.320107) (xy 91.962732 -393.292838) (xy 91.525852 -393.292838) (xy 91.525366 -393.320089)
			(xy 91.51761 -393.374037) (xy 91.502255 -393.426332) (xy 91.479613 -393.475909) (xy 91.450147 -393.521759)
			(xy 91.414456 -393.56295) (xy 91.373265 -393.598641) (xy 91.327415 -393.628107) (xy 91.277838 -393.650749)
			(xy 91.225543 -393.666104) (xy 91.171595 -393.67386) (xy 91.117093 -393.67386) (xy 91.063145 -393.666104)
			(xy 91.01085 -393.650749) (xy 90.961273 -393.628107) (xy 90.915423 -393.598641) (xy 90.874232 -393.56295)
			(xy 90.838541 -393.521759) (xy 90.809075 -393.475909) (xy 90.786433 -393.426332) (xy 90.771078 -393.374037)
			(xy 90.763322 -393.320089) (xy 90.762836 -393.292838) (xy 90.325956 -393.292838) (xy 90.32547 -393.320089)
			(xy 90.317714 -393.374037) (xy 90.302359 -393.426332) (xy 90.279717 -393.475909) (xy 90.250251 -393.521759)
			(xy 90.21456 -393.56295) (xy 90.173369 -393.598641) (xy 90.127519 -393.628107) (xy 90.077942 -393.650749)
			(xy 90.025647 -393.666104) (xy 89.971699 -393.67386) (xy 89.917197 -393.67386) (xy 89.863249 -393.666104)
			(xy 89.810954 -393.650749) (xy 89.761377 -393.628107) (xy 89.715527 -393.598641) (xy 89.674336 -393.56295)
			(xy 89.638645 -393.521759) (xy 89.609179 -393.475909) (xy 89.586537 -393.426332) (xy 89.571182 -393.374037)
			(xy 89.563426 -393.320089) (xy 89.56294 -393.292838) (xy 89.12606 -393.292838) (xy 89.125574 -393.320107)
			(xy 89.117812 -393.374091) (xy 89.102447 -393.426421) (xy 89.07979 -393.476031) (xy 89.050304 -393.521912)
			(xy 89.014589 -393.563129) (xy 88.973372 -393.598844) (xy 88.927491 -393.62833) (xy 88.877881 -393.650987)
			(xy 88.825551 -393.666352) (xy 88.771567 -393.674114) (xy 88.717029 -393.674114) (xy 88.663045 -393.666352)
			(xy 88.610715 -393.650987) (xy 88.561105 -393.62833) (xy 88.515224 -393.598844) (xy 88.474007 -393.563129)
			(xy 88.438292 -393.521912) (xy 88.408806 -393.476031) (xy 88.386149 -393.426421) (xy 88.370784 -393.374091)
			(xy 88.363022 -393.320107) (xy 88.362536 -393.292838) (xy 87.926164 -393.292838) (xy 87.925678 -393.320107)
			(xy 87.917916 -393.374091) (xy 87.902551 -393.426421) (xy 87.879894 -393.476031) (xy 87.850408 -393.521912)
			(xy 87.814693 -393.563129) (xy 87.773476 -393.598844) (xy 87.727595 -393.62833) (xy 87.677985 -393.650987)
			(xy 87.625655 -393.666352) (xy 87.571671 -393.674114) (xy 87.517133 -393.674114) (xy 87.463149 -393.666352)
			(xy 87.410819 -393.650987) (xy 87.361209 -393.62833) (xy 87.315328 -393.598844) (xy 87.274111 -393.563129)
			(xy 87.238396 -393.521912) (xy 87.20891 -393.476031) (xy 87.186253 -393.426421) (xy 87.170888 -393.374091)
			(xy 87.163126 -393.320107) (xy 87.16264 -393.292838) (xy 86.72576 -393.292838) (xy 86.725274 -393.320089)
			(xy 86.717518 -393.374037) (xy 86.702163 -393.426332) (xy 86.679521 -393.475909) (xy 86.650055 -393.521759)
			(xy 86.614364 -393.56295) (xy 86.573173 -393.598641) (xy 86.527323 -393.628107) (xy 86.477746 -393.650749)
			(xy 86.425451 -393.666104) (xy 86.371503 -393.67386) (xy 86.317001 -393.67386) (xy 86.263053 -393.666104)
			(xy 86.210758 -393.650749) (xy 86.161181 -393.628107) (xy 86.115331 -393.598641) (xy 86.07414 -393.56295)
			(xy 86.038449 -393.521759) (xy 86.008983 -393.475909) (xy 85.986341 -393.426332) (xy 85.970986 -393.374037)
			(xy 85.96323 -393.320089) (xy 85.962744 -393.292838) (xy 85.525864 -393.292838) (xy 85.525378 -393.320089)
			(xy 85.517622 -393.374037) (xy 85.502267 -393.426332) (xy 85.479625 -393.475909) (xy 85.450159 -393.521759)
			(xy 85.414468 -393.56295) (xy 85.373277 -393.598641) (xy 85.327427 -393.628107) (xy 85.27785 -393.650749)
			(xy 85.225555 -393.666104) (xy 85.171607 -393.67386) (xy 85.117105 -393.67386) (xy 85.063157 -393.666104)
			(xy 85.010862 -393.650749) (xy 84.961285 -393.628107) (xy 84.915435 -393.598641) (xy 84.874244 -393.56295)
			(xy 84.838553 -393.521759) (xy 84.809087 -393.475909) (xy 84.786445 -393.426332) (xy 84.77109 -393.374037)
			(xy 84.763334 -393.320089) (xy 84.762848 -393.292838) (xy 84.325968 -393.292838) (xy 84.325482 -393.320107)
			(xy 84.31772 -393.374091) (xy 84.302355 -393.426421) (xy 84.279698 -393.476031) (xy 84.250212 -393.521912)
			(xy 84.214497 -393.563129) (xy 84.17328 -393.598844) (xy 84.127399 -393.62833) (xy 84.077789 -393.650987)
			(xy 84.025459 -393.666352) (xy 83.971475 -393.674114) (xy 83.916937 -393.674114) (xy 83.862953 -393.666352)
			(xy 83.810623 -393.650987) (xy 83.761013 -393.62833) (xy 83.715132 -393.598844) (xy 83.673915 -393.563129)
			(xy 83.6382 -393.521912) (xy 83.608714 -393.476031) (xy 83.586057 -393.426421) (xy 83.570692 -393.374091)
			(xy 83.56293 -393.320107) (xy 83.562444 -393.292838) (xy 83.126072 -393.292838) (xy 83.125586 -393.320107)
			(xy 83.117824 -393.374091) (xy 83.102459 -393.426421) (xy 83.079802 -393.476031) (xy 83.050316 -393.521912)
			(xy 83.014601 -393.563129) (xy 82.973384 -393.598844) (xy 82.927503 -393.62833) (xy 82.877893 -393.650987)
			(xy 82.825563 -393.666352) (xy 82.771579 -393.674114) (xy 82.717041 -393.674114) (xy 82.663057 -393.666352)
			(xy 82.610727 -393.650987) (xy 82.561117 -393.62833) (xy 82.515236 -393.598844) (xy 82.474019 -393.563129)
			(xy 82.438304 -393.521912) (xy 82.408818 -393.476031) (xy 82.386161 -393.426421) (xy 82.370796 -393.374091)
			(xy 82.363034 -393.320107) (xy 82.362548 -393.292838) (xy 81.925668 -393.292838) (xy 81.925182 -393.320089)
			(xy 81.917426 -393.374037) (xy 81.902071 -393.426332) (xy 81.879429 -393.475909) (xy 81.849963 -393.521759)
			(xy 81.814272 -393.56295) (xy 81.773081 -393.598641) (xy 81.727231 -393.628107) (xy 81.677654 -393.650749)
			(xy 81.625359 -393.666104) (xy 81.571411 -393.67386) (xy 81.516909 -393.67386) (xy 81.462961 -393.666104)
			(xy 81.410666 -393.650749) (xy 81.361089 -393.628107) (xy 81.315239 -393.598641) (xy 81.274048 -393.56295)
			(xy 81.238357 -393.521759) (xy 81.208891 -393.475909) (xy 81.186249 -393.426332) (xy 81.170894 -393.374037)
			(xy 81.163138 -393.320089) (xy 81.162652 -393.292838) (xy 80.725772 -393.292838) (xy 80.725286 -393.320089)
			(xy 80.71753 -393.374037) (xy 80.702175 -393.426332) (xy 80.679533 -393.475909) (xy 80.650067 -393.521759)
			(xy 80.614376 -393.56295) (xy 80.573185 -393.598641) (xy 80.527335 -393.628107) (xy 80.477758 -393.650749)
			(xy 80.425463 -393.666104) (xy 80.371515 -393.67386) (xy 80.317013 -393.67386) (xy 80.263065 -393.666104)
			(xy 80.21077 -393.650749) (xy 80.161193 -393.628107) (xy 80.115343 -393.598641) (xy 80.074152 -393.56295)
			(xy 80.038461 -393.521759) (xy 80.008995 -393.475909) (xy 79.986353 -393.426332) (xy 79.970998 -393.374037)
			(xy 79.963242 -393.320089) (xy 79.962756 -393.292838) (xy 66.197988 -393.292838) (xy 66.197502 -393.320089)
			(xy 66.189746 -393.374037) (xy 66.174391 -393.426332) (xy 66.151749 -393.475909) (xy 66.122283 -393.521759)
			(xy 66.086592 -393.56295) (xy 66.045401 -393.598641) (xy 65.999551 -393.628107) (xy 65.949974 -393.650749)
			(xy 65.897679 -393.666104) (xy 65.843731 -393.67386) (xy 65.789229 -393.67386) (xy 65.735281 -393.666104)
			(xy 65.682986 -393.650749) (xy 65.633409 -393.628107) (xy 65.587559 -393.598641) (xy 65.546368 -393.56295)
			(xy 65.510677 -393.521759) (xy 65.481211 -393.475909) (xy 65.458569 -393.426332) (xy 65.443214 -393.374037)
			(xy 65.435458 -393.320089) (xy 65.434972 -393.292838) (xy 64.998092 -393.292838) (xy 64.997606 -393.320089)
			(xy 64.98985 -393.374037) (xy 64.974495 -393.426332) (xy 64.951853 -393.475909) (xy 64.922387 -393.521759)
			(xy 64.886696 -393.56295) (xy 64.845505 -393.598641) (xy 64.799655 -393.628107) (xy 64.750078 -393.650749)
			(xy 64.697783 -393.666104) (xy 64.643835 -393.67386) (xy 64.589333 -393.67386) (xy 64.535385 -393.666104)
			(xy 64.48309 -393.650749) (xy 64.433513 -393.628107) (xy 64.387663 -393.598641) (xy 64.346472 -393.56295)
			(xy 64.310781 -393.521759) (xy 64.281315 -393.475909) (xy 64.258673 -393.426332) (xy 64.243318 -393.374037)
			(xy 64.235562 -393.320089) (xy 64.235076 -393.292838) (xy 63.798196 -393.292838) (xy 63.79771 -393.320107)
			(xy 63.789948 -393.374091) (xy 63.774583 -393.426421) (xy 63.751926 -393.476031) (xy 63.72244 -393.521912)
			(xy 63.686725 -393.563129) (xy 63.645508 -393.598844) (xy 63.599627 -393.62833) (xy 63.550017 -393.650987)
			(xy 63.497687 -393.666352) (xy 63.443703 -393.674114) (xy 63.389165 -393.674114) (xy 63.335181 -393.666352)
			(xy 63.282851 -393.650987) (xy 63.233241 -393.62833) (xy 63.18736 -393.598844) (xy 63.146143 -393.563129)
			(xy 63.110428 -393.521912) (xy 63.080942 -393.476031) (xy 63.058285 -393.426421) (xy 63.04292 -393.374091)
			(xy 63.035158 -393.320107) (xy 63.034672 -393.292838) (xy 62.5983 -393.292838) (xy 62.597814 -393.320107)
			(xy 62.590052 -393.374091) (xy 62.574687 -393.426421) (xy 62.55203 -393.476031) (xy 62.522544 -393.521912)
			(xy 62.486829 -393.563129) (xy 62.445612 -393.598844) (xy 62.399731 -393.62833) (xy 62.350121 -393.650987)
			(xy 62.297791 -393.666352) (xy 62.243807 -393.674114) (xy 62.189269 -393.674114) (xy 62.135285 -393.666352)
			(xy 62.082955 -393.650987) (xy 62.033345 -393.62833) (xy 61.987464 -393.598844) (xy 61.946247 -393.563129)
			(xy 61.910532 -393.521912) (xy 61.881046 -393.476031) (xy 61.858389 -393.426421) (xy 61.843024 -393.374091)
			(xy 61.835262 -393.320107) (xy 61.834776 -393.292838) (xy 61.398404 -393.292838) (xy 61.397918 -393.320107)
			(xy 61.390156 -393.374091) (xy 61.374791 -393.426421) (xy 61.352134 -393.476031) (xy 61.322648 -393.521912)
			(xy 61.286933 -393.563129) (xy 61.245716 -393.598844) (xy 61.199835 -393.62833) (xy 61.150225 -393.650987)
			(xy 61.097895 -393.666352) (xy 61.043911 -393.674114) (xy 60.989373 -393.674114) (xy 60.935389 -393.666352)
			(xy 60.883059 -393.650987) (xy 60.833449 -393.62833) (xy 60.787568 -393.598844) (xy 60.746351 -393.563129)
			(xy 60.710636 -393.521912) (xy 60.68115 -393.476031) (xy 60.658493 -393.426421) (xy 60.643128 -393.374091)
			(xy 60.635366 -393.320107) (xy 60.63488 -393.292838) (xy 60.198508 -393.292838) (xy 60.198022 -393.320107)
			(xy 60.19026 -393.374091) (xy 60.174895 -393.426421) (xy 60.152238 -393.476031) (xy 60.122752 -393.521912)
			(xy 60.087037 -393.563129) (xy 60.04582 -393.598844) (xy 59.999939 -393.62833) (xy 59.950329 -393.650987)
			(xy 59.897999 -393.666352) (xy 59.844015 -393.674114) (xy 59.789477 -393.674114) (xy 59.735493 -393.666352)
			(xy 59.683163 -393.650987) (xy 59.633553 -393.62833) (xy 59.587672 -393.598844) (xy 59.546455 -393.563129)
			(xy 59.51074 -393.521912) (xy 59.481254 -393.476031) (xy 59.458597 -393.426421) (xy 59.443232 -393.374091)
			(xy 59.43547 -393.320107) (xy 59.434984 -393.292838) (xy 58.998104 -393.292838) (xy 58.997618 -393.320089)
			(xy 58.989862 -393.374037) (xy 58.974507 -393.426332) (xy 58.951865 -393.475909) (xy 58.922399 -393.521759)
			(xy 58.886708 -393.56295) (xy 58.845517 -393.598641) (xy 58.799667 -393.628107) (xy 58.75009 -393.650749)
			(xy 58.697795 -393.666104) (xy 58.643847 -393.67386) (xy 58.589345 -393.67386) (xy 58.535397 -393.666104)
			(xy 58.483102 -393.650749) (xy 58.433525 -393.628107) (xy 58.387675 -393.598641) (xy 58.346484 -393.56295)
			(xy 58.310793 -393.521759) (xy 58.281327 -393.475909) (xy 58.258685 -393.426332) (xy 58.24333 -393.374037)
			(xy 58.235574 -393.320089) (xy 58.235088 -393.292838) (xy 57.798208 -393.292838) (xy 57.797722 -393.320089)
			(xy 57.789966 -393.374037) (xy 57.774611 -393.426332) (xy 57.751969 -393.475909) (xy 57.722503 -393.521759)
			(xy 57.686812 -393.56295) (xy 57.645621 -393.598641) (xy 57.599771 -393.628107) (xy 57.550194 -393.650749)
			(xy 57.497899 -393.666104) (xy 57.443951 -393.67386) (xy 57.389449 -393.67386) (xy 57.335501 -393.666104)
			(xy 57.283206 -393.650749) (xy 57.233629 -393.628107) (xy 57.187779 -393.598641) (xy 57.146588 -393.56295)
			(xy 57.110897 -393.521759) (xy 57.081431 -393.475909) (xy 57.058789 -393.426332) (xy 57.043434 -393.374037)
			(xy 57.035678 -393.320089) (xy 57.035192 -393.292838) (xy 56.598312 -393.292838) (xy 56.597826 -393.320107)
			(xy 56.590064 -393.374091) (xy 56.574699 -393.426421) (xy 56.552042 -393.476031) (xy 56.522556 -393.521912)
			(xy 56.486841 -393.563129) (xy 56.445624 -393.598844) (xy 56.399743 -393.62833) (xy 56.350133 -393.650987)
			(xy 56.297803 -393.666352) (xy 56.243819 -393.674114) (xy 56.189281 -393.674114) (xy 56.135297 -393.666352)
			(xy 56.082967 -393.650987) (xy 56.033357 -393.62833) (xy 55.987476 -393.598844) (xy 55.946259 -393.563129)
			(xy 55.910544 -393.521912) (xy 55.881058 -393.476031) (xy 55.858401 -393.426421) (xy 55.843036 -393.374091)
			(xy 55.835274 -393.320107) (xy 55.834788 -393.292838) (xy 55.398416 -393.292838) (xy 55.39793 -393.320107)
			(xy 55.390168 -393.374091) (xy 55.374803 -393.426421) (xy 55.352146 -393.476031) (xy 55.32266 -393.521912)
			(xy 55.286945 -393.563129) (xy 55.245728 -393.598844) (xy 55.199847 -393.62833) (xy 55.150237 -393.650987)
			(xy 55.097907 -393.666352) (xy 55.043923 -393.674114) (xy 54.989385 -393.674114) (xy 54.935401 -393.666352)
			(xy 54.883071 -393.650987) (xy 54.833461 -393.62833) (xy 54.78758 -393.598844) (xy 54.746363 -393.563129)
			(xy 54.710648 -393.521912) (xy 54.681162 -393.476031) (xy 54.658505 -393.426421) (xy 54.64314 -393.374091)
			(xy 54.635378 -393.320107) (xy 54.634892 -393.292838) (xy 54.198012 -393.292838) (xy 54.197526 -393.320089)
			(xy 54.18977 -393.374037) (xy 54.174415 -393.426332) (xy 54.151773 -393.475909) (xy 54.122307 -393.521759)
			(xy 54.086616 -393.56295) (xy 54.045425 -393.598641) (xy 53.999575 -393.628107) (xy 53.949998 -393.650749)
			(xy 53.897703 -393.666104) (xy 53.843755 -393.67386) (xy 53.789253 -393.67386) (xy 53.735305 -393.666104)
			(xy 53.68301 -393.650749) (xy 53.633433 -393.628107) (xy 53.587583 -393.598641) (xy 53.546392 -393.56295)
			(xy 53.510701 -393.521759) (xy 53.481235 -393.475909) (xy 53.458593 -393.426332) (xy 53.443238 -393.374037)
			(xy 53.435482 -393.320089) (xy 53.434996 -393.292838) (xy 52.998116 -393.292838) (xy 52.99763 -393.320089)
			(xy 52.989874 -393.374037) (xy 52.974519 -393.426332) (xy 52.951877 -393.475909) (xy 52.922411 -393.521759)
			(xy 52.88672 -393.56295) (xy 52.845529 -393.598641) (xy 52.799679 -393.628107) (xy 52.750102 -393.650749)
			(xy 52.697807 -393.666104) (xy 52.643859 -393.67386) (xy 52.589357 -393.67386) (xy 52.535409 -393.666104)
			(xy 52.483114 -393.650749) (xy 52.433537 -393.628107) (xy 52.387687 -393.598641) (xy 52.346496 -393.56295)
			(xy 52.310805 -393.521759) (xy 52.281339 -393.475909) (xy 52.258697 -393.426332) (xy 52.243342 -393.374037)
			(xy 52.235586 -393.320089) (xy 52.2351 -393.292838) (xy 51.79822 -393.292838) (xy 51.797734 -393.320107)
			(xy 51.789972 -393.374091) (xy 51.774607 -393.426421) (xy 51.75195 -393.476031) (xy 51.722464 -393.521912)
			(xy 51.686749 -393.563129) (xy 51.645532 -393.598844) (xy 51.599651 -393.62833) (xy 51.550041 -393.650987)
			(xy 51.497711 -393.666352) (xy 51.443727 -393.674114) (xy 51.389189 -393.674114) (xy 51.335205 -393.666352)
			(xy 51.282875 -393.650987) (xy 51.233265 -393.62833) (xy 51.187384 -393.598844) (xy 51.146167 -393.563129)
			(xy 51.110452 -393.521912) (xy 51.080966 -393.476031) (xy 51.058309 -393.426421) (xy 51.042944 -393.374091)
			(xy 51.035182 -393.320107) (xy 51.034696 -393.292838) (xy 50.598324 -393.292838) (xy 50.597838 -393.320107)
			(xy 50.590076 -393.374091) (xy 50.574711 -393.426421) (xy 50.552054 -393.476031) (xy 50.522568 -393.521912)
			(xy 50.486853 -393.563129) (xy 50.445636 -393.598844) (xy 50.399755 -393.62833) (xy 50.350145 -393.650987)
			(xy 50.297815 -393.666352) (xy 50.243831 -393.674114) (xy 50.189293 -393.674114) (xy 50.135309 -393.666352)
			(xy 50.082979 -393.650987) (xy 50.033369 -393.62833) (xy 49.987488 -393.598844) (xy 49.946271 -393.563129)
			(xy 49.910556 -393.521912) (xy 49.88107 -393.476031) (xy 49.858413 -393.426421) (xy 49.843048 -393.374091)
			(xy 49.835286 -393.320107) (xy 49.8348 -393.292838) (xy 49.39792 -393.292838) (xy 49.397434 -393.320089)
			(xy 49.389678 -393.374037) (xy 49.374323 -393.426332) (xy 49.351681 -393.475909) (xy 49.322215 -393.521759)
			(xy 49.286524 -393.56295) (xy 49.245333 -393.598641) (xy 49.199483 -393.628107) (xy 49.149906 -393.650749)
			(xy 49.097611 -393.666104) (xy 49.043663 -393.67386) (xy 48.989161 -393.67386) (xy 48.935213 -393.666104)
			(xy 48.882918 -393.650749) (xy 48.833341 -393.628107) (xy 48.787491 -393.598641) (xy 48.7463 -393.56295)
			(xy 48.710609 -393.521759) (xy 48.681143 -393.475909) (xy 48.658501 -393.426332) (xy 48.643146 -393.374037)
			(xy 48.63539 -393.320089) (xy 48.634904 -393.292838) (xy 48.198024 -393.292838) (xy 48.197538 -393.320089)
			(xy 48.189782 -393.374037) (xy 48.174427 -393.426332) (xy 48.151785 -393.475909) (xy 48.122319 -393.521759)
			(xy 48.086628 -393.56295) (xy 48.045437 -393.598641) (xy 47.999587 -393.628107) (xy 47.95001 -393.650749)
			(xy 47.897715 -393.666104) (xy 47.843767 -393.67386) (xy 47.789265 -393.67386) (xy 47.735317 -393.666104)
			(xy 47.683022 -393.650749) (xy 47.633445 -393.628107) (xy 47.587595 -393.598641) (xy 47.546404 -393.56295)
			(xy 47.510713 -393.521759) (xy 47.481247 -393.475909) (xy 47.458605 -393.426332) (xy 47.44325 -393.374037)
			(xy 47.435494 -393.320089) (xy 47.435008 -393.292838) (xy 2.509012 -393.292838) (xy 2.509012 -393.692888)
			(xy 303.485804 -393.692888) (xy 303.485804 -393.69238) (xy 303.486244 -393.668388) (xy 303.493754 -393.620994)
			(xy 303.508585 -393.575359) (xy 303.530372 -393.532605) (xy 303.558579 -393.493786) (xy 303.592511 -393.459858)
			(xy 303.631333 -393.431655) (xy 303.674088 -393.409872) (xy 303.719725 -393.395046) (xy 303.76712 -393.387542)
			(xy 303.791112 -393.387072) (xy 303.815046 -393.38757) (xy 303.862329 -393.395022) (xy 303.907871 -393.409757)
			(xy 303.950558 -393.431416) (xy 303.989344 -393.459467) (xy 304.02328 -393.493224) (xy 304.051536 -393.531861)
			(xy 304.062892 -393.552934) (xy 304.0634 -393.55395) (xy 304.143706 -393.692888) (xy 304.6857 -393.692888)
			(xy 304.6857 -393.69238) (xy 304.686144 -393.668388) (xy 304.693654 -393.620995) (xy 304.708484 -393.57536)
			(xy 304.730271 -393.532606) (xy 304.758477 -393.493788) (xy 304.792409 -393.459859) (xy 304.83123 -393.431656)
			(xy 304.873986 -393.409873) (xy 304.919622 -393.395047) (xy 304.967016 -393.387542) (xy 304.991008 -393.387072)
			(xy 305.014941 -393.387573) (xy 305.062224 -393.395024) (xy 305.107767 -393.409759) (xy 305.150453 -393.431417)
			(xy 305.189239 -393.459468) (xy 305.223176 -393.493224) (xy 305.251432 -393.531861) (xy 305.262788 -393.552934)
			(xy 305.263296 -393.55395) (xy 305.343602 -393.692888) (xy 305.885596 -393.692888) (xy 305.885596 -393.69238)
			(xy 305.886044 -393.668388) (xy 305.893553 -393.620995) (xy 305.908384 -393.575361) (xy 305.93017 -393.532608)
			(xy 305.958376 -393.493789) (xy 305.992307 -393.459861) (xy 306.031128 -393.431658) (xy 306.073883 -393.409875)
			(xy 306.119519 -393.395048) (xy 306.166912 -393.387542) (xy 306.190904 -393.387072) (xy 306.191158 -393.387072)
			(xy 306.215093 -393.387532) (xy 306.262378 -393.394992) (xy 306.307921 -393.409734) (xy 306.350607 -393.431398)
			(xy 306.389393 -393.459455) (xy 306.423328 -393.493217) (xy 306.451583 -393.531859) (xy 306.462938 -393.552934)
			(xy 306.463446 -393.55395) (xy 306.543752 -393.692888) (xy 307.085492 -393.692888) (xy 307.085492 -393.69238)
			(xy 307.085921 -393.668374) (xy 307.093438 -393.620953) (xy 307.108285 -393.575293) (xy 307.130095 -393.53252)
			(xy 307.158331 -393.493687) (xy 307.192296 -393.459752) (xy 307.231154 -393.431552) (xy 307.273947 -393.40978)
			(xy 307.31962 -393.394974) (xy 307.367047 -393.387499) (xy 307.391054 -393.387072) (xy 307.414989 -393.387536)
			(xy 307.462274 -393.394994) (xy 307.507817 -393.409736) (xy 307.550503 -393.4314) (xy 307.589289 -393.459456)
			(xy 307.623224 -393.493218) (xy 307.651479 -393.531859) (xy 307.662834 -393.552934) (xy 307.663342 -393.55395)
			(xy 307.743648 -393.692888) (xy 308.285388 -393.692888) (xy 308.285388 -393.69238) (xy 308.285821 -393.668374)
			(xy 308.293338 -393.620954) (xy 308.308185 -393.575294) (xy 308.329994 -393.532521) (xy 308.35823 -393.493689)
			(xy 308.392194 -393.459754) (xy 308.431052 -393.431553) (xy 308.473844 -393.409781) (xy 308.519517 -393.394975)
			(xy 308.566943 -393.3875) (xy 308.59095 -393.387072) (xy 308.614885 -393.387539) (xy 308.662169 -393.394997)
			(xy 308.707712 -393.409738) (xy 308.750399 -393.431401) (xy 308.789184 -393.459457) (xy 308.82312 -393.493218)
			(xy 308.851375 -393.531859) (xy 308.86273 -393.552934) (xy 308.863238 -393.55395) (xy 308.943544 -393.692888)
			(xy 309.485792 -393.692888) (xy 309.485792 -393.69238) (xy 309.486244 -393.668388) (xy 309.493753 -393.620996)
			(xy 309.508583 -393.575362) (xy 309.530369 -393.532609) (xy 309.558575 -393.49379) (xy 309.592506 -393.459862)
			(xy 309.631326 -393.431659) (xy 309.67408 -393.409876) (xy 309.719715 -393.395049) (xy 309.767108 -393.387543)
			(xy 309.7911 -393.387072) (xy 309.815033 -393.38758) (xy 309.862316 -393.39503) (xy 309.907858 -393.409764)
			(xy 309.950544 -393.43142) (xy 309.989331 -393.45947) (xy 310.023268 -393.493226) (xy 310.051524 -393.531862)
			(xy 310.06288 -393.552934) (xy 310.063388 -393.55395) (xy 310.143694 -393.692888) (xy 310.685688 -393.692888)
			(xy 310.685688 -393.69238) (xy 310.686144 -393.668388) (xy 310.693653 -393.620996) (xy 310.708483 -393.575362)
			(xy 310.730269 -393.53261) (xy 310.758474 -393.493792) (xy 310.792404 -393.459863) (xy 310.831224 -393.43166)
			(xy 310.873977 -393.409877) (xy 310.919612 -393.395049) (xy 310.967004 -393.387543) (xy 310.990996 -393.387072)
			(xy 311.014932 -393.387502) (xy 311.062218 -393.394966) (xy 311.107762 -393.409714) (xy 311.150449 -393.431384)
			(xy 311.189234 -393.459445) (xy 311.223168 -393.493212) (xy 311.251422 -393.531857) (xy 311.262776 -393.552934)
			(xy 311.263284 -393.55395) (xy 311.34359 -393.692888) (xy 311.885584 -393.692888) (xy 311.885584 -393.69238)
			(xy 311.886044 -393.668389) (xy 311.893553 -393.620997) (xy 311.908383 -393.575363) (xy 311.930168 -393.532611)
			(xy 311.958373 -393.493793) (xy 311.992302 -393.459865) (xy 312.031121 -393.431662) (xy 312.073874 -393.409878)
			(xy 312.119509 -393.39505) (xy 312.166901 -393.387543) (xy 312.190892 -393.387072) (xy 312.191146 -393.387072)
			(xy 312.215081 -393.387542) (xy 312.262365 -393.394999) (xy 312.307908 -393.40974) (xy 312.350594 -393.431403)
			(xy 312.38938 -393.459458) (xy 312.423316 -393.493219) (xy 312.451571 -393.531859) (xy 312.462926 -393.552934)
			(xy 312.463434 -393.55395) (xy 312.54374 -393.692888) (xy 313.08548 -393.692888) (xy 313.08548 -393.69238)
			(xy 313.085921 -393.668374) (xy 313.093438 -393.620955) (xy 313.108284 -393.575296) (xy 313.130093 -393.532524)
			(xy 313.158327 -393.493692) (xy 313.192291 -393.459757) (xy 313.231147 -393.431556) (xy 313.273939 -393.409783)
			(xy 313.31961 -393.394977) (xy 313.367036 -393.3875) (xy 313.391042 -393.387072) (xy 313.414976 -393.387545)
			(xy 313.462261 -393.395002) (xy 313.507803 -393.409742) (xy 313.55049 -393.431404) (xy 313.589276 -393.459459)
			(xy 313.623212 -393.49322) (xy 313.651467 -393.53186) (xy 313.662822 -393.552934) (xy 313.66333 -393.55395)
			(xy 313.743636 -393.692888) (xy 314.285376 -393.692888) (xy 314.285376 -393.69238) (xy 314.285821 -393.668374)
			(xy 314.293338 -393.620955) (xy 314.308183 -393.575297) (xy 314.329992 -393.532525) (xy 314.358226 -393.493693)
			(xy 314.392189 -393.459758) (xy 314.431045 -393.431557) (xy 314.473836 -393.409785) (xy 314.519507 -393.394977)
			(xy 314.566932 -393.3875) (xy 314.590938 -393.387072) (xy 314.591192 -393.387072) (xy 314.615128 -393.387505)
			(xy 314.662414 -393.394969) (xy 314.707958 -393.409716) (xy 314.750644 -393.431385) (xy 314.78943 -393.459446)
			(xy 314.823364 -393.493212) (xy 314.851618 -393.531857) (xy 314.862972 -393.552934) (xy 314.86348 -393.55395)
			(xy 314.943786 -393.692888) (xy 315.48578 -393.692888) (xy 315.48578 -393.69238) (xy 315.486244 -393.668389)
			(xy 315.493753 -393.620998) (xy 315.508582 -393.575364) (xy 315.530367 -393.532612) (xy 315.558571 -393.493795)
			(xy 315.592501 -393.459866) (xy 315.631319 -393.431663) (xy 315.674072 -393.409879) (xy 315.719705 -393.395051)
			(xy 315.767097 -393.387543) (xy 315.791088 -393.387072) (xy 315.815024 -393.387508) (xy 315.86231 -393.394972)
			(xy 315.907853 -393.409718) (xy 315.95054 -393.431387) (xy 315.989325 -393.459447) (xy 316.02326 -393.493213)
			(xy 316.051514 -393.531858) (xy 316.062868 -393.552934) (xy 316.063376 -393.55395) (xy 316.143682 -393.692888)
			(xy 316.685676 -393.692888) (xy 316.685676 -393.69238) (xy 316.686144 -393.668389) (xy 316.693653 -393.620998)
			(xy 316.708482 -393.575365) (xy 316.730267 -393.532614) (xy 316.75847 -393.493796) (xy 316.792399 -393.459868)
			(xy 316.831217 -393.431664) (xy 316.873969 -393.40988) (xy 316.919602 -393.395052) (xy 316.966993 -393.387544)
			(xy 316.990984 -393.387072) (xy 316.991238 -393.387072) (xy 317.015172 -393.387549) (xy 317.062456 -393.395005)
			(xy 317.107999 -393.409744) (xy 317.150686 -393.431406) (xy 317.189472 -393.45946) (xy 317.223407 -393.49322)
			(xy 317.251663 -393.53186) (xy 317.263018 -393.552934) (xy 317.263526 -393.55395) (xy 317.343832 -393.692888)
			(xy 317.885572 -393.692888) (xy 317.885572 -393.69238) (xy 317.886021 -393.668375) (xy 317.893538 -393.620956)
			(xy 317.908383 -393.575298) (xy 317.930191 -393.532526) (xy 317.958425 -393.493694) (xy 317.992388 -393.45976)
			(xy 318.031243 -393.431558) (xy 318.074033 -393.409786) (xy 318.119703 -393.394978) (xy 318.167128 -393.387501)
			(xy 318.191134 -393.387072) (xy 318.215068 -393.387552) (xy 318.262352 -393.395007) (xy 318.307895 -393.409746)
			(xy 318.350581 -393.431407) (xy 318.389367 -393.459461) (xy 318.423303 -393.493221) (xy 318.451559 -393.53186)
			(xy 318.462914 -393.552934) (xy 318.463422 -393.55395) (xy 318.543728 -393.692888) (xy 319.085468 -393.692888)
			(xy 319.085468 -393.69238) (xy 319.085921 -393.668375) (xy 319.093437 -393.620957) (xy 319.108283 -393.575299)
			(xy 319.130091 -393.532527) (xy 319.158324 -393.493696) (xy 319.192286 -393.459761) (xy 319.231141 -393.43156)
			(xy 319.27393 -393.409787) (xy 319.3196 -393.394979) (xy 319.367024 -393.387501) (xy 319.39103 -393.387072)
			(xy 319.391284 -393.387072) (xy 319.41522 -393.387511) (xy 319.462506 -393.394974) (xy 319.508049 -393.40972)
			(xy 319.550736 -393.431388) (xy 319.589521 -393.459448) (xy 319.623456 -393.493214) (xy 319.65171 -393.531858)
			(xy 319.663064 -393.552934) (xy 319.663572 -393.55395) (xy 319.743878 -393.692888) (xy 320.285872 -393.692888)
			(xy 320.285872 -393.69238) (xy 320.286344 -393.668389) (xy 320.293853 -393.620999) (xy 320.308681 -393.575366)
			(xy 320.330466 -393.532615) (xy 320.358669 -393.493797) (xy 320.392597 -393.459869) (xy 320.431415 -393.431666)
			(xy 320.474166 -393.409881) (xy 320.519799 -393.395053) (xy 320.567189 -393.387544) (xy 320.59118 -393.387072)
			(xy 320.615116 -393.387515) (xy 320.662401 -393.394977) (xy 320.707945 -393.409722) (xy 320.750631 -393.43139)
			(xy 320.789417 -393.459449) (xy 320.823352 -393.493214) (xy 320.851606 -393.531858) (xy 320.86296 -393.552934)
			(xy 320.863468 -393.55395) (xy 320.943774 -393.692888) (xy 321.485768 -393.692888) (xy 321.485768 -393.69238)
			(xy 321.486244 -393.668389) (xy 321.493752 -393.620999) (xy 321.508581 -393.575367) (xy 321.530365 -393.532616)
			(xy 321.558568 -393.493799) (xy 321.592496 -393.459871) (xy 321.631313 -393.431667) (xy 321.674063 -393.409883)
			(xy 321.719695 -393.395053) (xy 321.767085 -393.387544) (xy 321.791076 -393.387072) (xy 321.815011 -393.387518)
			(xy 321.862297 -393.39498) (xy 321.90784 -393.409724) (xy 321.950527 -393.431391) (xy 321.989312 -393.45945)
			(xy 322.023247 -393.493215) (xy 322.051501 -393.531858) (xy 322.062856 -393.552934) (xy 322.063364 -393.55395)
			(xy 322.14367 -393.692888) (xy 336.013552 -393.692888) (xy 336.013552 -393.69238) (xy 336.014044 -393.66839)
			(xy 336.021552 -393.621002) (xy 336.03638 -393.575371) (xy 336.058162 -393.532621) (xy 336.086363 -393.493804)
			(xy 336.120289 -393.459876) (xy 336.159104 -393.431673) (xy 336.201852 -393.409887) (xy 336.247482 -393.395057)
			(xy 336.29487 -393.387546) (xy 336.31886 -393.387072) (xy 336.342795 -393.387531) (xy 336.39008 -393.39499)
			(xy 336.435623 -393.409733) (xy 336.47831 -393.431398) (xy 336.517095 -393.459455) (xy 336.551031 -393.493217)
			(xy 336.579285 -393.531859) (xy 336.59064 -393.552934) (xy 336.591148 -393.55395) (xy 336.671454 -393.692888)
			(xy 337.213448 -393.692888) (xy 337.213448 -393.69238) (xy 337.213944 -393.66839) (xy 337.221452 -393.621002)
			(xy 337.236279 -393.575372) (xy 337.258061 -393.532622) (xy 337.286262 -393.493805) (xy 337.320187 -393.459878)
			(xy 337.359001 -393.431674) (xy 337.401749 -393.409888) (xy 337.447379 -393.395057) (xy 337.494766 -393.387546)
			(xy 337.518756 -393.387072) (xy 337.542691 -393.387534) (xy 337.589976 -393.394993) (xy 337.635519 -393.409735)
			(xy 337.678205 -393.431399) (xy 337.716991 -393.459456) (xy 337.750926 -393.493218) (xy 337.779181 -393.531859)
			(xy 337.790536 -393.552934) (xy 337.791044 -393.55395) (xy 337.87135 -393.692888) (xy 338.413344 -393.692888)
			(xy 338.413344 -393.69238) (xy 338.413844 -393.668391) (xy 338.421352 -393.621003) (xy 338.436179 -393.575373)
			(xy 338.457961 -393.532623) (xy 338.486161 -393.493807) (xy 338.520086 -393.459879) (xy 338.558899 -393.431675)
			(xy 338.601647 -393.40989) (xy 338.647276 -393.395058) (xy 338.694663 -393.387546) (xy 338.718652 -393.387072)
			(xy 338.718906 -393.387072) (xy 338.742839 -393.387575) (xy 338.790122 -393.395026) (xy 338.835664 -393.40976)
			(xy 338.878351 -393.431418) (xy 338.917137 -393.459468) (xy 338.951074 -393.493225) (xy 338.97933 -393.531861)
			(xy 338.990686 -393.552934) (xy 338.991194 -393.55395) (xy 339.0715 -393.692888) (xy 339.61324 -393.692888)
			(xy 339.61324 -393.69238) (xy 339.613621 -393.668371) (xy 339.62114 -393.620946) (xy 339.63599 -393.575282)
			(xy 339.657804 -393.532506) (xy 339.686045 -393.493671) (xy 339.720016 -393.459735) (xy 339.758881 -393.431535)
			(xy 339.80168 -393.409766) (xy 339.84736 -393.394965) (xy 339.894793 -393.387496) (xy 339.918802 -393.387072)
			(xy 339.942735 -393.387578) (xy 339.990018 -393.395028) (xy 340.03556 -393.409763) (xy 340.078247 -393.43142)
			(xy 340.117033 -393.459469) (xy 340.15097 -393.493225) (xy 340.179226 -393.531861) (xy 340.190582 -393.552934)
			(xy 340.19109 -393.55395) (xy 340.271396 -393.692888) (xy 340.813136 -393.692888) (xy 340.813136 -393.69238)
			(xy 340.813521 -393.668371) (xy 340.82104 -393.620947) (xy 340.835889 -393.575283) (xy 340.857703 -393.532507)
			(xy 340.885944 -393.493672) (xy 340.919915 -393.459737) (xy 340.958779 -393.431537) (xy 341.001577 -393.409767)
			(xy 341.047256 -393.394965) (xy 341.094689 -393.387496) (xy 341.118698 -393.387072) (xy 341.142634 -393.3875)
			(xy 341.189921 -393.394965) (xy 341.235464 -393.409713) (xy 341.278151 -393.431383) (xy 341.316936 -393.459445)
			(xy 341.35087 -393.493212) (xy 341.379124 -393.531857) (xy 341.390478 -393.552934) (xy 341.390986 -393.55395)
			(xy 341.471292 -393.692888) (xy 342.01354 -393.692888) (xy 342.01354 -393.69238) (xy 342.01392 -393.668384)
			(xy 342.021431 -393.620983) (xy 342.036265 -393.575341) (xy 342.058057 -393.532582) (xy 342.08627 -393.493758)
			(xy 342.12021 -393.459826) (xy 342.15904 -393.431622) (xy 342.201804 -393.409839) (xy 342.247449 -393.395015)
			(xy 342.294852 -393.387515) (xy 342.318848 -393.387072) (xy 342.342783 -393.387541) (xy 342.390067 -393.394998)
			(xy 342.43561 -393.409739) (xy 342.478297 -393.431402) (xy 342.517082 -393.459458) (xy 342.551018 -393.493219)
			(xy 342.579273 -393.531859) (xy 342.590628 -393.552934) (xy 342.591136 -393.55395) (xy 342.671442 -393.692888)
			(xy 343.213436 -393.692888) (xy 343.213436 -393.69238) (xy 343.21382 -393.668384) (xy 343.221331 -393.620984)
			(xy 343.236165 -393.575342) (xy 343.257957 -393.532583) (xy 343.286169 -393.493759) (xy 343.320108 -393.459828)
			(xy 343.358938 -393.431623) (xy 343.401701 -393.40984) (xy 343.447346 -393.395016) (xy 343.494748 -393.387515)
			(xy 343.518744 -393.387072) (xy 343.542678 -393.387544) (xy 343.589963 -393.395001) (xy 343.635506 -393.409741)
			(xy 343.678192 -393.431404) (xy 343.716978 -393.459459) (xy 343.750914 -393.493219) (xy 343.779169 -393.53186)
			(xy 343.790524 -393.552934) (xy 343.791032 -393.55395) (xy 343.871338 -393.692888) (xy 344.413332 -393.692888)
			(xy 344.413332 -393.69238) (xy 344.41372 -393.668384) (xy 344.421231 -393.620984) (xy 344.436065 -393.575343)
			(xy 344.457856 -393.532584) (xy 344.486068 -393.493761) (xy 344.520006 -393.459829) (xy 344.558835 -393.431624)
			(xy 344.601598 -393.409842) (xy 344.647243 -393.395017) (xy 344.694644 -393.387515) (xy 344.71864 -393.387072)
			(xy 344.718894 -393.387072) (xy 344.74283 -393.387503) (xy 344.790116 -393.394968) (xy 344.83566 -393.409715)
			(xy 344.878347 -393.431385) (xy 344.917132 -393.459446) (xy 344.951066 -393.493212) (xy 344.97932 -393.531857)
			(xy 344.990674 -393.552934) (xy 344.991182 -393.55395) (xy 345.071488 -393.692888) (xy 345.613228 -393.692888)
			(xy 345.613228 -393.69238) (xy 345.613621 -393.668372) (xy 345.621139 -393.620948) (xy 345.635988 -393.575285)
			(xy 345.657802 -393.532509) (xy 345.686041 -393.493675) (xy 345.720011 -393.45974) (xy 345.758874 -393.431539)
			(xy 345.801672 -393.40977) (xy 345.84735 -393.394967) (xy 345.894781 -393.387497) (xy 345.91879 -393.387072)
			(xy 345.942726 -393.387506) (xy 345.990012 -393.39497) (xy 346.035556 -393.409717) (xy 346.078242 -393.431386)
			(xy 346.117027 -393.459447) (xy 346.150962 -393.493213) (xy 346.179216 -393.531857) (xy 346.19057 -393.552934)
			(xy 346.191078 -393.55395) (xy 346.271384 -393.692888) (xy 346.813124 -393.692888) (xy 346.813124 -393.69238)
			(xy 346.813521 -393.668372) (xy 346.821039 -393.620948) (xy 346.835888 -393.575286) (xy 346.857701 -393.53251)
			(xy 346.88594 -393.493676) (xy 346.919909 -393.459741) (xy 346.958772 -393.431541) (xy 347.001569 -393.409771)
			(xy 347.047246 -393.394968) (xy 347.094678 -393.387497) (xy 347.118686 -393.387072) (xy 347.142622 -393.38751)
			(xy 347.189908 -393.394973) (xy 347.235451 -393.409719) (xy 347.278138 -393.431388) (xy 347.316923 -393.459448)
			(xy 347.350858 -393.493213) (xy 347.379112 -393.531858) (xy 347.390466 -393.552934) (xy 347.390974 -393.55395)
			(xy 347.47128 -393.692888) (xy 348.013528 -393.692888) (xy 348.013528 -393.69238) (xy 348.01392 -393.668385)
			(xy 348.021431 -393.620985) (xy 348.036264 -393.575344) (xy 348.058055 -393.532585) (xy 348.086267 -393.493762)
			(xy 348.120205 -393.45983) (xy 348.159033 -393.431626) (xy 348.201796 -393.409843) (xy 348.247439 -393.395018)
			(xy 348.29484 -393.387515) (xy 348.318836 -393.387072) (xy 348.34277 -393.38755) (xy 348.390054 -393.395006)
			(xy 348.435597 -393.409745) (xy 348.478284 -393.431407) (xy 348.517069 -393.459461) (xy 348.551005 -393.49322)
			(xy 348.579261 -393.53186) (xy 348.590616 -393.552934) (xy 348.591124 -393.55395) (xy 348.67143 -393.692888)
			(xy 349.213424 -393.692888) (xy 349.213424 -393.69238) (xy 349.21382 -393.668385) (xy 349.221331 -393.620985)
			(xy 349.236164 -393.575345) (xy 349.257954 -393.532586) (xy 349.286166 -393.493764) (xy 349.320103 -393.459832)
			(xy 349.358931 -393.431627) (xy 349.401693 -393.409844) (xy 349.447336 -393.395018) (xy 349.494737 -393.387516)
			(xy 349.518732 -393.387072) (xy 349.542666 -393.387554) (xy 349.58995 -393.395009) (xy 349.635493 -393.409747)
			(xy 349.678179 -393.431408) (xy 349.716965 -393.459462) (xy 349.750901 -393.493221) (xy 349.779157 -393.53186)
			(xy 349.790512 -393.552934) (xy 349.79102 -393.55395) (xy 349.871326 -393.692888) (xy 350.41332 -393.692888)
			(xy 350.41332 -393.69238) (xy 350.41372 -393.668385) (xy 350.42123 -393.620986) (xy 350.436063 -393.575346)
			(xy 350.457854 -393.532588) (xy 350.486065 -393.493765) (xy 350.520001 -393.459833) (xy 350.558829 -393.431629)
			(xy 350.60159 -393.409845) (xy 350.647233 -393.395019) (xy 350.694633 -393.387516) (xy 350.718628 -393.387072)
			(xy 350.718882 -393.387072) (xy 350.742818 -393.387513) (xy 350.790103 -393.394976) (xy 350.835647 -393.409721)
			(xy 350.878334 -393.431389) (xy 350.917119 -393.459449) (xy 350.951054 -393.493214) (xy 350.979308 -393.531858)
			(xy 350.990662 -393.552934) (xy 350.99117 -393.55395) (xy 351.071476 -393.692888) (xy 351.613216 -393.692888)
			(xy 351.613216 -393.69238) (xy 351.613621 -393.668372) (xy 351.621139 -393.620949) (xy 351.635987 -393.575288)
			(xy 351.657799 -393.532513) (xy 351.686038 -393.493679) (xy 351.720006 -393.459744) (xy 351.758867 -393.431543)
			(xy 351.801664 -393.409773) (xy 351.84734 -393.394969) (xy 351.89477 -393.387497) (xy 351.918778 -393.387072)
			(xy 351.942713 -393.387516) (xy 351.989999 -393.394978) (xy 352.035543 -393.409723) (xy 352.078229 -393.431391)
			(xy 352.117015 -393.45945) (xy 352.150949 -393.493214) (xy 352.179204 -393.531858) (xy 352.190558 -393.552934)
			(xy 352.191066 -393.55395) (xy 352.271372 -393.692888) (xy 352.813112 -393.692888) (xy 352.813112 -393.69238)
			(xy 352.813521 -393.668373) (xy 352.821039 -393.62095) (xy 352.835887 -393.575289) (xy 352.857699 -393.532514)
			(xy 352.885937 -393.493681) (xy 352.919904 -393.459745) (xy 352.958765 -393.431545) (xy 353.001561 -393.409774)
			(xy 353.047236 -393.39497) (xy 353.094666 -393.387498) (xy 353.118674 -393.387072) (xy 353.118928 -393.387072)
			(xy 353.142862 -393.387557) (xy 353.190146 -393.395011) (xy 353.235688 -393.409749) (xy 353.278375 -393.43141)
			(xy 353.317161 -393.459463) (xy 353.351097 -393.493222) (xy 353.379353 -393.53186) (xy 353.390708 -393.552934)
			(xy 353.391216 -393.55395) (xy 353.471522 -393.692888) (xy 354.013516 -393.692888) (xy 354.013516 -393.69238)
			(xy 354.01392 -393.668385) (xy 354.02143 -393.620987) (xy 354.036263 -393.575347) (xy 354.058053 -393.532589)
			(xy 354.086263 -393.493766) (xy 354.1202 -393.459835) (xy 354.159026 -393.43163) (xy 354.201787 -393.409846)
			(xy 354.247429 -393.39502) (xy 354.294829 -393.387516) (xy 354.318824 -393.387072) (xy 354.342758 -393.38756)
			(xy 354.390042 -393.395014) (xy 354.435584 -393.409751) (xy 354.478271 -393.431411) (xy 354.517057 -393.459464)
			(xy 354.550993 -393.493222) (xy 354.579249 -393.53186) (xy 354.590604 -393.552934) (xy 354.591112 -393.55395)
			(xy 354.671418 -393.692888) (xy 370.586 -393.692888) (xy 370.586 -393.69238) (xy 370.586444 -393.668388)
			(xy 370.593954 -393.620995) (xy 370.608784 -393.57536) (xy 370.630571 -393.532606) (xy 370.658777 -393.493788)
			(xy 370.692709 -393.459859) (xy 370.73153 -393.431656) (xy 370.774286 -393.409873) (xy 370.819922 -393.395047)
			(xy 370.867316 -393.387542) (xy 370.891308 -393.387072) (xy 370.915241 -393.387573) (xy 370.962524 -393.395024)
			(xy 371.008067 -393.409759) (xy 371.050753 -393.431417) (xy 371.089539 -393.459468) (xy 371.123476 -393.493224)
			(xy 371.151732 -393.531861) (xy 371.163088 -393.552934) (xy 371.163596 -393.55395) (xy 371.243902 -393.692888)
			(xy 371.785896 -393.692888) (xy 371.785896 -393.69238) (xy 371.786344 -393.668388) (xy 371.793853 -393.620995)
			(xy 371.808684 -393.575361) (xy 371.83047 -393.532608) (xy 371.858676 -393.493789) (xy 371.892607 -393.459861)
			(xy 371.931428 -393.431658) (xy 371.974183 -393.409875) (xy 372.019819 -393.395048) (xy 372.067212 -393.387542)
			(xy 372.091204 -393.387072) (xy 372.115137 -393.387576) (xy 372.16242 -393.395027) (xy 372.207962 -393.409762)
			(xy 372.250649 -393.431419) (xy 372.289435 -393.459469) (xy 372.323372 -393.493225) (xy 372.351628 -393.531861)
			(xy 372.362984 -393.552934) (xy 372.363492 -393.55395) (xy 372.443798 -393.692888) (xy 372.985792 -393.692888)
			(xy 372.985792 -393.69238) (xy 372.986244 -393.668388) (xy 372.993753 -393.620996) (xy 373.008583 -393.575362)
			(xy 373.030369 -393.532609) (xy 373.058575 -393.49379) (xy 373.092506 -393.459862) (xy 373.131326 -393.431659)
			(xy 373.17408 -393.409876) (xy 373.219715 -393.395049) (xy 373.267108 -393.387543) (xy 373.2911 -393.387072)
			(xy 373.315033 -393.38758) (xy 373.362316 -393.39503) (xy 373.407858 -393.409764) (xy 373.450544 -393.43142)
			(xy 373.489331 -393.45947) (xy 373.523268 -393.493226) (xy 373.551524 -393.531862) (xy 373.56288 -393.552934)
			(xy 373.563388 -393.55395) (xy 373.643694 -393.692888) (xy 374.185688 -393.692888) (xy 374.185688 -393.69238)
			(xy 374.186121 -393.668374) (xy 374.193638 -393.620954) (xy 374.208485 -393.575294) (xy 374.230294 -393.532521)
			(xy 374.25853 -393.493689) (xy 374.292494 -393.459754) (xy 374.331352 -393.431553) (xy 374.374144 -393.409781)
			(xy 374.419817 -393.394975) (xy 374.467243 -393.3875) (xy 374.49125 -393.387072) (xy 374.515185 -393.387539)
			(xy 374.562469 -393.394997) (xy 374.608012 -393.409738) (xy 374.650699 -393.431401) (xy 374.689484 -393.459457)
			(xy 374.72342 -393.493218) (xy 374.751675 -393.531859) (xy 374.76303 -393.552934) (xy 374.763538 -393.55395)
			(xy 374.843844 -393.692888) (xy 375.385584 -393.692888) (xy 375.385584 -393.69238) (xy 375.386021 -393.668374)
			(xy 375.393538 -393.620954) (xy 375.408384 -393.575295) (xy 375.430194 -393.532522) (xy 375.458428 -393.49369)
			(xy 375.492393 -393.459755) (xy 375.53125 -393.431554) (xy 375.574041 -393.409782) (xy 375.619713 -393.394976)
			(xy 375.66714 -393.3875) (xy 375.691146 -393.387072) (xy 375.715081 -393.387542) (xy 375.762365 -393.394999)
			(xy 375.807908 -393.40974) (xy 375.850594 -393.431403) (xy 375.88938 -393.459458) (xy 375.923316 -393.493219)
			(xy 375.951571 -393.531859) (xy 375.962926 -393.552934) (xy 375.963434 -393.55395) (xy 376.04374 -393.692888)
			(xy 376.585988 -393.692888) (xy 376.585988 -393.69238) (xy 376.586444 -393.668388) (xy 376.593953 -393.620996)
			(xy 376.608783 -393.575362) (xy 376.630569 -393.53261) (xy 376.658774 -393.493792) (xy 376.692704 -393.459863)
			(xy 376.731524 -393.43166) (xy 376.774277 -393.409877) (xy 376.819912 -393.395049) (xy 376.867304 -393.387543)
			(xy 376.891296 -393.387072) (xy 376.915232 -393.387502) (xy 376.962518 -393.394966) (xy 377.008062 -393.409714)
			(xy 377.050749 -393.431384) (xy 377.089534 -393.459445) (xy 377.123468 -393.493212) (xy 377.151722 -393.531857)
			(xy 377.163076 -393.552934) (xy 377.163584 -393.55395) (xy 377.24389 -393.692888) (xy 377.785884 -393.692888)
			(xy 377.785884 -393.69238) (xy 377.786344 -393.668389) (xy 377.793853 -393.620997) (xy 377.808683 -393.575363)
			(xy 377.830468 -393.532611) (xy 377.858673 -393.493793) (xy 377.892602 -393.459865) (xy 377.931421 -393.431662)
			(xy 377.974174 -393.409878) (xy 378.019809 -393.39505) (xy 378.067201 -393.387543) (xy 378.091192 -393.387072)
			(xy 378.115128 -393.387505) (xy 378.162414 -393.394969) (xy 378.207958 -393.409716) (xy 378.250644 -393.431385)
			(xy 378.28943 -393.459446) (xy 378.323364 -393.493212) (xy 378.351618 -393.531857) (xy 378.362972 -393.552934)
			(xy 378.36348 -393.55395) (xy 378.443786 -393.692888) (xy 378.98578 -393.692888) (xy 378.98578 -393.69238)
			(xy 378.986244 -393.668389) (xy 378.993753 -393.620998) (xy 379.008582 -393.575364) (xy 379.030367 -393.532612)
			(xy 379.058571 -393.493795) (xy 379.092501 -393.459866) (xy 379.131319 -393.431663) (xy 379.174072 -393.409879)
			(xy 379.219705 -393.395051) (xy 379.267097 -393.387543) (xy 379.291088 -393.387072) (xy 379.315024 -393.387508)
			(xy 379.36231 -393.394972) (xy 379.407853 -393.409718) (xy 379.45054 -393.431387) (xy 379.489325 -393.459447)
			(xy 379.52326 -393.493213) (xy 379.551514 -393.531858) (xy 379.562868 -393.552934) (xy 379.563376 -393.55395)
			(xy 379.643682 -393.692888) (xy 380.185676 -393.692888) (xy 380.185676 -393.69238) (xy 380.186121 -393.668374)
			(xy 380.193638 -393.620955) (xy 380.208483 -393.575297) (xy 380.230292 -393.532525) (xy 380.258526 -393.493693)
			(xy 380.292489 -393.459758) (xy 380.331345 -393.431557) (xy 380.374136 -393.409785) (xy 380.419807 -393.394977)
			(xy 380.467232 -393.3875) (xy 380.491238 -393.387072) (xy 380.515172 -393.387549) (xy 380.562456 -393.395005)
			(xy 380.607999 -393.409744) (xy 380.650686 -393.431406) (xy 380.689472 -393.45946) (xy 380.723407 -393.49322)
			(xy 380.751663 -393.53186) (xy 380.763018 -393.552934) (xy 380.763526 -393.55395) (xy 380.843832 -393.692888)
			(xy 381.385572 -393.692888) (xy 381.385572 -393.69238) (xy 381.386021 -393.668375) (xy 381.393538 -393.620956)
			(xy 381.408383 -393.575298) (xy 381.430191 -393.532526) (xy 381.458425 -393.493694) (xy 381.492388 -393.45976)
			(xy 381.531243 -393.431558) (xy 381.574033 -393.409786) (xy 381.619703 -393.394978) (xy 381.667128 -393.387501)
			(xy 381.691134 -393.387072) (xy 381.715068 -393.387552) (xy 381.762352 -393.395007) (xy 381.807895 -393.409746)
			(xy 381.850581 -393.431407) (xy 381.889367 -393.459461) (xy 381.923303 -393.493221) (xy 381.951559 -393.53186)
			(xy 381.962914 -393.552934) (xy 381.963422 -393.55395) (xy 382.043728 -393.692888) (xy 382.585976 -393.692888)
			(xy 382.585976 -393.69238) (xy 382.586444 -393.668389) (xy 382.593953 -393.620998) (xy 382.608782 -393.575365)
			(xy 382.630567 -393.532614) (xy 382.65877 -393.493796) (xy 382.692699 -393.459868) (xy 382.731517 -393.431664)
			(xy 382.774269 -393.40988) (xy 382.819902 -393.395052) (xy 382.867293 -393.387544) (xy 382.891284 -393.387072)
			(xy 382.91522 -393.387511) (xy 382.962506 -393.394974) (xy 383.008049 -393.40972) (xy 383.050736 -393.431388)
			(xy 383.089521 -393.459448) (xy 383.123456 -393.493214) (xy 383.15171 -393.531858) (xy 383.163064 -393.552934)
			(xy 383.163572 -393.55395) (xy 383.243878 -393.692888) (xy 383.785872 -393.692888) (xy 383.785872 -393.69238)
			(xy 383.786344 -393.668389) (xy 383.793853 -393.620999) (xy 383.808681 -393.575366) (xy 383.830466 -393.532615)
			(xy 383.858669 -393.493797) (xy 383.892597 -393.459869) (xy 383.931415 -393.431666) (xy 383.974166 -393.409881)
			(xy 384.019799 -393.395053) (xy 384.067189 -393.387544) (xy 384.09118 -393.387072) (xy 384.115116 -393.387515)
			(xy 384.162401 -393.394977) (xy 384.207945 -393.409722) (xy 384.250631 -393.43139) (xy 384.289417 -393.459449)
			(xy 384.323352 -393.493214) (xy 384.351606 -393.531858) (xy 384.36296 -393.552934) (xy 384.363468 -393.55395)
			(xy 384.443774 -393.692888) (xy 384.985768 -393.692888) (xy 384.985768 -393.69238) (xy 384.986244 -393.668389)
			(xy 384.993752 -393.620999) (xy 385.008581 -393.575367) (xy 385.030365 -393.532616) (xy 385.058568 -393.493799)
			(xy 385.092496 -393.459871) (xy 385.131313 -393.431667) (xy 385.174063 -393.409883) (xy 385.219695 -393.395053)
			(xy 385.267085 -393.387544) (xy 385.291076 -393.387072) (xy 385.315011 -393.387518) (xy 385.362297 -393.39498)
			(xy 385.40784 -393.409724) (xy 385.450527 -393.431391) (xy 385.489312 -393.45945) (xy 385.523247 -393.493215)
			(xy 385.551501 -393.531858) (xy 385.562856 -393.552934) (xy 385.563364 -393.55395) (xy 385.64367 -393.692888)
			(xy 386.185664 -393.692888) (xy 386.185664 -393.69238) (xy 386.186121 -393.668375) (xy 386.193637 -393.620957)
			(xy 386.208482 -393.5753) (xy 386.23029 -393.532528) (xy 386.258522 -393.493697) (xy 386.292484 -393.459762)
			(xy 386.331339 -393.431561) (xy 386.374127 -393.409788) (xy 386.419797 -393.39498) (xy 386.467221 -393.387501)
			(xy 386.491226 -393.387072) (xy 386.51516 -393.387558) (xy 386.562444 -393.395013) (xy 386.607986 -393.40975)
			(xy 386.650673 -393.43141) (xy 386.689459 -393.459463) (xy 386.723395 -393.493222) (xy 386.751651 -393.53186)
			(xy 386.763006 -393.552934) (xy 386.763514 -393.55395) (xy 386.84382 -393.692888) (xy 387.38556 -393.692888)
			(xy 387.38556 -393.69238) (xy 387.386021 -393.668375) (xy 387.393537 -393.620958) (xy 387.408382 -393.575301)
			(xy 387.430189 -393.53253) (xy 387.458421 -393.493698) (xy 387.492383 -393.459764) (xy 387.531236 -393.431563)
			(xy 387.574025 -393.409789) (xy 387.619693 -393.394981) (xy 387.667117 -393.387502) (xy 387.691122 -393.387072)
			(xy 387.715056 -393.387562) (xy 387.762339 -393.395015) (xy 387.807882 -393.409752) (xy 387.850568 -393.431412)
			(xy 387.889354 -393.459464) (xy 387.923291 -393.493222) (xy 387.951547 -393.531861) (xy 387.962902 -393.552934)
			(xy 387.96341 -393.55395) (xy 388.043716 -393.692888) (xy 388.585964 -393.692888) (xy 388.585964 -393.69238)
			(xy 388.586444 -393.66839) (xy 388.593952 -393.621) (xy 388.608781 -393.575368) (xy 388.630564 -393.532617)
			(xy 388.658767 -393.4938) (xy 388.692694 -393.459872) (xy 388.73151 -393.431668) (xy 388.774261 -393.409884)
			(xy 388.819892 -393.395054) (xy 388.867282 -393.387545) (xy 388.891272 -393.387072) (xy 388.915207 -393.387521)
			(xy 388.962493 -393.394982) (xy 389.008036 -393.409727) (xy 389.050723 -393.431393) (xy 389.089508 -393.459451)
			(xy 389.123443 -393.493215) (xy 389.151697 -393.531858) (xy 389.163052 -393.552934) (xy 389.16356 -393.55395)
			(xy 389.243866 -393.692888) (xy 403.113748 -393.692888) (xy 403.113748 -393.69238) (xy 403.114244 -393.66839)
			(xy 403.121752 -393.621002) (xy 403.136579 -393.575372) (xy 403.158361 -393.532622) (xy 403.186562 -393.493805)
			(xy 403.220487 -393.459878) (xy 403.259301 -393.431674) (xy 403.302049 -393.409888) (xy 403.347679 -393.395057)
			(xy 403.395066 -393.387546) (xy 403.419056 -393.387072) (xy 403.442991 -393.387534) (xy 403.490276 -393.394993)
			(xy 403.535819 -393.409735) (xy 403.578505 -393.431399) (xy 403.617291 -393.459456) (xy 403.651226 -393.493218)
			(xy 403.679481 -393.531859) (xy 403.690836 -393.552934) (xy 403.691344 -393.55395) (xy 403.77165 -393.692888)
			(xy 404.313644 -393.692888) (xy 404.313644 -393.69238) (xy 404.314144 -393.668391) (xy 404.321652 -393.621003)
			(xy 404.336479 -393.575373) (xy 404.358261 -393.532623) (xy 404.386461 -393.493807) (xy 404.420386 -393.459879)
			(xy 404.459199 -393.431675) (xy 404.501947 -393.40989) (xy 404.547576 -393.395058) (xy 404.594963 -393.387546)
			(xy 404.618952 -393.387072) (xy 404.642887 -393.387537) (xy 404.690171 -393.394995) (xy 404.735714 -393.409737)
			(xy 404.778401 -393.431401) (xy 404.817187 -393.459457) (xy 404.851122 -393.493218) (xy 404.879377 -393.531859)
			(xy 404.890732 -393.552934) (xy 404.89124 -393.55395) (xy 404.971546 -393.692888) (xy 405.51354 -393.692888)
			(xy 405.51354 -393.69238) (xy 405.51392 -393.668384) (xy 405.521431 -393.620983) (xy 405.536265 -393.575341)
			(xy 405.558057 -393.532582) (xy 405.58627 -393.493758) (xy 405.62021 -393.459826) (xy 405.65904 -393.431622)
			(xy 405.701804 -393.409839) (xy 405.747449 -393.395015) (xy 405.794852 -393.387515) (xy 405.818848 -393.387072)
			(xy 405.842783 -393.387541) (xy 405.890067 -393.394998) (xy 405.93561 -393.409739) (xy 405.978297 -393.431402)
			(xy 406.017082 -393.459458) (xy 406.051018 -393.493219) (xy 406.079273 -393.531859) (xy 406.090628 -393.552934)
			(xy 406.091136 -393.55395) (xy 406.171442 -393.692888) (xy 406.713436 -393.692888) (xy 406.713436 -393.69238)
			(xy 406.713821 -393.668371) (xy 406.72134 -393.620947) (xy 406.736189 -393.575283) (xy 406.758003 -393.532507)
			(xy 406.786244 -393.493672) (xy 406.820215 -393.459737) (xy 406.859079 -393.431537) (xy 406.901877 -393.409767)
			(xy 406.947556 -393.394965) (xy 406.994989 -393.387496) (xy 407.018998 -393.387072) (xy 407.042934 -393.3875)
			(xy 407.090221 -393.394965) (xy 407.135764 -393.409713) (xy 407.178451 -393.431383) (xy 407.217236 -393.459445)
			(xy 407.25117 -393.493212) (xy 407.279424 -393.531857) (xy 407.290778 -393.552934) (xy 407.291286 -393.55395)
			(xy 407.371592 -393.692888) (xy 407.913332 -393.692888) (xy 407.913332 -393.69238) (xy 407.913721 -393.668372)
			(xy 407.92124 -393.620947) (xy 407.936089 -393.575284) (xy 407.957902 -393.532508) (xy 407.986142 -393.493674)
			(xy 408.020113 -393.459738) (xy 408.058976 -393.431538) (xy 408.101775 -393.409769) (xy 408.147453 -393.394966)
			(xy 408.194885 -393.387496) (xy 408.218894 -393.387072) (xy 408.24283 -393.387503) (xy 408.290116 -393.394968)
			(xy 408.33566 -393.409715) (xy 408.378347 -393.431385) (xy 408.417132 -393.459446) (xy 408.451066 -393.493212)
			(xy 408.47932 -393.531857) (xy 408.490674 -393.552934) (xy 408.491182 -393.55395) (xy 408.571488 -393.692888)
			(xy 409.113736 -393.692888) (xy 409.113736 -393.69238) (xy 409.11412 -393.668384) (xy 409.121631 -393.620984)
			(xy 409.136465 -393.575342) (xy 409.158257 -393.532583) (xy 409.186469 -393.493759) (xy 409.220408 -393.459828)
			(xy 409.259238 -393.431623) (xy 409.302001 -393.40984) (xy 409.347646 -393.395016) (xy 409.395048 -393.387515)
			(xy 409.419044 -393.387072) (xy 409.442978 -393.387544) (xy 409.490263 -393.395001) (xy 409.535806 -393.409741)
			(xy 409.578492 -393.431404) (xy 409.617278 -393.459459) (xy 409.651214 -393.493219) (xy 409.679469 -393.53186)
			(xy 409.690824 -393.552934) (xy 409.691332 -393.55395) (xy 409.771638 -393.692888) (xy 410.313632 -393.692888)
			(xy 410.313632 -393.69238) (xy 410.31402 -393.668384) (xy 410.321531 -393.620984) (xy 410.336365 -393.575343)
			(xy 410.358156 -393.532584) (xy 410.386368 -393.493761) (xy 410.420306 -393.459829) (xy 410.459135 -393.431624)
			(xy 410.501898 -393.409842) (xy 410.547543 -393.395017) (xy 410.594944 -393.387515) (xy 410.61894 -393.387072)
			(xy 410.642874 -393.387547) (xy 410.690159 -393.395003) (xy 410.735701 -393.409743) (xy 410.778388 -393.431405)
			(xy 410.817174 -393.45946) (xy 410.85111 -393.49322) (xy 410.879365 -393.53186) (xy 410.89072 -393.552934)
			(xy 410.891228 -393.55395) (xy 410.971534 -393.692888) (xy 411.513528 -393.692888) (xy 411.513528 -393.69238)
			(xy 411.51392 -393.668385) (xy 411.521431 -393.620985) (xy 411.536264 -393.575344) (xy 411.558055 -393.532585)
			(xy 411.586267 -393.493762) (xy 411.620205 -393.45983) (xy 411.659033 -393.431626) (xy 411.701796 -393.409843)
			(xy 411.747439 -393.395018) (xy 411.79484 -393.387515) (xy 411.818836 -393.387072) (xy 411.84277 -393.38755)
			(xy 411.890054 -393.395006) (xy 411.935597 -393.409745) (xy 411.978284 -393.431407) (xy 412.017069 -393.459461)
			(xy 412.051005 -393.49322) (xy 412.079261 -393.53186) (xy 412.090616 -393.552934) (xy 412.091124 -393.55395)
			(xy 412.17143 -393.692888) (xy 412.713424 -393.692888) (xy 412.713424 -393.69238) (xy 412.713821 -393.668372)
			(xy 412.721339 -393.620948) (xy 412.736188 -393.575286) (xy 412.758001 -393.53251) (xy 412.78624 -393.493676)
			(xy 412.820209 -393.459741) (xy 412.859072 -393.431541) (xy 412.901869 -393.409771) (xy 412.947546 -393.394968)
			(xy 412.994978 -393.387497) (xy 413.018986 -393.387072) (xy 413.042922 -393.38751) (xy 413.090208 -393.394973)
			(xy 413.135751 -393.409719) (xy 413.178438 -393.431388) (xy 413.217223 -393.459448) (xy 413.251158 -393.493213)
			(xy 413.279412 -393.531858) (xy 413.290766 -393.552934) (xy 413.291274 -393.55395) (xy 413.37158 -393.692888)
			(xy 413.91332 -393.692888) (xy 413.91332 -393.69238) (xy 413.913721 -393.668372) (xy 413.921239 -393.620949)
			(xy 413.936088 -393.575287) (xy 413.9579 -393.532512) (xy 413.986139 -393.493678) (xy 414.020108 -393.459742)
			(xy 414.05897 -393.431542) (xy 414.101766 -393.409772) (xy 414.147443 -393.394969) (xy 414.194874 -393.387497)
			(xy 414.218882 -393.387072) (xy 414.242818 -393.387513) (xy 414.290103 -393.394976) (xy 414.335647 -393.409721)
			(xy 414.378334 -393.431389) (xy 414.417119 -393.459449) (xy 414.451054 -393.493214) (xy 414.479308 -393.531858)
			(xy 414.490662 -393.552934) (xy 414.49117 -393.55395) (xy 414.571476 -393.692888) (xy 415.113724 -393.692888)
			(xy 415.113724 -393.69238) (xy 415.11412 -393.668385) (xy 415.121631 -393.620985) (xy 415.136464 -393.575345)
			(xy 415.158254 -393.532586) (xy 415.186466 -393.493764) (xy 415.220403 -393.459832) (xy 415.259231 -393.431627)
			(xy 415.301993 -393.409844) (xy 415.347636 -393.395018) (xy 415.395037 -393.387516) (xy 415.419032 -393.387072)
			(xy 415.442966 -393.387554) (xy 415.49025 -393.395009) (xy 415.535793 -393.409747) (xy 415.578479 -393.431408)
			(xy 415.617265 -393.459462) (xy 415.651201 -393.493221) (xy 415.679457 -393.53186) (xy 415.690812 -393.552934)
			(xy 415.69132 -393.55395) (xy 415.771626 -393.692888) (xy 416.31362 -393.692888) (xy 416.31362 -393.69238)
			(xy 416.31402 -393.668385) (xy 416.32153 -393.620986) (xy 416.336363 -393.575346) (xy 416.358154 -393.532588)
			(xy 416.386365 -393.493765) (xy 416.420301 -393.459833) (xy 416.459129 -393.431629) (xy 416.50189 -393.409845)
			(xy 416.547533 -393.395019) (xy 416.594933 -393.387516) (xy 416.618928 -393.387072) (xy 416.642862 -393.387557)
			(xy 416.690146 -393.395011) (xy 416.735688 -393.409749) (xy 416.778375 -393.43141) (xy 416.817161 -393.459463)
			(xy 416.851097 -393.493222) (xy 416.879353 -393.53186) (xy 416.890708 -393.552934) (xy 416.891216 -393.55395)
			(xy 416.971522 -393.692888) (xy 417.513516 -393.692888) (xy 417.513516 -393.69238) (xy 417.51392 -393.668385)
			(xy 417.52143 -393.620987) (xy 417.536263 -393.575347) (xy 417.558053 -393.532589) (xy 417.586263 -393.493766)
			(xy 417.6202 -393.459835) (xy 417.659026 -393.43163) (xy 417.701787 -393.409846) (xy 417.747429 -393.39502)
			(xy 417.794829 -393.387516) (xy 417.818824 -393.387072) (xy 417.842758 -393.38756) (xy 417.890042 -393.395014)
			(xy 417.935584 -393.409751) (xy 417.978271 -393.431411) (xy 418.017057 -393.459464) (xy 418.050993 -393.493222)
			(xy 418.079249 -393.53186) (xy 418.090604 -393.552934) (xy 418.091112 -393.55395) (xy 418.171418 -393.692888)
			(xy 418.713412 -393.692888) (xy 418.713412 -393.69238) (xy 418.713821 -393.668373) (xy 418.721339 -393.62095)
			(xy 418.736187 -393.575289) (xy 418.757999 -393.532514) (xy 418.786237 -393.493681) (xy 418.820204 -393.459745)
			(xy 418.859065 -393.431545) (xy 418.901861 -393.409774) (xy 418.947536 -393.39497) (xy 418.994966 -393.387498)
			(xy 419.018974 -393.387072) (xy 419.042909 -393.387519) (xy 419.090195 -393.394981) (xy 419.135738 -393.409726)
			(xy 419.178425 -393.431392) (xy 419.21721 -393.459451) (xy 419.251145 -393.493215) (xy 419.279399 -393.531858)
			(xy 419.290754 -393.552934) (xy 419.291262 -393.55395) (xy 419.371568 -393.692888) (xy 419.913308 -393.692888)
			(xy 419.913308 -393.69238) (xy 419.913721 -393.668373) (xy 419.921239 -393.620951) (xy 419.936087 -393.57529)
			(xy 419.957898 -393.532515) (xy 419.986135 -393.493682) (xy 420.020103 -393.459747) (xy 420.058963 -393.431546)
			(xy 420.101758 -393.409775) (xy 420.147433 -393.394971) (xy 420.194862 -393.387498) (xy 420.21887 -393.387072)
			(xy 420.242805 -393.387523) (xy 420.290091 -393.394984) (xy 420.335634 -393.409728) (xy 420.378321 -393.431394)
			(xy 420.417106 -393.459452) (xy 420.451041 -393.493216) (xy 420.479295 -393.531858) (xy 420.49065 -393.552934)
			(xy 420.491158 -393.55395) (xy 420.571464 -393.692888) (xy 421.113712 -393.692888) (xy 421.113712 -393.69238)
			(xy 421.114144 -393.668387) (xy 421.121654 -393.620993) (xy 421.136485 -393.575357) (xy 421.158273 -393.532603)
			(xy 421.186481 -393.493784) (xy 421.220414 -393.459855) (xy 421.259237 -393.431652) (xy 421.301994 -393.40987)
			(xy 421.347632 -393.395045) (xy 421.395027 -393.387541) (xy 421.41902 -393.387072) (xy 421.442954 -393.387563)
			(xy 421.490237 -393.395017) (xy 421.53578 -393.409753) (xy 421.578466 -393.431413) (xy 421.617252 -393.459465)
			(xy 421.651189 -393.493223) (xy 421.679444 -393.531861) (xy 421.6908 -393.552934) (xy 421.691308 -393.55395)
			(xy 422.083738 -394.232892) (xy 422.096563 -394.256225) (xy 422.114783 -394.306247) (xy 422.124043 -394.358673)
			(xy 422.124632 -394.385292) (xy 422.124154 -394.409296) (xy 422.116641 -394.456714) (xy 422.101799 -394.502371)
			(xy 422.079995 -394.545143) (xy 422.051765 -394.583974) (xy 422.017805 -394.617909) (xy 421.978953 -394.646111)
			(xy 421.936165 -394.667885) (xy 421.890498 -394.682693) (xy 421.843075 -394.690171) (xy 421.81907 -394.6906)
			(xy 421.795495 -394.69023) (xy 421.748906 -394.682984) (xy 421.703987 -394.668654) (xy 421.661808 -394.647582)
			(xy 421.623376 -394.620268) (xy 421.589605 -394.587365) (xy 421.5613 -394.549657) (xy 421.54983 -394.529056)
			(xy 421.549322 -394.528294) (xy 421.151558 -393.839954) (xy 421.139699 -393.817269) (xy 421.122842 -393.76894)
			(xy 421.114262 -393.71848) (xy 421.113712 -393.692888) (xy 420.571464 -393.692888) (xy 420.883588 -394.232892)
			(xy 420.896337 -394.256249) (xy 420.914447 -394.306281) (xy 420.92365 -394.358688) (xy 420.924228 -394.385292)
			(xy 420.92373 -394.409282) (xy 420.916226 -394.456672) (xy 420.901401 -394.502304) (xy 420.87962 -394.545055)
			(xy 420.85142 -394.583873) (xy 420.817494 -394.617801) (xy 420.778679 -394.646005) (xy 420.73593 -394.66779)
			(xy 420.690299 -394.682619) (xy 420.64291 -394.690128) (xy 420.61892 -394.6906) (xy 420.595347 -394.69019)
			(xy 420.548759 -394.682952) (xy 420.503841 -394.668629) (xy 420.461662 -394.647563) (xy 420.423229 -394.620256)
			(xy 420.389457 -394.587358) (xy 420.361151 -394.549655) (xy 420.34968 -394.529056) (xy 420.349172 -394.528294)
			(xy 419.951408 -393.839954) (xy 419.939474 -393.817295) (xy 419.922543 -393.768965) (xy 419.913891 -393.718491)
			(xy 419.913308 -393.692888) (xy 419.371568 -393.692888) (xy 419.683692 -394.232892) (xy 419.696442 -394.256249)
			(xy 419.714551 -394.306281) (xy 419.723754 -394.358688) (xy 419.724332 -394.385292) (xy 419.72383 -394.409282)
			(xy 419.716326 -394.456671) (xy 419.701501 -394.502303) (xy 419.679721 -394.545054) (xy 419.651521 -394.583871)
			(xy 419.617596 -394.6178) (xy 419.578781 -394.646004) (xy 419.536032 -394.667789) (xy 419.490402 -394.682618)
			(xy 419.443014 -394.690128) (xy 419.419024 -394.6906) (xy 419.395451 -394.690187) (xy 419.348863 -394.682949)
			(xy 419.303945 -394.668627) (xy 419.261767 -394.647561) (xy 419.223333 -394.620255) (xy 419.189561 -394.587358)
			(xy 419.161255 -394.549655) (xy 419.149784 -394.529056) (xy 419.149276 -394.528294) (xy 418.751512 -393.839954)
			(xy 418.739579 -393.817295) (xy 418.722647 -393.768965) (xy 418.713995 -393.718491) (xy 418.713412 -393.692888)
			(xy 418.171418 -393.692888) (xy 418.483542 -394.232892) (xy 418.496367 -394.256224) (xy 418.514587 -394.306247)
			(xy 418.523847 -394.358673) (xy 418.524436 -394.385292) (xy 418.523954 -394.409296) (xy 418.516441 -394.456713)
			(xy 418.5016 -394.50237) (xy 418.479796 -394.545141) (xy 418.451566 -394.583973) (xy 418.417607 -394.617908)
			(xy 418.378755 -394.64611) (xy 418.335968 -394.667883) (xy 418.290301 -394.682692) (xy 418.242879 -394.690171)
			(xy 418.218874 -394.6906) (xy 418.195299 -394.690227) (xy 418.14871 -394.682982) (xy 418.103791 -394.668652)
			(xy 418.061613 -394.64758) (xy 418.02318 -394.620267) (xy 417.989409 -394.587365) (xy 417.961104 -394.549657)
			(xy 417.949634 -394.529056) (xy 417.949126 -394.528294) (xy 417.551362 -393.839954) (xy 417.539504 -393.817268)
			(xy 417.522646 -393.76894) (xy 417.514066 -393.71848) (xy 417.513516 -393.692888) (xy 416.971522 -393.692888)
			(xy 417.283646 -394.232892) (xy 417.296471 -394.256224) (xy 417.314691 -394.306247) (xy 417.323951 -394.358673)
			(xy 417.32454 -394.385292) (xy 417.324054 -394.409296) (xy 417.316541 -394.456713) (xy 417.3017 -394.502369)
			(xy 417.279896 -394.54514) (xy 417.251667 -394.583972) (xy 417.217709 -394.617907) (xy 417.178857 -394.646108)
			(xy 417.136071 -394.667882) (xy 417.090404 -394.682691) (xy 417.042982 -394.69017) (xy 417.018978 -394.6906)
			(xy 416.995403 -394.690224) (xy 416.948814 -394.682979) (xy 416.903895 -394.66865) (xy 416.861717 -394.647579)
			(xy 416.823284 -394.620266) (xy 416.789513 -394.587364) (xy 416.761208 -394.549657) (xy 416.749738 -394.529056)
			(xy 416.74923 -394.528294) (xy 416.351466 -393.839954) (xy 416.339608 -393.817268) (xy 416.32275 -393.76894)
			(xy 416.31417 -393.71848) (xy 416.31362 -393.692888) (xy 415.771626 -393.692888) (xy 416.08375 -394.232892)
			(xy 416.096576 -394.256224) (xy 416.114795 -394.306247) (xy 416.124055 -394.358673) (xy 416.124644 -394.385292)
			(xy 416.124154 -394.409296) (xy 416.116641 -394.456712) (xy 416.101801 -394.502368) (xy 416.079997 -394.545139)
			(xy 416.051769 -394.58397) (xy 416.01781 -394.617905) (xy 415.97896 -394.646107) (xy 415.936174 -394.667881)
			(xy 415.890507 -394.68269) (xy 415.843086 -394.69017) (xy 415.819082 -394.6906) (xy 415.795507 -394.690221)
			(xy 415.748919 -394.682977) (xy 415.704 -394.668648) (xy 415.661821 -394.647577) (xy 415.623388 -394.620265)
			(xy 415.589617 -394.587364) (xy 415.561312 -394.549657) (xy 415.549842 -394.529056) (xy 415.549334 -394.528294)
			(xy 415.15157 -393.839954) (xy 415.139712 -393.817268) (xy 415.122855 -393.768939) (xy 415.114274 -393.71848)
			(xy 415.113724 -393.692888) (xy 414.571476 -393.692888) (xy 414.8836 -394.232892) (xy 414.89635 -394.256249)
			(xy 414.91446 -394.306281) (xy 414.923662 -394.358688) (xy 414.92424 -394.385292) (xy 414.92373 -394.409281)
			(xy 414.916226 -394.45667) (xy 414.901402 -394.502301) (xy 414.879622 -394.545051) (xy 414.851423 -394.583869)
			(xy 414.817499 -394.617797) (xy 414.778686 -394.646001) (xy 414.735938 -394.667787) (xy 414.690309 -394.682617)
			(xy 414.642921 -394.690127) (xy 414.618932 -394.6906) (xy 414.595359 -394.69018) (xy 414.548772 -394.682944)
			(xy 414.503854 -394.668623) (xy 414.461675 -394.647558) (xy 414.423242 -394.620253) (xy 414.38947 -394.587357)
			(xy 414.361163 -394.549654) (xy 414.349692 -394.529056) (xy 414.349184 -394.528294) (xy 413.95142 -393.839954)
			(xy 413.939487 -393.817294) (xy 413.922556 -393.768965) (xy 413.913903 -393.718491) (xy 413.91332 -393.692888)
			(xy 413.37158 -393.692888) (xy 413.683704 -394.232892) (xy 413.696455 -394.256249) (xy 413.714564 -394.306281)
			(xy 413.723766 -394.358688) (xy 413.724344 -394.385292) (xy 413.72383 -394.409281) (xy 413.716326 -394.456669)
			(xy 413.701502 -394.5023) (xy 413.679723 -394.54505) (xy 413.651524 -394.583867) (xy 413.617601 -394.617796)
			(xy 413.578788 -394.646) (xy 413.536041 -394.667785) (xy 413.490412 -394.682616) (xy 413.443025 -394.690127)
			(xy 413.419036 -394.6906) (xy 413.395463 -394.690177) (xy 413.348876 -394.682941) (xy 413.303958 -394.668621)
			(xy 413.26178 -394.647557) (xy 413.223346 -394.620252) (xy 413.189574 -394.587356) (xy 413.161267 -394.549654)
			(xy 413.149796 -394.529056) (xy 413.149288 -394.528294) (xy 412.751524 -393.839954) (xy 412.739592 -393.817294)
			(xy 412.72266 -393.768965) (xy 412.714007 -393.718491) (xy 412.713424 -393.692888) (xy 412.17143 -393.692888)
			(xy 412.483554 -394.232892) (xy 412.49638 -394.256224) (xy 412.514599 -394.306247) (xy 412.523859 -394.358673)
			(xy 412.524448 -394.385292) (xy 412.523954 -394.409296) (xy 412.516441 -394.456711) (xy 412.501601 -394.502367)
			(xy 412.479798 -394.545138) (xy 412.45157 -394.583969) (xy 412.417612 -394.617904) (xy 412.378762 -394.646106)
			(xy 412.335977 -394.66788) (xy 412.290311 -394.68269) (xy 412.24289 -394.69017) (xy 412.218886 -394.6906)
			(xy 412.195312 -394.690217) (xy 412.148723 -394.682974) (xy 412.103804 -394.668646) (xy 412.061626 -394.647576)
			(xy 412.023193 -394.620264) (xy 411.989421 -394.587363) (xy 411.961116 -394.549656) (xy 411.949646 -394.529056)
			(xy 411.949138 -394.528294) (xy 411.551374 -393.839954) (xy 411.539517 -393.817268) (xy 411.522659 -393.768939)
			(xy 411.514078 -393.718479) (xy 411.513528 -393.692888) (xy 410.971534 -393.692888) (xy 411.283658 -394.232892)
			(xy 411.296484 -394.256224) (xy 411.314704 -394.306247) (xy 411.323963 -394.358673) (xy 411.324552 -394.385292)
			(xy 411.324054 -394.409295) (xy 411.316542 -394.456711) (xy 411.301701 -394.502366) (xy 411.279899 -394.545137)
			(xy 411.251671 -394.583968) (xy 411.217714 -394.617902) (xy 411.178864 -394.646104) (xy 411.136079 -394.667879)
			(xy 411.090414 -394.682689) (xy 411.042994 -394.690169) (xy 411.01899 -394.6906) (xy 410.995416 -394.690214)
			(xy 410.948827 -394.682971) (xy 410.903908 -394.668644) (xy 410.86173 -394.647574) (xy 410.823297 -394.620263)
			(xy 410.789526 -394.587363) (xy 410.76122 -394.549656) (xy 410.74975 -394.529056) (xy 410.749242 -394.528294)
			(xy 410.351478 -393.839954) (xy 410.339621 -393.817268) (xy 410.322763 -393.768939) (xy 410.314182 -393.718479)
			(xy 410.313632 -393.692888) (xy 409.771638 -393.692888) (xy 410.083762 -394.232892) (xy 410.096589 -394.256224)
			(xy 410.114808 -394.306247) (xy 410.124067 -394.358673) (xy 410.124656 -394.385292) (xy 410.124154 -394.409295)
			(xy 410.116642 -394.45671) (xy 410.101802 -394.502365) (xy 410.079999 -394.545135) (xy 410.051772 -394.583966)
			(xy 410.017815 -394.617901) (xy 409.978966 -394.646103) (xy 409.936182 -394.667878) (xy 409.890517 -394.682688)
			(xy 409.843098 -394.690169) (xy 409.819094 -394.6906) (xy 409.79552 -394.690211) (xy 409.748931 -394.682969)
			(xy 409.704013 -394.668642) (xy 409.661834 -394.647573) (xy 409.623401 -394.620262) (xy 409.58963 -394.587362)
			(xy 409.561324 -394.549656) (xy 409.549854 -394.529056) (xy 409.549346 -394.528294) (xy 409.151582 -393.839954)
			(xy 409.139725 -393.817268) (xy 409.122867 -393.768939) (xy 409.114286 -393.718479) (xy 409.113736 -393.692888)
			(xy 408.571488 -393.692888) (xy 408.883612 -394.232892) (xy 408.896363 -394.256248) (xy 408.914472 -394.306281)
			(xy 408.923674 -394.358688) (xy 408.924252 -394.385292) (xy 408.92373 -394.409281) (xy 408.916227 -394.456668)
			(xy 408.901403 -394.502298) (xy 408.879624 -394.545048) (xy 408.851427 -394.583865) (xy 408.817504 -394.617793)
			(xy 408.778692 -394.645997) (xy 408.735946 -394.667783) (xy 408.690319 -394.682614) (xy 408.642933 -394.690126)
			(xy 408.618944 -394.6906) (xy 408.595371 -394.690171) (xy 408.548785 -394.682936) (xy 408.503867 -394.668616)
			(xy 408.461689 -394.647554) (xy 408.423255 -394.620249) (xy 408.389482 -394.587355) (xy 408.361175 -394.549654)
			(xy 408.349704 -394.529056) (xy 408.349196 -394.528294) (xy 407.951432 -393.839954) (xy 407.9395 -393.817294)
			(xy 407.922568 -393.768965) (xy 407.913915 -393.718491) (xy 407.913332 -393.692888) (xy 407.371592 -393.692888)
			(xy 407.683716 -394.232892) (xy 407.696468 -394.256248) (xy 407.714576 -394.306281) (xy 407.723778 -394.358688)
			(xy 407.724356 -394.385292) (xy 407.72383 -394.409281) (xy 407.716327 -394.456667) (xy 407.701503 -394.502297)
			(xy 407.679725 -394.545047) (xy 407.651528 -394.583863) (xy 407.617606 -394.617791) (xy 407.578794 -394.645996)
			(xy 407.536049 -394.667782) (xy 407.490422 -394.682614) (xy 407.443037 -394.690126) (xy 407.419048 -394.6906)
			(xy 407.395475 -394.690168) (xy 407.348889 -394.682933) (xy 407.303971 -394.668614) (xy 407.261793 -394.647552)
			(xy 407.223359 -394.620248) (xy 407.189586 -394.587354) (xy 407.161279 -394.549654) (xy 407.149808 -394.529056)
			(xy 407.1493 -394.528294) (xy 406.751536 -393.839954) (xy 406.739605 -393.817294) (xy 406.722672 -393.768964)
			(xy 406.714019 -393.718491) (xy 406.713436 -393.692888) (xy 406.171442 -393.692888) (xy 406.483566 -394.232892)
			(xy 406.496393 -394.256223) (xy 406.514612 -394.306247) (xy 406.523871 -394.358673) (xy 406.52446 -394.385292)
			(xy 406.524053 -394.4093) (xy 406.516538 -394.456724) (xy 406.501693 -394.502388) (xy 406.479882 -394.545164)
			(xy 406.451644 -394.583999) (xy 406.417675 -394.617935) (xy 406.378813 -394.646136) (xy 406.336016 -394.667905)
			(xy 406.290338 -394.682707) (xy 406.242906 -394.690176) (xy 406.218898 -394.6906) (xy 406.195324 -394.690208)
			(xy 406.148736 -394.682966) (xy 406.103817 -394.66864) (xy 406.061639 -394.647571) (xy 406.023206 -394.620261)
			(xy 405.989434 -394.587361) (xy 405.961128 -394.549656) (xy 405.949658 -394.529056) (xy 405.94915 -394.528294)
			(xy 405.551386 -393.839954) (xy 405.53953 -393.817267) (xy 405.522671 -393.768939) (xy 405.51409 -393.718479)
			(xy 405.51354 -393.692888) (xy 404.971546 -393.692888) (xy 405.28367 -394.232892) (xy 405.296497 -394.256223)
			(xy 405.314716 -394.306247) (xy 405.323975 -394.358673) (xy 405.324564 -394.385292) (xy 405.324153 -394.4093)
			(xy 405.316639 -394.456724) (xy 405.301793 -394.502387) (xy 405.279983 -394.545163) (xy 405.251745 -394.583998)
			(xy 405.217777 -394.617934) (xy 405.178915 -394.646134) (xy 405.136118 -394.667904) (xy 405.090441 -394.682706)
			(xy 405.04301 -394.690176) (xy 405.019002 -394.6906) (xy 404.995428 -394.690205) (xy 404.94884 -394.682963)
			(xy 404.903921 -394.668638) (xy 404.861743 -394.64757) (xy 404.82331 -394.62026) (xy 404.789538 -394.587361)
			(xy 404.761233 -394.549656) (xy 404.749762 -394.529056) (xy 404.749254 -394.528294) (xy 404.35149 -393.839954)
			(xy 404.339634 -393.817267) (xy 404.322775 -393.768939) (xy 404.314194 -393.718479) (xy 404.313644 -393.692888)
			(xy 403.77165 -393.692888) (xy 404.083774 -394.232892) (xy 404.096601 -394.256223) (xy 404.11482 -394.306247)
			(xy 404.124079 -394.358673) (xy 404.124668 -394.385292) (xy 404.124253 -394.4093) (xy 404.116739 -394.456723)
			(xy 404.101893 -394.502386) (xy 404.080083 -394.545162) (xy 404.051846 -394.583996) (xy 404.017879 -394.617932)
			(xy 403.979017 -394.646133) (xy 403.936221 -394.667903) (xy 403.890545 -394.682706) (xy 403.843114 -394.690176)
			(xy 403.819106 -394.6906) (xy 403.795532 -394.690201) (xy 403.748944 -394.682961) (xy 403.704026 -394.668636)
			(xy 403.661847 -394.647568) (xy 403.623414 -394.620259) (xy 403.589642 -394.58736) (xy 403.561337 -394.549655)
			(xy 403.549866 -394.529056) (xy 403.549358 -394.528294) (xy 403.151594 -393.839954) (xy 403.139738 -393.817267)
			(xy 403.122879 -393.768939) (xy 403.114298 -393.718479) (xy 403.113748 -393.692888) (xy 389.243866 -393.692888)
			(xy 389.55599 -394.232892) (xy 389.568819 -394.256222) (xy 389.587037 -394.306246) (xy 389.596295 -394.358673)
			(xy 389.596884 -394.385292) (xy 389.596453 -394.409299) (xy 389.588939 -394.456721) (xy 389.574095 -394.502382)
			(xy 389.552286 -394.545157) (xy 389.524051 -394.583991) (xy 389.490085 -394.617927) (xy 389.451226 -394.646128)
			(xy 389.408432 -394.667898) (xy 389.362758 -394.682702) (xy 389.315329 -394.690175) (xy 389.291322 -394.6906)
			(xy 389.267749 -394.690188) (xy 389.221161 -394.68295) (xy 389.176243 -394.668628) (xy 389.134065 -394.647562)
			(xy 389.095631 -394.620255) (xy 389.061859 -394.587358) (xy 389.033553 -394.549655) (xy 389.022082 -394.529056)
			(xy 389.021574 -394.528294) (xy 388.62381 -393.839954) (xy 388.611948 -393.81727) (xy 388.595093 -393.76894)
			(xy 388.586513 -393.71848) (xy 388.585964 -393.692888) (xy 388.043716 -393.692888) (xy 388.35584 -394.232892)
			(xy 388.368594 -394.256247) (xy 388.386701 -394.30628) (xy 388.395902 -394.358688) (xy 388.39648 -394.385292)
			(xy 388.396054 -394.409286) (xy 388.388548 -394.456684) (xy 388.373719 -394.502324) (xy 388.351932 -394.545082)
			(xy 388.323724 -394.583905) (xy 388.28979 -394.617837) (xy 388.250965 -394.646042) (xy 388.208206 -394.667826)
			(xy 388.162565 -394.682653) (xy 388.115166 -394.690156) (xy 388.091172 -394.6906) (xy 388.067597 -394.690229)
			(xy 388.021008 -394.682983) (xy 387.976089 -394.668653) (xy 387.93391 -394.647581) (xy 387.895478 -394.620268)
			(xy 387.861707 -394.587365) (xy 387.833402 -394.549657) (xy 387.821932 -394.529056) (xy 387.821424 -394.528294)
			(xy 387.42366 -393.839954) (xy 387.41173 -393.817293) (xy 387.394797 -393.768964) (xy 387.386143 -393.718491)
			(xy 387.38556 -393.692888) (xy 386.84382 -393.692888) (xy 387.155944 -394.232892) (xy 387.168698 -394.256247)
			(xy 387.186805 -394.30628) (xy 387.196006 -394.358688) (xy 387.196584 -394.385292) (xy 387.196154 -394.409286)
			(xy 387.188648 -394.456684) (xy 387.173819 -394.502323) (xy 387.152033 -394.545081) (xy 387.123825 -394.583904)
			(xy 387.089892 -394.617836) (xy 387.051067 -394.646041) (xy 387.008308 -394.667825) (xy 386.962668 -394.682652)
			(xy 386.91527 -394.690156) (xy 386.891276 -394.6906) (xy 386.867701 -394.690226) (xy 386.821112 -394.68298)
			(xy 386.776193 -394.668651) (xy 386.734015 -394.647579) (xy 386.695582 -394.620267) (xy 386.661811 -394.587365)
			(xy 386.633506 -394.549657) (xy 386.622036 -394.529056) (xy 386.621528 -394.528294) (xy 386.223764 -393.839954)
			(xy 386.211835 -393.817292) (xy 386.194901 -393.768964) (xy 386.186248 -393.718491) (xy 386.185664 -393.692888)
			(xy 385.64367 -393.692888) (xy 385.955794 -394.232892) (xy 385.968623 -394.256222) (xy 385.986841 -394.306246)
			(xy 385.996099 -394.358673) (xy 385.996688 -394.385292) (xy 385.996253 -394.409299) (xy 385.988739 -394.45672)
			(xy 385.973895 -394.502381) (xy 385.952087 -394.545156) (xy 385.923852 -394.58399) (xy 385.889887 -394.617925)
			(xy 385.851029 -394.646126) (xy 385.808235 -394.667897) (xy 385.762561 -394.682702) (xy 385.715133 -394.690174)
			(xy 385.691126 -394.6906) (xy 385.667553 -394.690185) (xy 385.620965 -394.682948) (xy 385.576047 -394.668626)
			(xy 385.533869 -394.64756) (xy 385.495436 -394.620254) (xy 385.461663 -394.587357) (xy 385.433357 -394.549655)
			(xy 385.421886 -394.529056) (xy 385.421378 -394.528294) (xy 385.023614 -393.839954) (xy 385.011752 -393.81727)
			(xy 384.994897 -393.76894) (xy 384.986317 -393.71848) (xy 384.985768 -393.692888) (xy 384.443774 -393.692888)
			(xy 384.755898 -394.232892) (xy 384.768719 -394.256226) (xy 384.786942 -394.306248) (xy 384.796203 -394.358674)
			(xy 384.796792 -394.385292) (xy 384.796353 -394.409298) (xy 384.78884 -394.45672) (xy 384.773996 -394.50238)
			(xy 384.752188 -394.545155) (xy 384.723953 -394.583988) (xy 384.689989 -394.617924) (xy 384.651131 -394.646125)
			(xy 384.608338 -394.667896) (xy 384.562664 -394.682701) (xy 384.515237 -394.690174) (xy 384.49123 -394.6906)
			(xy 384.467657 -394.690182) (xy 384.42107 -394.682945) (xy 384.376152 -394.668624) (xy 384.333973 -394.647559)
			(xy 384.29554 -394.620253) (xy 384.261768 -394.587357) (xy 384.233461 -394.549654) (xy 384.22199 -394.529056)
			(xy 384.221482 -394.528294) (xy 383.823718 -393.839954) (xy 383.811856 -393.81727) (xy 383.795001 -393.76894)
			(xy 383.786421 -393.71848) (xy 383.785872 -393.692888) (xy 383.243878 -393.692888) (xy 383.556002 -394.232892)
			(xy 383.568824 -394.256226) (xy 383.587046 -394.306248) (xy 383.596307 -394.358674) (xy 383.596896 -394.385292)
			(xy 383.596453 -394.409298) (xy 383.58894 -394.456719) (xy 383.574096 -394.502379) (xy 383.552288 -394.545153)
			(xy 383.524055 -394.583987) (xy 383.49009 -394.617922) (xy 383.451233 -394.646123) (xy 383.408441 -394.667895)
			(xy 383.362768 -394.6827) (xy 383.315341 -394.690174) (xy 383.291334 -394.6906) (xy 383.267761 -394.690179)
			(xy 383.221174 -394.682942) (xy 383.176256 -394.668622) (xy 383.134078 -394.647557) (xy 383.095644 -394.620252)
			(xy 383.061872 -394.587356) (xy 383.033565 -394.549654) (xy 383.022094 -394.529056) (xy 383.021586 -394.528294)
			(xy 382.623822 -393.839954) (xy 382.611961 -393.81727) (xy 382.595105 -393.76894) (xy 382.586526 -393.71848)
			(xy 382.585976 -393.692888) (xy 382.043728 -393.692888) (xy 382.355852 -394.232892) (xy 382.368607 -394.256246)
			(xy 382.386713 -394.30628) (xy 382.395914 -394.358688) (xy 382.396492 -394.385292) (xy 382.396054 -394.409286)
			(xy 382.388548 -394.456682) (xy 382.37372 -394.502321) (xy 382.351934 -394.545079) (xy 382.323728 -394.583901)
			(xy 382.289795 -394.617833) (xy 382.250972 -394.646038) (xy 382.208214 -394.667823) (xy 382.162575 -394.68265)
			(xy 382.115178 -394.690155) (xy 382.091184 -394.6906) (xy 382.06761 -394.690219) (xy 382.021021 -394.682975)
			(xy 381.976102 -394.668647) (xy 381.933923 -394.647576) (xy 381.895491 -394.620265) (xy 381.861719 -394.587363)
			(xy 381.833414 -394.549656) (xy 381.821944 -394.529056) (xy 381.821436 -394.528294) (xy 381.423672 -393.839954)
			(xy 381.411736 -393.817296) (xy 381.394806 -393.768965) (xy 381.386155 -393.718492) (xy 381.385572 -393.692888)
			(xy 380.843832 -393.692888) (xy 381.155956 -394.232892) (xy 381.168711 -394.256246) (xy 381.186817 -394.30628)
			(xy 381.196018 -394.358688) (xy 381.196596 -394.385292) (xy 381.196154 -394.409286) (xy 381.188648 -394.456682)
			(xy 381.17382 -394.50232) (xy 381.152035 -394.545077) (xy 381.123829 -394.5839) (xy 381.089897 -394.617831)
			(xy 381.051074 -394.646037) (xy 381.008317 -394.667822) (xy 380.962678 -394.682649) (xy 380.915282 -394.690155)
			(xy 380.891288 -394.6906) (xy 380.867714 -394.690216) (xy 380.821125 -394.682973) (xy 380.776206 -394.668645)
			(xy 380.734028 -394.647575) (xy 380.695595 -394.620264) (xy 380.661823 -394.587363) (xy 380.633518 -394.549656)
			(xy 380.622048 -394.529056) (xy 380.62154 -394.528294) (xy 380.223776 -393.839954) (xy 380.21184 -393.817296)
			(xy 380.19491 -393.768965) (xy 380.186259 -393.718492) (xy 380.185676 -393.692888) (xy 379.643682 -393.692888)
			(xy 379.955806 -394.232892) (xy 379.968628 -394.256226) (xy 379.98685 -394.306248) (xy 379.996111 -394.358674)
			(xy 379.9967 -394.385292) (xy 379.996254 -394.409298) (xy 379.98874 -394.456718) (xy 379.973896 -394.502378)
			(xy 379.952089 -394.545152) (xy 379.923856 -394.583985) (xy 379.889892 -394.617921) (xy 379.851035 -394.646122)
			(xy 379.808243 -394.667894) (xy 379.762571 -394.682699) (xy 379.715144 -394.690173) (xy 379.691138 -394.6906)
			(xy 379.667565 -394.690176) (xy 379.620978 -394.68294) (xy 379.57606 -394.66862) (xy 379.533882 -394.647556)
			(xy 379.495448 -394.620251) (xy 379.461676 -394.587356) (xy 379.433369 -394.549654) (xy 379.421898 -394.529056)
			(xy 379.42139 -394.528294) (xy 379.023626 -393.839954) (xy 379.011765 -393.81727) (xy 378.994909 -393.76894)
			(xy 378.98633 -393.71848) (xy 378.98578 -393.692888) (xy 378.443786 -393.692888) (xy 378.75591 -394.232892)
			(xy 378.768732 -394.256226) (xy 378.786954 -394.306248) (xy 378.796215 -394.358673) (xy 378.796804 -394.385292)
			(xy 378.796354 -394.409298) (xy 378.78884 -394.456718) (xy 378.773997 -394.502377) (xy 378.75219 -394.545151)
			(xy 378.723957 -394.583984) (xy 378.689994 -394.61792) (xy 378.651137 -394.646121) (xy 378.608346 -394.667893)
			(xy 378.562674 -394.682698) (xy 378.515248 -394.690173) (xy 378.491242 -394.6906) (xy 378.467669 -394.690172)
			(xy 378.421083 -394.682937) (xy 378.376165 -394.668617) (xy 378.333986 -394.647554) (xy 378.295553 -394.62025)
			(xy 378.26178 -394.587355) (xy 378.233473 -394.549654) (xy 378.222002 -394.529056) (xy 378.221494 -394.528294)
			(xy 377.82373 -393.839954) (xy 377.811869 -393.81727) (xy 377.795013 -393.76894) (xy 377.786434 -393.71848)
			(xy 377.785884 -393.692888) (xy 377.24389 -393.692888) (xy 377.556014 -394.232892) (xy 377.568837 -394.256226)
			(xy 377.587058 -394.306248) (xy 377.596319 -394.358673) (xy 377.596908 -394.385292) (xy 377.596454 -394.409298)
			(xy 377.58894 -394.456717) (xy 377.574097 -394.502377) (xy 377.552291 -394.54515) (xy 377.524058 -394.583983)
			(xy 377.490095 -394.617918) (xy 377.45124 -394.646119) (xy 377.408449 -394.667891) (xy 377.362778 -394.682698)
			(xy 377.315352 -394.690173) (xy 377.291346 -394.6906) (xy 377.267773 -394.690169) (xy 377.221187 -394.682935)
			(xy 377.176269 -394.668615) (xy 377.134091 -394.647553) (xy 377.095657 -394.620249) (xy 377.061884 -394.587355)
			(xy 377.033577 -394.549654) (xy 377.022106 -394.529056) (xy 377.021598 -394.528294) (xy 376.623834 -393.839954)
			(xy 376.611974 -393.81727) (xy 376.595118 -393.76894) (xy 376.586538 -393.71848) (xy 376.585988 -393.692888)
			(xy 376.04374 -393.692888) (xy 376.355864 -394.232892) (xy 376.36862 -394.256246) (xy 376.386726 -394.30628)
			(xy 376.395926 -394.358688) (xy 376.396504 -394.385292) (xy 376.396054 -394.409285) (xy 376.388549 -394.456681)
			(xy 376.373721 -394.502319) (xy 376.351936 -394.545075) (xy 376.323731 -394.583897) (xy 376.2898 -394.617829)
			(xy 376.250978 -394.646034) (xy 376.208222 -394.66782) (xy 376.162585 -394.682648) (xy 376.115189 -394.690154)
			(xy 376.091196 -394.6906) (xy 376.067622 -394.690209) (xy 376.021033 -394.682967) (xy 375.976115 -394.668641)
			(xy 375.933936 -394.647572) (xy 375.895503 -394.620262) (xy 375.861732 -394.587362) (xy 375.833426 -394.549656)
			(xy 375.821956 -394.529056) (xy 375.821448 -394.528294) (xy 375.423684 -393.839954) (xy 375.411748 -393.817296)
			(xy 375.394819 -393.768965) (xy 375.386167 -393.718492) (xy 375.385584 -393.692888) (xy 374.843844 -393.692888)
			(xy 375.155968 -394.232892) (xy 375.168724 -394.256246) (xy 375.18683 -394.30628) (xy 375.19603 -394.358688)
			(xy 375.196608 -394.385292) (xy 375.196154 -394.409285) (xy 375.188649 -394.45668) (xy 375.173821 -394.502318)
			(xy 375.152037 -394.545074) (xy 375.123832 -394.583896) (xy 375.089902 -394.617827) (xy 375.051081 -394.646033)
			(xy 375.008325 -394.667818) (xy 374.962688 -394.682647) (xy 374.915293 -394.690154) (xy 374.8913 -394.6906)
			(xy 374.867726 -394.690206) (xy 374.821138 -394.682965) (xy 374.776219 -394.668639) (xy 374.734041 -394.64757)
			(xy 374.695608 -394.620261) (xy 374.661836 -394.587361) (xy 374.63353 -394.549656) (xy 374.62206 -394.529056)
			(xy 374.621552 -394.528294) (xy 374.223788 -393.839954) (xy 374.211853 -393.817296) (xy 374.194923 -393.768965)
			(xy 374.186271 -393.718491) (xy 374.185688 -393.692888) (xy 373.643694 -393.692888) (xy 373.955818 -394.232892)
			(xy 373.968641 -394.256226) (xy 373.986862 -394.306248) (xy 373.996123 -394.358673) (xy 373.996712 -394.385292)
			(xy 373.996254 -394.409297) (xy 373.98874 -394.456717) (xy 373.973898 -394.502376) (xy 373.952091 -394.545149)
			(xy 373.923859 -394.583981) (xy 373.889897 -394.617917) (xy 373.851042 -394.646118) (xy 373.808252 -394.66789)
			(xy 373.762581 -394.682697) (xy 373.715156 -394.690172) (xy 373.69115 -394.6906) (xy 373.667577 -394.690166)
			(xy 373.620991 -394.682932) (xy 373.576073 -394.668613) (xy 373.533895 -394.647551) (xy 373.495461 -394.620248)
			(xy 373.461688 -394.587354) (xy 373.433381 -394.549653) (xy 373.42191 -394.529056) (xy 373.421402 -394.528294)
			(xy 373.023638 -393.839954) (xy 373.011778 -393.817269) (xy 372.994922 -393.76894) (xy 372.986342 -393.71848)
			(xy 372.985792 -393.692888) (xy 372.443798 -393.692888) (xy 372.755922 -394.232892) (xy 372.768745 -394.256225)
			(xy 372.786966 -394.306248) (xy 372.796227 -394.358673) (xy 372.796816 -394.385292) (xy 372.796354 -394.409297)
			(xy 372.78884 -394.456716) (xy 372.773998 -394.502375) (xy 372.752192 -394.545147) (xy 372.72396 -394.58398)
			(xy 372.689999 -394.617915) (xy 372.651144 -394.646117) (xy 372.608354 -394.667889) (xy 372.562684 -394.682696)
			(xy 372.51526 -394.690172) (xy 372.491254 -394.6906) (xy 372.467682 -394.690163) (xy 372.421095 -394.682929)
			(xy 372.376178 -394.668611) (xy 372.333999 -394.64755) (xy 372.295566 -394.620247) (xy 372.261793 -394.587353)
			(xy 372.233485 -394.549653) (xy 372.222014 -394.529056) (xy 372.221506 -394.528294) (xy 371.823742 -393.839954)
			(xy 371.811882 -393.817269) (xy 371.795026 -393.76894) (xy 371.786446 -393.71848) (xy 371.785896 -393.692888)
			(xy 371.243902 -393.692888) (xy 371.556026 -394.232892) (xy 371.56885 -394.256225) (xy 371.587071 -394.306247)
			(xy 371.596331 -394.358673) (xy 371.59692 -394.385292) (xy 371.596454 -394.409297) (xy 371.588941 -394.456716)
			(xy 371.574098 -394.502374) (xy 371.552293 -394.545146) (xy 371.524062 -394.583979) (xy 371.4901 -394.617914)
			(xy 371.451246 -394.646115) (xy 371.408457 -394.667888) (xy 371.362788 -394.682695) (xy 371.315363 -394.690172)
			(xy 371.291358 -394.6906) (xy 371.267786 -394.690159) (xy 371.2212 -394.682927) (xy 371.176282 -394.668609)
			(xy 371.134104 -394.647548) (xy 371.09567 -394.620246) (xy 371.061897 -394.587353) (xy 371.03359 -394.549653)
			(xy 371.022118 -394.529056) (xy 371.02161 -394.528294) (xy 370.623846 -393.839954) (xy 370.611986 -393.817269)
			(xy 370.59513 -393.76894) (xy 370.58655 -393.71848) (xy 370.586 -393.692888) (xy 354.671418 -393.692888)
			(xy 354.983542 -394.232892) (xy 354.996367 -394.256224) (xy 355.014587 -394.306247) (xy 355.023847 -394.358673)
			(xy 355.024436 -394.385292) (xy 355.023954 -394.409296) (xy 355.016441 -394.456713) (xy 355.0016 -394.50237)
			(xy 354.979796 -394.545141) (xy 354.951566 -394.583973) (xy 354.917607 -394.617908) (xy 354.878755 -394.64611)
			(xy 354.835968 -394.667883) (xy 354.790301 -394.682692) (xy 354.742879 -394.690171) (xy 354.718874 -394.6906)
			(xy 354.695299 -394.690227) (xy 354.64871 -394.682982) (xy 354.603791 -394.668652) (xy 354.561613 -394.64758)
			(xy 354.52318 -394.620267) (xy 354.489409 -394.587365) (xy 354.461104 -394.549657) (xy 354.449634 -394.529056)
			(xy 354.449126 -394.528294) (xy 354.051362 -393.839954) (xy 354.039504 -393.817268) (xy 354.022646 -393.76894)
			(xy 354.014066 -393.71848) (xy 354.013516 -393.692888) (xy 353.471522 -393.692888) (xy 353.783646 -394.232892)
			(xy 353.796471 -394.256224) (xy 353.814691 -394.306247) (xy 353.823951 -394.358673) (xy 353.82454 -394.385292)
			(xy 353.824054 -394.409296) (xy 353.816541 -394.456713) (xy 353.8017 -394.502369) (xy 353.779896 -394.54514)
			(xy 353.751667 -394.583972) (xy 353.717709 -394.617907) (xy 353.678857 -394.646108) (xy 353.636071 -394.667882)
			(xy 353.590404 -394.682691) (xy 353.542982 -394.69017) (xy 353.518978 -394.6906) (xy 353.518724 -394.6906)
			(xy 353.495151 -394.690187) (xy 353.448563 -394.682949) (xy 353.403645 -394.668627) (xy 353.361467 -394.647561)
			(xy 353.323033 -394.620255) (xy 353.289261 -394.587358) (xy 353.260955 -394.549655) (xy 353.249484 -394.529056)
			(xy 353.248976 -394.528294) (xy 352.851212 -393.839954) (xy 352.839279 -393.817295) (xy 352.822347 -393.768965)
			(xy 352.813695 -393.718491) (xy 352.813112 -393.692888) (xy 352.271372 -393.692888) (xy 352.583496 -394.232892)
			(xy 352.596246 -394.256249) (xy 352.614355 -394.306281) (xy 352.623558 -394.358688) (xy 352.624136 -394.385292)
			(xy 352.62363 -394.409282) (xy 352.616126 -394.45667) (xy 352.601301 -394.502302) (xy 352.579521 -394.545053)
			(xy 352.551322 -394.58387) (xy 352.517397 -394.617798) (xy 352.478583 -394.646002) (xy 352.435835 -394.667788)
			(xy 352.390205 -394.682618) (xy 352.342818 -394.690127) (xy 352.318828 -394.6906) (xy 352.295255 -394.690184)
			(xy 352.248668 -394.682946) (xy 352.20375 -394.668625) (xy 352.161571 -394.64756) (xy 352.123138 -394.620254)
			(xy 352.089365 -394.587357) (xy 352.061059 -394.549654) (xy 352.049588 -394.529056) (xy 352.04908 -394.528294)
			(xy 351.651316 -393.839954) (xy 351.639383 -393.817294) (xy 351.622452 -393.768965) (xy 351.613799 -393.718491)
			(xy 351.613216 -393.692888) (xy 351.071476 -393.692888) (xy 351.3836 -394.232892) (xy 351.39635 -394.256249)
			(xy 351.41446 -394.306281) (xy 351.423662 -394.358688) (xy 351.42424 -394.385292) (xy 351.42373 -394.409281)
			(xy 351.416226 -394.45667) (xy 351.401402 -394.502301) (xy 351.379622 -394.545051) (xy 351.351423 -394.583869)
			(xy 351.317499 -394.617797) (xy 351.278686 -394.646001) (xy 351.235938 -394.667787) (xy 351.190309 -394.682617)
			(xy 351.142921 -394.690127) (xy 351.118932 -394.6906) (xy 351.118678 -394.6906) (xy 351.095103 -394.690224)
			(xy 351.048514 -394.682979) (xy 351.003595 -394.66865) (xy 350.961417 -394.647579) (xy 350.922984 -394.620266)
			(xy 350.889213 -394.587364) (xy 350.860908 -394.549657) (xy 350.849438 -394.529056) (xy 350.84893 -394.528294)
			(xy 350.451166 -393.839954) (xy 350.439308 -393.817268) (xy 350.42245 -393.76894) (xy 350.41387 -393.71848)
			(xy 350.41332 -393.692888) (xy 349.871326 -393.692888) (xy 350.18345 -394.232892) (xy 350.196276 -394.256224)
			(xy 350.214495 -394.306247) (xy 350.223755 -394.358673) (xy 350.224344 -394.385292) (xy 350.223854 -394.409296)
			(xy 350.216341 -394.456712) (xy 350.201501 -394.502368) (xy 350.179697 -394.545139) (xy 350.151469 -394.58397)
			(xy 350.11751 -394.617905) (xy 350.07866 -394.646107) (xy 350.035874 -394.667881) (xy 349.990207 -394.68269)
			(xy 349.942786 -394.69017) (xy 349.918782 -394.6906) (xy 349.895207 -394.690221) (xy 349.848619 -394.682977)
			(xy 349.8037 -394.668648) (xy 349.761521 -394.647577) (xy 349.723088 -394.620265) (xy 349.689317 -394.587364)
			(xy 349.661012 -394.549657) (xy 349.649542 -394.529056) (xy 349.649034 -394.528294) (xy 349.25127 -393.839954)
			(xy 349.239412 -393.817268) (xy 349.222555 -393.768939) (xy 349.213974 -393.71848) (xy 349.213424 -393.692888)
			(xy 348.67143 -393.692888) (xy 348.983554 -394.232892) (xy 348.99638 -394.256224) (xy 349.014599 -394.306247)
			(xy 349.023859 -394.358673) (xy 349.024448 -394.385292) (xy 349.023954 -394.409296) (xy 349.016441 -394.456711)
			(xy 349.001601 -394.502367) (xy 348.979798 -394.545138) (xy 348.95157 -394.583969) (xy 348.917612 -394.617904)
			(xy 348.878762 -394.646106) (xy 348.835977 -394.66788) (xy 348.790311 -394.68269) (xy 348.74289 -394.69017)
			(xy 348.718886 -394.6906) (xy 348.695312 -394.690217) (xy 348.648723 -394.682974) (xy 348.603804 -394.668646)
			(xy 348.561626 -394.647576) (xy 348.523193 -394.620264) (xy 348.489421 -394.587363) (xy 348.461116 -394.549656)
			(xy 348.449646 -394.529056) (xy 348.449138 -394.528294) (xy 348.051374 -393.839954) (xy 348.039517 -393.817268)
			(xy 348.022659 -393.768939) (xy 348.014078 -393.718479) (xy 348.013528 -393.692888) (xy 347.47128 -393.692888)
			(xy 347.783404 -394.232892) (xy 347.796155 -394.256249) (xy 347.814264 -394.306281) (xy 347.823466 -394.358688)
			(xy 347.824044 -394.385292) (xy 347.82353 -394.409281) (xy 347.816026 -394.456669) (xy 347.801202 -394.5023)
			(xy 347.779423 -394.54505) (xy 347.751224 -394.583867) (xy 347.717301 -394.617796) (xy 347.678488 -394.646)
			(xy 347.635741 -394.667785) (xy 347.590112 -394.682616) (xy 347.542725 -394.690127) (xy 347.518736 -394.6906)
			(xy 347.495163 -394.690177) (xy 347.448576 -394.682941) (xy 347.403658 -394.668621) (xy 347.36148 -394.647557)
			(xy 347.323046 -394.620252) (xy 347.289274 -394.587356) (xy 347.260967 -394.549654) (xy 347.249496 -394.529056)
			(xy 347.248988 -394.528294) (xy 346.851224 -393.839954) (xy 346.839292 -393.817294) (xy 346.82236 -393.768965)
			(xy 346.813707 -393.718491) (xy 346.813124 -393.692888) (xy 346.271384 -393.692888) (xy 346.583508 -394.232892)
			(xy 346.596259 -394.256248) (xy 346.614368 -394.306281) (xy 346.62357 -394.358688) (xy 346.624148 -394.385292)
			(xy 346.62363 -394.409281) (xy 346.616126 -394.456669) (xy 346.601303 -394.502299) (xy 346.579524 -394.545049)
			(xy 346.551325 -394.583866) (xy 346.517403 -394.617794) (xy 346.47859 -394.645998) (xy 346.435843 -394.667784)
			(xy 346.390215 -394.682615) (xy 346.342829 -394.690126) (xy 346.31884 -394.6906) (xy 346.295267 -394.690174)
			(xy 346.24868 -394.682939) (xy 346.203763 -394.668618) (xy 346.161584 -394.647555) (xy 346.123151 -394.620251)
			(xy 346.089378 -394.587355) (xy 346.061071 -394.549654) (xy 346.0496 -394.529056) (xy 346.049092 -394.528294)
			(xy 345.651328 -393.839954) (xy 345.639396 -393.817294) (xy 345.622464 -393.768965) (xy 345.613811 -393.718491)
			(xy 345.613228 -393.692888) (xy 345.071488 -393.692888) (xy 345.383612 -394.232892) (xy 345.396363 -394.256248)
			(xy 345.414472 -394.306281) (xy 345.423674 -394.358688) (xy 345.424252 -394.385292) (xy 345.42373 -394.409281)
			(xy 345.416227 -394.456668) (xy 345.401403 -394.502298) (xy 345.379624 -394.545048) (xy 345.351427 -394.583865)
			(xy 345.317504 -394.617793) (xy 345.278692 -394.645997) (xy 345.235946 -394.667783) (xy 345.190319 -394.682614)
			(xy 345.142933 -394.690126) (xy 345.118944 -394.6906) (xy 345.11869 -394.6906) (xy 345.095116 -394.690214)
			(xy 345.048527 -394.682971) (xy 345.003608 -394.668644) (xy 344.96143 -394.647574) (xy 344.922997 -394.620263)
			(xy 344.889226 -394.587363) (xy 344.86092 -394.549656) (xy 344.84945 -394.529056) (xy 344.848942 -394.528294)
			(xy 344.451178 -393.839954) (xy 344.439321 -393.817268) (xy 344.422463 -393.768939) (xy 344.413882 -393.718479)
			(xy 344.413332 -393.692888) (xy 343.871338 -393.692888) (xy 344.183462 -394.232892) (xy 344.196289 -394.256224)
			(xy 344.214508 -394.306247) (xy 344.223767 -394.358673) (xy 344.224356 -394.385292) (xy 344.223854 -394.409295)
			(xy 344.216342 -394.45671) (xy 344.201502 -394.502365) (xy 344.179699 -394.545135) (xy 344.151472 -394.583966)
			(xy 344.117515 -394.617901) (xy 344.078666 -394.646103) (xy 344.035882 -394.667878) (xy 343.990217 -394.682688)
			(xy 343.942798 -394.690169) (xy 343.918794 -394.6906) (xy 343.89522 -394.690211) (xy 343.848631 -394.682969)
			(xy 343.803713 -394.668642) (xy 343.761534 -394.647573) (xy 343.723101 -394.620262) (xy 343.68933 -394.587362)
			(xy 343.661024 -394.549656) (xy 343.649554 -394.529056) (xy 343.649046 -394.528294) (xy 343.251282 -393.839954)
			(xy 343.239425 -393.817268) (xy 343.222567 -393.768939) (xy 343.213986 -393.718479) (xy 343.213436 -393.692888)
			(xy 342.671442 -393.692888) (xy 342.983566 -394.232892) (xy 342.996393 -394.256223) (xy 343.014612 -394.306247)
			(xy 343.023871 -394.358673) (xy 343.02446 -394.385292) (xy 343.024053 -394.4093) (xy 343.016538 -394.456724)
			(xy 343.001693 -394.502388) (xy 342.979882 -394.545164) (xy 342.951644 -394.583999) (xy 342.917675 -394.617935)
			(xy 342.878813 -394.646136) (xy 342.836016 -394.667905) (xy 342.790338 -394.682707) (xy 342.742906 -394.690176)
			(xy 342.718898 -394.6906) (xy 342.695324 -394.690208) (xy 342.648736 -394.682966) (xy 342.603817 -394.66864)
			(xy 342.561639 -394.647571) (xy 342.523206 -394.620261) (xy 342.489434 -394.587361) (xy 342.461128 -394.549656)
			(xy 342.449658 -394.529056) (xy 342.44915 -394.528294) (xy 342.051386 -393.839954) (xy 342.03953 -393.817267)
			(xy 342.022671 -393.768939) (xy 342.01409 -393.718479) (xy 342.01354 -393.692888) (xy 341.471292 -393.692888)
			(xy 341.783416 -394.232892) (xy 341.796168 -394.256248) (xy 341.814276 -394.306281) (xy 341.823478 -394.358688)
			(xy 341.824056 -394.385292) (xy 341.82353 -394.409281) (xy 341.816027 -394.456667) (xy 341.801203 -394.502297)
			(xy 341.779425 -394.545047) (xy 341.751228 -394.583863) (xy 341.717306 -394.617791) (xy 341.678494 -394.645996)
			(xy 341.635749 -394.667782) (xy 341.590122 -394.682614) (xy 341.542737 -394.690126) (xy 341.518748 -394.6906)
			(xy 341.495175 -394.690168) (xy 341.448589 -394.682933) (xy 341.403671 -394.668614) (xy 341.361493 -394.647552)
			(xy 341.323059 -394.620248) (xy 341.289286 -394.587354) (xy 341.260979 -394.549654) (xy 341.249508 -394.529056)
			(xy 341.249 -394.528294) (xy 340.851236 -393.839954) (xy 340.839305 -393.817294) (xy 340.822372 -393.768964)
			(xy 340.813719 -393.718491) (xy 340.813136 -393.692888) (xy 340.271396 -393.692888) (xy 340.58352 -394.232892)
			(xy 340.596272 -394.256248) (xy 340.61438 -394.306281) (xy 340.623582 -394.358688) (xy 340.62416 -394.385292)
			(xy 340.623754 -394.409287) (xy 340.616247 -394.456687) (xy 340.601417 -394.502329) (xy 340.579628 -394.545088)
			(xy 340.551418 -394.583912) (xy 340.517482 -394.617844) (xy 340.478654 -394.646049) (xy 340.435892 -394.667832)
			(xy 340.390248 -394.682657) (xy 340.342847 -394.690157) (xy 340.318852 -394.6906) (xy 340.295279 -394.690164)
			(xy 340.248693 -394.682931) (xy 340.203776 -394.668612) (xy 340.161597 -394.647551) (xy 340.123164 -394.620247)
			(xy 340.089391 -394.587354) (xy 340.061083 -394.549653) (xy 340.049612 -394.529056) (xy 340.049104 -394.528294)
			(xy 339.65134 -393.839954) (xy 339.639409 -393.817293) (xy 339.622476 -393.768964) (xy 339.613823 -393.718491)
			(xy 339.61324 -393.692888) (xy 339.0715 -393.692888) (xy 339.383624 -394.232892) (xy 339.396376 -394.256248)
			(xy 339.414484 -394.30628) (xy 339.423686 -394.358688) (xy 339.424264 -394.385292) (xy 339.423854 -394.409287)
			(xy 339.416347 -394.456687) (xy 339.401517 -394.502328) (xy 339.379729 -394.545087) (xy 339.351519 -394.583911)
			(xy 339.317583 -394.617843) (xy 339.278756 -394.646048) (xy 339.235995 -394.667831) (xy 339.190352 -394.682656)
			(xy 339.142951 -394.690157) (xy 339.118956 -394.6906) (xy 339.118702 -394.6906) (xy 339.095128 -394.690205)
			(xy 339.04854 -394.682963) (xy 339.003621 -394.668638) (xy 338.961443 -394.64757) (xy 338.92301 -394.62026)
			(xy 338.889238 -394.587361) (xy 338.860933 -394.549656) (xy 338.849462 -394.529056) (xy 338.848954 -394.528294)
			(xy 338.45119 -393.839954) (xy 338.439334 -393.817267) (xy 338.422475 -393.768939) (xy 338.413894 -393.718479)
			(xy 338.413344 -393.692888) (xy 337.87135 -393.692888) (xy 338.183474 -394.232892) (xy 338.196301 -394.256223)
			(xy 338.21452 -394.306247) (xy 338.223779 -394.358673) (xy 338.224368 -394.385292) (xy 338.223953 -394.4093)
			(xy 338.216439 -394.456723) (xy 338.201593 -394.502386) (xy 338.179783 -394.545162) (xy 338.151546 -394.583996)
			(xy 338.117579 -394.617932) (xy 338.078717 -394.646133) (xy 338.035921 -394.667903) (xy 337.990245 -394.682706)
			(xy 337.942814 -394.690176) (xy 337.918806 -394.6906) (xy 337.895232 -394.690201) (xy 337.848644 -394.682961)
			(xy 337.803726 -394.668636) (xy 337.761547 -394.647568) (xy 337.723114 -394.620259) (xy 337.689342 -394.58736)
			(xy 337.661037 -394.549655) (xy 337.649566 -394.529056) (xy 337.649058 -394.528294) (xy 337.251294 -393.839954)
			(xy 337.239438 -393.817267) (xy 337.222579 -393.768939) (xy 337.213998 -393.718479) (xy 337.213448 -393.692888)
			(xy 336.671454 -393.692888) (xy 336.983578 -394.232892) (xy 336.996406 -394.256223) (xy 337.014624 -394.306247)
			(xy 337.023883 -394.358673) (xy 337.024472 -394.385292) (xy 337.024053 -394.409299) (xy 337.016539 -394.456723)
			(xy 337.001694 -394.502385) (xy 336.979884 -394.545161) (xy 336.951648 -394.583995) (xy 336.91768 -394.617931)
			(xy 336.87882 -394.646132) (xy 336.836024 -394.667902) (xy 336.790348 -394.682705) (xy 336.742918 -394.690175)
			(xy 336.71891 -394.6906) (xy 336.695336 -394.690198) (xy 336.648748 -394.682958) (xy 336.60383 -394.668634)
			(xy 336.561652 -394.647566) (xy 336.523218 -394.620258) (xy 336.489447 -394.58736) (xy 336.461141 -394.549655)
			(xy 336.44967 -394.529056) (xy 336.449162 -394.528294) (xy 336.051398 -393.839954) (xy 336.039542 -393.817267)
			(xy 336.022683 -393.768939) (xy 336.014102 -393.718479) (xy 336.013552 -393.692888) (xy 322.14367 -393.692888)
			(xy 322.455794 -394.232892) (xy 322.468623 -394.256222) (xy 322.486841 -394.306246) (xy 322.496099 -394.358673)
			(xy 322.496688 -394.385292) (xy 322.496253 -394.409299) (xy 322.488739 -394.45672) (xy 322.473895 -394.502381)
			(xy 322.452087 -394.545156) (xy 322.423852 -394.58399) (xy 322.389887 -394.617925) (xy 322.351029 -394.646126)
			(xy 322.308235 -394.667897) (xy 322.262561 -394.682702) (xy 322.215133 -394.690174) (xy 322.191126 -394.6906)
			(xy 322.167553 -394.690185) (xy 322.120965 -394.682948) (xy 322.076047 -394.668626) (xy 322.033869 -394.64756)
			(xy 321.995436 -394.620254) (xy 321.961663 -394.587357) (xy 321.933357 -394.549655) (xy 321.921886 -394.529056)
			(xy 321.921378 -394.528294) (xy 321.523614 -393.839954) (xy 321.511752 -393.81727) (xy 321.494897 -393.76894)
			(xy 321.486317 -393.71848) (xy 321.485768 -393.692888) (xy 320.943774 -393.692888) (xy 321.255898 -394.232892)
			(xy 321.268719 -394.256226) (xy 321.286942 -394.306248) (xy 321.296203 -394.358674) (xy 321.296792 -394.385292)
			(xy 321.296353 -394.409298) (xy 321.28884 -394.45672) (xy 321.273996 -394.50238) (xy 321.252188 -394.545155)
			(xy 321.223953 -394.583988) (xy 321.189989 -394.617924) (xy 321.151131 -394.646125) (xy 321.108338 -394.667896)
			(xy 321.062664 -394.682701) (xy 321.015237 -394.690174) (xy 320.99123 -394.6906) (xy 320.967657 -394.690182)
			(xy 320.92107 -394.682945) (xy 320.876152 -394.668624) (xy 320.833973 -394.647559) (xy 320.79554 -394.620253)
			(xy 320.761768 -394.587357) (xy 320.733461 -394.549654) (xy 320.72199 -394.529056) (xy 320.721482 -394.528294)
			(xy 320.323718 -393.839954) (xy 320.311856 -393.81727) (xy 320.295001 -393.76894) (xy 320.286421 -393.71848)
			(xy 320.285872 -393.692888) (xy 319.743878 -393.692888) (xy 320.056002 -394.232892) (xy 320.068824 -394.256226)
			(xy 320.087046 -394.306248) (xy 320.096307 -394.358674) (xy 320.096896 -394.385292) (xy 320.096453 -394.409298)
			(xy 320.08894 -394.456719) (xy 320.074096 -394.502379) (xy 320.052288 -394.545153) (xy 320.024055 -394.583987)
			(xy 319.99009 -394.617922) (xy 319.951233 -394.646123) (xy 319.908441 -394.667895) (xy 319.862768 -394.6827)
			(xy 319.815341 -394.690174) (xy 319.791334 -394.6906) (xy 319.79108 -394.6906) (xy 319.767505 -394.690222)
			(xy 319.720916 -394.682978) (xy 319.675997 -394.668649) (xy 319.633819 -394.647578) (xy 319.595386 -394.620266)
			(xy 319.561615 -394.587364) (xy 319.53331 -394.549657) (xy 319.52184 -394.529056) (xy 319.521332 -394.528294)
			(xy 319.123568 -393.839954) (xy 319.111639 -393.817292) (xy 319.094706 -393.768964) (xy 319.086052 -393.718491)
			(xy 319.085468 -393.692888) (xy 318.543728 -393.692888) (xy 318.855852 -394.232892) (xy 318.868607 -394.256246)
			(xy 318.886713 -394.30628) (xy 318.895914 -394.358688) (xy 318.896492 -394.385292) (xy 318.896054 -394.409286)
			(xy 318.888548 -394.456682) (xy 318.87372 -394.502321) (xy 318.851934 -394.545079) (xy 318.823728 -394.583901)
			(xy 318.789795 -394.617833) (xy 318.750972 -394.646038) (xy 318.708214 -394.667823) (xy 318.662575 -394.68265)
			(xy 318.615178 -394.690155) (xy 318.591184 -394.6906) (xy 318.56761 -394.690219) (xy 318.521021 -394.682975)
			(xy 318.476102 -394.668647) (xy 318.433923 -394.647576) (xy 318.395491 -394.620265) (xy 318.361719 -394.587363)
			(xy 318.333414 -394.549656) (xy 318.321944 -394.529056) (xy 318.321436 -394.528294) (xy 317.923672 -393.839954)
			(xy 317.911736 -393.817296) (xy 317.894806 -393.768965) (xy 317.886155 -393.718492) (xy 317.885572 -393.692888)
			(xy 317.343832 -393.692888) (xy 317.655956 -394.232892) (xy 317.668711 -394.256246) (xy 317.686817 -394.30628)
			(xy 317.696018 -394.358688) (xy 317.696596 -394.385292) (xy 317.696154 -394.409286) (xy 317.688648 -394.456682)
			(xy 317.67382 -394.50232) (xy 317.652035 -394.545077) (xy 317.623829 -394.5839) (xy 317.589897 -394.617831)
			(xy 317.551074 -394.646037) (xy 317.508317 -394.667822) (xy 317.462678 -394.682649) (xy 317.415282 -394.690155)
			(xy 317.391288 -394.6906) (xy 317.391034 -394.6906) (xy 317.367461 -394.690179) (xy 317.320874 -394.682942)
			(xy 317.275956 -394.668622) (xy 317.233778 -394.647557) (xy 317.195344 -394.620252) (xy 317.161572 -394.587356)
			(xy 317.133265 -394.549654) (xy 317.121794 -394.529056) (xy 317.121286 -394.528294) (xy 316.723522 -393.839954)
			(xy 316.711661 -393.81727) (xy 316.694805 -393.76894) (xy 316.686226 -393.71848) (xy 316.685676 -393.692888)
			(xy 316.143682 -393.692888) (xy 316.455806 -394.232892) (xy 316.468628 -394.256226) (xy 316.48685 -394.306248)
			(xy 316.496111 -394.358674) (xy 316.4967 -394.385292) (xy 316.496254 -394.409298) (xy 316.48874 -394.456718)
			(xy 316.473896 -394.502378) (xy 316.452089 -394.545152) (xy 316.423856 -394.583985) (xy 316.389892 -394.617921)
			(xy 316.351035 -394.646122) (xy 316.308243 -394.667894) (xy 316.262571 -394.682699) (xy 316.215144 -394.690173)
			(xy 316.191138 -394.6906) (xy 316.167565 -394.690176) (xy 316.120978 -394.68294) (xy 316.07606 -394.66862)
			(xy 316.033882 -394.647556) (xy 315.995448 -394.620251) (xy 315.961676 -394.587356) (xy 315.933369 -394.549654)
			(xy 315.921898 -394.529056) (xy 315.92139 -394.528294) (xy 315.523626 -393.839954) (xy 315.511765 -393.81727)
			(xy 315.494909 -393.76894) (xy 315.48633 -393.71848) (xy 315.48578 -393.692888) (xy 314.943786 -393.692888)
			(xy 315.25591 -394.232892) (xy 315.268732 -394.256226) (xy 315.286954 -394.306248) (xy 315.296215 -394.358673)
			(xy 315.296804 -394.385292) (xy 315.296354 -394.409298) (xy 315.28884 -394.456718) (xy 315.273997 -394.502377)
			(xy 315.25219 -394.545151) (xy 315.223957 -394.583984) (xy 315.189994 -394.61792) (xy 315.151137 -394.646121)
			(xy 315.108346 -394.667893) (xy 315.062674 -394.682698) (xy 315.015248 -394.690173) (xy 314.991242 -394.6906)
			(xy 314.990988 -394.6906) (xy 314.967414 -394.690216) (xy 314.920825 -394.682973) (xy 314.875906 -394.668645)
			(xy 314.833728 -394.647575) (xy 314.795295 -394.620264) (xy 314.761523 -394.587363) (xy 314.733218 -394.549656)
			(xy 314.721748 -394.529056) (xy 314.72124 -394.528294) (xy 314.323476 -393.839954) (xy 314.31154 -393.817296)
			(xy 314.29461 -393.768965) (xy 314.285959 -393.718492) (xy 314.285376 -393.692888) (xy 313.743636 -393.692888)
			(xy 314.05576 -394.232892) (xy 314.068515 -394.256246) (xy 314.086621 -394.30628) (xy 314.095822 -394.358688)
			(xy 314.0964 -394.385292) (xy 314.095954 -394.409285) (xy 314.088449 -394.456681) (xy 314.073621 -394.50232)
			(xy 314.051836 -394.545076) (xy 314.02363 -394.583898) (xy 313.989698 -394.61783) (xy 313.950876 -394.646036)
			(xy 313.90812 -394.667821) (xy 313.862481 -394.682649) (xy 313.815085 -394.690154) (xy 313.791092 -394.6906)
			(xy 313.767518 -394.690213) (xy 313.720929 -394.68297) (xy 313.67601 -394.668643) (xy 313.633832 -394.647573)
			(xy 313.595399 -394.620263) (xy 313.561628 -394.587362) (xy 313.533322 -394.549656) (xy 313.521852 -394.529056)
			(xy 313.521344 -394.528294) (xy 313.12358 -393.839954) (xy 313.111644 -393.817296) (xy 313.094715 -393.768965)
			(xy 313.086063 -393.718492) (xy 313.08548 -393.692888) (xy 312.54374 -393.692888) (xy 312.855864 -394.232892)
			(xy 312.86862 -394.256246) (xy 312.886726 -394.30628) (xy 312.895926 -394.358688) (xy 312.896504 -394.385292)
			(xy 312.896054 -394.409285) (xy 312.888549 -394.456681) (xy 312.873721 -394.502319) (xy 312.851936 -394.545075)
			(xy 312.823731 -394.583897) (xy 312.7898 -394.617829) (xy 312.750978 -394.646034) (xy 312.708222 -394.66782)
			(xy 312.662585 -394.682648) (xy 312.615189 -394.690154) (xy 312.591196 -394.6906) (xy 312.590942 -394.6906)
			(xy 312.567369 -394.690172) (xy 312.520783 -394.682937) (xy 312.475865 -394.668617) (xy 312.433686 -394.647554)
			(xy 312.395253 -394.62025) (xy 312.36148 -394.587355) (xy 312.333173 -394.549654) (xy 312.321702 -394.529056)
			(xy 312.321194 -394.528294) (xy 311.92343 -393.839954) (xy 311.911569 -393.81727) (xy 311.894713 -393.76894)
			(xy 311.886134 -393.71848) (xy 311.885584 -393.692888) (xy 311.34359 -393.692888) (xy 311.655714 -394.232892)
			(xy 311.668537 -394.256226) (xy 311.686758 -394.306248) (xy 311.696019 -394.358673) (xy 311.696608 -394.385292)
			(xy 311.696154 -394.409298) (xy 311.68864 -394.456717) (xy 311.673797 -394.502377) (xy 311.651991 -394.54515)
			(xy 311.623758 -394.583983) (xy 311.589795 -394.617918) (xy 311.55094 -394.646119) (xy 311.508149 -394.667891)
			(xy 311.462478 -394.682698) (xy 311.415052 -394.690173) (xy 311.391046 -394.6906) (xy 311.367473 -394.690169)
			(xy 311.320887 -394.682935) (xy 311.275969 -394.668615) (xy 311.233791 -394.647553) (xy 311.195357 -394.620249)
			(xy 311.161584 -394.587355) (xy 311.133277 -394.549654) (xy 311.121806 -394.529056) (xy 311.121298 -394.528294)
			(xy 310.723534 -393.839954) (xy 310.711674 -393.81727) (xy 310.694818 -393.76894) (xy 310.686238 -393.71848)
			(xy 310.685688 -393.692888) (xy 310.143694 -393.692888) (xy 310.455818 -394.232892) (xy 310.468641 -394.256226)
			(xy 310.486862 -394.306248) (xy 310.496123 -394.358673) (xy 310.496712 -394.385292) (xy 310.496254 -394.409297)
			(xy 310.48874 -394.456717) (xy 310.473898 -394.502376) (xy 310.452091 -394.545149) (xy 310.423859 -394.583981)
			(xy 310.389897 -394.617917) (xy 310.351042 -394.646118) (xy 310.308252 -394.66789) (xy 310.262581 -394.682697)
			(xy 310.215156 -394.690172) (xy 310.19115 -394.6906) (xy 310.167577 -394.690166) (xy 310.120991 -394.682932)
			(xy 310.076073 -394.668613) (xy 310.033895 -394.647551) (xy 309.995461 -394.620248) (xy 309.961688 -394.587354)
			(xy 309.933381 -394.549653) (xy 309.92191 -394.529056) (xy 309.921402 -394.528294) (xy 309.523638 -393.839954)
			(xy 309.511778 -393.817269) (xy 309.494922 -393.76894) (xy 309.486342 -393.71848) (xy 309.485792 -393.692888)
			(xy 308.943544 -393.692888) (xy 309.255668 -394.232892) (xy 309.268424 -394.256246) (xy 309.28653 -394.30628)
			(xy 309.29573 -394.358688) (xy 309.296308 -394.385292) (xy 309.295854 -394.409285) (xy 309.288349 -394.45668)
			(xy 309.273521 -394.502318) (xy 309.251737 -394.545074) (xy 309.223532 -394.583896) (xy 309.189602 -394.617827)
			(xy 309.150781 -394.646033) (xy 309.108025 -394.667818) (xy 309.062388 -394.682647) (xy 309.014993 -394.690154)
			(xy 308.991 -394.6906) (xy 308.967426 -394.690206) (xy 308.920838 -394.682965) (xy 308.875919 -394.668639)
			(xy 308.833741 -394.64757) (xy 308.795308 -394.620261) (xy 308.761536 -394.587361) (xy 308.73323 -394.549656)
			(xy 308.72176 -394.529056) (xy 308.721252 -394.528294) (xy 308.323488 -393.839954) (xy 308.311553 -393.817296)
			(xy 308.294623 -393.768965) (xy 308.285971 -393.718491) (xy 308.285388 -393.692888) (xy 307.743648 -393.692888)
			(xy 308.055772 -394.232892) (xy 308.068528 -394.256246) (xy 308.086634 -394.30628) (xy 308.095834 -394.358688)
			(xy 308.096412 -394.385292) (xy 308.095954 -394.409285) (xy 308.088449 -394.45668) (xy 308.073622 -394.502317)
			(xy 308.051838 -394.545073) (xy 308.023634 -394.583894) (xy 307.989703 -394.617826) (xy 307.950883 -394.646032)
			(xy 307.908128 -394.667817) (xy 307.862491 -394.682646) (xy 307.815097 -394.690154) (xy 307.791104 -394.6906)
			(xy 307.76753 -394.690203) (xy 307.720942 -394.682962) (xy 307.676023 -394.668637) (xy 307.633845 -394.647569)
			(xy 307.595412 -394.62026) (xy 307.56164 -394.587361) (xy 307.533335 -394.549656) (xy 307.521864 -394.529056)
			(xy 307.521356 -394.528294) (xy 307.123592 -393.839954) (xy 307.111657 -393.817295) (xy 307.094727 -393.768965)
			(xy 307.086075 -393.718491) (xy 307.085492 -393.692888) (xy 306.543752 -393.692888) (xy 306.855876 -394.232892)
			(xy 306.868624 -394.25625) (xy 306.886735 -394.306281) (xy 306.895938 -394.358688) (xy 306.896516 -394.385292)
			(xy 306.89603 -394.409283) (xy 306.888525 -394.456673) (xy 306.8737 -394.502306) (xy 306.851918 -394.545059)
			(xy 306.823716 -394.583877) (xy 306.789789 -394.617806) (xy 306.750972 -394.646009) (xy 306.708221 -394.667793)
			(xy 306.662589 -394.682622) (xy 306.615199 -394.690129) (xy 306.591208 -394.6906) (xy 306.590954 -394.6906)
			(xy 306.567382 -394.690163) (xy 306.520795 -394.682929) (xy 306.475878 -394.668611) (xy 306.433699 -394.64755)
			(xy 306.395266 -394.620247) (xy 306.361493 -394.587353) (xy 306.333185 -394.549653) (xy 306.321714 -394.529056)
			(xy 306.321206 -394.528294) (xy 305.923442 -393.839954) (xy 305.911582 -393.817269) (xy 305.894726 -393.76894)
			(xy 305.886146 -393.71848) (xy 305.885596 -393.692888) (xy 305.343602 -393.692888) (xy 305.655726 -394.232892)
			(xy 305.66855 -394.256225) (xy 305.686771 -394.306247) (xy 305.696031 -394.358673) (xy 305.69662 -394.385292)
			(xy 305.696154 -394.409297) (xy 305.688641 -394.456716) (xy 305.673798 -394.502374) (xy 305.651993 -394.545146)
			(xy 305.623762 -394.583979) (xy 305.5898 -394.617914) (xy 305.550946 -394.646115) (xy 305.508157 -394.667888)
			(xy 305.462488 -394.682695) (xy 305.415063 -394.690172) (xy 305.391058 -394.6906) (xy 305.367486 -394.690159)
			(xy 305.3209 -394.682927) (xy 305.275982 -394.668609) (xy 305.233804 -394.647548) (xy 305.19537 -394.620246)
			(xy 305.161597 -394.587353) (xy 305.13329 -394.549653) (xy 305.121818 -394.529056) (xy 305.12131 -394.528294)
			(xy 304.723546 -393.839954) (xy 304.711686 -393.817269) (xy 304.69483 -393.76894) (xy 304.68625 -393.71848)
			(xy 304.6857 -393.692888) (xy 304.143706 -393.692888) (xy 304.45583 -394.232892) (xy 304.468654 -394.256225)
			(xy 304.486875 -394.306247) (xy 304.496135 -394.358673) (xy 304.496724 -394.385292) (xy 304.496254 -394.409297)
			(xy 304.488741 -394.456715) (xy 304.473899 -394.502373) (xy 304.452094 -394.545145) (xy 304.423863 -394.583977)
			(xy 304.389902 -394.617912) (xy 304.351049 -394.646114) (xy 304.30826 -394.667887) (xy 304.262591 -394.682694)
			(xy 304.215167 -394.690172) (xy 304.191162 -394.6906) (xy 304.16759 -394.690156) (xy 304.121004 -394.682924)
			(xy 304.076086 -394.668607) (xy 304.033908 -394.647547) (xy 303.995474 -394.620245) (xy 303.961701 -394.587352)
			(xy 303.933394 -394.549653) (xy 303.921922 -394.529056) (xy 303.921414 -394.528294) (xy 303.52365 -393.839954)
			(xy 303.511791 -393.817269) (xy 303.494934 -393.76894) (xy 303.486354 -393.71848) (xy 303.485804 -393.692888)
			(xy 2.509012 -393.692888) (xy 2.509012 -396.171674) (xy 296.901108 -396.171674) (xy 296.901108 -395.308074)
			(xy 296.901594 -395.280823) (xy 296.90935 -395.226875) (xy 296.924705 -395.17458) (xy 296.947347 -395.125003)
			(xy 296.976813 -395.079153) (xy 297.012504 -395.037962) (xy 297.053695 -395.002271) (xy 297.099545 -394.972805)
			(xy 297.149122 -394.950163) (xy 297.201417 -394.934808) (xy 297.255365 -394.927052) (xy 297.309867 -394.927052)
			(xy 297.363815 -394.934808) (xy 297.41611 -394.950163) (xy 297.465687 -394.972805) (xy 297.511537 -395.002271)
			(xy 297.552728 -395.037962) (xy 297.588419 -395.079153) (xy 297.617885 -395.125003) (xy 297.640527 -395.17458)
			(xy 297.655882 -395.226875) (xy 297.663638 -395.280823) (xy 297.664124 -395.308074) (xy 297.664124 -396.171674)
			(xy 329.428856 -396.171674) (xy 329.428856 -395.308074) (xy 329.429342 -395.280823) (xy 329.437098 -395.226875)
			(xy 329.452453 -395.17458) (xy 329.475095 -395.125003) (xy 329.504561 -395.079153) (xy 329.540252 -395.037962)
			(xy 329.581443 -395.002271) (xy 329.627293 -394.972805) (xy 329.67687 -394.950163) (xy 329.729165 -394.934808)
			(xy 329.783113 -394.927052) (xy 329.837615 -394.927052) (xy 329.891563 -394.934808) (xy 329.943858 -394.950163)
			(xy 329.993435 -394.972805) (xy 330.039285 -395.002271) (xy 330.080476 -395.037962) (xy 330.116167 -395.079153)
			(xy 330.145633 -395.125003) (xy 330.168275 -395.17458) (xy 330.18363 -395.226875) (xy 330.191386 -395.280823)
			(xy 330.191872 -395.308074) (xy 330.191872 -396.171674) (xy 364.001304 -396.171674) (xy 364.001304 -395.308074)
			(xy 364.00179 -395.280823) (xy 364.009546 -395.226875) (xy 364.024901 -395.17458) (xy 364.047543 -395.125003)
			(xy 364.077009 -395.079153) (xy 364.1127 -395.037962) (xy 364.153891 -395.002271) (xy 364.199741 -394.972805)
			(xy 364.249318 -394.950163) (xy 364.301613 -394.934808) (xy 364.355561 -394.927052) (xy 364.410063 -394.927052)
			(xy 364.464011 -394.934808) (xy 364.516306 -394.950163) (xy 364.565883 -394.972805) (xy 364.611733 -395.002271)
			(xy 364.652924 -395.037962) (xy 364.688615 -395.079153) (xy 364.718081 -395.125003) (xy 364.740723 -395.17458)
			(xy 364.756078 -395.226875) (xy 364.763834 -395.280823) (xy 364.76432 -395.308074) (xy 364.76432 -396.171674)
			(xy 396.529052 -396.171674) (xy 396.529052 -395.308074) (xy 396.529538 -395.280823) (xy 396.537294 -395.226875)
			(xy 396.552649 -395.17458) (xy 396.575291 -395.125003) (xy 396.604757 -395.079153) (xy 396.640448 -395.037962)
			(xy 396.681639 -395.002271) (xy 396.727489 -394.972805) (xy 396.777066 -394.950163) (xy 396.829361 -394.934808)
			(xy 396.883309 -394.927052) (xy 396.937811 -394.927052) (xy 396.991759 -394.934808) (xy 397.044054 -394.950163)
			(xy 397.093631 -394.972805) (xy 397.139481 -395.002271) (xy 397.180672 -395.037962) (xy 397.216363 -395.079153)
			(xy 397.245829 -395.125003) (xy 397.268471 -395.17458) (xy 397.283826 -395.226875) (xy 397.291582 -395.280823)
			(xy 397.292068 -395.308074) (xy 397.292068 -396.171674) (xy 397.291582 -396.198925) (xy 397.283826 -396.252873)
			(xy 397.268471 -396.305168) (xy 397.245829 -396.354745) (xy 397.216363 -396.400595) (xy 397.180672 -396.441786)
			(xy 397.139481 -396.477477) (xy 397.093631 -396.506943) (xy 397.044054 -396.529585) (xy 396.991759 -396.54494)
			(xy 396.937811 -396.552696) (xy 396.883309 -396.552696) (xy 396.829361 -396.54494) (xy 396.777066 -396.529585)
			(xy 396.727489 -396.506943) (xy 396.681639 -396.477477) (xy 396.640448 -396.441786) (xy 396.604757 -396.400595)
			(xy 396.575291 -396.354745) (xy 396.552649 -396.305168) (xy 396.537294 -396.252873) (xy 396.529538 -396.198925)
			(xy 396.529052 -396.171674) (xy 364.76432 -396.171674) (xy 364.763834 -396.198925) (xy 364.756078 -396.252873)
			(xy 364.740723 -396.305168) (xy 364.718081 -396.354745) (xy 364.688615 -396.400595) (xy 364.652924 -396.441786)
			(xy 364.611733 -396.477477) (xy 364.565883 -396.506943) (xy 364.516306 -396.529585) (xy 364.464011 -396.54494)
			(xy 364.410063 -396.552696) (xy 364.355561 -396.552696) (xy 364.301613 -396.54494) (xy 364.249318 -396.529585)
			(xy 364.199741 -396.506943) (xy 364.153891 -396.477477) (xy 364.1127 -396.441786) (xy 364.077009 -396.400595)
			(xy 364.047543 -396.354745) (xy 364.024901 -396.305168) (xy 364.009546 -396.252873) (xy 364.00179 -396.198925)
			(xy 364.001304 -396.171674) (xy 330.191872 -396.171674) (xy 330.191386 -396.198925) (xy 330.18363 -396.252873)
			(xy 330.168275 -396.305168) (xy 330.145633 -396.354745) (xy 330.116167 -396.400595) (xy 330.080476 -396.441786)
			(xy 330.039285 -396.477477) (xy 329.993435 -396.506943) (xy 329.943858 -396.529585) (xy 329.891563 -396.54494)
			(xy 329.837615 -396.552696) (xy 329.783113 -396.552696) (xy 329.729165 -396.54494) (xy 329.67687 -396.529585)
			(xy 329.627293 -396.506943) (xy 329.581443 -396.477477) (xy 329.540252 -396.441786) (xy 329.504561 -396.400595)
			(xy 329.475095 -396.354745) (xy 329.452453 -396.305168) (xy 329.437098 -396.252873) (xy 329.429342 -396.198925)
			(xy 329.428856 -396.171674) (xy 297.664124 -396.171674) (xy 297.663638 -396.198925) (xy 297.655882 -396.252873)
			(xy 297.640527 -396.305168) (xy 297.617885 -396.354745) (xy 297.588419 -396.400595) (xy 297.552728 -396.441786)
			(xy 297.511537 -396.477477) (xy 297.465687 -396.506943) (xy 297.41611 -396.529585) (xy 297.363815 -396.54494)
			(xy 297.309867 -396.552696) (xy 297.255365 -396.552696) (xy 297.201417 -396.54494) (xy 297.149122 -396.529585)
			(xy 297.099545 -396.506943) (xy 297.053695 -396.477477) (xy 297.012504 -396.441786) (xy 296.976813 -396.400595)
			(xy 296.947347 -396.354745) (xy 296.924705 -396.305168) (xy 296.90935 -396.252873) (xy 296.901594 -396.198925)
			(xy 296.901108 -396.171674) (xy 2.509012 -396.171674) (xy 2.509012 -397.133285) (xy 303.485946 -397.133285)
			(xy 303.493277 -397.085739) (xy 303.50797 -397.039929) (xy 303.529661 -396.996989) (xy 303.557813 -396.957979)
			(xy 303.591732 -396.923863) (xy 303.630579 -396.895485) (xy 303.673393 -396.873546) (xy 303.719117 -396.858589)
			(xy 303.766619 -396.850982) (xy 303.814727 -396.850915) (xy 303.862251 -396.858388) (xy 303.908016 -396.873218)
			(xy 303.950892 -396.895037) (xy 303.989818 -396.923306) (xy 304.023832 -396.957327) (xy 304.052094 -396.996258)
			(xy 304.0634 -397.017494) (xy 304.063908 -397.018764) (xy 304.130089 -397.133284) (xy 304.685849 -397.133284)
			(xy 304.693181 -397.085739) (xy 304.707873 -397.03993) (xy 304.729564 -396.996991) (xy 304.757716 -396.957981)
			(xy 304.791634 -396.923866) (xy 304.83048 -396.895488) (xy 304.873294 -396.87355) (xy 304.919017 -396.858592)
			(xy 304.966519 -396.850986) (xy 305.014626 -396.850918) (xy 305.062149 -396.858392) (xy 305.107914 -396.873221)
			(xy 305.150789 -396.895039) (xy 305.189714 -396.923308) (xy 305.223728 -396.957328) (xy 305.25199 -396.996259)
			(xy 305.263296 -397.017494) (xy 305.263804 -397.018764) (xy 305.343656 -397.15694) (xy 305.885596 -397.15694)
			(xy 305.885596 -397.156432) (xy 305.886104 -397.131519) (xy 305.894193 -397.082353) (xy 305.910146 -397.035149)
			(xy 305.92141 -397.012922) (xy 305.92141 -397.012668) (xy 305.933061 -396.991771) (xy 305.961857 -396.953565)
			(xy 305.996256 -396.920313) (xy 306.035416 -396.89283) (xy 306.078382 -396.871785) (xy 306.124103 -396.857694)
			(xy 306.171461 -396.850901) (xy 306.219298 -396.851573) (xy 306.266447 -396.859691) (xy 306.311754 -396.875059)
			(xy 306.354113 -396.8973) (xy 306.392487 -396.925872) (xy 306.42594 -396.960075) (xy 306.453653 -396.999074)
			(xy 306.464716 -397.020288) (xy 306.465478 -397.021812) (xy 306.529918 -397.133286) (xy 307.085808 -397.133286)
			(xy 307.09314 -397.085733) (xy 307.107835 -397.039917) (xy 307.129528 -396.99697) (xy 307.157686 -396.957954)
			(xy 307.19161 -396.923833) (xy 307.230463 -396.895451) (xy 307.273284 -396.873509) (xy 307.319015 -396.858551)
			(xy 307.366525 -396.850944) (xy 307.41464 -396.850878) (xy 307.462171 -396.858355) (xy 307.507942 -396.873188)
			(xy 307.550823 -396.895012) (xy 307.589754 -396.923288) (xy 307.623771 -396.957315) (xy 307.652035 -396.996254)
			(xy 307.663342 -397.017494) (xy 307.66385 -397.018764) (xy 307.730033 -397.133286) (xy 308.285712 -397.133286)
			(xy 308.293044 -397.085734) (xy 308.307738 -397.039918) (xy 308.329432 -396.996971) (xy 308.357588 -396.957956)
			(xy 308.391512 -396.923836) (xy 308.430364 -396.895454) (xy 308.473185 -396.873513) (xy 308.518915 -396.858554)
			(xy 308.566424 -396.850948) (xy 308.614539 -396.850882) (xy 308.662069 -396.858358) (xy 308.70784 -396.873191)
			(xy 308.75072 -396.895015) (xy 308.78965 -396.92329) (xy 308.823668 -396.957317) (xy 308.851931 -396.996255)
			(xy 308.863238 -397.017494) (xy 308.863746 -397.018764) (xy 308.929927 -397.133284) (xy 309.485956 -397.133284)
			(xy 309.493288 -397.08574) (xy 309.50798 -397.039933) (xy 309.52967 -396.996994) (xy 309.557821 -396.957986)
			(xy 309.591739 -396.923872) (xy 309.630584 -396.895495) (xy 309.673396 -396.873557) (xy 309.719117 -396.858599)
			(xy 309.766618 -396.850993) (xy 309.814724 -396.850925) (xy 309.862246 -396.858398) (xy 309.908009 -396.873226)
			(xy 309.950883 -396.895044) (xy 309.989807 -396.923311) (xy 310.023821 -396.95733) (xy 310.052082 -396.996259)
			(xy 310.063388 -397.017494) (xy 310.063896 -397.018764) (xy 310.130077 -397.133284) (xy 310.68586 -397.133284)
			(xy 310.693191 -397.085741) (xy 310.707883 -397.039934) (xy 310.729573 -396.996996) (xy 310.757724 -396.957988)
			(xy 310.791641 -396.923874) (xy 310.830485 -396.895498) (xy 310.873297 -396.87356) (xy 310.919017 -396.858603)
			(xy 310.966517 -396.850997) (xy 311.014622 -396.850929) (xy 311.062144 -396.858401) (xy 311.107907 -396.873229)
			(xy 311.15078 -396.895046) (xy 311.189704 -396.923313) (xy 311.223717 -396.957331) (xy 311.251978 -396.99626)
			(xy 311.263284 -397.017494) (xy 311.263792 -397.018764) (xy 311.343644 -397.15694) (xy 311.885584 -397.15694)
			(xy 311.885584 -397.156432) (xy 311.886093 -397.131519) (xy 311.894182 -397.082353) (xy 311.910134 -397.035149)
			(xy 311.921398 -397.012922) (xy 311.921398 -397.012668) (xy 311.933067 -396.991781) (xy 311.961861 -396.953576)
			(xy 311.996258 -396.920325) (xy 312.035417 -396.892842) (xy 312.078381 -396.871797) (xy 312.1241 -396.857706)
			(xy 312.171456 -396.850913) (xy 312.219292 -396.851583) (xy 312.266439 -396.8597) (xy 312.311745 -396.875067)
			(xy 312.354103 -396.897307) (xy 312.392476 -396.925876) (xy 312.425928 -396.960078) (xy 312.453641 -396.999075)
			(xy 312.464704 -397.020288) (xy 312.465466 -397.021812) (xy 312.529906 -397.133286) (xy 313.085819 -397.133286)
			(xy 313.093151 -397.085735) (xy 313.107845 -397.03992) (xy 313.129538 -396.996975) (xy 313.157693 -396.957961)
			(xy 313.191616 -396.923841) (xy 313.230467 -396.895461) (xy 313.273286 -396.87352) (xy 313.319015 -396.858561)
			(xy 313.366523 -396.850955) (xy 313.414636 -396.850889) (xy 313.462165 -396.858364) (xy 313.507935 -396.873197)
			(xy 313.550814 -396.895019) (xy 313.589743 -396.923293) (xy 313.62376 -396.957319) (xy 313.652023 -396.996255)
			(xy 313.66333 -397.017494) (xy 313.663838 -397.018764) (xy 313.730021 -397.133286) (xy 314.285722 -397.133286)
			(xy 314.293054 -397.085735) (xy 314.307748 -397.039921) (xy 314.329441 -396.996977) (xy 314.357596 -396.957963)
			(xy 314.391518 -396.923844) (xy 314.430369 -396.895464) (xy 314.473187 -396.873523) (xy 314.518915 -396.858565)
			(xy 314.566423 -396.850959) (xy 314.614535 -396.850892) (xy 314.662063 -396.858368) (xy 314.707832 -396.8732)
			(xy 314.750711 -396.895022) (xy 314.78964 -396.923295) (xy 314.823656 -396.95732) (xy 314.851919 -396.996256)
			(xy 314.863226 -397.017494) (xy 314.863734 -397.018764) (xy 314.929915 -397.133284) (xy 315.485967 -397.133284)
			(xy 315.493298 -397.085742) (xy 315.50799 -397.039936) (xy 315.529679 -396.997) (xy 315.557829 -396.957993)
			(xy 315.591745 -396.92388) (xy 315.630588 -396.895504) (xy 315.673398 -396.873567) (xy 315.719118 -396.85861)
			(xy 315.766616 -396.851004) (xy 315.81472 -396.850936) (xy 315.86224 -396.858408) (xy 315.908002 -396.873235)
			(xy 315.950874 -396.895051) (xy 315.989797 -396.923317) (xy 316.023809 -396.957333) (xy 316.05207 -396.99626)
			(xy 316.063376 -397.017494) (xy 316.063884 -397.018764) (xy 316.157051 -397.179979) (xy 316.685912 -397.179979)
			(xy 316.686161 -397.129044) (xy 316.694854 -397.078856) (xy 316.711752 -397.030805) (xy 316.736385 -396.986222)
			(xy 316.768071 -396.946342) (xy 316.805933 -396.912271) (xy 316.848922 -396.884951) (xy 316.895847 -396.86514)
			(xy 316.945408 -396.853387) (xy 316.996232 -396.850016) (xy 317.046911 -396.855122) (xy 317.096041 -396.868563)
			(xy 317.142261 -396.889967) (xy 317.184291 -396.91874) (xy 317.220966 -396.954086) (xy 317.251271 -396.995026)
			(xy 317.263272 -397.017494) (xy 317.26378 -397.018764) (xy 317.343632 -397.15694) (xy 317.885572 -397.15694)
			(xy 317.885572 -397.156432) (xy 317.886082 -397.131519) (xy 317.894171 -397.082353) (xy 317.910123 -397.035149)
			(xy 317.921386 -397.012922) (xy 317.921386 -397.012668) (xy 317.933073 -396.991792) (xy 317.961866 -396.953587)
			(xy 317.996261 -396.920337) (xy 318.035418 -396.892854) (xy 318.07838 -396.871809) (xy 318.124097 -396.857718)
			(xy 318.171451 -396.850924) (xy 318.219286 -396.851593) (xy 318.266431 -396.859709) (xy 318.311736 -396.875075)
			(xy 318.354092 -396.897313) (xy 318.392465 -396.925881) (xy 318.425916 -396.96008) (xy 318.453629 -396.999076)
			(xy 318.464692 -397.020288) (xy 318.465454 -397.021812) (xy 318.529894 -397.133285) (xy 319.08583 -397.133285)
			(xy 319.093161 -397.085736) (xy 319.107855 -397.039924) (xy 319.129547 -396.996981) (xy 319.157701 -396.957968)
			(xy 319.191623 -396.92385) (xy 319.230472 -396.89547) (xy 319.273289 -396.87353) (xy 319.319016 -396.858572)
			(xy 319.366522 -396.850966) (xy 319.414633 -396.850899) (xy 319.46216 -396.858374) (xy 319.507928 -396.873205)
			(xy 319.550805 -396.895026) (xy 319.589733 -396.923298) (xy 319.623749 -396.957322) (xy 319.652011 -396.996256)
			(xy 319.663318 -397.017494) (xy 319.663826 -397.018764) (xy 319.743678 -397.15694) (xy 320.285364 -397.15694)
			(xy 320.285364 -397.156432) (xy 320.28588 -397.131505) (xy 320.294022 -397.08232) (xy 320.310092 -397.035126)
			(xy 320.321432 -397.012922) (xy 320.321432 -397.012668) (xy 320.33305 -396.991751) (xy 320.361849 -396.953544)
			(xy 320.396251 -396.920292) (xy 320.435415 -396.892808) (xy 320.478384 -396.871763) (xy 320.524108 -396.857673)
			(xy 320.571469 -396.850881) (xy 320.61931 -396.851554) (xy 320.666462 -396.859675) (xy 320.711771 -396.875045)
			(xy 320.754132 -396.897289) (xy 320.792508 -396.925864) (xy 320.825961 -396.96007) (xy 320.853675 -396.999072)
			(xy 320.864738 -397.020288) (xy 320.8655 -397.021812) (xy 320.956931 -397.179977) (xy 321.486019 -397.179977)
			(xy 321.486268 -397.129044) (xy 321.494961 -397.078857) (xy 321.511858 -397.030807) (xy 321.536491 -396.986226)
			(xy 321.568176 -396.946348) (xy 321.606037 -396.912277) (xy 321.649025 -396.884958) (xy 321.695948 -396.865147)
			(xy 321.745508 -396.853394) (xy 321.79633 -396.850023) (xy 321.847007 -396.855129) (xy 321.896136 -396.868569)
			(xy 321.942355 -396.889972) (xy 321.984384 -396.918744) (xy 322.021058 -396.954088) (xy 322.051363 -396.995026)
			(xy 322.063364 -397.017494) (xy 322.063872 -397.018764) (xy 322.130055 -397.133287) (xy 336.013603 -397.133287)
			(xy 336.020935 -397.085732) (xy 336.035629 -397.039915) (xy 336.057324 -396.996967) (xy 336.085482 -396.95795)
			(xy 336.119407 -396.923829) (xy 336.15826 -396.895446) (xy 336.201082 -396.873504) (xy 336.246814 -396.858545)
			(xy 336.294325 -396.850939) (xy 336.342442 -396.850873) (xy 336.389974 -396.85835) (xy 336.435746 -396.873184)
			(xy 336.478628 -396.895009) (xy 336.517559 -396.923285) (xy 336.551577 -396.957314) (xy 336.579841 -396.996254)
			(xy 336.591148 -397.017494) (xy 336.591656 -397.018764) (xy 336.657839 -397.133287) (xy 337.213506 -397.133287)
			(xy 337.220838 -397.085733) (xy 337.235533 -397.039916) (xy 337.257227 -396.996969) (xy 337.285384 -396.957952)
			(xy 337.319309 -396.923831) (xy 337.358162 -396.895449) (xy 337.400983 -396.873508) (xy 337.446714 -396.858549)
			(xy 337.494225 -396.850942) (xy 337.54234 -396.850877) (xy 337.589872 -396.858353) (xy 337.635644 -396.873187)
			(xy 337.678525 -396.895011) (xy 337.717455 -396.923287) (xy 337.751473 -396.957315) (xy 337.779737 -396.996254)
			(xy 337.791044 -397.017494) (xy 337.791552 -397.018764) (xy 337.857735 -397.133286) (xy 338.41341 -397.133286)
			(xy 338.420742 -397.085733) (xy 338.435436 -397.039917) (xy 338.45713 -396.996971) (xy 338.485287 -396.957955)
			(xy 338.519211 -396.923834) (xy 338.558063 -396.895453) (xy 338.600884 -396.873511) (xy 338.646615 -396.858552)
			(xy 338.694124 -396.850946) (xy 338.742239 -396.85088) (xy 338.78977 -396.858356) (xy 338.835541 -396.87319)
			(xy 338.878422 -396.895014) (xy 338.917352 -396.923289) (xy 338.951369 -396.957316) (xy 338.979633 -396.996254)
			(xy 338.99094 -397.017494) (xy 338.991448 -397.018764) (xy 339.057629 -397.133284) (xy 339.613655 -397.133284)
			(xy 339.620986 -397.08574) (xy 339.635678 -397.039932) (xy 339.657368 -396.996993) (xy 339.68552 -396.957985)
			(xy 339.719438 -396.92387) (xy 339.758283 -396.895493) (xy 339.801095 -396.873555) (xy 339.846817 -396.858598)
			(xy 339.894318 -396.850991) (xy 339.942424 -396.850924) (xy 339.989947 -396.858397) (xy 340.03571 -396.873225)
			(xy 340.078584 -396.895043) (xy 340.117509 -396.923311) (xy 340.151522 -396.95733) (xy 340.179784 -396.996259)
			(xy 340.19109 -397.017494) (xy 340.191598 -397.018764) (xy 340.257779 -397.133284) (xy 340.813558 -397.133284)
			(xy 340.82089 -397.08574) (xy 340.835582 -397.039933) (xy 340.857271 -396.996995) (xy 340.885423 -396.957987)
			(xy 340.91934 -396.923873) (xy 340.958184 -396.895496) (xy 341.000996 -396.873558) (xy 341.046717 -396.858601)
			(xy 341.094218 -396.850995) (xy 341.142323 -396.850927) (xy 341.189845 -396.8584) (xy 341.235608 -396.873228)
			(xy 341.278481 -396.895045) (xy 341.317406 -396.923312) (xy 341.351419 -396.957331) (xy 341.37968 -396.996259)
			(xy 341.390986 -397.017494) (xy 341.391494 -397.018764) (xy 341.457677 -397.133286) (xy 342.013613 -397.133286)
			(xy 342.020945 -397.085734) (xy 342.03564 -397.039918) (xy 342.057333 -396.996972) (xy 342.08549 -396.957957)
			(xy 342.119413 -396.923837) (xy 342.158265 -396.895456) (xy 342.201085 -396.873515) (xy 342.246815 -396.858556)
			(xy 342.294324 -396.85095) (xy 342.342438 -396.850884) (xy 342.389968 -396.858359) (xy 342.435739 -396.873192)
			(xy 342.478619 -396.895016) (xy 342.517549 -396.92329) (xy 342.551566 -396.957317) (xy 342.579829 -396.996255)
			(xy 342.591136 -397.017494) (xy 342.591644 -397.018764) (xy 342.657827 -397.133286) (xy 343.213517 -397.133286)
			(xy 343.220849 -397.085734) (xy 343.235543 -397.03992) (xy 343.257236 -396.996974) (xy 343.285392 -396.95796)
			(xy 343.319315 -396.92384) (xy 343.358166 -396.895459) (xy 343.400986 -396.873518) (xy 343.446715 -396.85856)
			(xy 343.494223 -396.850953) (xy 343.542337 -396.850887) (xy 343.589866 -396.858363) (xy 343.635636 -396.873195)
			(xy 343.678516 -396.895018) (xy 343.717445 -396.923292) (xy 343.751462 -396.957318) (xy 343.779725 -396.996255)
			(xy 343.791032 -397.017494) (xy 343.79154 -397.018764) (xy 343.857723 -397.133286) (xy 344.413421 -397.133286)
			(xy 344.420752 -397.085735) (xy 344.435446 -397.039921) (xy 344.457139 -396.996976) (xy 344.485295 -396.957962)
			(xy 344.519217 -396.923843) (xy 344.558068 -396.895462) (xy 344.600887 -396.873522) (xy 344.646615 -396.858563)
			(xy 344.694123 -396.850957) (xy 344.742236 -396.850891) (xy 344.789764 -396.858366) (xy 344.835534 -396.873198)
			(xy 344.878413 -396.895021) (xy 344.917342 -396.923294) (xy 344.951358 -396.957319) (xy 344.979621 -396.996256)
			(xy 344.990928 -397.017494) (xy 344.991436 -397.018764) (xy 345.057617 -397.133284) (xy 345.613665 -397.133284)
			(xy 345.620997 -397.085741) (xy 345.635688 -397.039936) (xy 345.657377 -396.996999) (xy 345.685528 -396.957992)
			(xy 345.719444 -396.923879) (xy 345.758287 -396.895503) (xy 345.801098 -396.873565) (xy 345.846818 -396.858609)
			(xy 345.894317 -396.851002) (xy 345.942421 -396.850934) (xy 345.989941 -396.858406) (xy 346.035703 -396.873234)
			(xy 346.078575 -396.89505) (xy 346.117499 -396.923316) (xy 346.151511 -396.957333) (xy 346.179772 -396.99626)
			(xy 346.191078 -397.017494) (xy 346.191586 -397.018764) (xy 346.284753 -397.179979) (xy 346.813611 -397.179979)
			(xy 346.813859 -397.129044) (xy 346.822553 -397.078855) (xy 346.83945 -397.030804) (xy 346.864083 -396.986221)
			(xy 346.89577 -396.946341) (xy 346.933633 -396.912269) (xy 346.976622 -396.884949) (xy 347.023547 -396.865138)
			(xy 347.073108 -396.853385) (xy 347.123932 -396.850014) (xy 347.174611 -396.85512) (xy 347.223742 -396.868562)
			(xy 347.269962 -396.889966) (xy 347.311992 -396.918739) (xy 347.348668 -396.954086) (xy 347.378973 -396.995025)
			(xy 347.390974 -397.017494) (xy 347.391482 -397.018764) (xy 347.457665 -397.133286) (xy 348.013624 -397.133286)
			(xy 348.020956 -397.085735) (xy 348.03565 -397.039922) (xy 348.057342 -396.996978) (xy 348.085497 -396.957964)
			(xy 348.119419 -396.923846) (xy 348.15827 -396.895466) (xy 348.201088 -396.873525) (xy 348.246815 -396.858567)
			(xy 348.294322 -396.850961) (xy 348.342434 -396.850894) (xy 348.389962 -396.858369) (xy 348.435731 -396.873201)
			(xy 348.47861 -396.895023) (xy 348.517538 -396.923296) (xy 348.551554 -396.95732) (xy 348.579817 -396.996256)
			(xy 348.591124 -397.017494) (xy 348.591632 -397.018764) (xy 348.657814 -397.133285) (xy 349.213528 -397.133285)
			(xy 349.220859 -397.085736) (xy 349.235553 -397.039923) (xy 349.257245 -396.99698) (xy 349.2854 -396.957967)
			(xy 349.319322 -396.923849) (xy 349.358171 -396.895469) (xy 349.400989 -396.873529) (xy 349.446716 -396.858571)
			(xy 349.494222 -396.850964) (xy 349.542333 -396.850898) (xy 349.58986 -396.858372) (xy 349.635629 -396.873204)
			(xy 349.678507 -396.895025) (xy 349.717435 -396.923297) (xy 349.751451 -396.957321) (xy 349.779713 -396.996256)
			(xy 349.79102 -397.017494) (xy 349.791528 -397.018764) (xy 349.85771 -397.133285) (xy 350.413431 -397.133285)
			(xy 350.420763 -397.085737) (xy 350.435456 -397.039924) (xy 350.457148 -396.996982) (xy 350.485303 -396.957969)
			(xy 350.519224 -396.923851) (xy 350.558073 -396.895472) (xy 350.60089 -396.873532) (xy 350.646616 -396.858574)
			(xy 350.694121 -396.850968) (xy 350.742232 -396.850901) (xy 350.789759 -396.858376) (xy 350.835526 -396.873207)
			(xy 350.878404 -396.895028) (xy 350.917331 -396.923299) (xy 350.951347 -396.957323) (xy 350.979609 -396.996257)
			(xy 350.990916 -397.017494) (xy 350.991424 -397.018764) (xy 351.084589 -397.179977) (xy 351.613718 -397.179977)
			(xy 351.613966 -397.129044) (xy 351.62266 -397.078857) (xy 351.639557 -397.030807) (xy 351.664189 -396.986225)
			(xy 351.695875 -396.946346) (xy 351.733736 -396.912275) (xy 351.776724 -396.884956) (xy 351.823648 -396.865145)
			(xy 351.873208 -396.853392) (xy 351.92403 -396.850021) (xy 351.974708 -396.855127) (xy 352.023837 -396.868568)
			(xy 352.070056 -396.88997) (xy 352.112086 -396.918743) (xy 352.14876 -396.954088) (xy 352.179065 -396.995026)
			(xy 352.191066 -397.017494) (xy 352.191574 -397.018764) (xy 352.284739 -397.179976) (xy 352.813621 -397.179976)
			(xy 352.81387 -397.129044) (xy 352.822563 -397.078857) (xy 352.83946 -397.030808) (xy 352.864092 -396.986227)
			(xy 352.895778 -396.946349) (xy 352.933638 -396.912278) (xy 352.976626 -396.88496) (xy 353.023549 -396.865149)
			(xy 353.073108 -396.853396) (xy 353.123929 -396.850025) (xy 353.174606 -396.85513) (xy 353.223735 -396.86857)
			(xy 353.269953 -396.889973) (xy 353.311982 -396.918745) (xy 353.348657 -396.954089) (xy 353.378961 -396.995027)
			(xy 353.390962 -397.017494) (xy 353.39147 -397.018764) (xy 353.457652 -397.133285) (xy 354.013635 -397.133285)
			(xy 354.020967 -397.085737) (xy 354.03566 -397.039926) (xy 354.057351 -396.996983) (xy 354.085505 -396.957971)
			(xy 354.119426 -396.923854) (xy 354.158274 -396.895475) (xy 354.20109 -396.873536) (xy 354.246816 -396.858578)
			(xy 354.294321 -396.850971) (xy 354.342431 -396.850905) (xy 354.389957 -396.858379) (xy 354.435724 -396.873209)
			(xy 354.478601 -396.89503) (xy 354.517528 -396.923301) (xy 354.551543 -396.957324) (xy 354.579805 -396.996257)
			(xy 354.591112 -397.017494) (xy 354.59162 -397.018764) (xy 354.657801 -397.133284) (xy 370.586149 -397.133284)
			(xy 370.593481 -397.085739) (xy 370.608173 -397.03993) (xy 370.629864 -396.996991) (xy 370.658016 -396.957981)
			(xy 370.691934 -396.923866) (xy 370.73078 -396.895488) (xy 370.773594 -396.87355) (xy 370.819317 -396.858592)
			(xy 370.866819 -396.850986) (xy 370.914926 -396.850918) (xy 370.962449 -396.858392) (xy 371.008214 -396.873221)
			(xy 371.051089 -396.895039) (xy 371.090014 -396.923308) (xy 371.124028 -396.957328) (xy 371.15229 -396.996259)
			(xy 371.163596 -397.017494) (xy 371.164104 -397.018764) (xy 371.230285 -397.133284) (xy 371.786053 -397.133284)
			(xy 371.793384 -397.08574) (xy 371.808077 -397.039932) (xy 371.829767 -396.996992) (xy 371.857919 -396.957983)
			(xy 371.891837 -396.923869) (xy 371.930682 -396.895491) (xy 371.973495 -396.873553) (xy 372.019217 -396.858596)
			(xy 372.066718 -396.850989) (xy 372.114825 -396.850922) (xy 372.162347 -396.858395) (xy 372.208111 -396.873224)
			(xy 372.250986 -396.895042) (xy 372.289911 -396.92331) (xy 372.323924 -396.957329) (xy 372.352186 -396.996259)
			(xy 372.363492 -397.017494) (xy 372.364 -397.018764) (xy 372.430181 -397.133284) (xy 372.985956 -397.133284)
			(xy 372.993288 -397.08574) (xy 373.00798 -397.039933) (xy 373.02967 -396.996994) (xy 373.057821 -396.957986)
			(xy 373.091739 -396.923872) (xy 373.130584 -396.895495) (xy 373.173396 -396.873557) (xy 373.219117 -396.858599)
			(xy 373.266618 -396.850993) (xy 373.314724 -396.850925) (xy 373.362246 -396.858398) (xy 373.408009 -396.873226)
			(xy 373.450883 -396.895044) (xy 373.489807 -396.923311) (xy 373.523821 -396.95733) (xy 373.552082 -396.996259)
			(xy 373.563388 -397.017494) (xy 373.563896 -397.018764) (xy 373.630079 -397.133286) (xy 374.186012 -397.133286)
			(xy 374.193344 -397.085734) (xy 374.208038 -397.039918) (xy 374.229732 -396.996971) (xy 374.257888 -396.957956)
			(xy 374.291812 -396.923836) (xy 374.330664 -396.895454) (xy 374.373485 -396.873513) (xy 374.419215 -396.858554)
			(xy 374.466724 -396.850948) (xy 374.514839 -396.850882) (xy 374.562369 -396.858358) (xy 374.60814 -396.873191)
			(xy 374.65102 -396.895015) (xy 374.68995 -396.92329) (xy 374.723968 -396.957317) (xy 374.752231 -396.996255)
			(xy 374.763538 -397.017494) (xy 374.764046 -397.018764) (xy 374.830229 -397.133286) (xy 375.385915 -397.133286)
			(xy 375.393247 -397.085734) (xy 375.407941 -397.039919) (xy 375.429635 -396.996973) (xy 375.457791 -396.957958)
			(xy 375.491714 -396.923839) (xy 375.530566 -396.895457) (xy 375.573385 -396.873516) (xy 375.619115 -396.858558)
			(xy 375.666624 -396.850952) (xy 375.714737 -396.850885) (xy 375.762267 -396.858361) (xy 375.808037 -396.873194)
			(xy 375.850917 -396.895017) (xy 375.889847 -396.923291) (xy 375.923864 -396.957318) (xy 375.952127 -396.996255)
			(xy 375.963434 -397.017494) (xy 375.963942 -397.018764) (xy 376.030123 -397.133284) (xy 376.58616 -397.133284)
			(xy 376.593491 -397.085741) (xy 376.608183 -397.039934) (xy 376.629873 -396.996996) (xy 376.658024 -396.957988)
			(xy 376.691941 -396.923874) (xy 376.730785 -396.895498) (xy 376.773597 -396.87356) (xy 376.819317 -396.858603)
			(xy 376.866817 -396.850997) (xy 376.914922 -396.850929) (xy 376.962444 -396.858401) (xy 377.008207 -396.873229)
			(xy 377.05108 -396.895046) (xy 377.090004 -396.923313) (xy 377.124017 -396.957331) (xy 377.152278 -396.99626)
			(xy 377.163584 -397.017494) (xy 377.164092 -397.018764) (xy 377.230273 -397.133284) (xy 377.786064 -397.133284)
			(xy 377.793395 -397.085741) (xy 377.808087 -397.039935) (xy 377.829776 -396.996998) (xy 377.857927 -396.957991)
			(xy 377.891843 -396.923877) (xy 377.930687 -396.895501) (xy 377.973498 -396.873564) (xy 378.019218 -396.858607)
			(xy 378.066717 -396.851) (xy 378.114821 -396.850932) (xy 378.162342 -396.858405) (xy 378.208104 -396.873232)
			(xy 378.250977 -396.895049) (xy 378.2899 -396.923315) (xy 378.323913 -396.957332) (xy 378.352174 -396.99626)
			(xy 378.36348 -397.017494) (xy 378.363988 -397.018764) (xy 378.430169 -397.133284) (xy 378.985967 -397.133284)
			(xy 378.993298 -397.085742) (xy 379.00799 -397.039936) (xy 379.029679 -396.997) (xy 379.057829 -396.957993)
			(xy 379.091745 -396.92388) (xy 379.130588 -396.895504) (xy 379.173398 -396.873567) (xy 379.219118 -396.85861)
			(xy 379.266616 -396.851004) (xy 379.31472 -396.850936) (xy 379.36224 -396.858408) (xy 379.408002 -396.873235)
			(xy 379.450874 -396.895051) (xy 379.489797 -396.923317) (xy 379.523809 -396.957333) (xy 379.55207 -396.99626)
			(xy 379.563376 -397.017494) (xy 379.563884 -397.018764) (xy 379.630067 -397.133286) (xy 380.186022 -397.133286)
			(xy 380.193354 -397.085735) (xy 380.208048 -397.039921) (xy 380.229741 -396.996977) (xy 380.257896 -396.957963)
			(xy 380.291818 -396.923844) (xy 380.330669 -396.895464) (xy 380.373487 -396.873523) (xy 380.419215 -396.858565)
			(xy 380.466723 -396.850959) (xy 380.514835 -396.850892) (xy 380.562363 -396.858368) (xy 380.608132 -396.8732)
			(xy 380.651011 -396.895022) (xy 380.68994 -396.923295) (xy 380.723956 -396.95732) (xy 380.752219 -396.996256)
			(xy 380.763526 -397.017494) (xy 380.764034 -397.018764) (xy 380.830217 -397.133286) (xy 381.385926 -397.133286)
			(xy 381.393258 -397.085736) (xy 381.407951 -397.039923) (xy 381.429644 -396.996979) (xy 381.457799 -396.957966)
			(xy 381.49172 -396.923847) (xy 381.53057 -396.895467) (xy 381.573388 -396.873527) (xy 381.619116 -396.858569)
			(xy 381.666622 -396.850962) (xy 381.714734 -396.850896) (xy 381.762261 -396.858371) (xy 381.80803 -396.873202)
			(xy 381.850908 -396.895024) (xy 381.889837 -396.923297) (xy 381.923853 -396.957321) (xy 381.952115 -396.996256)
			(xy 381.963422 -397.017494) (xy 381.96393 -397.018764) (xy 382.057097 -397.179979) (xy 382.586212 -397.179979)
			(xy 382.586461 -397.129044) (xy 382.595154 -397.078856) (xy 382.612052 -397.030805) (xy 382.636685 -396.986222)
			(xy 382.668371 -396.946342) (xy 382.706233 -396.912271) (xy 382.749222 -396.884951) (xy 382.796147 -396.86514)
			(xy 382.845708 -396.853387) (xy 382.896532 -396.850016) (xy 382.947211 -396.855122) (xy 382.996341 -396.868563)
			(xy 383.042561 -396.889967) (xy 383.084591 -396.91874) (xy 383.121266 -396.954086) (xy 383.151571 -396.995026)
			(xy 383.163572 -397.017494) (xy 383.16408 -397.018764) (xy 383.257246 -397.179978) (xy 383.786116 -397.179978)
			(xy 383.786365 -397.129044) (xy 383.795058 -397.078856) (xy 383.811955 -397.030806) (xy 383.836588 -396.986224)
			(xy 383.868274 -396.946345) (xy 383.906135 -396.912274) (xy 383.949124 -396.884955) (xy 383.996048 -396.865144)
			(xy 384.045608 -396.85339) (xy 384.096431 -396.85002) (xy 384.147109 -396.855125) (xy 384.196238 -396.868566)
			(xy 384.242458 -396.889969) (xy 384.284487 -396.918742) (xy 384.321162 -396.954087) (xy 384.351467 -396.995026)
			(xy 384.363468 -397.017494) (xy 384.363976 -397.018764) (xy 384.457141 -397.179977) (xy 384.986019 -397.179977)
			(xy 384.986268 -397.129044) (xy 384.994961 -397.078857) (xy 385.011858 -397.030807) (xy 385.036491 -396.986226)
			(xy 385.068176 -396.946348) (xy 385.106037 -396.912277) (xy 385.149025 -396.884958) (xy 385.195948 -396.865147)
			(xy 385.245508 -396.853394) (xy 385.29633 -396.850023) (xy 385.347007 -396.855129) (xy 385.396136 -396.868569)
			(xy 385.442355 -396.889972) (xy 385.484384 -396.918744) (xy 385.521058 -396.954088) (xy 385.551363 -396.995026)
			(xy 385.563364 -397.017494) (xy 385.563872 -397.018764) (xy 385.630054 -397.133285) (xy 386.186033 -397.133285)
			(xy 386.193365 -397.085737) (xy 386.208058 -397.039925) (xy 386.22975 -396.996982) (xy 386.257904 -396.95797)
			(xy 386.291825 -396.923853) (xy 386.330673 -396.895474) (xy 386.37349 -396.873534) (xy 386.419216 -396.858576)
			(xy 386.466721 -396.85097) (xy 386.514831 -396.850903) (xy 386.562358 -396.858377) (xy 386.608125 -396.873208)
			(xy 386.651002 -396.895029) (xy 386.68993 -396.9233) (xy 386.723945 -396.957323) (xy 386.752207 -396.996257)
			(xy 386.763514 -397.017494) (xy 386.764022 -397.018764) (xy 386.830204 -397.133285) (xy 387.385937 -397.133285)
			(xy 387.393268 -397.085737) (xy 387.407961 -397.039926) (xy 387.429653 -396.996984) (xy 387.457807 -396.957973)
			(xy 387.491727 -396.923856) (xy 387.530575 -396.895477) (xy 387.573391 -396.873537) (xy 387.619116 -396.85858)
			(xy 387.666621 -396.850973) (xy 387.71473 -396.850906) (xy 387.762256 -396.85838) (xy 387.808023 -396.873211)
			(xy 387.850899 -396.895031) (xy 387.889826 -396.923302) (xy 387.923841 -396.957324) (xy 387.952103 -396.996257)
			(xy 387.96341 -397.017494) (xy 387.963918 -397.018764) (xy 388.057083 -397.179976) (xy 388.586223 -397.179976)
			(xy 388.586472 -397.129043) (xy 388.595165 -397.078858) (xy 388.612062 -397.030809) (xy 388.636694 -396.986228)
			(xy 388.668379 -396.94635) (xy 388.706239 -396.91228) (xy 388.749226 -396.884961) (xy 388.796149 -396.865151)
			(xy 388.845707 -396.853397) (xy 388.896529 -396.850027) (xy 388.947206 -396.855132) (xy 388.996334 -396.868572)
			(xy 389.042552 -396.889974) (xy 389.08458 -396.918746) (xy 389.121255 -396.95409) (xy 389.151559 -396.995027)
			(xy 389.16356 -397.017494) (xy 389.164068 -397.018764) (xy 389.230251 -397.133287) (xy 403.113806 -397.133287)
			(xy 403.121138 -397.085733) (xy 403.135833 -397.039916) (xy 403.157527 -396.996969) (xy 403.185684 -396.957952)
			(xy 403.219609 -396.923831) (xy 403.258462 -396.895449) (xy 403.301283 -396.873508) (xy 403.347014 -396.858549)
			(xy 403.394525 -396.850942) (xy 403.44264 -396.850877) (xy 403.490172 -396.858353) (xy 403.535944 -396.873187)
			(xy 403.578825 -396.895011) (xy 403.617755 -396.923287) (xy 403.651773 -396.957315) (xy 403.680037 -396.996254)
			(xy 403.691344 -397.017494) (xy 403.691852 -397.018764) (xy 403.758035 -397.133286) (xy 404.31371 -397.133286)
			(xy 404.321042 -397.085733) (xy 404.335736 -397.039917) (xy 404.35743 -396.996971) (xy 404.385587 -396.957955)
			(xy 404.419511 -396.923834) (xy 404.458363 -396.895453) (xy 404.501184 -396.873511) (xy 404.546915 -396.858552)
			(xy 404.594424 -396.850946) (xy 404.642539 -396.85088) (xy 404.69007 -396.858356) (xy 404.735841 -396.87319)
			(xy 404.778722 -396.895014) (xy 404.817652 -396.923289) (xy 404.851669 -396.957316) (xy 404.879933 -396.996254)
			(xy 404.89124 -397.017494) (xy 404.891748 -397.018764) (xy 404.9716 -397.15694) (xy 405.51354 -397.15694)
			(xy 405.51354 -397.156432) (xy 405.514043 -397.131518) (xy 405.522133 -397.082352) (xy 405.538088 -397.035149)
			(xy 405.549354 -397.012922) (xy 405.549354 -397.012668) (xy 405.560939 -396.991732) (xy 405.589741 -396.953523)
			(xy 405.624146 -396.92027) (xy 405.663314 -396.892785) (xy 405.706287 -396.871741) (xy 405.752014 -396.857652)
			(xy 405.799378 -396.850861) (xy 405.847222 -396.851535) (xy 405.894376 -396.859658) (xy 405.939688 -396.875031)
			(xy 405.982051 -396.897278) (xy 406.020428 -396.925855) (xy 406.053883 -396.960065) (xy 406.081596 -396.99907)
			(xy 406.09266 -397.020288) (xy 406.093422 -397.021812) (xy 406.157861 -397.133284) (xy 406.713858 -397.133284)
			(xy 406.72119 -397.08574) (xy 406.735882 -397.039933) (xy 406.757571 -396.996995) (xy 406.785723 -396.957987)
			(xy 406.81964 -396.923873) (xy 406.858484 -396.895496) (xy 406.901296 -396.873558) (xy 406.947017 -396.858601)
			(xy 406.994518 -396.850995) (xy 407.042623 -396.850927) (xy 407.090145 -396.8584) (xy 407.135908 -396.873228)
			(xy 407.178781 -396.895045) (xy 407.217706 -396.923312) (xy 407.251719 -396.957331) (xy 407.27998 -396.996259)
			(xy 407.291286 -397.017494) (xy 407.291794 -397.018764) (xy 407.357975 -397.133284) (xy 407.913762 -397.133284)
			(xy 407.921093 -397.085741) (xy 407.935785 -397.039935) (xy 407.957474 -396.996997) (xy 407.985625 -396.957989)
			(xy 408.019542 -396.923876) (xy 408.058386 -396.8955) (xy 408.101197 -396.873562) (xy 408.146918 -396.858605)
			(xy 408.194417 -396.850999) (xy 408.242522 -396.850931) (xy 408.290043 -396.858403) (xy 408.335805 -396.873231)
			(xy 408.378678 -396.895048) (xy 408.417602 -396.923314) (xy 408.451615 -396.957332) (xy 408.479876 -396.99626)
			(xy 408.491182 -397.017494) (xy 408.49169 -397.018764) (xy 408.557873 -397.133286) (xy 409.113817 -397.133286)
			(xy 409.121149 -397.085734) (xy 409.135843 -397.03992) (xy 409.157536 -396.996974) (xy 409.185692 -396.95796)
			(xy 409.219615 -396.92384) (xy 409.258466 -396.895459) (xy 409.301286 -396.873518) (xy 409.347015 -396.85856)
			(xy 409.394523 -396.850953) (xy 409.442637 -396.850887) (xy 409.490166 -396.858363) (xy 409.535936 -396.873195)
			(xy 409.578816 -396.895018) (xy 409.617745 -396.923292) (xy 409.651762 -396.957318) (xy 409.680025 -396.996255)
			(xy 409.691332 -397.017494) (xy 409.69184 -397.018764) (xy 409.758023 -397.133286) (xy 410.313721 -397.133286)
			(xy 410.321052 -397.085735) (xy 410.335746 -397.039921) (xy 410.357439 -396.996976) (xy 410.385595 -396.957962)
			(xy 410.419517 -396.923843) (xy 410.458368 -396.895462) (xy 410.501187 -396.873522) (xy 410.546915 -396.858563)
			(xy 410.594423 -396.850957) (xy 410.642536 -396.850891) (xy 410.690064 -396.858366) (xy 410.735834 -396.873198)
			(xy 410.778713 -396.895021) (xy 410.817642 -396.923294) (xy 410.851658 -396.957319) (xy 410.879921 -396.996256)
			(xy 410.891228 -397.017494) (xy 410.891736 -397.018764) (xy 410.971588 -397.15694) (xy 411.513528 -397.15694)
			(xy 411.513528 -397.156432) (xy 411.514032 -397.131518) (xy 411.522122 -397.082352) (xy 411.538077 -397.035149)
			(xy 411.549342 -397.012922) (xy 411.549342 -397.012668) (xy 411.560945 -396.991743) (xy 411.589745 -396.953534)
			(xy 411.624149 -396.920282) (xy 411.663315 -396.892797) (xy 411.706285 -396.871753) (xy 411.752011 -396.857663)
			(xy 411.799373 -396.850872) (xy 411.847216 -396.851545) (xy 411.894368 -396.859667) (xy 411.939679 -396.875038)
			(xy 411.98204 -396.897284) (xy 412.020417 -396.92586) (xy 412.053871 -396.960068) (xy 412.081585 -396.999071)
			(xy 412.092648 -397.020288) (xy 412.09341 -397.021812) (xy 412.184843 -397.179979) (xy 412.713911 -397.179979)
			(xy 412.714159 -397.129044) (xy 412.722853 -397.078855) (xy 412.73975 -397.030804) (xy 412.764383 -396.986221)
			(xy 412.79607 -396.946341) (xy 412.833933 -396.912269) (xy 412.876922 -396.884949) (xy 412.923847 -396.865138)
			(xy 412.973408 -396.853385) (xy 413.024232 -396.850014) (xy 413.074911 -396.85512) (xy 413.124042 -396.868562)
			(xy 413.170262 -396.889966) (xy 413.212292 -396.918739) (xy 413.248968 -396.954086) (xy 413.279273 -396.995025)
			(xy 413.291274 -397.017494) (xy 413.291782 -397.018764) (xy 413.384948 -397.179978) (xy 413.913814 -397.179978)
			(xy 413.914063 -397.129044) (xy 413.922756 -397.078856) (xy 413.939653 -397.030805) (xy 413.964286 -396.986223)
			(xy 413.995973 -396.946344) (xy 414.033834 -396.912272) (xy 414.076823 -396.884953) (xy 414.123748 -396.865142)
			(xy 414.173308 -396.853388) (xy 414.224131 -396.850018) (xy 414.27481 -396.855124) (xy 414.323939 -396.868565)
			(xy 414.370159 -396.889968) (xy 414.412189 -396.918741) (xy 414.448864 -396.954087) (xy 414.479169 -396.995026)
			(xy 414.49117 -397.017494) (xy 414.491678 -397.018764) (xy 414.55786 -397.133285) (xy 415.113828 -397.133285)
			(xy 415.121159 -397.085736) (xy 415.135853 -397.039923) (xy 415.157545 -396.99698) (xy 415.1857 -396.957967)
			(xy 415.219622 -396.923849) (xy 415.258471 -396.895469) (xy 415.301289 -396.873529) (xy 415.347016 -396.858571)
			(xy 415.394522 -396.850964) (xy 415.442633 -396.850898) (xy 415.49016 -396.858372) (xy 415.535929 -396.873204)
			(xy 415.578807 -396.895025) (xy 415.617735 -396.923297) (xy 415.651751 -396.957321) (xy 415.680013 -396.996256)
			(xy 415.69132 -397.017494) (xy 415.691828 -397.018764) (xy 415.75801 -397.133285) (xy 416.313731 -397.133285)
			(xy 416.321063 -397.085737) (xy 416.335756 -397.039924) (xy 416.357448 -396.996982) (xy 416.385603 -396.957969)
			(xy 416.419524 -396.923851) (xy 416.458373 -396.895472) (xy 416.50119 -396.873532) (xy 416.546916 -396.858574)
			(xy 416.594421 -396.850968) (xy 416.642532 -396.850901) (xy 416.690059 -396.858376) (xy 416.735826 -396.873207)
			(xy 416.778704 -396.895028) (xy 416.817631 -396.923299) (xy 416.851647 -396.957323) (xy 416.879909 -396.996257)
			(xy 416.891216 -397.017494) (xy 416.891724 -397.018764) (xy 416.971576 -397.15694) (xy 417.513516 -397.15694)
			(xy 417.513516 -397.156432) (xy 417.514021 -397.131519) (xy 417.522111 -397.082353) (xy 417.538065 -397.035149)
			(xy 417.54933 -397.012922) (xy 417.54933 -397.012668) (xy 417.560951 -396.991753) (xy 417.58975 -396.953546)
			(xy 417.624152 -396.920294) (xy 417.663315 -396.89281) (xy 417.706284 -396.871765) (xy 417.752008 -396.857675)
			(xy 417.799369 -396.850883) (xy 417.847209 -396.851556) (xy 417.89436 -396.859676) (xy 417.93967 -396.875046)
			(xy 417.98203 -396.89729) (xy 418.020406 -396.925864) (xy 418.053859 -396.96007) (xy 418.081573 -396.999072)
			(xy 418.092636 -397.020288) (xy 418.093398 -397.021812) (xy 418.184829 -397.179976) (xy 418.713921 -397.179976)
			(xy 418.71417 -397.129044) (xy 418.722863 -397.078857) (xy 418.73976 -397.030808) (xy 418.764392 -396.986227)
			(xy 418.796078 -396.946349) (xy 418.833938 -396.912278) (xy 418.876926 -396.88496) (xy 418.923849 -396.865149)
			(xy 418.973408 -396.853396) (xy 419.024229 -396.850025) (xy 419.074906 -396.85513) (xy 419.124035 -396.86857)
			(xy 419.170253 -396.889973) (xy 419.212282 -396.918745) (xy 419.248957 -396.954089) (xy 419.279261 -396.995027)
			(xy 419.291262 -397.017494) (xy 419.29177 -397.018764) (xy 419.371622 -397.15694) (xy 419.913308 -397.15694)
			(xy 419.913308 -397.156432) (xy 419.913819 -397.131504) (xy 419.921962 -397.082319) (xy 419.938035 -397.035126)
			(xy 419.949376 -397.012922) (xy 419.949376 -397.012668) (xy 419.961078 -396.991801) (xy 419.989869 -396.953597)
			(xy 420.024263 -396.920347) (xy 420.063418 -396.892864) (xy 420.106379 -396.871819) (xy 420.152094 -396.857728)
			(xy 420.199447 -396.850933) (xy 420.24728 -396.851601) (xy 420.294425 -396.859717) (xy 420.339728 -396.875081)
			(xy 420.382084 -396.897318) (xy 420.420456 -396.925885) (xy 420.453907 -396.960083) (xy 420.481619 -396.999076)
			(xy 420.492682 -397.020288) (xy 420.493444 -397.021812) (xy 420.557884 -397.133285) (xy 421.113839 -397.133285)
			(xy 421.12117 -397.085738) (xy 421.135863 -397.039927) (xy 421.157554 -396.996985) (xy 421.185708 -396.957974)
			(xy 421.219628 -396.923857) (xy 421.258476 -396.895478) (xy 421.301291 -396.873539) (xy 421.347016 -396.858581)
			(xy 421.39452 -396.850975) (xy 421.44263 -396.850908) (xy 421.490155 -396.858382) (xy 421.535921 -396.873212)
			(xy 421.578798 -396.895032) (xy 421.617725 -396.923303) (xy 421.651739 -396.957325) (xy 421.680002 -396.996257)
			(xy 421.691308 -397.017494) (xy 421.691816 -397.018764) (xy 422.083738 -397.696944) (xy 422.083992 -397.697452)
			(xy 422.084246 -397.697452) (xy 422.085516 -397.699992) (xy 422.097788 -397.722907) (xy 422.115194 -397.771885)
			(xy 422.124068 -397.823101) (xy 422.124632 -397.84909) (xy 422.124632 -397.849344) (xy 422.124202 -397.87335)
			(xy 422.116681 -397.920769) (xy 422.101833 -397.966427) (xy 422.080022 -398.009199) (xy 422.051786 -398.04803)
			(xy 422.017821 -398.081964) (xy 421.978965 -398.110165) (xy 421.936173 -398.131938) (xy 421.890502 -398.146745)
			(xy 421.843076 -398.154223) (xy 421.81907 -398.154652) (xy 421.795408 -398.154156) (xy 421.748649 -398.146856)
			(xy 421.703575 -398.132435) (xy 421.661263 -398.111238) (xy 421.622724 -398.083772) (xy 421.58888 -398.050693)
			(xy 421.560539 -398.012793) (xy 421.549068 -397.992092) (xy 421.548814 -397.99133) (xy 421.151558 -397.304006)
			(xy 421.13938 -397.280789) (xy 421.122264 -397.231239) (xy 421.117522 -397.205454) (xy 421.117522 -397.2052)
			(xy 421.11405 -397.181394) (xy 421.113839 -397.133285) (xy 420.557884 -397.133285) (xy 420.865808 -397.665956)
			(xy 420.866062 -397.666464) (xy 420.88562 -397.699992) (xy 420.897893 -397.722907) (xy 420.915298 -397.771885)
			(xy 420.924172 -397.823101) (xy 420.924736 -397.84909) (xy 420.924736 -397.849344) (xy 420.924302 -397.87335)
			(xy 420.916781 -397.920768) (xy 420.901933 -397.966426) (xy 420.880122 -398.009197) (xy 420.851887 -398.048029)
			(xy 420.817923 -398.081963) (xy 420.779067 -398.110164) (xy 420.736276 -398.131936) (xy 420.690605 -398.146744)
			(xy 420.64318 -398.154223) (xy 420.619174 -398.154652) (xy 420.61892 -398.154652) (xy 420.595348 -398.154215)
			(xy 420.548763 -398.146978) (xy 420.503847 -398.132658) (xy 420.46167 -398.111595) (xy 420.423236 -398.084293)
			(xy 420.389462 -398.051402) (xy 420.361153 -398.013704) (xy 420.34968 -397.993108) (xy 420.349172 -397.992346)
			(xy 419.951408 -397.304006) (xy 419.939493 -397.281337) (xy 419.922555 -397.233012) (xy 419.913896 -397.182542)
			(xy 419.913308 -397.15694) (xy 419.371622 -397.15694) (xy 419.683692 -397.696944) (xy 419.683946 -397.697452)
			(xy 419.6842 -397.697452) (xy 419.68547 -397.699992) (xy 419.697699 -397.722918) (xy 419.715022 -397.771903)
			(xy 419.72381 -397.823111) (xy 419.724332 -397.84909) (xy 419.724332 -397.849344) (xy 419.723878 -397.873335)
			(xy 419.716366 -397.920726) (xy 419.701534 -397.966359) (xy 419.679747 -398.00911) (xy 419.651542 -398.047927)
			(xy 419.617612 -398.081855) (xy 419.578793 -398.110058) (xy 419.53604 -398.131842) (xy 419.490407 -398.146671)
			(xy 419.443015 -398.15418) (xy 419.419024 -398.154652) (xy 419.39536 -398.154193) (xy 419.3486 -398.146886)
			(xy 419.303525 -398.132459) (xy 419.261213 -398.111256) (xy 419.222674 -398.083784) (xy 419.188831 -398.0507)
			(xy 419.160493 -398.012795) (xy 419.149022 -397.992092) (xy 419.148768 -397.99133) (xy 418.751512 -397.304006)
			(xy 418.739331 -397.28079) (xy 418.722218 -397.231239) (xy 418.717476 -397.205454) (xy 418.717476 -397.2052)
			(xy 418.713921 -397.179976) (xy 418.184829 -397.179976) (xy 418.465762 -397.665956) (xy 418.466016 -397.666464)
			(xy 418.485574 -397.699992) (xy 418.497804 -397.722918) (xy 418.515126 -397.771903) (xy 418.523914 -397.823111)
			(xy 418.524436 -397.84909) (xy 418.524436 -397.849344) (xy 418.523978 -397.873335) (xy 418.516466 -397.920726)
			(xy 418.501635 -397.966358) (xy 418.479848 -398.009109) (xy 418.451643 -398.047926) (xy 418.417713 -398.081853)
			(xy 418.378895 -398.110056) (xy 418.336143 -398.131841) (xy 418.29051 -398.14667) (xy 418.243119 -398.154179)
			(xy 418.219128 -398.154652) (xy 418.218874 -398.154652) (xy 418.195301 -398.154252) (xy 418.148714 -398.147008)
			(xy 418.103797 -398.132681) (xy 418.06162 -398.111613) (xy 418.023187 -398.084305) (xy 417.989414 -398.051408)
			(xy 417.961106 -398.013706) (xy 417.949634 -397.993108) (xy 417.949126 -397.992346) (xy 417.551362 -397.304006)
			(xy 417.539486 -397.281329) (xy 417.522635 -397.232996) (xy 417.514062 -397.182533) (xy 417.513516 -397.15694)
			(xy 416.971576 -397.15694) (xy 417.283646 -397.696944) (xy 417.2839 -397.697452) (xy 417.284154 -397.697452)
			(xy 417.285424 -397.699992) (xy 417.297697 -397.722907) (xy 417.315102 -397.771885) (xy 417.323976 -397.823101)
			(xy 417.32454 -397.84909) (xy 417.32454 -397.849344) (xy 417.324102 -397.873349) (xy 417.316581 -397.920768)
			(xy 417.301733 -397.966425) (xy 417.279923 -398.009196) (xy 417.251688 -398.048027) (xy 417.217725 -398.081961)
			(xy 417.178869 -398.110162) (xy 417.136079 -398.131935) (xy 417.090409 -398.146744) (xy 417.042984 -398.154222)
			(xy 417.018978 -398.154652) (xy 416.995313 -398.15423) (xy 416.948551 -398.146916) (xy 416.903475 -398.132482)
			(xy 416.861163 -398.111273) (xy 416.822625 -398.083796) (xy 416.788783 -398.050707) (xy 416.760446 -398.012797)
			(xy 416.748976 -397.992092) (xy 416.748722 -397.99133) (xy 416.351466 -397.304006) (xy 416.339288 -397.280789)
			(xy 416.322172 -397.231239) (xy 416.31743 -397.205454) (xy 416.31743 -397.2052) (xy 416.313943 -397.181396)
			(xy 416.313731 -397.133285) (xy 415.75801 -397.133285) (xy 416.08375 -397.696944) (xy 416.084004 -397.697452)
			(xy 416.084258 -397.697452) (xy 416.085528 -397.699992) (xy 416.097801 -397.722907) (xy 416.115206 -397.771885)
			(xy 416.12408 -397.823101) (xy 416.124644 -397.84909) (xy 416.124644 -397.849344) (xy 416.124202 -397.873349)
			(xy 416.116682 -397.920767) (xy 416.101834 -397.966424) (xy 416.080024 -398.009195) (xy 416.05179 -398.048026)
			(xy 416.017826 -398.08196) (xy 415.978971 -398.110161) (xy 415.936182 -398.131934) (xy 415.890512 -398.146743)
			(xy 415.843088 -398.154222) (xy 415.819082 -398.154652) (xy 415.795417 -398.154227) (xy 415.748655 -398.146914)
			(xy 415.70358 -398.13248) (xy 415.661267 -398.111272) (xy 415.622729 -398.083795) (xy 415.588887 -398.050706)
			(xy 415.56055 -398.012797) (xy 415.54908 -397.992092) (xy 415.548826 -397.99133) (xy 415.15157 -397.304006)
			(xy 415.139393 -397.280789) (xy 415.122277 -397.231238) (xy 415.117534 -397.205454) (xy 415.117534 -397.2052)
			(xy 415.114039 -397.181396) (xy 415.113828 -397.133285) (xy 414.55786 -397.133285) (xy 414.8836 -397.696944)
			(xy 414.883854 -397.697452) (xy 414.884108 -397.697452) (xy 414.885378 -397.699992) (xy 414.897608 -397.722918)
			(xy 414.91493 -397.771903) (xy 414.923718 -397.823111) (xy 414.92424 -397.84909) (xy 414.92424 -397.849344)
			(xy 414.923778 -397.873335) (xy 414.916266 -397.920725) (xy 414.901435 -397.966357) (xy 414.879649 -398.009107)
			(xy 414.851444 -398.047924) (xy 414.817515 -398.081852) (xy 414.778697 -398.110055) (xy 414.735946 -398.13184)
			(xy 414.690313 -398.146669) (xy 414.642923 -398.154179) (xy 414.618932 -398.154652) (xy 414.595269 -398.154187)
			(xy 414.548509 -398.146881) (xy 414.503434 -398.132455) (xy 414.461121 -398.111253) (xy 414.422583 -398.083782)
			(xy 414.38874 -398.050699) (xy 414.360401 -398.012794) (xy 414.34893 -397.992092) (xy 414.348676 -397.99133)
			(xy 413.95142 -397.304006) (xy 413.939239 -397.28079) (xy 413.922126 -397.231239) (xy 413.917384 -397.205454)
			(xy 413.917384 -397.2052) (xy 413.913814 -397.179978) (xy 413.384948 -397.179978) (xy 413.683704 -397.696944)
			(xy 413.683958 -397.697452) (xy 413.684212 -397.697452) (xy 413.685482 -397.699992) (xy 413.697712 -397.722918)
			(xy 413.715034 -397.771903) (xy 413.723822 -397.823111) (xy 413.724344 -397.84909) (xy 413.724344 -397.849344)
			(xy 413.723878 -397.873335) (xy 413.716367 -397.920724) (xy 413.701535 -397.966356) (xy 413.679749 -398.009106)
			(xy 413.651545 -398.047923) (xy 413.617617 -398.08185) (xy 413.578799 -398.110054) (xy 413.536049 -398.131838)
			(xy 413.490417 -398.146668) (xy 413.443027 -398.154179) (xy 413.419036 -398.154652) (xy 413.395373 -398.154184)
			(xy 413.348613 -398.146878) (xy 413.303538 -398.132453) (xy 413.261226 -398.111251) (xy 413.222687 -398.083781)
			(xy 413.188844 -398.050698) (xy 413.160505 -398.012794) (xy 413.149034 -397.992092) (xy 413.14878 -397.99133)
			(xy 412.751524 -397.304006) (xy 412.739344 -397.28079) (xy 412.72223 -397.231239) (xy 412.717488 -397.205454)
			(xy 412.717488 -397.2052) (xy 412.713911 -397.179979) (xy 412.184843 -397.179979) (xy 412.465774 -397.665956)
			(xy 412.466028 -397.666464) (xy 412.485586 -397.699992) (xy 412.497817 -397.722917) (xy 412.515138 -397.771902)
			(xy 412.523926 -397.823111) (xy 412.524448 -397.84909) (xy 412.524448 -397.849344) (xy 412.523978 -397.873334)
			(xy 412.516467 -397.920724) (xy 412.501636 -397.966355) (xy 412.47985 -398.009105) (xy 412.451646 -398.047922)
			(xy 412.417718 -398.081849) (xy 412.378902 -398.110052) (xy 412.336151 -398.131837) (xy 412.29052 -398.146668)
			(xy 412.24313 -398.154178) (xy 412.21914 -398.154652) (xy 412.218886 -398.154652) (xy 412.195313 -398.154242)
			(xy 412.148727 -398.147) (xy 412.10381 -398.132675) (xy 412.061633 -398.111608) (xy 412.0232 -398.084302)
			(xy 411.989427 -398.051406) (xy 411.961119 -398.013705) (xy 411.949646 -397.993108) (xy 411.949138 -397.992346)
			(xy 411.551374 -397.304006) (xy 411.539499 -397.281329) (xy 411.522648 -397.232996) (xy 411.514074 -397.182533)
			(xy 411.513528 -397.15694) (xy 410.971588 -397.15694) (xy 411.283658 -397.696944) (xy 411.283912 -397.697452)
			(xy 411.284166 -397.697452) (xy 411.285436 -397.699992) (xy 411.29771 -397.722906) (xy 411.315115 -397.771885)
			(xy 411.323988 -397.823101) (xy 411.324552 -397.84909) (xy 411.324552 -397.849344) (xy 411.324102 -397.873349)
			(xy 411.316582 -397.920766) (xy 411.301734 -397.966422) (xy 411.279925 -398.009193) (xy 411.251692 -398.048023)
			(xy 411.21773 -398.081957) (xy 411.178876 -398.110158) (xy 411.136087 -398.131932) (xy 411.090419 -398.146741)
			(xy 411.042995 -398.154222) (xy 411.01899 -398.154652) (xy 410.995325 -398.154221) (xy 410.948564 -398.146909)
			(xy 410.903488 -398.132476) (xy 410.861176 -398.111269) (xy 410.822638 -398.083793) (xy 410.788796 -398.050705)
			(xy 410.760458 -398.012796) (xy 410.748988 -397.992092) (xy 410.748734 -397.99133) (xy 410.351478 -397.304006)
			(xy 410.339301 -397.280788) (xy 410.322185 -397.231238) (xy 410.317442 -397.205454) (xy 410.317442 -397.2052)
			(xy 410.313932 -397.181398) (xy 410.313721 -397.133286) (xy 409.758023 -397.133286) (xy 410.083762 -397.696944)
			(xy 410.084016 -397.697452) (xy 410.08427 -397.697452) (xy 410.08554 -397.699992) (xy 410.097814 -397.722906)
			(xy 410.115219 -397.771885) (xy 410.124092 -397.823101) (xy 410.124656 -397.84909) (xy 410.124656 -397.849344)
			(xy 410.124202 -397.873349) (xy 410.116682 -397.920765) (xy 410.101835 -397.966421) (xy 410.080026 -398.009191)
			(xy 410.051793 -398.048022) (xy 410.017831 -398.081956) (xy 409.978978 -398.110157) (xy 409.93619 -398.131931)
			(xy 409.890522 -398.14674) (xy 409.843099 -398.154221) (xy 409.819094 -398.154652) (xy 409.795429 -398.154217)
			(xy 409.748668 -398.146906) (xy 409.703593 -398.132474) (xy 409.66128 -398.111267) (xy 409.622742 -398.083792)
			(xy 409.5889 -398.050704) (xy 409.560562 -398.012796) (xy 409.549092 -397.992092) (xy 409.548838 -397.99133)
			(xy 409.151582 -397.304006) (xy 409.139405 -397.280788) (xy 409.122289 -397.231238) (xy 409.117546 -397.205454)
			(xy 409.117546 -397.2052) (xy 409.114029 -397.181399) (xy 409.113817 -397.133286) (xy 408.557873 -397.133286)
			(xy 408.883612 -397.696944) (xy 408.883866 -397.697452) (xy 408.88412 -397.697452) (xy 408.88539 -397.699992)
			(xy 408.897621 -397.722917) (xy 408.914942 -397.771902) (xy 408.92373 -397.823111) (xy 408.924252 -397.84909)
			(xy 408.924252 -397.849344) (xy 408.923778 -397.873334) (xy 408.916267 -397.920723) (xy 408.901436 -397.966354)
			(xy 408.879651 -398.009104) (xy 408.851448 -398.04792) (xy 408.81752 -398.081848) (xy 408.778704 -398.110051)
			(xy 408.735954 -398.131836) (xy 408.690323 -398.146667) (xy 408.642934 -398.154178) (xy 408.618944 -398.154652)
			(xy 408.595281 -398.154177) (xy 408.548521 -398.146873) (xy 408.503447 -398.132449) (xy 408.461134 -398.111248)
			(xy 408.422596 -398.083779) (xy 408.388752 -398.050697) (xy 408.360413 -398.012794) (xy 408.348942 -397.992092)
			(xy 408.348688 -397.99133) (xy 407.951432 -397.304006) (xy 407.939252 -397.28079) (xy 407.922138 -397.231239)
			(xy 407.917396 -397.205454) (xy 407.917396 -397.2052) (xy 407.913973 -397.181388) (xy 407.913762 -397.133284)
			(xy 407.357975 -397.133284) (xy 407.683716 -397.696944) (xy 407.68397 -397.697452) (xy 407.684224 -397.697452)
			(xy 407.685494 -397.699992) (xy 407.697725 -397.722917) (xy 407.715046 -397.771902) (xy 407.723834 -397.823111)
			(xy 407.724356 -397.84909) (xy 407.724356 -397.849344) (xy 407.723878 -397.873334) (xy 407.716367 -397.920723)
			(xy 407.701536 -397.966353) (xy 407.679752 -398.009103) (xy 407.651549 -398.047919) (xy 407.617622 -398.081846)
			(xy 407.578806 -398.11005) (xy 407.536057 -398.131835) (xy 407.490427 -398.146666) (xy 407.443038 -398.154178)
			(xy 407.419048 -398.154652) (xy 407.395385 -398.154174) (xy 407.348626 -398.146871) (xy 407.303551 -398.132447)
			(xy 407.261239 -398.111247) (xy 407.2227 -398.083778) (xy 407.188857 -398.050697) (xy 407.160517 -398.012794)
			(xy 407.149046 -397.992092) (xy 407.148792 -397.99133) (xy 406.751536 -397.304006) (xy 406.739356 -397.28079)
			(xy 406.722242 -397.231239) (xy 406.7175 -397.205454) (xy 406.7175 -397.2052) (xy 406.714069 -397.181389)
			(xy 406.713858 -397.133284) (xy 406.157861 -397.133284) (xy 406.465786 -397.665956) (xy 406.46604 -397.666464)
			(xy 406.485598 -397.699992) (xy 406.497829 -397.722917) (xy 406.51515 -397.771902) (xy 406.523938 -397.823111)
			(xy 406.52446 -397.84909) (xy 406.52446 -397.849344) (xy 406.524102 -397.873341) (xy 406.516587 -397.920742)
			(xy 406.50175 -397.966385) (xy 406.479955 -398.009144) (xy 406.451739 -398.047968) (xy 406.417798 -398.081899)
			(xy 406.378966 -398.110103) (xy 406.3362 -398.131885) (xy 406.290553 -398.146709) (xy 406.243149 -398.154209)
			(xy 406.219152 -398.154652) (xy 406.218898 -398.154652) (xy 406.195325 -398.154232) (xy 406.14874 -398.146992)
			(xy 406.103823 -398.132669) (xy 406.061646 -398.111604) (xy 406.023213 -398.084299) (xy 405.989439 -398.051405)
			(xy 405.961131 -398.013705) (xy 405.949658 -397.993108) (xy 405.94915 -397.992346) (xy 405.551386 -397.304006)
			(xy 405.539512 -397.281328) (xy 405.52266 -397.232996) (xy 405.514086 -397.182533) (xy 405.51354 -397.15694)
			(xy 404.9716 -397.15694) (xy 405.28367 -397.696944) (xy 405.283924 -397.697452) (xy 405.284178 -397.697452)
			(xy 405.285448 -397.699992) (xy 405.297723 -397.722906) (xy 405.315127 -397.771885) (xy 405.324 -397.823101)
			(xy 405.324564 -397.84909) (xy 405.324564 -397.849344) (xy 405.324201 -397.873353) (xy 405.316679 -397.920779)
			(xy 405.301826 -397.966443) (xy 405.280009 -398.009219) (xy 405.251766 -398.048053) (xy 405.217793 -398.081989)
			(xy 405.178927 -398.110188) (xy 405.136126 -398.131957) (xy 405.090446 -398.146759) (xy 405.043012 -398.154228)
			(xy 405.019002 -398.154652) (xy 404.995338 -398.154211) (xy 404.948577 -398.146901) (xy 404.903501 -398.13247)
			(xy 404.861189 -398.111264) (xy 404.822651 -398.08379) (xy 404.788808 -398.050703) (xy 404.76047 -398.012796)
			(xy 404.749 -397.992092) (xy 404.748746 -397.99133) (xy 404.35149 -397.304006) (xy 404.339314 -397.280788)
			(xy 404.322197 -397.231238) (xy 404.317454 -397.205454) (xy 404.317454 -397.2052) (xy 404.313922 -397.181401)
			(xy 404.31371 -397.133286) (xy 403.758035 -397.133286) (xy 404.083774 -397.696944) (xy 404.084028 -397.697452)
			(xy 404.084282 -397.697452) (xy 404.085552 -397.699992) (xy 404.097827 -397.722906) (xy 404.115231 -397.771885)
			(xy 404.124104 -397.823101) (xy 404.124668 -397.84909) (xy 404.124668 -397.849344) (xy 404.124301 -397.873353)
			(xy 404.116779 -397.920778) (xy 404.101926 -397.966442) (xy 404.08011 -398.009218) (xy 404.051867 -398.048052)
			(xy 404.017895 -398.081987) (xy 403.979029 -398.110187) (xy 403.936229 -398.131956) (xy 403.890549 -398.146758)
			(xy 403.843116 -398.154228) (xy 403.819106 -398.154652) (xy 403.795442 -398.154208) (xy 403.748681 -398.146898)
			(xy 403.703606 -398.132468) (xy 403.661293 -398.111263) (xy 403.622755 -398.083789) (xy 403.588913 -398.050703)
			(xy 403.560574 -398.012795) (xy 403.549104 -397.992092) (xy 403.54885 -397.99133) (xy 403.151594 -397.304006)
			(xy 403.139412 -397.280791) (xy 403.122299 -397.231239) (xy 403.117558 -397.205454) (xy 403.117558 -397.2052)
			(xy 403.114018 -397.181402) (xy 403.113806 -397.133287) (xy 389.230251 -397.133287) (xy 389.55599 -397.696944)
			(xy 389.556244 -397.697452) (xy 389.556498 -397.697452) (xy 389.557768 -397.699992) (xy 389.570036 -397.722909)
			(xy 389.587445 -397.771886) (xy 389.59632 -397.823102) (xy 389.596884 -397.84909) (xy 389.596884 -397.849344)
			(xy 389.596501 -397.873352) (xy 389.588979 -397.920776) (xy 389.574128 -397.966438) (xy 389.552313 -398.009213)
			(xy 389.524072 -398.048046) (xy 389.490101 -398.081981) (xy 389.451238 -398.110181) (xy 389.40844 -398.131951)
			(xy 389.362762 -398.146755) (xy 389.315331 -398.154227) (xy 389.291322 -398.154652) (xy 389.267658 -398.154195)
			(xy 389.220898 -398.146888) (xy 389.175823 -398.13246) (xy 389.133511 -398.111257) (xy 389.094972 -398.083784)
			(xy 389.061129 -398.0507) (xy 389.032791 -398.012795) (xy 389.02132 -397.992092) (xy 389.021066 -397.99133)
			(xy 388.62381 -397.304006) (xy 388.611629 -397.280791) (xy 388.594516 -397.231239) (xy 388.589774 -397.205454)
			(xy 388.589774 -397.2052) (xy 388.586223 -397.179976) (xy 388.057083 -397.179976) (xy 388.35584 -397.696944)
			(xy 388.356094 -397.697452) (xy 388.356348 -397.697452) (xy 388.357618 -397.699992) (xy 388.369851 -397.722916)
			(xy 388.387171 -397.771902) (xy 388.395958 -397.823111) (xy 388.39648 -397.84909) (xy 388.39648 -397.849344)
			(xy 388.396078 -397.873338) (xy 388.388564 -397.920734) (xy 388.373729 -397.966371) (xy 388.351938 -398.009125)
			(xy 388.323726 -398.047945) (xy 388.28979 -398.081873) (xy 388.250964 -398.110075) (xy 388.208204 -398.131857)
			(xy 388.162564 -398.146681) (xy 388.115166 -398.154184) (xy 388.091172 -398.154652) (xy 388.06751 -398.154155)
			(xy 388.020751 -398.146855) (xy 387.975677 -398.132434) (xy 387.933365 -398.111238) (xy 387.894826 -398.083772)
			(xy 387.860982 -398.050693) (xy 387.832641 -398.012793) (xy 387.82117 -397.992092) (xy 387.820916 -397.99133)
			(xy 387.42366 -397.304006) (xy 387.411482 -397.280789) (xy 387.394366 -397.231239) (xy 387.389624 -397.205454)
			(xy 387.389624 -397.2052) (xy 387.386148 -397.181394) (xy 387.385937 -397.133285) (xy 386.830204 -397.133285)
			(xy 387.155944 -397.696944) (xy 387.156198 -397.697452) (xy 387.156452 -397.697452) (xy 387.157722 -397.699992)
			(xy 387.169955 -397.722916) (xy 387.187275 -397.771902) (xy 387.196062 -397.823111) (xy 387.196584 -397.84909)
			(xy 387.196584 -397.849344) (xy 387.196178 -397.873338) (xy 387.188664 -397.920733) (xy 387.17383 -397.96637)
			(xy 387.152038 -398.009124) (xy 387.123828 -398.047943) (xy 387.089892 -398.081872) (xy 387.051066 -398.110074)
			(xy 387.008307 -398.131856) (xy 386.962667 -398.14668) (xy 386.91527 -398.154183) (xy 386.891276 -398.154652)
			(xy 386.867611 -398.154232) (xy 386.820849 -398.146918) (xy 386.775773 -398.132483) (xy 386.733461 -398.111274)
			(xy 386.694923 -398.083796) (xy 386.661081 -398.050707) (xy 386.632744 -398.012797) (xy 386.621274 -397.992092)
			(xy 386.62102 -397.99133) (xy 386.223764 -397.304006) (xy 386.211586 -397.280789) (xy 386.19447 -397.231239)
			(xy 386.189728 -397.205454) (xy 386.189728 -397.2052) (xy 386.186245 -397.181395) (xy 386.186033 -397.133285)
			(xy 385.630054 -397.133285) (xy 385.955794 -397.696944) (xy 385.956048 -397.697452) (xy 385.956302 -397.697452)
			(xy 385.957572 -397.699992) (xy 385.969841 -397.722909) (xy 385.987249 -397.771886) (xy 385.996124 -397.823102)
			(xy 385.996688 -397.84909) (xy 385.996688 -397.849344) (xy 385.996301 -397.873352) (xy 385.98878 -397.920775)
			(xy 385.973928 -397.966437) (xy 385.952114 -398.009212) (xy 385.923873 -398.048045) (xy 385.889903 -398.08198)
			(xy 385.85104 -398.11018) (xy 385.808243 -398.13195) (xy 385.762566 -398.146754) (xy 385.715134 -398.154226)
			(xy 385.691126 -398.154652) (xy 385.667462 -398.154192) (xy 385.620702 -398.146885) (xy 385.575627 -398.132458)
			(xy 385.533315 -398.111255) (xy 385.494777 -398.083783) (xy 385.460934 -398.0507) (xy 385.432595 -398.012795)
			(xy 385.421124 -397.992092) (xy 385.42087 -397.99133) (xy 385.023614 -397.304006) (xy 385.011433 -397.28079)
			(xy 384.99432 -397.231239) (xy 384.989578 -397.205454) (xy 384.989578 -397.2052) (xy 384.986019 -397.179977)
			(xy 384.457141 -397.179977) (xy 384.755898 -397.696944) (xy 384.756152 -397.697452) (xy 384.756406 -397.697452)
			(xy 384.757676 -397.699992) (xy 384.769945 -397.722909) (xy 384.787353 -397.771886) (xy 384.796228 -397.823102)
			(xy 384.796792 -397.84909) (xy 384.796792 -397.849344) (xy 384.796401 -397.873352) (xy 384.78888 -397.920775)
			(xy 384.774029 -397.966436) (xy 384.752214 -398.009211) (xy 384.723974 -398.048044) (xy 384.690005 -398.081979)
			(xy 384.651142 -398.110179) (xy 384.608346 -398.131949) (xy 384.562669 -398.146753) (xy 384.515238 -398.154226)
			(xy 384.49123 -398.154652) (xy 384.467566 -398.154188) (xy 384.420807 -398.146882) (xy 384.375732 -398.132456)
			(xy 384.333419 -398.111254) (xy 384.294881 -398.083782) (xy 384.261038 -398.050699) (xy 384.232699 -398.012794)
			(xy 384.221228 -397.992092) (xy 384.220974 -397.99133) (xy 383.823718 -397.304006) (xy 383.811537 -397.28079)
			(xy 383.794424 -397.231239) (xy 383.789682 -397.205454) (xy 383.789682 -397.2052) (xy 383.786116 -397.179978)
			(xy 383.257246 -397.179978) (xy 383.556002 -397.696944) (xy 383.556256 -397.697452) (xy 383.55651 -397.697452)
			(xy 383.55778 -397.699992) (xy 383.570049 -397.722909) (xy 383.587457 -397.771886) (xy 383.596332 -397.823102)
			(xy 383.596896 -397.84909) (xy 383.596896 -397.849344) (xy 383.596501 -397.873352) (xy 383.58898 -397.920774)
			(xy 383.574129 -397.966435) (xy 383.552315 -398.009209) (xy 383.524075 -398.048042) (xy 383.490106 -398.081977)
			(xy 383.451245 -398.110177) (xy 383.408448 -398.131948) (xy 383.362772 -398.146752) (xy 383.315342 -398.154226)
			(xy 383.291334 -398.154652) (xy 383.267671 -398.154185) (xy 383.220911 -398.14688) (xy 383.175836 -398.132454)
			(xy 383.133524 -398.111252) (xy 383.094985 -398.083781) (xy 383.061142 -398.050699) (xy 383.032803 -398.012794)
			(xy 383.021332 -397.992092) (xy 383.021078 -397.99133) (xy 382.623822 -397.304006) (xy 382.611641 -397.28079)
			(xy 382.594528 -397.231239) (xy 382.589786 -397.205454) (xy 382.589786 -397.2052) (xy 382.586212 -397.179979)
			(xy 382.057097 -397.179979) (xy 382.355852 -397.696944) (xy 382.356106 -397.697452) (xy 382.35636 -397.697452)
			(xy 382.35763 -397.699992) (xy 382.369864 -397.722916) (xy 382.387183 -397.771902) (xy 382.395971 -397.823111)
			(xy 382.396492 -397.84909) (xy 382.396492 -397.849344) (xy 382.396078 -397.873337) (xy 382.388565 -397.920732)
			(xy 382.37373 -397.966368) (xy 382.35194 -398.009122) (xy 382.32373 -398.047941) (xy 382.289795 -398.081869)
			(xy 382.250971 -398.110071) (xy 382.208212 -398.131853) (xy 382.162574 -398.146679) (xy 382.115177 -398.154183)
			(xy 382.091184 -398.154652) (xy 382.067519 -398.154226) (xy 382.020757 -398.146913) (xy 381.975682 -398.132479)
			(xy 381.933369 -398.111271) (xy 381.894832 -398.083794) (xy 381.860989 -398.050706) (xy 381.832652 -398.012796)
			(xy 381.821182 -397.992092) (xy 381.820928 -397.99133) (xy 381.423672 -397.304006) (xy 381.411495 -397.280788)
			(xy 381.394379 -397.231238) (xy 381.389636 -397.205454) (xy 381.389636 -397.2052) (xy 381.386138 -397.181397)
			(xy 381.385926 -397.133286) (xy 380.830217 -397.133286) (xy 381.155956 -397.696944) (xy 381.15621 -397.697452)
			(xy 381.156464 -397.697452) (xy 381.157734 -397.699992) (xy 381.169968 -397.722915) (xy 381.187288 -397.771902)
			(xy 381.196075 -397.823111) (xy 381.196596 -397.84909) (xy 381.196596 -397.849344) (xy 381.196178 -397.873337)
			(xy 381.188665 -397.920731) (xy 381.173831 -397.966367) (xy 381.152041 -398.009121) (xy 381.123831 -398.047939)
			(xy 381.089897 -398.081868) (xy 381.051073 -398.11007) (xy 381.008315 -398.131852) (xy 380.962677 -398.146678)
			(xy 380.915281 -398.154182) (xy 380.891288 -398.154652) (xy 380.867623 -398.154222) (xy 380.820862 -398.14691)
			(xy 380.775786 -398.132477) (xy 380.733474 -398.111269) (xy 380.694936 -398.083793) (xy 380.661094 -398.050705)
			(xy 380.632756 -398.012796) (xy 380.621286 -397.992092) (xy 380.621032 -397.99133) (xy 380.223776 -397.304006)
			(xy 380.211599 -397.280788) (xy 380.194483 -397.231238) (xy 380.18974 -397.205454) (xy 380.18974 -397.2052)
			(xy 380.186234 -397.181398) (xy 380.186022 -397.133286) (xy 379.630067 -397.133286) (xy 379.955806 -397.696944)
			(xy 379.95606 -397.697452) (xy 379.956314 -397.697452) (xy 379.957584 -397.699992) (xy 379.969854 -397.722909)
			(xy 379.987261 -397.771886) (xy 379.996136 -397.823101) (xy 379.9967 -397.84909) (xy 379.9967 -397.849344)
			(xy 379.996301 -397.873351) (xy 379.98878 -397.920774) (xy 379.97393 -397.966434) (xy 379.952116 -398.009208)
			(xy 379.923877 -398.048041) (xy 379.889908 -398.081976) (xy 379.851047 -398.110176) (xy 379.808251 -398.131947)
			(xy 379.762576 -398.146752) (xy 379.715146 -398.154225) (xy 379.691138 -398.154652) (xy 379.667475 -398.154182)
			(xy 379.620715 -398.146877) (xy 379.57564 -398.132452) (xy 379.533328 -398.111251) (xy 379.494789 -398.08378)
			(xy 379.460946 -398.050698) (xy 379.432607 -398.012794) (xy 379.421136 -397.992092) (xy 379.420882 -397.99133)
			(xy 379.023626 -397.304006) (xy 379.011446 -397.28079) (xy 378.994332 -397.231239) (xy 378.98959 -397.205454)
			(xy 378.98959 -397.2052) (xy 378.986178 -397.181387) (xy 378.985967 -397.133284) (xy 378.430169 -397.133284)
			(xy 378.75591 -397.696944) (xy 378.756164 -397.697452) (xy 378.756418 -397.697452) (xy 378.757688 -397.699992)
			(xy 378.769958 -397.722908) (xy 378.787365 -397.771886) (xy 378.79624 -397.823101) (xy 378.796804 -397.84909)
			(xy 378.796804 -397.849344) (xy 378.796401 -397.873351) (xy 378.78888 -397.920773) (xy 378.77403 -397.966433)
			(xy 378.752217 -398.009207) (xy 378.723978 -398.04804) (xy 378.69001 -398.081974) (xy 378.651149 -398.110175)
			(xy 378.608354 -398.131946) (xy 378.562679 -398.146751) (xy 378.51525 -398.154225) (xy 378.491242 -398.154652)
			(xy 378.467579 -398.154179) (xy 378.420819 -398.146875) (xy 378.375745 -398.13245) (xy 378.333432 -398.111249)
			(xy 378.294894 -398.083779) (xy 378.26105 -398.050697) (xy 378.232711 -398.012794) (xy 378.22124 -397.992092)
			(xy 378.220986 -397.99133) (xy 377.82373 -397.304006) (xy 377.81155 -397.28079) (xy 377.794436 -397.231239)
			(xy 377.789694 -397.205454) (xy 377.789694 -397.2052) (xy 377.786274 -397.181388) (xy 377.786064 -397.133284)
			(xy 377.230273 -397.133284) (xy 377.556014 -397.696944) (xy 377.556268 -397.697452) (xy 377.556522 -397.697452)
			(xy 377.557792 -397.699992) (xy 377.570062 -397.722908) (xy 377.587469 -397.771886) (xy 377.596344 -397.823101)
			(xy 377.596908 -397.84909) (xy 377.596908 -397.849344) (xy 377.596501 -397.873351) (xy 377.58898 -397.920772)
			(xy 377.57413 -397.966432) (xy 377.552317 -398.009206) (xy 377.524079 -398.048038) (xy 377.490111 -398.081973)
			(xy 377.451251 -398.110173) (xy 377.408457 -398.131944) (xy 377.362782 -398.14675) (xy 377.315353 -398.154225)
			(xy 377.291346 -398.154652) (xy 377.267683 -398.154176) (xy 377.220924 -398.146872) (xy 377.175849 -398.132448)
			(xy 377.133537 -398.111248) (xy 377.094998 -398.083778) (xy 377.061154 -398.050697) (xy 377.032815 -398.012794)
			(xy 377.021344 -397.992092) (xy 377.02109 -397.99133) (xy 376.623834 -397.304006) (xy 376.611654 -397.28079)
			(xy 376.59454 -397.231239) (xy 376.589798 -397.205454) (xy 376.589798 -397.2052) (xy 376.586371 -397.181389)
			(xy 376.58616 -397.133284) (xy 376.030123 -397.133284) (xy 376.355864 -397.696944) (xy 376.356118 -397.697452)
			(xy 376.356372 -397.697452) (xy 376.357642 -397.699992) (xy 376.369877 -397.722915) (xy 376.387196 -397.771902)
			(xy 376.395983 -397.823111) (xy 376.396504 -397.84909) (xy 376.396504 -397.849344) (xy 376.396078 -397.873337)
			(xy 376.388565 -397.92073) (xy 376.373731 -397.966365) (xy 376.351942 -398.009118) (xy 376.323733 -398.047937)
			(xy 376.2898 -398.081865) (xy 376.250977 -398.110067) (xy 376.208221 -398.13185) (xy 376.162583 -398.146676)
			(xy 376.115189 -398.154182) (xy 376.091196 -398.154652) (xy 376.067531 -398.154216) (xy 376.02077 -398.146905)
			(xy 375.975695 -398.132473) (xy 375.933382 -398.111266) (xy 375.894844 -398.083791) (xy 375.861002 -398.050704)
			(xy 375.832664 -398.012796) (xy 375.821194 -397.992092) (xy 375.82094 -397.99133) (xy 375.423684 -397.304006)
			(xy 375.411508 -397.280788) (xy 375.394391 -397.231238) (xy 375.389648 -397.205454) (xy 375.389648 -397.2052)
			(xy 375.386127 -397.181399) (xy 375.385915 -397.133286) (xy 374.830229 -397.133286) (xy 375.155968 -397.696944)
			(xy 375.156222 -397.697452) (xy 375.156476 -397.697452) (xy 375.157746 -397.699992) (xy 375.169981 -397.722915)
			(xy 375.1873 -397.771902) (xy 375.196087 -397.823111) (xy 375.196608 -397.84909) (xy 375.196608 -397.849344)
			(xy 375.196178 -397.873336) (xy 375.188665 -397.92073) (xy 375.173832 -397.966364) (xy 375.152043 -398.009117)
			(xy 375.123835 -398.047935) (xy 375.089902 -398.081863) (xy 375.051079 -398.110066) (xy 375.008324 -398.131849)
			(xy 374.962687 -398.146676) (xy 374.915292 -398.154181) (xy 374.8913 -398.154652) (xy 374.867636 -398.154213)
			(xy 374.820875 -398.146902) (xy 374.775799 -398.132471) (xy 374.733487 -398.111265) (xy 374.694949 -398.08379)
			(xy 374.661106 -398.050703) (xy 374.632768 -398.012796) (xy 374.621298 -397.992092) (xy 374.621044 -397.99133)
			(xy 374.223788 -397.304006) (xy 374.211612 -397.280788) (xy 374.194495 -397.231238) (xy 374.189752 -397.205454)
			(xy 374.189752 -397.2052) (xy 374.186223 -397.1814) (xy 374.186012 -397.133286) (xy 373.630079 -397.133286)
			(xy 373.955818 -397.696944) (xy 373.956072 -397.697452) (xy 373.956326 -397.697452) (xy 373.957596 -397.699992)
			(xy 373.969867 -397.722908) (xy 373.987274 -397.771886) (xy 373.996148 -397.823101) (xy 373.996712 -397.84909)
			(xy 373.996712 -397.849344) (xy 373.996302 -397.873351) (xy 373.98878 -397.920772) (xy 373.973931 -397.966432)
			(xy 373.952118 -398.009205) (xy 373.92388 -398.048037) (xy 373.889913 -398.081971) (xy 373.851053 -398.110172)
			(xy 373.808259 -398.131943) (xy 373.762586 -398.146749) (xy 373.715157 -398.154225) (xy 373.69115 -398.154652)
			(xy 373.667487 -398.154172) (xy 373.620728 -398.146869) (xy 373.575653 -398.132446) (xy 373.533341 -398.111246)
			(xy 373.494802 -398.083777) (xy 373.460959 -398.050696) (xy 373.432619 -398.012793) (xy 373.421148 -397.992092)
			(xy 373.420894 -397.99133) (xy 373.023638 -397.304006) (xy 373.011458 -397.28079) (xy 372.994344 -397.231239)
			(xy 372.989602 -397.205454) (xy 372.989602 -397.2052) (xy 372.986167 -397.181389) (xy 372.985956 -397.133284)
			(xy 372.430181 -397.133284) (xy 372.755922 -397.696944) (xy 372.756176 -397.697452) (xy 372.75643 -397.697452)
			(xy 372.7577 -397.699992) (xy 372.769971 -397.722908) (xy 372.787378 -397.771886) (xy 372.796252 -397.823101)
			(xy 372.796816 -397.84909) (xy 372.796816 -397.849344) (xy 372.796402 -397.873351) (xy 372.788881 -397.920771)
			(xy 372.774031 -397.966431) (xy 372.752219 -398.009203) (xy 372.723981 -398.048036) (xy 372.690015 -398.08197)
			(xy 372.651156 -398.110171) (xy 372.608362 -398.131942) (xy 372.562689 -398.146748) (xy 372.515261 -398.154224)
			(xy 372.491254 -398.154652) (xy 372.467591 -398.154169) (xy 372.420832 -398.146867) (xy 372.375758 -398.132444)
			(xy 372.333445 -398.111245) (xy 372.294907 -398.083776) (xy 372.261063 -398.050696) (xy 372.232723 -398.012793)
			(xy 372.221252 -397.992092) (xy 372.220998 -397.99133) (xy 371.823742 -397.304006) (xy 371.811563 -397.280789)
			(xy 371.794448 -397.231239) (xy 371.789706 -397.205454) (xy 371.789706 -397.2052) (xy 371.786264 -397.18139)
			(xy 371.786053 -397.133284) (xy 371.230285 -397.133284) (xy 371.556026 -397.696944) (xy 371.55628 -397.697452)
			(xy 371.556534 -397.697452) (xy 371.557804 -397.699992) (xy 371.570075 -397.722908) (xy 371.587482 -397.771886)
			(xy 371.596356 -397.823101) (xy 371.59692 -397.84909) (xy 371.59692 -397.849344) (xy 371.596502 -397.87335)
			(xy 371.588981 -397.920771) (xy 371.574131 -397.96643) (xy 371.552319 -398.009202) (xy 371.524082 -398.048034)
			(xy 371.490116 -398.081969) (xy 371.451258 -398.110169) (xy 371.408465 -398.131941) (xy 371.362792 -398.146748)
			(xy 371.315365 -398.154224) (xy 371.291358 -398.154652) (xy 371.267695 -398.154166) (xy 371.220936 -398.146864)
			(xy 371.175862 -398.132442) (xy 371.13355 -398.111243) (xy 371.095011 -398.083775) (xy 371.061167 -398.050695)
			(xy 371.032827 -398.012793) (xy 371.021356 -397.992092) (xy 371.021102 -397.99133) (xy 370.623846 -397.304006)
			(xy 370.611667 -397.280789) (xy 370.594552 -397.231239) (xy 370.58981 -397.205454) (xy 370.58981 -397.2052)
			(xy 370.58636 -397.181391) (xy 370.586149 -397.133284) (xy 354.657801 -397.133284) (xy 354.983542 -397.696944)
			(xy 354.983796 -397.697452) (xy 354.98405 -397.697452) (xy 354.98532 -397.699992) (xy 354.997593 -397.722907)
			(xy 355.014998 -397.771885) (xy 355.023872 -397.823101) (xy 355.024436 -397.84909) (xy 355.024436 -397.849344)
			(xy 355.024002 -397.87335) (xy 355.016481 -397.920768) (xy 355.001633 -397.966426) (xy 354.979822 -398.009197)
			(xy 354.951587 -398.048029) (xy 354.917623 -398.081963) (xy 354.878767 -398.110164) (xy 354.835976 -398.131936)
			(xy 354.790305 -398.146744) (xy 354.74288 -398.154223) (xy 354.718874 -398.154652) (xy 354.695212 -398.154153)
			(xy 354.648453 -398.146854) (xy 354.603379 -398.132433) (xy 354.561067 -398.111237) (xy 354.522528 -398.083771)
			(xy 354.488684 -398.050693) (xy 354.460343 -398.012792) (xy 354.448872 -397.992092) (xy 354.448618 -397.99133)
			(xy 354.051362 -397.304006) (xy 354.039184 -397.280789) (xy 354.022068 -397.231239) (xy 354.017326 -397.205454)
			(xy 354.017326 -397.2052) (xy 354.013846 -397.181395) (xy 354.013635 -397.133285) (xy 353.457652 -397.133285)
			(xy 353.783392 -397.696944) (xy 353.783646 -397.697452) (xy 353.7839 -397.697452) (xy 353.78517 -397.699992)
			(xy 353.797399 -397.722918) (xy 353.814722 -397.771903) (xy 353.82351 -397.823111) (xy 353.824032 -397.84909)
			(xy 353.824032 -397.849344) (xy 353.823578 -397.873335) (xy 353.816066 -397.920726) (xy 353.801234 -397.966359)
			(xy 353.779447 -398.00911) (xy 353.751242 -398.047927) (xy 353.717312 -398.081855) (xy 353.678493 -398.110058)
			(xy 353.63574 -398.131842) (xy 353.590107 -398.146671) (xy 353.542715 -398.15418) (xy 353.518724 -398.154652)
			(xy 353.49506 -398.154193) (xy 353.4483 -398.146886) (xy 353.403225 -398.132459) (xy 353.360913 -398.111256)
			(xy 353.322374 -398.083784) (xy 353.288531 -398.0507) (xy 353.260193 -398.012795) (xy 353.248722 -397.992092)
			(xy 353.248468 -397.99133) (xy 352.851212 -397.304006) (xy 352.839031 -397.28079) (xy 352.821918 -397.231239)
			(xy 352.817176 -397.205454) (xy 352.817176 -397.2052) (xy 352.813621 -397.179976) (xy 352.284739 -397.179976)
			(xy 352.583496 -397.696944) (xy 352.58375 -397.697452) (xy 352.584004 -397.697452) (xy 352.585274 -397.699992)
			(xy 352.597504 -397.722918) (xy 352.614826 -397.771903) (xy 352.623614 -397.823111) (xy 352.624136 -397.84909)
			(xy 352.624136 -397.849344) (xy 352.623678 -397.873335) (xy 352.616166 -397.920726) (xy 352.601335 -397.966358)
			(xy 352.579548 -398.009109) (xy 352.551343 -398.047926) (xy 352.517413 -398.081853) (xy 352.478595 -398.110056)
			(xy 352.435843 -398.131841) (xy 352.39021 -398.14667) (xy 352.342819 -398.154179) (xy 352.318828 -398.154652)
			(xy 352.295164 -398.15419) (xy 352.248404 -398.146884) (xy 352.203329 -398.132457) (xy 352.161017 -398.111254)
			(xy 352.122479 -398.083783) (xy 352.088636 -398.050699) (xy 352.060297 -398.012794) (xy 352.048826 -397.992092)
			(xy 352.048572 -397.99133) (xy 351.651316 -397.304006) (xy 351.639135 -397.28079) (xy 351.622022 -397.231239)
			(xy 351.61728 -397.205454) (xy 351.61728 -397.2052) (xy 351.613718 -397.179977) (xy 351.084589 -397.179977)
			(xy 351.383346 -397.696944) (xy 351.3836 -397.697452) (xy 351.383854 -397.697452) (xy 351.385124 -397.699992)
			(xy 351.397397 -397.722907) (xy 351.414802 -397.771885) (xy 351.423676 -397.823101) (xy 351.42424 -397.84909)
			(xy 351.42424 -397.849344) (xy 351.423802 -397.873349) (xy 351.416281 -397.920768) (xy 351.401433 -397.966425)
			(xy 351.379623 -398.009196) (xy 351.351388 -398.048027) (xy 351.317425 -398.081961) (xy 351.278569 -398.110162)
			(xy 351.235779 -398.131935) (xy 351.190109 -398.146744) (xy 351.142684 -398.154222) (xy 351.118678 -398.154652)
			(xy 351.095013 -398.15423) (xy 351.048251 -398.146916) (xy 351.003175 -398.132482) (xy 350.960863 -398.111273)
			(xy 350.922325 -398.083796) (xy 350.888483 -398.050707) (xy 350.860146 -398.012797) (xy 350.848676 -397.992092)
			(xy 350.848422 -397.99133) (xy 350.451166 -397.304006) (xy 350.438988 -397.280789) (xy 350.421872 -397.231239)
			(xy 350.41713 -397.205454) (xy 350.41713 -397.2052) (xy 350.413643 -397.181396) (xy 350.413431 -397.133285)
			(xy 349.85771 -397.133285) (xy 350.18345 -397.696944) (xy 350.183704 -397.697452) (xy 350.183958 -397.697452)
			(xy 350.185228 -397.699992) (xy 350.197501 -397.722907) (xy 350.214906 -397.771885) (xy 350.22378 -397.823101)
			(xy 350.224344 -397.84909) (xy 350.224344 -397.849344) (xy 350.223902 -397.873349) (xy 350.216382 -397.920767)
			(xy 350.201534 -397.966424) (xy 350.179724 -398.009195) (xy 350.15149 -398.048026) (xy 350.117526 -398.08196)
			(xy 350.078671 -398.110161) (xy 350.035882 -398.131934) (xy 349.990212 -398.146743) (xy 349.942788 -398.154222)
			(xy 349.918782 -398.154652) (xy 349.895117 -398.154227) (xy 349.848355 -398.146914) (xy 349.80328 -398.13248)
			(xy 349.760967 -398.111272) (xy 349.722429 -398.083795) (xy 349.688587 -398.050706) (xy 349.66025 -398.012797)
			(xy 349.64878 -397.992092) (xy 349.648526 -397.99133) (xy 349.25127 -397.304006) (xy 349.239093 -397.280789)
			(xy 349.221977 -397.231238) (xy 349.217234 -397.205454) (xy 349.217234 -397.2052) (xy 349.213739 -397.181396)
			(xy 349.213528 -397.133285) (xy 348.657814 -397.133285) (xy 348.983554 -397.696944) (xy 348.983808 -397.697452)
			(xy 348.984062 -397.697452) (xy 348.985332 -397.699992) (xy 348.997606 -397.722907) (xy 349.015011 -397.771885)
			(xy 349.023884 -397.823101) (xy 349.024448 -397.84909) (xy 349.024448 -397.849344) (xy 349.024002 -397.873349)
			(xy 349.016482 -397.920767) (xy 349.001634 -397.966423) (xy 348.979825 -398.009194) (xy 348.951591 -398.048025)
			(xy 348.917628 -398.081959) (xy 348.878773 -398.11016) (xy 348.835984 -398.131933) (xy 348.790315 -398.146742)
			(xy 348.742891 -398.154222) (xy 348.718886 -398.154652) (xy 348.695221 -398.154224) (xy 348.64846 -398.146911)
			(xy 348.603384 -398.132478) (xy 348.561072 -398.11127) (xy 348.522534 -398.083794) (xy 348.488692 -398.050705)
			(xy 348.460354 -398.012796) (xy 348.448884 -397.992092) (xy 348.44863 -397.99133) (xy 348.051374 -397.304006)
			(xy 348.039197 -397.280788) (xy 348.022081 -397.231238) (xy 348.017338 -397.205454) (xy 348.017338 -397.2052)
			(xy 348.013836 -397.181397) (xy 348.013624 -397.133286) (xy 347.457665 -397.133286) (xy 347.783404 -397.696944)
			(xy 347.783658 -397.697452) (xy 347.783912 -397.697452) (xy 347.785182 -397.699992) (xy 347.797412 -397.722918)
			(xy 347.814734 -397.771903) (xy 347.823522 -397.823111) (xy 347.824044 -397.84909) (xy 347.824044 -397.849344)
			(xy 347.823578 -397.873335) (xy 347.816067 -397.920724) (xy 347.801235 -397.966356) (xy 347.779449 -398.009106)
			(xy 347.751245 -398.047923) (xy 347.717317 -398.08185) (xy 347.678499 -398.110054) (xy 347.635749 -398.131838)
			(xy 347.590117 -398.146668) (xy 347.542727 -398.154179) (xy 347.518736 -398.154652) (xy 347.495073 -398.154184)
			(xy 347.448313 -398.146878) (xy 347.403238 -398.132453) (xy 347.360926 -398.111251) (xy 347.322387 -398.083781)
			(xy 347.288544 -398.050698) (xy 347.260205 -398.012794) (xy 347.248734 -397.992092) (xy 347.24848 -397.99133)
			(xy 346.851224 -397.304006) (xy 346.839044 -397.28079) (xy 346.82193 -397.231239) (xy 346.817188 -397.205454)
			(xy 346.817188 -397.2052) (xy 346.813611 -397.179979) (xy 346.284753 -397.179979) (xy 346.583508 -397.696944)
			(xy 346.583762 -397.697452) (xy 346.584016 -397.697452) (xy 346.585286 -397.699992) (xy 346.597517 -397.722917)
			(xy 346.614838 -397.771902) (xy 346.623626 -397.823111) (xy 346.624148 -397.84909) (xy 346.624148 -397.849344)
			(xy 346.623678 -397.873334) (xy 346.616167 -397.920724) (xy 346.601336 -397.966355) (xy 346.57955 -398.009105)
			(xy 346.551346 -398.047922) (xy 346.517418 -398.081849) (xy 346.478602 -398.110052) (xy 346.435851 -398.131837)
			(xy 346.39022 -398.146668) (xy 346.34283 -398.154178) (xy 346.31884 -398.154652) (xy 346.295177 -398.15418)
			(xy 346.248417 -398.146876) (xy 346.203342 -398.132451) (xy 346.16103 -398.11125) (xy 346.122492 -398.08378)
			(xy 346.088648 -398.050698) (xy 346.060309 -398.012794) (xy 346.048838 -397.992092) (xy 346.048584 -397.99133)
			(xy 345.651328 -397.304006) (xy 345.639148 -397.28079) (xy 345.622034 -397.231239) (xy 345.617292 -397.205454)
			(xy 345.617292 -397.2052) (xy 345.613876 -397.181387) (xy 345.613665 -397.133284) (xy 345.057617 -397.133284)
			(xy 345.383358 -397.696944) (xy 345.383612 -397.697452) (xy 345.383866 -397.697452) (xy 345.385136 -397.699992)
			(xy 345.39741 -397.722906) (xy 345.414815 -397.771885) (xy 345.423688 -397.823101) (xy 345.424252 -397.84909)
			(xy 345.424252 -397.849344) (xy 345.423802 -397.873349) (xy 345.416282 -397.920766) (xy 345.401434 -397.966422)
			(xy 345.379625 -398.009193) (xy 345.351392 -398.048023) (xy 345.31743 -398.081957) (xy 345.278576 -398.110158)
			(xy 345.235787 -398.131932) (xy 345.190119 -398.146741) (xy 345.142695 -398.154222) (xy 345.11869 -398.154652)
			(xy 345.095025 -398.154221) (xy 345.048264 -398.146909) (xy 345.003188 -398.132476) (xy 344.960876 -398.111269)
			(xy 344.922338 -398.083793) (xy 344.888496 -398.050705) (xy 344.860158 -398.012796) (xy 344.848688 -397.992092)
			(xy 344.848434 -397.99133) (xy 344.451178 -397.304006) (xy 344.439001 -397.280788) (xy 344.421885 -397.231238)
			(xy 344.417142 -397.205454) (xy 344.417142 -397.2052) (xy 344.413632 -397.181398) (xy 344.413421 -397.133286)
			(xy 343.857723 -397.133286) (xy 344.183462 -397.696944) (xy 344.183716 -397.697452) (xy 344.18397 -397.697452)
			(xy 344.18524 -397.699992) (xy 344.197514 -397.722906) (xy 344.214919 -397.771885) (xy 344.223792 -397.823101)
			(xy 344.224356 -397.84909) (xy 344.224356 -397.849344) (xy 344.223902 -397.873349) (xy 344.216382 -397.920765)
			(xy 344.201535 -397.966421) (xy 344.179726 -398.009191) (xy 344.151493 -398.048022) (xy 344.117531 -398.081956)
			(xy 344.078678 -398.110157) (xy 344.03589 -398.131931) (xy 343.990222 -398.14674) (xy 343.942799 -398.154221)
			(xy 343.918794 -398.154652) (xy 343.895129 -398.154217) (xy 343.848368 -398.146906) (xy 343.803293 -398.132474)
			(xy 343.76098 -398.111267) (xy 343.722442 -398.083792) (xy 343.6886 -398.050704) (xy 343.660262 -398.012796)
			(xy 343.648792 -397.992092) (xy 343.648538 -397.99133) (xy 343.251282 -397.304006) (xy 343.239105 -397.280788)
			(xy 343.221989 -397.231238) (xy 343.217246 -397.205454) (xy 343.217246 -397.2052) (xy 343.213729 -397.181399)
			(xy 343.213517 -397.133286) (xy 342.657827 -397.133286) (xy 342.983566 -397.696944) (xy 342.98382 -397.697452)
			(xy 342.984074 -397.697452) (xy 342.985344 -397.699992) (xy 342.997619 -397.722906) (xy 343.015023 -397.771885)
			(xy 343.023896 -397.823101) (xy 343.02446 -397.84909) (xy 343.02446 -397.849344) (xy 343.024101 -397.873353)
			(xy 343.016579 -397.92078) (xy 343.001726 -397.966444) (xy 342.979909 -398.00922) (xy 342.951665 -398.048055)
			(xy 342.917691 -398.08199) (xy 342.878825 -398.11019) (xy 342.836023 -398.131958) (xy 342.790342 -398.146759)
			(xy 342.742908 -398.154228) (xy 342.718898 -398.154652) (xy 342.695234 -398.154214) (xy 342.648472 -398.146903)
			(xy 342.603397 -398.132472) (xy 342.561085 -398.111266) (xy 342.522547 -398.083791) (xy 342.488704 -398.050704)
			(xy 342.460366 -398.012796) (xy 342.448896 -397.992092) (xy 342.448642 -397.99133) (xy 342.051386 -397.304006)
			(xy 342.03921 -397.280788) (xy 342.022093 -397.231238) (xy 342.01735 -397.205454) (xy 342.01735 -397.2052)
			(xy 342.013825 -397.1814) (xy 342.013613 -397.133286) (xy 341.457677 -397.133286) (xy 341.783416 -397.696944)
			(xy 341.78367 -397.697452) (xy 341.783924 -397.697452) (xy 341.785194 -397.699992) (xy 341.797425 -397.722917)
			(xy 341.814746 -397.771902) (xy 341.823534 -397.823111) (xy 341.824056 -397.84909) (xy 341.824056 -397.849344)
			(xy 341.823578 -397.873334) (xy 341.816067 -397.920723) (xy 341.801236 -397.966353) (xy 341.779452 -398.009103)
			(xy 341.751249 -398.047919) (xy 341.717322 -398.081846) (xy 341.678506 -398.11005) (xy 341.635757 -398.131835)
			(xy 341.590127 -398.146666) (xy 341.542738 -398.154178) (xy 341.518748 -398.154652) (xy 341.495085 -398.154174)
			(xy 341.448326 -398.146871) (xy 341.403251 -398.132447) (xy 341.360939 -398.111247) (xy 341.3224 -398.083778)
			(xy 341.288557 -398.050697) (xy 341.260217 -398.012794) (xy 341.248746 -397.992092) (xy 341.248492 -397.99133)
			(xy 340.851236 -397.304006) (xy 340.839056 -397.28079) (xy 340.821942 -397.231239) (xy 340.8172 -397.205454)
			(xy 340.8172 -397.2052) (xy 340.813769 -397.181389) (xy 340.813558 -397.133284) (xy 340.257779 -397.133284)
			(xy 340.58352 -397.696944) (xy 340.583774 -397.697452) (xy 340.584028 -397.697452) (xy 340.585298 -397.699992)
			(xy 340.597529 -397.722917) (xy 340.61485 -397.771902) (xy 340.623638 -397.823111) (xy 340.62416 -397.84909)
			(xy 340.62416 -397.849344) (xy 340.623802 -397.873341) (xy 340.616287 -397.920742) (xy 340.60145 -397.966385)
			(xy 340.579655 -398.009144) (xy 340.551439 -398.047968) (xy 340.517498 -398.081899) (xy 340.478666 -398.110103)
			(xy 340.4359 -398.131885) (xy 340.390253 -398.146709) (xy 340.342849 -398.154209) (xy 340.318852 -398.154652)
			(xy 340.295189 -398.154171) (xy 340.24843 -398.146868) (xy 340.203356 -398.132445) (xy 340.161043 -398.111245)
			(xy 340.122505 -398.083777) (xy 340.088661 -398.050696) (xy 340.060321 -398.012793) (xy 340.04885 -397.992092)
			(xy 340.048596 -397.99133) (xy 339.65134 -397.304006) (xy 339.639161 -397.28079) (xy 339.622046 -397.231239)
			(xy 339.617304 -397.205454) (xy 339.617304 -397.2052) (xy 339.613866 -397.18139) (xy 339.613655 -397.133284)
			(xy 339.057629 -397.133284) (xy 339.38337 -397.696944) (xy 339.383624 -397.697452) (xy 339.383878 -397.697452)
			(xy 339.385148 -397.699992) (xy 339.397423 -397.722906) (xy 339.414827 -397.771885) (xy 339.4237 -397.823101)
			(xy 339.424264 -397.84909) (xy 339.424264 -397.849344) (xy 339.423901 -397.873353) (xy 339.416379 -397.920779)
			(xy 339.401526 -397.966443) (xy 339.379709 -398.009219) (xy 339.351466 -398.048053) (xy 339.317493 -398.081989)
			(xy 339.278627 -398.110188) (xy 339.235826 -398.131957) (xy 339.190146 -398.146759) (xy 339.142712 -398.154228)
			(xy 339.118702 -398.154652) (xy 339.095038 -398.154211) (xy 339.048277 -398.146901) (xy 339.003201 -398.13247)
			(xy 338.960889 -398.111264) (xy 338.922351 -398.08379) (xy 338.888508 -398.050703) (xy 338.86017 -398.012796)
			(xy 338.8487 -397.992092) (xy 338.848446 -397.99133) (xy 338.45119 -397.304006) (xy 338.439014 -397.280788)
			(xy 338.421897 -397.231238) (xy 338.417154 -397.205454) (xy 338.417154 -397.2052) (xy 338.413622 -397.181401)
			(xy 338.41341 -397.133286) (xy 337.857735 -397.133286) (xy 338.183474 -397.696944) (xy 338.183728 -397.697452)
			(xy 338.183982 -397.697452) (xy 338.185252 -397.699992) (xy 338.197527 -397.722906) (xy 338.214931 -397.771885)
			(xy 338.223804 -397.823101) (xy 338.224368 -397.84909) (xy 338.224368 -397.849344) (xy 338.224001 -397.873353)
			(xy 338.216479 -397.920778) (xy 338.201626 -397.966442) (xy 338.17981 -398.009218) (xy 338.151567 -398.048052)
			(xy 338.117595 -398.081987) (xy 338.078729 -398.110187) (xy 338.035929 -398.131956) (xy 337.990249 -398.146758)
			(xy 337.942816 -398.154228) (xy 337.918806 -398.154652) (xy 337.895142 -398.154208) (xy 337.848381 -398.146898)
			(xy 337.803306 -398.132468) (xy 337.760993 -398.111263) (xy 337.722455 -398.083789) (xy 337.688613 -398.050703)
			(xy 337.660274 -398.012795) (xy 337.648804 -397.992092) (xy 337.64855 -397.99133) (xy 337.251294 -397.304006)
			(xy 337.239112 -397.280791) (xy 337.221999 -397.231239) (xy 337.217258 -397.205454) (xy 337.217258 -397.2052)
			(xy 337.213718 -397.181402) (xy 337.213506 -397.133287) (xy 336.657839 -397.133287) (xy 336.983578 -397.696944)
			(xy 336.983832 -397.697452) (xy 336.984086 -397.697452) (xy 336.985356 -397.699992) (xy 336.997631 -397.722906)
			(xy 337.015035 -397.771885) (xy 337.023908 -397.823101) (xy 337.024472 -397.84909) (xy 337.024472 -397.849344)
			(xy 337.024101 -397.873353) (xy 337.016579 -397.920778) (xy 337.001727 -397.966441) (xy 336.979911 -398.009217)
			(xy 336.951668 -398.048051) (xy 336.917696 -398.081986) (xy 336.878831 -398.110185) (xy 336.836032 -398.131955)
			(xy 336.790352 -398.146757) (xy 336.742919 -398.154228) (xy 336.71891 -398.154652) (xy 336.695246 -398.154205)
			(xy 336.648485 -398.146896) (xy 336.60341 -398.132466) (xy 336.561098 -398.111261) (xy 336.522559 -398.083788)
			(xy 336.488717 -398.050702) (xy 336.460378 -398.012795) (xy 336.448908 -397.992092) (xy 336.448654 -397.99133)
			(xy 336.051398 -397.304006) (xy 336.039216 -397.280791) (xy 336.022103 -397.231239) (xy 336.017362 -397.205454)
			(xy 336.017362 -397.2052) (xy 336.013815 -397.181402) (xy 336.013603 -397.133287) (xy 322.130055 -397.133287)
			(xy 322.455794 -397.696944) (xy 322.456048 -397.697452) (xy 322.456302 -397.697452) (xy 322.457572 -397.699992)
			(xy 322.469841 -397.722909) (xy 322.487249 -397.771886) (xy 322.496124 -397.823102) (xy 322.496688 -397.84909)
			(xy 322.496688 -397.849344) (xy 322.496301 -397.873352) (xy 322.48878 -397.920775) (xy 322.473928 -397.966437)
			(xy 322.452114 -398.009212) (xy 322.423873 -398.048045) (xy 322.389903 -398.08198) (xy 322.35104 -398.11018)
			(xy 322.308243 -398.13195) (xy 322.262566 -398.146754) (xy 322.215134 -398.154226) (xy 322.191126 -398.154652)
			(xy 322.167462 -398.154192) (xy 322.120702 -398.146885) (xy 322.075627 -398.132458) (xy 322.033315 -398.111255)
			(xy 321.994777 -398.083783) (xy 321.960934 -398.0507) (xy 321.932595 -398.012795) (xy 321.921124 -397.992092)
			(xy 321.92087 -397.99133) (xy 321.523614 -397.304006) (xy 321.511433 -397.28079) (xy 321.49432 -397.231239)
			(xy 321.489578 -397.205454) (xy 321.489578 -397.2052) (xy 321.486019 -397.179977) (xy 320.956931 -397.179977)
			(xy 321.237864 -397.665956) (xy 321.238118 -397.666464) (xy 321.257676 -397.699992) (xy 321.269945 -397.722909)
			(xy 321.287353 -397.771886) (xy 321.296228 -397.823102) (xy 321.296792 -397.84909) (xy 321.296792 -397.849344)
			(xy 321.296401 -397.873352) (xy 321.28888 -397.920775) (xy 321.274029 -397.966436) (xy 321.252214 -398.009211)
			(xy 321.223974 -398.048044) (xy 321.190005 -398.081979) (xy 321.151142 -398.110179) (xy 321.108346 -398.131949)
			(xy 321.062669 -398.146753) (xy 321.015238 -398.154226) (xy 320.99123 -398.154652) (xy 320.990976 -398.154652)
			(xy 320.967403 -398.15425) (xy 320.920816 -398.147007) (xy 320.875899 -398.13268) (xy 320.833722 -398.111612)
			(xy 320.795289 -398.084305) (xy 320.761516 -398.051408) (xy 320.733208 -398.013706) (xy 320.721736 -397.993108)
			(xy 320.721228 -397.992346) (xy 320.323464 -397.304006) (xy 320.311554 -397.281335) (xy 320.294614 -397.233011)
			(xy 320.285952 -397.182542) (xy 320.285364 -397.15694) (xy 319.743678 -397.15694) (xy 320.055748 -397.696944)
			(xy 320.056002 -397.697452) (xy 320.056256 -397.697452) (xy 320.057526 -397.699992) (xy 320.06976 -397.722916)
			(xy 320.087079 -397.771902) (xy 320.095866 -397.823111) (xy 320.096388 -397.84909) (xy 320.096388 -397.849344)
			(xy 320.095978 -397.873337) (xy 320.088465 -397.920733) (xy 320.07363 -397.966369) (xy 320.051839 -398.009123)
			(xy 320.023629 -398.047942) (xy 319.989693 -398.08187) (xy 319.950868 -398.110073) (xy 319.90811 -398.131854)
			(xy 319.86247 -398.14668) (xy 319.815074 -398.154183) (xy 319.79108 -398.154652) (xy 319.767415 -398.154229)
			(xy 319.720653 -398.146915) (xy 319.675577 -398.132481) (xy 319.633265 -398.111272) (xy 319.594727 -398.083795)
			(xy 319.560885 -398.050706) (xy 319.532548 -398.012797) (xy 319.521078 -397.992092) (xy 319.520824 -397.99133)
			(xy 319.123568 -397.304006) (xy 319.11139 -397.280789) (xy 319.094275 -397.231239) (xy 319.089532 -397.205454)
			(xy 319.089532 -397.2052) (xy 319.086041 -397.181396) (xy 319.08583 -397.133285) (xy 318.529894 -397.133285)
			(xy 318.837818 -397.665956) (xy 318.838072 -397.666464) (xy 318.85763 -397.699992) (xy 318.869864 -397.722916)
			(xy 318.887183 -397.771902) (xy 318.895971 -397.823111) (xy 318.896492 -397.84909) (xy 318.896492 -397.849344)
			(xy 318.896078 -397.873337) (xy 318.888565 -397.920732) (xy 318.87373 -397.966368) (xy 318.85194 -398.009122)
			(xy 318.82373 -398.047941) (xy 318.789795 -398.081869) (xy 318.750971 -398.110071) (xy 318.708212 -398.131853)
			(xy 318.662574 -398.146679) (xy 318.615177 -398.154183) (xy 318.591184 -398.154652) (xy 318.59093 -398.154652)
			(xy 318.567358 -398.154207) (xy 318.520774 -398.146971) (xy 318.475858 -398.132652) (xy 318.43368 -398.111592)
			(xy 318.395247 -398.084291) (xy 318.361473 -398.0514) (xy 318.333163 -398.013704) (xy 318.32169 -397.993108)
			(xy 318.321182 -397.992346) (xy 317.923418 -397.304006) (xy 317.911539 -397.281331) (xy 317.89469 -397.232997)
			(xy 317.886118 -397.182533) (xy 317.885572 -397.15694) (xy 317.343632 -397.15694) (xy 317.655702 -397.696944)
			(xy 317.655956 -397.697452) (xy 317.65621 -397.697452) (xy 317.65748 -397.699992) (xy 317.669749 -397.722909)
			(xy 317.687157 -397.771886) (xy 317.696032 -397.823102) (xy 317.696596 -397.84909) (xy 317.696596 -397.849344)
			(xy 317.696201 -397.873352) (xy 317.68868 -397.920774) (xy 317.673829 -397.966435) (xy 317.652015 -398.009209)
			(xy 317.623775 -398.048042) (xy 317.589806 -398.081977) (xy 317.550945 -398.110177) (xy 317.508148 -398.131948)
			(xy 317.462472 -398.146752) (xy 317.415042 -398.154226) (xy 317.391034 -398.154652) (xy 317.367371 -398.154185)
			(xy 317.320611 -398.14688) (xy 317.275536 -398.132454) (xy 317.233224 -398.111252) (xy 317.194685 -398.083781)
			(xy 317.160842 -398.050699) (xy 317.132503 -398.012794) (xy 317.121032 -397.992092) (xy 317.120778 -397.99133)
			(xy 316.723522 -397.304006) (xy 316.711341 -397.28079) (xy 316.694228 -397.231239) (xy 316.689486 -397.205454)
			(xy 316.689486 -397.2052) (xy 316.685912 -397.179979) (xy 316.157051 -397.179979) (xy 316.455806 -397.696944)
			(xy 316.45606 -397.697452) (xy 316.456314 -397.697452) (xy 316.457584 -397.699992) (xy 316.469854 -397.722909)
			(xy 316.487261 -397.771886) (xy 316.496136 -397.823101) (xy 316.4967 -397.84909) (xy 316.4967 -397.849344)
			(xy 316.496301 -397.873351) (xy 316.48878 -397.920774) (xy 316.47393 -397.966434) (xy 316.452116 -398.009208)
			(xy 316.423877 -398.048041) (xy 316.389908 -398.081976) (xy 316.351047 -398.110176) (xy 316.308251 -398.131947)
			(xy 316.262576 -398.146752) (xy 316.215146 -398.154225) (xy 316.191138 -398.154652) (xy 316.167475 -398.154182)
			(xy 316.120715 -398.146877) (xy 316.07564 -398.132452) (xy 316.033328 -398.111251) (xy 315.994789 -398.08378)
			(xy 315.960946 -398.050698) (xy 315.932607 -398.012794) (xy 315.921136 -397.992092) (xy 315.920882 -397.99133)
			(xy 315.523626 -397.304006) (xy 315.511446 -397.28079) (xy 315.494332 -397.231239) (xy 315.48959 -397.205454)
			(xy 315.48959 -397.2052) (xy 315.486178 -397.181387) (xy 315.485967 -397.133284) (xy 314.929915 -397.133284)
			(xy 315.255656 -397.696944) (xy 315.25591 -397.697452) (xy 315.256164 -397.697452) (xy 315.257434 -397.699992)
			(xy 315.269668 -397.722915) (xy 315.286988 -397.771902) (xy 315.295775 -397.823111) (xy 315.296296 -397.84909)
			(xy 315.296296 -397.849344) (xy 315.295878 -397.873337) (xy 315.288365 -397.920731) (xy 315.273531 -397.966367)
			(xy 315.251741 -398.009121) (xy 315.223531 -398.047939) (xy 315.189597 -398.081868) (xy 315.150773 -398.11007)
			(xy 315.108015 -398.131852) (xy 315.062377 -398.146678) (xy 315.014981 -398.154182) (xy 314.990988 -398.154652)
			(xy 314.967323 -398.154222) (xy 314.920562 -398.14691) (xy 314.875486 -398.132477) (xy 314.833174 -398.111269)
			(xy 314.794636 -398.083793) (xy 314.760794 -398.050705) (xy 314.732456 -398.012796) (xy 314.720986 -397.992092)
			(xy 314.720732 -397.99133) (xy 314.323476 -397.304006) (xy 314.311299 -397.280788) (xy 314.294183 -397.231238)
			(xy 314.28944 -397.205454) (xy 314.28944 -397.2052) (xy 314.285934 -397.181398) (xy 314.285722 -397.133286)
			(xy 313.730021 -397.133286) (xy 314.05576 -397.696944) (xy 314.056014 -397.697452) (xy 314.056268 -397.697452)
			(xy 314.057538 -397.699992) (xy 314.069773 -397.722915) (xy 314.087092 -397.771902) (xy 314.095879 -397.823111)
			(xy 314.0964 -397.84909) (xy 314.0964 -397.849344) (xy 314.095978 -397.873337) (xy 314.088465 -397.920731)
			(xy 314.073631 -397.966366) (xy 314.051841 -398.009119) (xy 314.023632 -398.047938) (xy 313.989698 -398.081866)
			(xy 313.950875 -398.110069) (xy 313.908118 -398.131851) (xy 313.86248 -398.146677) (xy 313.815085 -398.154182)
			(xy 313.791092 -398.154652) (xy 313.767427 -398.154219) (xy 313.720666 -398.146907) (xy 313.67559 -398.132475)
			(xy 313.633278 -398.111268) (xy 313.59474 -398.083792) (xy 313.560898 -398.050705) (xy 313.53256 -398.012796)
			(xy 313.52109 -397.992092) (xy 313.520836 -397.99133) (xy 313.12358 -397.304006) (xy 313.111403 -397.280788)
			(xy 313.094287 -397.231238) (xy 313.089544 -397.205454) (xy 313.089544 -397.2052) (xy 313.086031 -397.181399)
			(xy 313.085819 -397.133286) (xy 312.529906 -397.133286) (xy 312.83783 -397.665956) (xy 312.838084 -397.666464)
			(xy 312.857642 -397.699992) (xy 312.869877 -397.722915) (xy 312.887196 -397.771902) (xy 312.895983 -397.823111)
			(xy 312.896504 -397.84909) (xy 312.896504 -397.849344) (xy 312.896078 -397.873337) (xy 312.888565 -397.92073)
			(xy 312.873731 -397.966365) (xy 312.851942 -398.009118) (xy 312.823733 -398.047937) (xy 312.7898 -398.081865)
			(xy 312.750977 -398.110067) (xy 312.708221 -398.13185) (xy 312.662583 -398.146676) (xy 312.615189 -398.154182)
			(xy 312.591196 -398.154652) (xy 312.590942 -398.154652) (xy 312.567371 -398.154197) (xy 312.520786 -398.146963)
			(xy 312.475871 -398.132646) (xy 312.433693 -398.111587) (xy 312.39526 -398.084288) (xy 312.361486 -398.051398)
			(xy 312.333176 -398.013703) (xy 312.321702 -397.993108) (xy 312.321194 -397.992346) (xy 311.92343 -397.304006)
			(xy 311.911552 -397.28133) (xy 311.894702 -397.232996) (xy 311.88613 -397.182533) (xy 311.885584 -397.15694)
			(xy 311.343644 -397.15694) (xy 311.655714 -397.696944) (xy 311.655968 -397.697452) (xy 311.656222 -397.697452)
			(xy 311.657492 -397.699992) (xy 311.669762 -397.722908) (xy 311.687169 -397.771886) (xy 311.696044 -397.823101)
			(xy 311.696608 -397.84909) (xy 311.696608 -397.849344) (xy 311.696201 -397.873351) (xy 311.68868 -397.920772)
			(xy 311.67383 -397.966432) (xy 311.652017 -398.009206) (xy 311.623779 -398.048038) (xy 311.589811 -398.081973)
			(xy 311.550951 -398.110173) (xy 311.508157 -398.131944) (xy 311.462482 -398.14675) (xy 311.415053 -398.154225)
			(xy 311.391046 -398.154652) (xy 311.367383 -398.154176) (xy 311.320624 -398.146872) (xy 311.275549 -398.132448)
			(xy 311.233237 -398.111248) (xy 311.194698 -398.083778) (xy 311.160854 -398.050697) (xy 311.132515 -398.012794)
			(xy 311.121044 -397.992092) (xy 311.12079 -397.99133) (xy 310.723534 -397.304006) (xy 310.711354 -397.28079)
			(xy 310.69424 -397.231239) (xy 310.689498 -397.205454) (xy 310.689498 -397.2052) (xy 310.686071 -397.181389)
			(xy 310.68586 -397.133284) (xy 310.130077 -397.133284) (xy 310.455818 -397.696944) (xy 310.456072 -397.697452)
			(xy 310.456326 -397.697452) (xy 310.457596 -397.699992) (xy 310.469867 -397.722908) (xy 310.487274 -397.771886)
			(xy 310.496148 -397.823101) (xy 310.496712 -397.84909) (xy 310.496712 -397.849344) (xy 310.496302 -397.873351)
			(xy 310.48878 -397.920772) (xy 310.473931 -397.966432) (xy 310.452118 -398.009205) (xy 310.42388 -398.048037)
			(xy 310.389913 -398.081971) (xy 310.351053 -398.110172) (xy 310.308259 -398.131943) (xy 310.262586 -398.146749)
			(xy 310.215157 -398.154225) (xy 310.19115 -398.154652) (xy 310.167487 -398.154172) (xy 310.120728 -398.146869)
			(xy 310.075653 -398.132446) (xy 310.033341 -398.111246) (xy 309.994802 -398.083777) (xy 309.960959 -398.050696)
			(xy 309.932619 -398.012793) (xy 309.921148 -397.992092) (xy 309.920894 -397.99133) (xy 309.523638 -397.304006)
			(xy 309.511458 -397.28079) (xy 309.494344 -397.231239) (xy 309.489602 -397.205454) (xy 309.489602 -397.2052)
			(xy 309.486167 -397.181389) (xy 309.485956 -397.133284) (xy 308.929927 -397.133284) (xy 309.255668 -397.696944)
			(xy 309.255922 -397.697452) (xy 309.256176 -397.697452) (xy 309.257446 -397.699992) (xy 309.269681 -397.722915)
			(xy 309.287 -397.771902) (xy 309.295787 -397.823111) (xy 309.296308 -397.84909) (xy 309.296308 -397.849344)
			(xy 309.295878 -397.873336) (xy 309.288365 -397.92073) (xy 309.273532 -397.966364) (xy 309.251743 -398.009117)
			(xy 309.223535 -398.047935) (xy 309.189602 -398.081863) (xy 309.150779 -398.110066) (xy 309.108024 -398.131849)
			(xy 309.062387 -398.146676) (xy 309.014992 -398.154181) (xy 308.991 -398.154652) (xy 308.967336 -398.154213)
			(xy 308.920575 -398.146902) (xy 308.875499 -398.132471) (xy 308.833187 -398.111265) (xy 308.794649 -398.08379)
			(xy 308.760806 -398.050703) (xy 308.732468 -398.012796) (xy 308.720998 -397.992092) (xy 308.720744 -397.99133)
			(xy 308.323488 -397.304006) (xy 308.311312 -397.280788) (xy 308.294195 -397.231238) (xy 308.289452 -397.205454)
			(xy 308.289452 -397.2052) (xy 308.285923 -397.1814) (xy 308.285712 -397.133286) (xy 307.730033 -397.133286)
			(xy 308.055772 -397.696944) (xy 308.056026 -397.697452) (xy 308.05628 -397.697452) (xy 308.05755 -397.699992)
			(xy 308.069786 -397.722915) (xy 308.087104 -397.771901) (xy 308.095891 -397.823111) (xy 308.096412 -397.84909)
			(xy 308.096412 -397.849344) (xy 308.095978 -397.873336) (xy 308.088465 -397.920729) (xy 308.073632 -397.966363)
			(xy 308.051844 -398.009116) (xy 308.023636 -398.047934) (xy 307.989703 -398.081862) (xy 307.950882 -398.110065)
			(xy 307.908126 -398.131848) (xy 307.86249 -398.146675) (xy 307.815096 -398.154181) (xy 307.791104 -398.154652)
			(xy 307.76744 -398.154209) (xy 307.720679 -398.146899) (xy 307.675603 -398.132469) (xy 307.633291 -398.111263)
			(xy 307.594753 -398.083789) (xy 307.56091 -398.050703) (xy 307.532572 -398.012796) (xy 307.521102 -397.992092)
			(xy 307.520848 -397.99133) (xy 307.123592 -397.304006) (xy 307.111409 -397.280791) (xy 307.094297 -397.231239)
			(xy 307.089556 -397.205454) (xy 307.089556 -397.2052) (xy 307.08602 -397.181401) (xy 307.085808 -397.133286)
			(xy 306.529918 -397.133286) (xy 306.837842 -397.665956) (xy 306.838096 -397.666464) (xy 306.857654 -397.699992)
			(xy 306.86989 -397.722915) (xy 306.887208 -397.771901) (xy 306.895995 -397.823111) (xy 306.896516 -397.84909)
			(xy 306.896516 -397.849344) (xy 306.896078 -397.873336) (xy 306.888566 -397.920728) (xy 306.873733 -397.966362)
			(xy 306.851944 -398.009115) (xy 306.823737 -398.047932) (xy 306.789805 -398.08186) (xy 306.750984 -398.110063)
			(xy 306.708229 -398.131846) (xy 306.662593 -398.146674) (xy 306.6152 -398.154181) (xy 306.591208 -398.154652)
			(xy 306.590954 -398.154652) (xy 306.567383 -398.154187) (xy 306.520799 -398.146955) (xy 306.475884 -398.13264)
			(xy 306.433706 -398.111583) (xy 306.395273 -398.084285) (xy 306.361498 -398.051397) (xy 306.333188 -398.013702)
			(xy 306.321714 -397.993108) (xy 306.321206 -397.992346) (xy 305.923442 -397.304006) (xy 305.911565 -397.28133)
			(xy 305.894715 -397.232996) (xy 305.886142 -397.182533) (xy 305.885596 -397.15694) (xy 305.343656 -397.15694)
			(xy 305.655726 -397.696944) (xy 305.65598 -397.697452) (xy 305.656234 -397.697452) (xy 305.657504 -397.699992)
			(xy 305.669775 -397.722908) (xy 305.687182 -397.771886) (xy 305.696056 -397.823101) (xy 305.69662 -397.84909)
			(xy 305.69662 -397.849344) (xy 305.696202 -397.87335) (xy 305.688681 -397.920771) (xy 305.673831 -397.96643)
			(xy 305.652019 -398.009202) (xy 305.623782 -398.048034) (xy 305.589816 -398.081969) (xy 305.550958 -398.110169)
			(xy 305.508165 -398.131941) (xy 305.462492 -398.146748) (xy 305.415065 -398.154224) (xy 305.391058 -398.154652)
			(xy 305.367395 -398.154166) (xy 305.320636 -398.146864) (xy 305.275562 -398.132442) (xy 305.23325 -398.111243)
			(xy 305.194711 -398.083775) (xy 305.160867 -398.050695) (xy 305.132527 -398.012793) (xy 305.121056 -397.992092)
			(xy 305.120802 -397.99133) (xy 304.723546 -397.304006) (xy 304.711367 -397.280789) (xy 304.694252 -397.231239)
			(xy 304.68951 -397.205454) (xy 304.68951 -397.2052) (xy 304.68606 -397.181391) (xy 304.685849 -397.133284)
			(xy 304.130089 -397.133284) (xy 304.45583 -397.696944) (xy 304.456084 -397.697452) (xy 304.456338 -397.697452)
			(xy 304.457608 -397.699992) (xy 304.46988 -397.722908) (xy 304.487286 -397.771886) (xy 304.49616 -397.823101)
			(xy 304.496724 -397.84909) (xy 304.496724 -397.849344) (xy 304.496302 -397.87335) (xy 304.488781 -397.92077)
			(xy 304.473932 -397.966429) (xy 304.45212 -398.009201) (xy 304.423884 -398.048033) (xy 304.389918 -398.081967)
			(xy 304.35106 -398.110168) (xy 304.308268 -398.13194) (xy 304.262595 -398.146747) (xy 304.215169 -398.154224)
			(xy 304.191162 -398.154652) (xy 304.167499 -398.154163) (xy 304.120741 -398.146861) (xy 304.075666 -398.132439)
			(xy 304.033354 -398.111241) (xy 303.994815 -398.083774) (xy 303.960971 -398.050695) (xy 303.932631 -398.012793)
			(xy 303.92116 -397.992092) (xy 303.920906 -397.99133) (xy 303.52365 -397.304006) (xy 303.511471 -397.280789)
			(xy 303.494356 -397.231239) (xy 303.489614 -397.205454) (xy 303.489614 -397.2052) (xy 303.486157 -397.181392)
			(xy 303.485946 -397.133285) (xy 2.509012 -397.133285) (xy 2.509012 -400.50847) (xy 103.485188 -400.50847)
			(xy 103.485723 -400.479553) (xy 103.494444 -400.422381) (xy 103.511697 -400.367182) (xy 103.537085 -400.315219)
			(xy 103.570027 -400.267685) (xy 103.609768 -400.225669) (xy 103.632254 -400.20748) (xy 103.641069 -400.199881)
			(xy 103.651246 -400.178974) (xy 103.651812 -400.167348) (xy 103.651812 -400.087592) (xy 103.651259 -400.075962)
			(xy 103.64108 -400.055053) (xy 103.632254 -400.04746) (xy 103.609742 -400.029303) (xy 103.57001 -399.987275)
			(xy 103.537076 -399.939733) (xy 103.511693 -399.887765) (xy 103.494443 -399.832562) (xy 103.48572 -399.775388)
			(xy 103.485188 -399.74647) (xy 103.485674 -399.719201) (xy 103.493436 -399.665217) (xy 103.508801 -399.612887)
			(xy 103.531458 -399.563277) (xy 103.560944 -399.517396) (xy 103.596659 -399.476179) (xy 103.637876 -399.440464)
			(xy 103.683757 -399.410978) (xy 103.733367 -399.388321) (xy 103.785697 -399.372956) (xy 103.839681 -399.365194)
			(xy 103.894219 -399.365194) (xy 103.948203 -399.372956) (xy 104.000533 -399.388321) (xy 104.050143 -399.410978)
			(xy 104.096024 -399.440464) (xy 104.137241 -399.476179) (xy 104.172956 -399.517396) (xy 104.202442 -399.563277)
			(xy 104.225099 -399.612887) (xy 104.240464 -399.665217) (xy 104.248226 -399.719201) (xy 104.248712 -399.74647)
			(xy 104.248206 -399.775388) (xy 104.239479 -399.832561) (xy 104.222221 -399.887762) (xy 104.196827 -399.939724)
			(xy 104.16388 -399.987257) (xy 104.124134 -400.029272) (xy 104.101646 -400.04746) (xy 104.092858 -400.055085)
			(xy 104.082666 -400.075972) (xy 104.082088 -400.087592) (xy 104.082088 -400.167348) (xy 104.082618 -400.178981)
			(xy 104.092814 -400.19989) (xy 104.101646 -400.20748) (xy 104.124129 -400.225671) (xy 104.163863 -400.267692)
			(xy 104.1968 -400.315227) (xy 104.222188 -400.367188) (xy 104.239445 -400.422385) (xy 104.248176 -400.479554)
			(xy 104.248712 -400.50847) (xy 104.248226 -400.535739) (xy 104.240464 -400.589723) (xy 104.225099 -400.642053)
			(xy 104.202442 -400.691663) (xy 104.172956 -400.737544) (xy 104.137241 -400.778761) (xy 104.096024 -400.814476)
			(xy 104.050143 -400.843962) (xy 104.000533 -400.866619) (xy 103.948203 -400.881984) (xy 103.894219 -400.889746)
			(xy 103.839681 -400.889746) (xy 103.785697 -400.881984) (xy 103.733367 -400.866619) (xy 103.683757 -400.843962)
			(xy 103.637876 -400.814476) (xy 103.596659 -400.778761) (xy 103.560944 -400.737544) (xy 103.531458 -400.691663)
			(xy 103.508801 -400.642053) (xy 103.493436 -400.589723) (xy 103.485674 -400.535739) (xy 103.485188 -400.50847)
			(xy 2.509012 -400.50847) (xy 2.509012 -403.371812) (xy 2.5095 -403.425034) (xy 2.517117 -403.531207)
			(xy 2.532283 -403.636566) (xy 2.554922 -403.740575) (xy 2.584919 -403.842706) (xy 2.622121 -403.942439)
			(xy 2.666338 -404.039266) (xy 2.717346 -404.132693) (xy 2.774884 -404.222247) (xy 2.838661 -404.307471)
			(xy 2.908351 -404.387931) (xy 2.945638 -404.425912) (xy 3.30962 -404.789894) (xy 37.568898 -404.789894)
			(xy 37.57287 -404.611651) (xy 37.584778 -404.433762) (xy 37.604599 -404.25658) (xy 37.632293 -404.080456)
			(xy 37.667805 -403.905741) (xy 37.711065 -403.732782) (xy 37.761987 -403.561921) (xy 37.82047 -403.393499)
			(xy 37.886397 -403.227849) (xy 37.959638 -403.0653) (xy 38.040048 -402.906175) (xy 38.127466 -402.75079)
			(xy 38.221719 -402.599454) (xy 38.32262 -402.452466) (xy 38.429969 -402.310119) (xy 38.543552 -402.172696)
			(xy 38.663145 -402.040469) (xy 38.788509 -401.9137) (xy 38.919396 -401.792642) (xy 39.055545 -401.677535)
			(xy 39.196687 -401.568607) (xy 39.342542 -401.466075) (xy 39.492819 -401.370141) (xy 39.64722 -401.280998)
			(xy 39.805439 -401.198821) (xy 39.967162 -401.123773) (xy 40.132067 -401.056005) (xy 40.299828 -400.995649)
			(xy 40.470111 -400.942827) (xy 40.642578 -400.897643) (xy 40.816886 -400.860186) (xy 40.99269 -400.830532)
			(xy 41.16964 -400.808739) (xy 41.347386 -400.794849) (xy 41.525573 -400.788892) (xy 41.70385 -400.790878)
			(xy 41.881861 -400.800804) (xy 42.059253 -400.81865) (xy 42.235673 -400.84438) (xy 42.410773 -400.877944)
			(xy 42.584204 -400.919274) (xy 42.755621 -400.96829) (xy 42.924684 -401.024892) (xy 43.091059 -401.08897)
			(xy 43.254413 -401.160396) (xy 43.414424 -401.239028) (xy 43.570773 -401.324709) (xy 43.72315 -401.417271)
			(xy 43.871253 -401.516528) (xy 44.014787 -401.622285) (xy 44.153467 -401.73433) (xy 44.287018 -401.852442)
			(xy 44.415175 -401.976386) (xy 44.537684 -402.105916) (xy 44.654301 -402.240775) (xy 44.764794 -402.380695)
			(xy 44.868945 -402.525398) (xy 44.966547 -402.674597) (xy 45.057405 -402.827996) (xy 45.141339 -402.98529)
			(xy 45.218184 -403.146166) (xy 45.287785 -403.310307) (xy 45.350006 -403.477384) (xy 45.404722 -403.647068)
			(xy 45.451824 -403.819021) (xy 45.49122 -403.992901) (xy 45.522831 -404.168364) (xy 45.546595 -404.34506)
			(xy 45.559703 -404.491748) (xy 47.413198 -404.491748) (xy 47.413198 -404.437252) (xy 47.420953 -404.38331)
			(xy 47.436306 -404.331021) (xy 47.458943 -404.281449) (xy 47.488404 -404.235603) (xy 47.52409 -404.194416)
			(xy 47.565274 -404.158726) (xy 47.611117 -404.12926) (xy 47.660687 -404.106618) (xy 47.712975 -404.091261)
			(xy 47.766916 -404.083501) (xy 47.794164 -404.083012) (xy 48.657764 -404.083012) (xy 48.68502 -404.083432)
			(xy 48.738978 -404.091186) (xy 48.791283 -404.106539) (xy 48.84087 -404.129181) (xy 48.88673 -404.15865)
			(xy 48.927929 -404.194345) (xy 48.963629 -404.235541) (xy 48.993102 -404.281398) (xy 49.015748 -404.330984)
			(xy 49.031107 -404.383287) (xy 49.038865 -404.437244) (xy 49.038865 -404.491752) (xy 50.476375 -404.491752)
			(xy 50.476375 -404.437248) (xy 50.484132 -404.3833) (xy 50.499487 -404.331005) (xy 50.522129 -404.281427)
			(xy 50.551596 -404.235576) (xy 50.587288 -404.194385) (xy 50.628479 -404.158693) (xy 50.67433 -404.129227)
			(xy 50.723908 -404.106586) (xy 50.776204 -404.091231) (xy 50.830152 -404.083475) (xy 50.857404 -404.083012)
			(xy 51.721004 -404.083012) (xy 51.748256 -404.083458) (xy 51.802207 -404.091215) (xy 51.854504 -404.106572)
			(xy 51.904083 -404.129214) (xy 51.949935 -404.158682) (xy 51.991127 -404.194376) (xy 52.02682 -404.235568)
			(xy 52.056288 -404.281421) (xy 52.07893 -404.331) (xy 52.094285 -404.383297) (xy 52.102042 -404.437248)
			(xy 52.102042 -404.491752) (xy 52.102042 -404.491753) (xy 53.539575 -404.491753) (xy 53.539575 -404.437247)
			(xy 53.547333 -404.383295) (xy 53.562691 -404.330996) (xy 53.585335 -404.281416) (xy 53.614806 -404.235563)
			(xy 53.650502 -404.194371) (xy 53.691698 -404.158679) (xy 53.737554 -404.129214) (xy 53.787137 -404.106575)
			(xy 53.839438 -404.091224) (xy 53.893391 -404.083472) (xy 53.920644 -404.083012) (xy 54.784244 -404.083012)
			(xy 54.811495 -404.083461) (xy 54.86544 -404.091223) (xy 54.917733 -404.106583) (xy 54.967307 -404.129227)
			(xy 55.013154 -404.158696) (xy 55.054341 -404.19439) (xy 55.09003 -404.235581) (xy 55.119494 -404.281432)
			(xy 55.142133 -404.331009) (xy 55.157487 -404.383303) (xy 55.165242 -404.437249) (xy 55.165242 -404.491749)
			(xy 56.602898 -404.491749) (xy 56.602898 -404.437251) (xy 56.610654 -404.383308) (xy 56.626007 -404.331017)
			(xy 56.648646 -404.281443) (xy 56.678109 -404.235596) (xy 56.713797 -404.194409) (xy 56.754983 -404.158719)
			(xy 56.800829 -404.129254) (xy 56.850402 -404.106613) (xy 56.902692 -404.091257) (xy 56.956635 -404.083499)
			(xy 56.983884 -404.083012) (xy 57.847484 -404.083012) (xy 57.874739 -404.083434) (xy 57.928695 -404.091189)
			(xy 57.980997 -404.106545) (xy 58.030582 -404.129188) (xy 58.07644 -404.158657) (xy 58.117636 -404.194352)
			(xy 58.153334 -404.235548) (xy 58.182805 -404.281404) (xy 58.20545 -404.330988) (xy 58.220807 -404.38329)
			(xy 58.228565 -404.437245) (xy 58.228565 -404.491753) (xy 59.666075 -404.491753) (xy 59.666075 -404.437247)
			(xy 59.673833 -404.383297) (xy 59.689189 -404.331) (xy 59.711832 -404.281421) (xy 59.741301 -404.235569)
			(xy 59.776995 -404.194378) (xy 59.818188 -404.158686) (xy 59.864042 -404.129221) (xy 59.913623 -404.106581)
			(xy 59.965921 -404.091227) (xy 60.019871 -404.083474) (xy 60.047124 -404.083012) (xy 60.910724 -404.083012)
			(xy 60.937976 -404.083459) (xy 60.991924 -404.091219) (xy 61.044218 -404.106577) (xy 61.093795 -404.129221)
			(xy 61.139645 -404.158689) (xy 61.180834 -404.194383) (xy 61.216525 -404.235575) (xy 61.245991 -404.281426)
			(xy 61.268631 -404.331004) (xy 61.283986 -404.3833) (xy 61.291742 -404.437248) (xy 61.291742 -404.491748)
			(xy 62.729398 -404.491748) (xy 62.729398 -404.437252) (xy 62.737153 -404.38331) (xy 62.752506 -404.331021)
			(xy 62.775143 -404.281449) (xy 62.804604 -404.235603) (xy 62.84029 -404.194416) (xy 62.881474 -404.158726)
			(xy 62.927317 -404.12926) (xy 62.976887 -404.106618) (xy 63.029175 -404.091261) (xy 63.083116 -404.083501)
			(xy 63.110364 -404.083012) (xy 63.973964 -404.083012) (xy 64.00122 -404.083432) (xy 64.055178 -404.091186)
			(xy 64.107483 -404.106539) (xy 64.15707 -404.129181) (xy 64.20293 -404.15865) (xy 64.244129 -404.194345)
			(xy 64.279829 -404.235541) (xy 64.309302 -404.281398) (xy 64.331948 -404.330984) (xy 64.347307 -404.383287)
			(xy 64.355065 -404.437244) (xy 64.355065 -404.491752) (xy 65.792575 -404.491752) (xy 65.792575 -404.437248)
			(xy 65.800332 -404.3833) (xy 65.815687 -404.331005) (xy 65.838329 -404.281427) (xy 65.867796 -404.235576)
			(xy 65.903488 -404.194385) (xy 65.944679 -404.158693) (xy 65.99053 -404.129227) (xy 66.040108 -404.106586)
			(xy 66.092404 -404.091231) (xy 66.146352 -404.083475) (xy 66.173604 -404.083012) (xy 67.037204 -404.083012)
			(xy 67.064456 -404.083458) (xy 67.118407 -404.091215) (xy 67.170704 -404.106572) (xy 67.220283 -404.129214)
			(xy 67.266135 -404.158682) (xy 67.307327 -404.194376) (xy 67.34302 -404.235568) (xy 67.372488 -404.281421)
			(xy 67.39513 -404.331) (xy 67.410485 -404.383297) (xy 67.418242 -404.437248) (xy 67.418242 -404.491752)
			(xy 67.418242 -404.491753) (xy 68.855775 -404.491753) (xy 68.855775 -404.437247) (xy 68.863533 -404.383295)
			(xy 68.878891 -404.330996) (xy 68.901535 -404.281416) (xy 68.931006 -404.235563) (xy 68.966702 -404.194371)
			(xy 69.007898 -404.158679) (xy 69.053754 -404.129214) (xy 69.103337 -404.106575) (xy 69.155638 -404.091224)
			(xy 69.209591 -404.083472) (xy 69.236844 -404.083012) (xy 70.100444 -404.083012) (xy 70.127695 -404.083461)
			(xy 70.18164 -404.091223) (xy 70.233933 -404.106583) (xy 70.283507 -404.129227) (xy 70.329354 -404.158696)
			(xy 70.370541 -404.19439) (xy 70.40623 -404.235581) (xy 70.435694 -404.281432) (xy 70.458333 -404.331009)
			(xy 70.473687 -404.383303) (xy 70.481442 -404.437249) (xy 70.481442 -404.491749) (xy 71.919098 -404.491749)
			(xy 71.919098 -404.437251) (xy 71.926854 -404.383308) (xy 71.942207 -404.331017) (xy 71.964846 -404.281443)
			(xy 71.994309 -404.235596) (xy 72.029997 -404.194409) (xy 72.071183 -404.158719) (xy 72.117029 -404.129254)
			(xy 72.166602 -404.106613) (xy 72.218892 -404.091257) (xy 72.272835 -404.083499) (xy 72.300084 -404.083012)
			(xy 73.163684 -404.083012) (xy 73.190939 -404.083434) (xy 73.244895 -404.091189) (xy 73.297197 -404.106545)
			(xy 73.346782 -404.129188) (xy 73.39264 -404.158657) (xy 73.433836 -404.194352) (xy 73.469534 -404.235548)
			(xy 73.499005 -404.281404) (xy 73.52165 -404.330988) (xy 73.537007 -404.38329) (xy 73.544765 -404.437245)
			(xy 73.544765 -404.491753) (xy 74.982275 -404.491753) (xy 74.982275 -404.437247) (xy 74.990033 -404.383297)
			(xy 75.005389 -404.331) (xy 75.028032 -404.281421) (xy 75.057501 -404.235569) (xy 75.093195 -404.194378)
			(xy 75.134388 -404.158686) (xy 75.180242 -404.129221) (xy 75.229823 -404.106581) (xy 75.282121 -404.091227)
			(xy 75.336071 -404.083474) (xy 75.363324 -404.083012) (xy 76.226924 -404.083012) (xy 76.254176 -404.083459)
			(xy 76.308124 -404.091219) (xy 76.360418 -404.106577) (xy 76.409995 -404.129221) (xy 76.455845 -404.158689)
			(xy 76.497034 -404.194383) (xy 76.532725 -404.235575) (xy 76.562191 -404.281426) (xy 76.584831 -404.331004)
			(xy 76.600186 -404.3833) (xy 76.607942 -404.437248) (xy 76.607942 -404.491748) (xy 78.045598 -404.491748)
			(xy 78.045598 -404.437252) (xy 78.053353 -404.38331) (xy 78.068706 -404.331021) (xy 78.091343 -404.281449)
			(xy 78.120804 -404.235603) (xy 78.15649 -404.194416) (xy 78.197674 -404.158726) (xy 78.243517 -404.12926)
			(xy 78.293087 -404.106618) (xy 78.345375 -404.091261) (xy 78.399316 -404.083501) (xy 78.426564 -404.083012)
			(xy 79.290164 -404.083012) (xy 79.31742 -404.083432) (xy 79.371378 -404.091186) (xy 79.423683 -404.106539)
			(xy 79.47327 -404.129181) (xy 79.51913 -404.15865) (xy 79.560329 -404.194345) (xy 79.596029 -404.235541)
			(xy 79.625502 -404.281398) (xy 79.648148 -404.330984) (xy 79.663507 -404.383287) (xy 79.671265 -404.437244)
			(xy 79.671265 -404.491752) (xy 81.108775 -404.491752) (xy 81.108775 -404.437248) (xy 81.116532 -404.3833)
			(xy 81.131887 -404.331005) (xy 81.154529 -404.281427) (xy 81.183996 -404.235576) (xy 81.219688 -404.194385)
			(xy 81.260879 -404.158693) (xy 81.30673 -404.129227) (xy 81.356308 -404.106586) (xy 81.408604 -404.091231)
			(xy 81.462552 -404.083475) (xy 81.489804 -404.083012) (xy 82.353404 -404.083012) (xy 82.380656 -404.083458)
			(xy 82.434607 -404.091215) (xy 82.486904 -404.106572) (xy 82.536483 -404.129214) (xy 82.582335 -404.158682)
			(xy 82.623527 -404.194376) (xy 82.65922 -404.235568) (xy 82.688688 -404.281421) (xy 82.71133 -404.331)
			(xy 82.726685 -404.383297) (xy 82.734442 -404.437248) (xy 82.734442 -404.491752) (xy 82.734442 -404.491753)
			(xy 84.171975 -404.491753) (xy 84.171975 -404.437247) (xy 84.179733 -404.383295) (xy 84.195091 -404.330996)
			(xy 84.217735 -404.281416) (xy 84.247206 -404.235563) (xy 84.282902 -404.194371) (xy 84.324098 -404.158679)
			(xy 84.369954 -404.129214) (xy 84.419537 -404.106575) (xy 84.471838 -404.091224) (xy 84.525791 -404.083472)
			(xy 84.553044 -404.083012) (xy 85.416644 -404.083012) (xy 85.443895 -404.083461) (xy 85.49784 -404.091223)
			(xy 85.550133 -404.106583) (xy 85.599707 -404.129227) (xy 85.645554 -404.158696) (xy 85.686741 -404.19439)
			(xy 85.72243 -404.235581) (xy 85.751894 -404.281432) (xy 85.774533 -404.331009) (xy 85.789887 -404.383303)
			(xy 85.797642 -404.437249) (xy 85.797642 -404.491749) (xy 87.235298 -404.491749) (xy 87.235298 -404.437251)
			(xy 87.243054 -404.383308) (xy 87.258407 -404.331017) (xy 87.281046 -404.281443) (xy 87.310509 -404.235596)
			(xy 87.346197 -404.194409) (xy 87.387383 -404.158719) (xy 87.433229 -404.129254) (xy 87.482802 -404.106613)
			(xy 87.535092 -404.091257) (xy 87.589035 -404.083499) (xy 87.616284 -404.083012) (xy 88.479884 -404.083012)
			(xy 88.507139 -404.083434) (xy 88.561095 -404.091189) (xy 88.613397 -404.106545) (xy 88.662982 -404.129188)
			(xy 88.70884 -404.158657) (xy 88.750036 -404.194352) (xy 88.785734 -404.235548) (xy 88.815205 -404.281404)
			(xy 88.83785 -404.330988) (xy 88.853207 -404.38329) (xy 88.860965 -404.437245) (xy 88.860965 -404.491753)
			(xy 90.298475 -404.491753) (xy 90.298475 -404.437247) (xy 90.306233 -404.383297) (xy 90.321589 -404.331)
			(xy 90.344232 -404.281421) (xy 90.373701 -404.235569) (xy 90.409395 -404.194378) (xy 90.450588 -404.158686)
			(xy 90.496442 -404.129221) (xy 90.546023 -404.106581) (xy 90.598321 -404.091227) (xy 90.652271 -404.083474)
			(xy 90.679524 -404.083012) (xy 91.543124 -404.083012) (xy 91.570376 -404.083459) (xy 91.624324 -404.091219)
			(xy 91.676618 -404.106577) (xy 91.726195 -404.129221) (xy 91.772045 -404.158689) (xy 91.813234 -404.194383)
			(xy 91.848925 -404.235575) (xy 91.878391 -404.281426) (xy 91.901031 -404.331004) (xy 91.916386 -404.3833)
			(xy 91.924142 -404.437248) (xy 91.924142 -404.491748) (xy 93.361798 -404.491748) (xy 93.361798 -404.437252)
			(xy 93.369553 -404.38331) (xy 93.384906 -404.331021) (xy 93.407543 -404.281449) (xy 93.437004 -404.235603)
			(xy 93.47269 -404.194416) (xy 93.513874 -404.158726) (xy 93.559717 -404.12926) (xy 93.609287 -404.106618)
			(xy 93.661575 -404.091261) (xy 93.715516 -404.083501) (xy 93.742764 -404.083012) (xy 94.606364 -404.083012)
			(xy 94.63362 -404.083432) (xy 94.687578 -404.091186) (xy 94.739883 -404.106539) (xy 94.78947 -404.129181)
			(xy 94.83533 -404.15865) (xy 94.876529 -404.194345) (xy 94.912229 -404.235541) (xy 94.941702 -404.281398)
			(xy 94.964348 -404.330984) (xy 94.979707 -404.383287) (xy 94.987465 -404.437244) (xy 94.987465 -404.491752)
			(xy 114.513075 -404.491752) (xy 114.513075 -404.437248) (xy 114.520832 -404.3833) (xy 114.536188 -404.331004)
			(xy 114.558829 -404.281426) (xy 114.588296 -404.235575) (xy 114.623989 -404.194384) (xy 114.66518 -404.158693)
			(xy 114.711031 -404.129226) (xy 114.76061 -404.106585) (xy 114.812906 -404.091231) (xy 114.866854 -404.083475)
			(xy 114.894106 -404.083012) (xy 115.757706 -404.083012) (xy 115.784958 -404.083458) (xy 115.838908 -404.091216)
			(xy 115.891205 -404.106572) (xy 115.940784 -404.129215) (xy 115.986636 -404.158683) (xy 116.027828 -404.194376)
			(xy 116.063521 -404.235569) (xy 116.092988 -404.281421) (xy 116.11563 -404.331001) (xy 116.130985 -404.383298)
			(xy 116.138742 -404.437248) (xy 116.138742 -404.491752) (xy 116.138742 -404.491754) (xy 117.576275 -404.491754)
			(xy 117.576275 -404.437246) (xy 117.584033 -404.383294) (xy 117.599391 -404.330996) (xy 117.622035 -404.281415)
			(xy 117.651506 -404.235562) (xy 117.687203 -404.19437) (xy 117.728399 -404.158679) (xy 117.774255 -404.129213)
			(xy 117.823839 -404.106575) (xy 117.876139 -404.091223) (xy 117.930092 -404.083472) (xy 117.957346 -404.083012)
			(xy 118.820946 -404.083012) (xy 118.848197 -404.083461) (xy 118.902142 -404.091223) (xy 118.954434 -404.106583)
			(xy 119.004008 -404.129228) (xy 119.049855 -404.158697) (xy 119.091042 -404.194391) (xy 119.12673 -404.235582)
			(xy 119.156194 -404.281432) (xy 119.178833 -404.331009) (xy 119.194187 -404.383303) (xy 119.201942 -404.437249)
			(xy 119.201942 -404.491749) (xy 120.639598 -404.491749) (xy 120.639598 -404.437251) (xy 120.647354 -404.383307)
			(xy 120.662708 -404.331016) (xy 120.685346 -404.281443) (xy 120.71481 -404.235596) (xy 120.750498 -404.194408)
			(xy 120.791684 -404.158718) (xy 120.83753 -404.129253) (xy 120.887103 -404.106612) (xy 120.939394 -404.091257)
			(xy 120.993337 -404.083499) (xy 121.020586 -404.083012) (xy 121.884186 -404.083012) (xy 121.911441 -404.083434)
			(xy 121.965396 -404.09119) (xy 122.017699 -404.106545) (xy 122.067283 -404.129188) (xy 122.113141 -404.158657)
			(xy 122.154337 -404.194353) (xy 122.190034 -404.235548) (xy 122.219505 -404.281405) (xy 122.24215 -404.330988)
			(xy 122.257507 -404.38329) (xy 122.265265 -404.437245) (xy 122.265265 -404.491753) (xy 123.702775 -404.491753)
			(xy 123.702775 -404.437247) (xy 123.710533 -404.383297) (xy 123.725889 -404.331) (xy 123.748532 -404.281421)
			(xy 123.778001 -404.235569) (xy 123.813696 -404.194377) (xy 123.854889 -404.158686) (xy 123.900743 -404.12922)
			(xy 123.950324 -404.10658) (xy 124.002622 -404.091227) (xy 124.056573 -404.083474) (xy 124.083826 -404.083012)
			(xy 124.947426 -404.083012) (xy 124.974677 -404.08346) (xy 125.028625 -404.09122) (xy 125.08092 -404.106578)
			(xy 125.130496 -404.129222) (xy 125.176346 -404.15869) (xy 125.217535 -404.194383) (xy 125.253226 -404.235575)
			(xy 125.282691 -404.281427) (xy 125.305331 -404.331005) (xy 125.320686 -404.3833) (xy 125.328442 -404.437249)
			(xy 125.328442 -404.491748) (xy 126.766098 -404.491748) (xy 126.766098 -404.437252) (xy 126.773853 -404.38331)
			(xy 126.789206 -404.331021) (xy 126.811843 -404.281448) (xy 126.841305 -404.235602) (xy 126.876991 -404.194415)
			(xy 126.918175 -404.158725) (xy 126.964018 -404.12926) (xy 127.013589 -404.106618) (xy 127.065877 -404.091261)
			(xy 127.119818 -404.083501) (xy 127.147066 -404.083012) (xy 128.010666 -404.083012) (xy 128.037922 -404.083433)
			(xy 128.091879 -404.091186) (xy 128.144184 -404.10654) (xy 128.193771 -404.129182) (xy 128.239631 -404.15865)
			(xy 128.28083 -404.194346) (xy 128.316529 -404.235542) (xy 128.346002 -404.281399) (xy 128.368648 -404.330984)
			(xy 128.384007 -404.383287) (xy 128.391765 -404.437244) (xy 128.391765 -404.491752) (xy 129.829275 -404.491752)
			(xy 129.829275 -404.437248) (xy 129.837032 -404.3833) (xy 129.852388 -404.331004) (xy 129.875029 -404.281426)
			(xy 129.904496 -404.235575) (xy 129.940189 -404.194384) (xy 129.98138 -404.158693) (xy 130.027231 -404.129226)
			(xy 130.07681 -404.106585) (xy 130.129106 -404.091231) (xy 130.183054 -404.083475) (xy 130.210306 -404.083012)
			(xy 131.073906 -404.083012) (xy 131.101158 -404.083458) (xy 131.155108 -404.091216) (xy 131.207405 -404.106572)
			(xy 131.256984 -404.129215) (xy 131.302836 -404.158683) (xy 131.344028 -404.194376) (xy 131.379721 -404.235569)
			(xy 131.409188 -404.281421) (xy 131.43183 -404.331001) (xy 131.447185 -404.383298) (xy 131.454942 -404.437248)
			(xy 131.454942 -404.491752) (xy 131.454942 -404.491754) (xy 132.892475 -404.491754) (xy 132.892475 -404.437246)
			(xy 132.900233 -404.383294) (xy 132.915591 -404.330996) (xy 132.938235 -404.281415) (xy 132.967706 -404.235562)
			(xy 133.003403 -404.19437) (xy 133.044599 -404.158679) (xy 133.090455 -404.129213) (xy 133.140039 -404.106575)
			(xy 133.192339 -404.091223) (xy 133.246292 -404.083472) (xy 133.273546 -404.083012) (xy 134.137146 -404.083012)
			(xy 134.164397 -404.083461) (xy 134.218342 -404.091223) (xy 134.270634 -404.106583) (xy 134.320208 -404.129228)
			(xy 134.366055 -404.158697) (xy 134.407242 -404.194391) (xy 134.44293 -404.235582) (xy 134.472394 -404.281432)
			(xy 134.495033 -404.331009) (xy 134.510387 -404.383303) (xy 134.518142 -404.437249) (xy 134.518142 -404.491749)
			(xy 135.955798 -404.491749) (xy 135.955798 -404.437251) (xy 135.963554 -404.383307) (xy 135.978908 -404.331016)
			(xy 136.001546 -404.281443) (xy 136.03101 -404.235596) (xy 136.066698 -404.194408) (xy 136.107884 -404.158718)
			(xy 136.15373 -404.129253) (xy 136.203303 -404.106612) (xy 136.255594 -404.091257) (xy 136.309537 -404.083499)
			(xy 136.336786 -404.083012) (xy 137.200386 -404.083012) (xy 137.227641 -404.083434) (xy 137.281596 -404.09119)
			(xy 137.333899 -404.106545) (xy 137.383483 -404.129188) (xy 137.429341 -404.158657) (xy 137.470537 -404.194353)
			(xy 137.506234 -404.235548) (xy 137.535705 -404.281405) (xy 137.55835 -404.330988) (xy 137.573707 -404.38329)
			(xy 137.581465 -404.437245) (xy 137.581465 -404.491753) (xy 139.018975 -404.491753) (xy 139.018975 -404.437247)
			(xy 139.026733 -404.383297) (xy 139.042089 -404.331) (xy 139.064732 -404.281421) (xy 139.094201 -404.235569)
			(xy 139.129896 -404.194377) (xy 139.171089 -404.158686) (xy 139.216943 -404.12922) (xy 139.266524 -404.10658)
			(xy 139.318822 -404.091227) (xy 139.372773 -404.083474) (xy 139.400026 -404.083012) (xy 140.263626 -404.083012)
			(xy 140.290877 -404.08346) (xy 140.344825 -404.09122) (xy 140.39712 -404.106578) (xy 140.446696 -404.129222)
			(xy 140.492546 -404.15869) (xy 140.533735 -404.194383) (xy 140.569426 -404.235575) (xy 140.598891 -404.281427)
			(xy 140.621531 -404.331005) (xy 140.636886 -404.3833) (xy 140.644642 -404.437249) (xy 140.644642 -404.491748)
			(xy 142.082298 -404.491748) (xy 142.082298 -404.437252) (xy 142.090053 -404.38331) (xy 142.105406 -404.331021)
			(xy 142.128043 -404.281448) (xy 142.157505 -404.235602) (xy 142.193191 -404.194415) (xy 142.234375 -404.158725)
			(xy 142.280218 -404.12926) (xy 142.329789 -404.106618) (xy 142.382077 -404.091261) (xy 142.436018 -404.083501)
			(xy 142.463266 -404.083012) (xy 143.326866 -404.083012) (xy 143.354122 -404.083433) (xy 143.408079 -404.091186)
			(xy 143.460384 -404.10654) (xy 143.509971 -404.129182) (xy 143.555831 -404.15865) (xy 143.59703 -404.194346)
			(xy 143.632729 -404.235542) (xy 143.662202 -404.281399) (xy 143.684848 -404.330984) (xy 143.700207 -404.383287)
			(xy 143.707965 -404.437244) (xy 143.707965 -404.491752) (xy 145.145475 -404.491752) (xy 145.145475 -404.437248)
			(xy 145.153232 -404.3833) (xy 145.168588 -404.331004) (xy 145.191229 -404.281426) (xy 145.220696 -404.235575)
			(xy 145.256389 -404.194384) (xy 145.29758 -404.158693) (xy 145.343431 -404.129226) (xy 145.39301 -404.106585)
			(xy 145.445306 -404.091231) (xy 145.499254 -404.083475) (xy 145.526506 -404.083012) (xy 146.390106 -404.083012)
			(xy 146.417358 -404.083458) (xy 146.471308 -404.091216) (xy 146.523605 -404.106572) (xy 146.573184 -404.129215)
			(xy 146.619036 -404.158683) (xy 146.660228 -404.194376) (xy 146.695921 -404.235569) (xy 146.725388 -404.281421)
			(xy 146.74803 -404.331001) (xy 146.763385 -404.383298) (xy 146.771142 -404.437248) (xy 146.771142 -404.491752)
			(xy 146.771142 -404.491754) (xy 148.208675 -404.491754) (xy 148.208675 -404.437246) (xy 148.216433 -404.383294)
			(xy 148.231791 -404.330996) (xy 148.254435 -404.281415) (xy 148.283906 -404.235562) (xy 148.319603 -404.19437)
			(xy 148.360799 -404.158679) (xy 148.406655 -404.129213) (xy 148.456239 -404.106575) (xy 148.508539 -404.091223)
			(xy 148.562492 -404.083472) (xy 148.589746 -404.083012) (xy 149.453346 -404.083012) (xy 149.480597 -404.083461)
			(xy 149.534542 -404.091223) (xy 149.586834 -404.106583) (xy 149.636408 -404.129228) (xy 149.682255 -404.158697)
			(xy 149.723442 -404.194391) (xy 149.75913 -404.235582) (xy 149.788594 -404.281432) (xy 149.811233 -404.331009)
			(xy 149.826587 -404.383303) (xy 149.834342 -404.437249) (xy 149.834342 -404.491749) (xy 151.271998 -404.491749)
			(xy 151.271998 -404.437251) (xy 151.279754 -404.383307) (xy 151.295108 -404.331016) (xy 151.317746 -404.281443)
			(xy 151.34721 -404.235596) (xy 151.382898 -404.194408) (xy 151.424084 -404.158718) (xy 151.46993 -404.129253)
			(xy 151.519503 -404.106612) (xy 151.571794 -404.091257) (xy 151.625737 -404.083499) (xy 151.652986 -404.083012)
			(xy 152.516586 -404.083012) (xy 152.543841 -404.083434) (xy 152.597796 -404.09119) (xy 152.650099 -404.106545)
			(xy 152.699683 -404.129188) (xy 152.745541 -404.158657) (xy 152.786737 -404.194353) (xy 152.822434 -404.235548)
			(xy 152.851905 -404.281405) (xy 152.87455 -404.330988) (xy 152.889907 -404.38329) (xy 152.897665 -404.437245)
			(xy 152.897665 -404.491753) (xy 154.335175 -404.491753) (xy 154.335175 -404.437247) (xy 154.342933 -404.383297)
			(xy 154.358289 -404.331) (xy 154.380932 -404.281421) (xy 154.410401 -404.235569) (xy 154.446096 -404.194377)
			(xy 154.487289 -404.158686) (xy 154.533143 -404.12922) (xy 154.582724 -404.10658) (xy 154.635022 -404.091227)
			(xy 154.688973 -404.083474) (xy 154.716226 -404.083012) (xy 155.579826 -404.083012) (xy 155.607077 -404.08346)
			(xy 155.661025 -404.09122) (xy 155.71332 -404.106578) (xy 155.762896 -404.129222) (xy 155.808746 -404.15869)
			(xy 155.849935 -404.194383) (xy 155.885626 -404.235575) (xy 155.915091 -404.281427) (xy 155.937731 -404.331005)
			(xy 155.953086 -404.3833) (xy 155.960842 -404.437249) (xy 155.960842 -404.491748) (xy 157.398498 -404.491748)
			(xy 157.398498 -404.437252) (xy 157.406253 -404.38331) (xy 157.421606 -404.331021) (xy 157.444243 -404.281448)
			(xy 157.473705 -404.235602) (xy 157.509391 -404.194415) (xy 157.550575 -404.158725) (xy 157.596418 -404.12926)
			(xy 157.645989 -404.106618) (xy 157.698277 -404.091261) (xy 157.752218 -404.083501) (xy 157.779466 -404.083012)
			(xy 158.643066 -404.083012) (xy 158.670322 -404.083433) (xy 158.724279 -404.091186) (xy 158.776584 -404.10654)
			(xy 158.826171 -404.129182) (xy 158.872031 -404.15865) (xy 158.91323 -404.194346) (xy 158.948929 -404.235542)
			(xy 158.978402 -404.281399) (xy 159.001048 -404.330984) (xy 159.016407 -404.383287) (xy 159.024165 -404.437244)
			(xy 159.024165 -404.491752) (xy 160.461675 -404.491752) (xy 160.461675 -404.437248) (xy 160.469432 -404.3833)
			(xy 160.484788 -404.331004) (xy 160.507429 -404.281426) (xy 160.536896 -404.235575) (xy 160.572589 -404.194384)
			(xy 160.61378 -404.158693) (xy 160.659631 -404.129226) (xy 160.70921 -404.106585) (xy 160.761506 -404.091231)
			(xy 160.815454 -404.083475) (xy 160.842706 -404.083012) (xy 161.706306 -404.083012) (xy 161.733558 -404.083458)
			(xy 161.787508 -404.091216) (xy 161.839805 -404.106572) (xy 161.889384 -404.129215) (xy 161.935236 -404.158683)
			(xy 161.976428 -404.194376) (xy 162.012121 -404.235569) (xy 162.041588 -404.281421) (xy 162.06423 -404.331001)
			(xy 162.079585 -404.383298) (xy 162.087342 -404.437248) (xy 162.087342 -404.491752) (xy 162.079585 -404.545702)
			(xy 162.06423 -404.597999) (xy 162.041588 -404.647579) (xy 162.012121 -404.693431) (xy 161.976428 -404.734624)
			(xy 161.935236 -404.770317) (xy 161.904774 -404.789894) (xy 166.998662 -404.789894) (xy 167.002634 -404.611651)
			(xy 167.014542 -404.433762) (xy 167.034363 -404.25658) (xy 167.062057 -404.080456) (xy 167.097569 -403.905741)
			(xy 167.140829 -403.732782) (xy 167.191751 -403.561921) (xy 167.250234 -403.393499) (xy 167.316161 -403.227849)
			(xy 167.389402 -403.0653) (xy 167.469812 -402.906175) (xy 167.55723 -402.75079) (xy 167.651483 -402.599454)
			(xy 167.752384 -402.452466) (xy 167.859733 -402.310119) (xy 167.973316 -402.172696) (xy 168.092909 -402.040469)
			(xy 168.218273 -401.9137) (xy 168.34916 -401.792642) (xy 168.485309 -401.677535) (xy 168.626451 -401.568607)
			(xy 168.772306 -401.466075) (xy 168.922583 -401.370141) (xy 169.076984 -401.280998) (xy 169.235203 -401.198821)
			(xy 169.396926 -401.123773) (xy 169.561831 -401.056005) (xy 169.729592 -400.995649) (xy 169.899875 -400.942827)
			(xy 170.072342 -400.897643) (xy 170.24665 -400.860186) (xy 170.422454 -400.830532) (xy 170.599404 -400.808739)
			(xy 170.77715 -400.794849) (xy 170.955337 -400.788892) (xy 171.133614 -400.790878) (xy 171.311625 -400.800804)
			(xy 171.489017 -400.81865) (xy 171.665437 -400.84438) (xy 171.840537 -400.877944) (xy 172.013968 -400.919274)
			(xy 172.185385 -400.96829) (xy 172.354448 -401.024892) (xy 172.520823 -401.08897) (xy 172.684177 -401.160396)
			(xy 172.844188 -401.239028) (xy 173.000537 -401.324709) (xy 173.152914 -401.417271) (xy 173.301017 -401.516528)
			(xy 173.444551 -401.622285) (xy 173.583231 -401.73433) (xy 173.716782 -401.852442) (xy 173.844939 -401.976386)
			(xy 173.967448 -402.105916) (xy 174.084065 -402.240775) (xy 174.194558 -402.380695) (xy 174.298709 -402.525398)
			(xy 174.396311 -402.674597) (xy 174.487169 -402.827996) (xy 174.571103 -402.98529) (xy 174.647948 -403.146166)
			(xy 174.680622 -403.223222) (xy 183.966612 -403.223222) (xy 183.966612 -403.222714) (xy 183.967041 -403.181385)
			(xy 183.974705 -403.099084) (xy 183.989967 -403.017847) (xy 184.012697 -402.938376) (xy 184.042698 -402.861355)
			(xy 184.079712 -402.787448) (xy 184.12342 -402.717292) (xy 184.173445 -402.651491) (xy 184.201054 -402.620734)
			(xy 184.207126 -402.613482) (xy 184.214027 -402.59589) (xy 184.214516 -402.586444) (xy 184.214516 -402.555964)
			(xy 184.214137 -402.546498) (xy 184.207208 -402.528878) (xy 184.201054 -402.521674) (xy 184.173435 -402.490923)
			(xy 184.123404 -402.425124) (xy 184.07969 -402.354969) (xy 184.042671 -402.281062) (xy 184.012666 -402.20404)
			(xy 183.989932 -402.124568) (xy 183.974667 -402.043329) (xy 183.967002 -401.961026) (xy 183.967002 -401.878366)
			(xy 183.974668 -401.796062) (xy 183.989934 -401.714824) (xy 184.012668 -401.635352) (xy 184.042675 -401.55833)
			(xy 184.079695 -401.484423) (xy 184.123409 -401.414268) (xy 184.173441 -401.34847) (xy 184.201054 -401.317714)
			(xy 184.207134 -401.310468) (xy 184.214031 -401.292871) (xy 184.214516 -401.283424) (xy 184.214516 -401.252944)
			(xy 184.214097 -401.243482) (xy 184.207196 -401.225862) (xy 184.201054 -401.218654) (xy 184.173435 -401.187907)
			(xy 184.12342 -401.1221) (xy 184.079722 -401.05194) (xy 184.042717 -400.97803) (xy 184.012723 -400.901008)
			(xy 183.989999 -400.821537) (xy 183.974741 -400.740302) (xy 183.967081 -400.658002) (xy 183.966612 -400.616674)
			(xy 183.967088 -400.575568) (xy 183.974674 -400.493705) (xy 183.98978 -400.412892) (xy 184.012276 -400.333817)
			(xy 184.041971 -400.257154) (xy 184.078611 -400.183558) (xy 184.121884 -400.113655) (xy 184.171421 -400.048042)
			(xy 184.226799 -399.987279) (xy 184.287547 -399.931883) (xy 184.353145 -399.882327) (xy 184.423036 -399.839034)
			(xy 184.496622 -399.802373) (xy 184.573276 -399.772657) (xy 184.652345 -399.750138) (xy 184.733154 -399.735009)
			(xy 184.815014 -399.727399) (xy 184.85612 -399.726912) (xy 184.900625 -399.727439) (xy 184.989189 -399.736331)
			(xy 185.076422 -399.754024) (xy 185.161452 -399.780341) (xy 185.243428 -399.815019) (xy 185.321531 -399.857711)
			(xy 185.394979 -399.90799) (xy 185.463038 -399.965354) (xy 185.494422 -399.996914) (xy 185.501871 -400.003965)
			(xy 185.52075 -400.011949) (xy 185.530998 -400.012408) (xy 185.603642 -400.012408) (xy 185.613891 -400.011949)
			(xy 185.632766 -400.003963) (xy 185.640218 -399.996914) (xy 185.671594 -399.965346) (xy 185.739655 -399.907985)
			(xy 185.813105 -399.857708) (xy 185.891209 -399.815019) (xy 185.973186 -399.780344) (xy 186.058217 -399.75403)
			(xy 186.145451 -399.736341) (xy 186.234015 -399.727453) (xy 186.27852 -399.726912) (xy 186.32201 -399.727445)
			(xy 186.408572 -399.735955) (xy 186.493892 -399.752871) (xy 186.577152 -399.778033) (xy 186.65756 -399.811201)
			(xy 186.734348 -399.852056) (xy 186.806782 -399.900211) (xy 186.874171 -399.955204) (xy 186.905392 -399.985484)
			(xy 186.905646 -399.985738) (xy 186.913054 -399.992282) (xy 186.931335 -399.999743) (xy 186.941206 -400.000216)
			(xy 187.012834 -400.000216) (xy 187.022717 -399.999799) (xy 187.041016 -399.992329) (xy 187.048394 -399.985738)
			(xy 187.048648 -399.985484) (xy 187.079882 -399.955217) (xy 187.14727 -399.900227) (xy 187.219703 -399.852074)
			(xy 187.296489 -399.811218) (xy 187.376895 -399.77805) (xy 187.460154 -399.752886) (xy 187.54547 -399.735966)
			(xy 187.632031 -399.727452) (xy 187.67552 -399.726912) (xy 187.716616 -399.727347) (xy 187.798457 -399.734931)
			(xy 187.87925 -399.750033) (xy 187.958305 -399.772524) (xy 188.034948 -399.802212) (xy 188.108525 -399.838843)
			(xy 188.178409 -399.882106) (xy 188.244005 -399.931632) (xy 188.304751 -399.986997) (xy 188.360132 -400.047731)
			(xy 188.409673 -400.113314) (xy 188.452953 -400.183188) (xy 188.489602 -400.256756) (xy 188.519308 -400.333392)
			(xy 188.541818 -400.412442) (xy 188.556939 -400.493231) (xy 188.564543 -400.57507) (xy 188.565028 -400.616166)
			(xy 188.565028 -400.616674) (xy 188.564581 -400.658002) (xy 188.556919 -400.740303) (xy 188.541658 -400.821539)
			(xy 188.518931 -400.901009) (xy 188.488932 -400.97803) (xy 188.451921 -401.051937) (xy 188.408216 -401.122094)
			(xy 188.358194 -401.187896) (xy 188.330586 -401.218654) (xy 188.324524 -401.225913) (xy 188.317616 -401.2435)
			(xy 188.317124 -401.252944) (xy 188.317124 -401.283424) (xy 188.3175 -401.292891) (xy 188.32443 -401.310511)
			(xy 188.330586 -401.317714) (xy 188.358194 -401.348474) (xy 188.408229 -401.414271) (xy 188.451946 -401.484425)
			(xy 188.488968 -401.558331) (xy 188.518976 -401.635351) (xy 188.541712 -401.714823) (xy 188.556979 -401.796062)
			(xy 188.564645 -401.878365) (xy 188.564646 -401.961026) (xy 188.55698 -402.04333) (xy 188.541714 -402.124568)
			(xy 188.518979 -402.20404) (xy 188.488972 -402.281061) (xy 188.45195 -402.354968) (xy 188.408234 -402.425122)
			(xy 188.3582 -402.490919) (xy 188.330586 -402.521674) (xy 188.324516 -402.528927) (xy 188.317612 -402.546518)
			(xy 188.317124 -402.555964) (xy 188.317124 -402.586444) (xy 188.31749 -402.595912) (xy 188.324426 -402.613532)
			(xy 188.330586 -402.620734) (xy 188.358206 -402.65148) (xy 188.40822 -402.717288) (xy 188.451917 -402.787448)
			(xy 188.488922 -402.861358) (xy 188.518915 -402.93838) (xy 188.541639 -403.017851) (xy 188.556897 -403.099086)
			(xy 188.564559 -403.181386) (xy 188.565028 -403.222714) (xy 188.56457 -403.265938) (xy 188.556182 -403.351979)
			(xy 188.539486 -403.436801) (xy 188.514639 -403.519602) (xy 188.481877 -403.599602) (xy 188.441508 -403.676046)
			(xy 188.393913 -403.748214) (xy 188.339541 -403.815423) (xy 188.278905 -403.87704) (xy 188.212577 -403.932484)
			(xy 188.17717 -403.957282) (xy 188.169401 -403.962991) (xy 188.158572 -403.978928) (xy 188.15443 -403.997746)
			(xy 188.15558 -404.00732) (xy 188.172598 -404.112984) (xy 188.191902 -404.134828) (xy 188.20638 -404.138892)
			(xy 188.235359 -404.147534) (xy 188.292177 -404.168255) (xy 188.319918 -404.180294) (xy 188.32986 -404.1841)
			(xy 188.351124 -404.1841) (xy 188.361066 -404.180294) (xy 188.403727 -404.162032) (xy 188.492015 -404.133439)
			(xy 188.582798 -404.114182) (xy 188.675091 -404.104469) (xy 188.721492 -404.10384) (xy 188.767894 -404.104473)
			(xy 188.860191 -404.114162) (xy 188.950976 -404.133414) (xy 189.039262 -404.162019) (xy 189.081918 -404.180294)
			(xy 189.09186 -404.1841) (xy 189.113124 -404.1841) (xy 189.123066 -404.180294) (xy 189.165727 -404.162032)
			(xy 189.254015 -404.133439) (xy 189.344798 -404.114182) (xy 189.437091 -404.104469) (xy 189.483492 -404.10384)
			(xy 189.524604 -404.10426) (xy 189.606477 -404.111848) (xy 189.6873 -404.126959) (xy 189.766384 -404.149465)
			(xy 189.843053 -404.179173) (xy 189.916654 -404.21583) (xy 189.986557 -404.259123) (xy 190.052166 -404.308683)
			(xy 190.112922 -404.364086) (xy 190.168305 -404.42486) (xy 190.217843 -404.490486) (xy 190.261113 -404.560403)
			(xy 190.297746 -404.634016) (xy 190.327429 -404.710695) (xy 190.349908 -404.789786) (xy 190.364993 -404.870614)
			(xy 190.372553 -404.95249) (xy 190.373 -404.993602) (xy 190.372419 -405.039998) (xy 190.362773 -405.132286)
			(xy 190.343577 -405.22307) (xy 190.315038 -405.311363) (xy 190.2968 -405.354028) (xy 190.292994 -405.36397)
			(xy 190.292995 -405.385234) (xy 190.2968 -405.395176) (xy 190.315045 -405.437838) (xy 190.343589 -405.52613)
			(xy 190.362782 -405.616916) (xy 190.372415 -405.709206) (xy 190.373 -405.755602) (xy 190.372419 -405.801998)
			(xy 190.362773 -405.894286) (xy 190.343577 -405.98507) (xy 190.315038 -406.073363) (xy 190.2968 -406.116028)
			(xy 190.292994 -406.12597) (xy 190.292995 -406.147234) (xy 190.2968 -406.157176) (xy 190.315045 -406.199838)
			(xy 190.343589 -406.28813) (xy 190.362782 -406.378916) (xy 190.372415 -406.471206) (xy 190.373 -406.517602)
			(xy 190.37258 -406.55737) (xy 190.365551 -406.636594) (xy 190.351469 -406.714872) (xy 190.330446 -406.791578)
			(xy 190.302651 -406.866098) (xy 190.285878 -406.902158) (xy 190.281544 -406.912659) (xy 190.281545 -406.935345)
			(xy 190.285878 -406.945846) (xy 190.302637 -406.981911) (xy 190.330411 -407.056437) (xy 190.351429 -407.133142)
			(xy 190.365522 -407.211416) (xy 190.372579 -407.290635) (xy 190.373 -407.330402) (xy 190.372419 -407.376798)
			(xy 190.362773 -407.469086) (xy 190.343577 -407.55987) (xy 190.315038 -407.648163) (xy 190.2968 -407.690828)
			(xy 190.292994 -407.70077) (xy 190.292995 -407.722034) (xy 190.2968 -407.731976) (xy 190.315022 -407.774579)
			(xy 190.34354 -407.862746) (xy 190.362733 -407.953402) (xy 190.372392 -408.045562) (xy 190.372573 -408.059382)
			(xy 196.354192 -408.059382) (xy 196.354769 -408.012986) (xy 196.364415 -407.920698) (xy 196.383613 -407.829914)
			(xy 196.412153 -407.741621) (xy 196.430392 -407.698956) (xy 196.434208 -407.689017) (xy 196.434201 -407.66775)
			(xy 196.430392 -407.657808) (xy 196.412141 -407.615148) (xy 196.383599 -407.526855) (xy 196.364407 -407.436069)
			(xy 196.354776 -407.343778) (xy 196.354192 -407.297382) (xy 196.354769 -407.250986) (xy 196.364415 -407.158698)
			(xy 196.383613 -407.067914) (xy 196.412153 -406.979621) (xy 196.430392 -406.936956) (xy 196.434208 -406.927017)
			(xy 196.434201 -406.90575) (xy 196.430392 -406.895808) (xy 196.412141 -406.853148) (xy 196.383599 -406.764855)
			(xy 196.364407 -406.674069) (xy 196.354776 -406.581778) (xy 196.354192 -406.535382) (xy 196.354769 -406.488986)
			(xy 196.364415 -406.396698) (xy 196.383613 -406.305914) (xy 196.412153 -406.217621) (xy 196.430392 -406.174956)
			(xy 196.434208 -406.165017) (xy 196.434201 -406.14375) (xy 196.430392 -406.133808) (xy 196.412141 -406.091148)
			(xy 196.383599 -406.002855) (xy 196.364407 -405.912069) (xy 196.354776 -405.819778) (xy 196.354192 -405.773382)
			(xy 196.354769 -405.726986) (xy 196.364415 -405.634698) (xy 196.383613 -405.543914) (xy 196.412153 -405.455621)
			(xy 196.430392 -405.412956) (xy 196.434208 -405.403017) (xy 196.434201 -405.38175) (xy 196.430392 -405.371808)
			(xy 196.412164 -405.329208) (xy 196.383648 -405.241039) (xy 196.364457 -405.150383) (xy 196.354799 -405.058222)
			(xy 196.354192 -405.01189) (xy 196.354192 -405.011382) (xy 196.354695 -404.970276) (xy 196.362281 -404.888416)
			(xy 196.377385 -404.807604) (xy 196.39988 -404.72853) (xy 196.429573 -404.651868) (xy 196.466212 -404.578272)
			(xy 196.509483 -404.50837) (xy 196.559018 -404.442758) (xy 196.614395 -404.381994) (xy 196.67514 -404.326599)
			(xy 196.740737 -404.277043) (xy 196.810626 -404.233749) (xy 196.88421 -404.197087) (xy 196.960862 -404.16737)
			(xy 197.039929 -404.14485) (xy 197.120736 -404.12972) (xy 197.202594 -404.122108) (xy 197.2437 -404.12162)
			(xy 197.290102 -404.122252) (xy 197.382399 -404.131941) (xy 197.473184 -404.151193) (xy 197.56147 -404.179799)
			(xy 197.604126 -404.198074) (xy 197.614068 -404.20188) (xy 197.635332 -404.20188) (xy 197.645274 -404.198074)
			(xy 197.673976 -404.185882) (xy 197.682795 -404.181969) (xy 197.696833 -404.168752) (xy 197.704997 -404.151285)
			(xy 197.70598 -404.141686) (xy 197.711314 -404.049992) (xy 197.711428 -404.040421) (xy 197.705477 -404.022248)
			(xy 197.693313 -404.007492) (xy 197.685152 -404.002494) (xy 197.647554 -403.981253) (xy 197.576288 -403.932477)
			(xy 197.510083 -403.877025) (xy 197.449561 -403.81542) (xy 197.395292 -403.748241) (xy 197.347788 -403.67612)
			(xy 197.307493 -403.599737) (xy 197.274789 -403.519809) (xy 197.249982 -403.437088) (xy 197.233306 -403.352354)
			(xy 197.224918 -403.266402) (xy 197.224396 -403.223222) (xy 197.224864 -403.181887) (xy 197.232535 -403.099572)
			(xy 197.247812 -403.018325) (xy 197.270564 -402.938847) (xy 197.300593 -402.861823) (xy 197.337642 -402.787918)
			(xy 197.38139 -402.717771) (xy 197.431459 -402.651987) (xy 197.459092 -402.621242) (xy 197.465153 -402.613982)
			(xy 197.472063 -402.596396) (xy 197.472554 -402.586952) (xy 197.472554 -402.556472) (xy 197.472185 -402.547004)
			(xy 197.465251 -402.529384) (xy 197.459092 -402.522182) (xy 197.431443 -402.491454) (xy 197.3814 -402.425653)
			(xy 197.337673 -402.355495) (xy 197.300638 -402.281587) (xy 197.270614 -402.204563) (xy 197.24786 -402.125088)
			(xy 197.232571 -402.043846) (xy 197.22488 -401.961536) (xy 197.224396 -401.920202) (xy 197.224852 -401.878866)
			(xy 197.232524 -401.796552) (xy 197.247803 -401.715304) (xy 197.270556 -401.635826) (xy 197.300588 -401.558802)
			(xy 197.337638 -401.484897) (xy 197.381388 -401.414751) (xy 197.431459 -401.348967) (xy 197.459092 -401.318222)
			(xy 197.465161 -401.310968) (xy 197.472066 -401.293378) (xy 197.472554 -401.283932) (xy 197.472554 -401.253452)
			(xy 197.472146 -401.243989) (xy 197.465239 -401.226367) (xy 197.459092 -401.219162) (xy 197.431482 -401.1884)
			(xy 197.381436 -401.122604) (xy 197.337705 -401.052453) (xy 197.300666 -400.978549) (xy 197.270637 -400.90153)
			(xy 197.247877 -400.82206) (xy 197.232582 -400.740821) (xy 197.224883 -400.658515) (xy 197.224396 -400.617182)
			(xy 197.224896 -400.576069) (xy 197.232484 -400.494193) (xy 197.247594 -400.413367) (xy 197.270097 -400.334279)
			(xy 197.299801 -400.257605) (xy 197.336453 -400.183999) (xy 197.379739 -400.114089) (xy 197.429291 -400.04847)
			(xy 197.484686 -399.987703) (xy 197.545451 -399.932307) (xy 197.611069 -399.882753) (xy 197.680978 -399.839464)
			(xy 197.754583 -399.802811) (xy 197.831256 -399.773105) (xy 197.910343 -399.7506) (xy 197.991169 -399.735487)
			(xy 198.073045 -399.727897) (xy 198.114158 -399.72742) (xy 198.158662 -399.727949) (xy 198.247226 -399.736844)
			(xy 198.334458 -399.754538) (xy 198.419487 -399.780856) (xy 198.501463 -399.815534) (xy 198.579565 -399.858225)
			(xy 198.653014 -399.908502) (xy 198.721075 -399.965864) (xy 198.75246 -399.997422) (xy 198.759931 -400.004447)
			(xy 198.778793 -400.012446) (xy 198.789036 -400.012916) (xy 198.86168 -400.012916) (xy 198.871931 -400.012475)
			(xy 198.890805 -400.004477) (xy 198.898256 -399.997422) (xy 198.929663 -399.965886) (xy 198.997719 -399.908523)
			(xy 199.071164 -399.858243) (xy 199.149263 -399.81555) (xy 199.231236 -399.780871) (xy 199.316263 -399.754552)
			(xy 199.403493 -399.736858) (xy 199.492055 -399.727964) (xy 199.536558 -399.72742) (xy 199.580049 -399.727926)
			(xy 199.666612 -399.736439) (xy 199.751932 -399.75336) (xy 199.835193 -399.778526) (xy 199.915601 -399.811696)
			(xy 199.992388 -399.852556) (xy 200.064821 -399.900714) (xy 200.132209 -399.95571) (xy 200.16343 -399.985992)
			(xy 200.163684 -399.986246) (xy 200.171078 -399.992808) (xy 200.189369 -400.000258) (xy 200.199244 -400.000724)
			(xy 200.270872 -400.000724) (xy 200.280751 -400.000273) (xy 200.29905 -399.992827) (xy 200.306432 -399.986246)
			(xy 200.306686 -399.985992) (xy 200.337904 -399.955708) (xy 200.405295 -399.900719) (xy 200.47773 -399.852567)
			(xy 200.554518 -399.811713) (xy 200.634927 -399.778547) (xy 200.718187 -399.753386) (xy 200.803506 -399.736469)
			(xy 200.890068 -399.727958) (xy 200.933558 -399.72742) (xy 200.974672 -399.727938) (xy 201.056549 -399.735522)
			(xy 201.137376 -399.750627) (xy 201.216466 -399.773127) (xy 201.293142 -399.802827) (xy 201.36675 -399.839476)
			(xy 201.436663 -399.882761) (xy 201.502283 -399.932312) (xy 201.563052 -399.987706) (xy 201.61845 -400.04847)
			(xy 201.668005 -400.114088) (xy 201.711294 -400.183998) (xy 201.747948 -400.257603) (xy 201.777654 -400.334277)
			(xy 201.800159 -400.413365) (xy 201.81527 -400.494192) (xy 201.822859 -400.576068) (xy 201.82332 -400.617182)
			(xy 201.82285 -400.658517) (xy 201.815179 -400.740831) (xy 201.799902 -400.822078) (xy 201.777151 -400.901557)
			(xy 201.747121 -400.978581) (xy 201.710073 -401.052485) (xy 201.666325 -401.122632) (xy 201.616256 -401.188416)
			(xy 201.588624 -401.219162) (xy 201.582551 -401.226413) (xy 201.575651 -401.244006) (xy 201.575162 -401.253452)
			(xy 201.575162 -401.283932) (xy 201.575549 -401.293397) (xy 201.582473 -401.311017) (xy 201.588624 -401.318222)
			(xy 201.61626 -401.348962) (xy 201.666306 -401.41476) (xy 201.710036 -401.484914) (xy 201.747073 -401.558821)
			(xy 201.777099 -401.635843) (xy 201.799855 -401.715317) (xy 201.815145 -401.796559) (xy 201.822837 -401.878868)
			(xy 201.82332 -401.920202) (xy 201.822863 -401.961538) (xy 201.81519 -402.043852) (xy 201.799911 -402.125099)
			(xy 201.777158 -402.204578) (xy 201.747126 -402.281602) (xy 201.710076 -402.355506) (xy 201.666327 -402.425653)
			(xy 201.616257 -402.491437) (xy 201.588624 -402.522182) (xy 201.582543 -402.529427) (xy 201.575647 -402.547025)
			(xy 201.575162 -402.556472) (xy 201.575162 -402.586952) (xy 201.575589 -402.596413) (xy 201.582485 -402.614033)
			(xy 201.588624 -402.621242) (xy 201.616222 -402.652015) (xy 201.66627 -402.717808) (xy 201.710004 -402.787957)
			(xy 201.747046 -402.861859) (xy 201.777077 -402.938876) (xy 201.799838 -403.018346) (xy 201.815134 -403.099584)
			(xy 201.822833 -403.18189) (xy 201.82332 -403.223222) (xy 201.822801 -403.266183) (xy 201.814523 -403.351705)
			(xy 201.798036 -403.43603) (xy 201.773494 -403.518372) (xy 201.741125 -403.597963) (xy 201.701232 -403.674062)
			(xy 201.654186 -403.745959) (xy 201.600426 -403.812984) (xy 201.540453 -403.874513) (xy 201.474826 -403.929971)
			(xy 201.404156 -403.978842) (xy 201.366882 -404.000208) (xy 201.35873 -404.005265) (xy 201.346612 -404.020117)
			(xy 201.34076 -404.03837) (xy 201.340974 -404.04796) (xy 201.348086 -404.154386) (xy 201.365358 -404.178008)
			(xy 201.379328 -404.183342) (xy 201.417266 -404.198729) (xy 201.490382 -404.235572) (xy 201.559803 -404.27898)
			(xy 201.62494 -404.328584) (xy 201.685242 -404.383965) (xy 201.740199 -404.444654) (xy 201.789346 -404.510137)
			(xy 201.832266 -404.57986) (xy 201.868597 -404.653232) (xy 201.89803 -404.729633) (xy 201.920317 -404.808416)
			(xy 201.935269 -404.888913) (xy 201.942758 -404.970445) (xy 201.943208 -405.011382) (xy 201.942619 -405.057777)
			(xy 201.932976 -405.150066) (xy 201.913781 -405.240849) (xy 201.885245 -405.329143) (xy 201.867008 -405.371808)
			(xy 201.863213 -405.381753) (xy 201.863206 -405.403014) (xy 201.867008 -405.412956) (xy 201.885247 -405.455621)
			(xy 201.913792 -405.543912) (xy 201.932987 -405.634696) (xy 201.942622 -405.726986) (xy 201.943208 -405.773382)
			(xy 201.942619 -405.819777) (xy 201.932976 -405.912066) (xy 201.913781 -406.002849) (xy 201.885245 -406.091143)
			(xy 201.867008 -406.133808) (xy 201.863213 -406.143753) (xy 201.863206 -406.165014) (xy 201.867008 -406.174956)
			(xy 201.885247 -406.217621) (xy 201.913792 -406.305912) (xy 201.932987 -406.396696) (xy 201.942622 -406.488986)
			(xy 201.943208 -406.535382) (xy 201.942619 -406.581777) (xy 201.932976 -406.674066) (xy 201.913781 -406.764849)
			(xy 201.885245 -406.853143) (xy 201.867008 -406.895808) (xy 201.863213 -406.905753) (xy 201.863206 -406.927014)
			(xy 201.867008 -406.936956) (xy 201.885247 -406.979621) (xy 201.913792 -407.067912) (xy 201.932987 -407.158696)
			(xy 201.942622 -407.250986) (xy 201.943208 -407.297382) (xy 201.942619 -407.343777) (xy 201.932976 -407.436066)
			(xy 201.913781 -407.526849) (xy 201.885245 -407.615143) (xy 201.867008 -407.657808) (xy 201.863213 -407.667753)
			(xy 201.863206 -407.689014) (xy 201.867008 -407.698956) (xy 201.885224 -407.741561) (xy 201.913743 -407.829728)
			(xy 201.932938 -407.920383) (xy 201.942599 -408.012542) (xy 201.943208 -408.058874) (xy 201.943208 -408.059382)
			(xy 201.943201 -408.05989) (xy 206.260192 -408.05989) (xy 206.260192 -408.059382) (xy 206.260717 -408.017997)
			(xy 206.268406 -407.935585) (xy 206.283716 -407.854244) (xy 206.306513 -407.774675) (xy 206.336602 -407.697568)
			(xy 206.373723 -407.623589) (xy 206.417553 -407.553377) (xy 206.467715 -407.487539) (xy 206.523774 -407.426645)
			(xy 206.585247 -407.37122) (xy 206.651602 -407.321743) (xy 206.722265 -407.278644) (xy 206.796625 -407.242293)
			(xy 206.87404 -407.213005) (xy 206.953841 -407.191034) (xy 206.994506 -407.183336) (xy 207.004634 -407.181051)
			(xy 207.021956 -407.169641) (xy 207.033359 -407.152314) (xy 207.035654 -407.142188) (xy 207.043393 -407.101149)
			(xy 207.065607 -407.020638) (xy 207.095268 -406.942562) (xy 207.132115 -406.86761) (xy 207.175825 -406.796441)
			(xy 207.226012 -406.729682) (xy 207.282235 -406.66792) (xy 207.343998 -406.611699) (xy 207.410759 -406.561513)
			(xy 207.481929 -406.517805) (xy 207.556881 -406.48096) (xy 207.634957 -406.4513) (xy 207.715469 -406.429089)
			(xy 207.756506 -406.421336) (xy 207.766634 -406.419051) (xy 207.783956 -406.407641) (xy 207.795359 -406.390314)
			(xy 207.797654 -406.380188) (xy 207.804281 -406.344944) (xy 207.822478 -406.275571) (xy 207.846186 -406.207884)
			(xy 207.860392 -406.174956) (xy 207.864208 -406.165017) (xy 207.864201 -406.14375) (xy 207.860392 -406.133808)
			(xy 207.842141 -406.091148) (xy 207.813599 -406.002855) (xy 207.794407 -405.912069) (xy 207.784776 -405.819778)
			(xy 207.784192 -405.773382) (xy 207.784769 -405.726986) (xy 207.794415 -405.634698) (xy 207.813613 -405.543914)
			(xy 207.842153 -405.455621) (xy 207.860392 -405.412956) (xy 207.864208 -405.403017) (xy 207.864201 -405.38175)
			(xy 207.860392 -405.371808) (xy 207.842164 -405.329208) (xy 207.813648 -405.241039) (xy 207.794457 -405.150383)
			(xy 207.784799 -405.058222) (xy 207.784192 -405.01189) (xy 207.784192 -405.011382) (xy 207.784669 -404.970705)
			(xy 207.792097 -404.889692) (xy 207.80689 -404.809694) (xy 207.828923 -404.731381) (xy 207.858013 -404.655407)
			(xy 207.893918 -404.582405) (xy 207.936336 -404.512985) (xy 207.984914 -404.447728) (xy 208.039247 -404.387177)
			(xy 208.09888 -404.33184) (xy 208.163316 -404.282176) (xy 208.232016 -404.238603) (xy 208.304407 -404.201482)
			(xy 208.341976 -404.185882) (xy 208.350795 -404.181969) (xy 208.364833 -404.168752) (xy 208.372997 -404.151285)
			(xy 208.37398 -404.141686) (xy 208.379314 -404.049992) (xy 208.379428 -404.040421) (xy 208.373477 -404.022248)
			(xy 208.361313 -404.007492) (xy 208.353152 -404.002494) (xy 208.315554 -403.981253) (xy 208.244288 -403.932477)
			(xy 208.178083 -403.877025) (xy 208.117561 -403.81542) (xy 208.063292 -403.748241) (xy 208.015788 -403.67612)
			(xy 207.975493 -403.599737) (xy 207.942789 -403.519809) (xy 207.917982 -403.437088) (xy 207.901306 -403.352354)
			(xy 207.892918 -403.266402) (xy 207.892396 -403.223222) (xy 207.892864 -403.181887) (xy 207.900535 -403.099572)
			(xy 207.915812 -403.018325) (xy 207.938564 -402.938847) (xy 207.968593 -402.861823) (xy 208.005642 -402.787918)
			(xy 208.04939 -402.717771) (xy 208.099459 -402.651987) (xy 208.127092 -402.621242) (xy 208.133153 -402.613982)
			(xy 208.140063 -402.596396) (xy 208.140554 -402.586952) (xy 208.140554 -402.556472) (xy 208.140185 -402.547004)
			(xy 208.133251 -402.529384) (xy 208.127092 -402.522182) (xy 208.099443 -402.491454) (xy 208.0494 -402.425653)
			(xy 208.005673 -402.355495) (xy 207.968638 -402.281587) (xy 207.938614 -402.204563) (xy 207.91586 -402.125088)
			(xy 207.900571 -402.043846) (xy 207.89288 -401.961536) (xy 207.892396 -401.920202) (xy 207.892852 -401.878866)
			(xy 207.900524 -401.796552) (xy 207.915803 -401.715304) (xy 207.938556 -401.635826) (xy 207.968588 -401.558802)
			(xy 208.005638 -401.484897) (xy 208.049388 -401.414751) (xy 208.099459 -401.348967) (xy 208.127092 -401.318222)
			(xy 208.133161 -401.310968) (xy 208.140066 -401.293378) (xy 208.140554 -401.283932) (xy 208.140554 -401.253452)
			(xy 208.140146 -401.243989) (xy 208.133239 -401.226367) (xy 208.127092 -401.219162) (xy 208.099482 -401.1884)
			(xy 208.049436 -401.122604) (xy 208.005705 -401.052453) (xy 207.968666 -400.978549) (xy 207.938637 -400.90153)
			(xy 207.915877 -400.82206) (xy 207.900582 -400.740821) (xy 207.892883 -400.658515) (xy 207.892396 -400.617182)
			(xy 207.892896 -400.576069) (xy 207.900484 -400.494193) (xy 207.915594 -400.413367) (xy 207.938097 -400.334279)
			(xy 207.967801 -400.257605) (xy 208.004453 -400.183999) (xy 208.047739 -400.114089) (xy 208.097291 -400.04847)
			(xy 208.152686 -399.987703) (xy 208.213451 -399.932307) (xy 208.279069 -399.882753) (xy 208.348978 -399.839464)
			(xy 208.422583 -399.802811) (xy 208.499256 -399.773105) (xy 208.578343 -399.7506) (xy 208.659169 -399.735487)
			(xy 208.741045 -399.727897) (xy 208.782158 -399.72742) (xy 208.826662 -399.727949) (xy 208.915226 -399.736844)
			(xy 209.002458 -399.754538) (xy 209.087487 -399.780856) (xy 209.169463 -399.815534) (xy 209.247565 -399.858225)
			(xy 209.321014 -399.908502) (xy 209.389075 -399.965864) (xy 209.42046 -399.997422) (xy 209.427931 -400.004447)
			(xy 209.446793 -400.012446) (xy 209.457036 -400.012916) (xy 209.52968 -400.012916) (xy 209.539931 -400.012475)
			(xy 209.558805 -400.004477) (xy 209.566256 -399.997422) (xy 209.597663 -399.965886) (xy 209.665719 -399.908523)
			(xy 209.739164 -399.858243) (xy 209.817263 -399.81555) (xy 209.899236 -399.780871) (xy 209.984263 -399.754552)
			(xy 210.071493 -399.736858) (xy 210.160055 -399.727964) (xy 210.204558 -399.72742) (xy 210.248049 -399.727926)
			(xy 210.334612 -399.736439) (xy 210.419932 -399.75336) (xy 210.503193 -399.778526) (xy 210.583601 -399.811696)
			(xy 210.660388 -399.852556) (xy 210.732821 -399.900714) (xy 210.800209 -399.95571) (xy 210.83143 -399.985992)
			(xy 210.831684 -399.986246) (xy 210.839078 -399.992808) (xy 210.857369 -400.000258) (xy 210.867244 -400.000724)
			(xy 210.938872 -400.000724) (xy 210.948751 -400.000273) (xy 210.96705 -399.992827) (xy 210.974432 -399.986246)
			(xy 210.974686 -399.985992) (xy 211.005904 -399.955708) (xy 211.073295 -399.900719) (xy 211.14573 -399.852567)
			(xy 211.222518 -399.811713) (xy 211.302927 -399.778547) (xy 211.386187 -399.753386) (xy 211.471506 -399.736469)
			(xy 211.558068 -399.727958) (xy 211.601558 -399.72742) (xy 211.642672 -399.727938) (xy 211.724549 -399.735522)
			(xy 211.805376 -399.750627) (xy 211.884466 -399.773127) (xy 211.961142 -399.802827) (xy 212.03475 -399.839476)
			(xy 212.104663 -399.882761) (xy 212.170283 -399.932312) (xy 212.231052 -399.987706) (xy 212.28645 -400.04847)
			(xy 212.336005 -400.114088) (xy 212.379294 -400.183998) (xy 212.415948 -400.257603) (xy 212.445654 -400.334277)
			(xy 212.468159 -400.413365) (xy 212.48327 -400.494192) (xy 212.490859 -400.576068) (xy 212.49132 -400.617182)
			(xy 212.49085 -400.658517) (xy 212.483179 -400.740831) (xy 212.467902 -400.822078) (xy 212.445151 -400.901557)
			(xy 212.415121 -400.978581) (xy 212.378073 -401.052485) (xy 212.334325 -401.122632) (xy 212.284256 -401.188416)
			(xy 212.256624 -401.219162) (xy 212.250551 -401.226413) (xy 212.243651 -401.244006) (xy 212.243162 -401.253452)
			(xy 212.243162 -401.283932) (xy 212.243549 -401.293397) (xy 212.250473 -401.311017) (xy 212.256624 -401.318222)
			(xy 212.28426 -401.348962) (xy 212.334306 -401.41476) (xy 212.378036 -401.484914) (xy 212.415073 -401.558821)
			(xy 212.445099 -401.635843) (xy 212.467855 -401.715317) (xy 212.483145 -401.796559) (xy 212.490837 -401.878868)
			(xy 212.49132 -401.920202) (xy 212.490863 -401.961538) (xy 212.48319 -402.043852) (xy 212.467911 -402.125099)
			(xy 212.445158 -402.204578) (xy 212.415126 -402.281602) (xy 212.378076 -402.355506) (xy 212.334327 -402.425653)
			(xy 212.284257 -402.491437) (xy 212.256624 -402.522182) (xy 212.250543 -402.529427) (xy 212.243647 -402.547025)
			(xy 212.243162 -402.556472) (xy 212.243162 -402.586952) (xy 212.243589 -402.596413) (xy 212.250485 -402.614033)
			(xy 212.256624 -402.621242) (xy 212.284222 -402.652015) (xy 212.33427 -402.717808) (xy 212.378004 -402.787957)
			(xy 212.415046 -402.861859) (xy 212.445077 -402.938876) (xy 212.467838 -403.018346) (xy 212.483134 -403.099584)
			(xy 212.490833 -403.18189) (xy 212.49132 -403.223222) (xy 212.490801 -403.266183) (xy 212.482523 -403.351705)
			(xy 212.466036 -403.43603) (xy 212.441494 -403.518372) (xy 212.409125 -403.597963) (xy 212.369232 -403.674062)
			(xy 212.322186 -403.745959) (xy 212.268426 -403.812984) (xy 212.208453 -403.874513) (xy 212.142826 -403.929971)
			(xy 212.072156 -403.978842) (xy 212.034882 -404.000208) (xy 212.02673 -404.005265) (xy 212.014612 -404.020117)
			(xy 212.00876 -404.03837) (xy 212.008974 -404.04796) (xy 212.016086 -404.154386) (xy 212.033358 -404.178008)
			(xy 212.047328 -404.183342) (xy 212.085266 -404.198729) (xy 212.158382 -404.235572) (xy 212.227803 -404.27898)
			(xy 212.29294 -404.328584) (xy 212.353242 -404.383965) (xy 212.408199 -404.444654) (xy 212.457346 -404.510137)
			(xy 212.500266 -404.57986) (xy 212.536597 -404.653232) (xy 212.56603 -404.729633) (xy 212.588317 -404.808416)
			(xy 212.603269 -404.888913) (xy 212.610758 -404.970445) (xy 212.611208 -405.011382) (xy 212.610619 -405.057777)
			(xy 212.600976 -405.150066) (xy 212.581781 -405.240849) (xy 212.553245 -405.329143) (xy 212.535008 -405.371808)
			(xy 212.531213 -405.381753) (xy 212.531206 -405.403014) (xy 212.535008 -405.412956) (xy 212.553247 -405.455621)
			(xy 212.581792 -405.543912) (xy 212.600987 -405.634696) (xy 212.610622 -405.726986) (xy 212.611208 -405.773382)
			(xy 212.610619 -405.819777) (xy 212.600976 -405.912066) (xy 212.581781 -406.002849) (xy 212.553245 -406.091143)
			(xy 212.535008 -406.133808) (xy 212.531213 -406.143753) (xy 212.531206 -406.165014) (xy 212.535008 -406.174956)
			(xy 212.549234 -406.207876) (xy 212.572955 -406.275561) (xy 212.591136 -406.34494) (xy 212.597746 -406.380188)
			(xy 212.600055 -406.390309) (xy 212.611454 -406.407631) (xy 212.628772 -406.419037) (xy 212.638894 -406.421336)
			(xy 212.679556 -406.42906) (xy 212.75936 -406.451024) (xy 212.83678 -406.480305) (xy 212.911146 -406.51665)
			(xy 212.981814 -406.559745) (xy 213.048174 -406.609217) (xy 213.109652 -406.66464) (xy 213.165716 -406.725533)
			(xy 213.215883 -406.791369) (xy 213.259718 -406.861581) (xy 213.296841 -406.935561) (xy 213.326933 -407.012669)
			(xy 213.349733 -407.092239) (xy 213.365045 -407.173582) (xy 213.372734 -407.255996) (xy 213.373208 -407.297382)
			(xy 213.373208 -407.29789) (xy 213.372596 -407.344222) (xy 213.362926 -407.436379) (xy 213.343732 -407.527034)
			(xy 213.315222 -407.615202) (xy 213.297008 -407.657808) (xy 213.293213 -407.667753) (xy 213.293206 -407.689014)
			(xy 213.297008 -407.698956) (xy 213.315224 -407.741561) (xy 213.343743 -407.829728) (xy 213.362938 -407.920383)
			(xy 213.372599 -408.012542) (xy 213.373208 -408.058874) (xy 213.373208 -408.059382) (xy 213.373201 -408.05989)
			(xy 216.928192 -408.05989) (xy 216.928192 -408.059382) (xy 216.928717 -408.017997) (xy 216.936406 -407.935585)
			(xy 216.951716 -407.854244) (xy 216.974513 -407.774675) (xy 217.004602 -407.697568) (xy 217.041723 -407.623589)
			(xy 217.085553 -407.553377) (xy 217.135715 -407.487539) (xy 217.191774 -407.426645) (xy 217.253247 -407.37122)
			(xy 217.319602 -407.321743) (xy 217.390265 -407.278644) (xy 217.464625 -407.242293) (xy 217.54204 -407.213005)
			(xy 217.621841 -407.191034) (xy 217.662506 -407.183336) (xy 217.672634 -407.181051) (xy 217.689956 -407.169641)
			(xy 217.701359 -407.152314) (xy 217.703654 -407.142188) (xy 217.711393 -407.101149) (xy 217.733607 -407.020638)
			(xy 217.763268 -406.942562) (xy 217.800115 -406.86761) (xy 217.843825 -406.796441) (xy 217.894012 -406.729682)
			(xy 217.950235 -406.66792) (xy 218.011998 -406.611699) (xy 218.078759 -406.561513) (xy 218.149929 -406.517805)
			(xy 218.224881 -406.48096) (xy 218.302957 -406.4513) (xy 218.383469 -406.429089) (xy 218.424506 -406.421336)
			(xy 218.434634 -406.419051) (xy 218.451956 -406.407641) (xy 218.463359 -406.390314) (xy 218.465654 -406.380188)
			(xy 218.472281 -406.344944) (xy 218.490478 -406.275571) (xy 218.514186 -406.207884) (xy 218.528392 -406.174956)
			(xy 218.532208 -406.165017) (xy 218.532201 -406.14375) (xy 218.528392 -406.133808) (xy 218.510141 -406.091148)
			(xy 218.481599 -406.002855) (xy 218.462407 -405.912069) (xy 218.452776 -405.819778) (xy 218.452192 -405.773382)
			(xy 218.452769 -405.726986) (xy 218.462415 -405.634698) (xy 218.481613 -405.543914) (xy 218.510153 -405.455621)
			(xy 218.528392 -405.412956) (xy 218.532208 -405.403017) (xy 218.532201 -405.38175) (xy 218.528392 -405.371808)
			(xy 218.510164 -405.329208) (xy 218.481648 -405.241039) (xy 218.462457 -405.150383) (xy 218.452799 -405.058222)
			(xy 218.452192 -405.01189) (xy 218.452192 -405.011382) (xy 218.452669 -404.970705) (xy 218.460097 -404.889692)
			(xy 218.47489 -404.809694) (xy 218.496923 -404.731381) (xy 218.526013 -404.655407) (xy 218.561918 -404.582405)
			(xy 218.604336 -404.512985) (xy 218.652914 -404.447728) (xy 218.707247 -404.387177) (xy 218.76688 -404.33184)
			(xy 218.831316 -404.282176) (xy 218.900016 -404.238603) (xy 218.972407 -404.201482) (xy 219.009976 -404.185882)
			(xy 219.018795 -404.181969) (xy 219.032833 -404.168752) (xy 219.040997 -404.151285) (xy 219.04198 -404.141686)
			(xy 219.047314 -404.049992) (xy 219.047428 -404.040421) (xy 219.041477 -404.022248) (xy 219.029313 -404.007492)
			(xy 219.021152 -404.002494) (xy 218.983554 -403.981253) (xy 218.912288 -403.932477) (xy 218.846083 -403.877025)
			(xy 218.785561 -403.81542) (xy 218.731292 -403.748241) (xy 218.683788 -403.67612) (xy 218.643493 -403.599737)
			(xy 218.610789 -403.519809) (xy 218.585982 -403.437088) (xy 218.569306 -403.352354) (xy 218.560918 -403.266402)
			(xy 218.560396 -403.223222) (xy 218.560864 -403.181887) (xy 218.568535 -403.099572) (xy 218.583812 -403.018325)
			(xy 218.606564 -402.938847) (xy 218.636593 -402.861823) (xy 218.673642 -402.787918) (xy 218.71739 -402.717771)
			(xy 218.767459 -402.651987) (xy 218.795092 -402.621242) (xy 218.801153 -402.613982) (xy 218.808063 -402.596396)
			(xy 218.808554 -402.586952) (xy 218.808554 -402.556472) (xy 218.808185 -402.547004) (xy 218.801251 -402.529384)
			(xy 218.795092 -402.522182) (xy 218.767443 -402.491454) (xy 218.7174 -402.425653) (xy 218.673673 -402.355495)
			(xy 218.636638 -402.281587) (xy 218.606614 -402.204563) (xy 218.58386 -402.125088) (xy 218.568571 -402.043846)
			(xy 218.56088 -401.961536) (xy 218.560396 -401.920202) (xy 218.560852 -401.878866) (xy 218.568524 -401.796552)
			(xy 218.583803 -401.715304) (xy 218.606556 -401.635826) (xy 218.636588 -401.558802) (xy 218.673638 -401.484897)
			(xy 218.717388 -401.414751) (xy 218.767459 -401.348967) (xy 218.795092 -401.318222) (xy 218.801161 -401.310968)
			(xy 218.808066 -401.293378) (xy 218.808554 -401.283932) (xy 218.808554 -401.253452) (xy 218.808146 -401.243989)
			(xy 218.801239 -401.226367) (xy 218.795092 -401.219162) (xy 218.767482 -401.1884) (xy 218.717436 -401.122604)
			(xy 218.673705 -401.052453) (xy 218.636666 -400.978549) (xy 218.606637 -400.90153) (xy 218.583877 -400.82206)
			(xy 218.568582 -400.740821) (xy 218.560883 -400.658515) (xy 218.560396 -400.617182) (xy 218.560896 -400.576069)
			(xy 218.568484 -400.494193) (xy 218.583594 -400.413367) (xy 218.606097 -400.334279) (xy 218.635801 -400.257605)
			(xy 218.672453 -400.183999) (xy 218.715739 -400.114089) (xy 218.765291 -400.04847) (xy 218.820686 -399.987703)
			(xy 218.881451 -399.932307) (xy 218.947069 -399.882753) (xy 219.016978 -399.839464) (xy 219.090583 -399.802811)
			(xy 219.167256 -399.773105) (xy 219.246343 -399.7506) (xy 219.327169 -399.735487) (xy 219.409045 -399.727897)
			(xy 219.450158 -399.72742) (xy 219.494662 -399.727949) (xy 219.583226 -399.736844) (xy 219.670458 -399.754538)
			(xy 219.755487 -399.780856) (xy 219.837463 -399.815534) (xy 219.915565 -399.858225) (xy 219.989014 -399.908502)
			(xy 220.057075 -399.965864) (xy 220.08846 -399.997422) (xy 220.095931 -400.004447) (xy 220.114793 -400.012446)
			(xy 220.125036 -400.012916) (xy 220.19768 -400.012916) (xy 220.207931 -400.012475) (xy 220.226805 -400.004477)
			(xy 220.234256 -399.997422) (xy 220.265663 -399.965886) (xy 220.333719 -399.908523) (xy 220.407164 -399.858243)
			(xy 220.485263 -399.81555) (xy 220.567236 -399.780871) (xy 220.652263 -399.754552) (xy 220.739493 -399.736858)
			(xy 220.828055 -399.727964) (xy 220.872558 -399.72742) (xy 220.916049 -399.727926) (xy 221.002612 -399.736439)
			(xy 221.087932 -399.75336) (xy 221.171193 -399.778526) (xy 221.251601 -399.811696) (xy 221.328388 -399.852556)
			(xy 221.400821 -399.900714) (xy 221.468209 -399.95571) (xy 221.49943 -399.985992) (xy 221.499684 -399.986246)
			(xy 221.507078 -399.992808) (xy 221.525369 -400.000258) (xy 221.535244 -400.000724) (xy 221.606872 -400.000724)
			(xy 221.616751 -400.000273) (xy 221.63505 -399.992827) (xy 221.642432 -399.986246) (xy 221.642686 -399.985992)
			(xy 221.673904 -399.955708) (xy 221.741295 -399.900719) (xy 221.81373 -399.852567) (xy 221.890518 -399.811713)
			(xy 221.970927 -399.778547) (xy 222.054187 -399.753386) (xy 222.139506 -399.736469) (xy 222.226068 -399.727958)
			(xy 222.269558 -399.72742) (xy 222.310672 -399.727938) (xy 222.392549 -399.735522) (xy 222.473376 -399.750627)
			(xy 222.552466 -399.773127) (xy 222.629142 -399.802827) (xy 222.70275 -399.839476) (xy 222.772663 -399.882761)
			(xy 222.838283 -399.932312) (xy 222.899052 -399.987706) (xy 222.95445 -400.04847) (xy 223.004005 -400.114088)
			(xy 223.047294 -400.183998) (xy 223.083948 -400.257603) (xy 223.113654 -400.334277) (xy 223.136159 -400.413365)
			(xy 223.15127 -400.494192) (xy 223.158859 -400.576068) (xy 223.15932 -400.617182) (xy 223.15885 -400.658517)
			(xy 223.151179 -400.740831) (xy 223.135902 -400.822078) (xy 223.113151 -400.901557) (xy 223.083121 -400.978581)
			(xy 223.046073 -401.052485) (xy 223.002325 -401.122632) (xy 222.952256 -401.188416) (xy 222.924624 -401.219162)
			(xy 222.918551 -401.226413) (xy 222.911651 -401.244006) (xy 222.911162 -401.253452) (xy 222.911162 -401.283932)
			(xy 222.911549 -401.293397) (xy 222.918473 -401.311017) (xy 222.924624 -401.318222) (xy 222.95226 -401.348962)
			(xy 223.002306 -401.41476) (xy 223.046036 -401.484914) (xy 223.083073 -401.558821) (xy 223.113099 -401.635843)
			(xy 223.135855 -401.715317) (xy 223.151145 -401.796559) (xy 223.158837 -401.878868) (xy 223.15932 -401.920202)
			(xy 223.158863 -401.961538) (xy 223.15119 -402.043852) (xy 223.135911 -402.125099) (xy 223.113158 -402.204578)
			(xy 223.083126 -402.281602) (xy 223.046076 -402.355506) (xy 223.002327 -402.425653) (xy 222.952257 -402.491437)
			(xy 222.924624 -402.522182) (xy 222.918543 -402.529427) (xy 222.911647 -402.547025) (xy 222.911162 -402.556472)
			(xy 222.911162 -402.586952) (xy 222.911589 -402.596413) (xy 222.918485 -402.614033) (xy 222.924624 -402.621242)
			(xy 222.952222 -402.652015) (xy 223.00227 -402.717808) (xy 223.046004 -402.787957) (xy 223.083046 -402.861859)
			(xy 223.113077 -402.938876) (xy 223.135838 -403.018346) (xy 223.151134 -403.099584) (xy 223.158833 -403.18189)
			(xy 223.15932 -403.223222) (xy 223.158801 -403.266183) (xy 223.150523 -403.351705) (xy 223.134036 -403.43603)
			(xy 223.109494 -403.518372) (xy 223.077125 -403.597963) (xy 223.037232 -403.674062) (xy 222.990186 -403.745959)
			(xy 222.936426 -403.812984) (xy 222.876453 -403.874513) (xy 222.810826 -403.929971) (xy 222.740156 -403.978842)
			(xy 222.702882 -404.000208) (xy 222.69473 -404.005265) (xy 222.682612 -404.020117) (xy 222.67676 -404.03837)
			(xy 222.676974 -404.04796) (xy 222.684086 -404.154386) (xy 222.701358 -404.178008) (xy 222.715328 -404.183342)
			(xy 222.753266 -404.198729) (xy 222.826382 -404.235572) (xy 222.895803 -404.27898) (xy 222.96094 -404.328584)
			(xy 223.021242 -404.383965) (xy 223.076199 -404.444654) (xy 223.125346 -404.510137) (xy 223.168266 -404.57986)
			(xy 223.204597 -404.653232) (xy 223.23403 -404.729633) (xy 223.256317 -404.808416) (xy 223.271269 -404.888913)
			(xy 223.278758 -404.970445) (xy 223.279208 -405.011382) (xy 223.278619 -405.057777) (xy 223.268976 -405.150066)
			(xy 223.249781 -405.240849) (xy 223.221245 -405.329143) (xy 223.203008 -405.371808) (xy 223.199213 -405.381753)
			(xy 223.199206 -405.403014) (xy 223.203008 -405.412956) (xy 223.221247 -405.455621) (xy 223.249792 -405.543912)
			(xy 223.268987 -405.634696) (xy 223.278622 -405.726986) (xy 223.279208 -405.773382) (xy 223.278619 -405.819777)
			(xy 223.268976 -405.912066) (xy 223.249781 -406.002849) (xy 223.221245 -406.091143) (xy 223.203008 -406.133808)
			(xy 223.199213 -406.143753) (xy 223.199206 -406.165014) (xy 223.203008 -406.174956) (xy 223.217234 -406.207876)
			(xy 223.240955 -406.275561) (xy 223.259136 -406.34494) (xy 223.265746 -406.380188) (xy 223.268055 -406.390309)
			(xy 223.279454 -406.407631) (xy 223.296772 -406.419037) (xy 223.306894 -406.421336) (xy 223.347556 -406.42906)
			(xy 223.42736 -406.451024) (xy 223.50478 -406.480305) (xy 223.579146 -406.51665) (xy 223.649814 -406.559745)
			(xy 223.716174 -406.609217) (xy 223.777652 -406.66464) (xy 223.833716 -406.725533) (xy 223.883883 -406.791369)
			(xy 223.927718 -406.861581) (xy 223.964841 -406.935561) (xy 223.994933 -407.012669) (xy 224.017733 -407.092239)
			(xy 224.033045 -407.173582) (xy 224.040734 -407.255996) (xy 224.041208 -407.297382) (xy 224.041208 -407.29789)
			(xy 224.040596 -407.344222) (xy 224.030926 -407.436379) (xy 224.011732 -407.527034) (xy 223.983222 -407.615202)
			(xy 223.965008 -407.657808) (xy 223.961213 -407.667753) (xy 223.961206 -407.689014) (xy 223.965008 -407.698956)
			(xy 223.983224 -407.741561) (xy 224.011743 -407.829728) (xy 224.030938 -407.920383) (xy 224.040599 -408.012542)
			(xy 224.041208 -408.058874) (xy 224.041208 -408.059382) (xy 224.041201 -408.05989) (xy 227.596192 -408.05989)
			(xy 227.596192 -408.059382) (xy 227.596717 -408.017997) (xy 227.604406 -407.935585) (xy 227.619716 -407.854244)
			(xy 227.642513 -407.774675) (xy 227.672602 -407.697568) (xy 227.709723 -407.623589) (xy 227.753553 -407.553377)
			(xy 227.803715 -407.487539) (xy 227.859774 -407.426645) (xy 227.921247 -407.37122) (xy 227.987602 -407.321743)
			(xy 228.058265 -407.278644) (xy 228.132625 -407.242293) (xy 228.21004 -407.213005) (xy 228.289841 -407.191034)
			(xy 228.330506 -407.183336) (xy 228.340634 -407.181051) (xy 228.357956 -407.169641) (xy 228.369359 -407.152314)
			(xy 228.371654 -407.142188) (xy 228.379393 -407.101149) (xy 228.401607 -407.020638) (xy 228.431268 -406.942562)
			(xy 228.468115 -406.86761) (xy 228.511825 -406.796441) (xy 228.562012 -406.729682) (xy 228.618235 -406.66792)
			(xy 228.679998 -406.611699) (xy 228.746759 -406.561513) (xy 228.817929 -406.517805) (xy 228.892881 -406.48096)
			(xy 228.970957 -406.4513) (xy 229.051469 -406.429089) (xy 229.092506 -406.421336) (xy 229.102634 -406.419051)
			(xy 229.119956 -406.407641) (xy 229.131359 -406.390314) (xy 229.133654 -406.380188) (xy 229.140281 -406.344944)
			(xy 229.158478 -406.275571) (xy 229.182186 -406.207884) (xy 229.196392 -406.174956) (xy 229.200208 -406.165017)
			(xy 229.200201 -406.14375) (xy 229.196392 -406.133808) (xy 229.178141 -406.091148) (xy 229.149599 -406.002855)
			(xy 229.130407 -405.912069) (xy 229.120776 -405.819778) (xy 229.120192 -405.773382) (xy 229.120769 -405.726986)
			(xy 229.130415 -405.634698) (xy 229.149613 -405.543914) (xy 229.178153 -405.455621) (xy 229.196392 -405.412956)
			(xy 229.200208 -405.403017) (xy 229.200201 -405.38175) (xy 229.196392 -405.371808) (xy 229.178164 -405.329208)
			(xy 229.149648 -405.241039) (xy 229.130457 -405.150383) (xy 229.120799 -405.058222) (xy 229.120192 -405.01189)
			(xy 229.120192 -405.011382) (xy 229.120669 -404.970705) (xy 229.128097 -404.889692) (xy 229.14289 -404.809694)
			(xy 229.164923 -404.731381) (xy 229.194013 -404.655407) (xy 229.229918 -404.582405) (xy 229.272336 -404.512985)
			(xy 229.320914 -404.447728) (xy 229.375247 -404.387177) (xy 229.43488 -404.33184) (xy 229.499316 -404.282176)
			(xy 229.568016 -404.238603) (xy 229.640407 -404.201482) (xy 229.677976 -404.185882) (xy 229.686795 -404.181969)
			(xy 229.700833 -404.168752) (xy 229.708997 -404.151285) (xy 229.70998 -404.141686) (xy 229.715314 -404.049992)
			(xy 229.715428 -404.040421) (xy 229.709477 -404.022248) (xy 229.697313 -404.007492) (xy 229.689152 -404.002494)
			(xy 229.651554 -403.981253) (xy 229.580288 -403.932477) (xy 229.514083 -403.877025) (xy 229.453561 -403.81542)
			(xy 229.399292 -403.748241) (xy 229.351788 -403.67612) (xy 229.311493 -403.599737) (xy 229.278789 -403.519809)
			(xy 229.253982 -403.437088) (xy 229.237306 -403.352354) (xy 229.228918 -403.266402) (xy 229.228396 -403.223222)
			(xy 229.228864 -403.181887) (xy 229.236535 -403.099572) (xy 229.251812 -403.018325) (xy 229.274564 -402.938847)
			(xy 229.304593 -402.861823) (xy 229.341642 -402.787918) (xy 229.38539 -402.717771) (xy 229.435459 -402.651987)
			(xy 229.463092 -402.621242) (xy 229.469153 -402.613982) (xy 229.476063 -402.596396) (xy 229.476554 -402.586952)
			(xy 229.476554 -402.556472) (xy 229.476185 -402.547004) (xy 229.469251 -402.529384) (xy 229.463092 -402.522182)
			(xy 229.435443 -402.491454) (xy 229.3854 -402.425653) (xy 229.341673 -402.355495) (xy 229.304638 -402.281587)
			(xy 229.274614 -402.204563) (xy 229.25186 -402.125088) (xy 229.236571 -402.043846) (xy 229.22888 -401.961536)
			(xy 229.228396 -401.920202) (xy 229.228852 -401.878866) (xy 229.236524 -401.796552) (xy 229.251803 -401.715304)
			(xy 229.274556 -401.635826) (xy 229.304588 -401.558802) (xy 229.341638 -401.484897) (xy 229.385388 -401.414751)
			(xy 229.435459 -401.348967) (xy 229.463092 -401.318222) (xy 229.469161 -401.310968) (xy 229.476066 -401.293378)
			(xy 229.476554 -401.283932) (xy 229.476554 -401.253452) (xy 229.476146 -401.243989) (xy 229.469239 -401.226367)
			(xy 229.463092 -401.219162) (xy 229.435482 -401.1884) (xy 229.385436 -401.122604) (xy 229.341705 -401.052453)
			(xy 229.304666 -400.978549) (xy 229.274637 -400.90153) (xy 229.251877 -400.82206) (xy 229.236582 -400.740821)
			(xy 229.228883 -400.658515) (xy 229.228396 -400.617182) (xy 229.228896 -400.576069) (xy 229.236484 -400.494193)
			(xy 229.251594 -400.413367) (xy 229.274097 -400.334279) (xy 229.303801 -400.257605) (xy 229.340453 -400.183999)
			(xy 229.383739 -400.114089) (xy 229.433291 -400.04847) (xy 229.488686 -399.987703) (xy 229.549451 -399.932307)
			(xy 229.615069 -399.882753) (xy 229.684978 -399.839464) (xy 229.758583 -399.802811) (xy 229.835256 -399.773105)
			(xy 229.914343 -399.7506) (xy 229.995169 -399.735487) (xy 230.077045 -399.727897) (xy 230.118158 -399.72742)
			(xy 230.162662 -399.727949) (xy 230.251226 -399.736844) (xy 230.338458 -399.754538) (xy 230.423487 -399.780856)
			(xy 230.505463 -399.815534) (xy 230.583565 -399.858225) (xy 230.657014 -399.908502) (xy 230.725075 -399.965864)
			(xy 230.75646 -399.997422) (xy 230.763931 -400.004447) (xy 230.782793 -400.012446) (xy 230.793036 -400.012916)
			(xy 230.86568 -400.012916) (xy 230.875931 -400.012475) (xy 230.894805 -400.004477) (xy 230.902256 -399.997422)
			(xy 230.933663 -399.965886) (xy 231.001719 -399.908523) (xy 231.075164 -399.858243) (xy 231.153263 -399.81555)
			(xy 231.235236 -399.780871) (xy 231.320263 -399.754552) (xy 231.407493 -399.736858) (xy 231.496055 -399.727964)
			(xy 231.540558 -399.72742) (xy 231.584049 -399.727926) (xy 231.670612 -399.736439) (xy 231.755932 -399.75336)
			(xy 231.839193 -399.778526) (xy 231.919601 -399.811696) (xy 231.996388 -399.852556) (xy 232.068821 -399.900714)
			(xy 232.136209 -399.95571) (xy 232.16743 -399.985992) (xy 232.167684 -399.986246) (xy 232.175078 -399.992808)
			(xy 232.193369 -400.000258) (xy 232.203244 -400.000724) (xy 232.274872 -400.000724) (xy 232.284751 -400.000273)
			(xy 232.30305 -399.992827) (xy 232.310432 -399.986246) (xy 232.310686 -399.985992) (xy 232.341904 -399.955708)
			(xy 232.409295 -399.900719) (xy 232.48173 -399.852567) (xy 232.558518 -399.811713) (xy 232.638927 -399.778547)
			(xy 232.722187 -399.753386) (xy 232.807506 -399.736469) (xy 232.894068 -399.727958) (xy 232.937558 -399.72742)
			(xy 232.978672 -399.727938) (xy 233.060549 -399.735522) (xy 233.141376 -399.750627) (xy 233.220466 -399.773127)
			(xy 233.297142 -399.802827) (xy 233.37075 -399.839476) (xy 233.440663 -399.882761) (xy 233.506283 -399.932312)
			(xy 233.567052 -399.987706) (xy 233.62245 -400.04847) (xy 233.672005 -400.114088) (xy 233.715294 -400.183998)
			(xy 233.751948 -400.257603) (xy 233.781654 -400.334277) (xy 233.804159 -400.413365) (xy 233.81927 -400.494192)
			(xy 233.826859 -400.576068) (xy 233.82732 -400.617182) (xy 233.82685 -400.658517) (xy 233.819179 -400.740831)
			(xy 233.803902 -400.822078) (xy 233.781151 -400.901557) (xy 233.751121 -400.978581) (xy 233.714073 -401.052485)
			(xy 233.670325 -401.122632) (xy 233.620256 -401.188416) (xy 233.592624 -401.219162) (xy 233.586551 -401.226413)
			(xy 233.579651 -401.244006) (xy 233.579162 -401.253452) (xy 233.579162 -401.283932) (xy 233.579549 -401.293397)
			(xy 233.586473 -401.311017) (xy 233.592624 -401.318222) (xy 233.62026 -401.348962) (xy 233.670306 -401.41476)
			(xy 233.714036 -401.484914) (xy 233.751073 -401.558821) (xy 233.781099 -401.635843) (xy 233.803855 -401.715317)
			(xy 233.819145 -401.796559) (xy 233.826837 -401.878868) (xy 233.82732 -401.920202) (xy 233.826863 -401.961538)
			(xy 233.81919 -402.043852) (xy 233.803911 -402.125099) (xy 233.781158 -402.204578) (xy 233.751126 -402.281602)
			(xy 233.714076 -402.355506) (xy 233.670327 -402.425653) (xy 233.620257 -402.491437) (xy 233.592624 -402.522182)
			(xy 233.586543 -402.529427) (xy 233.579647 -402.547025) (xy 233.579162 -402.556472) (xy 233.579162 -402.586952)
			(xy 233.579589 -402.596413) (xy 233.586485 -402.614033) (xy 233.592624 -402.621242) (xy 233.620222 -402.652015)
			(xy 233.67027 -402.717808) (xy 233.714004 -402.787957) (xy 233.751046 -402.861859) (xy 233.781077 -402.938876)
			(xy 233.803838 -403.018346) (xy 233.819134 -403.099584) (xy 233.826833 -403.18189) (xy 233.82732 -403.223222)
			(xy 233.826801 -403.266183) (xy 233.818523 -403.351705) (xy 233.802036 -403.43603) (xy 233.777494 -403.518372)
			(xy 233.745125 -403.597963) (xy 233.705232 -403.674062) (xy 233.658186 -403.745959) (xy 233.604426 -403.812984)
			(xy 233.544453 -403.874513) (xy 233.478826 -403.929971) (xy 233.408156 -403.978842) (xy 233.370882 -404.000208)
			(xy 233.36273 -404.005265) (xy 233.350612 -404.020117) (xy 233.34476 -404.03837) (xy 233.344974 -404.04796)
			(xy 233.352086 -404.154386) (xy 233.369358 -404.178008) (xy 233.383328 -404.183342) (xy 233.421266 -404.198729)
			(xy 233.494382 -404.235572) (xy 233.563803 -404.27898) (xy 233.62894 -404.328584) (xy 233.689242 -404.383965)
			(xy 233.744199 -404.444654) (xy 233.793346 -404.510137) (xy 233.836266 -404.57986) (xy 233.872597 -404.653232)
			(xy 233.90203 -404.729633) (xy 233.924317 -404.808416) (xy 233.939269 -404.888913) (xy 233.946758 -404.970445)
			(xy 233.947208 -405.011382) (xy 233.946619 -405.057777) (xy 233.936976 -405.150066) (xy 233.917781 -405.240849)
			(xy 233.889245 -405.329143) (xy 233.871008 -405.371808) (xy 233.867213 -405.381753) (xy 233.867206 -405.403014)
			(xy 233.871008 -405.412956) (xy 233.889247 -405.455621) (xy 233.917792 -405.543912) (xy 233.936987 -405.634696)
			(xy 233.946622 -405.726986) (xy 233.947208 -405.773382) (xy 233.946619 -405.819777) (xy 233.936976 -405.912066)
			(xy 233.917781 -406.002849) (xy 233.889245 -406.091143) (xy 233.871008 -406.133808) (xy 233.867213 -406.143753)
			(xy 233.867206 -406.165014) (xy 233.871008 -406.174956) (xy 233.885234 -406.207876) (xy 233.908955 -406.275561)
			(xy 233.927136 -406.34494) (xy 233.933746 -406.380188) (xy 233.936055 -406.390309) (xy 233.947454 -406.407631)
			(xy 233.964772 -406.419037) (xy 233.974894 -406.421336) (xy 234.015556 -406.42906) (xy 234.09536 -406.451024)
			(xy 234.17278 -406.480305) (xy 234.247146 -406.51665) (xy 234.317814 -406.559745) (xy 234.384174 -406.609217)
			(xy 234.445652 -406.66464) (xy 234.501716 -406.725533) (xy 234.551883 -406.791369) (xy 234.595718 -406.861581)
			(xy 234.632841 -406.935561) (xy 234.662933 -407.012669) (xy 234.685733 -407.092239) (xy 234.701045 -407.173582)
			(xy 234.708734 -407.255996) (xy 234.709208 -407.297382) (xy 234.709208 -407.29789) (xy 234.708596 -407.344222)
			(xy 234.698926 -407.436379) (xy 234.679732 -407.527034) (xy 234.651222 -407.615202) (xy 234.633008 -407.657808)
			(xy 234.629213 -407.667753) (xy 234.629206 -407.689014) (xy 234.633008 -407.698956) (xy 234.651224 -407.741561)
			(xy 234.679743 -407.829728) (xy 234.698938 -407.920383) (xy 234.708599 -408.012542) (xy 234.709208 -408.058874)
			(xy 234.709208 -408.059382) (xy 234.70867 -408.100487) (xy 234.701088 -408.182347) (xy 234.685987 -408.263158)
			(xy 234.663495 -408.342232) (xy 234.633804 -408.418893) (xy 234.597168 -408.492489) (xy 234.5539 -408.562391)
			(xy 234.504367 -408.628004) (xy 234.448992 -408.688767) (xy 234.388249 -408.744164) (xy 234.322654 -408.79372)
			(xy 234.252767 -408.837014) (xy 234.179184 -408.873676) (xy 234.102533 -408.903394) (xy 234.023468 -408.925914)
			(xy 233.942662 -408.941044) (xy 233.860805 -408.948656) (xy 233.8197 -408.949144) (xy 233.773298 -408.948515)
			(xy 233.681001 -408.938826) (xy 233.590215 -408.919572) (xy 233.50193 -408.890965) (xy 233.459274 -408.87269)
			(xy 233.449332 -408.868884) (xy 233.428068 -408.868884) (xy 233.418126 -408.87269) (xy 233.375466 -408.890954)
			(xy 233.287177 -408.919546) (xy 233.196394 -408.938803) (xy 233.104101 -408.948515) (xy 233.0577 -408.949144)
			(xy 233.011298 -408.948515) (xy 232.919001 -408.938826) (xy 232.828215 -408.919572) (xy 232.73993 -408.890965)
			(xy 232.697274 -408.87269) (xy 232.687332 -408.868884) (xy 232.666068 -408.868884) (xy 232.656126 -408.87269)
			(xy 232.613466 -408.890954) (xy 232.525177 -408.919546) (xy 232.434394 -408.938803) (xy 232.342101 -408.948515)
			(xy 232.2957 -408.949144) (xy 232.249298 -408.948515) (xy 232.157001 -408.938826) (xy 232.066215 -408.919572)
			(xy 231.97793 -408.890965) (xy 231.935274 -408.87269) (xy 231.925332 -408.868884) (xy 231.904068 -408.868884)
			(xy 231.894126 -408.87269) (xy 231.851466 -408.890954) (xy 231.763177 -408.919546) (xy 231.672394 -408.938803)
			(xy 231.580101 -408.948515) (xy 231.5337 -408.949144) (xy 231.487298 -408.948515) (xy 231.395001 -408.938826)
			(xy 231.304215 -408.919572) (xy 231.21593 -408.890965) (xy 231.173274 -408.87269) (xy 231.163332 -408.868884)
			(xy 231.142068 -408.868884) (xy 231.132126 -408.87269) (xy 231.089466 -408.890954) (xy 231.001177 -408.919546)
			(xy 230.910394 -408.938803) (xy 230.818101 -408.948515) (xy 230.7717 -408.949144) (xy 230.725298 -408.948515)
			(xy 230.633001 -408.938826) (xy 230.542215 -408.919572) (xy 230.45393 -408.890965) (xy 230.411274 -408.87269)
			(xy 230.401332 -408.868884) (xy 230.380068 -408.868884) (xy 230.370126 -408.87269) (xy 230.327466 -408.890954)
			(xy 230.239177 -408.919546) (xy 230.148394 -408.938803) (xy 230.056101 -408.948515) (xy 230.0097 -408.949144)
			(xy 229.963298 -408.948515) (xy 229.871001 -408.938826) (xy 229.780215 -408.919572) (xy 229.69193 -408.890965)
			(xy 229.649274 -408.87269) (xy 229.639332 -408.868884) (xy 229.618068 -408.868884) (xy 229.608126 -408.87269)
			(xy 229.565466 -408.890954) (xy 229.477177 -408.919546) (xy 229.386394 -408.938803) (xy 229.294101 -408.948515)
			(xy 229.2477 -408.949144) (xy 229.201298 -408.948515) (xy 229.109001 -408.938826) (xy 229.018215 -408.919572)
			(xy 228.92993 -408.890965) (xy 228.887274 -408.87269) (xy 228.877332 -408.868884) (xy 228.856068 -408.868884)
			(xy 228.846126 -408.87269) (xy 228.803466 -408.890954) (xy 228.715177 -408.919546) (xy 228.624394 -408.938803)
			(xy 228.532101 -408.948515) (xy 228.4857 -408.949144) (xy 228.444606 -408.948634) (xy 228.362769 -408.941052)
			(xy 228.281979 -408.925953) (xy 228.202928 -408.903466) (xy 228.126287 -408.873782) (xy 228.052712 -408.837155)
			(xy 227.98283 -408.793896) (xy 227.917236 -408.744376) (xy 227.85649 -408.689016) (xy 227.801109 -408.628288)
			(xy 227.751568 -408.56271) (xy 227.708286 -408.492841) (xy 227.671635 -408.419278) (xy 227.641926 -408.342647)
			(xy 227.619413 -408.263603) (xy 227.604288 -408.182819) (xy 227.59668 -408.100984) (xy 227.596192 -408.05989)
			(xy 224.041201 -408.05989) (xy 224.04067 -408.100487) (xy 224.033088 -408.182347) (xy 224.017987 -408.263158)
			(xy 223.995495 -408.342232) (xy 223.965804 -408.418893) (xy 223.929168 -408.492489) (xy 223.8859 -408.562391)
			(xy 223.836367 -408.628004) (xy 223.780992 -408.688767) (xy 223.720249 -408.744164) (xy 223.654654 -408.79372)
			(xy 223.584767 -408.837014) (xy 223.511184 -408.873676) (xy 223.434533 -408.903394) (xy 223.355468 -408.925914)
			(xy 223.274662 -408.941044) (xy 223.192805 -408.948656) (xy 223.1517 -408.949144) (xy 223.105298 -408.948515)
			(xy 223.013001 -408.938826) (xy 222.922215 -408.919572) (xy 222.83393 -408.890965) (xy 222.791274 -408.87269)
			(xy 222.781332 -408.868884) (xy 222.760068 -408.868884) (xy 222.750126 -408.87269) (xy 222.707466 -408.890954)
			(xy 222.619177 -408.919546) (xy 222.528394 -408.938803) (xy 222.436101 -408.948515) (xy 222.3897 -408.949144)
			(xy 222.343298 -408.948515) (xy 222.251001 -408.938826) (xy 222.160215 -408.919572) (xy 222.07193 -408.890965)
			(xy 222.029274 -408.87269) (xy 222.019332 -408.868884) (xy 221.998068 -408.868884) (xy 221.988126 -408.87269)
			(xy 221.945466 -408.890954) (xy 221.857177 -408.919546) (xy 221.766394 -408.938803) (xy 221.674101 -408.948515)
			(xy 221.6277 -408.949144) (xy 221.581298 -408.948515) (xy 221.489001 -408.938826) (xy 221.398215 -408.919572)
			(xy 221.30993 -408.890965) (xy 221.267274 -408.87269) (xy 221.257332 -408.868884) (xy 221.236068 -408.868884)
			(xy 221.226126 -408.87269) (xy 221.183466 -408.890954) (xy 221.095177 -408.919546) (xy 221.004394 -408.938803)
			(xy 220.912101 -408.948515) (xy 220.8657 -408.949144) (xy 220.819298 -408.948515) (xy 220.727001 -408.938826)
			(xy 220.636215 -408.919572) (xy 220.54793 -408.890965) (xy 220.505274 -408.87269) (xy 220.495332 -408.868884)
			(xy 220.474068 -408.868884) (xy 220.464126 -408.87269) (xy 220.421466 -408.890954) (xy 220.333177 -408.919546)
			(xy 220.242394 -408.938803) (xy 220.150101 -408.948515) (xy 220.1037 -408.949144) (xy 220.057298 -408.948515)
			(xy 219.965001 -408.938826) (xy 219.874215 -408.919572) (xy 219.78593 -408.890965) (xy 219.743274 -408.87269)
			(xy 219.733332 -408.868884) (xy 219.712068 -408.868884) (xy 219.702126 -408.87269) (xy 219.659466 -408.890954)
			(xy 219.571177 -408.919546) (xy 219.480394 -408.938803) (xy 219.388101 -408.948515) (xy 219.3417 -408.949144)
			(xy 219.295298 -408.948515) (xy 219.203001 -408.938826) (xy 219.112215 -408.919572) (xy 219.02393 -408.890965)
			(xy 218.981274 -408.87269) (xy 218.971332 -408.868884) (xy 218.950068 -408.868884) (xy 218.940126 -408.87269)
			(xy 218.897466 -408.890954) (xy 218.809177 -408.919546) (xy 218.718394 -408.938803) (xy 218.626101 -408.948515)
			(xy 218.5797 -408.949144) (xy 218.533298 -408.948515) (xy 218.441001 -408.938826) (xy 218.350215 -408.919572)
			(xy 218.26193 -408.890965) (xy 218.219274 -408.87269) (xy 218.209332 -408.868884) (xy 218.188068 -408.868884)
			(xy 218.178126 -408.87269) (xy 218.135466 -408.890954) (xy 218.047177 -408.919546) (xy 217.956394 -408.938803)
			(xy 217.864101 -408.948515) (xy 217.8177 -408.949144) (xy 217.776606 -408.948634) (xy 217.694769 -408.941052)
			(xy 217.613979 -408.925953) (xy 217.534928 -408.903466) (xy 217.458287 -408.873782) (xy 217.384712 -408.837155)
			(xy 217.31483 -408.793896) (xy 217.249236 -408.744376) (xy 217.18849 -408.689016) (xy 217.133109 -408.628288)
			(xy 217.083568 -408.56271) (xy 217.040286 -408.492841) (xy 217.003635 -408.419278) (xy 216.973926 -408.342647)
			(xy 216.951413 -408.263603) (xy 216.936288 -408.182819) (xy 216.92868 -408.100984) (xy 216.928192 -408.05989)
			(xy 213.373201 -408.05989) (xy 213.37267 -408.100487) (xy 213.365088 -408.182347) (xy 213.349987 -408.263158)
			(xy 213.327495 -408.342232) (xy 213.297804 -408.418893) (xy 213.261168 -408.492489) (xy 213.2179 -408.562391)
			(xy 213.168367 -408.628004) (xy 213.112992 -408.688767) (xy 213.052249 -408.744164) (xy 212.986654 -408.79372)
			(xy 212.916767 -408.837014) (xy 212.843184 -408.873676) (xy 212.766533 -408.903394) (xy 212.687468 -408.925914)
			(xy 212.606662 -408.941044) (xy 212.524805 -408.948656) (xy 212.4837 -408.949144) (xy 212.437298 -408.948515)
			(xy 212.345001 -408.938826) (xy 212.254215 -408.919572) (xy 212.16593 -408.890965) (xy 212.123274 -408.87269)
			(xy 212.113332 -408.868884) (xy 212.092068 -408.868884) (xy 212.082126 -408.87269) (xy 212.039466 -408.890954)
			(xy 211.951177 -408.919546) (xy 211.860394 -408.938803) (xy 211.768101 -408.948515) (xy 211.7217 -408.949144)
			(xy 211.675298 -408.948515) (xy 211.583001 -408.938826) (xy 211.492215 -408.919572) (xy 211.40393 -408.890965)
			(xy 211.361274 -408.87269) (xy 211.351332 -408.868884) (xy 211.330068 -408.868884) (xy 211.320126 -408.87269)
			(xy 211.277466 -408.890954) (xy 211.189177 -408.919546) (xy 211.098394 -408.938803) (xy 211.006101 -408.948515)
			(xy 210.9597 -408.949144) (xy 210.913298 -408.948515) (xy 210.821001 -408.938826) (xy 210.730215 -408.919572)
			(xy 210.64193 -408.890965) (xy 210.599274 -408.87269) (xy 210.589332 -408.868884) (xy 210.568068 -408.868884)
			(xy 210.558126 -408.87269) (xy 210.515466 -408.890954) (xy 210.427177 -408.919546) (xy 210.336394 -408.938803)
			(xy 210.244101 -408.948515) (xy 210.1977 -408.949144) (xy 210.151298 -408.948515) (xy 210.059001 -408.938826)
			(xy 209.968215 -408.919572) (xy 209.87993 -408.890965) (xy 209.837274 -408.87269) (xy 209.827332 -408.868884)
			(xy 209.806068 -408.868884) (xy 209.796126 -408.87269) (xy 209.753466 -408.890954) (xy 209.665177 -408.919546)
			(xy 209.574394 -408.938803) (xy 209.482101 -408.948515) (xy 209.4357 -408.949144) (xy 209.389298 -408.948515)
			(xy 209.297001 -408.938826) (xy 209.206215 -408.919572) (xy 209.11793 -408.890965) (xy 209.075274 -408.87269)
			(xy 209.065332 -408.868884) (xy 209.044068 -408.868884) (xy 209.034126 -408.87269) (xy 208.991466 -408.890954)
			(xy 208.903177 -408.919546) (xy 208.812394 -408.938803) (xy 208.720101 -408.948515) (xy 208.6737 -408.949144)
			(xy 208.627298 -408.948515) (xy 208.535001 -408.938826) (xy 208.444215 -408.919572) (xy 208.35593 -408.890965)
			(xy 208.313274 -408.87269) (xy 208.303332 -408.868884) (xy 208.282068 -408.868884) (xy 208.272126 -408.87269)
			(xy 208.229466 -408.890954) (xy 208.141177 -408.919546) (xy 208.050394 -408.938803) (xy 207.958101 -408.948515)
			(xy 207.9117 -408.949144) (xy 207.865298 -408.948515) (xy 207.773001 -408.938826) (xy 207.682215 -408.919572)
			(xy 207.59393 -408.890965) (xy 207.551274 -408.87269) (xy 207.541332 -408.868884) (xy 207.520068 -408.868884)
			(xy 207.510126 -408.87269) (xy 207.467466 -408.890954) (xy 207.379177 -408.919546) (xy 207.288394 -408.938803)
			(xy 207.196101 -408.948515) (xy 207.1497 -408.949144) (xy 207.108606 -408.948634) (xy 207.026769 -408.941052)
			(xy 206.945979 -408.925953) (xy 206.866928 -408.903466) (xy 206.790287 -408.873782) (xy 206.716712 -408.837155)
			(xy 206.64683 -408.793896) (xy 206.581236 -408.744376) (xy 206.52049 -408.689016) (xy 206.465109 -408.628288)
			(xy 206.415568 -408.56271) (xy 206.372286 -408.492841) (xy 206.335635 -408.419278) (xy 206.305926 -408.342647)
			(xy 206.283413 -408.263603) (xy 206.268288 -408.182819) (xy 206.26068 -408.100984) (xy 206.260192 -408.05989)
			(xy 201.943201 -408.05989) (xy 201.94267 -408.100487) (xy 201.935088 -408.182347) (xy 201.919987 -408.263158)
			(xy 201.897495 -408.342232) (xy 201.867804 -408.418893) (xy 201.831168 -408.492489) (xy 201.7879 -408.562391)
			(xy 201.738367 -408.628004) (xy 201.682992 -408.688767) (xy 201.622249 -408.744164) (xy 201.556654 -408.79372)
			(xy 201.486767 -408.837014) (xy 201.413184 -408.873676) (xy 201.336533 -408.903394) (xy 201.257468 -408.925914)
			(xy 201.176662 -408.941044) (xy 201.094805 -408.948656) (xy 201.0537 -408.949144) (xy 201.007298 -408.948515)
			(xy 200.915001 -408.938826) (xy 200.824215 -408.919572) (xy 200.73593 -408.890965) (xy 200.693274 -408.87269)
			(xy 200.683332 -408.868884) (xy 200.662068 -408.868884) (xy 200.652126 -408.87269) (xy 200.609466 -408.890954)
			(xy 200.521177 -408.919546) (xy 200.430394 -408.938803) (xy 200.338101 -408.948515) (xy 200.2917 -408.949144)
			(xy 200.245298 -408.948515) (xy 200.153001 -408.938826) (xy 200.062215 -408.919572) (xy 199.97393 -408.890965)
			(xy 199.931274 -408.87269) (xy 199.921332 -408.868884) (xy 199.900068 -408.868884) (xy 199.890126 -408.87269)
			(xy 199.847466 -408.890954) (xy 199.759177 -408.919546) (xy 199.668394 -408.938803) (xy 199.576101 -408.948515)
			(xy 199.5297 -408.949144) (xy 199.483298 -408.948515) (xy 199.391001 -408.938826) (xy 199.300215 -408.919572)
			(xy 199.21193 -408.890965) (xy 199.169274 -408.87269) (xy 199.159332 -408.868884) (xy 199.138068 -408.868884)
			(xy 199.128126 -408.87269) (xy 199.085466 -408.890954) (xy 198.997177 -408.919546) (xy 198.906394 -408.938803)
			(xy 198.814101 -408.948515) (xy 198.7677 -408.949144) (xy 198.721298 -408.948515) (xy 198.629001 -408.938826)
			(xy 198.538215 -408.919572) (xy 198.44993 -408.890965) (xy 198.407274 -408.87269) (xy 198.397332 -408.868884)
			(xy 198.376068 -408.868884) (xy 198.366126 -408.87269) (xy 198.323466 -408.890954) (xy 198.235177 -408.919546)
			(xy 198.144394 -408.938803) (xy 198.052101 -408.948515) (xy 198.0057 -408.949144) (xy 197.959298 -408.948515)
			(xy 197.867001 -408.938826) (xy 197.776215 -408.919572) (xy 197.68793 -408.890965) (xy 197.645274 -408.87269)
			(xy 197.635332 -408.868884) (xy 197.614068 -408.868884) (xy 197.604126 -408.87269) (xy 197.561466 -408.890954)
			(xy 197.473177 -408.919546) (xy 197.382394 -408.938803) (xy 197.290101 -408.948515) (xy 197.2437 -408.949144)
			(xy 197.20259 -408.948648) (xy 197.120722 -408.94106) (xy 197.039903 -408.92595) (xy 196.960824 -408.903446)
			(xy 196.884158 -408.873741) (xy 196.810562 -408.837087) (xy 196.740661 -408.793799) (xy 196.675054 -408.744244)
			(xy 196.6143 -408.688846) (xy 196.558917 -408.628078) (xy 196.509378 -408.562459) (xy 196.466106 -408.492548)
			(xy 196.429471 -408.418942) (xy 196.399784 -408.342269) (xy 196.3773 -408.263184) (xy 196.36221 -408.182362)
			(xy 196.354642 -408.100492) (xy 196.354192 -408.059382) (xy 190.372573 -408.059382) (xy 190.373 -408.091894)
			(xy 190.373 -408.092402) (xy 190.372489 -408.133508) (xy 190.364905 -408.215368) (xy 190.349802 -408.296181)
			(xy 190.327308 -408.375255) (xy 190.297616 -408.451917) (xy 190.260978 -408.525513) (xy 190.217707 -408.595415)
			(xy 190.168173 -408.661028) (xy 190.112797 -408.721791) (xy 190.052051 -408.777187) (xy 189.986455 -408.826743)
			(xy 189.916566 -408.870037) (xy 189.842982 -408.906699) (xy 189.76633 -408.936416) (xy 189.687263 -408.958936)
			(xy 189.606456 -408.974065) (xy 189.524598 -408.981676) (xy 189.483492 -408.982164) (xy 189.43709 -408.981537)
			(xy 189.344793 -408.971846) (xy 189.254007 -408.952593) (xy 189.165722 -408.923985) (xy 189.123066 -408.90571)
			(xy 189.113124 -408.901904) (xy 189.09186 -408.901904) (xy 189.081918 -408.90571) (xy 189.039259 -408.923977)
			(xy 188.95097 -408.952569) (xy 188.860187 -408.971824) (xy 188.767893 -408.981535) (xy 188.721492 -408.982164)
			(xy 188.67509 -408.981537) (xy 188.582793 -408.971846) (xy 188.492007 -408.952593) (xy 188.403722 -408.923985)
			(xy 188.361066 -408.90571) (xy 188.351124 -408.901904) (xy 188.32986 -408.901904) (xy 188.319918 -408.90571)
			(xy 188.277259 -408.923977) (xy 188.18897 -408.952569) (xy 188.098187 -408.971824) (xy 188.005893 -408.981535)
			(xy 187.959492 -408.982164) (xy 187.91309 -408.981537) (xy 187.820793 -408.971846) (xy 187.730007 -408.952593)
			(xy 187.641722 -408.923985) (xy 187.599066 -408.90571) (xy 187.589124 -408.901904) (xy 187.56786 -408.901904)
			(xy 187.557918 -408.90571) (xy 187.515259 -408.923977) (xy 187.42697 -408.952569) (xy 187.336187 -408.971824)
			(xy 187.243893 -408.981535) (xy 187.197492 -408.982164) (xy 187.15109 -408.981537) (xy 187.058793 -408.971846)
			(xy 186.968007 -408.952593) (xy 186.879722 -408.923985) (xy 186.837066 -408.90571) (xy 186.827124 -408.901904)
			(xy 186.80586 -408.901904) (xy 186.795918 -408.90571) (xy 186.753259 -408.923977) (xy 186.66497 -408.952569)
			(xy 186.574187 -408.971824) (xy 186.481893 -408.981535) (xy 186.435492 -408.982164) (xy 186.38909 -408.981537)
			(xy 186.296793 -408.971846) (xy 186.206007 -408.952593) (xy 186.117722 -408.923985) (xy 186.075066 -408.90571)
			(xy 186.065124 -408.901904) (xy 186.04386 -408.901904) (xy 186.033918 -408.90571) (xy 185.991259 -408.923977)
			(xy 185.90297 -408.952569) (xy 185.812187 -408.971824) (xy 185.719893 -408.981535) (xy 185.673492 -408.982164)
			(xy 185.63238 -408.981755) (xy 185.550507 -408.974166) (xy 185.469683 -408.959054) (xy 185.3906 -408.936547)
			(xy 185.31393 -408.906837) (xy 185.24033 -408.870179) (xy 185.170427 -408.826885) (xy 185.104818 -408.777325)
			(xy 185.044063 -408.721921) (xy 184.98868 -408.661146) (xy 184.939142 -408.59552) (xy 184.895872 -408.525602)
			(xy 184.859239 -408.451989) (xy 184.829556 -408.37531) (xy 184.807076 -408.296219) (xy 184.791992 -408.21539)
			(xy 184.784431 -408.133514) (xy 184.783984 -408.092402) (xy 184.784568 -408.046006) (xy 184.794213 -407.953718)
			(xy 184.813409 -407.862934) (xy 184.841946 -407.774641) (xy 184.860184 -407.731976) (xy 184.863989 -407.722034)
			(xy 184.86399 -407.70077) (xy 184.860184 -407.690828) (xy 184.841939 -407.648166) (xy 184.813395 -407.559873)
			(xy 184.794202 -407.469088) (xy 184.784569 -407.376798) (xy 184.783984 -407.330402) (xy 184.784407 -407.290634)
			(xy 184.791436 -407.211411) (xy 184.805517 -407.133132) (xy 184.826539 -407.056426) (xy 184.854333 -406.981906)
			(xy 184.871106 -406.945846) (xy 184.875438 -406.935345) (xy 184.875439 -406.912659) (xy 184.871106 -406.902158)
			(xy 184.854347 -406.866093) (xy 184.826573 -406.791567) (xy 184.805556 -406.714862) (xy 184.791462 -406.636588)
			(xy 184.784405 -406.557369) (xy 184.783984 -406.517602) (xy 184.784568 -406.471206) (xy 184.794213 -406.378918)
			(xy 184.813409 -406.288134) (xy 184.841946 -406.199841) (xy 184.860184 -406.157176) (xy 184.863989 -406.147234)
			(xy 184.86399 -406.12597) (xy 184.860184 -406.116028) (xy 184.841939 -406.073366) (xy 184.813395 -405.985073)
			(xy 184.794202 -405.894288) (xy 184.784569 -405.801998) (xy 184.783984 -405.755602) (xy 184.784568 -405.709206)
			(xy 184.794213 -405.616918) (xy 184.813409 -405.526134) (xy 184.841946 -405.437841) (xy 184.860184 -405.395176)
			(xy 184.863989 -405.385234) (xy 184.86399 -405.36397) (xy 184.860184 -405.354028) (xy 184.841962 -405.311425)
			(xy 184.813445 -405.223258) (xy 184.794252 -405.132602) (xy 184.784592 -405.040442) (xy 184.783984 -404.99411)
			(xy 184.783984 -404.993602) (xy 184.784497 -404.950127) (xy 184.792981 -404.863592) (xy 184.809868 -404.778298)
			(xy 184.834996 -404.695058) (xy 184.868127 -404.614668) (xy 184.908943 -404.537893) (xy 184.957056 -404.465468)
			(xy 185.012005 -404.398082) (xy 185.073268 -404.33638) (xy 185.140259 -404.28095) (xy 185.212338 -404.232321)
			(xy 185.288819 -404.190956) (xy 185.368971 -404.157252) (xy 185.452028 -404.131529) (xy 185.5372 -404.114033)
			(xy 185.623672 -404.104931) (xy 185.667142 -404.104094) (xy 185.677625 -404.103496) (xy 185.6968 -404.094996)
			(xy 185.710988 -404.07955) (xy 185.714894 -404.069804) (xy 185.745882 -403.978872) (xy 185.748725 -403.96876)
			(xy 185.74698 -403.947853) (xy 185.737043 -403.929376) (xy 185.729118 -403.922484) (xy 185.70573 -403.903812)
			(xy 185.661243 -403.863772) (xy 185.640218 -403.842474) (xy 185.632756 -403.835439) (xy 185.613887 -403.827446)
			(xy 185.603642 -403.82698) (xy 185.530998 -403.82698) (xy 185.520746 -403.827411) (xy 185.501872 -403.835417)
			(xy 185.494422 -403.842474) (xy 185.463025 -403.87402) (xy 185.394968 -403.931383) (xy 185.321521 -403.981662)
			(xy 185.24342 -404.024354) (xy 185.161446 -404.059031) (xy 185.076418 -404.085348) (xy 184.989186 -404.103041)
			(xy 184.900624 -404.111933) (xy 184.85612 -404.112476) (xy 184.815024 -404.112015) (xy 184.733183 -404.104434)
			(xy 184.652391 -404.089335) (xy 184.573336 -404.066848) (xy 184.496692 -404.037162) (xy 184.423115 -404.000533)
			(xy 184.35323 -403.957272) (xy 184.287634 -403.907749) (xy 184.226887 -403.852384) (xy 184.171506 -403.791652)
			(xy 184.121965 -403.72607) (xy 184.078685 -403.656197) (xy 184.042035 -403.582629) (xy 184.012329 -403.505994)
			(xy 183.98982 -403.426945) (xy 183.9747 -403.346156) (xy 183.967097 -403.264318) (xy 183.966612 -403.223222)
			(xy 174.680622 -403.223222) (xy 174.717549 -403.310307) (xy 174.77977 -403.477384) (xy 174.834486 -403.647068)
			(xy 174.881588 -403.819021) (xy 174.920984 -403.992901) (xy 174.952595 -404.168364) (xy 174.976359 -404.34506)
			(xy 174.992227 -404.52264) (xy 175.000169 -404.70075) (xy 175.000666 -404.789894) (xy 175.000169 -404.879038)
			(xy 174.992227 -405.057148) (xy 174.976359 -405.234728) (xy 174.952595 -405.411424) (xy 174.920984 -405.586887)
			(xy 174.881588 -405.760767) (xy 174.834486 -405.93272) (xy 174.77977 -406.102404) (xy 174.717549 -406.269481)
			(xy 174.647948 -406.433622) (xy 174.571103 -406.594498) (xy 174.487169 -406.751792) (xy 174.396311 -406.905191)
			(xy 174.298709 -407.05439) (xy 174.194558 -407.199093) (xy 174.084065 -407.339013) (xy 173.967448 -407.473872)
			(xy 173.844939 -407.603402) (xy 173.716782 -407.727346) (xy 173.583231 -407.845458) (xy 173.444551 -407.957503)
			(xy 173.301017 -408.06326) (xy 173.152914 -408.162517) (xy 173.000537 -408.255079) (xy 172.844188 -408.34076)
			(xy 172.684177 -408.419392) (xy 172.520823 -408.490818) (xy 172.354448 -408.554896) (xy 172.185385 -408.611498)
			(xy 172.013968 -408.660514) (xy 171.840537 -408.701844) (xy 171.665437 -408.735408) (xy 171.489017 -408.761138)
			(xy 171.311625 -408.778984) (xy 171.133614 -408.78891) (xy 170.955337 -408.790896) (xy 170.77715 -408.784939)
			(xy 170.599404 -408.771049) (xy 170.422454 -408.749256) (xy 170.24665 -408.719602) (xy 170.072342 -408.682145)
			(xy 169.899875 -408.636961) (xy 169.729592 -408.584139) (xy 169.561831 -408.523783) (xy 169.396926 -408.456015)
			(xy 169.235203 -408.380967) (xy 169.076984 -408.29879) (xy 168.922583 -408.209647) (xy 168.772306 -408.113713)
			(xy 168.626451 -408.011181) (xy 168.485309 -407.902253) (xy 168.34916 -407.787146) (xy 168.218273 -407.666088)
			(xy 168.092909 -407.539319) (xy 167.973316 -407.407092) (xy 167.859733 -407.269669) (xy 167.752384 -407.127322)
			(xy 167.651483 -406.980334) (xy 167.55723 -406.828998) (xy 167.469812 -406.673613) (xy 167.389402 -406.514488)
			(xy 167.316161 -406.351939) (xy 167.250234 -406.186289) (xy 167.191751 -406.017867) (xy 167.140829 -405.847006)
			(xy 167.097569 -405.674047) (xy 167.062057 -405.499332) (xy 167.034363 -405.323208) (xy 167.014542 -405.146026)
			(xy 167.002634 -404.968137) (xy 166.998662 -404.789894) (xy 161.904774 -404.789894) (xy 161.889384 -404.799785)
			(xy 161.839805 -404.822428) (xy 161.787508 -404.837784) (xy 161.733558 -404.845542) (xy 161.706306 -404.846028)
			(xy 160.842706 -404.846028) (xy 160.815454 -404.845525) (xy 160.761506 -404.837769) (xy 160.70921 -404.822415)
			(xy 160.659631 -404.799774) (xy 160.61378 -404.770307) (xy 160.572589 -404.734616) (xy 160.536896 -404.693425)
			(xy 160.507429 -404.647574) (xy 160.484788 -404.597996) (xy 160.469432 -404.5457) (xy 160.461675 -404.491752)
			(xy 159.024165 -404.491752) (xy 159.024165 -404.491756) (xy 159.016407 -404.545713) (xy 159.001048 -404.598016)
			(xy 158.978402 -404.647601) (xy 158.948929 -404.693458) (xy 158.91323 -404.734654) (xy 158.872031 -404.77035)
			(xy 158.826171 -404.799818) (xy 158.776584 -404.82246) (xy 158.724279 -404.837814) (xy 158.670322 -404.845567)
			(xy 158.643066 -404.846028) (xy 157.779466 -404.846028) (xy 157.752218 -404.845499) (xy 157.698277 -404.837739)
			(xy 157.645989 -404.822382) (xy 157.596418 -404.79974) (xy 157.550575 -404.770275) (xy 157.509391 -404.734585)
			(xy 157.473705 -404.693398) (xy 157.444243 -404.647552) (xy 157.421606 -404.597979) (xy 157.406253 -404.54569)
			(xy 157.398498 -404.491748) (xy 155.960842 -404.491748) (xy 155.960842 -404.491751) (xy 155.953086 -404.5457)
			(xy 155.937731 -404.597995) (xy 155.915091 -404.647573) (xy 155.885626 -404.693425) (xy 155.849935 -404.734617)
			(xy 155.808746 -404.77031) (xy 155.762896 -404.799778) (xy 155.71332 -404.822422) (xy 155.661025 -404.83778)
			(xy 155.607077 -404.84554) (xy 155.579826 -404.846028) (xy 154.716226 -404.846028) (xy 154.688973 -404.845526)
			(xy 154.635022 -404.837773) (xy 154.582724 -404.82242) (xy 154.533143 -404.79978) (xy 154.487289 -404.770314)
			(xy 154.446096 -404.734623) (xy 154.410401 -404.693431) (xy 154.380932 -404.647579) (xy 154.358289 -404.598)
			(xy 154.342933 -404.545703) (xy 154.335175 -404.491753) (xy 152.897665 -404.491753) (xy 152.897665 -404.491755)
			(xy 152.889907 -404.54571) (xy 152.87455 -404.598012) (xy 152.851905 -404.647595) (xy 152.822434 -404.693452)
			(xy 152.786737 -404.734647) (xy 152.745541 -404.770343) (xy 152.699683 -404.799812) (xy 152.650099 -404.822455)
			(xy 152.597796 -404.83781) (xy 152.543841 -404.845566) (xy 152.516586 -404.846028) (xy 151.652986 -404.846028)
			(xy 151.625737 -404.845501) (xy 151.571794 -404.837743) (xy 151.519503 -404.822388) (xy 151.46993 -404.799747)
			(xy 151.424084 -404.770282) (xy 151.382898 -404.734592) (xy 151.34721 -404.693404) (xy 151.317746 -404.647557)
			(xy 151.295108 -404.597984) (xy 151.279754 -404.545693) (xy 151.271998 -404.491749) (xy 149.834342 -404.491749)
			(xy 149.834342 -404.491751) (xy 149.826587 -404.545697) (xy 149.811233 -404.597991) (xy 149.788594 -404.647568)
			(xy 149.75913 -404.693418) (xy 149.723442 -404.734609) (xy 149.682255 -404.770303) (xy 149.636408 -404.799772)
			(xy 149.586834 -404.822417) (xy 149.534542 -404.837777) (xy 149.480597 -404.845539) (xy 149.453346 -404.846028)
			(xy 148.589746 -404.846028) (xy 148.562492 -404.845528) (xy 148.508539 -404.837777) (xy 148.456239 -404.822425)
			(xy 148.406655 -404.799787) (xy 148.360799 -404.770321) (xy 148.319603 -404.73463) (xy 148.283906 -404.693438)
			(xy 148.254435 -404.647585) (xy 148.231791 -404.598004) (xy 148.216433 -404.545706) (xy 148.208675 -404.491754)
			(xy 146.771142 -404.491754) (xy 146.763385 -404.545702) (xy 146.74803 -404.597999) (xy 146.725388 -404.647579)
			(xy 146.695921 -404.693431) (xy 146.660228 -404.734624) (xy 146.619036 -404.770317) (xy 146.573184 -404.799785)
			(xy 146.523605 -404.822428) (xy 146.471308 -404.837784) (xy 146.417358 -404.845542) (xy 146.390106 -404.846028)
			(xy 145.526506 -404.846028) (xy 145.499254 -404.845525) (xy 145.445306 -404.837769) (xy 145.39301 -404.822415)
			(xy 145.343431 -404.799774) (xy 145.29758 -404.770307) (xy 145.256389 -404.734616) (xy 145.220696 -404.693425)
			(xy 145.191229 -404.647574) (xy 145.168588 -404.597996) (xy 145.153232 -404.5457) (xy 145.145475 -404.491752)
			(xy 143.707965 -404.491752) (xy 143.707965 -404.491756) (xy 143.700207 -404.545713) (xy 143.684848 -404.598016)
			(xy 143.662202 -404.647601) (xy 143.632729 -404.693458) (xy 143.59703 -404.734654) (xy 143.555831 -404.77035)
			(xy 143.509971 -404.799818) (xy 143.460384 -404.82246) (xy 143.408079 -404.837814) (xy 143.354122 -404.845567)
			(xy 143.326866 -404.846028) (xy 142.463266 -404.846028) (xy 142.436018 -404.845499) (xy 142.382077 -404.837739)
			(xy 142.329789 -404.822382) (xy 142.280218 -404.79974) (xy 142.234375 -404.770275) (xy 142.193191 -404.734585)
			(xy 142.157505 -404.693398) (xy 142.128043 -404.647552) (xy 142.105406 -404.597979) (xy 142.090053 -404.54569)
			(xy 142.082298 -404.491748) (xy 140.644642 -404.491748) (xy 140.644642 -404.491751) (xy 140.636886 -404.5457)
			(xy 140.621531 -404.597995) (xy 140.598891 -404.647573) (xy 140.569426 -404.693425) (xy 140.533735 -404.734617)
			(xy 140.492546 -404.77031) (xy 140.446696 -404.799778) (xy 140.39712 -404.822422) (xy 140.344825 -404.83778)
			(xy 140.290877 -404.84554) (xy 140.263626 -404.846028) (xy 139.400026 -404.846028) (xy 139.372773 -404.845526)
			(xy 139.318822 -404.837773) (xy 139.266524 -404.82242) (xy 139.216943 -404.79978) (xy 139.171089 -404.770314)
			(xy 139.129896 -404.734623) (xy 139.094201 -404.693431) (xy 139.064732 -404.647579) (xy 139.042089 -404.598)
			(xy 139.026733 -404.545703) (xy 139.018975 -404.491753) (xy 137.581465 -404.491753) (xy 137.581465 -404.491755)
			(xy 137.573707 -404.54571) (xy 137.55835 -404.598012) (xy 137.535705 -404.647595) (xy 137.506234 -404.693452)
			(xy 137.470537 -404.734647) (xy 137.429341 -404.770343) (xy 137.383483 -404.799812) (xy 137.333899 -404.822455)
			(xy 137.281596 -404.83781) (xy 137.227641 -404.845566) (xy 137.200386 -404.846028) (xy 136.336786 -404.846028)
			(xy 136.309537 -404.845501) (xy 136.255594 -404.837743) (xy 136.203303 -404.822388) (xy 136.15373 -404.799747)
			(xy 136.107884 -404.770282) (xy 136.066698 -404.734592) (xy 136.03101 -404.693404) (xy 136.001546 -404.647557)
			(xy 135.978908 -404.597984) (xy 135.963554 -404.545693) (xy 135.955798 -404.491749) (xy 134.518142 -404.491749)
			(xy 134.518142 -404.491751) (xy 134.510387 -404.545697) (xy 134.495033 -404.597991) (xy 134.472394 -404.647568)
			(xy 134.44293 -404.693418) (xy 134.407242 -404.734609) (xy 134.366055 -404.770303) (xy 134.320208 -404.799772)
			(xy 134.270634 -404.822417) (xy 134.218342 -404.837777) (xy 134.164397 -404.845539) (xy 134.137146 -404.846028)
			(xy 133.273546 -404.846028) (xy 133.246292 -404.845528) (xy 133.192339 -404.837777) (xy 133.140039 -404.822425)
			(xy 133.090455 -404.799787) (xy 133.044599 -404.770321) (xy 133.003403 -404.73463) (xy 132.967706 -404.693438)
			(xy 132.938235 -404.647585) (xy 132.915591 -404.598004) (xy 132.900233 -404.545706) (xy 132.892475 -404.491754)
			(xy 131.454942 -404.491754) (xy 131.447185 -404.545702) (xy 131.43183 -404.597999) (xy 131.409188 -404.647579)
			(xy 131.379721 -404.693431) (xy 131.344028 -404.734624) (xy 131.302836 -404.770317) (xy 131.256984 -404.799785)
			(xy 131.207405 -404.822428) (xy 131.155108 -404.837784) (xy 131.101158 -404.845542) (xy 131.073906 -404.846028)
			(xy 130.210306 -404.846028) (xy 130.183054 -404.845525) (xy 130.129106 -404.837769) (xy 130.07681 -404.822415)
			(xy 130.027231 -404.799774) (xy 129.98138 -404.770307) (xy 129.940189 -404.734616) (xy 129.904496 -404.693425)
			(xy 129.875029 -404.647574) (xy 129.852388 -404.597996) (xy 129.837032 -404.5457) (xy 129.829275 -404.491752)
			(xy 128.391765 -404.491752) (xy 128.391765 -404.491756) (xy 128.384007 -404.545713) (xy 128.368648 -404.598016)
			(xy 128.346002 -404.647601) (xy 128.316529 -404.693458) (xy 128.28083 -404.734654) (xy 128.239631 -404.77035)
			(xy 128.193771 -404.799818) (xy 128.144184 -404.82246) (xy 128.091879 -404.837814) (xy 128.037922 -404.845567)
			(xy 128.010666 -404.846028) (xy 127.147066 -404.846028) (xy 127.119818 -404.845499) (xy 127.065877 -404.837739)
			(xy 127.013589 -404.822382) (xy 126.964018 -404.79974) (xy 126.918175 -404.770275) (xy 126.876991 -404.734585)
			(xy 126.841305 -404.693398) (xy 126.811843 -404.647552) (xy 126.789206 -404.597979) (xy 126.773853 -404.54569)
			(xy 126.766098 -404.491748) (xy 125.328442 -404.491748) (xy 125.328442 -404.491751) (xy 125.320686 -404.5457)
			(xy 125.305331 -404.597995) (xy 125.282691 -404.647573) (xy 125.253226 -404.693425) (xy 125.217535 -404.734617)
			(xy 125.176346 -404.77031) (xy 125.130496 -404.799778) (xy 125.08092 -404.822422) (xy 125.028625 -404.83778)
			(xy 124.974677 -404.84554) (xy 124.947426 -404.846028) (xy 124.083826 -404.846028) (xy 124.056573 -404.845526)
			(xy 124.002622 -404.837773) (xy 123.950324 -404.82242) (xy 123.900743 -404.79978) (xy 123.854889 -404.770314)
			(xy 123.813696 -404.734623) (xy 123.778001 -404.693431) (xy 123.748532 -404.647579) (xy 123.725889 -404.598)
			(xy 123.710533 -404.545703) (xy 123.702775 -404.491753) (xy 122.265265 -404.491753) (xy 122.265265 -404.491755)
			(xy 122.257507 -404.54571) (xy 122.24215 -404.598012) (xy 122.219505 -404.647595) (xy 122.190034 -404.693452)
			(xy 122.154337 -404.734647) (xy 122.113141 -404.770343) (xy 122.067283 -404.799812) (xy 122.017699 -404.822455)
			(xy 121.965396 -404.83781) (xy 121.911441 -404.845566) (xy 121.884186 -404.846028) (xy 121.020586 -404.846028)
			(xy 120.993337 -404.845501) (xy 120.939394 -404.837743) (xy 120.887103 -404.822388) (xy 120.83753 -404.799747)
			(xy 120.791684 -404.770282) (xy 120.750498 -404.734592) (xy 120.71481 -404.693404) (xy 120.685346 -404.647557)
			(xy 120.662708 -404.597984) (xy 120.647354 -404.545693) (xy 120.639598 -404.491749) (xy 119.201942 -404.491749)
			(xy 119.201942 -404.491751) (xy 119.194187 -404.545697) (xy 119.178833 -404.597991) (xy 119.156194 -404.647568)
			(xy 119.12673 -404.693418) (xy 119.091042 -404.734609) (xy 119.049855 -404.770303) (xy 119.004008 -404.799772)
			(xy 118.954434 -404.822417) (xy 118.902142 -404.837777) (xy 118.848197 -404.845539) (xy 118.820946 -404.846028)
			(xy 117.957346 -404.846028) (xy 117.930092 -404.845528) (xy 117.876139 -404.837777) (xy 117.823839 -404.822425)
			(xy 117.774255 -404.799787) (xy 117.728399 -404.770321) (xy 117.687203 -404.73463) (xy 117.651506 -404.693438)
			(xy 117.622035 -404.647585) (xy 117.599391 -404.598004) (xy 117.584033 -404.545706) (xy 117.576275 -404.491754)
			(xy 116.138742 -404.491754) (xy 116.130985 -404.545702) (xy 116.11563 -404.597999) (xy 116.092988 -404.647579)
			(xy 116.063521 -404.693431) (xy 116.027828 -404.734624) (xy 115.986636 -404.770317) (xy 115.940784 -404.799785)
			(xy 115.891205 -404.822428) (xy 115.838908 -404.837784) (xy 115.784958 -404.845542) (xy 115.757706 -404.846028)
			(xy 114.894106 -404.846028) (xy 114.866854 -404.845525) (xy 114.812906 -404.837769) (xy 114.76061 -404.822415)
			(xy 114.711031 -404.799774) (xy 114.66518 -404.770307) (xy 114.623989 -404.734616) (xy 114.588296 -404.693425)
			(xy 114.558829 -404.647574) (xy 114.536188 -404.597996) (xy 114.520832 -404.5457) (xy 114.513075 -404.491752)
			(xy 94.987465 -404.491752) (xy 94.987465 -404.491756) (xy 94.979707 -404.545713) (xy 94.964348 -404.598016)
			(xy 94.941702 -404.647602) (xy 94.912229 -404.693459) (xy 94.876529 -404.734655) (xy 94.83533 -404.77035)
			(xy 94.78947 -404.799819) (xy 94.739883 -404.822461) (xy 94.687578 -404.837814) (xy 94.63362 -404.845568)
			(xy 94.606364 -404.846028) (xy 93.742764 -404.846028) (xy 93.715516 -404.845499) (xy 93.661575 -404.837739)
			(xy 93.609287 -404.822382) (xy 93.559717 -404.79974) (xy 93.513874 -404.770274) (xy 93.47269 -404.734584)
			(xy 93.437004 -404.693397) (xy 93.407543 -404.647551) (xy 93.384906 -404.597979) (xy 93.369553 -404.54569)
			(xy 93.361798 -404.491748) (xy 91.924142 -404.491748) (xy 91.924142 -404.491752) (xy 91.916386 -404.5457)
			(xy 91.901031 -404.597996) (xy 91.878391 -404.647574) (xy 91.848925 -404.693425) (xy 91.813234 -404.734617)
			(xy 91.772045 -404.770311) (xy 91.726195 -404.799779) (xy 91.676618 -404.822423) (xy 91.624324 -404.837781)
			(xy 91.570376 -404.845541) (xy 91.543124 -404.846028) (xy 90.679524 -404.846028) (xy 90.652271 -404.845526)
			(xy 90.598321 -404.837773) (xy 90.546023 -404.822419) (xy 90.496442 -404.799779) (xy 90.450588 -404.770314)
			(xy 90.409395 -404.734622) (xy 90.373701 -404.693431) (xy 90.344232 -404.647579) (xy 90.321589 -404.598)
			(xy 90.306233 -404.545703) (xy 90.298475 -404.491753) (xy 88.860965 -404.491753) (xy 88.860965 -404.491755)
			(xy 88.853207 -404.54571) (xy 88.83785 -404.598012) (xy 88.815205 -404.647596) (xy 88.785734 -404.693452)
			(xy 88.750036 -404.734648) (xy 88.70884 -404.770343) (xy 88.662982 -404.799812) (xy 88.613397 -404.822455)
			(xy 88.561095 -404.837811) (xy 88.507139 -404.845566) (xy 88.479884 -404.846028) (xy 87.616284 -404.846028)
			(xy 87.589035 -404.845501) (xy 87.535092 -404.837743) (xy 87.482802 -404.822387) (xy 87.433229 -404.799746)
			(xy 87.387383 -404.770281) (xy 87.346197 -404.734591) (xy 87.310509 -404.693404) (xy 87.281046 -404.647557)
			(xy 87.258407 -404.597983) (xy 87.243054 -404.545692) (xy 87.235298 -404.491749) (xy 85.797642 -404.491749)
			(xy 85.797642 -404.491751) (xy 85.789887 -404.545697) (xy 85.774533 -404.597991) (xy 85.751894 -404.647568)
			(xy 85.72243 -404.693419) (xy 85.686741 -404.73461) (xy 85.645554 -404.770304) (xy 85.599707 -404.799773)
			(xy 85.550133 -404.822417) (xy 85.49784 -404.837777) (xy 85.443895 -404.845539) (xy 85.416644 -404.846028)
			(xy 84.553044 -404.846028) (xy 84.525791 -404.845528) (xy 84.471838 -404.837776) (xy 84.419537 -404.822425)
			(xy 84.369954 -404.799786) (xy 84.324098 -404.770321) (xy 84.282902 -404.734629) (xy 84.247206 -404.693437)
			(xy 84.217735 -404.647584) (xy 84.195091 -404.598004) (xy 84.179733 -404.545705) (xy 84.171975 -404.491753)
			(xy 82.734442 -404.491753) (xy 82.726685 -404.545703) (xy 82.71133 -404.598) (xy 82.688688 -404.647579)
			(xy 82.65922 -404.693432) (xy 82.623527 -404.734624) (xy 82.582335 -404.770318) (xy 82.536483 -404.799786)
			(xy 82.486904 -404.822428) (xy 82.434607 -404.837785) (xy 82.380656 -404.845542) (xy 82.353404 -404.846028)
			(xy 81.489804 -404.846028) (xy 81.462552 -404.845525) (xy 81.408604 -404.837769) (xy 81.356308 -404.822414)
			(xy 81.30673 -404.799773) (xy 81.260879 -404.770307) (xy 81.219688 -404.734615) (xy 81.183996 -404.693424)
			(xy 81.154529 -404.647573) (xy 81.131887 -404.597995) (xy 81.116532 -404.5457) (xy 81.108775 -404.491752)
			(xy 79.671265 -404.491752) (xy 79.671265 -404.491756) (xy 79.663507 -404.545713) (xy 79.648148 -404.598016)
			(xy 79.625502 -404.647602) (xy 79.596029 -404.693459) (xy 79.560329 -404.734655) (xy 79.51913 -404.77035)
			(xy 79.47327 -404.799819) (xy 79.423683 -404.822461) (xy 79.371378 -404.837814) (xy 79.31742 -404.845568)
			(xy 79.290164 -404.846028) (xy 78.426564 -404.846028) (xy 78.399316 -404.845499) (xy 78.345375 -404.837739)
			(xy 78.293087 -404.822382) (xy 78.243517 -404.79974) (xy 78.197674 -404.770274) (xy 78.15649 -404.734584)
			(xy 78.120804 -404.693397) (xy 78.091343 -404.647551) (xy 78.068706 -404.597979) (xy 78.053353 -404.54569)
			(xy 78.045598 -404.491748) (xy 76.607942 -404.491748) (xy 76.607942 -404.491752) (xy 76.600186 -404.5457)
			(xy 76.584831 -404.597996) (xy 76.562191 -404.647574) (xy 76.532725 -404.693425) (xy 76.497034 -404.734617)
			(xy 76.455845 -404.770311) (xy 76.409995 -404.799779) (xy 76.360418 -404.822423) (xy 76.308124 -404.837781)
			(xy 76.254176 -404.845541) (xy 76.226924 -404.846028) (xy 75.363324 -404.846028) (xy 75.336071 -404.845526)
			(xy 75.282121 -404.837773) (xy 75.229823 -404.822419) (xy 75.180242 -404.799779) (xy 75.134388 -404.770314)
			(xy 75.093195 -404.734622) (xy 75.057501 -404.693431) (xy 75.028032 -404.647579) (xy 75.005389 -404.598)
			(xy 74.990033 -404.545703) (xy 74.982275 -404.491753) (xy 73.544765 -404.491753) (xy 73.544765 -404.491755)
			(xy 73.537007 -404.54571) (xy 73.52165 -404.598012) (xy 73.499005 -404.647596) (xy 73.469534 -404.693452)
			(xy 73.433836 -404.734648) (xy 73.39264 -404.770343) (xy 73.346782 -404.799812) (xy 73.297197 -404.822455)
			(xy 73.244895 -404.837811) (xy 73.190939 -404.845566) (xy 73.163684 -404.846028) (xy 72.300084 -404.846028)
			(xy 72.272835 -404.845501) (xy 72.218892 -404.837743) (xy 72.166602 -404.822387) (xy 72.117029 -404.799746)
			(xy 72.071183 -404.770281) (xy 72.029997 -404.734591) (xy 71.994309 -404.693404) (xy 71.964846 -404.647557)
			(xy 71.942207 -404.597983) (xy 71.926854 -404.545692) (xy 71.919098 -404.491749) (xy 70.481442 -404.491749)
			(xy 70.481442 -404.491751) (xy 70.473687 -404.545697) (xy 70.458333 -404.597991) (xy 70.435694 -404.647568)
			(xy 70.40623 -404.693419) (xy 70.370541 -404.73461) (xy 70.329354 -404.770304) (xy 70.283507 -404.799773)
			(xy 70.233933 -404.822417) (xy 70.18164 -404.837777) (xy 70.127695 -404.845539) (xy 70.100444 -404.846028)
			(xy 69.236844 -404.846028) (xy 69.209591 -404.845528) (xy 69.155638 -404.837776) (xy 69.103337 -404.822425)
			(xy 69.053754 -404.799786) (xy 69.007898 -404.770321) (xy 68.966702 -404.734629) (xy 68.931006 -404.693437)
			(xy 68.901535 -404.647584) (xy 68.878891 -404.598004) (xy 68.863533 -404.545705) (xy 68.855775 -404.491753)
			(xy 67.418242 -404.491753) (xy 67.410485 -404.545703) (xy 67.39513 -404.598) (xy 67.372488 -404.647579)
			(xy 67.34302 -404.693432) (xy 67.307327 -404.734624) (xy 67.266135 -404.770318) (xy 67.220283 -404.799786)
			(xy 67.170704 -404.822428) (xy 67.118407 -404.837785) (xy 67.064456 -404.845542) (xy 67.037204 -404.846028)
			(xy 66.173604 -404.846028) (xy 66.146352 -404.845525) (xy 66.092404 -404.837769) (xy 66.040108 -404.822414)
			(xy 65.99053 -404.799773) (xy 65.944679 -404.770307) (xy 65.903488 -404.734615) (xy 65.867796 -404.693424)
			(xy 65.838329 -404.647573) (xy 65.815687 -404.597995) (xy 65.800332 -404.5457) (xy 65.792575 -404.491752)
			(xy 64.355065 -404.491752) (xy 64.355065 -404.491756) (xy 64.347307 -404.545713) (xy 64.331948 -404.598016)
			(xy 64.309302 -404.647602) (xy 64.279829 -404.693459) (xy 64.244129 -404.734655) (xy 64.20293 -404.77035)
			(xy 64.15707 -404.799819) (xy 64.107483 -404.822461) (xy 64.055178 -404.837814) (xy 64.00122 -404.845568)
			(xy 63.973964 -404.846028) (xy 63.110364 -404.846028) (xy 63.083116 -404.845499) (xy 63.029175 -404.837739)
			(xy 62.976887 -404.822382) (xy 62.927317 -404.79974) (xy 62.881474 -404.770274) (xy 62.84029 -404.734584)
			(xy 62.804604 -404.693397) (xy 62.775143 -404.647551) (xy 62.752506 -404.597979) (xy 62.737153 -404.54569)
			(xy 62.729398 -404.491748) (xy 61.291742 -404.491748) (xy 61.291742 -404.491752) (xy 61.283986 -404.5457)
			(xy 61.268631 -404.597996) (xy 61.245991 -404.647574) (xy 61.216525 -404.693425) (xy 61.180834 -404.734617)
			(xy 61.139645 -404.770311) (xy 61.093795 -404.799779) (xy 61.044218 -404.822423) (xy 60.991924 -404.837781)
			(xy 60.937976 -404.845541) (xy 60.910724 -404.846028) (xy 60.047124 -404.846028) (xy 60.019871 -404.845526)
			(xy 59.965921 -404.837773) (xy 59.913623 -404.822419) (xy 59.864042 -404.799779) (xy 59.818188 -404.770314)
			(xy 59.776995 -404.734622) (xy 59.741301 -404.693431) (xy 59.711832 -404.647579) (xy 59.689189 -404.598)
			(xy 59.673833 -404.545703) (xy 59.666075 -404.491753) (xy 58.228565 -404.491753) (xy 58.228565 -404.491755)
			(xy 58.220807 -404.54571) (xy 58.20545 -404.598012) (xy 58.182805 -404.647596) (xy 58.153334 -404.693452)
			(xy 58.117636 -404.734648) (xy 58.07644 -404.770343) (xy 58.030582 -404.799812) (xy 57.980997 -404.822455)
			(xy 57.928695 -404.837811) (xy 57.874739 -404.845566) (xy 57.847484 -404.846028) (xy 56.983884 -404.846028)
			(xy 56.956635 -404.845501) (xy 56.902692 -404.837743) (xy 56.850402 -404.822387) (xy 56.800829 -404.799746)
			(xy 56.754983 -404.770281) (xy 56.713797 -404.734591) (xy 56.678109 -404.693404) (xy 56.648646 -404.647557)
			(xy 56.626007 -404.597983) (xy 56.610654 -404.545692) (xy 56.602898 -404.491749) (xy 55.165242 -404.491749)
			(xy 55.165242 -404.491751) (xy 55.157487 -404.545697) (xy 55.142133 -404.597991) (xy 55.119494 -404.647568)
			(xy 55.09003 -404.693419) (xy 55.054341 -404.73461) (xy 55.013154 -404.770304) (xy 54.967307 -404.799773)
			(xy 54.917733 -404.822417) (xy 54.86544 -404.837777) (xy 54.811495 -404.845539) (xy 54.784244 -404.846028)
			(xy 53.920644 -404.846028) (xy 53.893391 -404.845528) (xy 53.839438 -404.837776) (xy 53.787137 -404.822425)
			(xy 53.737554 -404.799786) (xy 53.691698 -404.770321) (xy 53.650502 -404.734629) (xy 53.614806 -404.693437)
			(xy 53.585335 -404.647584) (xy 53.562691 -404.598004) (xy 53.547333 -404.545705) (xy 53.539575 -404.491753)
			(xy 52.102042 -404.491753) (xy 52.094285 -404.545703) (xy 52.07893 -404.598) (xy 52.056288 -404.647579)
			(xy 52.02682 -404.693432) (xy 51.991127 -404.734624) (xy 51.949935 -404.770318) (xy 51.904083 -404.799786)
			(xy 51.854504 -404.822428) (xy 51.802207 -404.837785) (xy 51.748256 -404.845542) (xy 51.721004 -404.846028)
			(xy 50.857404 -404.846028) (xy 50.830152 -404.845525) (xy 50.776204 -404.837769) (xy 50.723908 -404.822414)
			(xy 50.67433 -404.799773) (xy 50.628479 -404.770307) (xy 50.587288 -404.734615) (xy 50.551596 -404.693424)
			(xy 50.522129 -404.647573) (xy 50.499487 -404.597995) (xy 50.484132 -404.5457) (xy 50.476375 -404.491752)
			(xy 49.038865 -404.491752) (xy 49.038865 -404.491756) (xy 49.031107 -404.545713) (xy 49.015748 -404.598016)
			(xy 48.993102 -404.647602) (xy 48.963629 -404.693459) (xy 48.927929 -404.734655) (xy 48.88673 -404.77035)
			(xy 48.84087 -404.799819) (xy 48.791283 -404.822461) (xy 48.738978 -404.837814) (xy 48.68502 -404.845568)
			(xy 48.657764 -404.846028) (xy 47.794164 -404.846028) (xy 47.766916 -404.845499) (xy 47.712975 -404.837739)
			(xy 47.660687 -404.822382) (xy 47.611117 -404.79974) (xy 47.565274 -404.770274) (xy 47.52409 -404.734584)
			(xy 47.488404 -404.693397) (xy 47.458943 -404.647551) (xy 47.436306 -404.597979) (xy 47.420953 -404.54569)
			(xy 47.413198 -404.491748) (xy 45.559703 -404.491748) (xy 45.562463 -404.52264) (xy 45.570405 -404.70075)
			(xy 45.570902 -404.789894) (xy 45.570405 -404.879038) (xy 45.562463 -405.057148) (xy 45.546595 -405.234728)
			(xy 45.522831 -405.411424) (xy 45.49122 -405.586887) (xy 45.479552 -405.638385) (xy 104.009796 -405.638385)
			(xy 104.013672 -405.584006) (xy 104.025246 -405.530732) (xy 104.044281 -405.479646) (xy 104.070391 -405.431789)
			(xy 104.103044 -405.388132) (xy 104.121966 -405.368506) (xy 104.732582 -404.757636) (xy 104.75423 -404.736857)
			(xy 104.802784 -404.701606) (xy 104.856253 -404.67438) (xy 104.91332 -404.655848) (xy 104.972583 -404.646465)
			(xy 105.002584 -404.645876) (xy 105.029856 -404.646316) (xy 105.083846 -404.654077) (xy 105.136181 -404.669444)
			(xy 105.185797 -404.692102) (xy 105.231683 -404.721592) (xy 105.272904 -404.757312) (xy 105.308622 -404.798535)
			(xy 105.338108 -404.844422) (xy 105.360764 -404.894039) (xy 105.376127 -404.946376) (xy 105.383885 -405.000366)
			(xy 105.384346 -405.027638) (xy 105.383744 -405.057639) (xy 105.374371 -405.116904) (xy 105.355845 -405.173974)
			(xy 105.328623 -405.227445) (xy 105.29971 -405.267273) (xy 106.824184 -405.267273) (xy 106.824184 -405.212727)
			(xy 106.831947 -405.158735) (xy 106.847315 -405.106398) (xy 106.869976 -405.05678) (xy 106.899467 -405.010893)
			(xy 106.935189 -404.969671) (xy 106.976414 -404.933951) (xy 107.022303 -404.904463) (xy 107.071922 -404.881806)
			(xy 107.12426 -404.866441) (xy 107.178252 -404.858682) (xy 107.205526 -404.85822) (xy 108.069126 -404.85822)
			(xy 108.096393 -404.858744) (xy 108.150371 -404.866508) (xy 108.202695 -404.881875) (xy 108.2523 -404.904532)
			(xy 108.298175 -404.934017) (xy 108.339388 -404.969731) (xy 108.375098 -405.010946) (xy 108.404581 -405.056823)
			(xy 108.427234 -405.106429) (xy 108.442597 -405.158754) (xy 108.450358 -405.212733) (xy 108.450358 -405.267267)
			(xy 108.442597 -405.321246) (xy 108.427234 -405.373571) (xy 108.404581 -405.423177) (xy 108.375098 -405.469054)
			(xy 108.339388 -405.510269) (xy 108.298175 -405.545983) (xy 108.2523 -405.575468) (xy 108.202695 -405.598125)
			(xy 108.150371 -405.613492) (xy 108.096393 -405.621256) (xy 108.069126 -405.621744) (xy 107.205526 -405.621744)
			(xy 107.178252 -405.621318) (xy 107.12426 -405.613559) (xy 107.071922 -405.598194) (xy 107.022303 -405.575537)
			(xy 106.976414 -405.546049) (xy 106.935189 -405.510329) (xy 106.899467 -405.469107) (xy 106.869976 -405.42322)
			(xy 106.847315 -405.373602) (xy 106.831947 -405.321265) (xy 106.824184 -405.267273) (xy 105.29971 -405.267273)
			(xy 105.293374 -405.276001) (xy 105.272586 -405.29764) (xy 104.661716 -405.908256) (xy 104.642167 -405.927256)
			(xy 104.598511 -405.959909) (xy 104.550654 -405.986019) (xy 104.499568 -406.005054) (xy 104.446294 -406.016628)
			(xy 104.391915 -406.020504) (xy 104.337538 -406.016603) (xy 104.284269 -406.005006) (xy 104.233192 -405.985949)
			(xy 104.185346 -405.959818) (xy 104.141704 -405.927145) (xy 104.103155 -405.888596) (xy 104.070482 -405.844954)
			(xy 104.044351 -405.797108) (xy 104.025294 -405.746031) (xy 104.013697 -405.692762) (xy 104.009796 -405.638385)
			(xy 45.479552 -405.638385) (xy 45.451824 -405.760767) (xy 45.404722 -405.93272) (xy 45.350006 -406.102404)
			(xy 45.287785 -406.269481) (xy 45.218184 -406.433622) (xy 45.141339 -406.594498) (xy 45.057405 -406.751792)
			(xy 44.966547 -406.905191) (xy 44.883756 -407.031749) (xy 48.944798 -407.031749) (xy 48.944798 -406.977251)
			(xy 48.952554 -406.923308) (xy 48.967907 -406.871017) (xy 48.990546 -406.821443) (xy 49.020009 -406.775596)
			(xy 49.055697 -406.734409) (xy 49.096883 -406.698719) (xy 49.142729 -406.669254) (xy 49.192302 -406.646613)
			(xy 49.244592 -406.631257) (xy 49.298535 -406.623499) (xy 49.325784 -406.623012) (xy 50.189384 -406.623012)
			(xy 50.216639 -406.623434) (xy 50.270595 -406.631189) (xy 50.322897 -406.646545) (xy 50.372482 -406.669188)
			(xy 50.41834 -406.698657) (xy 50.459536 -406.734352) (xy 50.495234 -406.775548) (xy 50.524705 -406.821404)
			(xy 50.54735 -406.870988) (xy 50.562707 -406.92329) (xy 50.570465 -406.977245) (xy 50.570465 -407.031753)
			(xy 52.007975 -407.031753) (xy 52.007975 -406.977247) (xy 52.015733 -406.923297) (xy 52.031089 -406.871)
			(xy 52.053732 -406.821421) (xy 52.083201 -406.775569) (xy 52.118895 -406.734378) (xy 52.160088 -406.698686)
			(xy 52.205942 -406.669221) (xy 52.255523 -406.646581) (xy 52.307821 -406.631227) (xy 52.361771 -406.623474)
			(xy 52.389024 -406.623012) (xy 53.252624 -406.623012) (xy 53.279876 -406.623459) (xy 53.333824 -406.631219)
			(xy 53.386118 -406.646577) (xy 53.435695 -406.669221) (xy 53.481545 -406.698689) (xy 53.522734 -406.734383)
			(xy 53.558425 -406.775575) (xy 53.587891 -406.821426) (xy 53.610531 -406.871004) (xy 53.625886 -406.9233)
			(xy 53.633642 -406.977248) (xy 53.633642 -407.031748) (xy 55.071298 -407.031748) (xy 55.071298 -406.977252)
			(xy 55.079053 -406.92331) (xy 55.094406 -406.871021) (xy 55.117043 -406.821449) (xy 55.146504 -406.775603)
			(xy 55.18219 -406.734416) (xy 55.223374 -406.698726) (xy 55.269217 -406.66926) (xy 55.318787 -406.646618)
			(xy 55.371075 -406.631261) (xy 55.425016 -406.623501) (xy 55.452264 -406.623012) (xy 56.315864 -406.623012)
			(xy 56.34312 -406.623432) (xy 56.397078 -406.631186) (xy 56.449383 -406.646539) (xy 56.49897 -406.669181)
			(xy 56.54483 -406.69865) (xy 56.586029 -406.734345) (xy 56.621729 -406.775541) (xy 56.651202 -406.821398)
			(xy 56.673848 -406.870984) (xy 56.689207 -406.923287) (xy 56.696965 -406.977244) (xy 56.696965 -407.031752)
			(xy 58.134475 -407.031752) (xy 58.134475 -406.977248) (xy 58.142232 -406.9233) (xy 58.157587 -406.871005)
			(xy 58.180229 -406.821427) (xy 58.209696 -406.775576) (xy 58.245388 -406.734385) (xy 58.286579 -406.698693)
			(xy 58.33243 -406.669227) (xy 58.382008 -406.646586) (xy 58.434304 -406.631231) (xy 58.488252 -406.623475)
			(xy 58.515504 -406.623012) (xy 59.379104 -406.623012) (xy 59.406356 -406.623458) (xy 59.460307 -406.631215)
			(xy 59.512604 -406.646572) (xy 59.562183 -406.669214) (xy 59.608035 -406.698682) (xy 59.649227 -406.734376)
			(xy 59.68492 -406.775568) (xy 59.714388 -406.821421) (xy 59.73703 -406.871) (xy 59.752385 -406.923297)
			(xy 59.760142 -406.977248) (xy 59.760142 -407.031752) (xy 59.760142 -407.031753) (xy 61.197675 -407.031753)
			(xy 61.197675 -406.977247) (xy 61.205433 -406.923295) (xy 61.220791 -406.870996) (xy 61.243435 -406.821416)
			(xy 61.272906 -406.775563) (xy 61.308602 -406.734371) (xy 61.349798 -406.698679) (xy 61.395654 -406.669214)
			(xy 61.445237 -406.646575) (xy 61.497538 -406.631224) (xy 61.551491 -406.623472) (xy 61.578744 -406.623012)
			(xy 62.442344 -406.623012) (xy 62.469595 -406.623461) (xy 62.52354 -406.631223) (xy 62.575833 -406.646583)
			(xy 62.625407 -406.669227) (xy 62.671254 -406.698696) (xy 62.712441 -406.73439) (xy 62.74813 -406.775581)
			(xy 62.777594 -406.821432) (xy 62.800233 -406.871009) (xy 62.815587 -406.923303) (xy 62.823342 -406.977249)
			(xy 62.823342 -407.031749) (xy 64.260998 -407.031749) (xy 64.260998 -406.977251) (xy 64.268754 -406.923308)
			(xy 64.284107 -406.871017) (xy 64.306746 -406.821443) (xy 64.336209 -406.775596) (xy 64.371897 -406.734409)
			(xy 64.413083 -406.698719) (xy 64.458929 -406.669254) (xy 64.508502 -406.646613) (xy 64.560792 -406.631257)
			(xy 64.614735 -406.623499) (xy 64.641984 -406.623012) (xy 65.505584 -406.623012) (xy 65.532839 -406.623434)
			(xy 65.586795 -406.631189) (xy 65.639097 -406.646545) (xy 65.688682 -406.669188) (xy 65.73454 -406.698657)
			(xy 65.775736 -406.734352) (xy 65.811434 -406.775548) (xy 65.840905 -406.821404) (xy 65.86355 -406.870988)
			(xy 65.878907 -406.92329) (xy 65.886665 -406.977245) (xy 65.886665 -407.031753) (xy 67.324175 -407.031753)
			(xy 67.324175 -406.977247) (xy 67.331933 -406.923297) (xy 67.347289 -406.871) (xy 67.369932 -406.821421)
			(xy 67.399401 -406.775569) (xy 67.435095 -406.734378) (xy 67.476288 -406.698686) (xy 67.522142 -406.669221)
			(xy 67.571723 -406.646581) (xy 67.624021 -406.631227) (xy 67.677971 -406.623474) (xy 67.705224 -406.623012)
			(xy 68.568824 -406.623012) (xy 68.596076 -406.623459) (xy 68.650024 -406.631219) (xy 68.702318 -406.646577)
			(xy 68.751895 -406.669221) (xy 68.797745 -406.698689) (xy 68.838934 -406.734383) (xy 68.874625 -406.775575)
			(xy 68.904091 -406.821426) (xy 68.926731 -406.871004) (xy 68.942086 -406.9233) (xy 68.949842 -406.977248)
			(xy 68.949842 -407.031748) (xy 70.387498 -407.031748) (xy 70.387498 -406.977252) (xy 70.395253 -406.92331)
			(xy 70.410606 -406.871021) (xy 70.433243 -406.821449) (xy 70.462704 -406.775603) (xy 70.49839 -406.734416)
			(xy 70.539574 -406.698726) (xy 70.585417 -406.66926) (xy 70.634987 -406.646618) (xy 70.687275 -406.631261)
			(xy 70.741216 -406.623501) (xy 70.768464 -406.623012) (xy 71.632064 -406.623012) (xy 71.65932 -406.623432)
			(xy 71.713278 -406.631186) (xy 71.765583 -406.646539) (xy 71.81517 -406.669181) (xy 71.86103 -406.69865)
			(xy 71.902229 -406.734345) (xy 71.937929 -406.775541) (xy 71.967402 -406.821398) (xy 71.990048 -406.870984)
			(xy 72.005407 -406.923287) (xy 72.013165 -406.977244) (xy 72.013165 -407.031752) (xy 73.450675 -407.031752)
			(xy 73.450675 -406.977248) (xy 73.458432 -406.9233) (xy 73.473787 -406.871005) (xy 73.496429 -406.821427)
			(xy 73.525896 -406.775576) (xy 73.561588 -406.734385) (xy 73.602779 -406.698693) (xy 73.64863 -406.669227)
			(xy 73.698208 -406.646586) (xy 73.750504 -406.631231) (xy 73.804452 -406.623475) (xy 73.831704 -406.623012)
			(xy 74.695304 -406.623012) (xy 74.722556 -406.623458) (xy 74.776507 -406.631215) (xy 74.828804 -406.646572)
			(xy 74.878383 -406.669214) (xy 74.924235 -406.698682) (xy 74.965427 -406.734376) (xy 75.00112 -406.775568)
			(xy 75.030588 -406.821421) (xy 75.05323 -406.871) (xy 75.068585 -406.923297) (xy 75.076342 -406.977248)
			(xy 75.076342 -407.031752) (xy 75.076342 -407.031753) (xy 76.513875 -407.031753) (xy 76.513875 -406.977247)
			(xy 76.521633 -406.923295) (xy 76.536991 -406.870996) (xy 76.559635 -406.821416) (xy 76.589106 -406.775563)
			(xy 76.624802 -406.734371) (xy 76.665998 -406.698679) (xy 76.711854 -406.669214) (xy 76.761437 -406.646575)
			(xy 76.813738 -406.631224) (xy 76.867691 -406.623472) (xy 76.894944 -406.623012) (xy 77.758544 -406.623012)
			(xy 77.785795 -406.623461) (xy 77.83974 -406.631223) (xy 77.892033 -406.646583) (xy 77.941607 -406.669227)
			(xy 77.987454 -406.698696) (xy 78.028641 -406.73439) (xy 78.06433 -406.775581) (xy 78.093794 -406.821432)
			(xy 78.116433 -406.871009) (xy 78.131787 -406.923303) (xy 78.139542 -406.977249) (xy 78.139542 -407.031749)
			(xy 79.577198 -407.031749) (xy 79.577198 -406.977251) (xy 79.584954 -406.923308) (xy 79.600307 -406.871017)
			(xy 79.622946 -406.821443) (xy 79.652409 -406.775596) (xy 79.688097 -406.734409) (xy 79.729283 -406.698719)
			(xy 79.775129 -406.669254) (xy 79.824702 -406.646613) (xy 79.876992 -406.631257) (xy 79.930935 -406.623499)
			(xy 79.958184 -406.623012) (xy 80.821784 -406.623012) (xy 80.849039 -406.623434) (xy 80.902995 -406.631189)
			(xy 80.955297 -406.646545) (xy 81.004882 -406.669188) (xy 81.05074 -406.698657) (xy 81.091936 -406.734352)
			(xy 81.127634 -406.775548) (xy 81.157105 -406.821404) (xy 81.17975 -406.870988) (xy 81.195107 -406.92329)
			(xy 81.202865 -406.977245) (xy 81.202865 -407.031753) (xy 82.640375 -407.031753) (xy 82.640375 -406.977247)
			(xy 82.648133 -406.923297) (xy 82.663489 -406.871) (xy 82.686132 -406.821421) (xy 82.715601 -406.775569)
			(xy 82.751295 -406.734378) (xy 82.792488 -406.698686) (xy 82.838342 -406.669221) (xy 82.887923 -406.646581)
			(xy 82.940221 -406.631227) (xy 82.994171 -406.623474) (xy 83.021424 -406.623012) (xy 83.885024 -406.623012)
			(xy 83.912276 -406.623459) (xy 83.966224 -406.631219) (xy 84.018518 -406.646577) (xy 84.068095 -406.669221)
			(xy 84.113945 -406.698689) (xy 84.155134 -406.734383) (xy 84.190825 -406.775575) (xy 84.220291 -406.821426)
			(xy 84.242931 -406.871004) (xy 84.258286 -406.9233) (xy 84.266042 -406.977248) (xy 84.266042 -407.031748)
			(xy 85.703698 -407.031748) (xy 85.703698 -406.977252) (xy 85.711453 -406.92331) (xy 85.726806 -406.871021)
			(xy 85.749443 -406.821449) (xy 85.778904 -406.775603) (xy 85.81459 -406.734416) (xy 85.855774 -406.698726)
			(xy 85.901617 -406.66926) (xy 85.951187 -406.646618) (xy 86.003475 -406.631261) (xy 86.057416 -406.623501)
			(xy 86.084664 -406.623012) (xy 86.948264 -406.623012) (xy 86.97552 -406.623432) (xy 87.029478 -406.631186)
			(xy 87.081783 -406.646539) (xy 87.13137 -406.669181) (xy 87.17723 -406.69865) (xy 87.218429 -406.734345)
			(xy 87.254129 -406.775541) (xy 87.283602 -406.821398) (xy 87.306248 -406.870984) (xy 87.321607 -406.923287)
			(xy 87.329365 -406.977244) (xy 87.329365 -407.031752) (xy 88.766875 -407.031752) (xy 88.766875 -406.977248)
			(xy 88.774632 -406.9233) (xy 88.789987 -406.871005) (xy 88.812629 -406.821427) (xy 88.842096 -406.775576)
			(xy 88.877788 -406.734385) (xy 88.918979 -406.698693) (xy 88.96483 -406.669227) (xy 89.014408 -406.646586)
			(xy 89.066704 -406.631231) (xy 89.120652 -406.623475) (xy 89.147904 -406.623012) (xy 90.011504 -406.623012)
			(xy 90.038756 -406.623458) (xy 90.092707 -406.631215) (xy 90.145004 -406.646572) (xy 90.194583 -406.669214)
			(xy 90.240435 -406.698682) (xy 90.281627 -406.734376) (xy 90.31732 -406.775568) (xy 90.346788 -406.821421)
			(xy 90.36943 -406.871) (xy 90.384785 -406.923297) (xy 90.392542 -406.977248) (xy 90.392542 -407.031752)
			(xy 90.392542 -407.031753) (xy 91.830075 -407.031753) (xy 91.830075 -406.977247) (xy 91.837833 -406.923295)
			(xy 91.853191 -406.870996) (xy 91.875835 -406.821416) (xy 91.905306 -406.775563) (xy 91.941002 -406.734371)
			(xy 91.982198 -406.698679) (xy 92.028054 -406.669214) (xy 92.077637 -406.646575) (xy 92.129938 -406.631224)
			(xy 92.183891 -406.623472) (xy 92.211144 -406.623012) (xy 93.074744 -406.623012) (xy 93.101995 -406.623461)
			(xy 93.15594 -406.631223) (xy 93.208233 -406.646583) (xy 93.257807 -406.669227) (xy 93.303654 -406.698696)
			(xy 93.344841 -406.73439) (xy 93.38053 -406.775581) (xy 93.409994 -406.821432) (xy 93.432633 -406.871009)
			(xy 93.447987 -406.923303) (xy 93.455742 -406.977249) (xy 93.455742 -407.031749) (xy 94.893398 -407.031749)
			(xy 94.893398 -406.977251) (xy 94.901154 -406.923308) (xy 94.916507 -406.871017) (xy 94.939146 -406.821443)
			(xy 94.968609 -406.775596) (xy 95.004297 -406.734409) (xy 95.045483 -406.698719) (xy 95.091329 -406.669254)
			(xy 95.140902 -406.646613) (xy 95.193192 -406.631257) (xy 95.247135 -406.623499) (xy 95.274384 -406.623012)
			(xy 96.137984 -406.623012) (xy 96.165239 -406.623434) (xy 96.219195 -406.631189) (xy 96.271497 -406.646545)
			(xy 96.321082 -406.669188) (xy 96.36694 -406.698657) (xy 96.408136 -406.734352) (xy 96.443834 -406.775548)
			(xy 96.473305 -406.821404) (xy 96.49595 -406.870988) (xy 96.511307 -406.92329) (xy 96.519065 -406.977245)
			(xy 96.519065 -407.031753) (xy 116.044675 -407.031753) (xy 116.044675 -406.977247) (xy 116.052433 -406.923297)
			(xy 116.067789 -406.871) (xy 116.090432 -406.821421) (xy 116.119901 -406.775569) (xy 116.155596 -406.734377)
			(xy 116.196789 -406.698686) (xy 116.242643 -406.66922) (xy 116.292224 -406.64658) (xy 116.344522 -406.631227)
			(xy 116.398473 -406.623474) (xy 116.425726 -406.623012) (xy 117.289326 -406.623012) (xy 117.316577 -406.62346)
			(xy 117.370525 -406.63122) (xy 117.42282 -406.646578) (xy 117.472396 -406.669222) (xy 117.518246 -406.69869)
			(xy 117.559435 -406.734383) (xy 117.595126 -406.775575) (xy 117.624591 -406.821427) (xy 117.647231 -406.871005)
			(xy 117.662586 -406.9233) (xy 117.670342 -406.977249) (xy 117.670342 -407.031748) (xy 119.107998 -407.031748)
			(xy 119.107998 -406.977252) (xy 119.115753 -406.92331) (xy 119.131106 -406.871021) (xy 119.153743 -406.821448)
			(xy 119.183205 -406.775602) (xy 119.218891 -406.734415) (xy 119.260075 -406.698725) (xy 119.305918 -406.66926)
			(xy 119.355489 -406.646618) (xy 119.407777 -406.631261) (xy 119.461718 -406.623501) (xy 119.488966 -406.623012)
			(xy 120.352566 -406.623012) (xy 120.379822 -406.623433) (xy 120.433779 -406.631186) (xy 120.486084 -406.64654)
			(xy 120.535671 -406.669182) (xy 120.581531 -406.69865) (xy 120.62273 -406.734346) (xy 120.658429 -406.775542)
			(xy 120.687902 -406.821399) (xy 120.710548 -406.870984) (xy 120.725907 -406.923287) (xy 120.733665 -406.977244)
			(xy 120.733665 -407.031752) (xy 122.171175 -407.031752) (xy 122.171175 -406.977248) (xy 122.178932 -406.9233)
			(xy 122.194288 -406.871004) (xy 122.216929 -406.821426) (xy 122.246396 -406.775575) (xy 122.282089 -406.734384)
			(xy 122.32328 -406.698693) (xy 122.369131 -406.669226) (xy 122.41871 -406.646585) (xy 122.471006 -406.631231)
			(xy 122.524954 -406.623475) (xy 122.552206 -406.623012) (xy 123.415806 -406.623012) (xy 123.443058 -406.623458)
			(xy 123.497008 -406.631216) (xy 123.549305 -406.646572) (xy 123.598884 -406.669215) (xy 123.644736 -406.698683)
			(xy 123.685928 -406.734376) (xy 123.721621 -406.775569) (xy 123.751088 -406.821421) (xy 123.77373 -406.871001)
			(xy 123.789085 -406.923298) (xy 123.796842 -406.977248) (xy 123.796842 -407.031752) (xy 123.796842 -407.031754)
			(xy 125.234375 -407.031754) (xy 125.234375 -406.977246) (xy 125.242133 -406.923294) (xy 125.257491 -406.870996)
			(xy 125.280135 -406.821415) (xy 125.309606 -406.775562) (xy 125.345303 -406.73437) (xy 125.386499 -406.698679)
			(xy 125.432355 -406.669213) (xy 125.481939 -406.646575) (xy 125.534239 -406.631223) (xy 125.588192 -406.623472)
			(xy 125.615446 -406.623012) (xy 126.479046 -406.623012) (xy 126.506297 -406.623461) (xy 126.560242 -406.631223)
			(xy 126.612534 -406.646583) (xy 126.662108 -406.669228) (xy 126.707955 -406.698697) (xy 126.749142 -406.734391)
			(xy 126.78483 -406.775582) (xy 126.814294 -406.821432) (xy 126.836933 -406.871009) (xy 126.852287 -406.923303)
			(xy 126.860042 -406.977249) (xy 126.860042 -407.031749) (xy 128.297698 -407.031749) (xy 128.297698 -406.977251)
			(xy 128.305454 -406.923307) (xy 128.320808 -406.871016) (xy 128.343446 -406.821443) (xy 128.37291 -406.775596)
			(xy 128.408598 -406.734408) (xy 128.449784 -406.698718) (xy 128.49563 -406.669253) (xy 128.545203 -406.646612)
			(xy 128.597494 -406.631257) (xy 128.651437 -406.623499) (xy 128.678686 -406.623012) (xy 129.542286 -406.623012)
			(xy 129.569541 -406.623434) (xy 129.623496 -406.63119) (xy 129.675799 -406.646545) (xy 129.725383 -406.669188)
			(xy 129.771241 -406.698657) (xy 129.812437 -406.734353) (xy 129.848134 -406.775548) (xy 129.877605 -406.821405)
			(xy 129.90025 -406.870988) (xy 129.915607 -406.92329) (xy 129.923365 -406.977245) (xy 129.923365 -407.031753)
			(xy 131.360875 -407.031753) (xy 131.360875 -406.977247) (xy 131.368633 -406.923297) (xy 131.383989 -406.871)
			(xy 131.406632 -406.821421) (xy 131.436101 -406.775569) (xy 131.471796 -406.734377) (xy 131.512989 -406.698686)
			(xy 131.558843 -406.66922) (xy 131.608424 -406.64658) (xy 131.660722 -406.631227) (xy 131.714673 -406.623474)
			(xy 131.741926 -406.623012) (xy 132.605526 -406.623012) (xy 132.632777 -406.62346) (xy 132.686725 -406.63122)
			(xy 132.73902 -406.646578) (xy 132.788596 -406.669222) (xy 132.834446 -406.69869) (xy 132.875635 -406.734383)
			(xy 132.911326 -406.775575) (xy 132.940791 -406.821427) (xy 132.963431 -406.871005) (xy 132.978786 -406.9233)
			(xy 132.986542 -406.977249) (xy 132.986542 -407.031748) (xy 134.424198 -407.031748) (xy 134.424198 -406.977252)
			(xy 134.431953 -406.92331) (xy 134.447306 -406.871021) (xy 134.469943 -406.821448) (xy 134.499405 -406.775602)
			(xy 134.535091 -406.734415) (xy 134.576275 -406.698725) (xy 134.622118 -406.66926) (xy 134.671689 -406.646618)
			(xy 134.723977 -406.631261) (xy 134.777918 -406.623501) (xy 134.805166 -406.623012) (xy 135.668766 -406.623012)
			(xy 135.696022 -406.623433) (xy 135.749979 -406.631186) (xy 135.802284 -406.64654) (xy 135.851871 -406.669182)
			(xy 135.897731 -406.69865) (xy 135.93893 -406.734346) (xy 135.974629 -406.775542) (xy 136.004102 -406.821399)
			(xy 136.026748 -406.870984) (xy 136.042107 -406.923287) (xy 136.049865 -406.977244) (xy 136.049865 -407.031752)
			(xy 137.487375 -407.031752) (xy 137.487375 -406.977248) (xy 137.495132 -406.9233) (xy 137.510488 -406.871004)
			(xy 137.533129 -406.821426) (xy 137.562596 -406.775575) (xy 137.598289 -406.734384) (xy 137.63948 -406.698693)
			(xy 137.685331 -406.669226) (xy 137.73491 -406.646585) (xy 137.787206 -406.631231) (xy 137.841154 -406.623475)
			(xy 137.868406 -406.623012) (xy 138.732006 -406.623012) (xy 138.759258 -406.623458) (xy 138.813208 -406.631216)
			(xy 138.865505 -406.646572) (xy 138.915084 -406.669215) (xy 138.960936 -406.698683) (xy 139.002128 -406.734376)
			(xy 139.037821 -406.775569) (xy 139.067288 -406.821421) (xy 139.08993 -406.871001) (xy 139.105285 -406.923298)
			(xy 139.113042 -406.977248) (xy 139.113042 -407.031752) (xy 139.113042 -407.031754) (xy 140.550575 -407.031754)
			(xy 140.550575 -406.977246) (xy 140.558333 -406.923294) (xy 140.573691 -406.870996) (xy 140.596335 -406.821415)
			(xy 140.625806 -406.775562) (xy 140.661503 -406.73437) (xy 140.702699 -406.698679) (xy 140.748555 -406.669213)
			(xy 140.798139 -406.646575) (xy 140.850439 -406.631223) (xy 140.904392 -406.623472) (xy 140.931646 -406.623012)
			(xy 141.795246 -406.623012) (xy 141.822497 -406.623461) (xy 141.876442 -406.631223) (xy 141.928734 -406.646583)
			(xy 141.978308 -406.669228) (xy 142.024155 -406.698697) (xy 142.065342 -406.734391) (xy 142.10103 -406.775582)
			(xy 142.130494 -406.821432) (xy 142.153133 -406.871009) (xy 142.168487 -406.923303) (xy 142.176242 -406.977249)
			(xy 142.176242 -407.031749) (xy 143.613898 -407.031749) (xy 143.613898 -406.977251) (xy 143.621654 -406.923307)
			(xy 143.637008 -406.871016) (xy 143.659646 -406.821443) (xy 143.68911 -406.775596) (xy 143.724798 -406.734408)
			(xy 143.765984 -406.698718) (xy 143.81183 -406.669253) (xy 143.861403 -406.646612) (xy 143.913694 -406.631257)
			(xy 143.967637 -406.623499) (xy 143.994886 -406.623012) (xy 144.858486 -406.623012) (xy 144.885741 -406.623434)
			(xy 144.939696 -406.63119) (xy 144.991999 -406.646545) (xy 145.041583 -406.669188) (xy 145.087441 -406.698657)
			(xy 145.128637 -406.734353) (xy 145.164334 -406.775548) (xy 145.193805 -406.821405) (xy 145.21645 -406.870988)
			(xy 145.231807 -406.92329) (xy 145.239565 -406.977245) (xy 145.239565 -407.031753) (xy 146.677075 -407.031753)
			(xy 146.677075 -406.977247) (xy 146.684833 -406.923297) (xy 146.700189 -406.871) (xy 146.722832 -406.821421)
			(xy 146.752301 -406.775569) (xy 146.787996 -406.734377) (xy 146.829189 -406.698686) (xy 146.875043 -406.66922)
			(xy 146.924624 -406.64658) (xy 146.976922 -406.631227) (xy 147.030873 -406.623474) (xy 147.058126 -406.623012)
			(xy 147.921726 -406.623012) (xy 147.948977 -406.62346) (xy 148.002925 -406.63122) (xy 148.05522 -406.646578)
			(xy 148.104796 -406.669222) (xy 148.150646 -406.69869) (xy 148.191835 -406.734383) (xy 148.227526 -406.775575)
			(xy 148.256991 -406.821427) (xy 148.279631 -406.871005) (xy 148.294986 -406.9233) (xy 148.302742 -406.977249)
			(xy 148.302742 -407.031748) (xy 149.740398 -407.031748) (xy 149.740398 -406.977252) (xy 149.748153 -406.92331)
			(xy 149.763506 -406.871021) (xy 149.786143 -406.821448) (xy 149.815605 -406.775602) (xy 149.851291 -406.734415)
			(xy 149.892475 -406.698725) (xy 149.938318 -406.66926) (xy 149.987889 -406.646618) (xy 150.040177 -406.631261)
			(xy 150.094118 -406.623501) (xy 150.121366 -406.623012) (xy 150.984966 -406.623012) (xy 151.012222 -406.623433)
			(xy 151.066179 -406.631186) (xy 151.118484 -406.64654) (xy 151.168071 -406.669182) (xy 151.213931 -406.69865)
			(xy 151.25513 -406.734346) (xy 151.290829 -406.775542) (xy 151.320302 -406.821399) (xy 151.342948 -406.870984)
			(xy 151.358307 -406.923287) (xy 151.366065 -406.977244) (xy 151.366065 -407.031752) (xy 152.803575 -407.031752)
			(xy 152.803575 -406.977248) (xy 152.811332 -406.9233) (xy 152.826688 -406.871004) (xy 152.849329 -406.821426)
			(xy 152.878796 -406.775575) (xy 152.914489 -406.734384) (xy 152.95568 -406.698693) (xy 153.001531 -406.669226)
			(xy 153.05111 -406.646585) (xy 153.103406 -406.631231) (xy 153.157354 -406.623475) (xy 153.184606 -406.623012)
			(xy 154.048206 -406.623012) (xy 154.075458 -406.623458) (xy 154.129408 -406.631216) (xy 154.181705 -406.646572)
			(xy 154.231284 -406.669215) (xy 154.277136 -406.698683) (xy 154.318328 -406.734376) (xy 154.354021 -406.775569)
			(xy 154.383488 -406.821421) (xy 154.40613 -406.871001) (xy 154.421485 -406.923298) (xy 154.429242 -406.977248)
			(xy 154.429242 -407.031752) (xy 154.429242 -407.031754) (xy 155.866775 -407.031754) (xy 155.866775 -406.977246)
			(xy 155.874533 -406.923294) (xy 155.889891 -406.870996) (xy 155.912535 -406.821415) (xy 155.942006 -406.775562)
			(xy 155.977703 -406.73437) (xy 156.018899 -406.698679) (xy 156.064755 -406.669213) (xy 156.114339 -406.646575)
			(xy 156.166639 -406.631223) (xy 156.220592 -406.623472) (xy 156.247846 -406.623012) (xy 157.111446 -406.623012)
			(xy 157.138697 -406.623461) (xy 157.192642 -406.631223) (xy 157.244934 -406.646583) (xy 157.294508 -406.669228)
			(xy 157.340355 -406.698697) (xy 157.381542 -406.734391) (xy 157.41723 -406.775582) (xy 157.446694 -406.821432)
			(xy 157.469333 -406.871009) (xy 157.484687 -406.923303) (xy 157.492442 -406.977249) (xy 157.492442 -407.031749)
			(xy 158.930098 -407.031749) (xy 158.930098 -406.977251) (xy 158.937854 -406.923307) (xy 158.953208 -406.871016)
			(xy 158.975846 -406.821443) (xy 159.00531 -406.775596) (xy 159.040998 -406.734408) (xy 159.082184 -406.698718)
			(xy 159.12803 -406.669253) (xy 159.177603 -406.646612) (xy 159.229894 -406.631257) (xy 159.283837 -406.623499)
			(xy 159.311086 -406.623012) (xy 160.174686 -406.623012) (xy 160.201941 -406.623434) (xy 160.255896 -406.63119)
			(xy 160.308199 -406.646545) (xy 160.357783 -406.669188) (xy 160.403641 -406.698657) (xy 160.444837 -406.734353)
			(xy 160.480534 -406.775548) (xy 160.510005 -406.821405) (xy 160.53265 -406.870988) (xy 160.548007 -406.92329)
			(xy 160.555765 -406.977245) (xy 160.555765 -407.031753) (xy 161.993275 -407.031753) (xy 161.993275 -406.977247)
			(xy 162.001033 -406.923297) (xy 162.016389 -406.871) (xy 162.039032 -406.821421) (xy 162.068501 -406.775569)
			(xy 162.104196 -406.734377) (xy 162.145389 -406.698686) (xy 162.191243 -406.66922) (xy 162.240824 -406.64658)
			(xy 162.293122 -406.631227) (xy 162.347073 -406.623474) (xy 162.374326 -406.623012) (xy 163.237926 -406.623012)
			(xy 163.265177 -406.62346) (xy 163.319125 -406.63122) (xy 163.37142 -406.646578) (xy 163.420996 -406.669222)
			(xy 163.466846 -406.69869) (xy 163.508035 -406.734383) (xy 163.543726 -406.775575) (xy 163.573191 -406.821427)
			(xy 163.595831 -406.871005) (xy 163.611186 -406.9233) (xy 163.618942 -406.977249) (xy 163.618942 -407.031751)
			(xy 163.611186 -407.0857) (xy 163.595831 -407.137995) (xy 163.573191 -407.187573) (xy 163.543726 -407.233425)
			(xy 163.508035 -407.274617) (xy 163.466846 -407.31031) (xy 163.420996 -407.339778) (xy 163.37142 -407.362422)
			(xy 163.319125 -407.37778) (xy 163.265177 -407.38554) (xy 163.237926 -407.386028) (xy 162.374326 -407.386028)
			(xy 162.347073 -407.385526) (xy 162.293122 -407.377773) (xy 162.240824 -407.36242) (xy 162.191243 -407.33978)
			(xy 162.145389 -407.310314) (xy 162.104196 -407.274623) (xy 162.068501 -407.233431) (xy 162.039032 -407.187579)
			(xy 162.016389 -407.138) (xy 162.001033 -407.085703) (xy 161.993275 -407.031753) (xy 160.555765 -407.031753)
			(xy 160.555765 -407.031755) (xy 160.548007 -407.08571) (xy 160.53265 -407.138012) (xy 160.510005 -407.187595)
			(xy 160.480534 -407.233452) (xy 160.444837 -407.274647) (xy 160.403641 -407.310343) (xy 160.357783 -407.339812)
			(xy 160.308199 -407.362455) (xy 160.255896 -407.37781) (xy 160.201941 -407.385566) (xy 160.174686 -407.386028)
			(xy 159.311086 -407.386028) (xy 159.283837 -407.385501) (xy 159.229894 -407.377743) (xy 159.177603 -407.362388)
			(xy 159.12803 -407.339747) (xy 159.082184 -407.310282) (xy 159.040998 -407.274592) (xy 159.00531 -407.233404)
			(xy 158.975846 -407.187557) (xy 158.953208 -407.137984) (xy 158.937854 -407.085693) (xy 158.930098 -407.031749)
			(xy 157.492442 -407.031749) (xy 157.492442 -407.031751) (xy 157.484687 -407.085697) (xy 157.469333 -407.137991)
			(xy 157.446694 -407.187568) (xy 157.41723 -407.233418) (xy 157.381542 -407.274609) (xy 157.340355 -407.310303)
			(xy 157.294508 -407.339772) (xy 157.244934 -407.362417) (xy 157.192642 -407.377777) (xy 157.138697 -407.385539)
			(xy 157.111446 -407.386028) (xy 156.247846 -407.386028) (xy 156.220592 -407.385528) (xy 156.166639 -407.377777)
			(xy 156.114339 -407.362425) (xy 156.064755 -407.339787) (xy 156.018899 -407.310321) (xy 155.977703 -407.27463)
			(xy 155.942006 -407.233438) (xy 155.912535 -407.187585) (xy 155.889891 -407.138004) (xy 155.874533 -407.085706)
			(xy 155.866775 -407.031754) (xy 154.429242 -407.031754) (xy 154.421485 -407.085702) (xy 154.40613 -407.137999)
			(xy 154.383488 -407.187579) (xy 154.354021 -407.233431) (xy 154.318328 -407.274624) (xy 154.277136 -407.310317)
			(xy 154.231284 -407.339785) (xy 154.181705 -407.362428) (xy 154.129408 -407.377784) (xy 154.075458 -407.385542)
			(xy 154.048206 -407.386028) (xy 153.184606 -407.386028) (xy 153.157354 -407.385525) (xy 153.103406 -407.377769)
			(xy 153.05111 -407.362415) (xy 153.001531 -407.339774) (xy 152.95568 -407.310307) (xy 152.914489 -407.274616)
			(xy 152.878796 -407.233425) (xy 152.849329 -407.187574) (xy 152.826688 -407.137996) (xy 152.811332 -407.0857)
			(xy 152.803575 -407.031752) (xy 151.366065 -407.031752) (xy 151.366065 -407.031756) (xy 151.358307 -407.085713)
			(xy 151.342948 -407.138016) (xy 151.320302 -407.187601) (xy 151.290829 -407.233458) (xy 151.25513 -407.274654)
			(xy 151.213931 -407.31035) (xy 151.168071 -407.339818) (xy 151.118484 -407.36246) (xy 151.066179 -407.377814)
			(xy 151.012222 -407.385567) (xy 150.984966 -407.386028) (xy 150.121366 -407.386028) (xy 150.094118 -407.385499)
			(xy 150.040177 -407.377739) (xy 149.987889 -407.362382) (xy 149.938318 -407.33974) (xy 149.892475 -407.310275)
			(xy 149.851291 -407.274585) (xy 149.815605 -407.233398) (xy 149.786143 -407.187552) (xy 149.763506 -407.137979)
			(xy 149.748153 -407.08569) (xy 149.740398 -407.031748) (xy 148.302742 -407.031748) (xy 148.302742 -407.031751)
			(xy 148.294986 -407.0857) (xy 148.279631 -407.137995) (xy 148.256991 -407.187573) (xy 148.227526 -407.233425)
			(xy 148.191835 -407.274617) (xy 148.150646 -407.31031) (xy 148.104796 -407.339778) (xy 148.05522 -407.362422)
			(xy 148.002925 -407.37778) (xy 147.948977 -407.38554) (xy 147.921726 -407.386028) (xy 147.058126 -407.386028)
			(xy 147.030873 -407.385526) (xy 146.976922 -407.377773) (xy 146.924624 -407.36242) (xy 146.875043 -407.33978)
			(xy 146.829189 -407.310314) (xy 146.787996 -407.274623) (xy 146.752301 -407.233431) (xy 146.722832 -407.187579)
			(xy 146.700189 -407.138) (xy 146.684833 -407.085703) (xy 146.677075 -407.031753) (xy 145.239565 -407.031753)
			(xy 145.239565 -407.031755) (xy 145.231807 -407.08571) (xy 145.21645 -407.138012) (xy 145.193805 -407.187595)
			(xy 145.164334 -407.233452) (xy 145.128637 -407.274647) (xy 145.087441 -407.310343) (xy 145.041583 -407.339812)
			(xy 144.991999 -407.362455) (xy 144.939696 -407.37781) (xy 144.885741 -407.385566) (xy 144.858486 -407.386028)
			(xy 143.994886 -407.386028) (xy 143.967637 -407.385501) (xy 143.913694 -407.377743) (xy 143.861403 -407.362388)
			(xy 143.81183 -407.339747) (xy 143.765984 -407.310282) (xy 143.724798 -407.274592) (xy 143.68911 -407.233404)
			(xy 143.659646 -407.187557) (xy 143.637008 -407.137984) (xy 143.621654 -407.085693) (xy 143.613898 -407.031749)
			(xy 142.176242 -407.031749) (xy 142.176242 -407.031751) (xy 142.168487 -407.085697) (xy 142.153133 -407.137991)
			(xy 142.130494 -407.187568) (xy 142.10103 -407.233418) (xy 142.065342 -407.274609) (xy 142.024155 -407.310303)
			(xy 141.978308 -407.339772) (xy 141.928734 -407.362417) (xy 141.876442 -407.377777) (xy 141.822497 -407.385539)
			(xy 141.795246 -407.386028) (xy 140.931646 -407.386028) (xy 140.904392 -407.385528) (xy 140.850439 -407.377777)
			(xy 140.798139 -407.362425) (xy 140.748555 -407.339787) (xy 140.702699 -407.310321) (xy 140.661503 -407.27463)
			(xy 140.625806 -407.233438) (xy 140.596335 -407.187585) (xy 140.573691 -407.138004) (xy 140.558333 -407.085706)
			(xy 140.550575 -407.031754) (xy 139.113042 -407.031754) (xy 139.105285 -407.085702) (xy 139.08993 -407.137999)
			(xy 139.067288 -407.187579) (xy 139.037821 -407.233431) (xy 139.002128 -407.274624) (xy 138.960936 -407.310317)
			(xy 138.915084 -407.339785) (xy 138.865505 -407.362428) (xy 138.813208 -407.377784) (xy 138.759258 -407.385542)
			(xy 138.732006 -407.386028) (xy 137.868406 -407.386028) (xy 137.841154 -407.385525) (xy 137.787206 -407.377769)
			(xy 137.73491 -407.362415) (xy 137.685331 -407.339774) (xy 137.63948 -407.310307) (xy 137.598289 -407.274616)
			(xy 137.562596 -407.233425) (xy 137.533129 -407.187574) (xy 137.510488 -407.137996) (xy 137.495132 -407.0857)
			(xy 137.487375 -407.031752) (xy 136.049865 -407.031752) (xy 136.049865 -407.031756) (xy 136.042107 -407.085713)
			(xy 136.026748 -407.138016) (xy 136.004102 -407.187601) (xy 135.974629 -407.233458) (xy 135.93893 -407.274654)
			(xy 135.897731 -407.31035) (xy 135.851871 -407.339818) (xy 135.802284 -407.36246) (xy 135.749979 -407.377814)
			(xy 135.696022 -407.385567) (xy 135.668766 -407.386028) (xy 134.805166 -407.386028) (xy 134.777918 -407.385499)
			(xy 134.723977 -407.377739) (xy 134.671689 -407.362382) (xy 134.622118 -407.33974) (xy 134.576275 -407.310275)
			(xy 134.535091 -407.274585) (xy 134.499405 -407.233398) (xy 134.469943 -407.187552) (xy 134.447306 -407.137979)
			(xy 134.431953 -407.08569) (xy 134.424198 -407.031748) (xy 132.986542 -407.031748) (xy 132.986542 -407.031751)
			(xy 132.978786 -407.0857) (xy 132.963431 -407.137995) (xy 132.940791 -407.187573) (xy 132.911326 -407.233425)
			(xy 132.875635 -407.274617) (xy 132.834446 -407.31031) (xy 132.788596 -407.339778) (xy 132.73902 -407.362422)
			(xy 132.686725 -407.37778) (xy 132.632777 -407.38554) (xy 132.605526 -407.386028) (xy 131.741926 -407.386028)
			(xy 131.714673 -407.385526) (xy 131.660722 -407.377773) (xy 131.608424 -407.36242) (xy 131.558843 -407.33978)
			(xy 131.512989 -407.310314) (xy 131.471796 -407.274623) (xy 131.436101 -407.233431) (xy 131.406632 -407.187579)
			(xy 131.383989 -407.138) (xy 131.368633 -407.085703) (xy 131.360875 -407.031753) (xy 129.923365 -407.031753)
			(xy 129.923365 -407.031755) (xy 129.915607 -407.08571) (xy 129.90025 -407.138012) (xy 129.877605 -407.187595)
			(xy 129.848134 -407.233452) (xy 129.812437 -407.274647) (xy 129.771241 -407.310343) (xy 129.725383 -407.339812)
			(xy 129.675799 -407.362455) (xy 129.623496 -407.37781) (xy 129.569541 -407.385566) (xy 129.542286 -407.386028)
			(xy 128.678686 -407.386028) (xy 128.651437 -407.385501) (xy 128.597494 -407.377743) (xy 128.545203 -407.362388)
			(xy 128.49563 -407.339747) (xy 128.449784 -407.310282) (xy 128.408598 -407.274592) (xy 128.37291 -407.233404)
			(xy 128.343446 -407.187557) (xy 128.320808 -407.137984) (xy 128.305454 -407.085693) (xy 128.297698 -407.031749)
			(xy 126.860042 -407.031749) (xy 126.860042 -407.031751) (xy 126.852287 -407.085697) (xy 126.836933 -407.137991)
			(xy 126.814294 -407.187568) (xy 126.78483 -407.233418) (xy 126.749142 -407.274609) (xy 126.707955 -407.310303)
			(xy 126.662108 -407.339772) (xy 126.612534 -407.362417) (xy 126.560242 -407.377777) (xy 126.506297 -407.385539)
			(xy 126.479046 -407.386028) (xy 125.615446 -407.386028) (xy 125.588192 -407.385528) (xy 125.534239 -407.377777)
			(xy 125.481939 -407.362425) (xy 125.432355 -407.339787) (xy 125.386499 -407.310321) (xy 125.345303 -407.27463)
			(xy 125.309606 -407.233438) (xy 125.280135 -407.187585) (xy 125.257491 -407.138004) (xy 125.242133 -407.085706)
			(xy 125.234375 -407.031754) (xy 123.796842 -407.031754) (xy 123.789085 -407.085702) (xy 123.77373 -407.137999)
			(xy 123.751088 -407.187579) (xy 123.721621 -407.233431) (xy 123.685928 -407.274624) (xy 123.644736 -407.310317)
			(xy 123.598884 -407.339785) (xy 123.549305 -407.362428) (xy 123.497008 -407.377784) (xy 123.443058 -407.385542)
			(xy 123.415806 -407.386028) (xy 122.552206 -407.386028) (xy 122.524954 -407.385525) (xy 122.471006 -407.377769)
			(xy 122.41871 -407.362415) (xy 122.369131 -407.339774) (xy 122.32328 -407.310307) (xy 122.282089 -407.274616)
			(xy 122.246396 -407.233425) (xy 122.216929 -407.187574) (xy 122.194288 -407.137996) (xy 122.178932 -407.0857)
			(xy 122.171175 -407.031752) (xy 120.733665 -407.031752) (xy 120.733665 -407.031756) (xy 120.725907 -407.085713)
			(xy 120.710548 -407.138016) (xy 120.687902 -407.187601) (xy 120.658429 -407.233458) (xy 120.62273 -407.274654)
			(xy 120.581531 -407.31035) (xy 120.535671 -407.339818) (xy 120.486084 -407.36246) (xy 120.433779 -407.377814)
			(xy 120.379822 -407.385567) (xy 120.352566 -407.386028) (xy 119.488966 -407.386028) (xy 119.461718 -407.385499)
			(xy 119.407777 -407.377739) (xy 119.355489 -407.362382) (xy 119.305918 -407.33974) (xy 119.260075 -407.310275)
			(xy 119.218891 -407.274585) (xy 119.183205 -407.233398) (xy 119.153743 -407.187552) (xy 119.131106 -407.137979)
			(xy 119.115753 -407.08569) (xy 119.107998 -407.031748) (xy 117.670342 -407.031748) (xy 117.670342 -407.031751)
			(xy 117.662586 -407.0857) (xy 117.647231 -407.137995) (xy 117.624591 -407.187573) (xy 117.595126 -407.233425)
			(xy 117.559435 -407.274617) (xy 117.518246 -407.31031) (xy 117.472396 -407.339778) (xy 117.42282 -407.362422)
			(xy 117.370525 -407.37778) (xy 117.316577 -407.38554) (xy 117.289326 -407.386028) (xy 116.425726 -407.386028)
			(xy 116.398473 -407.385526) (xy 116.344522 -407.377773) (xy 116.292224 -407.36242) (xy 116.242643 -407.33978)
			(xy 116.196789 -407.310314) (xy 116.155596 -407.274623) (xy 116.119901 -407.233431) (xy 116.090432 -407.187579)
			(xy 116.067789 -407.138) (xy 116.052433 -407.085703) (xy 116.044675 -407.031753) (xy 96.519065 -407.031753)
			(xy 96.519065 -407.031755) (xy 96.511307 -407.08571) (xy 96.49595 -407.138012) (xy 96.473305 -407.187596)
			(xy 96.443834 -407.233452) (xy 96.408136 -407.274648) (xy 96.36694 -407.310343) (xy 96.321082 -407.339812)
			(xy 96.271497 -407.362455) (xy 96.219195 -407.377811) (xy 96.165239 -407.385566) (xy 96.137984 -407.386028)
			(xy 95.274384 -407.386028) (xy 95.247135 -407.385501) (xy 95.193192 -407.377743) (xy 95.140902 -407.362387)
			(xy 95.091329 -407.339746) (xy 95.045483 -407.310281) (xy 95.004297 -407.274591) (xy 94.968609 -407.233404)
			(xy 94.939146 -407.187557) (xy 94.916507 -407.137983) (xy 94.901154 -407.085692) (xy 94.893398 -407.031749)
			(xy 93.455742 -407.031749) (xy 93.455742 -407.031751) (xy 93.447987 -407.085697) (xy 93.432633 -407.137991)
			(xy 93.409994 -407.187568) (xy 93.38053 -407.233419) (xy 93.344841 -407.27461) (xy 93.303654 -407.310304)
			(xy 93.257807 -407.339773) (xy 93.208233 -407.362417) (xy 93.15594 -407.377777) (xy 93.101995 -407.385539)
			(xy 93.074744 -407.386028) (xy 92.211144 -407.386028) (xy 92.183891 -407.385528) (xy 92.129938 -407.377776)
			(xy 92.077637 -407.362425) (xy 92.028054 -407.339786) (xy 91.982198 -407.310321) (xy 91.941002 -407.274629)
			(xy 91.905306 -407.233437) (xy 91.875835 -407.187584) (xy 91.853191 -407.138004) (xy 91.837833 -407.085705)
			(xy 91.830075 -407.031753) (xy 90.392542 -407.031753) (xy 90.384785 -407.085703) (xy 90.36943 -407.138)
			(xy 90.346788 -407.187579) (xy 90.31732 -407.233432) (xy 90.281627 -407.274624) (xy 90.240435 -407.310318)
			(xy 90.194583 -407.339786) (xy 90.145004 -407.362428) (xy 90.092707 -407.377785) (xy 90.038756 -407.385542)
			(xy 90.011504 -407.386028) (xy 89.147904 -407.386028) (xy 89.120652 -407.385525) (xy 89.066704 -407.377769)
			(xy 89.014408 -407.362414) (xy 88.96483 -407.339773) (xy 88.918979 -407.310307) (xy 88.877788 -407.274615)
			(xy 88.842096 -407.233424) (xy 88.812629 -407.187573) (xy 88.789987 -407.137995) (xy 88.774632 -407.0857)
			(xy 88.766875 -407.031752) (xy 87.329365 -407.031752) (xy 87.329365 -407.031756) (xy 87.321607 -407.085713)
			(xy 87.306248 -407.138016) (xy 87.283602 -407.187602) (xy 87.254129 -407.233459) (xy 87.218429 -407.274655)
			(xy 87.17723 -407.31035) (xy 87.13137 -407.339819) (xy 87.081783 -407.362461) (xy 87.029478 -407.377814)
			(xy 86.97552 -407.385568) (xy 86.948264 -407.386028) (xy 86.084664 -407.386028) (xy 86.057416 -407.385499)
			(xy 86.003475 -407.377739) (xy 85.951187 -407.362382) (xy 85.901617 -407.33974) (xy 85.855774 -407.310274)
			(xy 85.81459 -407.274584) (xy 85.778904 -407.233397) (xy 85.749443 -407.187551) (xy 85.726806 -407.137979)
			(xy 85.711453 -407.08569) (xy 85.703698 -407.031748) (xy 84.266042 -407.031748) (xy 84.266042 -407.031752)
			(xy 84.258286 -407.0857) (xy 84.242931 -407.137996) (xy 84.220291 -407.187574) (xy 84.190825 -407.233425)
			(xy 84.155134 -407.274617) (xy 84.113945 -407.310311) (xy 84.068095 -407.339779) (xy 84.018518 -407.362423)
			(xy 83.966224 -407.377781) (xy 83.912276 -407.385541) (xy 83.885024 -407.386028) (xy 83.021424 -407.386028)
			(xy 82.994171 -407.385526) (xy 82.940221 -407.377773) (xy 82.887923 -407.362419) (xy 82.838342 -407.339779)
			(xy 82.792488 -407.310314) (xy 82.751295 -407.274622) (xy 82.715601 -407.233431) (xy 82.686132 -407.187579)
			(xy 82.663489 -407.138) (xy 82.648133 -407.085703) (xy 82.640375 -407.031753) (xy 81.202865 -407.031753)
			(xy 81.202865 -407.031755) (xy 81.195107 -407.08571) (xy 81.17975 -407.138012) (xy 81.157105 -407.187596)
			(xy 81.127634 -407.233452) (xy 81.091936 -407.274648) (xy 81.05074 -407.310343) (xy 81.004882 -407.339812)
			(xy 80.955297 -407.362455) (xy 80.902995 -407.377811) (xy 80.849039 -407.385566) (xy 80.821784 -407.386028)
			(xy 79.958184 -407.386028) (xy 79.930935 -407.385501) (xy 79.876992 -407.377743) (xy 79.824702 -407.362387)
			(xy 79.775129 -407.339746) (xy 79.729283 -407.310281) (xy 79.688097 -407.274591) (xy 79.652409 -407.233404)
			(xy 79.622946 -407.187557) (xy 79.600307 -407.137983) (xy 79.584954 -407.085692) (xy 79.577198 -407.031749)
			(xy 78.139542 -407.031749) (xy 78.139542 -407.031751) (xy 78.131787 -407.085697) (xy 78.116433 -407.137991)
			(xy 78.093794 -407.187568) (xy 78.06433 -407.233419) (xy 78.028641 -407.27461) (xy 77.987454 -407.310304)
			(xy 77.941607 -407.339773) (xy 77.892033 -407.362417) (xy 77.83974 -407.377777) (xy 77.785795 -407.385539)
			(xy 77.758544 -407.386028) (xy 76.894944 -407.386028) (xy 76.867691 -407.385528) (xy 76.813738 -407.377776)
			(xy 76.761437 -407.362425) (xy 76.711854 -407.339786) (xy 76.665998 -407.310321) (xy 76.624802 -407.274629)
			(xy 76.589106 -407.233437) (xy 76.559635 -407.187584) (xy 76.536991 -407.138004) (xy 76.521633 -407.085705)
			(xy 76.513875 -407.031753) (xy 75.076342 -407.031753) (xy 75.068585 -407.085703) (xy 75.05323 -407.138)
			(xy 75.030588 -407.187579) (xy 75.00112 -407.233432) (xy 74.965427 -407.274624) (xy 74.924235 -407.310318)
			(xy 74.878383 -407.339786) (xy 74.828804 -407.362428) (xy 74.776507 -407.377785) (xy 74.722556 -407.385542)
			(xy 74.695304 -407.386028) (xy 73.831704 -407.386028) (xy 73.804452 -407.385525) (xy 73.750504 -407.377769)
			(xy 73.698208 -407.362414) (xy 73.64863 -407.339773) (xy 73.602779 -407.310307) (xy 73.561588 -407.274615)
			(xy 73.525896 -407.233424) (xy 73.496429 -407.187573) (xy 73.473787 -407.137995) (xy 73.458432 -407.0857)
			(xy 73.450675 -407.031752) (xy 72.013165 -407.031752) (xy 72.013165 -407.031756) (xy 72.005407 -407.085713)
			(xy 71.990048 -407.138016) (xy 71.967402 -407.187602) (xy 71.937929 -407.233459) (xy 71.902229 -407.274655)
			(xy 71.86103 -407.31035) (xy 71.81517 -407.339819) (xy 71.765583 -407.362461) (xy 71.713278 -407.377814)
			(xy 71.65932 -407.385568) (xy 71.632064 -407.386028) (xy 70.768464 -407.386028) (xy 70.741216 -407.385499)
			(xy 70.687275 -407.377739) (xy 70.634987 -407.362382) (xy 70.585417 -407.33974) (xy 70.539574 -407.310274)
			(xy 70.49839 -407.274584) (xy 70.462704 -407.233397) (xy 70.433243 -407.187551) (xy 70.410606 -407.137979)
			(xy 70.395253 -407.08569) (xy 70.387498 -407.031748) (xy 68.949842 -407.031748) (xy 68.949842 -407.031752)
			(xy 68.942086 -407.0857) (xy 68.926731 -407.137996) (xy 68.904091 -407.187574) (xy 68.874625 -407.233425)
			(xy 68.838934 -407.274617) (xy 68.797745 -407.310311) (xy 68.751895 -407.339779) (xy 68.702318 -407.362423)
			(xy 68.650024 -407.377781) (xy 68.596076 -407.385541) (xy 68.568824 -407.386028) (xy 67.705224 -407.386028)
			(xy 67.677971 -407.385526) (xy 67.624021 -407.377773) (xy 67.571723 -407.362419) (xy 67.522142 -407.339779)
			(xy 67.476288 -407.310314) (xy 67.435095 -407.274622) (xy 67.399401 -407.233431) (xy 67.369932 -407.187579)
			(xy 67.347289 -407.138) (xy 67.331933 -407.085703) (xy 67.324175 -407.031753) (xy 65.886665 -407.031753)
			(xy 65.886665 -407.031755) (xy 65.878907 -407.08571) (xy 65.86355 -407.138012) (xy 65.840905 -407.187596)
			(xy 65.811434 -407.233452) (xy 65.775736 -407.274648) (xy 65.73454 -407.310343) (xy 65.688682 -407.339812)
			(xy 65.639097 -407.362455) (xy 65.586795 -407.377811) (xy 65.532839 -407.385566) (xy 65.505584 -407.386028)
			(xy 64.641984 -407.386028) (xy 64.614735 -407.385501) (xy 64.560792 -407.377743) (xy 64.508502 -407.362387)
			(xy 64.458929 -407.339746) (xy 64.413083 -407.310281) (xy 64.371897 -407.274591) (xy 64.336209 -407.233404)
			(xy 64.306746 -407.187557) (xy 64.284107 -407.137983) (xy 64.268754 -407.085692) (xy 64.260998 -407.031749)
			(xy 62.823342 -407.031749) (xy 62.823342 -407.031751) (xy 62.815587 -407.085697) (xy 62.800233 -407.137991)
			(xy 62.777594 -407.187568) (xy 62.74813 -407.233419) (xy 62.712441 -407.27461) (xy 62.671254 -407.310304)
			(xy 62.625407 -407.339773) (xy 62.575833 -407.362417) (xy 62.52354 -407.377777) (xy 62.469595 -407.385539)
			(xy 62.442344 -407.386028) (xy 61.578744 -407.386028) (xy 61.551491 -407.385528) (xy 61.497538 -407.377776)
			(xy 61.445237 -407.362425) (xy 61.395654 -407.339786) (xy 61.349798 -407.310321) (xy 61.308602 -407.274629)
			(xy 61.272906 -407.233437) (xy 61.243435 -407.187584) (xy 61.220791 -407.138004) (xy 61.205433 -407.085705)
			(xy 61.197675 -407.031753) (xy 59.760142 -407.031753) (xy 59.752385 -407.085703) (xy 59.73703 -407.138)
			(xy 59.714388 -407.187579) (xy 59.68492 -407.233432) (xy 59.649227 -407.274624) (xy 59.608035 -407.310318)
			(xy 59.562183 -407.339786) (xy 59.512604 -407.362428) (xy 59.460307 -407.377785) (xy 59.406356 -407.385542)
			(xy 59.379104 -407.386028) (xy 58.515504 -407.386028) (xy 58.488252 -407.385525) (xy 58.434304 -407.377769)
			(xy 58.382008 -407.362414) (xy 58.33243 -407.339773) (xy 58.286579 -407.310307) (xy 58.245388 -407.274615)
			(xy 58.209696 -407.233424) (xy 58.180229 -407.187573) (xy 58.157587 -407.137995) (xy 58.142232 -407.0857)
			(xy 58.134475 -407.031752) (xy 56.696965 -407.031752) (xy 56.696965 -407.031756) (xy 56.689207 -407.085713)
			(xy 56.673848 -407.138016) (xy 56.651202 -407.187602) (xy 56.621729 -407.233459) (xy 56.586029 -407.274655)
			(xy 56.54483 -407.31035) (xy 56.49897 -407.339819) (xy 56.449383 -407.362461) (xy 56.397078 -407.377814)
			(xy 56.34312 -407.385568) (xy 56.315864 -407.386028) (xy 55.452264 -407.386028) (xy 55.425016 -407.385499)
			(xy 55.371075 -407.377739) (xy 55.318787 -407.362382) (xy 55.269217 -407.33974) (xy 55.223374 -407.310274)
			(xy 55.18219 -407.274584) (xy 55.146504 -407.233397) (xy 55.117043 -407.187551) (xy 55.094406 -407.137979)
			(xy 55.079053 -407.08569) (xy 55.071298 -407.031748) (xy 53.633642 -407.031748) (xy 53.633642 -407.031752)
			(xy 53.625886 -407.0857) (xy 53.610531 -407.137996) (xy 53.587891 -407.187574) (xy 53.558425 -407.233425)
			(xy 53.522734 -407.274617) (xy 53.481545 -407.310311) (xy 53.435695 -407.339779) (xy 53.386118 -407.362423)
			(xy 53.333824 -407.377781) (xy 53.279876 -407.385541) (xy 53.252624 -407.386028) (xy 52.389024 -407.386028)
			(xy 52.361771 -407.385526) (xy 52.307821 -407.377773) (xy 52.255523 -407.362419) (xy 52.205942 -407.339779)
			(xy 52.160088 -407.310314) (xy 52.118895 -407.274622) (xy 52.083201 -407.233431) (xy 52.053732 -407.187579)
			(xy 52.031089 -407.138) (xy 52.015733 -407.085703) (xy 52.007975 -407.031753) (xy 50.570465 -407.031753)
			(xy 50.570465 -407.031755) (xy 50.562707 -407.08571) (xy 50.54735 -407.138012) (xy 50.524705 -407.187596)
			(xy 50.495234 -407.233452) (xy 50.459536 -407.274648) (xy 50.41834 -407.310343) (xy 50.372482 -407.339812)
			(xy 50.322897 -407.362455) (xy 50.270595 -407.377811) (xy 50.216639 -407.385566) (xy 50.189384 -407.386028)
			(xy 49.325784 -407.386028) (xy 49.298535 -407.385501) (xy 49.244592 -407.377743) (xy 49.192302 -407.362387)
			(xy 49.142729 -407.339746) (xy 49.096883 -407.310281) (xy 49.055697 -407.274591) (xy 49.020009 -407.233404)
			(xy 48.990546 -407.187557) (xy 48.967907 -407.137983) (xy 48.952554 -407.085692) (xy 48.944798 -407.031749)
			(xy 44.883756 -407.031749) (xy 44.868945 -407.05439) (xy 44.764794 -407.199093) (xy 44.654301 -407.339013)
			(xy 44.537684 -407.473872) (xy 44.415175 -407.603402) (xy 44.287018 -407.727346) (xy 44.153467 -407.845458)
			(xy 44.014787 -407.957503) (xy 43.871253 -408.06326) (xy 43.72315 -408.162517) (xy 43.570773 -408.255079)
			(xy 43.414424 -408.34076) (xy 43.254413 -408.419392) (xy 43.091059 -408.490818) (xy 42.924684 -408.554896)
			(xy 42.755621 -408.611498) (xy 42.584204 -408.660514) (xy 42.410773 -408.701844) (xy 42.235673 -408.735408)
			(xy 42.059253 -408.761138) (xy 41.881861 -408.778984) (xy 41.70385 -408.78891) (xy 41.525573 -408.790896)
			(xy 41.347386 -408.784939) (xy 41.16964 -408.771049) (xy 40.99269 -408.749256) (xy 40.816886 -408.719602)
			(xy 40.642578 -408.682145) (xy 40.470111 -408.636961) (xy 40.299828 -408.584139) (xy 40.132067 -408.523783)
			(xy 39.967162 -408.456015) (xy 39.805439 -408.380967) (xy 39.64722 -408.29879) (xy 39.492819 -408.209647)
			(xy 39.342542 -408.113713) (xy 39.196687 -408.011181) (xy 39.055545 -407.902253) (xy 38.919396 -407.787146)
			(xy 38.788509 -407.666088) (xy 38.663145 -407.539319) (xy 38.543552 -407.407092) (xy 38.429969 -407.269669)
			(xy 38.32262 -407.127322) (xy 38.221719 -406.980334) (xy 38.127466 -406.828998) (xy 38.040048 -406.673613)
			(xy 37.959638 -406.514488) (xy 37.886397 -406.351939) (xy 37.82047 -406.186289) (xy 37.761987 -406.017867)
			(xy 37.711065 -405.847006) (xy 37.667805 -405.674047) (xy 37.632293 -405.499332) (xy 37.604599 -405.323208)
			(xy 37.584778 -405.146026) (xy 37.57287 -404.968137) (xy 37.568898 -404.789894) (xy 3.30962 -404.789894)
			(xy 6.274054 -407.754328) (xy 6.323479 -407.804444) (xy 6.417291 -407.909404) (xy 6.50507 -408.019459)
			(xy 6.58654 -408.134261) (xy 6.661445 -408.253452) (xy 6.72955 -408.376654) (xy 6.79064 -408.503481)
			(xy 6.844523 -408.633534) (xy 6.891029 -408.766403) (xy 6.930013 -408.901671) (xy 6.961351 -409.038912)
			(xy 6.984945 -409.177694) (xy 7.00072 -409.31758) (xy 7.008628 -409.458131) (xy 7.00913 -409.528518)
			(xy 7.00913 -409.563824) (xy 102.192836 -409.563824) (xy 102.192836 -408.700224) (xy 102.193322 -408.672955)
			(xy 102.201084 -408.618971) (xy 102.216449 -408.566641) (xy 102.239106 -408.517031) (xy 102.268592 -408.47115)
			(xy 102.304307 -408.429933) (xy 102.345524 -408.394218) (xy 102.391405 -408.364732) (xy 102.441015 -408.342075)
			(xy 102.493345 -408.32671) (xy 102.547329 -408.318948) (xy 102.601867 -408.318948) (xy 102.655851 -408.32671)
			(xy 102.708181 -408.342075) (xy 102.757791 -408.364732) (xy 102.803672 -408.394218) (xy 102.844889 -408.429933)
			(xy 102.880604 -408.47115) (xy 102.91009 -408.517031) (xy 102.932747 -408.566641) (xy 102.948112 -408.618971)
			(xy 102.955874 -408.672955) (xy 102.95636 -408.700224) (xy 102.95636 -409.563824) (xy 102.955874 -409.591093)
			(xy 102.948112 -409.645077) (xy 102.932747 -409.697407) (xy 102.91009 -409.747017) (xy 102.880604 -409.792898)
			(xy 102.844889 -409.834115) (xy 102.803672 -409.86983) (xy 102.757791 -409.899316) (xy 102.748244 -409.903676)
			(xy 110.559596 -409.903676) (xy 110.559596 -409.040076) (xy 110.560082 -409.012825) (xy 110.567838 -408.958877)
			(xy 110.583193 -408.906582) (xy 110.605835 -408.857005) (xy 110.635301 -408.811155) (xy 110.670992 -408.769964)
			(xy 110.712183 -408.734273) (xy 110.758033 -408.704807) (xy 110.80761 -408.682165) (xy 110.859905 -408.66681)
			(xy 110.913853 -408.659054) (xy 110.968355 -408.659054) (xy 111.022303 -408.66681) (xy 111.074598 -408.682165)
			(xy 111.124175 -408.704807) (xy 111.170025 -408.734273) (xy 111.211216 -408.769964) (xy 111.246907 -408.811155)
			(xy 111.276373 -408.857005) (xy 111.299015 -408.906582) (xy 111.31437 -408.958877) (xy 111.322126 -409.012825)
			(xy 111.322612 -409.040076) (xy 111.322612 -409.903676) (xy 111.322126 -409.930927) (xy 111.31437 -409.984875)
			(xy 111.299015 -410.03717) (xy 111.28975 -410.057456) (xy 116.044623 -410.057456) (xy 116.044623 -410.002944)
			(xy 116.052381 -409.948986) (xy 116.06774 -409.896681) (xy 116.090386 -409.847095) (xy 116.119859 -409.801237)
			(xy 116.155559 -409.76004) (xy 116.196758 -409.724344) (xy 116.242618 -409.694874) (xy 116.292206 -409.672231)
			(xy 116.344511 -409.656876) (xy 116.39847 -409.649121) (xy 116.425726 -409.64866) (xy 117.289326 -409.64866)
			(xy 117.316574 -409.649212) (xy 117.370514 -409.656971) (xy 117.422801 -409.672327) (xy 117.472371 -409.694968)
			(xy 117.518214 -409.724432) (xy 117.559398 -409.760121) (xy 117.595084 -409.801307) (xy 117.624545 -409.847152)
			(xy 117.647182 -409.896723) (xy 117.662535 -409.949011) (xy 117.67029 -410.002952) (xy 117.67029 -410.057448)
			(xy 117.670289 -410.057452) (xy 119.107946 -410.057452) (xy 119.107946 -410.002948) (xy 119.115702 -409.948999)
			(xy 119.131057 -409.896702) (xy 119.153697 -409.847123) (xy 119.183163 -409.801271) (xy 119.218854 -409.760078)
			(xy 119.260043 -409.724383) (xy 119.305893 -409.694914) (xy 119.35547 -409.672269) (xy 119.407765 -409.656909)
			(xy 119.461714 -409.649148) (xy 119.488966 -409.64866) (xy 120.352566 -409.64866) (xy 120.379818 -409.649185)
			(xy 120.433768 -409.656937) (xy 120.486066 -409.672289) (xy 120.535646 -409.694928) (xy 120.5815 -409.724392)
			(xy 120.622693 -409.760083) (xy 120.658387 -409.801273) (xy 120.687856 -409.847124) (xy 120.710499 -409.896702)
			(xy 120.725855 -409.948999) (xy 120.733613 -410.002948) (xy 120.733613 -410.057452) (xy 120.733613 -410.057455)
			(xy 122.171123 -410.057455) (xy 122.171123 -410.002945) (xy 122.178881 -409.948989) (xy 122.194238 -409.896686)
			(xy 122.216883 -409.847101) (xy 122.246354 -409.801244) (xy 122.282052 -409.760047) (xy 122.323249 -409.724351)
			(xy 122.369106 -409.69488) (xy 122.418691 -409.672236) (xy 122.470994 -409.656879) (xy 122.524951 -409.649123)
			(xy 122.552206 -409.64866) (xy 123.415806 -409.64866) (xy 123.443055 -409.649211) (xy 123.496997 -409.656967)
			(xy 123.549287 -409.672321) (xy 123.598859 -409.694961) (xy 123.644705 -409.724425) (xy 123.685891 -409.760113)
			(xy 123.721579 -409.8013) (xy 123.751042 -409.847146) (xy 123.773681 -409.896719) (xy 123.789034 -409.949009)
			(xy 123.79679 -410.002951) (xy 123.79679 -410.057449) (xy 123.796789 -410.057457) (xy 125.234323 -410.057457)
			(xy 125.234323 -410.002943) (xy 125.242082 -409.948983) (xy 125.257442 -409.896677) (xy 125.280089 -409.84709)
			(xy 125.309564 -409.801231) (xy 125.345266 -409.760033) (xy 125.386467 -409.724337) (xy 125.43233 -409.694867)
			(xy 125.48192 -409.672225) (xy 125.534228 -409.656872) (xy 125.588189 -409.64912) (xy 125.615446 -409.64866)
			(xy 126.479046 -409.64866) (xy 126.506293 -409.649213) (xy 126.560231 -409.656975) (xy 126.612516 -409.672332)
			(xy 126.662083 -409.694974) (xy 126.707924 -409.724439) (xy 126.749105 -409.760128) (xy 126.784788 -409.801313)
			(xy 126.814248 -409.847157) (xy 126.836884 -409.896727) (xy 126.852235 -409.949014) (xy 126.85999 -410.002953)
			(xy 126.85999 -410.057447) (xy 126.859989 -410.057453) (xy 128.297646 -410.057453) (xy 128.297646 -410.002947)
			(xy 128.305403 -409.948996) (xy 128.320758 -409.896698) (xy 128.3434 -409.847118) (xy 128.372868 -409.801264)
			(xy 128.408561 -409.760071) (xy 128.449753 -409.724376) (xy 128.495605 -409.694907) (xy 128.545185 -409.672263)
			(xy 128.597482 -409.656906) (xy 128.651433 -409.649147) (xy 128.678686 -409.64866) (xy 129.542286 -409.64866)
			(xy 129.569537 -409.649186) (xy 129.623485 -409.656941) (xy 129.67578 -409.672295) (xy 129.725358 -409.694934)
			(xy 129.771209 -409.724399) (xy 129.8124 -409.76009) (xy 129.848092 -409.80128) (xy 129.877559 -409.84713)
			(xy 129.900201 -409.896707) (xy 129.915556 -409.949001) (xy 129.923313 -410.002949) (xy 129.923313 -410.057451)
			(xy 129.923312 -410.057456) (xy 131.360823 -410.057456) (xy 131.360823 -410.002944) (xy 131.368581 -409.948986)
			(xy 131.38394 -409.896681) (xy 131.406586 -409.847095) (xy 131.436059 -409.801237) (xy 131.471759 -409.76004)
			(xy 131.512958 -409.724344) (xy 131.558818 -409.694874) (xy 131.608406 -409.672231) (xy 131.660711 -409.656876)
			(xy 131.71467 -409.649121) (xy 131.741926 -409.64866) (xy 132.605526 -409.64866) (xy 132.632774 -409.649212)
			(xy 132.686714 -409.656971) (xy 132.739001 -409.672327) (xy 132.788571 -409.694968) (xy 132.834414 -409.724432)
			(xy 132.875598 -409.760121) (xy 132.911284 -409.801307) (xy 132.940745 -409.847152) (xy 132.963382 -409.896723)
			(xy 132.978735 -409.949011) (xy 132.98649 -410.002952) (xy 132.98649 -410.057448) (xy 132.986489 -410.057452)
			(xy 134.424146 -410.057452) (xy 134.424146 -410.002948) (xy 134.431902 -409.948999) (xy 134.447257 -409.896702)
			(xy 134.469897 -409.847123) (xy 134.499363 -409.801271) (xy 134.535054 -409.760078) (xy 134.576243 -409.724383)
			(xy 134.622093 -409.694914) (xy 134.67167 -409.672269) (xy 134.723965 -409.656909) (xy 134.777914 -409.649148)
			(xy 134.805166 -409.64866) (xy 135.668766 -409.64866) (xy 135.696018 -409.649185) (xy 135.749968 -409.656937)
			(xy 135.802266 -409.672289) (xy 135.851846 -409.694928) (xy 135.8977 -409.724392) (xy 135.938893 -409.760083)
			(xy 135.974587 -409.801273) (xy 136.004056 -409.847124) (xy 136.026699 -409.896702) (xy 136.042055 -409.948999)
			(xy 136.049813 -410.002948) (xy 136.049813 -410.057452) (xy 136.049813 -410.057455) (xy 137.487323 -410.057455)
			(xy 137.487323 -410.002945) (xy 137.495081 -409.948989) (xy 137.510438 -409.896686) (xy 137.533083 -409.847101)
			(xy 137.562554 -409.801244) (xy 137.598252 -409.760047) (xy 137.639449 -409.724351) (xy 137.685306 -409.69488)
			(xy 137.734891 -409.672236) (xy 137.787194 -409.656879) (xy 137.841151 -409.649123) (xy 137.868406 -409.64866)
			(xy 138.732006 -409.64866) (xy 138.759255 -409.649211) (xy 138.813197 -409.656967) (xy 138.865487 -409.672321)
			(xy 138.915059 -409.694961) (xy 138.960905 -409.724425) (xy 139.002091 -409.760113) (xy 139.037779 -409.8013)
			(xy 139.067242 -409.847146) (xy 139.089881 -409.896719) (xy 139.105234 -409.949009) (xy 139.11299 -410.002951)
			(xy 139.11299 -410.057449) (xy 139.112989 -410.057457) (xy 140.550523 -410.057457) (xy 140.550523 -410.002943)
			(xy 140.558282 -409.948983) (xy 140.573642 -409.896677) (xy 140.596289 -409.84709) (xy 140.625764 -409.801231)
			(xy 140.661466 -409.760033) (xy 140.702667 -409.724337) (xy 140.74853 -409.694867) (xy 140.79812 -409.672225)
			(xy 140.850428 -409.656872) (xy 140.904389 -409.64912) (xy 140.931646 -409.64866) (xy 141.795246 -409.64866)
			(xy 141.822493 -409.649213) (xy 141.876431 -409.656975) (xy 141.928716 -409.672332) (xy 141.978283 -409.694974)
			(xy 142.024124 -409.724439) (xy 142.065305 -409.760128) (xy 142.100988 -409.801313) (xy 142.130448 -409.847157)
			(xy 142.153084 -409.896727) (xy 142.168435 -409.949014) (xy 142.17619 -410.002953) (xy 142.17619 -410.057447)
			(xy 142.176189 -410.057453) (xy 143.613846 -410.057453) (xy 143.613846 -410.002947) (xy 143.621603 -409.948996)
			(xy 143.636958 -409.896698) (xy 143.6596 -409.847118) (xy 143.689068 -409.801264) (xy 143.724761 -409.760071)
			(xy 143.765953 -409.724376) (xy 143.811805 -409.694907) (xy 143.861385 -409.672263) (xy 143.913682 -409.656906)
			(xy 143.967633 -409.649147) (xy 143.994886 -409.64866) (xy 144.858486 -409.64866) (xy 144.885737 -409.649186)
			(xy 144.939685 -409.656941) (xy 144.99198 -409.672295) (xy 145.041558 -409.694934) (xy 145.087409 -409.724399)
			(xy 145.1286 -409.76009) (xy 145.164292 -409.80128) (xy 145.193759 -409.84713) (xy 145.216401 -409.896707)
			(xy 145.231756 -409.949001) (xy 145.239513 -410.002949) (xy 145.239513 -410.057451) (xy 145.239512 -410.057456)
			(xy 146.677023 -410.057456) (xy 146.677023 -410.002944) (xy 146.684781 -409.948986) (xy 146.70014 -409.896681)
			(xy 146.722786 -409.847095) (xy 146.752259 -409.801237) (xy 146.787959 -409.76004) (xy 146.829158 -409.724344)
			(xy 146.875018 -409.694874) (xy 146.924606 -409.672231) (xy 146.976911 -409.656876) (xy 147.03087 -409.649121)
			(xy 147.058126 -409.64866) (xy 147.921726 -409.64866) (xy 147.948974 -409.649212) (xy 148.002914 -409.656971)
			(xy 148.055201 -409.672327) (xy 148.104771 -409.694968) (xy 148.150614 -409.724432) (xy 148.191798 -409.760121)
			(xy 148.227484 -409.801307) (xy 148.256945 -409.847152) (xy 148.279582 -409.896723) (xy 148.294935 -409.949011)
			(xy 148.30269 -410.002952) (xy 148.30269 -410.057448) (xy 148.302689 -410.057452) (xy 149.740346 -410.057452)
			(xy 149.740346 -410.002948) (xy 149.748102 -409.948999) (xy 149.763457 -409.896702) (xy 149.786097 -409.847123)
			(xy 149.815563 -409.801271) (xy 149.851254 -409.760078) (xy 149.892443 -409.724383) (xy 149.938293 -409.694914)
			(xy 149.98787 -409.672269) (xy 150.040165 -409.656909) (xy 150.094114 -409.649148) (xy 150.121366 -409.64866)
			(xy 150.984966 -409.64866) (xy 151.012218 -409.649185) (xy 151.066168 -409.656937) (xy 151.118466 -409.672289)
			(xy 151.168046 -409.694928) (xy 151.2139 -409.724392) (xy 151.255093 -409.760083) (xy 151.290787 -409.801273)
			(xy 151.320256 -409.847124) (xy 151.342899 -409.896702) (xy 151.358255 -409.948999) (xy 151.366013 -410.002948)
			(xy 151.366013 -410.057452) (xy 151.366013 -410.057455) (xy 152.803523 -410.057455) (xy 152.803523 -410.002945)
			(xy 152.811281 -409.948989) (xy 152.826638 -409.896686) (xy 152.849283 -409.847101) (xy 152.878754 -409.801244)
			(xy 152.914452 -409.760047) (xy 152.955649 -409.724351) (xy 153.001506 -409.69488) (xy 153.051091 -409.672236)
			(xy 153.103394 -409.656879) (xy 153.157351 -409.649123) (xy 153.184606 -409.64866) (xy 154.048206 -409.64866)
			(xy 154.075455 -409.649211) (xy 154.129397 -409.656967) (xy 154.181687 -409.672321) (xy 154.231259 -409.694961)
			(xy 154.277105 -409.724425) (xy 154.318291 -409.760113) (xy 154.353979 -409.8013) (xy 154.383442 -409.847146)
			(xy 154.406081 -409.896719) (xy 154.421434 -409.949009) (xy 154.42919 -410.002951) (xy 154.42919 -410.057449)
			(xy 154.429189 -410.057457) (xy 155.866723 -410.057457) (xy 155.866723 -410.002943) (xy 155.874482 -409.948983)
			(xy 155.889842 -409.896677) (xy 155.912489 -409.84709) (xy 155.941964 -409.801231) (xy 155.977666 -409.760033)
			(xy 156.018867 -409.724337) (xy 156.06473 -409.694867) (xy 156.11432 -409.672225) (xy 156.166628 -409.656872)
			(xy 156.220589 -409.64912) (xy 156.247846 -409.64866) (xy 157.111446 -409.64866) (xy 157.138693 -409.649213)
			(xy 157.192631 -409.656975) (xy 157.244916 -409.672332) (xy 157.294483 -409.694974) (xy 157.340324 -409.724439)
			(xy 157.381505 -409.760128) (xy 157.417188 -409.801313) (xy 157.446648 -409.847157) (xy 157.469284 -409.896727)
			(xy 157.484635 -409.949014) (xy 157.49239 -410.002953) (xy 157.49239 -410.057447) (xy 157.492389 -410.057453)
			(xy 158.930046 -410.057453) (xy 158.930046 -410.002947) (xy 158.937803 -409.948996) (xy 158.953158 -409.896698)
			(xy 158.9758 -409.847118) (xy 159.005268 -409.801264) (xy 159.040961 -409.760071) (xy 159.082153 -409.724376)
			(xy 159.128005 -409.694907) (xy 159.177585 -409.672263) (xy 159.229882 -409.656906) (xy 159.283833 -409.649147)
			(xy 159.311086 -409.64866) (xy 160.174686 -409.64866) (xy 160.201937 -409.649186) (xy 160.255885 -409.656941)
			(xy 160.30818 -409.672295) (xy 160.357758 -409.694934) (xy 160.403609 -409.724399) (xy 160.4448 -409.76009)
			(xy 160.480492 -409.80128) (xy 160.509959 -409.84713) (xy 160.532601 -409.896707) (xy 160.547956 -409.949001)
			(xy 160.555713 -410.002949) (xy 160.555713 -410.057451) (xy 160.555712 -410.057456) (xy 161.993223 -410.057456)
			(xy 161.993223 -410.002944) (xy 162.000981 -409.948986) (xy 162.01634 -409.896681) (xy 162.038986 -409.847095)
			(xy 162.068459 -409.801237) (xy 162.104159 -409.76004) (xy 162.145358 -409.724344) (xy 162.191218 -409.694874)
			(xy 162.240806 -409.672231) (xy 162.293111 -409.656876) (xy 162.34707 -409.649121) (xy 162.374326 -409.64866)
			(xy 163.237926 -409.64866) (xy 163.265174 -409.649212) (xy 163.319114 -409.656971) (xy 163.371401 -409.672327)
			(xy 163.420971 -409.694968) (xy 163.466814 -409.724432) (xy 163.507998 -409.760121) (xy 163.543684 -409.801307)
			(xy 163.573145 -409.847152) (xy 163.595782 -409.896723) (xy 163.611135 -409.949011) (xy 163.61889 -410.002952)
			(xy 163.61889 -410.057448) (xy 163.611135 -410.111389) (xy 163.595782 -410.163677) (xy 163.573145 -410.213248)
			(xy 163.543684 -410.259093) (xy 163.507998 -410.300279) (xy 163.466814 -410.335968) (xy 163.420971 -410.365432)
			(xy 163.371401 -410.388073) (xy 163.319114 -410.403429) (xy 163.265174 -410.411188) (xy 163.237926 -410.411676)
			(xy 162.374326 -410.411676) (xy 162.34707 -410.411279) (xy 162.293111 -410.403524) (xy 162.240806 -410.388169)
			(xy 162.191218 -410.365526) (xy 162.145358 -410.336056) (xy 162.104159 -410.30036) (xy 162.068459 -410.259163)
			(xy 162.038986 -410.213305) (xy 162.01634 -410.163719) (xy 162.000981 -410.111414) (xy 161.993223 -410.057456)
			(xy 160.555712 -410.057456) (xy 160.547956 -410.111399) (xy 160.532601 -410.163693) (xy 160.509959 -410.21327)
			(xy 160.480492 -410.25912) (xy 160.4448 -410.30031) (xy 160.403609 -410.336001) (xy 160.357758 -410.365466)
			(xy 160.30818 -410.388105) (xy 160.255885 -410.403459) (xy 160.201937 -410.411214) (xy 160.174686 -410.411676)
			(xy 159.311086 -410.411676) (xy 159.283833 -410.411253) (xy 159.229882 -410.403494) (xy 159.177585 -410.388137)
			(xy 159.128005 -410.365493) (xy 159.082153 -410.336024) (xy 159.040961 -410.300329) (xy 159.005268 -410.259136)
			(xy 158.9758 -410.213282) (xy 158.953158 -410.163702) (xy 158.937803 -410.111404) (xy 158.930046 -410.057453)
			(xy 157.492389 -410.057453) (xy 157.484635 -410.111386) (xy 157.469284 -410.163673) (xy 157.446648 -410.213243)
			(xy 157.417188 -410.259087) (xy 157.381505 -410.300272) (xy 157.340324 -410.335961) (xy 157.294483 -410.365426)
			(xy 157.244916 -410.388068) (xy 157.192631 -410.403425) (xy 157.138693 -410.411187) (xy 157.111446 -410.411676)
			(xy 156.247846 -410.411676) (xy 156.220589 -410.41128) (xy 156.166628 -410.403528) (xy 156.11432 -410.388175)
			(xy 156.06473 -410.365533) (xy 156.018867 -410.336063) (xy 155.977666 -410.300367) (xy 155.941964 -410.259169)
			(xy 155.912489 -410.21331) (xy 155.889842 -410.163723) (xy 155.874482 -410.111417) (xy 155.866723 -410.057457)
			(xy 154.429189 -410.057457) (xy 154.421434 -410.111391) (xy 154.406081 -410.163681) (xy 154.383442 -410.213254)
			(xy 154.353979 -410.2591) (xy 154.318291 -410.300287) (xy 154.277105 -410.335975) (xy 154.231259 -410.365439)
			(xy 154.181687 -410.388079) (xy 154.129397 -410.403433) (xy 154.075455 -410.411189) (xy 154.048206 -410.411676)
			(xy 153.184606 -410.411676) (xy 153.157351 -410.411277) (xy 153.103394 -410.403521) (xy 153.051091 -410.388164)
			(xy 153.001506 -410.36552) (xy 152.955649 -410.336049) (xy 152.914452 -410.300353) (xy 152.878754 -410.259156)
			(xy 152.849283 -410.213299) (xy 152.826638 -410.163714) (xy 152.811281 -410.111411) (xy 152.803523 -410.057455)
			(xy 151.366013 -410.057455) (xy 151.358255 -410.111402) (xy 151.342899 -410.163698) (xy 151.320256 -410.213276)
			(xy 151.290787 -410.259127) (xy 151.255093 -410.300317) (xy 151.2139 -410.336008) (xy 151.168046 -410.365472)
			(xy 151.118466 -410.388111) (xy 151.066168 -410.403463) (xy 151.012218 -410.411215) (xy 150.984966 -410.411676)
			(xy 150.121366 -410.411676) (xy 150.094114 -410.411252) (xy 150.040165 -410.403491) (xy 149.98787 -410.388131)
			(xy 149.938293 -410.365486) (xy 149.892443 -410.336017) (xy 149.851254 -410.300322) (xy 149.815563 -410.259129)
			(xy 149.786097 -410.213277) (xy 149.763457 -410.163698) (xy 149.748102 -410.111401) (xy 149.740346 -410.057452)
			(xy 148.302689 -410.057452) (xy 148.294935 -410.111389) (xy 148.279582 -410.163677) (xy 148.256945 -410.213248)
			(xy 148.227484 -410.259093) (xy 148.191798 -410.300279) (xy 148.150614 -410.335968) (xy 148.104771 -410.365432)
			(xy 148.055201 -410.388073) (xy 148.002914 -410.403429) (xy 147.948974 -410.411188) (xy 147.921726 -410.411676)
			(xy 147.058126 -410.411676) (xy 147.03087 -410.411279) (xy 146.976911 -410.403524) (xy 146.924606 -410.388169)
			(xy 146.875018 -410.365526) (xy 146.829158 -410.336056) (xy 146.787959 -410.30036) (xy 146.752259 -410.259163)
			(xy 146.722786 -410.213305) (xy 146.70014 -410.163719) (xy 146.684781 -410.111414) (xy 146.677023 -410.057456)
			(xy 145.239512 -410.057456) (xy 145.231756 -410.111399) (xy 145.216401 -410.163693) (xy 145.193759 -410.21327)
			(xy 145.164292 -410.25912) (xy 145.1286 -410.30031) (xy 145.087409 -410.336001) (xy 145.041558 -410.365466)
			(xy 144.99198 -410.388105) (xy 144.939685 -410.403459) (xy 144.885737 -410.411214) (xy 144.858486 -410.411676)
			(xy 143.994886 -410.411676) (xy 143.967633 -410.411253) (xy 143.913682 -410.403494) (xy 143.861385 -410.388137)
			(xy 143.811805 -410.365493) (xy 143.765953 -410.336024) (xy 143.724761 -410.300329) (xy 143.689068 -410.259136)
			(xy 143.6596 -410.213282) (xy 143.636958 -410.163702) (xy 143.621603 -410.111404) (xy 143.613846 -410.057453)
			(xy 142.176189 -410.057453) (xy 142.168435 -410.111386) (xy 142.153084 -410.163673) (xy 142.130448 -410.213243)
			(xy 142.100988 -410.259087) (xy 142.065305 -410.300272) (xy 142.024124 -410.335961) (xy 141.978283 -410.365426)
			(xy 141.928716 -410.388068) (xy 141.876431 -410.403425) (xy 141.822493 -410.411187) (xy 141.795246 -410.411676)
			(xy 140.931646 -410.411676) (xy 140.904389 -410.41128) (xy 140.850428 -410.403528) (xy 140.79812 -410.388175)
			(xy 140.74853 -410.365533) (xy 140.702667 -410.336063) (xy 140.661466 -410.300367) (xy 140.625764 -410.259169)
			(xy 140.596289 -410.21331) (xy 140.573642 -410.163723) (xy 140.558282 -410.111417) (xy 140.550523 -410.057457)
			(xy 139.112989 -410.057457) (xy 139.105234 -410.111391) (xy 139.089881 -410.163681) (xy 139.067242 -410.213254)
			(xy 139.037779 -410.2591) (xy 139.002091 -410.300287) (xy 138.960905 -410.335975) (xy 138.915059 -410.365439)
			(xy 138.865487 -410.388079) (xy 138.813197 -410.403433) (xy 138.759255 -410.411189) (xy 138.732006 -410.411676)
			(xy 137.868406 -410.411676) (xy 137.841151 -410.411277) (xy 137.787194 -410.403521) (xy 137.734891 -410.388164)
			(xy 137.685306 -410.36552) (xy 137.639449 -410.336049) (xy 137.598252 -410.300353) (xy 137.562554 -410.259156)
			(xy 137.533083 -410.213299) (xy 137.510438 -410.163714) (xy 137.495081 -410.111411) (xy 137.487323 -410.057455)
			(xy 136.049813 -410.057455) (xy 136.042055 -410.111402) (xy 136.026699 -410.163698) (xy 136.004056 -410.213276)
			(xy 135.974587 -410.259127) (xy 135.938893 -410.300317) (xy 135.8977 -410.336008) (xy 135.851846 -410.365472)
			(xy 135.802266 -410.388111) (xy 135.749968 -410.403463) (xy 135.696018 -410.411215) (xy 135.668766 -410.411676)
			(xy 134.805166 -410.411676) (xy 134.777914 -410.411252) (xy 134.723965 -410.403491) (xy 134.67167 -410.388131)
			(xy 134.622093 -410.365486) (xy 134.576243 -410.336017) (xy 134.535054 -410.300322) (xy 134.499363 -410.259129)
			(xy 134.469897 -410.213277) (xy 134.447257 -410.163698) (xy 134.431902 -410.111401) (xy 134.424146 -410.057452)
			(xy 132.986489 -410.057452) (xy 132.978735 -410.111389) (xy 132.963382 -410.163677) (xy 132.940745 -410.213248)
			(xy 132.911284 -410.259093) (xy 132.875598 -410.300279) (xy 132.834414 -410.335968) (xy 132.788571 -410.365432)
			(xy 132.739001 -410.388073) (xy 132.686714 -410.403429) (xy 132.632774 -410.411188) (xy 132.605526 -410.411676)
			(xy 131.741926 -410.411676) (xy 131.71467 -410.411279) (xy 131.660711 -410.403524) (xy 131.608406 -410.388169)
			(xy 131.558818 -410.365526) (xy 131.512958 -410.336056) (xy 131.471759 -410.30036) (xy 131.436059 -410.259163)
			(xy 131.406586 -410.213305) (xy 131.38394 -410.163719) (xy 131.368581 -410.111414) (xy 131.360823 -410.057456)
			(xy 129.923312 -410.057456) (xy 129.915556 -410.111399) (xy 129.900201 -410.163693) (xy 129.877559 -410.21327)
			(xy 129.848092 -410.25912) (xy 129.8124 -410.30031) (xy 129.771209 -410.336001) (xy 129.725358 -410.365466)
			(xy 129.67578 -410.388105) (xy 129.623485 -410.403459) (xy 129.569537 -410.411214) (xy 129.542286 -410.411676)
			(xy 128.678686 -410.411676) (xy 128.651433 -410.411253) (xy 128.597482 -410.403494) (xy 128.545185 -410.388137)
			(xy 128.495605 -410.365493) (xy 128.449753 -410.336024) (xy 128.408561 -410.300329) (xy 128.372868 -410.259136)
			(xy 128.3434 -410.213282) (xy 128.320758 -410.163702) (xy 128.305403 -410.111404) (xy 128.297646 -410.057453)
			(xy 126.859989 -410.057453) (xy 126.852235 -410.111386) (xy 126.836884 -410.163673) (xy 126.814248 -410.213243)
			(xy 126.784788 -410.259087) (xy 126.749105 -410.300272) (xy 126.707924 -410.335961) (xy 126.662083 -410.365426)
			(xy 126.612516 -410.388068) (xy 126.560231 -410.403425) (xy 126.506293 -410.411187) (xy 126.479046 -410.411676)
			(xy 125.615446 -410.411676) (xy 125.588189 -410.41128) (xy 125.534228 -410.403528) (xy 125.48192 -410.388175)
			(xy 125.43233 -410.365533) (xy 125.386467 -410.336063) (xy 125.345266 -410.300367) (xy 125.309564 -410.259169)
			(xy 125.280089 -410.21331) (xy 125.257442 -410.163723) (xy 125.242082 -410.111417) (xy 125.234323 -410.057457)
			(xy 123.796789 -410.057457) (xy 123.789034 -410.111391) (xy 123.773681 -410.163681) (xy 123.751042 -410.213254)
			(xy 123.721579 -410.2591) (xy 123.685891 -410.300287) (xy 123.644705 -410.335975) (xy 123.598859 -410.365439)
			(xy 123.549287 -410.388079) (xy 123.496997 -410.403433) (xy 123.443055 -410.411189) (xy 123.415806 -410.411676)
			(xy 122.552206 -410.411676) (xy 122.524951 -410.411277) (xy 122.470994 -410.403521) (xy 122.418691 -410.388164)
			(xy 122.369106 -410.36552) (xy 122.323249 -410.336049) (xy 122.282052 -410.300353) (xy 122.246354 -410.259156)
			(xy 122.216883 -410.213299) (xy 122.194238 -410.163714) (xy 122.178881 -410.111411) (xy 122.171123 -410.057455)
			(xy 120.733613 -410.057455) (xy 120.725855 -410.111402) (xy 120.710499 -410.163698) (xy 120.687856 -410.213276)
			(xy 120.658387 -410.259127) (xy 120.622693 -410.300317) (xy 120.5815 -410.336008) (xy 120.535646 -410.365472)
			(xy 120.486066 -410.388111) (xy 120.433768 -410.403463) (xy 120.379818 -410.411215) (xy 120.352566 -410.411676)
			(xy 119.488966 -410.411676) (xy 119.461714 -410.411252) (xy 119.407765 -410.403491) (xy 119.35547 -410.388131)
			(xy 119.305893 -410.365486) (xy 119.260043 -410.336017) (xy 119.218854 -410.300322) (xy 119.183163 -410.259129)
			(xy 119.153697 -410.213277) (xy 119.131057 -410.163698) (xy 119.115702 -410.111401) (xy 119.107946 -410.057452)
			(xy 117.670289 -410.057452) (xy 117.662535 -410.111389) (xy 117.647182 -410.163677) (xy 117.624545 -410.213248)
			(xy 117.595084 -410.259093) (xy 117.559398 -410.300279) (xy 117.518214 -410.335968) (xy 117.472371 -410.365432)
			(xy 117.422801 -410.388073) (xy 117.370514 -410.403429) (xy 117.316574 -410.411188) (xy 117.289326 -410.411676)
			(xy 116.425726 -410.411676) (xy 116.39847 -410.411279) (xy 116.344511 -410.403524) (xy 116.292206 -410.388169)
			(xy 116.242618 -410.365526) (xy 116.196758 -410.336056) (xy 116.155559 -410.30036) (xy 116.119859 -410.259163)
			(xy 116.090386 -410.213305) (xy 116.06774 -410.163719) (xy 116.052381 -410.111414) (xy 116.044623 -410.057456)
			(xy 111.28975 -410.057456) (xy 111.276373 -410.086747) (xy 111.246907 -410.132597) (xy 111.211216 -410.173788)
			(xy 111.170025 -410.209479) (xy 111.124175 -410.238945) (xy 111.074598 -410.261587) (xy 111.022303 -410.276942)
			(xy 110.968355 -410.284698) (xy 110.913853 -410.284698) (xy 110.859905 -410.276942) (xy 110.80761 -410.261587)
			(xy 110.758033 -410.238945) (xy 110.712183 -410.209479) (xy 110.670992 -410.173788) (xy 110.635301 -410.132597)
			(xy 110.605835 -410.086747) (xy 110.583193 -410.03717) (xy 110.567838 -409.984875) (xy 110.560082 -409.930927)
			(xy 110.559596 -409.903676) (xy 102.748244 -409.903676) (xy 102.708181 -409.921973) (xy 102.655851 -409.937338)
			(xy 102.601867 -409.9451) (xy 102.547329 -409.9451) (xy 102.493345 -409.937338) (xy 102.441015 -409.921973)
			(xy 102.391405 -409.899316) (xy 102.345524 -409.86983) (xy 102.304307 -409.834115) (xy 102.268592 -409.792898)
			(xy 102.239106 -409.747017) (xy 102.216449 -409.697407) (xy 102.201084 -409.645077) (xy 102.193322 -409.591093)
			(xy 102.192836 -409.563824) (xy 7.00913 -409.563824) (xy 7.00913 -410.057453) (xy 48.944746 -410.057453)
			(xy 48.944746 -410.002947) (xy 48.952503 -409.948996) (xy 48.967858 -409.896698) (xy 48.9905 -409.847118)
			(xy 49.019967 -409.801265) (xy 49.05566 -409.760071) (xy 49.096852 -409.724377) (xy 49.142704 -409.694908)
			(xy 49.192283 -409.672264) (xy 49.244581 -409.656906) (xy 49.298531 -409.649147) (xy 49.325784 -409.64866)
			(xy 50.189384 -409.64866) (xy 50.216635 -409.649186) (xy 50.270583 -409.656941) (xy 50.322879 -409.672294)
			(xy 50.372457 -409.694934) (xy 50.418308 -409.724399) (xy 50.459499 -409.760089) (xy 50.495192 -409.801279)
			(xy 50.524659 -409.847129) (xy 50.5473 -409.896706) (xy 50.562656 -409.949001) (xy 50.570413 -410.002949)
			(xy 50.570413 -410.057451) (xy 50.570412 -410.057456) (xy 52.007923 -410.057456) (xy 52.007923 -410.002944)
			(xy 52.015681 -409.948986) (xy 52.03104 -409.896682) (xy 52.053686 -409.847096) (xy 52.083159 -409.801238)
			(xy 52.118858 -409.760041) (xy 52.160057 -409.724344) (xy 52.205917 -409.694874) (xy 52.255504 -409.672231)
			(xy 52.30781 -409.656876) (xy 52.361768 -409.649121) (xy 52.389024 -409.64866) (xy 53.252624 -409.64866)
			(xy 53.279872 -409.649212) (xy 53.333812 -409.65697) (xy 53.3861 -409.672326) (xy 53.43567 -409.694967)
			(xy 53.481513 -409.724431) (xy 53.522697 -409.76012) (xy 53.558383 -409.801306) (xy 53.587845 -409.847151)
			(xy 53.610482 -409.896723) (xy 53.625835 -409.949011) (xy 53.63359 -410.002952) (xy 53.63359 -410.057448)
			(xy 53.633589 -410.057452) (xy 55.071246 -410.057452) (xy 55.071246 -410.002948) (xy 55.079002 -409.948999)
			(xy 55.094357 -409.896703) (xy 55.116997 -409.847124) (xy 55.146462 -409.801271) (xy 55.182153 -409.760079)
			(xy 55.223342 -409.724384) (xy 55.269192 -409.694914) (xy 55.318769 -409.672269) (xy 55.371064 -409.65691)
			(xy 55.425012 -409.649148) (xy 55.452264 -409.64866) (xy 56.315864 -409.64866) (xy 56.343116 -409.649185)
			(xy 56.397067 -409.656937) (xy 56.449364 -409.672289) (xy 56.498945 -409.694927) (xy 56.544799 -409.724392)
			(xy 56.585992 -409.760082) (xy 56.621687 -409.801273) (xy 56.651156 -409.847124) (xy 56.673799 -409.896702)
			(xy 56.689155 -409.948998) (xy 56.696913 -410.002948) (xy 56.696913 -410.057452) (xy 56.696913 -410.057455)
			(xy 58.134423 -410.057455) (xy 58.134423 -410.002945) (xy 58.142181 -409.948989) (xy 58.157538 -409.896686)
			(xy 58.180183 -409.847102) (xy 58.209654 -409.801244) (xy 58.245351 -409.760048) (xy 58.286548 -409.724351)
			(xy 58.332405 -409.694881) (xy 58.38199 -409.672237) (xy 58.434293 -409.65688) (xy 58.488249 -409.649123)
			(xy 58.515504 -409.64866) (xy 59.379104 -409.64866) (xy 59.406353 -409.64921) (xy 59.460295 -409.656967)
			(xy 59.512585 -409.672321) (xy 59.562158 -409.69496) (xy 59.608004 -409.724424) (xy 59.64919 -409.760113)
			(xy 59.684878 -409.801299) (xy 59.714342 -409.847146) (xy 59.73698 -409.896718) (xy 59.752334 -409.949008)
			(xy 59.76009 -410.002951) (xy 59.76009 -410.057449) (xy 59.760089 -410.057457) (xy 61.197623 -410.057457)
			(xy 61.197623 -410.002943) (xy 61.205382 -409.948983) (xy 61.220741 -409.896678) (xy 61.243389 -409.84709)
			(xy 61.272864 -409.801231) (xy 61.308565 -409.760034) (xy 61.349767 -409.724337) (xy 61.395629 -409.694868)
			(xy 61.445219 -409.672226) (xy 61.497527 -409.656872) (xy 61.551487 -409.64912) (xy 61.578744 -409.64866)
			(xy 62.442344 -409.64866) (xy 62.469591 -409.649213) (xy 62.523529 -409.656974) (xy 62.575814 -409.672332)
			(xy 62.625382 -409.694973) (xy 62.671223 -409.724438) (xy 62.712404 -409.760127) (xy 62.748088 -409.801313)
			(xy 62.777548 -409.847157) (xy 62.800184 -409.896727) (xy 62.815535 -409.949014) (xy 62.82329 -410.002953)
			(xy 62.82329 -410.057447) (xy 62.823289 -410.057453) (xy 64.260946 -410.057453) (xy 64.260946 -410.002947)
			(xy 64.268703 -409.948996) (xy 64.284058 -409.896698) (xy 64.3067 -409.847118) (xy 64.336167 -409.801265)
			(xy 64.37186 -409.760071) (xy 64.413052 -409.724377) (xy 64.458904 -409.694908) (xy 64.508483 -409.672264)
			(xy 64.560781 -409.656906) (xy 64.614731 -409.649147) (xy 64.641984 -409.64866) (xy 65.505584 -409.64866)
			(xy 65.532835 -409.649186) (xy 65.586783 -409.656941) (xy 65.639079 -409.672294) (xy 65.688657 -409.694934)
			(xy 65.734508 -409.724399) (xy 65.775699 -409.760089) (xy 65.811392 -409.801279) (xy 65.840859 -409.847129)
			(xy 65.8635 -409.896706) (xy 65.878856 -409.949001) (xy 65.886613 -410.002949) (xy 65.886613 -410.057451)
			(xy 65.886612 -410.057456) (xy 67.324123 -410.057456) (xy 67.324123 -410.002944) (xy 67.331881 -409.948986)
			(xy 67.34724 -409.896682) (xy 67.369886 -409.847096) (xy 67.399359 -409.801238) (xy 67.435058 -409.760041)
			(xy 67.476257 -409.724344) (xy 67.522117 -409.694874) (xy 67.571704 -409.672231) (xy 67.62401 -409.656876)
			(xy 67.677968 -409.649121) (xy 67.705224 -409.64866) (xy 68.568824 -409.64866) (xy 68.596072 -409.649212)
			(xy 68.650012 -409.65697) (xy 68.7023 -409.672326) (xy 68.75187 -409.694967) (xy 68.797713 -409.724431)
			(xy 68.838897 -409.76012) (xy 68.874583 -409.801306) (xy 68.904045 -409.847151) (xy 68.926682 -409.896723)
			(xy 68.942035 -409.949011) (xy 68.94979 -410.002952) (xy 68.94979 -410.057448) (xy 68.949789 -410.057452)
			(xy 70.387446 -410.057452) (xy 70.387446 -410.002948) (xy 70.395202 -409.948999) (xy 70.410557 -409.896703)
			(xy 70.433197 -409.847124) (xy 70.462662 -409.801271) (xy 70.498353 -409.760079) (xy 70.539542 -409.724384)
			(xy 70.585392 -409.694914) (xy 70.634969 -409.672269) (xy 70.687264 -409.65691) (xy 70.741212 -409.649148)
			(xy 70.768464 -409.64866) (xy 71.632064 -409.64866) (xy 71.659316 -409.649185) (xy 71.713267 -409.656937)
			(xy 71.765564 -409.672289) (xy 71.815145 -409.694927) (xy 71.860999 -409.724392) (xy 71.902192 -409.760082)
			(xy 71.937887 -409.801273) (xy 71.967356 -409.847124) (xy 71.989999 -409.896702) (xy 72.005355 -409.948998)
			(xy 72.013113 -410.002948) (xy 72.013113 -410.057452) (xy 72.013113 -410.057455) (xy 73.450623 -410.057455)
			(xy 73.450623 -410.002945) (xy 73.458381 -409.948989) (xy 73.473738 -409.896686) (xy 73.496383 -409.847102)
			(xy 73.525854 -409.801244) (xy 73.561551 -409.760048) (xy 73.602748 -409.724351) (xy 73.648605 -409.694881)
			(xy 73.69819 -409.672237) (xy 73.750493 -409.65688) (xy 73.804449 -409.649123) (xy 73.831704 -409.64866)
			(xy 74.695304 -409.64866) (xy 74.722553 -409.64921) (xy 74.776495 -409.656967) (xy 74.828785 -409.672321)
			(xy 74.878358 -409.69496) (xy 74.924204 -409.724424) (xy 74.96539 -409.760113) (xy 75.001078 -409.801299)
			(xy 75.030542 -409.847146) (xy 75.05318 -409.896718) (xy 75.068534 -409.949008) (xy 75.07629 -410.002951)
			(xy 75.07629 -410.057449) (xy 75.076289 -410.057457) (xy 76.513823 -410.057457) (xy 76.513823 -410.002943)
			(xy 76.521582 -409.948983) (xy 76.536941 -409.896678) (xy 76.559589 -409.84709) (xy 76.589064 -409.801231)
			(xy 76.624765 -409.760034) (xy 76.665967 -409.724337) (xy 76.711829 -409.694868) (xy 76.761419 -409.672226)
			(xy 76.813727 -409.656872) (xy 76.867687 -409.64912) (xy 76.894944 -409.64866) (xy 77.758544 -409.64866)
			(xy 77.785791 -409.649213) (xy 77.839729 -409.656974) (xy 77.892014 -409.672332) (xy 77.941582 -409.694973)
			(xy 77.987423 -409.724438) (xy 78.028604 -409.760127) (xy 78.064288 -409.801313) (xy 78.093748 -409.847157)
			(xy 78.116384 -409.896727) (xy 78.131735 -409.949014) (xy 78.13949 -410.002953) (xy 78.13949 -410.057447)
			(xy 78.139489 -410.057453) (xy 79.577146 -410.057453) (xy 79.577146 -410.002947) (xy 79.584903 -409.948996)
			(xy 79.600258 -409.896698) (xy 79.6229 -409.847118) (xy 79.652367 -409.801265) (xy 79.68806 -409.760071)
			(xy 79.729252 -409.724377) (xy 79.775104 -409.694908) (xy 79.824683 -409.672264) (xy 79.876981 -409.656906)
			(xy 79.930931 -409.649147) (xy 79.958184 -409.64866) (xy 80.821784 -409.64866) (xy 80.849035 -409.649186)
			(xy 80.902983 -409.656941) (xy 80.955279 -409.672294) (xy 81.004857 -409.694934) (xy 81.050708 -409.724399)
			(xy 81.091899 -409.760089) (xy 81.127592 -409.801279) (xy 81.157059 -409.847129) (xy 81.1797 -409.896706)
			(xy 81.195056 -409.949001) (xy 81.202813 -410.002949) (xy 81.202813 -410.057451) (xy 81.202812 -410.057456)
			(xy 82.640323 -410.057456) (xy 82.640323 -410.002944) (xy 82.648081 -409.948986) (xy 82.66344 -409.896682)
			(xy 82.686086 -409.847096) (xy 82.715559 -409.801238) (xy 82.751258 -409.760041) (xy 82.792457 -409.724344)
			(xy 82.838317 -409.694874) (xy 82.887904 -409.672231) (xy 82.94021 -409.656876) (xy 82.994168 -409.649121)
			(xy 83.021424 -409.64866) (xy 83.885024 -409.64866) (xy 83.912272 -409.649212) (xy 83.966212 -409.65697)
			(xy 84.0185 -409.672326) (xy 84.06807 -409.694967) (xy 84.113913 -409.724431) (xy 84.155097 -409.76012)
			(xy 84.190783 -409.801306) (xy 84.220245 -409.847151) (xy 84.242882 -409.896723) (xy 84.258235 -409.949011)
			(xy 84.26599 -410.002952) (xy 84.26599 -410.057448) (xy 84.265989 -410.057452) (xy 85.703646 -410.057452)
			(xy 85.703646 -410.002948) (xy 85.711402 -409.948999) (xy 85.726757 -409.896703) (xy 85.749397 -409.847124)
			(xy 85.778862 -409.801271) (xy 85.814553 -409.760079) (xy 85.855742 -409.724384) (xy 85.901592 -409.694914)
			(xy 85.951169 -409.672269) (xy 86.003464 -409.65691) (xy 86.057412 -409.649148) (xy 86.084664 -409.64866)
			(xy 86.948264 -409.64866) (xy 86.975516 -409.649185) (xy 87.029467 -409.656937) (xy 87.081764 -409.672289)
			(xy 87.131345 -409.694927) (xy 87.177199 -409.724392) (xy 87.218392 -409.760082) (xy 87.254087 -409.801273)
			(xy 87.283556 -409.847124) (xy 87.306199 -409.896702) (xy 87.321555 -409.948998) (xy 87.329313 -410.002948)
			(xy 87.329313 -410.057452) (xy 87.329313 -410.057455) (xy 88.766823 -410.057455) (xy 88.766823 -410.002945)
			(xy 88.774581 -409.948989) (xy 88.789938 -409.896686) (xy 88.812583 -409.847102) (xy 88.842054 -409.801244)
			(xy 88.877751 -409.760048) (xy 88.918948 -409.724351) (xy 88.964805 -409.694881) (xy 89.01439 -409.672237)
			(xy 89.066693 -409.65688) (xy 89.120649 -409.649123) (xy 89.147904 -409.64866) (xy 90.011504 -409.64866)
			(xy 90.038753 -409.64921) (xy 90.092695 -409.656967) (xy 90.144985 -409.672321) (xy 90.194558 -409.69496)
			(xy 90.240404 -409.724424) (xy 90.28159 -409.760113) (xy 90.317278 -409.801299) (xy 90.346742 -409.847146)
			(xy 90.36938 -409.896718) (xy 90.384734 -409.949008) (xy 90.39249 -410.002951) (xy 90.39249 -410.057449)
			(xy 90.392489 -410.057457) (xy 91.830023 -410.057457) (xy 91.830023 -410.002943) (xy 91.837782 -409.948983)
			(xy 91.853141 -409.896678) (xy 91.875789 -409.84709) (xy 91.905264 -409.801231) (xy 91.940965 -409.760034)
			(xy 91.982167 -409.724337) (xy 92.028029 -409.694868) (xy 92.077619 -409.672226) (xy 92.129927 -409.656872)
			(xy 92.183887 -409.64912) (xy 92.211144 -409.64866) (xy 93.074744 -409.64866) (xy 93.101991 -409.649213)
			(xy 93.155929 -409.656974) (xy 93.208214 -409.672332) (xy 93.257782 -409.694973) (xy 93.303623 -409.724438)
			(xy 93.344804 -409.760127) (xy 93.380488 -409.801313) (xy 93.409948 -409.847157) (xy 93.432584 -409.896727)
			(xy 93.447935 -409.949014) (xy 93.45569 -410.002953) (xy 93.45569 -410.057447) (xy 93.455689 -410.057453)
			(xy 94.893346 -410.057453) (xy 94.893346 -410.002947) (xy 94.901103 -409.948996) (xy 94.916458 -409.896698)
			(xy 94.9391 -409.847118) (xy 94.968567 -409.801265) (xy 95.00426 -409.760071) (xy 95.045452 -409.724377)
			(xy 95.091304 -409.694908) (xy 95.140883 -409.672264) (xy 95.193181 -409.656906) (xy 95.247131 -409.649147)
			(xy 95.274384 -409.64866) (xy 96.137984 -409.64866) (xy 96.165235 -409.649186) (xy 96.219183 -409.656941)
			(xy 96.271479 -409.672294) (xy 96.321057 -409.694934) (xy 96.366908 -409.724399) (xy 96.408099 -409.760089)
			(xy 96.443792 -409.801279) (xy 96.473259 -409.847129) (xy 96.4959 -409.896706) (xy 96.511256 -409.949001)
			(xy 96.519013 -410.002949) (xy 96.519013 -410.057451) (xy 96.511256 -410.111399) (xy 96.4959 -410.163694)
			(xy 96.473259 -410.213271) (xy 96.443792 -410.259121) (xy 96.408099 -410.300311) (xy 96.366908 -410.336001)
			(xy 96.321057 -410.365466) (xy 96.271479 -410.388106) (xy 96.219183 -410.403459) (xy 96.165235 -410.411214)
			(xy 96.137984 -410.411676) (xy 95.274384 -410.411676) (xy 95.247131 -410.411253) (xy 95.193181 -410.403494)
			(xy 95.140883 -410.388136) (xy 95.091304 -410.365492) (xy 95.045452 -410.336023) (xy 95.00426 -410.300329)
			(xy 94.968567 -410.259135) (xy 94.9391 -410.213282) (xy 94.916458 -410.163702) (xy 94.901103 -410.111404)
			(xy 94.893346 -410.057453) (xy 93.455689 -410.057453) (xy 93.447935 -410.111386) (xy 93.432584 -410.163673)
			(xy 93.409948 -410.213243) (xy 93.380488 -410.259087) (xy 93.344804 -410.300273) (xy 93.303623 -410.335962)
			(xy 93.257782 -410.365427) (xy 93.208214 -410.388068) (xy 93.155929 -410.403426) (xy 93.101991 -410.411187)
			(xy 93.074744 -410.411676) (xy 92.211144 -410.411676) (xy 92.183887 -410.41128) (xy 92.129927 -410.403528)
			(xy 92.077619 -410.388174) (xy 92.028029 -410.365532) (xy 91.982167 -410.336063) (xy 91.940965 -410.300366)
			(xy 91.905264 -410.259169) (xy 91.875789 -410.21331) (xy 91.853141 -410.163722) (xy 91.837782 -410.111417)
			(xy 91.830023 -410.057457) (xy 90.392489 -410.057457) (xy 90.384734 -410.111392) (xy 90.36938 -410.163682)
			(xy 90.346742 -410.213254) (xy 90.317278 -410.259101) (xy 90.28159 -410.300287) (xy 90.240404 -410.335976)
			(xy 90.194558 -410.36544) (xy 90.144985 -410.388079) (xy 90.092695 -410.403433) (xy 90.038753 -410.41119)
			(xy 90.011504 -410.411676) (xy 89.147904 -410.411676) (xy 89.120649 -410.411277) (xy 89.066693 -410.40352)
			(xy 89.01439 -410.388163) (xy 88.964805 -410.365519) (xy 88.918948 -410.336049) (xy 88.877751 -410.300352)
			(xy 88.842054 -410.259156) (xy 88.812583 -410.213298) (xy 88.789938 -410.163714) (xy 88.774581 -410.111411)
			(xy 88.766823 -410.057455) (xy 87.329313 -410.057455) (xy 87.321555 -410.111402) (xy 87.306199 -410.163698)
			(xy 87.283556 -410.213276) (xy 87.254087 -410.259127) (xy 87.218392 -410.300318) (xy 87.177199 -410.336008)
			(xy 87.131345 -410.365473) (xy 87.081764 -410.388111) (xy 87.029467 -410.403463) (xy 86.975516 -410.411215)
			(xy 86.948264 -410.411676) (xy 86.084664 -410.411676) (xy 86.057412 -410.411252) (xy 86.003464 -410.40349)
			(xy 85.951169 -410.388131) (xy 85.901592 -410.365486) (xy 85.855742 -410.336016) (xy 85.814553 -410.300321)
			(xy 85.778862 -410.259129) (xy 85.749397 -410.213276) (xy 85.726757 -410.163697) (xy 85.711402 -410.111401)
			(xy 85.703646 -410.057452) (xy 84.265989 -410.057452) (xy 84.258235 -410.111389) (xy 84.242882 -410.163677)
			(xy 84.220245 -410.213249) (xy 84.190783 -410.259094) (xy 84.155097 -410.30028) (xy 84.113913 -410.335969)
			(xy 84.06807 -410.365433) (xy 84.0185 -410.388074) (xy 83.966212 -410.40343) (xy 83.912272 -410.411188)
			(xy 83.885024 -410.411676) (xy 83.021424 -410.411676) (xy 82.994168 -410.411279) (xy 82.94021 -410.403524)
			(xy 82.887904 -410.388169) (xy 82.838317 -410.365526) (xy 82.792457 -410.336056) (xy 82.751258 -410.300359)
			(xy 82.715559 -410.259162) (xy 82.686086 -410.213304) (xy 82.66344 -410.163718) (xy 82.648081 -410.111414)
			(xy 82.640323 -410.057456) (xy 81.202812 -410.057456) (xy 81.195056 -410.111399) (xy 81.1797 -410.163694)
			(xy 81.157059 -410.213271) (xy 81.127592 -410.259121) (xy 81.091899 -410.300311) (xy 81.050708 -410.336001)
			(xy 81.004857 -410.365466) (xy 80.955279 -410.388106) (xy 80.902983 -410.403459) (xy 80.849035 -410.411214)
			(xy 80.821784 -410.411676) (xy 79.958184 -410.411676) (xy 79.930931 -410.411253) (xy 79.876981 -410.403494)
			(xy 79.824683 -410.388136) (xy 79.775104 -410.365492) (xy 79.729252 -410.336023) (xy 79.68806 -410.300329)
			(xy 79.652367 -410.259135) (xy 79.6229 -410.213282) (xy 79.600258 -410.163702) (xy 79.584903 -410.111404)
			(xy 79.577146 -410.057453) (xy 78.139489 -410.057453) (xy 78.131735 -410.111386) (xy 78.116384 -410.163673)
			(xy 78.093748 -410.213243) (xy 78.064288 -410.259087) (xy 78.028604 -410.300273) (xy 77.987423 -410.335962)
			(xy 77.941582 -410.365427) (xy 77.892014 -410.388068) (xy 77.839729 -410.403426) (xy 77.785791 -410.411187)
			(xy 77.758544 -410.411676) (xy 76.894944 -410.411676) (xy 76.867687 -410.41128) (xy 76.813727 -410.403528)
			(xy 76.761419 -410.388174) (xy 76.711829 -410.365532) (xy 76.665967 -410.336063) (xy 76.624765 -410.300366)
			(xy 76.589064 -410.259169) (xy 76.559589 -410.21331) (xy 76.536941 -410.163722) (xy 76.521582 -410.111417)
			(xy 76.513823 -410.057457) (xy 75.076289 -410.057457) (xy 75.068534 -410.111392) (xy 75.05318 -410.163682)
			(xy 75.030542 -410.213254) (xy 75.001078 -410.259101) (xy 74.96539 -410.300287) (xy 74.924204 -410.335976)
			(xy 74.878358 -410.36544) (xy 74.828785 -410.388079) (xy 74.776495 -410.403433) (xy 74.722553 -410.41119)
			(xy 74.695304 -410.411676) (xy 73.831704 -410.411676) (xy 73.804449 -410.411277) (xy 73.750493 -410.40352)
			(xy 73.69819 -410.388163) (xy 73.648605 -410.365519) (xy 73.602748 -410.336049) (xy 73.561551 -410.300352)
			(xy 73.525854 -410.259156) (xy 73.496383 -410.213298) (xy 73.473738 -410.163714) (xy 73.458381 -410.111411)
			(xy 73.450623 -410.057455) (xy 72.013113 -410.057455) (xy 72.005355 -410.111402) (xy 71.989999 -410.163698)
			(xy 71.967356 -410.213276) (xy 71.937887 -410.259127) (xy 71.902192 -410.300318) (xy 71.860999 -410.336008)
			(xy 71.815145 -410.365473) (xy 71.765564 -410.388111) (xy 71.713267 -410.403463) (xy 71.659316 -410.411215)
			(xy 71.632064 -410.411676) (xy 70.768464 -410.411676) (xy 70.741212 -410.411252) (xy 70.687264 -410.40349)
			(xy 70.634969 -410.388131) (xy 70.585392 -410.365486) (xy 70.539542 -410.336016) (xy 70.498353 -410.300321)
			(xy 70.462662 -410.259129) (xy 70.433197 -410.213276) (xy 70.410557 -410.163697) (xy 70.395202 -410.111401)
			(xy 70.387446 -410.057452) (xy 68.949789 -410.057452) (xy 68.942035 -410.111389) (xy 68.926682 -410.163677)
			(xy 68.904045 -410.213249) (xy 68.874583 -410.259094) (xy 68.838897 -410.30028) (xy 68.797713 -410.335969)
			(xy 68.75187 -410.365433) (xy 68.7023 -410.388074) (xy 68.650012 -410.40343) (xy 68.596072 -410.411188)
			(xy 68.568824 -410.411676) (xy 67.705224 -410.411676) (xy 67.677968 -410.411279) (xy 67.62401 -410.403524)
			(xy 67.571704 -410.388169) (xy 67.522117 -410.365526) (xy 67.476257 -410.336056) (xy 67.435058 -410.300359)
			(xy 67.399359 -410.259162) (xy 67.369886 -410.213304) (xy 67.34724 -410.163718) (xy 67.331881 -410.111414)
			(xy 67.324123 -410.057456) (xy 65.886612 -410.057456) (xy 65.878856 -410.111399) (xy 65.8635 -410.163694)
			(xy 65.840859 -410.213271) (xy 65.811392 -410.259121) (xy 65.775699 -410.300311) (xy 65.734508 -410.336001)
			(xy 65.688657 -410.365466) (xy 65.639079 -410.388106) (xy 65.586783 -410.403459) (xy 65.532835 -410.411214)
			(xy 65.505584 -410.411676) (xy 64.641984 -410.411676) (xy 64.614731 -410.411253) (xy 64.560781 -410.403494)
			(xy 64.508483 -410.388136) (xy 64.458904 -410.365492) (xy 64.413052 -410.336023) (xy 64.37186 -410.300329)
			(xy 64.336167 -410.259135) (xy 64.3067 -410.213282) (xy 64.284058 -410.163702) (xy 64.268703 -410.111404)
			(xy 64.260946 -410.057453) (xy 62.823289 -410.057453) (xy 62.815535 -410.111386) (xy 62.800184 -410.163673)
			(xy 62.777548 -410.213243) (xy 62.748088 -410.259087) (xy 62.712404 -410.300273) (xy 62.671223 -410.335962)
			(xy 62.625382 -410.365427) (xy 62.575814 -410.388068) (xy 62.523529 -410.403426) (xy 62.469591 -410.411187)
			(xy 62.442344 -410.411676) (xy 61.578744 -410.411676) (xy 61.551487 -410.41128) (xy 61.497527 -410.403528)
			(xy 61.445219 -410.388174) (xy 61.395629 -410.365532) (xy 61.349767 -410.336063) (xy 61.308565 -410.300366)
			(xy 61.272864 -410.259169) (xy 61.243389 -410.21331) (xy 61.220741 -410.163722) (xy 61.205382 -410.111417)
			(xy 61.197623 -410.057457) (xy 59.760089 -410.057457) (xy 59.752334 -410.111392) (xy 59.73698 -410.163682)
			(xy 59.714342 -410.213254) (xy 59.684878 -410.259101) (xy 59.64919 -410.300287) (xy 59.608004 -410.335976)
			(xy 59.562158 -410.36544) (xy 59.512585 -410.388079) (xy 59.460295 -410.403433) (xy 59.406353 -410.41119)
			(xy 59.379104 -410.411676) (xy 58.515504 -410.411676) (xy 58.488249 -410.411277) (xy 58.434293 -410.40352)
			(xy 58.38199 -410.388163) (xy 58.332405 -410.365519) (xy 58.286548 -410.336049) (xy 58.245351 -410.300352)
			(xy 58.209654 -410.259156) (xy 58.180183 -410.213298) (xy 58.157538 -410.163714) (xy 58.142181 -410.111411)
			(xy 58.134423 -410.057455) (xy 56.696913 -410.057455) (xy 56.689155 -410.111402) (xy 56.673799 -410.163698)
			(xy 56.651156 -410.213276) (xy 56.621687 -410.259127) (xy 56.585992 -410.300318) (xy 56.544799 -410.336008)
			(xy 56.498945 -410.365473) (xy 56.449364 -410.388111) (xy 56.397067 -410.403463) (xy 56.343116 -410.411215)
			(xy 56.315864 -410.411676) (xy 55.452264 -410.411676) (xy 55.425012 -410.411252) (xy 55.371064 -410.40349)
			(xy 55.318769 -410.388131) (xy 55.269192 -410.365486) (xy 55.223342 -410.336016) (xy 55.182153 -410.300321)
			(xy 55.146462 -410.259129) (xy 55.116997 -410.213276) (xy 55.094357 -410.163697) (xy 55.079002 -410.111401)
			(xy 55.071246 -410.057452) (xy 53.633589 -410.057452) (xy 53.625835 -410.111389) (xy 53.610482 -410.163677)
			(xy 53.587845 -410.213249) (xy 53.558383 -410.259094) (xy 53.522697 -410.30028) (xy 53.481513 -410.335969)
			(xy 53.43567 -410.365433) (xy 53.3861 -410.388074) (xy 53.333812 -410.40343) (xy 53.279872 -410.411188)
			(xy 53.252624 -410.411676) (xy 52.389024 -410.411676) (xy 52.361768 -410.411279) (xy 52.30781 -410.403524)
			(xy 52.255504 -410.388169) (xy 52.205917 -410.365526) (xy 52.160057 -410.336056) (xy 52.118858 -410.300359)
			(xy 52.083159 -410.259162) (xy 52.053686 -410.213304) (xy 52.03104 -410.163718) (xy 52.015681 -410.111414)
			(xy 52.007923 -410.057456) (xy 50.570412 -410.057456) (xy 50.562656 -410.111399) (xy 50.5473 -410.163694)
			(xy 50.524659 -410.213271) (xy 50.495192 -410.259121) (xy 50.459499 -410.300311) (xy 50.418308 -410.336001)
			(xy 50.372457 -410.365466) (xy 50.322879 -410.388106) (xy 50.270583 -410.403459) (xy 50.216635 -410.411214)
			(xy 50.189384 -410.411676) (xy 49.325784 -410.411676) (xy 49.298531 -410.411253) (xy 49.244581 -410.403494)
			(xy 49.192283 -410.388136) (xy 49.142704 -410.365492) (xy 49.096852 -410.336023) (xy 49.05566 -410.300329)
			(xy 49.019967 -410.259135) (xy 48.9905 -410.213282) (xy 48.967858 -410.163702) (xy 48.952503 -410.111404)
			(xy 48.944746 -410.057453) (xy 7.00913 -410.057453) (xy 7.00913 -413.4485) (xy 38.974268 -413.4485)
			(xy 38.974268 -412.5849) (xy 38.974754 -412.557631) (xy 38.982516 -412.503647) (xy 38.997881 -412.451317)
			(xy 39.020538 -412.401707) (xy 39.050024 -412.355826) (xy 39.085739 -412.314609) (xy 39.126956 -412.278894)
			(xy 39.172837 -412.249408) (xy 39.222447 -412.226751) (xy 39.274777 -412.211386) (xy 39.328761 -412.203624)
			(xy 39.383299 -412.203624) (xy 39.437283 -412.211386) (xy 39.489613 -412.226751) (xy 39.539223 -412.249408)
			(xy 39.585104 -412.278894) (xy 39.626321 -412.314609) (xy 39.662036 -412.355826) (xy 39.691522 -412.401707)
			(xy 39.714179 -412.451317) (xy 39.729544 -412.503647) (xy 39.737306 -412.557631) (xy 39.737792 -412.5849)
			(xy 39.737792 -412.597452) (xy 47.413146 -412.597452) (xy 47.413146 -412.542948) (xy 47.420902 -412.488999)
			(xy 47.436257 -412.436703) (xy 47.458897 -412.387124) (xy 47.488362 -412.341271) (xy 47.524053 -412.300079)
			(xy 47.565242 -412.264384) (xy 47.611092 -412.234914) (xy 47.660669 -412.212269) (xy 47.712964 -412.19691)
			(xy 47.766912 -412.189148) (xy 47.794164 -412.18866) (xy 48.657764 -412.18866) (xy 48.685016 -412.189185)
			(xy 48.738967 -412.196937) (xy 48.791264 -412.212289) (xy 48.840845 -412.234927) (xy 48.886699 -412.264392)
			(xy 48.927892 -412.300082) (xy 48.963587 -412.341273) (xy 48.993056 -412.387124) (xy 49.015699 -412.436702)
			(xy 49.031055 -412.488998) (xy 49.038813 -412.542948) (xy 49.038813 -412.597452) (xy 49.038813 -412.597455)
			(xy 50.476323 -412.597455) (xy 50.476323 -412.542945) (xy 50.484081 -412.488989) (xy 50.499438 -412.436686)
			(xy 50.522083 -412.387102) (xy 50.551554 -412.341244) (xy 50.587251 -412.300048) (xy 50.628448 -412.264351)
			(xy 50.674305 -412.234881) (xy 50.72389 -412.212237) (xy 50.776193 -412.19688) (xy 50.830149 -412.189123)
			(xy 50.857404 -412.18866) (xy 51.721004 -412.18866) (xy 51.748253 -412.18921) (xy 51.802195 -412.196967)
			(xy 51.854485 -412.212321) (xy 51.904058 -412.23496) (xy 51.949904 -412.264424) (xy 51.99109 -412.300113)
			(xy 52.026778 -412.341299) (xy 52.056242 -412.387146) (xy 52.07888 -412.436718) (xy 52.094234 -412.489008)
			(xy 52.10199 -412.542951) (xy 52.10199 -412.597449) (xy 52.101989 -412.597457) (xy 53.539523 -412.597457)
			(xy 53.539523 -412.542943) (xy 53.547282 -412.488983) (xy 53.562641 -412.436678) (xy 53.585289 -412.38709)
			(xy 53.614764 -412.341231) (xy 53.650465 -412.300034) (xy 53.691667 -412.264337) (xy 53.737529 -412.234868)
			(xy 53.787119 -412.212226) (xy 53.839427 -412.196872) (xy 53.893387 -412.18912) (xy 53.920644 -412.18866)
			(xy 54.784244 -412.18866) (xy 54.811491 -412.189213) (xy 54.865429 -412.196974) (xy 54.917714 -412.212332)
			(xy 54.967282 -412.234973) (xy 55.013123 -412.264438) (xy 55.054304 -412.300127) (xy 55.089988 -412.341313)
			(xy 55.119448 -412.387157) (xy 55.142084 -412.436727) (xy 55.157435 -412.489014) (xy 55.16519 -412.542953)
			(xy 55.16519 -412.597447) (xy 55.165189 -412.597453) (xy 56.602846 -412.597453) (xy 56.602846 -412.542947)
			(xy 56.610603 -412.488996) (xy 56.625958 -412.436698) (xy 56.6486 -412.387118) (xy 56.678067 -412.341265)
			(xy 56.71376 -412.300071) (xy 56.754952 -412.264377) (xy 56.800804 -412.234908) (xy 56.850383 -412.212264)
			(xy 56.902681 -412.196906) (xy 56.956631 -412.189147) (xy 56.983884 -412.18866) (xy 57.847484 -412.18866)
			(xy 57.874735 -412.189186) (xy 57.928683 -412.196941) (xy 57.980979 -412.212294) (xy 58.030557 -412.234934)
			(xy 58.076408 -412.264399) (xy 58.117599 -412.300089) (xy 58.153292 -412.341279) (xy 58.182759 -412.387129)
			(xy 58.2054 -412.436706) (xy 58.220756 -412.489001) (xy 58.228513 -412.542949) (xy 58.228513 -412.597451)
			(xy 58.228512 -412.597456) (xy 59.666023 -412.597456) (xy 59.666023 -412.542944) (xy 59.673781 -412.488986)
			(xy 59.68914 -412.436682) (xy 59.711786 -412.387096) (xy 59.741259 -412.341238) (xy 59.776958 -412.300041)
			(xy 59.818157 -412.264344) (xy 59.864017 -412.234874) (xy 59.913604 -412.212231) (xy 59.96591 -412.196876)
			(xy 60.019868 -412.189121) (xy 60.047124 -412.18866) (xy 60.910724 -412.18866) (xy 60.937972 -412.189212)
			(xy 60.991912 -412.19697) (xy 61.0442 -412.212326) (xy 61.09377 -412.234967) (xy 61.139613 -412.264431)
			(xy 61.180797 -412.30012) (xy 61.216483 -412.341306) (xy 61.245945 -412.387151) (xy 61.268582 -412.436723)
			(xy 61.283935 -412.489011) (xy 61.29169 -412.542952) (xy 61.29169 -412.597448) (xy 61.291689 -412.597452)
			(xy 62.729346 -412.597452) (xy 62.729346 -412.542948) (xy 62.737102 -412.488999) (xy 62.752457 -412.436703)
			(xy 62.775097 -412.387124) (xy 62.804562 -412.341271) (xy 62.840253 -412.300079) (xy 62.881442 -412.264384)
			(xy 62.927292 -412.234914) (xy 62.976869 -412.212269) (xy 63.029164 -412.19691) (xy 63.083112 -412.189148)
			(xy 63.110364 -412.18866) (xy 63.973964 -412.18866) (xy 64.001216 -412.189185) (xy 64.055167 -412.196937)
			(xy 64.107464 -412.212289) (xy 64.157045 -412.234927) (xy 64.202899 -412.264392) (xy 64.244092 -412.300082)
			(xy 64.279787 -412.341273) (xy 64.309256 -412.387124) (xy 64.331899 -412.436702) (xy 64.347255 -412.488998)
			(xy 64.355013 -412.542948) (xy 64.355013 -412.597452) (xy 64.355013 -412.597455) (xy 65.792523 -412.597455)
			(xy 65.792523 -412.542945) (xy 65.800281 -412.488989) (xy 65.815638 -412.436686) (xy 65.838283 -412.387102)
			(xy 65.867754 -412.341244) (xy 65.903451 -412.300048) (xy 65.944648 -412.264351) (xy 65.990505 -412.234881)
			(xy 66.04009 -412.212237) (xy 66.092393 -412.19688) (xy 66.146349 -412.189123) (xy 66.173604 -412.18866)
			(xy 67.037204 -412.18866) (xy 67.064453 -412.18921) (xy 67.118395 -412.196967) (xy 67.170685 -412.212321)
			(xy 67.220258 -412.23496) (xy 67.266104 -412.264424) (xy 67.30729 -412.300113) (xy 67.342978 -412.341299)
			(xy 67.372442 -412.387146) (xy 67.39508 -412.436718) (xy 67.410434 -412.489008) (xy 67.41819 -412.542951)
			(xy 67.41819 -412.597449) (xy 67.418189 -412.597457) (xy 68.855723 -412.597457) (xy 68.855723 -412.542943)
			(xy 68.863482 -412.488983) (xy 68.878841 -412.436678) (xy 68.901489 -412.38709) (xy 68.930964 -412.341231)
			(xy 68.966665 -412.300034) (xy 69.007867 -412.264337) (xy 69.053729 -412.234868) (xy 69.103319 -412.212226)
			(xy 69.155627 -412.196872) (xy 69.209587 -412.18912) (xy 69.236844 -412.18866) (xy 70.100444 -412.18866)
			(xy 70.127691 -412.189213) (xy 70.181629 -412.196974) (xy 70.233914 -412.212332) (xy 70.283482 -412.234973)
			(xy 70.329323 -412.264438) (xy 70.370504 -412.300127) (xy 70.406188 -412.341313) (xy 70.435648 -412.387157)
			(xy 70.458284 -412.436727) (xy 70.473635 -412.489014) (xy 70.48139 -412.542953) (xy 70.48139 -412.597447)
			(xy 70.481389 -412.597453) (xy 71.919046 -412.597453) (xy 71.919046 -412.542947) (xy 71.926803 -412.488996)
			(xy 71.942158 -412.436698) (xy 71.9648 -412.387118) (xy 71.994267 -412.341265) (xy 72.02996 -412.300071)
			(xy 72.071152 -412.264377) (xy 72.117004 -412.234908) (xy 72.166583 -412.212264) (xy 72.218881 -412.196906)
			(xy 72.272831 -412.189147) (xy 72.300084 -412.18866) (xy 73.163684 -412.18866) (xy 73.190935 -412.189186)
			(xy 73.244883 -412.196941) (xy 73.297179 -412.212294) (xy 73.346757 -412.234934) (xy 73.392608 -412.264399)
			(xy 73.433799 -412.300089) (xy 73.469492 -412.341279) (xy 73.498959 -412.387129) (xy 73.5216 -412.436706)
			(xy 73.536956 -412.489001) (xy 73.544713 -412.542949) (xy 73.544713 -412.597451) (xy 73.544712 -412.597456)
			(xy 74.982223 -412.597456) (xy 74.982223 -412.542944) (xy 74.989981 -412.488986) (xy 75.00534 -412.436682)
			(xy 75.027986 -412.387096) (xy 75.057459 -412.341238) (xy 75.093158 -412.300041) (xy 75.134357 -412.264344)
			(xy 75.180217 -412.234874) (xy 75.229804 -412.212231) (xy 75.28211 -412.196876) (xy 75.336068 -412.189121)
			(xy 75.363324 -412.18866) (xy 76.226924 -412.18866) (xy 76.254172 -412.189212) (xy 76.308112 -412.19697)
			(xy 76.3604 -412.212326) (xy 76.40997 -412.234967) (xy 76.455813 -412.264431) (xy 76.496997 -412.30012)
			(xy 76.532683 -412.341306) (xy 76.562145 -412.387151) (xy 76.584782 -412.436723) (xy 76.600135 -412.489011)
			(xy 76.60789 -412.542952) (xy 76.60789 -412.597448) (xy 76.607889 -412.597452) (xy 78.045546 -412.597452)
			(xy 78.045546 -412.542948) (xy 78.053302 -412.488999) (xy 78.068657 -412.436703) (xy 78.091297 -412.387124)
			(xy 78.120762 -412.341271) (xy 78.156453 -412.300079) (xy 78.197642 -412.264384) (xy 78.243492 -412.234914)
			(xy 78.293069 -412.212269) (xy 78.345364 -412.19691) (xy 78.399312 -412.189148) (xy 78.426564 -412.18866)
			(xy 79.290164 -412.18866) (xy 79.317416 -412.189185) (xy 79.371367 -412.196937) (xy 79.423664 -412.212289)
			(xy 79.473245 -412.234927) (xy 79.519099 -412.264392) (xy 79.560292 -412.300082) (xy 79.595987 -412.341273)
			(xy 79.625456 -412.387124) (xy 79.648099 -412.436702) (xy 79.663455 -412.488998) (xy 79.671213 -412.542948)
			(xy 79.671213 -412.597452) (xy 79.671213 -412.597455) (xy 81.108723 -412.597455) (xy 81.108723 -412.542945)
			(xy 81.116481 -412.488989) (xy 81.131838 -412.436686) (xy 81.154483 -412.387102) (xy 81.183954 -412.341244)
			(xy 81.219651 -412.300048) (xy 81.260848 -412.264351) (xy 81.306705 -412.234881) (xy 81.35629 -412.212237)
			(xy 81.408593 -412.19688) (xy 81.462549 -412.189123) (xy 81.489804 -412.18866) (xy 82.353404 -412.18866)
			(xy 82.380653 -412.18921) (xy 82.434595 -412.196967) (xy 82.486885 -412.212321) (xy 82.536458 -412.23496)
			(xy 82.582304 -412.264424) (xy 82.62349 -412.300113) (xy 82.659178 -412.341299) (xy 82.688642 -412.387146)
			(xy 82.71128 -412.436718) (xy 82.726634 -412.489008) (xy 82.73439 -412.542951) (xy 82.73439 -412.597449)
			(xy 82.734389 -412.597457) (xy 84.171923 -412.597457) (xy 84.171923 -412.542943) (xy 84.179682 -412.488983)
			(xy 84.195041 -412.436678) (xy 84.217689 -412.38709) (xy 84.247164 -412.341231) (xy 84.282865 -412.300034)
			(xy 84.324067 -412.264337) (xy 84.369929 -412.234868) (xy 84.419519 -412.212226) (xy 84.471827 -412.196872)
			(xy 84.525787 -412.18912) (xy 84.553044 -412.18866) (xy 85.416644 -412.18866) (xy 85.443891 -412.189213)
			(xy 85.497829 -412.196974) (xy 85.550114 -412.212332) (xy 85.599682 -412.234973) (xy 85.645523 -412.264438)
			(xy 85.686704 -412.300127) (xy 85.722388 -412.341313) (xy 85.751848 -412.387157) (xy 85.774484 -412.436727)
			(xy 85.789835 -412.489014) (xy 85.79759 -412.542953) (xy 85.79759 -412.597447) (xy 85.797589 -412.597453)
			(xy 87.235246 -412.597453) (xy 87.235246 -412.542947) (xy 87.243003 -412.488996) (xy 87.258358 -412.436698)
			(xy 87.281 -412.387118) (xy 87.310467 -412.341265) (xy 87.34616 -412.300071) (xy 87.387352 -412.264377)
			(xy 87.433204 -412.234908) (xy 87.482783 -412.212264) (xy 87.535081 -412.196906) (xy 87.589031 -412.189147)
			(xy 87.616284 -412.18866) (xy 88.479884 -412.18866) (xy 88.507135 -412.189186) (xy 88.561083 -412.196941)
			(xy 88.613379 -412.212294) (xy 88.662957 -412.234934) (xy 88.708808 -412.264399) (xy 88.749999 -412.300089)
			(xy 88.785692 -412.341279) (xy 88.815159 -412.387129) (xy 88.8378 -412.436706) (xy 88.853156 -412.489001)
			(xy 88.860913 -412.542949) (xy 88.860913 -412.597451) (xy 88.860912 -412.597456) (xy 90.298423 -412.597456)
			(xy 90.298423 -412.542944) (xy 90.306181 -412.488986) (xy 90.32154 -412.436682) (xy 90.344186 -412.387096)
			(xy 90.373659 -412.341238) (xy 90.409358 -412.300041) (xy 90.450557 -412.264344) (xy 90.496417 -412.234874)
			(xy 90.546004 -412.212231) (xy 90.59831 -412.196876) (xy 90.652268 -412.189121) (xy 90.679524 -412.18866)
			(xy 91.543124 -412.18866) (xy 91.570372 -412.189212) (xy 91.624312 -412.19697) (xy 91.6766 -412.212326)
			(xy 91.72617 -412.234967) (xy 91.772013 -412.264431) (xy 91.813197 -412.30012) (xy 91.848883 -412.341306)
			(xy 91.878345 -412.387151) (xy 91.900982 -412.436723) (xy 91.916335 -412.489011) (xy 91.92409 -412.542952)
			(xy 91.92409 -412.597448) (xy 91.924089 -412.597452) (xy 93.361746 -412.597452) (xy 93.361746 -412.542948)
			(xy 93.369502 -412.488999) (xy 93.384857 -412.436703) (xy 93.407497 -412.387124) (xy 93.436962 -412.341271)
			(xy 93.472653 -412.300079) (xy 93.513842 -412.264384) (xy 93.559692 -412.234914) (xy 93.609269 -412.212269)
			(xy 93.661564 -412.19691) (xy 93.715512 -412.189148) (xy 93.742764 -412.18866) (xy 94.606364 -412.18866)
			(xy 94.633616 -412.189185) (xy 94.687567 -412.196937) (xy 94.739864 -412.212289) (xy 94.789445 -412.234927)
			(xy 94.835299 -412.264392) (xy 94.876492 -412.300082) (xy 94.912187 -412.341273) (xy 94.941656 -412.387124)
			(xy 94.964299 -412.436702) (xy 94.979655 -412.488998) (xy 94.987413 -412.542948) (xy 94.987413 -412.597452)
			(xy 94.987413 -412.597455) (xy 114.513023 -412.597455) (xy 114.513023 -412.542945) (xy 114.520781 -412.488989)
			(xy 114.536138 -412.436686) (xy 114.558783 -412.387101) (xy 114.588254 -412.341244) (xy 114.623952 -412.300047)
			(xy 114.665149 -412.264351) (xy 114.711006 -412.23488) (xy 114.760591 -412.212236) (xy 114.812894 -412.196879)
			(xy 114.866851 -412.189123) (xy 114.894106 -412.18866) (xy 115.757706 -412.18866) (xy 115.784955 -412.189211)
			(xy 115.838897 -412.196967) (xy 115.891187 -412.212321) (xy 115.940759 -412.234961) (xy 115.986605 -412.264425)
			(xy 116.027791 -412.300113) (xy 116.063479 -412.3413) (xy 116.092942 -412.387146) (xy 116.115581 -412.436719)
			(xy 116.130934 -412.489009) (xy 116.13869 -412.542951) (xy 116.13869 -412.597449) (xy 116.138689 -412.597457)
			(xy 117.576223 -412.597457) (xy 117.576223 -412.542943) (xy 117.583982 -412.488983) (xy 117.599342 -412.436677)
			(xy 117.621989 -412.38709) (xy 117.651464 -412.341231) (xy 117.687166 -412.300033) (xy 117.728367 -412.264337)
			(xy 117.77423 -412.234867) (xy 117.82382 -412.212225) (xy 117.876128 -412.196872) (xy 117.930089 -412.18912)
			(xy 117.957346 -412.18866) (xy 118.820946 -412.18866) (xy 118.848193 -412.189213) (xy 118.902131 -412.196975)
			(xy 118.954416 -412.212332) (xy 119.003983 -412.234974) (xy 119.049824 -412.264439) (xy 119.091005 -412.300128)
			(xy 119.126688 -412.341313) (xy 119.156148 -412.387157) (xy 119.178784 -412.436727) (xy 119.194135 -412.489014)
			(xy 119.20189 -412.542953) (xy 119.20189 -412.597447) (xy 119.201889 -412.597453) (xy 120.639546 -412.597453)
			(xy 120.639546 -412.542947) (xy 120.647303 -412.488996) (xy 120.662658 -412.436698) (xy 120.6853 -412.387118)
			(xy 120.714768 -412.341264) (xy 120.750461 -412.300071) (xy 120.791653 -412.264376) (xy 120.837505 -412.234907)
			(xy 120.887085 -412.212263) (xy 120.939382 -412.196906) (xy 120.993333 -412.189147) (xy 121.020586 -412.18866)
			(xy 121.884186 -412.18866) (xy 121.911437 -412.189186) (xy 121.965385 -412.196941) (xy 122.01768 -412.212295)
			(xy 122.067258 -412.234934) (xy 122.113109 -412.264399) (xy 122.1543 -412.30009) (xy 122.189992 -412.34128)
			(xy 122.219459 -412.38713) (xy 122.242101 -412.436707) (xy 122.257456 -412.489001) (xy 122.265213 -412.542949)
			(xy 122.265213 -412.597451) (xy 122.265212 -412.597456) (xy 123.702723 -412.597456) (xy 123.702723 -412.542944)
			(xy 123.710481 -412.488986) (xy 123.72584 -412.436681) (xy 123.748486 -412.387095) (xy 123.777959 -412.341237)
			(xy 123.813659 -412.30004) (xy 123.854858 -412.264344) (xy 123.900718 -412.234874) (xy 123.950306 -412.212231)
			(xy 124.002611 -412.196876) (xy 124.05657 -412.189121) (xy 124.083826 -412.18866) (xy 124.947426 -412.18866)
			(xy 124.974674 -412.189212) (xy 125.028614 -412.196971) (xy 125.080901 -412.212327) (xy 125.130471 -412.234968)
			(xy 125.176314 -412.264432) (xy 125.217498 -412.300121) (xy 125.253184 -412.341307) (xy 125.282645 -412.387152)
			(xy 125.305282 -412.436723) (xy 125.320635 -412.489011) (xy 125.32839 -412.542952) (xy 125.32839 -412.597448)
			(xy 125.328389 -412.597452) (xy 126.766046 -412.597452) (xy 126.766046 -412.542948) (xy 126.773802 -412.488999)
			(xy 126.789157 -412.436702) (xy 126.811797 -412.387123) (xy 126.841263 -412.341271) (xy 126.876954 -412.300078)
			(xy 126.918143 -412.264383) (xy 126.963993 -412.234914) (xy 127.01357 -412.212269) (xy 127.065865 -412.196909)
			(xy 127.119814 -412.189148) (xy 127.147066 -412.18866) (xy 128.010666 -412.18866) (xy 128.037918 -412.189185)
			(xy 128.091868 -412.196937) (xy 128.144166 -412.212289) (xy 128.193746 -412.234928) (xy 128.2396 -412.264392)
			(xy 128.280793 -412.300083) (xy 128.316487 -412.341273) (xy 128.345956 -412.387124) (xy 128.368599 -412.436702)
			(xy 128.383955 -412.488999) (xy 128.391713 -412.542948) (xy 128.391713 -412.597452) (xy 128.391713 -412.597455)
			(xy 129.829223 -412.597455) (xy 129.829223 -412.542945) (xy 129.836981 -412.488989) (xy 129.852338 -412.436686)
			(xy 129.874983 -412.387101) (xy 129.904454 -412.341244) (xy 129.940152 -412.300047) (xy 129.981349 -412.264351)
			(xy 130.027206 -412.23488) (xy 130.076791 -412.212236) (xy 130.129094 -412.196879) (xy 130.183051 -412.189123)
			(xy 130.210306 -412.18866) (xy 131.073906 -412.18866) (xy 131.101155 -412.189211) (xy 131.155097 -412.196967)
			(xy 131.207387 -412.212321) (xy 131.256959 -412.234961) (xy 131.302805 -412.264425) (xy 131.343991 -412.300113)
			(xy 131.379679 -412.3413) (xy 131.409142 -412.387146) (xy 131.431781 -412.436719) (xy 131.447134 -412.489009)
			(xy 131.45489 -412.542951) (xy 131.45489 -412.597449) (xy 131.454889 -412.597457) (xy 132.892423 -412.597457)
			(xy 132.892423 -412.542943) (xy 132.900182 -412.488983) (xy 132.915542 -412.436677) (xy 132.938189 -412.38709)
			(xy 132.967664 -412.341231) (xy 133.003366 -412.300033) (xy 133.044567 -412.264337) (xy 133.09043 -412.234867)
			(xy 133.14002 -412.212225) (xy 133.192328 -412.196872) (xy 133.246289 -412.18912) (xy 133.273546 -412.18866)
			(xy 134.137146 -412.18866) (xy 134.164393 -412.189213) (xy 134.218331 -412.196975) (xy 134.270616 -412.212332)
			(xy 134.320183 -412.234974) (xy 134.366024 -412.264439) (xy 134.407205 -412.300128) (xy 134.442888 -412.341313)
			(xy 134.472348 -412.387157) (xy 134.494984 -412.436727) (xy 134.510335 -412.489014) (xy 134.51809 -412.542953)
			(xy 134.51809 -412.597447) (xy 134.518089 -412.597453) (xy 135.955746 -412.597453) (xy 135.955746 -412.542947)
			(xy 135.963503 -412.488996) (xy 135.978858 -412.436698) (xy 136.0015 -412.387118) (xy 136.030968 -412.341264)
			(xy 136.066661 -412.300071) (xy 136.107853 -412.264376) (xy 136.153705 -412.234907) (xy 136.203285 -412.212263)
			(xy 136.255582 -412.196906) (xy 136.309533 -412.189147) (xy 136.336786 -412.18866) (xy 137.200386 -412.18866)
			(xy 137.227637 -412.189186) (xy 137.281585 -412.196941) (xy 137.33388 -412.212295) (xy 137.383458 -412.234934)
			(xy 137.429309 -412.264399) (xy 137.4705 -412.30009) (xy 137.506192 -412.34128) (xy 137.535659 -412.38713)
			(xy 137.558301 -412.436707) (xy 137.573656 -412.489001) (xy 137.581413 -412.542949) (xy 137.581413 -412.597451)
			(xy 137.581412 -412.597456) (xy 139.018923 -412.597456) (xy 139.018923 -412.542944) (xy 139.026681 -412.488986)
			(xy 139.04204 -412.436681) (xy 139.064686 -412.387095) (xy 139.094159 -412.341237) (xy 139.129859 -412.30004)
			(xy 139.171058 -412.264344) (xy 139.216918 -412.234874) (xy 139.266506 -412.212231) (xy 139.318811 -412.196876)
			(xy 139.37277 -412.189121) (xy 139.400026 -412.18866) (xy 140.263626 -412.18866) (xy 140.290874 -412.189212)
			(xy 140.344814 -412.196971) (xy 140.397101 -412.212327) (xy 140.446671 -412.234968) (xy 140.492514 -412.264432)
			(xy 140.533698 -412.300121) (xy 140.569384 -412.341307) (xy 140.598845 -412.387152) (xy 140.621482 -412.436723)
			(xy 140.636835 -412.489011) (xy 140.64459 -412.542952) (xy 140.64459 -412.597448) (xy 140.644589 -412.597452)
			(xy 142.082246 -412.597452) (xy 142.082246 -412.542948) (xy 142.090002 -412.488999) (xy 142.105357 -412.436702)
			(xy 142.127997 -412.387123) (xy 142.157463 -412.341271) (xy 142.193154 -412.300078) (xy 142.234343 -412.264383)
			(xy 142.280193 -412.234914) (xy 142.32977 -412.212269) (xy 142.382065 -412.196909) (xy 142.436014 -412.189148)
			(xy 142.463266 -412.18866) (xy 143.326866 -412.18866) (xy 143.354118 -412.189185) (xy 143.408068 -412.196937)
			(xy 143.460366 -412.212289) (xy 143.509946 -412.234928) (xy 143.5558 -412.264392) (xy 143.596993 -412.300083)
			(xy 143.632687 -412.341273) (xy 143.662156 -412.387124) (xy 143.684799 -412.436702) (xy 143.700155 -412.488999)
			(xy 143.707913 -412.542948) (xy 143.707913 -412.597452) (xy 143.707913 -412.597455) (xy 145.145423 -412.597455)
			(xy 145.145423 -412.542945) (xy 145.153181 -412.488989) (xy 145.168538 -412.436686) (xy 145.191183 -412.387101)
			(xy 145.220654 -412.341244) (xy 145.256352 -412.300047) (xy 145.297549 -412.264351) (xy 145.343406 -412.23488)
			(xy 145.392991 -412.212236) (xy 145.445294 -412.196879) (xy 145.499251 -412.189123) (xy 145.526506 -412.18866)
			(xy 146.390106 -412.18866) (xy 146.417355 -412.189211) (xy 146.471297 -412.196967) (xy 146.523587 -412.212321)
			(xy 146.573159 -412.234961) (xy 146.619005 -412.264425) (xy 146.660191 -412.300113) (xy 146.695879 -412.3413)
			(xy 146.725342 -412.387146) (xy 146.747981 -412.436719) (xy 146.763334 -412.489009) (xy 146.77109 -412.542951)
			(xy 146.77109 -412.597449) (xy 146.771089 -412.597457) (xy 148.208623 -412.597457) (xy 148.208623 -412.542943)
			(xy 148.216382 -412.488983) (xy 148.231742 -412.436677) (xy 148.254389 -412.38709) (xy 148.283864 -412.341231)
			(xy 148.319566 -412.300033) (xy 148.360767 -412.264337) (xy 148.40663 -412.234867) (xy 148.45622 -412.212225)
			(xy 148.508528 -412.196872) (xy 148.562489 -412.18912) (xy 148.589746 -412.18866) (xy 149.453346 -412.18866)
			(xy 149.480593 -412.189213) (xy 149.534531 -412.196975) (xy 149.586816 -412.212332) (xy 149.636383 -412.234974)
			(xy 149.682224 -412.264439) (xy 149.723405 -412.300128) (xy 149.759088 -412.341313) (xy 149.788548 -412.387157)
			(xy 149.811184 -412.436727) (xy 149.826535 -412.489014) (xy 149.83429 -412.542953) (xy 149.83429 -412.597447)
			(xy 149.834289 -412.597453) (xy 151.271946 -412.597453) (xy 151.271946 -412.542947) (xy 151.279703 -412.488996)
			(xy 151.295058 -412.436698) (xy 151.3177 -412.387118) (xy 151.347168 -412.341264) (xy 151.382861 -412.300071)
			(xy 151.424053 -412.264376) (xy 151.469905 -412.234907) (xy 151.519485 -412.212263) (xy 151.571782 -412.196906)
			(xy 151.625733 -412.189147) (xy 151.652986 -412.18866) (xy 152.516586 -412.18866) (xy 152.543837 -412.189186)
			(xy 152.597785 -412.196941) (xy 152.65008 -412.212295) (xy 152.699658 -412.234934) (xy 152.745509 -412.264399)
			(xy 152.7867 -412.30009) (xy 152.822392 -412.34128) (xy 152.851859 -412.38713) (xy 152.874501 -412.436707)
			(xy 152.889856 -412.489001) (xy 152.897613 -412.542949) (xy 152.897613 -412.597451) (xy 152.897612 -412.597456)
			(xy 154.335123 -412.597456) (xy 154.335123 -412.542944) (xy 154.342881 -412.488986) (xy 154.35824 -412.436681)
			(xy 154.380886 -412.387095) (xy 154.410359 -412.341237) (xy 154.446059 -412.30004) (xy 154.487258 -412.264344)
			(xy 154.533118 -412.234874) (xy 154.582706 -412.212231) (xy 154.635011 -412.196876) (xy 154.68897 -412.189121)
			(xy 154.716226 -412.18866) (xy 155.579826 -412.18866) (xy 155.607074 -412.189212) (xy 155.661014 -412.196971)
			(xy 155.713301 -412.212327) (xy 155.762871 -412.234968) (xy 155.808714 -412.264432) (xy 155.849898 -412.300121)
			(xy 155.885584 -412.341307) (xy 155.915045 -412.387152) (xy 155.937682 -412.436723) (xy 155.953035 -412.489011)
			(xy 155.96079 -412.542952) (xy 155.96079 -412.597448) (xy 155.960789 -412.597452) (xy 157.398446 -412.597452)
			(xy 157.398446 -412.542948) (xy 157.406202 -412.488999) (xy 157.421557 -412.436702) (xy 157.444197 -412.387123)
			(xy 157.473663 -412.341271) (xy 157.509354 -412.300078) (xy 157.550543 -412.264383) (xy 157.596393 -412.234914)
			(xy 157.64597 -412.212269) (xy 157.698265 -412.196909) (xy 157.752214 -412.189148) (xy 157.779466 -412.18866)
			(xy 158.643066 -412.18866) (xy 158.670318 -412.189185) (xy 158.724268 -412.196937) (xy 158.776566 -412.212289)
			(xy 158.826146 -412.234928) (xy 158.872 -412.264392) (xy 158.913193 -412.300083) (xy 158.948887 -412.341273)
			(xy 158.978356 -412.387124) (xy 159.000999 -412.436702) (xy 159.016355 -412.488999) (xy 159.024113 -412.542948)
			(xy 159.024113 -412.597452) (xy 159.024113 -412.597455) (xy 160.461623 -412.597455) (xy 160.461623 -412.542945)
			(xy 160.469381 -412.488989) (xy 160.484738 -412.436686) (xy 160.507383 -412.387101) (xy 160.536854 -412.341244)
			(xy 160.572552 -412.300047) (xy 160.613749 -412.264351) (xy 160.659606 -412.23488) (xy 160.709191 -412.212236)
			(xy 160.761494 -412.196879) (xy 160.815451 -412.189123) (xy 160.842706 -412.18866) (xy 161.706306 -412.18866)
			(xy 161.733555 -412.189211) (xy 161.787497 -412.196967) (xy 161.839787 -412.212321) (xy 161.889359 -412.234961)
			(xy 161.935205 -412.264425) (xy 161.976391 -412.300113) (xy 162.012079 -412.3413) (xy 162.041542 -412.387146)
			(xy 162.064181 -412.436719) (xy 162.079534 -412.489009) (xy 162.08729 -412.542951) (xy 162.08729 -412.597449)
			(xy 162.079534 -412.651391) (xy 162.064181 -412.703681) (xy 162.041542 -412.753254) (xy 162.012079 -412.7991)
			(xy 161.976391 -412.840287) (xy 161.935205 -412.875975) (xy 161.889359 -412.905439) (xy 161.839787 -412.928079)
			(xy 161.787497 -412.943433) (xy 161.733555 -412.951189) (xy 161.706306 -412.951676) (xy 160.842706 -412.951676)
			(xy 160.815451 -412.951277) (xy 160.761494 -412.943521) (xy 160.709191 -412.928164) (xy 160.659606 -412.90552)
			(xy 160.613749 -412.876049) (xy 160.572552 -412.840353) (xy 160.536854 -412.799156) (xy 160.507383 -412.753299)
			(xy 160.484738 -412.703714) (xy 160.469381 -412.651411) (xy 160.461623 -412.597455) (xy 159.024113 -412.597455)
			(xy 159.016355 -412.651402) (xy 159.000999 -412.703698) (xy 158.978356 -412.753276) (xy 158.948887 -412.799127)
			(xy 158.913193 -412.840317) (xy 158.872 -412.876008) (xy 158.826146 -412.905472) (xy 158.776566 -412.928111)
			(xy 158.724268 -412.943463) (xy 158.670318 -412.951215) (xy 158.643066 -412.951676) (xy 157.779466 -412.951676)
			(xy 157.752214 -412.951252) (xy 157.698265 -412.943491) (xy 157.64597 -412.928131) (xy 157.596393 -412.905486)
			(xy 157.550543 -412.876017) (xy 157.509354 -412.840322) (xy 157.473663 -412.799129) (xy 157.444197 -412.753277)
			(xy 157.421557 -412.703698) (xy 157.406202 -412.651401) (xy 157.398446 -412.597452) (xy 155.960789 -412.597452)
			(xy 155.953035 -412.651389) (xy 155.937682 -412.703677) (xy 155.915045 -412.753248) (xy 155.885584 -412.799093)
			(xy 155.849898 -412.840279) (xy 155.808714 -412.875968) (xy 155.762871 -412.905432) (xy 155.713301 -412.928073)
			(xy 155.661014 -412.943429) (xy 155.607074 -412.951188) (xy 155.579826 -412.951676) (xy 154.716226 -412.951676)
			(xy 154.68897 -412.951279) (xy 154.635011 -412.943524) (xy 154.582706 -412.928169) (xy 154.533118 -412.905526)
			(xy 154.487258 -412.876056) (xy 154.446059 -412.84036) (xy 154.410359 -412.799163) (xy 154.380886 -412.753305)
			(xy 154.35824 -412.703719) (xy 154.342881 -412.651414) (xy 154.335123 -412.597456) (xy 152.897612 -412.597456)
			(xy 152.889856 -412.651399) (xy 152.874501 -412.703693) (xy 152.851859 -412.75327) (xy 152.822392 -412.79912)
			(xy 152.7867 -412.84031) (xy 152.745509 -412.876001) (xy 152.699658 -412.905466) (xy 152.65008 -412.928105)
			(xy 152.597785 -412.943459) (xy 152.543837 -412.951214) (xy 152.516586 -412.951676) (xy 151.652986 -412.951676)
			(xy 151.625733 -412.951253) (xy 151.571782 -412.943494) (xy 151.519485 -412.928137) (xy 151.469905 -412.905493)
			(xy 151.424053 -412.876024) (xy 151.382861 -412.840329) (xy 151.347168 -412.799136) (xy 151.3177 -412.753282)
			(xy 151.295058 -412.703702) (xy 151.279703 -412.651404) (xy 151.271946 -412.597453) (xy 149.834289 -412.597453)
			(xy 149.826535 -412.651386) (xy 149.811184 -412.703673) (xy 149.788548 -412.753243) (xy 149.759088 -412.799087)
			(xy 149.723405 -412.840272) (xy 149.682224 -412.875961) (xy 149.636383 -412.905426) (xy 149.586816 -412.928068)
			(xy 149.534531 -412.943425) (xy 149.480593 -412.951187) (xy 149.453346 -412.951676) (xy 148.589746 -412.951676)
			(xy 148.562489 -412.95128) (xy 148.508528 -412.943528) (xy 148.45622 -412.928175) (xy 148.40663 -412.905533)
			(xy 148.360767 -412.876063) (xy 148.319566 -412.840367) (xy 148.283864 -412.799169) (xy 148.254389 -412.75331)
			(xy 148.231742 -412.703723) (xy 148.216382 -412.651417) (xy 148.208623 -412.597457) (xy 146.771089 -412.597457)
			(xy 146.763334 -412.651391) (xy 146.747981 -412.703681) (xy 146.725342 -412.753254) (xy 146.695879 -412.7991)
			(xy 146.660191 -412.840287) (xy 146.619005 -412.875975) (xy 146.573159 -412.905439) (xy 146.523587 -412.928079)
			(xy 146.471297 -412.943433) (xy 146.417355 -412.951189) (xy 146.390106 -412.951676) (xy 145.526506 -412.951676)
			(xy 145.499251 -412.951277) (xy 145.445294 -412.943521) (xy 145.392991 -412.928164) (xy 145.343406 -412.90552)
			(xy 145.297549 -412.876049) (xy 145.256352 -412.840353) (xy 145.220654 -412.799156) (xy 145.191183 -412.753299)
			(xy 145.168538 -412.703714) (xy 145.153181 -412.651411) (xy 145.145423 -412.597455) (xy 143.707913 -412.597455)
			(xy 143.700155 -412.651402) (xy 143.684799 -412.703698) (xy 143.662156 -412.753276) (xy 143.632687 -412.799127)
			(xy 143.596993 -412.840317) (xy 143.5558 -412.876008) (xy 143.509946 -412.905472) (xy 143.460366 -412.928111)
			(xy 143.408068 -412.943463) (xy 143.354118 -412.951215) (xy 143.326866 -412.951676) (xy 142.463266 -412.951676)
			(xy 142.436014 -412.951252) (xy 142.382065 -412.943491) (xy 142.32977 -412.928131) (xy 142.280193 -412.905486)
			(xy 142.234343 -412.876017) (xy 142.193154 -412.840322) (xy 142.157463 -412.799129) (xy 142.127997 -412.753277)
			(xy 142.105357 -412.703698) (xy 142.090002 -412.651401) (xy 142.082246 -412.597452) (xy 140.644589 -412.597452)
			(xy 140.636835 -412.651389) (xy 140.621482 -412.703677) (xy 140.598845 -412.753248) (xy 140.569384 -412.799093)
			(xy 140.533698 -412.840279) (xy 140.492514 -412.875968) (xy 140.446671 -412.905432) (xy 140.397101 -412.928073)
			(xy 140.344814 -412.943429) (xy 140.290874 -412.951188) (xy 140.263626 -412.951676) (xy 139.400026 -412.951676)
			(xy 139.37277 -412.951279) (xy 139.318811 -412.943524) (xy 139.266506 -412.928169) (xy 139.216918 -412.905526)
			(xy 139.171058 -412.876056) (xy 139.129859 -412.84036) (xy 139.094159 -412.799163) (xy 139.064686 -412.753305)
			(xy 139.04204 -412.703719) (xy 139.026681 -412.651414) (xy 139.018923 -412.597456) (xy 137.581412 -412.597456)
			(xy 137.573656 -412.651399) (xy 137.558301 -412.703693) (xy 137.535659 -412.75327) (xy 137.506192 -412.79912)
			(xy 137.4705 -412.84031) (xy 137.429309 -412.876001) (xy 137.383458 -412.905466) (xy 137.33388 -412.928105)
			(xy 137.281585 -412.943459) (xy 137.227637 -412.951214) (xy 137.200386 -412.951676) (xy 136.336786 -412.951676)
			(xy 136.309533 -412.951253) (xy 136.255582 -412.943494) (xy 136.203285 -412.928137) (xy 136.153705 -412.905493)
			(xy 136.107853 -412.876024) (xy 136.066661 -412.840329) (xy 136.030968 -412.799136) (xy 136.0015 -412.753282)
			(xy 135.978858 -412.703702) (xy 135.963503 -412.651404) (xy 135.955746 -412.597453) (xy 134.518089 -412.597453)
			(xy 134.510335 -412.651386) (xy 134.494984 -412.703673) (xy 134.472348 -412.753243) (xy 134.442888 -412.799087)
			(xy 134.407205 -412.840272) (xy 134.366024 -412.875961) (xy 134.320183 -412.905426) (xy 134.270616 -412.928068)
			(xy 134.218331 -412.943425) (xy 134.164393 -412.951187) (xy 134.137146 -412.951676) (xy 133.273546 -412.951676)
			(xy 133.246289 -412.95128) (xy 133.192328 -412.943528) (xy 133.14002 -412.928175) (xy 133.09043 -412.905533)
			(xy 133.044567 -412.876063) (xy 133.003366 -412.840367) (xy 132.967664 -412.799169) (xy 132.938189 -412.75331)
			(xy 132.915542 -412.703723) (xy 132.900182 -412.651417) (xy 132.892423 -412.597457) (xy 131.454889 -412.597457)
			(xy 131.447134 -412.651391) (xy 131.431781 -412.703681) (xy 131.409142 -412.753254) (xy 131.379679 -412.7991)
			(xy 131.343991 -412.840287) (xy 131.302805 -412.875975) (xy 131.256959 -412.905439) (xy 131.207387 -412.928079)
			(xy 131.155097 -412.943433) (xy 131.101155 -412.951189) (xy 131.073906 -412.951676) (xy 130.210306 -412.951676)
			(xy 130.183051 -412.951277) (xy 130.129094 -412.943521) (xy 130.076791 -412.928164) (xy 130.027206 -412.90552)
			(xy 129.981349 -412.876049) (xy 129.940152 -412.840353) (xy 129.904454 -412.799156) (xy 129.874983 -412.753299)
			(xy 129.852338 -412.703714) (xy 129.836981 -412.651411) (xy 129.829223 -412.597455) (xy 128.391713 -412.597455)
			(xy 128.383955 -412.651402) (xy 128.368599 -412.703698) (xy 128.345956 -412.753276) (xy 128.316487 -412.799127)
			(xy 128.280793 -412.840317) (xy 128.2396 -412.876008) (xy 128.193746 -412.905472) (xy 128.144166 -412.928111)
			(xy 128.091868 -412.943463) (xy 128.037918 -412.951215) (xy 128.010666 -412.951676) (xy 127.147066 -412.951676)
			(xy 127.119814 -412.951252) (xy 127.065865 -412.943491) (xy 127.01357 -412.928131) (xy 126.963993 -412.905486)
			(xy 126.918143 -412.876017) (xy 126.876954 -412.840322) (xy 126.841263 -412.799129) (xy 126.811797 -412.753277)
			(xy 126.789157 -412.703698) (xy 126.773802 -412.651401) (xy 126.766046 -412.597452) (xy 125.328389 -412.597452)
			(xy 125.320635 -412.651389) (xy 125.305282 -412.703677) (xy 125.282645 -412.753248) (xy 125.253184 -412.799093)
			(xy 125.217498 -412.840279) (xy 125.176314 -412.875968) (xy 125.130471 -412.905432) (xy 125.080901 -412.928073)
			(xy 125.028614 -412.943429) (xy 124.974674 -412.951188) (xy 124.947426 -412.951676) (xy 124.083826 -412.951676)
			(xy 124.05657 -412.951279) (xy 124.002611 -412.943524) (xy 123.950306 -412.928169) (xy 123.900718 -412.905526)
			(xy 123.854858 -412.876056) (xy 123.813659 -412.84036) (xy 123.777959 -412.799163) (xy 123.748486 -412.753305)
			(xy 123.72584 -412.703719) (xy 123.710481 -412.651414) (xy 123.702723 -412.597456) (xy 122.265212 -412.597456)
			(xy 122.257456 -412.651399) (xy 122.242101 -412.703693) (xy 122.219459 -412.75327) (xy 122.189992 -412.79912)
			(xy 122.1543 -412.84031) (xy 122.113109 -412.876001) (xy 122.067258 -412.905466) (xy 122.01768 -412.928105)
			(xy 121.965385 -412.943459) (xy 121.911437 -412.951214) (xy 121.884186 -412.951676) (xy 121.020586 -412.951676)
			(xy 120.993333 -412.951253) (xy 120.939382 -412.943494) (xy 120.887085 -412.928137) (xy 120.837505 -412.905493)
			(xy 120.791653 -412.876024) (xy 120.750461 -412.840329) (xy 120.714768 -412.799136) (xy 120.6853 -412.753282)
			(xy 120.662658 -412.703702) (xy 120.647303 -412.651404) (xy 120.639546 -412.597453) (xy 119.201889 -412.597453)
			(xy 119.194135 -412.651386) (xy 119.178784 -412.703673) (xy 119.156148 -412.753243) (xy 119.126688 -412.799087)
			(xy 119.091005 -412.840272) (xy 119.049824 -412.875961) (xy 119.003983 -412.905426) (xy 118.954416 -412.928068)
			(xy 118.902131 -412.943425) (xy 118.848193 -412.951187) (xy 118.820946 -412.951676) (xy 117.957346 -412.951676)
			(xy 117.930089 -412.95128) (xy 117.876128 -412.943528) (xy 117.82382 -412.928175) (xy 117.77423 -412.905533)
			(xy 117.728367 -412.876063) (xy 117.687166 -412.840367) (xy 117.651464 -412.799169) (xy 117.621989 -412.75331)
			(xy 117.599342 -412.703723) (xy 117.583982 -412.651417) (xy 117.576223 -412.597457) (xy 116.138689 -412.597457)
			(xy 116.130934 -412.651391) (xy 116.115581 -412.703681) (xy 116.092942 -412.753254) (xy 116.063479 -412.7991)
			(xy 116.027791 -412.840287) (xy 115.986605 -412.875975) (xy 115.940759 -412.905439) (xy 115.891187 -412.928079)
			(xy 115.838897 -412.943433) (xy 115.784955 -412.951189) (xy 115.757706 -412.951676) (xy 114.894106 -412.951676)
			(xy 114.866851 -412.951277) (xy 114.812894 -412.943521) (xy 114.760591 -412.928164) (xy 114.711006 -412.90552)
			(xy 114.665149 -412.876049) (xy 114.623952 -412.840353) (xy 114.588254 -412.799156) (xy 114.558783 -412.753299)
			(xy 114.536138 -412.703714) (xy 114.520781 -412.651411) (xy 114.513023 -412.597455) (xy 94.987413 -412.597455)
			(xy 94.979655 -412.651402) (xy 94.964299 -412.703698) (xy 94.941656 -412.753276) (xy 94.912187 -412.799127)
			(xy 94.876492 -412.840318) (xy 94.835299 -412.876008) (xy 94.789445 -412.905473) (xy 94.739864 -412.928111)
			(xy 94.687567 -412.943463) (xy 94.633616 -412.951215) (xy 94.606364 -412.951676) (xy 93.742764 -412.951676)
			(xy 93.715512 -412.951252) (xy 93.661564 -412.94349) (xy 93.609269 -412.928131) (xy 93.559692 -412.905486)
			(xy 93.513842 -412.876016) (xy 93.472653 -412.840321) (xy 93.436962 -412.799129) (xy 93.407497 -412.753276)
			(xy 93.384857 -412.703697) (xy 93.369502 -412.651401) (xy 93.361746 -412.597452) (xy 91.924089 -412.597452)
			(xy 91.916335 -412.651389) (xy 91.900982 -412.703677) (xy 91.878345 -412.753249) (xy 91.848883 -412.799094)
			(xy 91.813197 -412.84028) (xy 91.772013 -412.875969) (xy 91.72617 -412.905433) (xy 91.6766 -412.928074)
			(xy 91.624312 -412.94343) (xy 91.570372 -412.951188) (xy 91.543124 -412.951676) (xy 90.679524 -412.951676)
			(xy 90.652268 -412.951279) (xy 90.59831 -412.943524) (xy 90.546004 -412.928169) (xy 90.496417 -412.905526)
			(xy 90.450557 -412.876056) (xy 90.409358 -412.840359) (xy 90.373659 -412.799162) (xy 90.344186 -412.753304)
			(xy 90.32154 -412.703718) (xy 90.306181 -412.651414) (xy 90.298423 -412.597456) (xy 88.860912 -412.597456)
			(xy 88.853156 -412.651399) (xy 88.8378 -412.703694) (xy 88.815159 -412.753271) (xy 88.785692 -412.799121)
			(xy 88.749999 -412.840311) (xy 88.708808 -412.876001) (xy 88.662957 -412.905466) (xy 88.613379 -412.928106)
			(xy 88.561083 -412.943459) (xy 88.507135 -412.951214) (xy 88.479884 -412.951676) (xy 87.616284 -412.951676)
			(xy 87.589031 -412.951253) (xy 87.535081 -412.943494) (xy 87.482783 -412.928136) (xy 87.433204 -412.905492)
			(xy 87.387352 -412.876023) (xy 87.34616 -412.840329) (xy 87.310467 -412.799135) (xy 87.281 -412.753282)
			(xy 87.258358 -412.703702) (xy 87.243003 -412.651404) (xy 87.235246 -412.597453) (xy 85.797589 -412.597453)
			(xy 85.789835 -412.651386) (xy 85.774484 -412.703673) (xy 85.751848 -412.753243) (xy 85.722388 -412.799087)
			(xy 85.686704 -412.840273) (xy 85.645523 -412.875962) (xy 85.599682 -412.905427) (xy 85.550114 -412.928068)
			(xy 85.497829 -412.943426) (xy 85.443891 -412.951187) (xy 85.416644 -412.951676) (xy 84.553044 -412.951676)
			(xy 84.525787 -412.95128) (xy 84.471827 -412.943528) (xy 84.419519 -412.928174) (xy 84.369929 -412.905532)
			(xy 84.324067 -412.876063) (xy 84.282865 -412.840366) (xy 84.247164 -412.799169) (xy 84.217689 -412.75331)
			(xy 84.195041 -412.703722) (xy 84.179682 -412.651417) (xy 84.171923 -412.597457) (xy 82.734389 -412.597457)
			(xy 82.726634 -412.651392) (xy 82.71128 -412.703682) (xy 82.688642 -412.753254) (xy 82.659178 -412.799101)
			(xy 82.62349 -412.840287) (xy 82.582304 -412.875976) (xy 82.536458 -412.90544) (xy 82.486885 -412.928079)
			(xy 82.434595 -412.943433) (xy 82.380653 -412.95119) (xy 82.353404 -412.951676) (xy 81.489804 -412.951676)
			(xy 81.462549 -412.951277) (xy 81.408593 -412.94352) (xy 81.35629 -412.928163) (xy 81.306705 -412.905519)
			(xy 81.260848 -412.876049) (xy 81.219651 -412.840352) (xy 81.183954 -412.799156) (xy 81.154483 -412.753298)
			(xy 81.131838 -412.703714) (xy 81.116481 -412.651411) (xy 81.108723 -412.597455) (xy 79.671213 -412.597455)
			(xy 79.663455 -412.651402) (xy 79.648099 -412.703698) (xy 79.625456 -412.753276) (xy 79.595987 -412.799127)
			(xy 79.560292 -412.840318) (xy 79.519099 -412.876008) (xy 79.473245 -412.905473) (xy 79.423664 -412.928111)
			(xy 79.371367 -412.943463) (xy 79.317416 -412.951215) (xy 79.290164 -412.951676) (xy 78.426564 -412.951676)
			(xy 78.399312 -412.951252) (xy 78.345364 -412.94349) (xy 78.293069 -412.928131) (xy 78.243492 -412.905486)
			(xy 78.197642 -412.876016) (xy 78.156453 -412.840321) (xy 78.120762 -412.799129) (xy 78.091297 -412.753276)
			(xy 78.068657 -412.703697) (xy 78.053302 -412.651401) (xy 78.045546 -412.597452) (xy 76.607889 -412.597452)
			(xy 76.600135 -412.651389) (xy 76.584782 -412.703677) (xy 76.562145 -412.753249) (xy 76.532683 -412.799094)
			(xy 76.496997 -412.84028) (xy 76.455813 -412.875969) (xy 76.40997 -412.905433) (xy 76.3604 -412.928074)
			(xy 76.308112 -412.94343) (xy 76.254172 -412.951188) (xy 76.226924 -412.951676) (xy 75.363324 -412.951676)
			(xy 75.336068 -412.951279) (xy 75.28211 -412.943524) (xy 75.229804 -412.928169) (xy 75.180217 -412.905526)
			(xy 75.134357 -412.876056) (xy 75.093158 -412.840359) (xy 75.057459 -412.799162) (xy 75.027986 -412.753304)
			(xy 75.00534 -412.703718) (xy 74.989981 -412.651414) (xy 74.982223 -412.597456) (xy 73.544712 -412.597456)
			(xy 73.536956 -412.651399) (xy 73.5216 -412.703694) (xy 73.498959 -412.753271) (xy 73.469492 -412.799121)
			(xy 73.433799 -412.840311) (xy 73.392608 -412.876001) (xy 73.346757 -412.905466) (xy 73.297179 -412.928106)
			(xy 73.244883 -412.943459) (xy 73.190935 -412.951214) (xy 73.163684 -412.951676) (xy 72.300084 -412.951676)
			(xy 72.272831 -412.951253) (xy 72.218881 -412.943494) (xy 72.166583 -412.928136) (xy 72.117004 -412.905492)
			(xy 72.071152 -412.876023) (xy 72.02996 -412.840329) (xy 71.994267 -412.799135) (xy 71.9648 -412.753282)
			(xy 71.942158 -412.703702) (xy 71.926803 -412.651404) (xy 71.919046 -412.597453) (xy 70.481389 -412.597453)
			(xy 70.473635 -412.651386) (xy 70.458284 -412.703673) (xy 70.435648 -412.753243) (xy 70.406188 -412.799087)
			(xy 70.370504 -412.840273) (xy 70.329323 -412.875962) (xy 70.283482 -412.905427) (xy 70.233914 -412.928068)
			(xy 70.181629 -412.943426) (xy 70.127691 -412.951187) (xy 70.100444 -412.951676) (xy 69.236844 -412.951676)
			(xy 69.209587 -412.95128) (xy 69.155627 -412.943528) (xy 69.103319 -412.928174) (xy 69.053729 -412.905532)
			(xy 69.007867 -412.876063) (xy 68.966665 -412.840366) (xy 68.930964 -412.799169) (xy 68.901489 -412.75331)
			(xy 68.878841 -412.703722) (xy 68.863482 -412.651417) (xy 68.855723 -412.597457) (xy 67.418189 -412.597457)
			(xy 67.410434 -412.651392) (xy 67.39508 -412.703682) (xy 67.372442 -412.753254) (xy 67.342978 -412.799101)
			(xy 67.30729 -412.840287) (xy 67.266104 -412.875976) (xy 67.220258 -412.90544) (xy 67.170685 -412.928079)
			(xy 67.118395 -412.943433) (xy 67.064453 -412.95119) (xy 67.037204 -412.951676) (xy 66.173604 -412.951676)
			(xy 66.146349 -412.951277) (xy 66.092393 -412.94352) (xy 66.04009 -412.928163) (xy 65.990505 -412.905519)
			(xy 65.944648 -412.876049) (xy 65.903451 -412.840352) (xy 65.867754 -412.799156) (xy 65.838283 -412.753298)
			(xy 65.815638 -412.703714) (xy 65.800281 -412.651411) (xy 65.792523 -412.597455) (xy 64.355013 -412.597455)
			(xy 64.347255 -412.651402) (xy 64.331899 -412.703698) (xy 64.309256 -412.753276) (xy 64.279787 -412.799127)
			(xy 64.244092 -412.840318) (xy 64.202899 -412.876008) (xy 64.157045 -412.905473) (xy 64.107464 -412.928111)
			(xy 64.055167 -412.943463) (xy 64.001216 -412.951215) (xy 63.973964 -412.951676) (xy 63.110364 -412.951676)
			(xy 63.083112 -412.951252) (xy 63.029164 -412.94349) (xy 62.976869 -412.928131) (xy 62.927292 -412.905486)
			(xy 62.881442 -412.876016) (xy 62.840253 -412.840321) (xy 62.804562 -412.799129) (xy 62.775097 -412.753276)
			(xy 62.752457 -412.703697) (xy 62.737102 -412.651401) (xy 62.729346 -412.597452) (xy 61.291689 -412.597452)
			(xy 61.283935 -412.651389) (xy 61.268582 -412.703677) (xy 61.245945 -412.753249) (xy 61.216483 -412.799094)
			(xy 61.180797 -412.84028) (xy 61.139613 -412.875969) (xy 61.09377 -412.905433) (xy 61.0442 -412.928074)
			(xy 60.991912 -412.94343) (xy 60.937972 -412.951188) (xy 60.910724 -412.951676) (xy 60.047124 -412.951676)
			(xy 60.019868 -412.951279) (xy 59.96591 -412.943524) (xy 59.913604 -412.928169) (xy 59.864017 -412.905526)
			(xy 59.818157 -412.876056) (xy 59.776958 -412.840359) (xy 59.741259 -412.799162) (xy 59.711786 -412.753304)
			(xy 59.68914 -412.703718) (xy 59.673781 -412.651414) (xy 59.666023 -412.597456) (xy 58.228512 -412.597456)
			(xy 58.220756 -412.651399) (xy 58.2054 -412.703694) (xy 58.182759 -412.753271) (xy 58.153292 -412.799121)
			(xy 58.117599 -412.840311) (xy 58.076408 -412.876001) (xy 58.030557 -412.905466) (xy 57.980979 -412.928106)
			(xy 57.928683 -412.943459) (xy 57.874735 -412.951214) (xy 57.847484 -412.951676) (xy 56.983884 -412.951676)
			(xy 56.956631 -412.951253) (xy 56.902681 -412.943494) (xy 56.850383 -412.928136) (xy 56.800804 -412.905492)
			(xy 56.754952 -412.876023) (xy 56.71376 -412.840329) (xy 56.678067 -412.799135) (xy 56.6486 -412.753282)
			(xy 56.625958 -412.703702) (xy 56.610603 -412.651404) (xy 56.602846 -412.597453) (xy 55.165189 -412.597453)
			(xy 55.157435 -412.651386) (xy 55.142084 -412.703673) (xy 55.119448 -412.753243) (xy 55.089988 -412.799087)
			(xy 55.054304 -412.840273) (xy 55.013123 -412.875962) (xy 54.967282 -412.905427) (xy 54.917714 -412.928068)
			(xy 54.865429 -412.943426) (xy 54.811491 -412.951187) (xy 54.784244 -412.951676) (xy 53.920644 -412.951676)
			(xy 53.893387 -412.95128) (xy 53.839427 -412.943528) (xy 53.787119 -412.928174) (xy 53.737529 -412.905532)
			(xy 53.691667 -412.876063) (xy 53.650465 -412.840366) (xy 53.614764 -412.799169) (xy 53.585289 -412.75331)
			(xy 53.562641 -412.703722) (xy 53.547282 -412.651417) (xy 53.539523 -412.597457) (xy 52.101989 -412.597457)
			(xy 52.094234 -412.651392) (xy 52.07888 -412.703682) (xy 52.056242 -412.753254) (xy 52.026778 -412.799101)
			(xy 51.99109 -412.840287) (xy 51.949904 -412.875976) (xy 51.904058 -412.90544) (xy 51.854485 -412.928079)
			(xy 51.802195 -412.943433) (xy 51.748253 -412.95119) (xy 51.721004 -412.951676) (xy 50.857404 -412.951676)
			(xy 50.830149 -412.951277) (xy 50.776193 -412.94352) (xy 50.72389 -412.928163) (xy 50.674305 -412.905519)
			(xy 50.628448 -412.876049) (xy 50.587251 -412.840352) (xy 50.551554 -412.799156) (xy 50.522083 -412.753298)
			(xy 50.499438 -412.703714) (xy 50.484081 -412.651411) (xy 50.476323 -412.597455) (xy 49.038813 -412.597455)
			(xy 49.031055 -412.651402) (xy 49.015699 -412.703698) (xy 48.993056 -412.753276) (xy 48.963587 -412.799127)
			(xy 48.927892 -412.840318) (xy 48.886699 -412.876008) (xy 48.840845 -412.905473) (xy 48.791264 -412.928111)
			(xy 48.738967 -412.943463) (xy 48.685016 -412.951215) (xy 48.657764 -412.951676) (xy 47.794164 -412.951676)
			(xy 47.766912 -412.951252) (xy 47.712964 -412.94349) (xy 47.660669 -412.928131) (xy 47.611092 -412.905486)
			(xy 47.565242 -412.876016) (xy 47.524053 -412.840321) (xy 47.488362 -412.799129) (xy 47.458897 -412.753276)
			(xy 47.436257 -412.703697) (xy 47.420902 -412.651401) (xy 47.413146 -412.597452) (xy 39.737792 -412.597452)
			(xy 39.737792 -413.4485) (xy 39.737556 -413.461769) (xy 105.629431 -413.461769) (xy 105.629431 -413.407231)
			(xy 105.637193 -413.353247) (xy 105.652559 -413.300918) (xy 105.675215 -413.251308) (xy 105.704702 -413.205427)
			(xy 105.740417 -413.16421) (xy 105.781635 -413.128496) (xy 105.827517 -413.099011) (xy 105.877127 -413.076355)
			(xy 105.929457 -413.060991) (xy 105.983441 -413.053231) (xy 106.01071 -413.052768) (xy 106.87431 -413.052768)
			(xy 106.901581 -413.053195) (xy 106.955568 -413.060959) (xy 107.0079 -413.076326) (xy 107.057513 -413.098985)
			(xy 107.103396 -413.128473) (xy 107.144616 -413.164191) (xy 107.180333 -413.205412) (xy 107.20982 -413.251296)
			(xy 107.232477 -413.300909) (xy 107.247844 -413.353242) (xy 107.255606 -413.407229) (xy 107.255606 -413.461771)
			(xy 107.247844 -413.515758) (xy 107.232477 -413.568091) (xy 107.20982 -413.617704) (xy 107.180333 -413.663588)
			(xy 107.144616 -413.704809) (xy 107.103396 -413.740527) (xy 107.057513 -413.770015) (xy 107.0079 -413.792674)
			(xy 106.955568 -413.808041) (xy 106.901581 -413.815805) (xy 106.87431 -413.816292) (xy 106.01071 -413.816292)
			(xy 105.983441 -413.815769) (xy 105.929457 -413.808009) (xy 105.877127 -413.792645) (xy 105.827517 -413.769989)
			(xy 105.781635 -413.740504) (xy 105.740417 -413.70479) (xy 105.704702 -413.663573) (xy 105.675215 -413.617692)
			(xy 105.652559 -413.568082) (xy 105.637193 -413.515753) (xy 105.629431 -413.461769) (xy 39.737556 -413.461769)
			(xy 39.737306 -413.475769) (xy 39.729544 -413.529753) (xy 39.714179 -413.582083) (xy 39.691522 -413.631693)
			(xy 39.662036 -413.677574) (xy 39.626321 -413.718791) (xy 39.585104 -413.754506) (xy 39.539223 -413.783992)
			(xy 39.489613 -413.806649) (xy 39.437283 -413.822014) (xy 39.383299 -413.829776) (xy 39.328761 -413.829776)
			(xy 39.274777 -413.822014) (xy 39.222447 -413.806649) (xy 39.172837 -413.783992) (xy 39.126956 -413.754506)
			(xy 39.085739 -413.718791) (xy 39.050024 -413.677574) (xy 39.020538 -413.631693) (xy 38.997881 -413.582083)
			(xy 38.982516 -413.529753) (xy 38.974754 -413.475769) (xy 38.974268 -413.4485) (xy 7.00913 -413.4485)
			(xy 7.00913 -415.383726) (xy 41.206928 -415.383726) (xy 41.206928 -414.520126) (xy 41.207414 -414.492857)
			(xy 41.215176 -414.438873) (xy 41.230541 -414.386543) (xy 41.253198 -414.336933) (xy 41.282684 -414.291052)
			(xy 41.318399 -414.249835) (xy 41.359616 -414.21412) (xy 41.405497 -414.184634) (xy 41.455107 -414.161977)
			(xy 41.507437 -414.146612) (xy 41.561421 -414.13885) (xy 41.615959 -414.13885) (xy 41.669943 -414.146612)
			(xy 41.722273 -414.161977) (xy 41.771883 -414.184634) (xy 41.817764 -414.21412) (xy 41.858981 -414.249835)
			(xy 41.894696 -414.291052) (xy 41.924182 -414.336933) (xy 41.946839 -414.386543) (xy 41.962204 -414.438873)
			(xy 41.969966 -414.492857) (xy 41.970452 -414.520126) (xy 41.970452 -415.383726) (xy 41.969966 -415.410995)
			(xy 41.962204 -415.464979) (xy 41.946839 -415.517309) (xy 41.924182 -415.566919) (xy 41.894696 -415.6128)
			(xy 41.858981 -415.654017) (xy 41.817764 -415.689732) (xy 41.771883 -415.719218) (xy 41.722273 -415.741875)
			(xy 41.669943 -415.75724) (xy 41.615959 -415.765002) (xy 41.561421 -415.765002) (xy 41.507437 -415.75724)
			(xy 41.455107 -415.741875) (xy 41.405497 -415.719218) (xy 41.359616 -415.689732) (xy 41.318399 -415.654017)
			(xy 41.282684 -415.6128) (xy 41.253198 -415.566919) (xy 41.230541 -415.517309) (xy 41.215176 -415.464979)
			(xy 41.207414 -415.410995) (xy 41.206928 -415.383726) (xy 7.00913 -415.383726) (xy 7.00913 -417.465002)
			(xy 35.832796 -417.465002) (xy 35.832796 -416.601402) (xy 35.833282 -416.574151) (xy 35.841038 -416.520203)
			(xy 35.856393 -416.467908) (xy 35.879035 -416.418331) (xy 35.908501 -416.372481) (xy 35.944192 -416.33129)
			(xy 35.985383 -416.295599) (xy 36.031233 -416.266133) (xy 36.08081 -416.243491) (xy 36.133105 -416.228136)
			(xy 36.187053 -416.22038) (xy 36.241555 -416.22038) (xy 36.295503 -416.228136) (xy 36.347798 -416.243491)
			(xy 36.397375 -416.266133) (xy 36.443225 -416.295599) (xy 36.484416 -416.33129) (xy 36.520107 -416.372481)
			(xy 36.549573 -416.418331) (xy 36.572215 -416.467908) (xy 36.58757 -416.520203) (xy 36.595326 -416.574151)
			(xy 36.595812 -416.601402) (xy 36.595812 -417.436808) (xy 48.812704 -417.436808) (xy 48.812704 -416.573208)
			(xy 48.81319 -416.545939) (xy 48.820952 -416.491955) (xy 48.836317 -416.439625) (xy 48.858974 -416.390015)
			(xy 48.88846 -416.344134) (xy 48.924175 -416.302917) (xy 48.965392 -416.267202) (xy 49.011273 -416.237716)
			(xy 49.060883 -416.215059) (xy 49.113213 -416.199694) (xy 49.167197 -416.191932) (xy 49.221735 -416.191932)
			(xy 49.275719 -416.199694) (xy 49.328049 -416.215059) (xy 49.377659 -416.237716) (xy 49.42354 -416.267202)
			(xy 49.464757 -416.302917) (xy 49.500472 -416.344134) (xy 49.529958 -416.390015) (xy 49.552615 -416.439625)
			(xy 49.56798 -416.491955) (xy 49.575742 -416.545939) (xy 49.576228 -416.573208) (xy 49.576228 -417.436808)
			(xy 49.575742 -417.464077) (xy 49.56798 -417.518061) (xy 49.552615 -417.570391) (xy 49.529958 -417.620001)
			(xy 49.500472 -417.665882) (xy 49.464757 -417.707099) (xy 49.42354 -417.742814) (xy 49.377659 -417.7723)
			(xy 49.328049 -417.794957) (xy 49.275719 -417.810322) (xy 49.221735 -417.818084) (xy 49.167197 -417.818084)
			(xy 49.113213 -417.810322) (xy 49.060883 -417.794957) (xy 49.011273 -417.7723) (xy 48.965392 -417.742814)
			(xy 48.924175 -417.707099) (xy 48.88846 -417.665882) (xy 48.858974 -417.620001) (xy 48.836317 -417.570391)
			(xy 48.820952 -417.518061) (xy 48.81319 -417.464077) (xy 48.812704 -417.436808) (xy 36.595812 -417.436808)
			(xy 36.595812 -417.465002) (xy 36.595326 -417.492253) (xy 36.58757 -417.546201) (xy 36.572215 -417.598496)
			(xy 36.549573 -417.648073) (xy 36.520107 -417.693923) (xy 36.484416 -417.735114) (xy 36.443225 -417.770805)
			(xy 36.397375 -417.800271) (xy 36.347798 -417.822913) (xy 36.295503 -417.838268) (xy 36.241555 -417.846024)
			(xy 36.187053 -417.846024) (xy 36.133105 -417.838268) (xy 36.08081 -417.822913) (xy 36.031233 -417.800271)
			(xy 35.985383 -417.770805) (xy 35.944192 -417.735114) (xy 35.908501 -417.693923) (xy 35.879035 -417.648073)
			(xy 35.856393 -417.598496) (xy 35.841038 -417.546201) (xy 35.833282 -417.492253) (xy 35.832796 -417.465002)
			(xy 7.00913 -417.465002) (xy 7.00913 -419.64102) (xy 51.809904 -419.64102) (xy 51.809904 -418.77742)
			(xy 51.81039 -418.750151) (xy 51.818152 -418.696167) (xy 51.833517 -418.643837) (xy 51.856174 -418.594227)
			(xy 51.88566 -418.548346) (xy 51.921375 -418.507129) (xy 51.962592 -418.471414) (xy 52.008473 -418.441928)
			(xy 52.058083 -418.419271) (xy 52.110413 -418.403906) (xy 52.164397 -418.396144) (xy 52.218935 -418.396144)
			(xy 52.272919 -418.403906) (xy 52.325249 -418.419271) (xy 52.374859 -418.441928) (xy 52.42074 -418.471414)
			(xy 52.461957 -418.507129) (xy 52.497672 -418.548346) (xy 52.527158 -418.594227) (xy 52.549815 -418.643837)
			(xy 52.56518 -418.696167) (xy 52.572942 -418.750151) (xy 52.573428 -418.77742) (xy 52.573428 -419.64102)
			(xy 52.572942 -419.668289) (xy 52.56518 -419.722273) (xy 52.549815 -419.774603) (xy 52.527158 -419.824213)
			(xy 52.497672 -419.870094) (xy 52.461957 -419.911311) (xy 52.42074 -419.947026) (xy 52.374859 -419.976512)
			(xy 52.325249 -419.999169) (xy 52.272919 -420.014534) (xy 52.218935 -420.022296) (xy 52.164397 -420.022296)
			(xy 52.110413 -420.014534) (xy 52.058083 -419.999169) (xy 52.008473 -419.976512) (xy 51.962592 -419.947026)
			(xy 51.921375 -419.911311) (xy 51.88566 -419.870094) (xy 51.856174 -419.824213) (xy 51.833517 -419.774603)
			(xy 51.818152 -419.722273) (xy 51.81039 -419.668289) (xy 51.809904 -419.64102) (xy 7.00913 -419.64102)
			(xy 7.00913 -421.200326) (xy 10.01268 -421.200326) (xy 10.01268 -420.336726) (xy 10.013166 -420.309475)
			(xy 10.020922 -420.255527) (xy 10.036277 -420.203232) (xy 10.058919 -420.153655) (xy 10.088385 -420.107805)
			(xy 10.124076 -420.066614) (xy 10.165267 -420.030923) (xy 10.211117 -420.001457) (xy 10.260694 -419.978815)
			(xy 10.312989 -419.96346) (xy 10.366937 -419.955704) (xy 10.421439 -419.955704) (xy 10.475387 -419.96346)
			(xy 10.527682 -419.978815) (xy 10.577259 -420.001457) (xy 10.623109 -420.030923) (xy 10.6643 -420.066614)
			(xy 10.699991 -420.107805) (xy 10.729457 -420.153655) (xy 10.752099 -420.203232) (xy 10.767454 -420.255527)
			(xy 10.77521 -420.309475) (xy 10.775696 -420.336726) (xy 10.775696 -421.200326) (xy 10.77521 -421.227577)
			(xy 10.769122 -421.269922) (xy 21.420836 -421.269922) (xy 21.420836 -420.406322) (xy 21.421322 -420.379071)
			(xy 21.429078 -420.325123) (xy 21.444433 -420.272828) (xy 21.467075 -420.223251) (xy 21.496541 -420.177401)
			(xy 21.532232 -420.13621) (xy 21.573423 -420.100519) (xy 21.619273 -420.071053) (xy 21.66885 -420.048411)
			(xy 21.721145 -420.033056) (xy 21.775093 -420.0253) (xy 21.829595 -420.0253) (xy 21.883543 -420.033056)
			(xy 21.935838 -420.048411) (xy 21.985415 -420.071053) (xy 22.031265 -420.100519) (xy 22.072456 -420.13621)
			(xy 22.108147 -420.177401) (xy 22.137613 -420.223251) (xy 22.160255 -420.272828) (xy 22.17561 -420.325123)
			(xy 22.183366 -420.379071) (xy 22.183852 -420.406322) (xy 22.183852 -420.760398) (xy 58.141108 -420.760398)
			(xy 58.141108 -418.218874) (xy 58.141589 -418.206761) (xy 58.14908 -418.183722) (xy 58.16332 -418.164123)
			(xy 58.182918 -418.149882) (xy 58.205957 -418.14239) (xy 58.21807 -418.141912) (xy 59.15787 -418.141912)
			(xy 59.169989 -418.142385) (xy 59.193042 -418.149866) (xy 59.212655 -418.164105) (xy 59.226908 -418.183708)
			(xy 59.234406 -418.206756) (xy 59.234832 -418.218874) (xy 59.234832 -420.760398) (xy 59.234438 -420.772524)
			(xy 59.226942 -420.795587) (xy 59.212685 -420.815205) (xy 59.193062 -420.829455) (xy 59.169996 -420.836942)
			(xy 59.15787 -420.83736) (xy 58.21807 -420.83736) (xy 58.205954 -420.836914) (xy 58.182909 -420.829418)
			(xy 58.163308 -420.81517) (xy 58.149067 -420.795562) (xy 58.141581 -420.772515) (xy 58.141108 -420.760398)
			(xy 22.183852 -420.760398) (xy 22.183852 -421.269922) (xy 22.183366 -421.297173) (xy 22.17561 -421.351121)
			(xy 22.160255 -421.403416) (xy 22.137613 -421.452993) (xy 22.108147 -421.498843) (xy 22.072456 -421.540034)
			(xy 22.031265 -421.575725) (xy 21.985415 -421.605191) (xy 21.935838 -421.627833) (xy 21.883543 -421.643188)
			(xy 21.829595 -421.650944) (xy 21.775093 -421.650944) (xy 21.721145 -421.643188) (xy 21.66885 -421.627833)
			(xy 21.619273 -421.605191) (xy 21.573423 -421.575725) (xy 21.532232 -421.540034) (xy 21.496541 -421.498843)
			(xy 21.467075 -421.452993) (xy 21.444433 -421.403416) (xy 21.429078 -421.351121) (xy 21.421322 -421.297173)
			(xy 21.420836 -421.269922) (xy 10.769122 -421.269922) (xy 10.767454 -421.281525) (xy 10.752099 -421.33382)
			(xy 10.729457 -421.383397) (xy 10.699991 -421.429247) (xy 10.6643 -421.470438) (xy 10.623109 -421.506129)
			(xy 10.577259 -421.535595) (xy 10.527682 -421.558237) (xy 10.475387 -421.573592) (xy 10.421439 -421.581348)
			(xy 10.366937 -421.581348) (xy 10.312989 -421.573592) (xy 10.260694 -421.558237) (xy 10.211117 -421.535595)
			(xy 10.165267 -421.506129) (xy 10.124076 -421.470438) (xy 10.088385 -421.429247) (xy 10.058919 -421.383397)
			(xy 10.036277 -421.33382) (xy 10.020922 -421.281525) (xy 10.013166 -421.227577) (xy 10.01268 -421.200326)
			(xy 7.00913 -421.200326) (xy 7.00913 -422.130474) (xy 24.87676 -422.130474) (xy 24.87676 -421.266874)
			(xy 24.877246 -421.239605) (xy 24.885008 -421.185621) (xy 24.900373 -421.133291) (xy 24.92303 -421.083681)
			(xy 24.952516 -421.0378) (xy 24.988231 -420.996583) (xy 25.029448 -420.960868) (xy 25.075329 -420.931382)
			(xy 25.124939 -420.908725) (xy 25.177269 -420.89336) (xy 25.231253 -420.885598) (xy 25.285791 -420.885598)
			(xy 25.339775 -420.89336) (xy 25.392105 -420.908725) (xy 25.441715 -420.931382) (xy 25.487596 -420.960868)
			(xy 25.528813 -420.996583) (xy 25.564528 -421.0378) (xy 25.594014 -421.083681) (xy 25.616671 -421.133291)
			(xy 25.632036 -421.185621) (xy 25.639798 -421.239605) (xy 25.640284 -421.266874) (xy 25.640284 -421.726974)
			(xy 27.323192 -421.726974) (xy 27.323192 -421.672426) (xy 27.330955 -421.618434) (xy 27.346324 -421.566097)
			(xy 27.368985 -421.51648) (xy 27.398477 -421.470593) (xy 27.4342 -421.429371) (xy 27.475427 -421.393652)
			(xy 27.521317 -421.364165) (xy 27.570936 -421.341509) (xy 27.623276 -421.326146) (xy 27.677268 -421.318389)
			(xy 27.704542 -421.317928) (xy 28.568142 -421.317928) (xy 28.595409 -421.318437) (xy 28.649386 -421.326204)
			(xy 28.701709 -421.341572) (xy 28.751313 -421.36423) (xy 28.797187 -421.393716) (xy 28.838399 -421.429431)
			(xy 28.874109 -421.470646) (xy 28.90359 -421.516524) (xy 28.926243 -421.56613) (xy 28.941605 -421.618455)
			(xy 28.949366 -421.672433) (xy 28.949366 -421.726967) (xy 28.941605 -421.780945) (xy 28.926243 -421.83327)
			(xy 28.90359 -421.882876) (xy 28.874109 -421.928754) (xy 28.838399 -421.969969) (xy 28.797187 -422.005684)
			(xy 28.751313 -422.03517) (xy 28.701709 -422.057828) (xy 28.649386 -422.073196) (xy 28.595409 -422.080963)
			(xy 28.568142 -422.081452) (xy 27.704542 -422.081452) (xy 27.677268 -422.081011) (xy 27.623276 -422.073254)
			(xy 27.570936 -422.057891) (xy 27.521317 -422.035235) (xy 27.475427 -422.005748) (xy 27.4342 -421.970029)
			(xy 27.398477 -421.928807) (xy 27.368985 -421.88292) (xy 27.346324 -421.833303) (xy 27.330955 -421.780966)
			(xy 27.323192 -421.726974) (xy 25.640284 -421.726974) (xy 25.640284 -422.130474) (xy 25.639798 -422.157743)
			(xy 25.632036 -422.211727) (xy 25.616671 -422.264057) (xy 25.594014 -422.313667) (xy 25.564528 -422.359548)
			(xy 25.528813 -422.400765) (xy 25.487596 -422.43648) (xy 25.441715 -422.465966) (xy 25.392105 -422.488623)
			(xy 25.339775 -422.503988) (xy 25.285791 -422.51175) (xy 25.231253 -422.51175) (xy 25.177269 -422.503988)
			(xy 25.124939 -422.488623) (xy 25.075329 -422.465966) (xy 25.029448 -422.43648) (xy 24.988231 -422.400765)
			(xy 24.952516 -422.359548) (xy 24.92303 -422.313667) (xy 24.900373 -422.264057) (xy 24.885008 -422.211727)
			(xy 24.877246 -422.157743) (xy 24.87676 -422.130474) (xy 7.00913 -422.130474) (xy 7.00913 -422.66627)
			(xy 38.762906 -422.66627) (xy 38.762906 -422.61173) (xy 38.770668 -422.557744) (xy 38.786034 -422.505412)
			(xy 38.808691 -422.4558) (xy 38.838178 -422.409918) (xy 38.873894 -422.368698) (xy 38.915113 -422.332981)
			(xy 38.960995 -422.303494) (xy 39.010607 -422.280836) (xy 39.062938 -422.26547) (xy 39.116924 -422.257707)
			(xy 39.144194 -422.25722) (xy 40.007794 -422.25722) (xy 40.035064 -422.257719) (xy 40.089049 -422.26548)
			(xy 40.14138 -422.280845) (xy 40.190991 -422.303501) (xy 40.236874 -422.332987) (xy 40.278093 -422.368703)
			(xy 40.313809 -422.409921) (xy 40.343296 -422.455803) (xy 40.365953 -422.505414) (xy 40.381319 -422.557745)
			(xy 40.389081 -422.61173) (xy 40.389081 -422.66627) (xy 40.381319 -422.720255) (xy 40.365953 -422.772586)
			(xy 40.343296 -422.822197) (xy 40.313809 -422.868079) (xy 40.278093 -422.909297) (xy 40.236874 -422.945013)
			(xy 40.190991 -422.974499) (xy 40.14138 -422.997155) (xy 40.089049 -423.01252) (xy 40.035064 -423.020281)
			(xy 40.007794 -423.020744) (xy 39.144194 -423.020744) (xy 39.116924 -423.020293) (xy 39.062938 -423.01253)
			(xy 39.010607 -422.997164) (xy 38.960995 -422.974506) (xy 38.915113 -422.945019) (xy 38.873894 -422.909302)
			(xy 38.838178 -422.868082) (xy 38.808691 -422.8222) (xy 38.786034 -422.772588) (xy 38.770668 -422.720256)
			(xy 38.762906 -422.66627) (xy 7.00913 -422.66627) (xy 7.00913 -423.057828) (xy 41.652952 -423.057828)
			(xy 41.652952 -422.194228) (xy 41.653438 -422.166959) (xy 41.6612 -422.112975) (xy 41.676565 -422.060645)
			(xy 41.699222 -422.011035) (xy 41.728708 -421.965154) (xy 41.764423 -421.923937) (xy 41.80564 -421.888222)
			(xy 41.851521 -421.858736) (xy 41.901131 -421.836079) (xy 41.953461 -421.820714) (xy 42.007445 -421.812952)
			(xy 42.061983 -421.812952) (xy 42.115967 -421.820714) (xy 42.168297 -421.836079) (xy 42.217907 -421.858736)
			(xy 42.263788 -421.888222) (xy 42.305005 -421.923937) (xy 42.34072 -421.965154) (xy 42.370206 -422.011035)
			(xy 42.392863 -422.060645) (xy 42.408228 -422.112975) (xy 42.41599 -422.166959) (xy 42.416476 -422.194228)
			(xy 42.416476 -423.057828) (xy 42.41599 -423.085097) (xy 42.408228 -423.139081) (xy 42.392863 -423.191411)
			(xy 42.370206 -423.241021) (xy 42.34072 -423.286902) (xy 42.305005 -423.328119) (xy 42.263788 -423.363834)
			(xy 42.217907 -423.39332) (xy 42.168297 -423.415977) (xy 42.115967 -423.431342) (xy 42.061983 -423.439104)
			(xy 42.007445 -423.439104) (xy 41.953461 -423.431342) (xy 41.901131 -423.415977) (xy 41.851521 -423.39332)
			(xy 41.80564 -423.363834) (xy 41.764423 -423.328119) (xy 41.728708 -423.286902) (xy 41.699222 -423.241021)
			(xy 41.676565 -423.191411) (xy 41.6612 -423.139081) (xy 41.653438 -423.085097) (xy 41.652952 -423.057828)
			(xy 7.00913 -423.057828) (xy 7.00913 -425.887642) (xy 10.204704 -425.887642) (xy 10.204704 -425.024042)
			(xy 10.20519 -424.996773) (xy 10.212952 -424.942789) (xy 10.228317 -424.890459) (xy 10.250974 -424.840849)
			(xy 10.28046 -424.794968) (xy 10.316175 -424.753751) (xy 10.357392 -424.718036) (xy 10.403273 -424.68855)
			(xy 10.452883 -424.665893) (xy 10.505213 -424.650528) (xy 10.559197 -424.642766) (xy 10.613735 -424.642766)
			(xy 10.667719 -424.650528) (xy 10.720049 -424.665893) (xy 10.769659 -424.68855) (xy 10.81554 -424.718036)
			(xy 10.856757 -424.753751) (xy 10.892472 -424.794968) (xy 10.921958 -424.840849) (xy 10.944615 -424.890459)
			(xy 10.95998 -424.942789) (xy 10.967742 -424.996773) (xy 10.968228 -425.024042) (xy 10.968228 -425.328334)
			(xy 21.942552 -425.328334) (xy 21.942552 -424.464734) (xy 21.943038 -424.437465) (xy 21.9508 -424.383481)
			(xy 21.966165 -424.331151) (xy 21.988822 -424.281541) (xy 22.018308 -424.23566) (xy 22.054023 -424.194443)
			(xy 22.09524 -424.158728) (xy 22.141121 -424.129242) (xy 22.190731 -424.106585) (xy 22.243061 -424.09122)
			(xy 22.297045 -424.083458) (xy 22.351583 -424.083458) (xy 22.405567 -424.09122) (xy 22.457897 -424.106585)
			(xy 22.507507 -424.129242) (xy 22.553388 -424.158728) (xy 22.594605 -424.194443) (xy 22.63032 -424.23566)
			(xy 22.659806 -424.281541) (xy 22.682463 -424.331151) (xy 22.691108 -424.360594) (xy 58.141108 -424.360594)
			(xy 58.141108 -421.81907) (xy 58.141586 -421.806957) (xy 58.149077 -421.783918) (xy 58.163319 -421.764319)
			(xy 58.182918 -421.750077) (xy 58.205957 -421.742586) (xy 58.21807 -421.742108) (xy 59.15787 -421.742108)
			(xy 59.16998 -421.742637) (xy 59.193017 -421.750112) (xy 59.207184 -421.760396) (xy 60.141104 -421.760396)
			(xy 60.141104 -419.218872) (xy 60.141493 -419.206761) (xy 60.149 -419.183732) (xy 60.163269 -419.164159)
			(xy 60.182896 -419.149966) (xy 60.205954 -419.142547) (xy 60.218066 -419.142164) (xy 61.157866 -419.142164)
			(xy 61.169956 -419.142637) (xy 61.19296 -419.150087) (xy 61.212542 -419.164271) (xy 61.226793 -419.183805)
			(xy 61.234322 -419.206783) (xy 61.234828 -419.218872) (xy 61.234828 -421.760396) (xy 61.234381 -421.772502)
			(xy 61.226886 -421.795524) (xy 61.212631 -421.815095) (xy 61.193018 -421.829291) (xy 61.169973 -421.836717)
			(xy 61.157866 -421.837104) (xy 60.218066 -421.837104) (xy 60.205979 -421.836623) (xy 60.182985 -421.829162)
			(xy 60.163409 -421.814977) (xy 60.149158 -421.79545) (xy 60.141619 -421.772481) (xy 60.141104 -421.760396)
			(xy 59.207184 -421.760396) (xy 59.212617 -421.76434) (xy 59.22686 -421.783929) (xy 59.234354 -421.80696)
			(xy 59.234832 -421.81907) (xy 59.234832 -424.360594) (xy 62.1411 -424.360594) (xy 62.1411 -421.81907)
			(xy 62.141585 -421.806958) (xy 62.149076 -421.78392) (xy 62.163316 -421.764322) (xy 62.182913 -421.75008)
			(xy 62.20595 -421.742587) (xy 62.218062 -421.742108) (xy 63.157862 -421.742108) (xy 63.16998 -421.742592)
			(xy 63.193032 -421.75007) (xy 63.207258 -421.760396) (xy 68.141088 -421.760396) (xy 68.141088 -419.218872)
			(xy 68.141492 -419.206763) (xy 68.148998 -419.183737) (xy 68.163263 -419.164165) (xy 68.182886 -419.149971)
			(xy 68.205939 -419.142549) (xy 68.21805 -419.142164) (xy 69.15785 -419.142164) (xy 69.169939 -419.14265)
			(xy 69.192942 -419.150096) (xy 69.212525 -419.164277) (xy 69.226777 -419.183808) (xy 69.234306 -419.206784)
			(xy 69.234812 -419.218872) (xy 69.234812 -420.760398) (xy 70.141084 -420.760398) (xy 70.141084 -418.218874)
			(xy 70.141438 -418.206745) (xy 70.148943 -418.183678) (xy 70.16321 -418.164059) (xy 70.182842 -418.14981)
			(xy 70.205917 -418.142327) (xy 70.218046 -418.141912) (xy 71.157846 -418.141912) (xy 71.16996 -418.142372)
			(xy 71.193001 -418.149869) (xy 71.212599 -418.164115) (xy 71.22684 -418.183717) (xy 71.234331 -418.20676)
			(xy 71.234808 -418.218874) (xy 71.234808 -418.3761) (xy 77.661008 -418.3761) (xy 77.661008 -417.5125)
			(xy 77.661494 -417.485231) (xy 77.669256 -417.431247) (xy 77.684621 -417.378917) (xy 77.707278 -417.329307)
			(xy 77.736764 -417.283426) (xy 77.772479 -417.242209) (xy 77.813696 -417.206494) (xy 77.859577 -417.177008)
			(xy 77.909187 -417.154351) (xy 77.961517 -417.138986) (xy 78.015501 -417.131224) (xy 78.070039 -417.131224)
			(xy 78.124023 -417.138986) (xy 78.176353 -417.154351) (xy 78.225963 -417.177008) (xy 78.271844 -417.206494)
			(xy 78.313061 -417.242209) (xy 78.348776 -417.283426) (xy 78.378262 -417.329307) (xy 78.400919 -417.378917)
			(xy 78.416284 -417.431247) (xy 78.424046 -417.485231) (xy 78.424532 -417.5125) (xy 78.424532 -418.3761)
			(xy 78.424046 -418.403369) (xy 78.416284 -418.457353) (xy 78.400919 -418.509683) (xy 78.378262 -418.559293)
			(xy 78.348776 -418.605174) (xy 78.313061 -418.646391) (xy 78.271844 -418.682106) (xy 78.225963 -418.711592)
			(xy 78.176353 -418.734249) (xy 78.124023 -418.749614) (xy 78.070039 -418.757376) (xy 78.015501 -418.757376)
			(xy 77.961517 -418.749614) (xy 77.909187 -418.734249) (xy 77.859577 -418.711592) (xy 77.813696 -418.682106)
			(xy 77.772479 -418.646391) (xy 77.736764 -418.605174) (xy 77.707278 -418.559293) (xy 77.684621 -418.509683)
			(xy 77.669256 -418.457353) (xy 77.661494 -418.403369) (xy 77.661008 -418.3761) (xy 71.234808 -418.3761)
			(xy 71.234808 -420.760398) (xy 71.234287 -420.772508) (xy 71.226806 -420.795543) (xy 71.212575 -420.815141)
			(xy 71.192986 -420.829384) (xy 71.169956 -420.83688) (xy 71.157846 -420.83736) (xy 70.218046 -420.83736)
			(xy 70.205925 -420.836901) (xy 70.182868 -420.829421) (xy 70.163252 -420.81518) (xy 70.148999 -420.795572)
			(xy 70.141506 -420.772518) (xy 70.141084 -420.760398) (xy 69.234812 -420.760398) (xy 69.234812 -421.760396)
			(xy 69.234381 -421.772503) (xy 69.226884 -421.795529) (xy 69.212626 -421.815101) (xy 69.193008 -421.829296)
			(xy 69.169959 -421.836719) (xy 69.15785 -421.837104) (xy 68.21805 -421.837104) (xy 68.205967 -421.836551)
			(xy 68.182976 -421.829113) (xy 68.163399 -421.814947) (xy 68.149145 -421.795434) (xy 68.141604 -421.772476)
			(xy 68.141088 -421.760396) (xy 63.207258 -421.760396) (xy 63.212645 -421.764306) (xy 63.226899 -421.783907)
			(xy 63.234398 -421.806953) (xy 63.234824 -421.81907) (xy 63.234824 -424.360594) (xy 63.234434 -424.37272)
			(xy 63.226939 -424.395785) (xy 63.212681 -424.415404) (xy 63.193057 -424.429654) (xy 63.169988 -424.437139)
			(xy 63.157862 -424.437556) (xy 62.218062 -424.437556) (xy 62.205945 -424.437121) (xy 62.182899 -424.429622)
			(xy 62.163298 -424.415371) (xy 62.149058 -424.395761) (xy 62.141572 -424.372711) (xy 62.1411 -424.360594)
			(xy 59.234832 -424.360594) (xy 59.234434 -424.372719) (xy 59.22694 -424.395783) (xy 59.212684 -424.415401)
			(xy 59.193062 -424.429651) (xy 59.169996 -424.437138) (xy 59.15787 -424.437556) (xy 58.21807 -424.437556)
			(xy 58.205953 -424.437114) (xy 58.182908 -424.429618) (xy 58.163306 -424.415368) (xy 58.149066 -424.39576)
			(xy 58.14158 -424.372711) (xy 58.141108 -424.360594) (xy 22.691108 -424.360594) (xy 22.697828 -424.383481)
			(xy 22.70559 -424.437465) (xy 22.706076 -424.464734) (xy 22.706076 -425.328334) (xy 22.70559 -425.355603)
			(xy 22.697828 -425.409587) (xy 22.682463 -425.461917) (xy 22.659806 -425.511527) (xy 22.63032 -425.557408)
			(xy 22.594605 -425.598625) (xy 22.553388 -425.63434) (xy 22.507507 -425.663826) (xy 22.457897 -425.686483)
			(xy 22.405567 -425.701848) (xy 22.351583 -425.70961) (xy 22.297045 -425.70961) (xy 22.243061 -425.701848)
			(xy 22.190731 -425.686483) (xy 22.141121 -425.663826) (xy 22.09524 -425.63434) (xy 22.054023 -425.598625)
			(xy 22.018308 -425.557408) (xy 21.988822 -425.511527) (xy 21.966165 -425.461917) (xy 21.9508 -425.409587)
			(xy 21.943038 -425.355603) (xy 21.942552 -425.328334) (xy 10.968228 -425.328334) (xy 10.968228 -425.887642)
			(xy 10.967742 -425.914911) (xy 10.964527 -425.937273) (xy 38.737196 -425.937273) (xy 38.737196 -425.882727)
			(xy 38.744959 -425.828736) (xy 38.760327 -425.776399) (xy 38.782988 -425.726782) (xy 38.81248 -425.680896)
			(xy 38.848202 -425.639674) (xy 38.889428 -425.603956) (xy 38.935317 -425.574469) (xy 38.984936 -425.551813)
			(xy 39.037275 -425.53645) (xy 39.091267 -425.528693) (xy 39.11854 -425.528232) (xy 39.98214 -425.528232)
			(xy 40.009407 -425.528733) (xy 40.063385 -425.536499) (xy 40.115709 -425.551868) (xy 40.165314 -425.574526)
			(xy 40.211189 -425.604012) (xy 40.252401 -425.639727) (xy 40.288112 -425.680943) (xy 40.317593 -425.726821)
			(xy 40.340246 -425.776428) (xy 40.355609 -425.828754) (xy 40.36337 -425.882733) (xy 40.36337 -425.937267)
			(xy 40.355609 -425.991246) (xy 40.340246 -426.043572) (xy 40.317593 -426.093179) (xy 40.288112 -426.139057)
			(xy 40.252401 -426.180273) (xy 40.211189 -426.215988) (xy 40.165314 -426.245474) (xy 40.115709 -426.268132)
			(xy 40.063385 -426.283501) (xy 40.009407 -426.291267) (xy 39.98214 -426.291756) (xy 39.11854 -426.291756)
			(xy 39.091267 -426.291307) (xy 39.037275 -426.28355) (xy 38.984936 -426.268187) (xy 38.935317 -426.245531)
			(xy 38.889428 -426.216044) (xy 38.848202 -426.180326) (xy 38.81248 -426.139104) (xy 38.782988 -426.093218)
			(xy 38.760327 -426.043601) (xy 38.744959 -425.991264) (xy 38.737196 -425.937273) (xy 10.964527 -425.937273)
			(xy 10.95998 -425.968895) (xy 10.944615 -426.021225) (xy 10.921958 -426.070835) (xy 10.892472 -426.116716)
			(xy 10.856757 -426.157933) (xy 10.81554 -426.193648) (xy 10.769659 -426.223134) (xy 10.720049 -426.245791)
			(xy 10.667719 -426.261156) (xy 10.613735 -426.268918) (xy 10.559197 -426.268918) (xy 10.505213 -426.261156)
			(xy 10.452883 -426.245791) (xy 10.403273 -426.223134) (xy 10.357392 -426.193648) (xy 10.316175 -426.157933)
			(xy 10.28046 -426.116716) (xy 10.250974 -426.070835) (xy 10.228317 -426.021225) (xy 10.212952 -425.968895)
			(xy 10.20519 -425.914911) (xy 10.204704 -425.887642) (xy 7.00913 -425.887642) (xy 7.00913 -426.333158)
			(xy 41.613836 -426.333158) (xy 41.613836 -425.469558) (xy 41.614322 -425.442307) (xy 41.622078 -425.388359)
			(xy 41.637433 -425.336064) (xy 41.660075 -425.286487) (xy 41.689541 -425.240637) (xy 41.725232 -425.199446)
			(xy 41.766423 -425.163755) (xy 41.812273 -425.134289) (xy 41.86185 -425.111647) (xy 41.914145 -425.096292)
			(xy 41.968093 -425.088536) (xy 42.022595 -425.088536) (xy 42.076543 -425.096292) (xy 42.128838 -425.111647)
			(xy 42.178415 -425.134289) (xy 42.224265 -425.163755) (xy 42.265456 -425.199446) (xy 42.301147 -425.240637)
			(xy 42.330613 -425.286487) (xy 42.353255 -425.336064) (xy 42.36861 -425.388359) (xy 42.376366 -425.442307)
			(xy 42.376852 -425.469558) (xy 42.376852 -426.333158) (xy 42.376366 -426.360409) (xy 42.36861 -426.414357)
			(xy 42.353255 -426.466652) (xy 42.330613 -426.516229) (xy 42.301147 -426.562079) (xy 42.265456 -426.60327)
			(xy 42.224265 -426.638961) (xy 42.178415 -426.668427) (xy 42.128838 -426.691069) (xy 42.076543 -426.706424)
			(xy 42.022595 -426.71418) (xy 41.968093 -426.71418) (xy 41.914145 -426.706424) (xy 41.86185 -426.691069)
			(xy 41.812273 -426.668427) (xy 41.766423 -426.638961) (xy 41.725232 -426.60327) (xy 41.689541 -426.562079)
			(xy 41.660075 -426.516229) (xy 41.637433 -426.466652) (xy 41.622078 -426.414357) (xy 41.614322 -426.360409)
			(xy 41.613836 -426.333158) (xy 7.00913 -426.333158) (xy 7.00913 -428.615602) (xy 25.13076 -428.615602)
			(xy 25.13076 -427.752002) (xy 25.131246 -427.724733) (xy 25.139008 -427.670749) (xy 25.154373 -427.618419)
			(xy 25.17703 -427.568809) (xy 25.206516 -427.522928) (xy 25.242231 -427.481711) (xy 25.283448 -427.445996)
			(xy 25.329329 -427.41651) (xy 25.378939 -427.393853) (xy 25.431269 -427.378488) (xy 25.485253 -427.370726)
			(xy 25.539791 -427.370726) (xy 25.593775 -427.378488) (xy 25.646105 -427.393853) (xy 25.695715 -427.41651)
			(xy 25.741596 -427.445996) (xy 25.782813 -427.481711) (xy 25.818528 -427.522928) (xy 25.848014 -427.568809)
			(xy 25.870671 -427.618419) (xy 25.886036 -427.670749) (xy 25.893798 -427.724733) (xy 25.894284 -427.752002)
			(xy 25.894284 -428.211072) (xy 26.941204 -428.211072) (xy 26.941204 -428.156528) (xy 26.948966 -428.102539)
			(xy 26.964334 -428.050205) (xy 26.986993 -428.00059) (xy 27.016483 -427.954705) (xy 27.052203 -427.913485)
			(xy 27.093426 -427.877767) (xy 27.139313 -427.848281) (xy 27.188929 -427.825625) (xy 27.241265 -427.810261)
			(xy 27.295254 -427.802502) (xy 27.322526 -427.80204) (xy 28.186126 -427.80204) (xy 28.213394 -427.802524)
			(xy 28.267375 -427.810289) (xy 28.319702 -427.825657) (xy 28.369309 -427.848314) (xy 28.415187 -427.877801)
			(xy 28.456402 -427.913517) (xy 28.492114 -427.954734) (xy 28.495843 -427.960536) (xy 58.141108 -427.960536)
			(xy 58.141108 -425.419012) (xy 58.141527 -425.406903) (xy 58.149024 -425.383875) (xy 58.163285 -425.364301)
			(xy 58.182906 -425.350106) (xy 58.20596 -425.342687) (xy 58.21807 -425.342304) (xy 59.15787 -425.342304)
			(xy 59.169954 -425.342832) (xy 59.192948 -425.350276) (xy 59.212525 -425.364448) (xy 59.226778 -425.383967)
			(xy 59.234317 -425.40693) (xy 59.234832 -425.419012) (xy 59.234832 -427.960536) (xy 59.234415 -427.972644)
			(xy 59.226909 -427.995667) (xy 59.212647 -428.015236) (xy 59.193028 -428.029431) (xy 59.169979 -428.036856)
			(xy 59.15787 -428.037244) (xy 58.21807 -428.037244) (xy 58.205977 -428.036818) (xy 58.182973 -428.029351)
			(xy 58.163392 -428.015154) (xy 58.149143 -427.995612) (xy 58.141615 -427.972627) (xy 58.141108 -427.960536)
			(xy 28.495843 -427.960536) (xy 28.521598 -428.000614) (xy 28.544253 -428.050222) (xy 28.559617 -428.10255)
			(xy 28.567378 -428.156532) (xy 28.567378 -428.211068) (xy 28.559617 -428.26505) (xy 28.544253 -428.317378)
			(xy 28.521598 -428.366986) (xy 28.492114 -428.412866) (xy 28.456402 -428.454083) (xy 28.415187 -428.489799)
			(xy 28.369309 -428.519286) (xy 28.319702 -428.541943) (xy 28.267375 -428.557311) (xy 28.213394 -428.565076)
			(xy 28.186126 -428.565564) (xy 27.322526 -428.565564) (xy 27.295254 -428.565098) (xy 27.241265 -428.557339)
			(xy 27.188929 -428.541975) (xy 27.139313 -428.519319) (xy 27.093426 -428.489833) (xy 27.052203 -428.454115)
			(xy 27.016483 -428.412895) (xy 26.986993 -428.36701) (xy 26.964334 -428.317395) (xy 26.948966 -428.265061)
			(xy 26.941204 -428.211072) (xy 25.894284 -428.211072) (xy 25.894284 -428.615602) (xy 25.893798 -428.642871)
			(xy 25.886036 -428.696855) (xy 25.870671 -428.749185) (xy 25.848014 -428.798795) (xy 25.818528 -428.844676)
			(xy 25.782813 -428.885893) (xy 25.741596 -428.921608) (xy 25.695715 -428.951094) (xy 25.646105 -428.973751)
			(xy 25.593775 -428.989116) (xy 25.539791 -428.996878) (xy 25.485253 -428.996878) (xy 25.431269 -428.989116)
			(xy 25.378939 -428.973751) (xy 25.329329 -428.951094) (xy 25.283448 -428.921608) (xy 25.242231 -428.885893)
			(xy 25.206516 -428.844676) (xy 25.17703 -428.798795) (xy 25.154373 -428.749185) (xy 25.139008 -428.696855)
			(xy 25.131246 -428.642871) (xy 25.13076 -428.615602) (xy 7.00913 -428.615602) (xy 7.00913 -431.560478)
			(xy 58.141108 -431.560478) (xy 58.141108 -429.018954) (xy 58.141572 -429.00684) (xy 58.149068 -428.9838)
			(xy 58.163313 -428.964202) (xy 58.182915 -428.949961) (xy 58.205956 -428.94247) (xy 58.21807 -428.941992)
			(xy 59.15787 -428.941992) (xy 59.169978 -428.942537) (xy 59.193013 -428.95001) (xy 59.207512 -428.960534)
			(xy 60.141104 -428.960534) (xy 60.141104 -426.41901) (xy 60.14162 -426.406899) (xy 60.1491 -426.383862)
			(xy 60.163332 -426.364263) (xy 60.182923 -426.35002) (xy 60.205956 -426.342527) (xy 60.218066 -426.342048)
			(xy 61.157866 -426.342048) (xy 61.169988 -426.342489) (xy 61.193047 -426.349973) (xy 61.212664 -426.364219)
			(xy 61.226916 -426.383831) (xy 61.234407 -426.406888) (xy 61.234828 -426.41901) (xy 61.234828 -427.960536)
			(xy 62.1411 -427.960536) (xy 62.1411 -425.419012) (xy 62.141527 -425.406904) (xy 62.149023 -425.383877)
			(xy 62.163282 -425.364304) (xy 62.182901 -425.350109) (xy 62.205952 -425.342688) (xy 62.218062 -425.342304)
			(xy 63.157862 -425.342304) (xy 63.169946 -425.342839) (xy 63.192939 -425.350281) (xy 63.207185 -425.360592)
			(xy 64.141096 -425.360592) (xy 64.141096 -422.819068) (xy 64.141489 -422.806958) (xy 64.148997 -422.78393)
			(xy 64.163265 -422.764358) (xy 64.18289 -422.750164) (xy 64.205946 -422.742744) (xy 64.218058 -422.74236)
			(xy 65.157858 -422.74236) (xy 65.169947 -422.742843) (xy 65.19295 -422.750291) (xy 65.212532 -422.764473)
			(xy 65.226784 -422.784004) (xy 65.234313 -422.80698) (xy 65.23482 -422.819068) (xy 65.23482 -425.360592)
			(xy 65.234377 -425.372698) (xy 65.226883 -425.395722) (xy 65.212627 -425.415294) (xy 65.193012 -425.429489)
			(xy 65.169966 -425.436914) (xy 65.157858 -425.4373) (xy 64.218058 -425.4373) (xy 64.20597 -425.436829)
			(xy 64.182975 -425.429366) (xy 64.163399 -425.415179) (xy 64.149149 -425.395649) (xy 64.141611 -425.372678)
			(xy 64.141096 -425.360592) (xy 63.207185 -425.360592) (xy 63.212517 -425.364451) (xy 63.22677 -425.383968)
			(xy 63.234309 -425.40693) (xy 63.234824 -425.419012) (xy 63.234824 -427.960536) (xy 63.234415 -427.972644)
			(xy 63.226908 -427.995669) (xy 63.212644 -428.015239) (xy 63.193023 -428.029433) (xy 63.169972 -428.036857)
			(xy 63.157862 -428.037244) (xy 62.218062 -428.037244) (xy 62.205969 -428.036825) (xy 62.182964 -428.029356)
			(xy 62.163384 -428.015157) (xy 62.149135 -427.995613) (xy 62.141607 -427.972628) (xy 62.1411 -427.960536)
			(xy 61.234828 -427.960536) (xy 61.234828 -428.960534) (xy 61.234417 -428.972654) (xy 61.226916 -428.995704)
			(xy 61.21266 -429.015308) (xy 61.193043 -429.029547) (xy 61.169986 -429.037027) (xy 61.157866 -429.037496)
			(xy 60.218066 -429.037496) (xy 60.205953 -429.037018) (xy 60.182914 -429.029525) (xy 60.163316 -429.015284)
			(xy 60.149075 -428.995686) (xy 60.141582 -428.972647) (xy 60.141104 -428.960534) (xy 59.207512 -428.960534)
			(xy 59.212611 -428.964235) (xy 59.226855 -428.983819) (xy 59.234351 -429.006846) (xy 59.234832 -429.018954)
			(xy 59.234832 -431.560478) (xy 59.234421 -431.572603) (xy 59.226931 -431.595666) (xy 59.212678 -431.615284)
			(xy 59.193059 -431.629535) (xy 59.169995 -431.637022) (xy 59.15787 -431.63744) (xy 58.21807 -431.63744)
			(xy 58.205952 -431.637014) (xy 58.182904 -431.629515) (xy 58.163301 -431.615262) (xy 58.149061 -431.59565)
			(xy 58.141578 -431.572597) (xy 58.141108 -431.560478) (xy 7.00913 -431.560478) (xy 7.00913 -435.16042)
			(xy 58.141108 -435.16042) (xy 58.141108 -432.618896) (xy 58.141513 -432.606786) (xy 58.149014 -432.583757)
			(xy 58.163279 -432.564184) (xy 58.182903 -432.549989) (xy 58.205959 -432.54257) (xy 58.21807 -432.542188)
			(xy 59.15787 -432.542188) (xy 59.169963 -432.542634) (xy 59.19297 -432.550088) (xy 59.207307 -432.560476)
			(xy 60.141104 -432.560476) (xy 60.141104 -430.018952) (xy 60.141476 -430.00684) (xy 60.148989 -429.983811)
			(xy 60.163262 -429.964238) (xy 60.182893 -429.950045) (xy 60.205953 -429.942626) (xy 60.218066 -429.942244)
			(xy 61.157866 -429.942244) (xy 61.169954 -429.942736) (xy 61.192954 -429.950184) (xy 61.212535 -429.964364)
			(xy 61.226787 -429.983893) (xy 61.234319 -430.006866) (xy 61.234828 -430.018952) (xy 61.234828 -431.560478)
			(xy 62.1411 -431.560478) (xy 62.1411 -429.018954) (xy 62.141572 -429.006841) (xy 62.149067 -428.983803)
			(xy 62.163311 -428.964205) (xy 62.18291 -428.949964) (xy 62.205949 -428.942471) (xy 62.218062 -428.941992)
			(xy 63.157862 -428.941992) (xy 63.16997 -428.942543) (xy 63.193004 -428.950015) (xy 63.207499 -428.960534)
			(xy 64.141096 -428.960534) (xy 64.141096 -426.41901) (xy 64.14162 -426.4069) (xy 64.149099 -426.383864)
			(xy 64.163329 -426.364266) (xy 64.182918 -426.350023) (xy 64.205948 -426.342528) (xy 64.218058 -426.342048)
			(xy 65.157858 -426.342048) (xy 65.16998 -426.342496) (xy 65.193039 -426.349978) (xy 65.212655 -426.364222)
			(xy 65.226908 -426.383833) (xy 65.234399 -426.406889) (xy 65.23482 -426.41901) (xy 65.23482 -427.960536)
			(xy 66.141092 -427.960536) (xy 66.141092 -425.419012) (xy 66.141527 -425.406905) (xy 66.149022 -425.383879)
			(xy 66.163279 -425.364307) (xy 66.182896 -425.350111) (xy 66.205945 -425.342689) (xy 66.218054 -425.342304)
			(xy 67.157854 -425.342304) (xy 67.169938 -425.342846) (xy 67.192931 -425.350286) (xy 67.207172 -425.360592)
			(xy 68.141088 -425.360592) (xy 68.141088 -422.819068) (xy 68.141489 -422.806959) (xy 68.148996 -422.783932)
			(xy 68.163262 -422.764361) (xy 68.182885 -422.750167) (xy 68.205939 -422.742745) (xy 68.21805 -422.74236)
			(xy 69.15785 -422.74236) (xy 69.169939 -422.74285) (xy 69.192941 -422.750296) (xy 69.212524 -422.764475)
			(xy 69.226775 -422.784006) (xy 69.234305 -422.806981) (xy 69.234812 -422.819068) (xy 69.234812 -424.360594)
			(xy 70.141084 -424.360594) (xy 70.141084 -421.81907) (xy 70.141435 -421.806941) (xy 70.148941 -421.783873)
			(xy 70.163209 -421.764255) (xy 70.182842 -421.750006) (xy 70.205917 -421.742523) (xy 70.218046 -421.742108)
			(xy 71.157846 -421.742108) (xy 71.16996 -421.742572) (xy 71.193 -421.750068) (xy 71.207209 -421.760396)
			(xy 72.14108 -421.760396) (xy 72.14108 -419.218872) (xy 72.141492 -419.206764) (xy 72.148997 -419.183739)
			(xy 72.16326 -419.164168) (xy 72.182881 -419.149974) (xy 72.205932 -419.14255) (xy 72.218042 -419.142164)
			(xy 73.157842 -419.142164) (xy 73.169936 -419.142572) (xy 73.192942 -419.150043) (xy 73.212524 -419.164244)
			(xy 73.226772 -419.183791) (xy 73.234298 -419.206779) (xy 73.234804 -419.218872) (xy 73.234804 -420.921688)
			(xy 75.13828 -420.921688) (xy 75.13828 -420.058088) (xy 75.138766 -420.030819) (xy 75.146528 -419.976835)
			(xy 75.161893 -419.924505) (xy 75.18455 -419.874895) (xy 75.214036 -419.829014) (xy 75.249751 -419.787797)
			(xy 75.290968 -419.752082) (xy 75.336849 -419.722596) (xy 75.386459 -419.699939) (xy 75.438789 -419.684574)
			(xy 75.492773 -419.676812) (xy 75.547311 -419.676812) (xy 75.601295 -419.684574) (xy 75.653625 -419.699939)
			(xy 75.703235 -419.722596) (xy 75.749116 -419.752082) (xy 75.790333 -419.787797) (xy 75.826048 -419.829014)
			(xy 75.855534 -419.874895) (xy 75.878191 -419.924505) (xy 75.893556 -419.976835) (xy 75.901318 -420.030819)
			(xy 75.901804 -420.058088) (xy 75.901804 -420.921688) (xy 75.901318 -420.948957) (xy 75.893556 -421.002941)
			(xy 75.878191 -421.055271) (xy 75.855534 -421.104881) (xy 75.844472 -421.122094) (xy 97.149412 -421.122094)
			(xy 97.149412 -414.328102) (xy 97.149934 -414.317948) (xy 97.157703 -414.299183) (xy 97.17206 -414.284819)
			(xy 97.19082 -414.27704) (xy 97.200974 -414.27654) (xy 102.099618 -414.27654) (xy 102.109777 -414.277018)
			(xy 102.128547 -414.284799) (xy 102.142912 -414.29917) (xy 102.150685 -414.317943) (xy 102.15118 -414.328102)
			(xy 102.15118 -420.700708) (xy 194.5894 -420.700708) (xy 194.5894 -413.816038) (xy 194.589861 -413.791087)
			(xy 194.597682 -413.741803) (xy 194.613107 -413.694345) (xy 194.635757 -413.649879) (xy 194.665075 -413.609499)
			(xy 194.682364 -413.591502) (xy 195.571872 -412.701994) (xy 195.589874 -412.684712) (xy 195.630249 -412.655387)
			(xy 195.674713 -412.632738) (xy 195.722172 -412.617322) (xy 195.771458 -412.609518) (xy 195.796408 -412.60903)
			(xy 226.779074 -412.60903) (xy 226.789144 -412.60861) (xy 226.807743 -412.600887) (xy 226.815142 -412.594044)
			(xy 229.321106 -410.08808) (xy 229.339091 -410.070779) (xy 229.37947 -410.041457) (xy 229.423939 -410.018812)
			(xy 229.471402 -410.0034) (xy 229.520691 -409.995602) (xy 229.545642 -409.995116) (xy 234.563158 -409.995116)
			(xy 234.573228 -409.994691) (xy 234.591827 -409.986972) (xy 234.599226 -409.98013) (xy 238.550196 -406.02916)
			(xy 238.557046 -406.021767) (xy 238.56476 -406.003162) (xy 238.565182 -405.993092) (xy 238.565182 -397.979646)
			(xy 238.565653 -397.954696) (xy 238.573473 -397.905412) (xy 238.588896 -397.857954) (xy 238.611543 -397.813489)
			(xy 238.640859 -397.773107) (xy 238.658146 -397.75511) (xy 239.17656 -397.236696) (xy 239.194568 -397.21942)
			(xy 239.234941 -397.190094) (xy 239.279403 -397.167444) (xy 239.326861 -397.152026) (xy 239.376146 -397.144221)
			(xy 239.401096 -397.143732) (xy 279.415748 -397.143732) (xy 279.440697 -397.144221) (xy 279.48998 -397.152039)
			(xy 279.537437 -397.167458) (xy 279.581902 -397.190101) (xy 279.622285 -397.219411) (xy 279.640284 -397.236696)
			(xy 280.592276 -398.188688) (xy 280.609561 -398.206688) (xy 280.638886 -398.247062) (xy 280.661536 -398.291527)
			(xy 280.676951 -398.338987) (xy 280.684753 -398.388274) (xy 280.68524 -398.413224) (xy 280.68524 -401.674838)
			(xy 303.434496 -401.674838) (xy 303.434496 -400.811238) (xy 303.434982 -400.783969) (xy 303.442744 -400.729985)
			(xy 303.458109 -400.677655) (xy 303.480766 -400.628045) (xy 303.510252 -400.582164) (xy 303.545967 -400.540947)
			(xy 303.587184 -400.505232) (xy 303.633065 -400.475746) (xy 303.682675 -400.453089) (xy 303.735005 -400.437724)
			(xy 303.788989 -400.429962) (xy 303.843527 -400.429962) (xy 303.897511 -400.437724) (xy 303.949841 -400.453089)
			(xy 303.999451 -400.475746) (xy 304.045332 -400.505232) (xy 304.086549 -400.540947) (xy 304.122264 -400.582164)
			(xy 304.15175 -400.628045) (xy 304.174407 -400.677655) (xy 304.189772 -400.729985) (xy 304.197534 -400.783969)
			(xy 304.19802 -400.811238) (xy 304.19802 -401.674838) (xy 304.634392 -401.674838) (xy 304.634392 -400.811238)
			(xy 304.634878 -400.783969) (xy 304.64264 -400.729985) (xy 304.658005 -400.677655) (xy 304.680662 -400.628045)
			(xy 304.710148 -400.582164) (xy 304.745863 -400.540947) (xy 304.78708 -400.505232) (xy 304.832961 -400.475746)
			(xy 304.882571 -400.453089) (xy 304.934901 -400.437724) (xy 304.988885 -400.429962) (xy 305.043423 -400.429962)
			(xy 305.097407 -400.437724) (xy 305.149737 -400.453089) (xy 305.199347 -400.475746) (xy 305.245228 -400.505232)
			(xy 305.286445 -400.540947) (xy 305.32216 -400.582164) (xy 305.351646 -400.628045) (xy 305.374303 -400.677655)
			(xy 305.389668 -400.729985) (xy 305.39743 -400.783969) (xy 305.397916 -400.811238) (xy 305.397916 -401.674838)
			(xy 305.834796 -401.674838) (xy 305.834796 -400.811238) (xy 305.835282 -400.783987) (xy 305.843038 -400.730039)
			(xy 305.858393 -400.677744) (xy 305.881035 -400.628167) (xy 305.910501 -400.582317) (xy 305.946192 -400.541126)
			(xy 305.987383 -400.505435) (xy 306.033233 -400.475969) (xy 306.08281 -400.453327) (xy 306.135105 -400.437972)
			(xy 306.189053 -400.430216) (xy 306.243555 -400.430216) (xy 306.297503 -400.437972) (xy 306.349798 -400.453327)
			(xy 306.399375 -400.475969) (xy 306.445225 -400.505435) (xy 306.486416 -400.541126) (xy 306.522107 -400.582317)
			(xy 306.551573 -400.628167) (xy 306.574215 -400.677744) (xy 306.58957 -400.730039) (xy 306.597326 -400.783987)
			(xy 306.597812 -400.811238) (xy 306.597812 -401.674838) (xy 307.034692 -401.674838) (xy 307.034692 -400.811238)
			(xy 307.035178 -400.783987) (xy 307.042934 -400.730039) (xy 307.058289 -400.677744) (xy 307.080931 -400.628167)
			(xy 307.110397 -400.582317) (xy 307.146088 -400.541126) (xy 307.187279 -400.505435) (xy 307.233129 -400.475969)
			(xy 307.282706 -400.453327) (xy 307.335001 -400.437972) (xy 307.388949 -400.430216) (xy 307.443451 -400.430216)
			(xy 307.497399 -400.437972) (xy 307.549694 -400.453327) (xy 307.599271 -400.475969) (xy 307.645121 -400.505435)
			(xy 307.686312 -400.541126) (xy 307.722003 -400.582317) (xy 307.751469 -400.628167) (xy 307.774111 -400.677744)
			(xy 307.789466 -400.730039) (xy 307.797222 -400.783987) (xy 307.797708 -400.811238) (xy 307.797708 -401.674838)
			(xy 308.234588 -401.674838) (xy 308.234588 -400.811238) (xy 308.235074 -400.783969) (xy 308.242836 -400.729985)
			(xy 308.258201 -400.677655) (xy 308.280858 -400.628045) (xy 308.310344 -400.582164) (xy 308.346059 -400.540947)
			(xy 308.387276 -400.505232) (xy 308.433157 -400.475746) (xy 308.482767 -400.453089) (xy 308.535097 -400.437724)
			(xy 308.589081 -400.429962) (xy 308.643619 -400.429962) (xy 308.697603 -400.437724) (xy 308.749933 -400.453089)
			(xy 308.799543 -400.475746) (xy 308.845424 -400.505232) (xy 308.886641 -400.540947) (xy 308.922356 -400.582164)
			(xy 308.951842 -400.628045) (xy 308.974499 -400.677655) (xy 308.989864 -400.729985) (xy 308.997626 -400.783969)
			(xy 308.998112 -400.811238) (xy 308.998112 -401.674838) (xy 309.434484 -401.674838) (xy 309.434484 -400.811238)
			(xy 309.43497 -400.783969) (xy 309.442732 -400.729985) (xy 309.458097 -400.677655) (xy 309.480754 -400.628045)
			(xy 309.51024 -400.582164) (xy 309.545955 -400.540947) (xy 309.587172 -400.505232) (xy 309.633053 -400.475746)
			(xy 309.682663 -400.453089) (xy 309.734993 -400.437724) (xy 309.788977 -400.429962) (xy 309.843515 -400.429962)
			(xy 309.897499 -400.437724) (xy 309.949829 -400.453089) (xy 309.999439 -400.475746) (xy 310.04532 -400.505232)
			(xy 310.086537 -400.540947) (xy 310.122252 -400.582164) (xy 310.151738 -400.628045) (xy 310.174395 -400.677655)
			(xy 310.18976 -400.729985) (xy 310.197522 -400.783969) (xy 310.198008 -400.811238) (xy 310.198008 -401.674838)
			(xy 310.634888 -401.674838) (xy 310.634888 -400.811238) (xy 310.635374 -400.783987) (xy 310.64313 -400.730039)
			(xy 310.658485 -400.677744) (xy 310.681127 -400.628167) (xy 310.710593 -400.582317) (xy 310.746284 -400.541126)
			(xy 310.787475 -400.505435) (xy 310.833325 -400.475969) (xy 310.882902 -400.453327) (xy 310.935197 -400.437972)
			(xy 310.989145 -400.430216) (xy 311.043647 -400.430216) (xy 311.097595 -400.437972) (xy 311.14989 -400.453327)
			(xy 311.199467 -400.475969) (xy 311.245317 -400.505435) (xy 311.286508 -400.541126) (xy 311.322199 -400.582317)
			(xy 311.351665 -400.628167) (xy 311.374307 -400.677744) (xy 311.389662 -400.730039) (xy 311.397418 -400.783987)
			(xy 311.397904 -400.811238) (xy 311.397904 -401.674838) (xy 311.834784 -401.674838) (xy 311.834784 -400.811238)
			(xy 311.83527 -400.783987) (xy 311.843026 -400.730039) (xy 311.858381 -400.677744) (xy 311.881023 -400.628167)
			(xy 311.910489 -400.582317) (xy 311.94618 -400.541126) (xy 311.987371 -400.505435) (xy 312.033221 -400.475969)
			(xy 312.082798 -400.453327) (xy 312.135093 -400.437972) (xy 312.189041 -400.430216) (xy 312.243543 -400.430216)
			(xy 312.297491 -400.437972) (xy 312.349786 -400.453327) (xy 312.399363 -400.475969) (xy 312.445213 -400.505435)
			(xy 312.486404 -400.541126) (xy 312.522095 -400.582317) (xy 312.551561 -400.628167) (xy 312.574203 -400.677744)
			(xy 312.589558 -400.730039) (xy 312.597314 -400.783987) (xy 312.5978 -400.811238) (xy 312.5978 -401.674838)
			(xy 313.03468 -401.674838) (xy 313.03468 -400.811238) (xy 313.035166 -400.783969) (xy 313.042928 -400.729985)
			(xy 313.058293 -400.677655) (xy 313.08095 -400.628045) (xy 313.110436 -400.582164) (xy 313.146151 -400.540947)
			(xy 313.187368 -400.505232) (xy 313.233249 -400.475746) (xy 313.282859 -400.453089) (xy 313.335189 -400.437724)
			(xy 313.389173 -400.429962) (xy 313.443711 -400.429962) (xy 313.497695 -400.437724) (xy 313.550025 -400.453089)
			(xy 313.599635 -400.475746) (xy 313.645516 -400.505232) (xy 313.686733 -400.540947) (xy 313.722448 -400.582164)
			(xy 313.751934 -400.628045) (xy 313.774591 -400.677655) (xy 313.789956 -400.729985) (xy 313.797718 -400.783969)
			(xy 313.798204 -400.811238) (xy 313.798204 -401.674838) (xy 314.234576 -401.674838) (xy 314.234576 -400.811238)
			(xy 314.235062 -400.783969) (xy 314.242824 -400.729985) (xy 314.258189 -400.677655) (xy 314.280846 -400.628045)
			(xy 314.310332 -400.582164) (xy 314.346047 -400.540947) (xy 314.387264 -400.505232) (xy 314.433145 -400.475746)
			(xy 314.482755 -400.453089) (xy 314.535085 -400.437724) (xy 314.589069 -400.429962) (xy 314.643607 -400.429962)
			(xy 314.697591 -400.437724) (xy 314.749921 -400.453089) (xy 314.799531 -400.475746) (xy 314.845412 -400.505232)
			(xy 314.886629 -400.540947) (xy 314.922344 -400.582164) (xy 314.95183 -400.628045) (xy 314.974487 -400.677655)
			(xy 314.989852 -400.729985) (xy 314.997614 -400.783969) (xy 314.9981 -400.811238) (xy 314.9981 -401.674838)
			(xy 315.43498 -401.674838) (xy 315.43498 -400.811238) (xy 315.435466 -400.783987) (xy 315.443222 -400.730039)
			(xy 315.458577 -400.677744) (xy 315.481219 -400.628167) (xy 315.510685 -400.582317) (xy 315.546376 -400.541126)
			(xy 315.587567 -400.505435) (xy 315.633417 -400.475969) (xy 315.682994 -400.453327) (xy 315.735289 -400.437972)
			(xy 315.789237 -400.430216) (xy 315.843739 -400.430216) (xy 315.897687 -400.437972) (xy 315.949982 -400.453327)
			(xy 315.999559 -400.475969) (xy 316.045409 -400.505435) (xy 316.0866 -400.541126) (xy 316.122291 -400.582317)
			(xy 316.151757 -400.628167) (xy 316.174399 -400.677744) (xy 316.189754 -400.730039) (xy 316.19751 -400.783987)
			(xy 316.197996 -400.811238) (xy 316.197996 -401.674838) (xy 316.634876 -401.674838) (xy 316.634876 -400.811238)
			(xy 316.635362 -400.783987) (xy 316.643118 -400.730039) (xy 316.658473 -400.677744) (xy 316.681115 -400.628167)
			(xy 316.710581 -400.582317) (xy 316.746272 -400.541126) (xy 316.787463 -400.505435) (xy 316.833313 -400.475969)
			(xy 316.88289 -400.453327) (xy 316.935185 -400.437972) (xy 316.989133 -400.430216) (xy 317.043635 -400.430216)
			(xy 317.097583 -400.437972) (xy 317.149878 -400.453327) (xy 317.199455 -400.475969) (xy 317.245305 -400.505435)
			(xy 317.286496 -400.541126) (xy 317.322187 -400.582317) (xy 317.351653 -400.628167) (xy 317.374295 -400.677744)
			(xy 317.38965 -400.730039) (xy 317.397406 -400.783987) (xy 317.397892 -400.811238) (xy 317.397892 -401.674838)
			(xy 317.834772 -401.674838) (xy 317.834772 -400.811238) (xy 317.835258 -400.783987) (xy 317.843014 -400.730039)
			(xy 317.858369 -400.677744) (xy 317.881011 -400.628167) (xy 317.910477 -400.582317) (xy 317.946168 -400.541126)
			(xy 317.987359 -400.505435) (xy 318.033209 -400.475969) (xy 318.082786 -400.453327) (xy 318.135081 -400.437972)
			(xy 318.189029 -400.430216) (xy 318.243531 -400.430216) (xy 318.297479 -400.437972) (xy 318.349774 -400.453327)
			(xy 318.399351 -400.475969) (xy 318.445201 -400.505435) (xy 318.486392 -400.541126) (xy 318.522083 -400.582317)
			(xy 318.551549 -400.628167) (xy 318.574191 -400.677744) (xy 318.589546 -400.730039) (xy 318.597302 -400.783987)
			(xy 318.597788 -400.811238) (xy 318.597788 -401.674838) (xy 319.034668 -401.674838) (xy 319.034668 -400.811238)
			(xy 319.035154 -400.783987) (xy 319.04291 -400.730039) (xy 319.058265 -400.677744) (xy 319.080907 -400.628167)
			(xy 319.110373 -400.582317) (xy 319.146064 -400.541126) (xy 319.187255 -400.505435) (xy 319.233105 -400.475969)
			(xy 319.282682 -400.453327) (xy 319.334977 -400.437972) (xy 319.388925 -400.430216) (xy 319.443427 -400.430216)
			(xy 319.497375 -400.437972) (xy 319.54967 -400.453327) (xy 319.599247 -400.475969) (xy 319.645097 -400.505435)
			(xy 319.686288 -400.541126) (xy 319.721979 -400.582317) (xy 319.751445 -400.628167) (xy 319.774087 -400.677744)
			(xy 319.789442 -400.730039) (xy 319.797198 -400.783987) (xy 319.797684 -400.811238) (xy 319.797684 -401.674838)
			(xy 320.234564 -401.674838) (xy 320.234564 -400.811238) (xy 320.23505 -400.783969) (xy 320.242812 -400.729985)
			(xy 320.258177 -400.677655) (xy 320.280834 -400.628045) (xy 320.31032 -400.582164) (xy 320.346035 -400.540947)
			(xy 320.387252 -400.505232) (xy 320.433133 -400.475746) (xy 320.482743 -400.453089) (xy 320.535073 -400.437724)
			(xy 320.589057 -400.429962) (xy 320.643595 -400.429962) (xy 320.697579 -400.437724) (xy 320.749909 -400.453089)
			(xy 320.799519 -400.475746) (xy 320.8454 -400.505232) (xy 320.886617 -400.540947) (xy 320.922332 -400.582164)
			(xy 320.951818 -400.628045) (xy 320.974475 -400.677655) (xy 320.98984 -400.729985) (xy 320.997602 -400.783969)
			(xy 320.998088 -400.811238) (xy 320.998088 -401.674838) (xy 321.43446 -401.674838) (xy 321.43446 -400.811238)
			(xy 321.434946 -400.783969) (xy 321.442708 -400.729985) (xy 321.458073 -400.677655) (xy 321.48073 -400.628045)
			(xy 321.510216 -400.582164) (xy 321.545931 -400.540947) (xy 321.587148 -400.505232) (xy 321.633029 -400.475746)
			(xy 321.682639 -400.453089) (xy 321.734969 -400.437724) (xy 321.788953 -400.429962) (xy 321.843491 -400.429962)
			(xy 321.897475 -400.437724) (xy 321.949805 -400.453089) (xy 321.999415 -400.475746) (xy 322.045296 -400.505232)
			(xy 322.086513 -400.540947) (xy 322.122228 -400.582164) (xy 322.151714 -400.628045) (xy 322.174371 -400.677655)
			(xy 322.189736 -400.729985) (xy 322.197498 -400.783969) (xy 322.197984 -400.811238) (xy 322.197984 -401.674838)
			(xy 335.962244 -401.674838) (xy 335.962244 -400.811238) (xy 335.96273 -400.783969) (xy 335.970492 -400.729985)
			(xy 335.985857 -400.677655) (xy 336.008514 -400.628045) (xy 336.038 -400.582164) (xy 336.073715 -400.540947)
			(xy 336.114932 -400.505232) (xy 336.160813 -400.475746) (xy 336.210423 -400.453089) (xy 336.262753 -400.437724)
			(xy 336.316737 -400.429962) (xy 336.371275 -400.429962) (xy 336.425259 -400.437724) (xy 336.477589 -400.453089)
			(xy 336.527199 -400.475746) (xy 336.57308 -400.505232) (xy 336.614297 -400.540947) (xy 336.650012 -400.582164)
			(xy 336.679498 -400.628045) (xy 336.702155 -400.677655) (xy 336.71752 -400.729985) (xy 336.725282 -400.783969)
			(xy 336.725768 -400.811238) (xy 336.725768 -401.674838) (xy 337.16214 -401.674838) (xy 337.16214 -400.811238)
			(xy 337.162626 -400.783969) (xy 337.170388 -400.729985) (xy 337.185753 -400.677655) (xy 337.20841 -400.628045)
			(xy 337.237896 -400.582164) (xy 337.273611 -400.540947) (xy 337.314828 -400.505232) (xy 337.360709 -400.475746)
			(xy 337.410319 -400.453089) (xy 337.462649 -400.437724) (xy 337.516633 -400.429962) (xy 337.571171 -400.429962)
			(xy 337.625155 -400.437724) (xy 337.677485 -400.453089) (xy 337.727095 -400.475746) (xy 337.772976 -400.505232)
			(xy 337.814193 -400.540947) (xy 337.849908 -400.582164) (xy 337.879394 -400.628045) (xy 337.902051 -400.677655)
			(xy 337.917416 -400.729985) (xy 337.925178 -400.783969) (xy 337.925664 -400.811238) (xy 337.925664 -401.674838)
			(xy 338.362544 -401.674838) (xy 338.362544 -400.811238) (xy 338.36303 -400.783987) (xy 338.370786 -400.730039)
			(xy 338.386141 -400.677744) (xy 338.408783 -400.628167) (xy 338.438249 -400.582317) (xy 338.47394 -400.541126)
			(xy 338.515131 -400.505435) (xy 338.560981 -400.475969) (xy 338.610558 -400.453327) (xy 338.662853 -400.437972)
			(xy 338.716801 -400.430216) (xy 338.771303 -400.430216) (xy 338.825251 -400.437972) (xy 338.877546 -400.453327)
			(xy 338.927123 -400.475969) (xy 338.972973 -400.505435) (xy 339.014164 -400.541126) (xy 339.049855 -400.582317)
			(xy 339.079321 -400.628167) (xy 339.101963 -400.677744) (xy 339.117318 -400.730039) (xy 339.125074 -400.783987)
			(xy 339.12556 -400.811238) (xy 339.12556 -401.674838) (xy 339.56244 -401.674838) (xy 339.56244 -400.811238)
			(xy 339.562926 -400.783987) (xy 339.570682 -400.730039) (xy 339.586037 -400.677744) (xy 339.608679 -400.628167)
			(xy 339.638145 -400.582317) (xy 339.673836 -400.541126) (xy 339.715027 -400.505435) (xy 339.760877 -400.475969)
			(xy 339.810454 -400.453327) (xy 339.862749 -400.437972) (xy 339.916697 -400.430216) (xy 339.971199 -400.430216)
			(xy 340.025147 -400.437972) (xy 340.077442 -400.453327) (xy 340.127019 -400.475969) (xy 340.172869 -400.505435)
			(xy 340.21406 -400.541126) (xy 340.249751 -400.582317) (xy 340.279217 -400.628167) (xy 340.301859 -400.677744)
			(xy 340.317214 -400.730039) (xy 340.32497 -400.783987) (xy 340.325456 -400.811238) (xy 340.325456 -401.674838)
			(xy 340.762336 -401.674838) (xy 340.762336 -400.811238) (xy 340.762822 -400.783969) (xy 340.770584 -400.729985)
			(xy 340.785949 -400.677655) (xy 340.808606 -400.628045) (xy 340.838092 -400.582164) (xy 340.873807 -400.540947)
			(xy 340.915024 -400.505232) (xy 340.960905 -400.475746) (xy 341.010515 -400.453089) (xy 341.062845 -400.437724)
			(xy 341.116829 -400.429962) (xy 341.171367 -400.429962) (xy 341.225351 -400.437724) (xy 341.277681 -400.453089)
			(xy 341.327291 -400.475746) (xy 341.373172 -400.505232) (xy 341.414389 -400.540947) (xy 341.450104 -400.582164)
			(xy 341.47959 -400.628045) (xy 341.502247 -400.677655) (xy 341.517612 -400.729985) (xy 341.525374 -400.783969)
			(xy 341.52586 -400.811238) (xy 341.52586 -401.674838) (xy 341.962232 -401.674838) (xy 341.962232 -400.811238)
			(xy 341.962718 -400.783969) (xy 341.97048 -400.729985) (xy 341.985845 -400.677655) (xy 342.008502 -400.628045)
			(xy 342.037988 -400.582164) (xy 342.073703 -400.540947) (xy 342.11492 -400.505232) (xy 342.160801 -400.475746)
			(xy 342.210411 -400.453089) (xy 342.262741 -400.437724) (xy 342.316725 -400.429962) (xy 342.371263 -400.429962)
			(xy 342.425247 -400.437724) (xy 342.477577 -400.453089) (xy 342.527187 -400.475746) (xy 342.573068 -400.505232)
			(xy 342.614285 -400.540947) (xy 342.65 -400.582164) (xy 342.679486 -400.628045) (xy 342.702143 -400.677655)
			(xy 342.717508 -400.729985) (xy 342.72527 -400.783969) (xy 342.725756 -400.811238) (xy 342.725756 -401.674838)
			(xy 343.162636 -401.674838) (xy 343.162636 -400.811238) (xy 343.163122 -400.783987) (xy 343.170878 -400.730039)
			(xy 343.186233 -400.677744) (xy 343.208875 -400.628167) (xy 343.238341 -400.582317) (xy 343.274032 -400.541126)
			(xy 343.315223 -400.505435) (xy 343.361073 -400.475969) (xy 343.41065 -400.453327) (xy 343.462945 -400.437972)
			(xy 343.516893 -400.430216) (xy 343.571395 -400.430216) (xy 343.625343 -400.437972) (xy 343.677638 -400.453327)
			(xy 343.727215 -400.475969) (xy 343.773065 -400.505435) (xy 343.814256 -400.541126) (xy 343.849947 -400.582317)
			(xy 343.879413 -400.628167) (xy 343.902055 -400.677744) (xy 343.91741 -400.730039) (xy 343.925166 -400.783987)
			(xy 343.925652 -400.811238) (xy 343.925652 -401.674838) (xy 344.362532 -401.674838) (xy 344.362532 -400.811238)
			(xy 344.363018 -400.783987) (xy 344.370774 -400.730039) (xy 344.386129 -400.677744) (xy 344.408771 -400.628167)
			(xy 344.438237 -400.582317) (xy 344.473928 -400.541126) (xy 344.515119 -400.505435) (xy 344.560969 -400.475969)
			(xy 344.610546 -400.453327) (xy 344.662841 -400.437972) (xy 344.716789 -400.430216) (xy 344.771291 -400.430216)
			(xy 344.825239 -400.437972) (xy 344.877534 -400.453327) (xy 344.927111 -400.475969) (xy 344.972961 -400.505435)
			(xy 345.014152 -400.541126) (xy 345.049843 -400.582317) (xy 345.079309 -400.628167) (xy 345.101951 -400.677744)
			(xy 345.117306 -400.730039) (xy 345.125062 -400.783987) (xy 345.125548 -400.811238) (xy 345.125548 -401.674838)
			(xy 345.562428 -401.674838) (xy 345.562428 -400.811238) (xy 345.562914 -400.783969) (xy 345.570676 -400.729985)
			(xy 345.586041 -400.677655) (xy 345.608698 -400.628045) (xy 345.638184 -400.582164) (xy 345.673899 -400.540947)
			(xy 345.715116 -400.505232) (xy 345.760997 -400.475746) (xy 345.810607 -400.453089) (xy 345.862937 -400.437724)
			(xy 345.916921 -400.429962) (xy 345.971459 -400.429962) (xy 346.025443 -400.437724) (xy 346.077773 -400.453089)
			(xy 346.127383 -400.475746) (xy 346.173264 -400.505232) (xy 346.214481 -400.540947) (xy 346.250196 -400.582164)
			(xy 346.279682 -400.628045) (xy 346.302339 -400.677655) (xy 346.317704 -400.729985) (xy 346.325466 -400.783969)
			(xy 346.325952 -400.811238) (xy 346.325952 -401.674838) (xy 346.762324 -401.674838) (xy 346.762324 -400.811238)
			(xy 346.76281 -400.783969) (xy 346.770572 -400.729985) (xy 346.785937 -400.677655) (xy 346.808594 -400.628045)
			(xy 346.83808 -400.582164) (xy 346.873795 -400.540947) (xy 346.915012 -400.505232) (xy 346.960893 -400.475746)
			(xy 347.010503 -400.453089) (xy 347.062833 -400.437724) (xy 347.116817 -400.429962) (xy 347.171355 -400.429962)
			(xy 347.225339 -400.437724) (xy 347.277669 -400.453089) (xy 347.327279 -400.475746) (xy 347.37316 -400.505232)
			(xy 347.414377 -400.540947) (xy 347.450092 -400.582164) (xy 347.479578 -400.628045) (xy 347.502235 -400.677655)
			(xy 347.5176 -400.729985) (xy 347.525362 -400.783969) (xy 347.525848 -400.811238) (xy 347.525848 -401.674838)
			(xy 347.962728 -401.674838) (xy 347.962728 -400.811238) (xy 347.963214 -400.783987) (xy 347.97097 -400.730039)
			(xy 347.986325 -400.677744) (xy 348.008967 -400.628167) (xy 348.038433 -400.582317) (xy 348.074124 -400.541126)
			(xy 348.115315 -400.505435) (xy 348.161165 -400.475969) (xy 348.210742 -400.453327) (xy 348.263037 -400.437972)
			(xy 348.316985 -400.430216) (xy 348.371487 -400.430216) (xy 348.425435 -400.437972) (xy 348.47773 -400.453327)
			(xy 348.527307 -400.475969) (xy 348.573157 -400.505435) (xy 348.614348 -400.541126) (xy 348.650039 -400.582317)
			(xy 348.679505 -400.628167) (xy 348.702147 -400.677744) (xy 348.717502 -400.730039) (xy 348.725258 -400.783987)
			(xy 348.725744 -400.811238) (xy 348.725744 -401.674838) (xy 349.162624 -401.674838) (xy 349.162624 -400.811238)
			(xy 349.16311 -400.783987) (xy 349.170866 -400.730039) (xy 349.186221 -400.677744) (xy 349.208863 -400.628167)
			(xy 349.238329 -400.582317) (xy 349.27402 -400.541126) (xy 349.315211 -400.505435) (xy 349.361061 -400.475969)
			(xy 349.410638 -400.453327) (xy 349.462933 -400.437972) (xy 349.516881 -400.430216) (xy 349.571383 -400.430216)
			(xy 349.625331 -400.437972) (xy 349.677626 -400.453327) (xy 349.727203 -400.475969) (xy 349.773053 -400.505435)
			(xy 349.814244 -400.541126) (xy 349.849935 -400.582317) (xy 349.879401 -400.628167) (xy 349.902043 -400.677744)
			(xy 349.917398 -400.730039) (xy 349.925154 -400.783987) (xy 349.92564 -400.811238) (xy 349.92564 -401.674838)
			(xy 350.36252 -401.674838) (xy 350.36252 -400.811238) (xy 350.363006 -400.783987) (xy 350.370762 -400.730039)
			(xy 350.386117 -400.677744) (xy 350.408759 -400.628167) (xy 350.438225 -400.582317) (xy 350.473916 -400.541126)
			(xy 350.515107 -400.505435) (xy 350.560957 -400.475969) (xy 350.610534 -400.453327) (xy 350.662829 -400.437972)
			(xy 350.716777 -400.430216) (xy 350.771279 -400.430216) (xy 350.825227 -400.437972) (xy 350.877522 -400.453327)
			(xy 350.927099 -400.475969) (xy 350.972949 -400.505435) (xy 351.01414 -400.541126) (xy 351.049831 -400.582317)
			(xy 351.079297 -400.628167) (xy 351.101939 -400.677744) (xy 351.117294 -400.730039) (xy 351.12505 -400.783987)
			(xy 351.125536 -400.811238) (xy 351.125536 -401.674838) (xy 351.562416 -401.674838) (xy 351.562416 -400.811238)
			(xy 351.562902 -400.783987) (xy 351.570658 -400.730039) (xy 351.586013 -400.677744) (xy 351.608655 -400.628167)
			(xy 351.638121 -400.582317) (xy 351.673812 -400.541126) (xy 351.715003 -400.505435) (xy 351.760853 -400.475969)
			(xy 351.81043 -400.453327) (xy 351.862725 -400.437972) (xy 351.916673 -400.430216) (xy 351.971175 -400.430216)
			(xy 352.025123 -400.437972) (xy 352.077418 -400.453327) (xy 352.126995 -400.475969) (xy 352.172845 -400.505435)
			(xy 352.214036 -400.541126) (xy 352.249727 -400.582317) (xy 352.279193 -400.628167) (xy 352.301835 -400.677744)
			(xy 352.31719 -400.730039) (xy 352.324946 -400.783987) (xy 352.325432 -400.811238) (xy 352.325432 -401.674838)
			(xy 352.762312 -401.674838) (xy 352.762312 -400.811238) (xy 352.762798 -400.783969) (xy 352.77056 -400.729985)
			(xy 352.785925 -400.677655) (xy 352.808582 -400.628045) (xy 352.838068 -400.582164) (xy 352.873783 -400.540947)
			(xy 352.915 -400.505232) (xy 352.960881 -400.475746) (xy 353.010491 -400.453089) (xy 353.062821 -400.437724)
			(xy 353.116805 -400.429962) (xy 353.171343 -400.429962) (xy 353.225327 -400.437724) (xy 353.277657 -400.453089)
			(xy 353.327267 -400.475746) (xy 353.373148 -400.505232) (xy 353.414365 -400.540947) (xy 353.45008 -400.582164)
			(xy 353.479566 -400.628045) (xy 353.502223 -400.677655) (xy 353.517588 -400.729985) (xy 353.52535 -400.783969)
			(xy 353.525836 -400.811238) (xy 353.525836 -401.674838) (xy 353.962208 -401.674838) (xy 353.962208 -400.811238)
			(xy 353.962694 -400.783969) (xy 353.970456 -400.729985) (xy 353.985821 -400.677655) (xy 354.008478 -400.628045)
			(xy 354.037964 -400.582164) (xy 354.073679 -400.540947) (xy 354.114896 -400.505232) (xy 354.160777 -400.475746)
			(xy 354.210387 -400.453089) (xy 354.262717 -400.437724) (xy 354.316701 -400.429962) (xy 354.371239 -400.429962)
			(xy 354.425223 -400.437724) (xy 354.477553 -400.453089) (xy 354.527163 -400.475746) (xy 354.573044 -400.505232)
			(xy 354.614261 -400.540947) (xy 354.649976 -400.582164) (xy 354.679462 -400.628045) (xy 354.702119 -400.677655)
			(xy 354.717484 -400.729985) (xy 354.725246 -400.783969) (xy 354.725732 -400.811238) (xy 354.725732 -401.674838)
			(xy 370.534692 -401.674838) (xy 370.534692 -400.811238) (xy 370.535178 -400.783969) (xy 370.54294 -400.729985)
			(xy 370.558305 -400.677655) (xy 370.580962 -400.628045) (xy 370.610448 -400.582164) (xy 370.646163 -400.540947)
			(xy 370.68738 -400.505232) (xy 370.733261 -400.475746) (xy 370.782871 -400.453089) (xy 370.835201 -400.437724)
			(xy 370.889185 -400.429962) (xy 370.943723 -400.429962) (xy 370.997707 -400.437724) (xy 371.050037 -400.453089)
			(xy 371.099647 -400.475746) (xy 371.145528 -400.505232) (xy 371.186745 -400.540947) (xy 371.22246 -400.582164)
			(xy 371.251946 -400.628045) (xy 371.274603 -400.677655) (xy 371.289968 -400.729985) (xy 371.29773 -400.783969)
			(xy 371.298216 -400.811238) (xy 371.298216 -401.674838) (xy 371.734588 -401.674838) (xy 371.734588 -400.811238)
			(xy 371.735074 -400.783969) (xy 371.742836 -400.729985) (xy 371.758201 -400.677655) (xy 371.780858 -400.628045)
			(xy 371.810344 -400.582164) (xy 371.846059 -400.540947) (xy 371.887276 -400.505232) (xy 371.933157 -400.475746)
			(xy 371.982767 -400.453089) (xy 372.035097 -400.437724) (xy 372.089081 -400.429962) (xy 372.143619 -400.429962)
			(xy 372.197603 -400.437724) (xy 372.249933 -400.453089) (xy 372.299543 -400.475746) (xy 372.345424 -400.505232)
			(xy 372.386641 -400.540947) (xy 372.422356 -400.582164) (xy 372.451842 -400.628045) (xy 372.474499 -400.677655)
			(xy 372.489864 -400.729985) (xy 372.497626 -400.783969) (xy 372.498112 -400.811238) (xy 372.498112 -401.674838)
			(xy 372.934992 -401.674838) (xy 372.934992 -400.811238) (xy 372.935478 -400.783987) (xy 372.943234 -400.730039)
			(xy 372.958589 -400.677744) (xy 372.981231 -400.628167) (xy 373.010697 -400.582317) (xy 373.046388 -400.541126)
			(xy 373.087579 -400.505435) (xy 373.133429 -400.475969) (xy 373.183006 -400.453327) (xy 373.235301 -400.437972)
			(xy 373.289249 -400.430216) (xy 373.343751 -400.430216) (xy 373.397699 -400.437972) (xy 373.449994 -400.453327)
			(xy 373.499571 -400.475969) (xy 373.545421 -400.505435) (xy 373.586612 -400.541126) (xy 373.622303 -400.582317)
			(xy 373.651769 -400.628167) (xy 373.674411 -400.677744) (xy 373.689766 -400.730039) (xy 373.697522 -400.783987)
			(xy 373.698008 -400.811238) (xy 373.698008 -401.674838) (xy 374.134888 -401.674838) (xy 374.134888 -400.811238)
			(xy 374.135374 -400.783987) (xy 374.14313 -400.730039) (xy 374.158485 -400.677744) (xy 374.181127 -400.628167)
			(xy 374.210593 -400.582317) (xy 374.246284 -400.541126) (xy 374.287475 -400.505435) (xy 374.333325 -400.475969)
			(xy 374.382902 -400.453327) (xy 374.435197 -400.437972) (xy 374.489145 -400.430216) (xy 374.543647 -400.430216)
			(xy 374.597595 -400.437972) (xy 374.64989 -400.453327) (xy 374.699467 -400.475969) (xy 374.745317 -400.505435)
			(xy 374.786508 -400.541126) (xy 374.822199 -400.582317) (xy 374.851665 -400.628167) (xy 374.874307 -400.677744)
			(xy 374.889662 -400.730039) (xy 374.897418 -400.783987) (xy 374.897904 -400.811238) (xy 374.897904 -401.674838)
			(xy 375.334784 -401.674838) (xy 375.334784 -400.811238) (xy 375.33527 -400.783969) (xy 375.343032 -400.729985)
			(xy 375.358397 -400.677655) (xy 375.381054 -400.628045) (xy 375.41054 -400.582164) (xy 375.446255 -400.540947)
			(xy 375.487472 -400.505232) (xy 375.533353 -400.475746) (xy 375.582963 -400.453089) (xy 375.635293 -400.437724)
			(xy 375.689277 -400.429962) (xy 375.743815 -400.429962) (xy 375.797799 -400.437724) (xy 375.850129 -400.453089)
			(xy 375.899739 -400.475746) (xy 375.94562 -400.505232) (xy 375.986837 -400.540947) (xy 376.022552 -400.582164)
			(xy 376.052038 -400.628045) (xy 376.074695 -400.677655) (xy 376.09006 -400.729985) (xy 376.097822 -400.783969)
			(xy 376.098308 -400.811238) (xy 376.098308 -401.674838) (xy 376.53468 -401.674838) (xy 376.53468 -400.811238)
			(xy 376.535166 -400.783969) (xy 376.542928 -400.729985) (xy 376.558293 -400.677655) (xy 376.58095 -400.628045)
			(xy 376.610436 -400.582164) (xy 376.646151 -400.540947) (xy 376.687368 -400.505232) (xy 376.733249 -400.475746)
			(xy 376.782859 -400.453089) (xy 376.835189 -400.437724) (xy 376.889173 -400.429962) (xy 376.943711 -400.429962)
			(xy 376.997695 -400.437724) (xy 377.050025 -400.453089) (xy 377.099635 -400.475746) (xy 377.145516 -400.505232)
			(xy 377.186733 -400.540947) (xy 377.222448 -400.582164) (xy 377.251934 -400.628045) (xy 377.274591 -400.677655)
			(xy 377.289956 -400.729985) (xy 377.297718 -400.783969) (xy 377.298204 -400.811238) (xy 377.298204 -401.674838)
			(xy 377.735084 -401.674838) (xy 377.735084 -400.811238) (xy 377.73557 -400.783987) (xy 377.743326 -400.730039)
			(xy 377.758681 -400.677744) (xy 377.781323 -400.628167) (xy 377.810789 -400.582317) (xy 377.84648 -400.541126)
			(xy 377.887671 -400.505435) (xy 377.933521 -400.475969) (xy 377.983098 -400.453327) (xy 378.035393 -400.437972)
			(xy 378.089341 -400.430216) (xy 378.143843 -400.430216) (xy 378.197791 -400.437972) (xy 378.250086 -400.453327)
			(xy 378.299663 -400.475969) (xy 378.345513 -400.505435) (xy 378.386704 -400.541126) (xy 378.422395 -400.582317)
			(xy 378.451861 -400.628167) (xy 378.474503 -400.677744) (xy 378.489858 -400.730039) (xy 378.497614 -400.783987)
			(xy 378.4981 -400.811238) (xy 378.4981 -401.674838) (xy 378.93498 -401.674838) (xy 378.93498 -400.811238)
			(xy 378.935466 -400.783987) (xy 378.943222 -400.730039) (xy 378.958577 -400.677744) (xy 378.981219 -400.628167)
			(xy 379.010685 -400.582317) (xy 379.046376 -400.541126) (xy 379.087567 -400.505435) (xy 379.133417 -400.475969)
			(xy 379.182994 -400.453327) (xy 379.235289 -400.437972) (xy 379.289237 -400.430216) (xy 379.343739 -400.430216)
			(xy 379.397687 -400.437972) (xy 379.449982 -400.453327) (xy 379.499559 -400.475969) (xy 379.545409 -400.505435)
			(xy 379.5866 -400.541126) (xy 379.622291 -400.582317) (xy 379.651757 -400.628167) (xy 379.674399 -400.677744)
			(xy 379.689754 -400.730039) (xy 379.69751 -400.783987) (xy 379.697996 -400.811238) (xy 379.697996 -401.674838)
			(xy 380.134876 -401.674838) (xy 380.134876 -400.811238) (xy 380.135362 -400.783969) (xy 380.143124 -400.729985)
			(xy 380.158489 -400.677655) (xy 380.181146 -400.628045) (xy 380.210632 -400.582164) (xy 380.246347 -400.540947)
			(xy 380.287564 -400.505232) (xy 380.333445 -400.475746) (xy 380.383055 -400.453089) (xy 380.435385 -400.437724)
			(xy 380.489369 -400.429962) (xy 380.543907 -400.429962) (xy 380.597891 -400.437724) (xy 380.650221 -400.453089)
			(xy 380.699831 -400.475746) (xy 380.745712 -400.505232) (xy 380.786929 -400.540947) (xy 380.822644 -400.582164)
			(xy 380.85213 -400.628045) (xy 380.874787 -400.677655) (xy 380.890152 -400.729985) (xy 380.897914 -400.783969)
			(xy 380.8984 -400.811238) (xy 380.8984 -401.674838) (xy 381.334772 -401.674838) (xy 381.334772 -400.811238)
			(xy 381.335258 -400.783969) (xy 381.34302 -400.729985) (xy 381.358385 -400.677655) (xy 381.381042 -400.628045)
			(xy 381.410528 -400.582164) (xy 381.446243 -400.540947) (xy 381.48746 -400.505232) (xy 381.533341 -400.475746)
			(xy 381.582951 -400.453089) (xy 381.635281 -400.437724) (xy 381.689265 -400.429962) (xy 381.743803 -400.429962)
			(xy 381.797787 -400.437724) (xy 381.850117 -400.453089) (xy 381.899727 -400.475746) (xy 381.945608 -400.505232)
			(xy 381.986825 -400.540947) (xy 382.02254 -400.582164) (xy 382.052026 -400.628045) (xy 382.074683 -400.677655)
			(xy 382.090048 -400.729985) (xy 382.09781 -400.783969) (xy 382.098296 -400.811238) (xy 382.098296 -401.674838)
			(xy 382.535176 -401.674838) (xy 382.535176 -400.811238) (xy 382.535662 -400.783987) (xy 382.543418 -400.730039)
			(xy 382.558773 -400.677744) (xy 382.581415 -400.628167) (xy 382.610881 -400.582317) (xy 382.646572 -400.541126)
			(xy 382.687763 -400.505435) (xy 382.733613 -400.475969) (xy 382.78319 -400.453327) (xy 382.835485 -400.437972)
			(xy 382.889433 -400.430216) (xy 382.943935 -400.430216) (xy 382.997883 -400.437972) (xy 383.050178 -400.453327)
			(xy 383.099755 -400.475969) (xy 383.145605 -400.505435) (xy 383.186796 -400.541126) (xy 383.222487 -400.582317)
			(xy 383.251953 -400.628167) (xy 383.274595 -400.677744) (xy 383.28995 -400.730039) (xy 383.297706 -400.783987)
			(xy 383.298192 -400.811238) (xy 383.298192 -401.674838) (xy 383.735072 -401.674838) (xy 383.735072 -400.811238)
			(xy 383.735558 -400.783987) (xy 383.743314 -400.730039) (xy 383.758669 -400.677744) (xy 383.781311 -400.628167)
			(xy 383.810777 -400.582317) (xy 383.846468 -400.541126) (xy 383.887659 -400.505435) (xy 383.933509 -400.475969)
			(xy 383.983086 -400.453327) (xy 384.035381 -400.437972) (xy 384.089329 -400.430216) (xy 384.143831 -400.430216)
			(xy 384.197779 -400.437972) (xy 384.250074 -400.453327) (xy 384.299651 -400.475969) (xy 384.345501 -400.505435)
			(xy 384.386692 -400.541126) (xy 384.422383 -400.582317) (xy 384.451849 -400.628167) (xy 384.474491 -400.677744)
			(xy 384.489846 -400.730039) (xy 384.497602 -400.783987) (xy 384.498088 -400.811238) (xy 384.498088 -401.674838)
			(xy 384.934968 -401.674838) (xy 384.934968 -400.811238) (xy 384.935454 -400.783987) (xy 384.94321 -400.730039)
			(xy 384.958565 -400.677744) (xy 384.981207 -400.628167) (xy 385.010673 -400.582317) (xy 385.046364 -400.541126)
			(xy 385.087555 -400.505435) (xy 385.133405 -400.475969) (xy 385.182982 -400.453327) (xy 385.235277 -400.437972)
			(xy 385.289225 -400.430216) (xy 385.343727 -400.430216) (xy 385.397675 -400.437972) (xy 385.44997 -400.453327)
			(xy 385.499547 -400.475969) (xy 385.545397 -400.505435) (xy 385.586588 -400.541126) (xy 385.622279 -400.582317)
			(xy 385.651745 -400.628167) (xy 385.674387 -400.677744) (xy 385.689742 -400.730039) (xy 385.697498 -400.783987)
			(xy 385.697984 -400.811238) (xy 385.697984 -401.674838) (xy 386.134864 -401.674838) (xy 386.134864 -400.811238)
			(xy 386.13535 -400.783987) (xy 386.143106 -400.730039) (xy 386.158461 -400.677744) (xy 386.181103 -400.628167)
			(xy 386.210569 -400.582317) (xy 386.24626 -400.541126) (xy 386.287451 -400.505435) (xy 386.333301 -400.475969)
			(xy 386.382878 -400.453327) (xy 386.435173 -400.437972) (xy 386.489121 -400.430216) (xy 386.543623 -400.430216)
			(xy 386.597571 -400.437972) (xy 386.649866 -400.453327) (xy 386.699443 -400.475969) (xy 386.745293 -400.505435)
			(xy 386.786484 -400.541126) (xy 386.822175 -400.582317) (xy 386.851641 -400.628167) (xy 386.874283 -400.677744)
			(xy 386.889638 -400.730039) (xy 386.897394 -400.783987) (xy 386.89788 -400.811238) (xy 386.89788 -401.674838)
			(xy 387.33476 -401.674838) (xy 387.33476 -400.811238) (xy 387.335246 -400.783969) (xy 387.343008 -400.729985)
			(xy 387.358373 -400.677655) (xy 387.38103 -400.628045) (xy 387.410516 -400.582164) (xy 387.446231 -400.540947)
			(xy 387.487448 -400.505232) (xy 387.533329 -400.475746) (xy 387.582939 -400.453089) (xy 387.635269 -400.437724)
			(xy 387.689253 -400.429962) (xy 387.743791 -400.429962) (xy 387.797775 -400.437724) (xy 387.850105 -400.453089)
			(xy 387.899715 -400.475746) (xy 387.945596 -400.505232) (xy 387.986813 -400.540947) (xy 388.022528 -400.582164)
			(xy 388.052014 -400.628045) (xy 388.074671 -400.677655) (xy 388.090036 -400.729985) (xy 388.097798 -400.783969)
			(xy 388.098284 -400.811238) (xy 388.098284 -401.674838) (xy 388.534656 -401.674838) (xy 388.534656 -400.811238)
			(xy 388.535142 -400.783969) (xy 388.542904 -400.729985) (xy 388.558269 -400.677655) (xy 388.580926 -400.628045)
			(xy 388.610412 -400.582164) (xy 388.646127 -400.540947) (xy 388.687344 -400.505232) (xy 388.733225 -400.475746)
			(xy 388.782835 -400.453089) (xy 388.835165 -400.437724) (xy 388.889149 -400.429962) (xy 388.943687 -400.429962)
			(xy 388.997671 -400.437724) (xy 389.050001 -400.453089) (xy 389.099611 -400.475746) (xy 389.145492 -400.505232)
			(xy 389.186709 -400.540947) (xy 389.222424 -400.582164) (xy 389.25191 -400.628045) (xy 389.274567 -400.677655)
			(xy 389.289932 -400.729985) (xy 389.297694 -400.783969) (xy 389.29818 -400.811238) (xy 389.29818 -401.674838)
			(xy 403.06244 -401.674838) (xy 403.06244 -400.811238) (xy 403.062926 -400.783969) (xy 403.070688 -400.729985)
			(xy 403.086053 -400.677655) (xy 403.10871 -400.628045) (xy 403.138196 -400.582164) (xy 403.173911 -400.540947)
			(xy 403.215128 -400.505232) (xy 403.261009 -400.475746) (xy 403.310619 -400.453089) (xy 403.362949 -400.437724)
			(xy 403.416933 -400.429962) (xy 403.471471 -400.429962) (xy 403.525455 -400.437724) (xy 403.577785 -400.453089)
			(xy 403.627395 -400.475746) (xy 403.673276 -400.505232) (xy 403.714493 -400.540947) (xy 403.750208 -400.582164)
			(xy 403.779694 -400.628045) (xy 403.802351 -400.677655) (xy 403.817716 -400.729985) (xy 403.825478 -400.783969)
			(xy 403.825964 -400.811238) (xy 403.825964 -401.674838) (xy 404.262336 -401.674838) (xy 404.262336 -400.811238)
			(xy 404.262822 -400.783969) (xy 404.270584 -400.729985) (xy 404.285949 -400.677655) (xy 404.308606 -400.628045)
			(xy 404.338092 -400.582164) (xy 404.373807 -400.540947) (xy 404.415024 -400.505232) (xy 404.460905 -400.475746)
			(xy 404.510515 -400.453089) (xy 404.562845 -400.437724) (xy 404.616829 -400.429962) (xy 404.671367 -400.429962)
			(xy 404.725351 -400.437724) (xy 404.777681 -400.453089) (xy 404.827291 -400.475746) (xy 404.873172 -400.505232)
			(xy 404.914389 -400.540947) (xy 404.950104 -400.582164) (xy 404.97959 -400.628045) (xy 405.002247 -400.677655)
			(xy 405.017612 -400.729985) (xy 405.025374 -400.783969) (xy 405.02586 -400.811238) (xy 405.02586 -401.674838)
			(xy 405.46274 -401.674838) (xy 405.46274 -400.811238) (xy 405.463226 -400.783987) (xy 405.470982 -400.730039)
			(xy 405.486337 -400.677744) (xy 405.508979 -400.628167) (xy 405.538445 -400.582317) (xy 405.574136 -400.541126)
			(xy 405.615327 -400.505435) (xy 405.661177 -400.475969) (xy 405.710754 -400.453327) (xy 405.763049 -400.437972)
			(xy 405.816997 -400.430216) (xy 405.871499 -400.430216) (xy 405.925447 -400.437972) (xy 405.977742 -400.453327)
			(xy 406.027319 -400.475969) (xy 406.073169 -400.505435) (xy 406.11436 -400.541126) (xy 406.150051 -400.582317)
			(xy 406.179517 -400.628167) (xy 406.202159 -400.677744) (xy 406.217514 -400.730039) (xy 406.22527 -400.783987)
			(xy 406.225756 -400.811238) (xy 406.225756 -401.674838) (xy 406.662636 -401.674838) (xy 406.662636 -400.811238)
			(xy 406.663122 -400.783987) (xy 406.670878 -400.730039) (xy 406.686233 -400.677744) (xy 406.708875 -400.628167)
			(xy 406.738341 -400.582317) (xy 406.774032 -400.541126) (xy 406.815223 -400.505435) (xy 406.861073 -400.475969)
			(xy 406.91065 -400.453327) (xy 406.962945 -400.437972) (xy 407.016893 -400.430216) (xy 407.071395 -400.430216)
			(xy 407.125343 -400.437972) (xy 407.177638 -400.453327) (xy 407.227215 -400.475969) (xy 407.273065 -400.505435)
			(xy 407.314256 -400.541126) (xy 407.349947 -400.582317) (xy 407.379413 -400.628167) (xy 407.402055 -400.677744)
			(xy 407.41741 -400.730039) (xy 407.425166 -400.783987) (xy 407.425652 -400.811238) (xy 407.425652 -401.674838)
			(xy 407.862532 -401.674838) (xy 407.862532 -400.811238) (xy 407.863018 -400.783969) (xy 407.87078 -400.729985)
			(xy 407.886145 -400.677655) (xy 407.908802 -400.628045) (xy 407.938288 -400.582164) (xy 407.974003 -400.540947)
			(xy 408.01522 -400.505232) (xy 408.061101 -400.475746) (xy 408.110711 -400.453089) (xy 408.163041 -400.437724)
			(xy 408.217025 -400.429962) (xy 408.271563 -400.429962) (xy 408.325547 -400.437724) (xy 408.377877 -400.453089)
			(xy 408.427487 -400.475746) (xy 408.473368 -400.505232) (xy 408.514585 -400.540947) (xy 408.5503 -400.582164)
			(xy 408.579786 -400.628045) (xy 408.602443 -400.677655) (xy 408.617808 -400.729985) (xy 408.62557 -400.783969)
			(xy 408.626056 -400.811238) (xy 408.626056 -401.674838) (xy 409.062428 -401.674838) (xy 409.062428 -400.811238)
			(xy 409.062914 -400.783969) (xy 409.070676 -400.729985) (xy 409.086041 -400.677655) (xy 409.108698 -400.628045)
			(xy 409.138184 -400.582164) (xy 409.173899 -400.540947) (xy 409.215116 -400.505232) (xy 409.260997 -400.475746)
			(xy 409.310607 -400.453089) (xy 409.362937 -400.437724) (xy 409.416921 -400.429962) (xy 409.471459 -400.429962)
			(xy 409.525443 -400.437724) (xy 409.577773 -400.453089) (xy 409.627383 -400.475746) (xy 409.673264 -400.505232)
			(xy 409.714481 -400.540947) (xy 409.750196 -400.582164) (xy 409.779682 -400.628045) (xy 409.802339 -400.677655)
			(xy 409.817704 -400.729985) (xy 409.825466 -400.783969) (xy 409.825952 -400.811238) (xy 409.825952 -401.674838)
			(xy 410.262832 -401.674838) (xy 410.262832 -400.811238) (xy 410.263318 -400.783987) (xy 410.271074 -400.730039)
			(xy 410.286429 -400.677744) (xy 410.309071 -400.628167) (xy 410.338537 -400.582317) (xy 410.374228 -400.541126)
			(xy 410.415419 -400.505435) (xy 410.461269 -400.475969) (xy 410.510846 -400.453327) (xy 410.563141 -400.437972)
			(xy 410.617089 -400.430216) (xy 410.671591 -400.430216) (xy 410.725539 -400.437972) (xy 410.777834 -400.453327)
			(xy 410.827411 -400.475969) (xy 410.873261 -400.505435) (xy 410.914452 -400.541126) (xy 410.950143 -400.582317)
			(xy 410.979609 -400.628167) (xy 411.002251 -400.677744) (xy 411.017606 -400.730039) (xy 411.025362 -400.783987)
			(xy 411.025848 -400.811238) (xy 411.025848 -401.674838) (xy 411.462728 -401.674838) (xy 411.462728 -400.811238)
			(xy 411.463214 -400.783987) (xy 411.47097 -400.730039) (xy 411.486325 -400.677744) (xy 411.508967 -400.628167)
			(xy 411.538433 -400.582317) (xy 411.574124 -400.541126) (xy 411.615315 -400.505435) (xy 411.661165 -400.475969)
			(xy 411.710742 -400.453327) (xy 411.763037 -400.437972) (xy 411.816985 -400.430216) (xy 411.871487 -400.430216)
			(xy 411.925435 -400.437972) (xy 411.97773 -400.453327) (xy 412.027307 -400.475969) (xy 412.073157 -400.505435)
			(xy 412.114348 -400.541126) (xy 412.150039 -400.582317) (xy 412.179505 -400.628167) (xy 412.202147 -400.677744)
			(xy 412.217502 -400.730039) (xy 412.225258 -400.783987) (xy 412.225744 -400.811238) (xy 412.225744 -401.674838)
			(xy 412.662624 -401.674838) (xy 412.662624 -400.811238) (xy 412.66311 -400.783969) (xy 412.670872 -400.729985)
			(xy 412.686237 -400.677655) (xy 412.708894 -400.628045) (xy 412.73838 -400.582164) (xy 412.774095 -400.540947)
			(xy 412.815312 -400.505232) (xy 412.861193 -400.475746) (xy 412.910803 -400.453089) (xy 412.963133 -400.437724)
			(xy 413.017117 -400.429962) (xy 413.071655 -400.429962) (xy 413.125639 -400.437724) (xy 413.177969 -400.453089)
			(xy 413.227579 -400.475746) (xy 413.27346 -400.505232) (xy 413.314677 -400.540947) (xy 413.350392 -400.582164)
			(xy 413.379878 -400.628045) (xy 413.402535 -400.677655) (xy 413.4179 -400.729985) (xy 413.425662 -400.783969)
			(xy 413.426148 -400.811238) (xy 413.426148 -401.674838) (xy 413.86252 -401.674838) (xy 413.86252 -400.811238)
			(xy 413.863006 -400.783969) (xy 413.870768 -400.729985) (xy 413.886133 -400.677655) (xy 413.90879 -400.628045)
			(xy 413.938276 -400.582164) (xy 413.973991 -400.540947) (xy 414.015208 -400.505232) (xy 414.061089 -400.475746)
			(xy 414.110699 -400.453089) (xy 414.163029 -400.437724) (xy 414.217013 -400.429962) (xy 414.271551 -400.429962)
			(xy 414.325535 -400.437724) (xy 414.377865 -400.453089) (xy 414.427475 -400.475746) (xy 414.473356 -400.505232)
			(xy 414.514573 -400.540947) (xy 414.550288 -400.582164) (xy 414.579774 -400.628045) (xy 414.602431 -400.677655)
			(xy 414.617796 -400.729985) (xy 414.625558 -400.783969) (xy 414.626044 -400.811238) (xy 414.626044 -401.674838)
			(xy 415.062924 -401.674838) (xy 415.062924 -400.811238) (xy 415.06341 -400.783987) (xy 415.071166 -400.730039)
			(xy 415.086521 -400.677744) (xy 415.109163 -400.628167) (xy 415.138629 -400.582317) (xy 415.17432 -400.541126)
			(xy 415.215511 -400.505435) (xy 415.261361 -400.475969) (xy 415.310938 -400.453327) (xy 415.363233 -400.437972)
			(xy 415.417181 -400.430216) (xy 415.471683 -400.430216) (xy 415.525631 -400.437972) (xy 415.577926 -400.453327)
			(xy 415.627503 -400.475969) (xy 415.673353 -400.505435) (xy 415.714544 -400.541126) (xy 415.750235 -400.582317)
			(xy 415.779701 -400.628167) (xy 415.802343 -400.677744) (xy 415.817698 -400.730039) (xy 415.825454 -400.783987)
			(xy 415.82594 -400.811238) (xy 415.82594 -401.674838) (xy 416.26282 -401.674838) (xy 416.26282 -400.811238)
			(xy 416.263306 -400.783987) (xy 416.271062 -400.730039) (xy 416.286417 -400.677744) (xy 416.309059 -400.628167)
			(xy 416.338525 -400.582317) (xy 416.374216 -400.541126) (xy 416.415407 -400.505435) (xy 416.461257 -400.475969)
			(xy 416.510834 -400.453327) (xy 416.563129 -400.437972) (xy 416.617077 -400.430216) (xy 416.671579 -400.430216)
			(xy 416.725527 -400.437972) (xy 416.777822 -400.453327) (xy 416.827399 -400.475969) (xy 416.873249 -400.505435)
			(xy 416.91444 -400.541126) (xy 416.950131 -400.582317) (xy 416.979597 -400.628167) (xy 417.002239 -400.677744)
			(xy 417.017594 -400.730039) (xy 417.02535 -400.783987) (xy 417.025836 -400.811238) (xy 417.025836 -401.674838)
			(xy 417.462716 -401.674838) (xy 417.462716 -400.811238) (xy 417.463202 -400.783987) (xy 417.470958 -400.730039)
			(xy 417.486313 -400.677744) (xy 417.508955 -400.628167) (xy 417.538421 -400.582317) (xy 417.574112 -400.541126)
			(xy 417.615303 -400.505435) (xy 417.661153 -400.475969) (xy 417.71073 -400.453327) (xy 417.763025 -400.437972)
			(xy 417.816973 -400.430216) (xy 417.871475 -400.430216) (xy 417.925423 -400.437972) (xy 417.977718 -400.453327)
			(xy 418.027295 -400.475969) (xy 418.073145 -400.505435) (xy 418.114336 -400.541126) (xy 418.150027 -400.582317)
			(xy 418.179493 -400.628167) (xy 418.202135 -400.677744) (xy 418.21749 -400.730039) (xy 418.225246 -400.783987)
			(xy 418.225732 -400.811238) (xy 418.225732 -401.674838) (xy 418.662612 -401.674838) (xy 418.662612 -400.811238)
			(xy 418.663098 -400.783987) (xy 418.670854 -400.730039) (xy 418.686209 -400.677744) (xy 418.708851 -400.628167)
			(xy 418.738317 -400.582317) (xy 418.774008 -400.541126) (xy 418.815199 -400.505435) (xy 418.861049 -400.475969)
			(xy 418.910626 -400.453327) (xy 418.962921 -400.437972) (xy 419.016869 -400.430216) (xy 419.071371 -400.430216)
			(xy 419.125319 -400.437972) (xy 419.177614 -400.453327) (xy 419.227191 -400.475969) (xy 419.273041 -400.505435)
			(xy 419.314232 -400.541126) (xy 419.349923 -400.582317) (xy 419.379389 -400.628167) (xy 419.402031 -400.677744)
			(xy 419.417386 -400.730039) (xy 419.425142 -400.783987) (xy 419.425628 -400.811238) (xy 419.425628 -401.674838)
			(xy 419.862508 -401.674838) (xy 419.862508 -400.811238) (xy 419.862994 -400.783969) (xy 419.870756 -400.729985)
			(xy 419.886121 -400.677655) (xy 419.908778 -400.628045) (xy 419.938264 -400.582164) (xy 419.973979 -400.540947)
			(xy 420.015196 -400.505232) (xy 420.061077 -400.475746) (xy 420.110687 -400.453089) (xy 420.163017 -400.437724)
			(xy 420.217001 -400.429962) (xy 420.271539 -400.429962) (xy 420.325523 -400.437724) (xy 420.377853 -400.453089)
			(xy 420.427463 -400.475746) (xy 420.473344 -400.505232) (xy 420.514561 -400.540947) (xy 420.550276 -400.582164)
			(xy 420.579762 -400.628045) (xy 420.602419 -400.677655) (xy 420.617784 -400.729985) (xy 420.625546 -400.783969)
			(xy 420.626032 -400.811238) (xy 420.626032 -401.674838) (xy 421.062404 -401.674838) (xy 421.062404 -400.811238)
			(xy 421.06289 -400.783969) (xy 421.070652 -400.729985) (xy 421.086017 -400.677655) (xy 421.108674 -400.628045)
			(xy 421.13816 -400.582164) (xy 421.173875 -400.540947) (xy 421.215092 -400.505232) (xy 421.260973 -400.475746)
			(xy 421.310583 -400.453089) (xy 421.362913 -400.437724) (xy 421.416897 -400.429962) (xy 421.471435 -400.429962)
			(xy 421.525419 -400.437724) (xy 421.577749 -400.453089) (xy 421.627359 -400.475746) (xy 421.67324 -400.505232)
			(xy 421.714457 -400.540947) (xy 421.750172 -400.582164) (xy 421.779658 -400.628045) (xy 421.802315 -400.677655)
			(xy 421.81768 -400.729985) (xy 421.825442 -400.783969) (xy 421.825928 -400.811238) (xy 421.825928 -401.674838)
			(xy 421.825442 -401.702107) (xy 421.81768 -401.756091) (xy 421.802315 -401.808421) (xy 421.779658 -401.858031)
			(xy 421.750172 -401.903912) (xy 421.714457 -401.945129) (xy 421.67324 -401.980844) (xy 421.627359 -402.01033)
			(xy 421.577749 -402.032987) (xy 421.525419 -402.048352) (xy 421.471435 -402.056114) (xy 421.416897 -402.056114)
			(xy 421.362913 -402.048352) (xy 421.310583 -402.032987) (xy 421.260973 -402.01033) (xy 421.215092 -401.980844)
			(xy 421.173875 -401.945129) (xy 421.13816 -401.903912) (xy 421.108674 -401.858031) (xy 421.086017 -401.808421)
			(xy 421.070652 -401.756091) (xy 421.06289 -401.702107) (xy 421.062404 -401.674838) (xy 420.626032 -401.674838)
			(xy 420.625546 -401.702107) (xy 420.617784 -401.756091) (xy 420.602419 -401.808421) (xy 420.579762 -401.858031)
			(xy 420.550276 -401.903912) (xy 420.514561 -401.945129) (xy 420.473344 -401.980844) (xy 420.427463 -402.01033)
			(xy 420.377853 -402.032987) (xy 420.325523 -402.048352) (xy 420.271539 -402.056114) (xy 420.217001 -402.056114)
			(xy 420.163017 -402.048352) (xy 420.110687 -402.032987) (xy 420.061077 -402.01033) (xy 420.015196 -401.980844)
			(xy 419.973979 -401.945129) (xy 419.938264 -401.903912) (xy 419.908778 -401.858031) (xy 419.886121 -401.808421)
			(xy 419.870756 -401.756091) (xy 419.862994 -401.702107) (xy 419.862508 -401.674838) (xy 419.425628 -401.674838)
			(xy 419.425142 -401.702089) (xy 419.417386 -401.756037) (xy 419.402031 -401.808332) (xy 419.379389 -401.857909)
			(xy 419.349923 -401.903759) (xy 419.314232 -401.94495) (xy 419.273041 -401.980641) (xy 419.227191 -402.010107)
			(xy 419.177614 -402.032749) (xy 419.125319 -402.048104) (xy 419.071371 -402.05586) (xy 419.016869 -402.05586)
			(xy 418.962921 -402.048104) (xy 418.910626 -402.032749) (xy 418.861049 -402.010107) (xy 418.815199 -401.980641)
			(xy 418.774008 -401.94495) (xy 418.738317 -401.903759) (xy 418.708851 -401.857909) (xy 418.686209 -401.808332)
			(xy 418.670854 -401.756037) (xy 418.663098 -401.702089) (xy 418.662612 -401.674838) (xy 418.225732 -401.674838)
			(xy 418.225246 -401.702089) (xy 418.21749 -401.756037) (xy 418.202135 -401.808332) (xy 418.179493 -401.857909)
			(xy 418.150027 -401.903759) (xy 418.114336 -401.94495) (xy 418.073145 -401.980641) (xy 418.027295 -402.010107)
			(xy 417.977718 -402.032749) (xy 417.925423 -402.048104) (xy 417.871475 -402.05586) (xy 417.816973 -402.05586)
			(xy 417.763025 -402.048104) (xy 417.71073 -402.032749) (xy 417.661153 -402.010107) (xy 417.615303 -401.980641)
			(xy 417.574112 -401.94495) (xy 417.538421 -401.903759) (xy 417.508955 -401.857909) (xy 417.486313 -401.808332)
			(xy 417.470958 -401.756037) (xy 417.463202 -401.702089) (xy 417.462716 -401.674838) (xy 417.025836 -401.674838)
			(xy 417.02535 -401.702089) (xy 417.017594 -401.756037) (xy 417.002239 -401.808332) (xy 416.979597 -401.857909)
			(xy 416.950131 -401.903759) (xy 416.91444 -401.94495) (xy 416.873249 -401.980641) (xy 416.827399 -402.010107)
			(xy 416.777822 -402.032749) (xy 416.725527 -402.048104) (xy 416.671579 -402.05586) (xy 416.617077 -402.05586)
			(xy 416.563129 -402.048104) (xy 416.510834 -402.032749) (xy 416.461257 -402.010107) (xy 416.415407 -401.980641)
			(xy 416.374216 -401.94495) (xy 416.338525 -401.903759) (xy 416.309059 -401.857909) (xy 416.286417 -401.808332)
			(xy 416.271062 -401.756037) (xy 416.263306 -401.702089) (xy 416.26282 -401.674838) (xy 415.82594 -401.674838)
			(xy 415.825454 -401.702089) (xy 415.817698 -401.756037) (xy 415.802343 -401.808332) (xy 415.779701 -401.857909)
			(xy 415.750235 -401.903759) (xy 415.714544 -401.94495) (xy 415.673353 -401.980641) (xy 415.627503 -402.010107)
			(xy 415.577926 -402.032749) (xy 415.525631 -402.048104) (xy 415.471683 -402.05586) (xy 415.417181 -402.05586)
			(xy 415.363233 -402.048104) (xy 415.310938 -402.032749) (xy 415.261361 -402.010107) (xy 415.215511 -401.980641)
			(xy 415.17432 -401.94495) (xy 415.138629 -401.903759) (xy 415.109163 -401.857909) (xy 415.086521 -401.808332)
			(xy 415.071166 -401.756037) (xy 415.06341 -401.702089) (xy 415.062924 -401.674838) (xy 414.626044 -401.674838)
			(xy 414.625558 -401.702107) (xy 414.617796 -401.756091) (xy 414.602431 -401.808421) (xy 414.579774 -401.858031)
			(xy 414.550288 -401.903912) (xy 414.514573 -401.945129) (xy 414.473356 -401.980844) (xy 414.427475 -402.01033)
			(xy 414.377865 -402.032987) (xy 414.325535 -402.048352) (xy 414.271551 -402.056114) (xy 414.217013 -402.056114)
			(xy 414.163029 -402.048352) (xy 414.110699 -402.032987) (xy 414.061089 -402.01033) (xy 414.015208 -401.980844)
			(xy 413.973991 -401.945129) (xy 413.938276 -401.903912) (xy 413.90879 -401.858031) (xy 413.886133 -401.808421)
			(xy 413.870768 -401.756091) (xy 413.863006 -401.702107) (xy 413.86252 -401.674838) (xy 413.426148 -401.674838)
			(xy 413.425662 -401.702107) (xy 413.4179 -401.756091) (xy 413.402535 -401.808421) (xy 413.379878 -401.858031)
			(xy 413.350392 -401.903912) (xy 413.314677 -401.945129) (xy 413.27346 -401.980844) (xy 413.227579 -402.01033)
			(xy 413.177969 -402.032987) (xy 413.125639 -402.048352) (xy 413.071655 -402.056114) (xy 413.017117 -402.056114)
			(xy 412.963133 -402.048352) (xy 412.910803 -402.032987) (xy 412.861193 -402.01033) (xy 412.815312 -401.980844)
			(xy 412.774095 -401.945129) (xy 412.73838 -401.903912) (xy 412.708894 -401.858031) (xy 412.686237 -401.808421)
			(xy 412.670872 -401.756091) (xy 412.66311 -401.702107) (xy 412.662624 -401.674838) (xy 412.225744 -401.674838)
			(xy 412.225258 -401.702089) (xy 412.217502 -401.756037) (xy 412.202147 -401.808332) (xy 412.179505 -401.857909)
			(xy 412.150039 -401.903759) (xy 412.114348 -401.94495) (xy 412.073157 -401.980641) (xy 412.027307 -402.010107)
			(xy 411.97773 -402.032749) (xy 411.925435 -402.048104) (xy 411.871487 -402.05586) (xy 411.816985 -402.05586)
			(xy 411.763037 -402.048104) (xy 411.710742 -402.032749) (xy 411.661165 -402.010107) (xy 411.615315 -401.980641)
			(xy 411.574124 -401.94495) (xy 411.538433 -401.903759) (xy 411.508967 -401.857909) (xy 411.486325 -401.808332)
			(xy 411.47097 -401.756037) (xy 411.463214 -401.702089) (xy 411.462728 -401.674838) (xy 411.025848 -401.674838)
			(xy 411.025362 -401.702089) (xy 411.017606 -401.756037) (xy 411.002251 -401.808332) (xy 410.979609 -401.857909)
			(xy 410.950143 -401.903759) (xy 410.914452 -401.94495) (xy 410.873261 -401.980641) (xy 410.827411 -402.010107)
			(xy 410.777834 -402.032749) (xy 410.725539 -402.048104) (xy 410.671591 -402.05586) (xy 410.617089 -402.05586)
			(xy 410.563141 -402.048104) (xy 410.510846 -402.032749) (xy 410.461269 -402.010107) (xy 410.415419 -401.980641)
			(xy 410.374228 -401.94495) (xy 410.338537 -401.903759) (xy 410.309071 -401.857909) (xy 410.286429 -401.808332)
			(xy 410.271074 -401.756037) (xy 410.263318 -401.702089) (xy 410.262832 -401.674838) (xy 409.825952 -401.674838)
			(xy 409.825466 -401.702107) (xy 409.817704 -401.756091) (xy 409.802339 -401.808421) (xy 409.779682 -401.858031)
			(xy 409.750196 -401.903912) (xy 409.714481 -401.945129) (xy 409.673264 -401.980844) (xy 409.627383 -402.01033)
			(xy 409.577773 -402.032987) (xy 409.525443 -402.048352) (xy 409.471459 -402.056114) (xy 409.416921 -402.056114)
			(xy 409.362937 -402.048352) (xy 409.310607 -402.032987) (xy 409.260997 -402.01033) (xy 409.215116 -401.980844)
			(xy 409.173899 -401.945129) (xy 409.138184 -401.903912) (xy 409.108698 -401.858031) (xy 409.086041 -401.808421)
			(xy 409.070676 -401.756091) (xy 409.062914 -401.702107) (xy 409.062428 -401.674838) (xy 408.626056 -401.674838)
			(xy 408.62557 -401.702107) (xy 408.617808 -401.756091) (xy 408.602443 -401.808421) (xy 408.579786 -401.858031)
			(xy 408.5503 -401.903912) (xy 408.514585 -401.945129) (xy 408.473368 -401.980844) (xy 408.427487 -402.01033)
			(xy 408.377877 -402.032987) (xy 408.325547 -402.048352) (xy 408.271563 -402.056114) (xy 408.217025 -402.056114)
			(xy 408.163041 -402.048352) (xy 408.110711 -402.032987) (xy 408.061101 -402.01033) (xy 408.01522 -401.980844)
			(xy 407.974003 -401.945129) (xy 407.938288 -401.903912) (xy 407.908802 -401.858031) (xy 407.886145 -401.808421)
			(xy 407.87078 -401.756091) (xy 407.863018 -401.702107) (xy 407.862532 -401.674838) (xy 407.425652 -401.674838)
			(xy 407.425166 -401.702089) (xy 407.41741 -401.756037) (xy 407.402055 -401.808332) (xy 407.379413 -401.857909)
			(xy 407.349947 -401.903759) (xy 407.314256 -401.94495) (xy 407.273065 -401.980641) (xy 407.227215 -402.010107)
			(xy 407.177638 -402.032749) (xy 407.125343 -402.048104) (xy 407.071395 -402.05586) (xy 407.016893 -402.05586)
			(xy 406.962945 -402.048104) (xy 406.91065 -402.032749) (xy 406.861073 -402.010107) (xy 406.815223 -401.980641)
			(xy 406.774032 -401.94495) (xy 406.738341 -401.903759) (xy 406.708875 -401.857909) (xy 406.686233 -401.808332)
			(xy 406.670878 -401.756037) (xy 406.663122 -401.702089) (xy 406.662636 -401.674838) (xy 406.225756 -401.674838)
			(xy 406.22527 -401.702089) (xy 406.217514 -401.756037) (xy 406.202159 -401.808332) (xy 406.179517 -401.857909)
			(xy 406.150051 -401.903759) (xy 406.11436 -401.94495) (xy 406.073169 -401.980641) (xy 406.027319 -402.010107)
			(xy 405.977742 -402.032749) (xy 405.925447 -402.048104) (xy 405.871499 -402.05586) (xy 405.816997 -402.05586)
			(xy 405.763049 -402.048104) (xy 405.710754 -402.032749) (xy 405.661177 -402.010107) (xy 405.615327 -401.980641)
			(xy 405.574136 -401.94495) (xy 405.538445 -401.903759) (xy 405.508979 -401.857909) (xy 405.486337 -401.808332)
			(xy 405.470982 -401.756037) (xy 405.463226 -401.702089) (xy 405.46274 -401.674838) (xy 405.02586 -401.674838)
			(xy 405.025374 -401.702107) (xy 405.017612 -401.756091) (xy 405.002247 -401.808421) (xy 404.97959 -401.858031)
			(xy 404.950104 -401.903912) (xy 404.914389 -401.945129) (xy 404.873172 -401.980844) (xy 404.827291 -402.01033)
			(xy 404.777681 -402.032987) (xy 404.725351 -402.048352) (xy 404.671367 -402.056114) (xy 404.616829 -402.056114)
			(xy 404.562845 -402.048352) (xy 404.510515 -402.032987) (xy 404.460905 -402.01033) (xy 404.415024 -401.980844)
			(xy 404.373807 -401.945129) (xy 404.338092 -401.903912) (xy 404.308606 -401.858031) (xy 404.285949 -401.808421)
			(xy 404.270584 -401.756091) (xy 404.262822 -401.702107) (xy 404.262336 -401.674838) (xy 403.825964 -401.674838)
			(xy 403.825478 -401.702107) (xy 403.817716 -401.756091) (xy 403.802351 -401.808421) (xy 403.779694 -401.858031)
			(xy 403.750208 -401.903912) (xy 403.714493 -401.945129) (xy 403.673276 -401.980844) (xy 403.627395 -402.01033)
			(xy 403.577785 -402.032987) (xy 403.525455 -402.048352) (xy 403.471471 -402.056114) (xy 403.416933 -402.056114)
			(xy 403.362949 -402.048352) (xy 403.310619 -402.032987) (xy 403.261009 -402.01033) (xy 403.215128 -401.980844)
			(xy 403.173911 -401.945129) (xy 403.138196 -401.903912) (xy 403.10871 -401.858031) (xy 403.086053 -401.808421)
			(xy 403.070688 -401.756091) (xy 403.062926 -401.702107) (xy 403.06244 -401.674838) (xy 389.29818 -401.674838)
			(xy 389.297694 -401.702107) (xy 389.289932 -401.756091) (xy 389.274567 -401.808421) (xy 389.25191 -401.858031)
			(xy 389.222424 -401.903912) (xy 389.186709 -401.945129) (xy 389.145492 -401.980844) (xy 389.099611 -402.01033)
			(xy 389.050001 -402.032987) (xy 388.997671 -402.048352) (xy 388.943687 -402.056114) (xy 388.889149 -402.056114)
			(xy 388.835165 -402.048352) (xy 388.782835 -402.032987) (xy 388.733225 -402.01033) (xy 388.687344 -401.980844)
			(xy 388.646127 -401.945129) (xy 388.610412 -401.903912) (xy 388.580926 -401.858031) (xy 388.558269 -401.808421)
			(xy 388.542904 -401.756091) (xy 388.535142 -401.702107) (xy 388.534656 -401.674838) (xy 388.098284 -401.674838)
			(xy 388.097798 -401.702107) (xy 388.090036 -401.756091) (xy 388.074671 -401.808421) (xy 388.052014 -401.858031)
			(xy 388.022528 -401.903912) (xy 387.986813 -401.945129) (xy 387.945596 -401.980844) (xy 387.899715 -402.01033)
			(xy 387.850105 -402.032987) (xy 387.797775 -402.048352) (xy 387.743791 -402.056114) (xy 387.689253 -402.056114)
			(xy 387.635269 -402.048352) (xy 387.582939 -402.032987) (xy 387.533329 -402.01033) (xy 387.487448 -401.980844)
			(xy 387.446231 -401.945129) (xy 387.410516 -401.903912) (xy 387.38103 -401.858031) (xy 387.358373 -401.808421)
			(xy 387.343008 -401.756091) (xy 387.335246 -401.702107) (xy 387.33476 -401.674838) (xy 386.89788 -401.674838)
			(xy 386.897394 -401.702089) (xy 386.889638 -401.756037) (xy 386.874283 -401.808332) (xy 386.851641 -401.857909)
			(xy 386.822175 -401.903759) (xy 386.786484 -401.94495) (xy 386.745293 -401.980641) (xy 386.699443 -402.010107)
			(xy 386.649866 -402.032749) (xy 386.597571 -402.048104) (xy 386.543623 -402.05586) (xy 386.489121 -402.05586)
			(xy 386.435173 -402.048104) (xy 386.382878 -402.032749) (xy 386.333301 -402.010107) (xy 386.287451 -401.980641)
			(xy 386.24626 -401.94495) (xy 386.210569 -401.903759) (xy 386.181103 -401.857909) (xy 386.158461 -401.808332)
			(xy 386.143106 -401.756037) (xy 386.13535 -401.702089) (xy 386.134864 -401.674838) (xy 385.697984 -401.674838)
			(xy 385.697498 -401.702089) (xy 385.689742 -401.756037) (xy 385.674387 -401.808332) (xy 385.651745 -401.857909)
			(xy 385.622279 -401.903759) (xy 385.586588 -401.94495) (xy 385.545397 -401.980641) (xy 385.499547 -402.010107)
			(xy 385.44997 -402.032749) (xy 385.397675 -402.048104) (xy 385.343727 -402.05586) (xy 385.289225 -402.05586)
			(xy 385.235277 -402.048104) (xy 385.182982 -402.032749) (xy 385.133405 -402.010107) (xy 385.087555 -401.980641)
			(xy 385.046364 -401.94495) (xy 385.010673 -401.903759) (xy 384.981207 -401.857909) (xy 384.958565 -401.808332)
			(xy 384.94321 -401.756037) (xy 384.935454 -401.702089) (xy 384.934968 -401.674838) (xy 384.498088 -401.674838)
			(xy 384.497602 -401.702089) (xy 384.489846 -401.756037) (xy 384.474491 -401.808332) (xy 384.451849 -401.857909)
			(xy 384.422383 -401.903759) (xy 384.386692 -401.94495) (xy 384.345501 -401.980641) (xy 384.299651 -402.010107)
			(xy 384.250074 -402.032749) (xy 384.197779 -402.048104) (xy 384.143831 -402.05586) (xy 384.089329 -402.05586)
			(xy 384.035381 -402.048104) (xy 383.983086 -402.032749) (xy 383.933509 -402.010107) (xy 383.887659 -401.980641)
			(xy 383.846468 -401.94495) (xy 383.810777 -401.903759) (xy 383.781311 -401.857909) (xy 383.758669 -401.808332)
			(xy 383.743314 -401.756037) (xy 383.735558 -401.702089) (xy 383.735072 -401.674838) (xy 383.298192 -401.674838)
			(xy 383.297706 -401.702089) (xy 383.28995 -401.756037) (xy 383.274595 -401.808332) (xy 383.251953 -401.857909)
			(xy 383.222487 -401.903759) (xy 383.186796 -401.94495) (xy 383.145605 -401.980641) (xy 383.099755 -402.010107)
			(xy 383.050178 -402.032749) (xy 382.997883 -402.048104) (xy 382.943935 -402.05586) (xy 382.889433 -402.05586)
			(xy 382.835485 -402.048104) (xy 382.78319 -402.032749) (xy 382.733613 -402.010107) (xy 382.687763 -401.980641)
			(xy 382.646572 -401.94495) (xy 382.610881 -401.903759) (xy 382.581415 -401.857909) (xy 382.558773 -401.808332)
			(xy 382.543418 -401.756037) (xy 382.535662 -401.702089) (xy 382.535176 -401.674838) (xy 382.098296 -401.674838)
			(xy 382.09781 -401.702107) (xy 382.090048 -401.756091) (xy 382.074683 -401.808421) (xy 382.052026 -401.858031)
			(xy 382.02254 -401.903912) (xy 381.986825 -401.945129) (xy 381.945608 -401.980844) (xy 381.899727 -402.01033)
			(xy 381.850117 -402.032987) (xy 381.797787 -402.048352) (xy 381.743803 -402.056114) (xy 381.689265 -402.056114)
			(xy 381.635281 -402.048352) (xy 381.582951 -402.032987) (xy 381.533341 -402.01033) (xy 381.48746 -401.980844)
			(xy 381.446243 -401.945129) (xy 381.410528 -401.903912) (xy 381.381042 -401.858031) (xy 381.358385 -401.808421)
			(xy 381.34302 -401.756091) (xy 381.335258 -401.702107) (xy 381.334772 -401.674838) (xy 380.8984 -401.674838)
			(xy 380.897914 -401.702107) (xy 380.890152 -401.756091) (xy 380.874787 -401.808421) (xy 380.85213 -401.858031)
			(xy 380.822644 -401.903912) (xy 380.786929 -401.945129) (xy 380.745712 -401.980844) (xy 380.699831 -402.01033)
			(xy 380.650221 -402.032987) (xy 380.597891 -402.048352) (xy 380.543907 -402.056114) (xy 380.489369 -402.056114)
			(xy 380.435385 -402.048352) (xy 380.383055 -402.032987) (xy 380.333445 -402.01033) (xy 380.287564 -401.980844)
			(xy 380.246347 -401.945129) (xy 380.210632 -401.903912) (xy 380.181146 -401.858031) (xy 380.158489 -401.808421)
			(xy 380.143124 -401.756091) (xy 380.135362 -401.702107) (xy 380.134876 -401.674838) (xy 379.697996 -401.674838)
			(xy 379.69751 -401.702089) (xy 379.689754 -401.756037) (xy 379.674399 -401.808332) (xy 379.651757 -401.857909)
			(xy 379.622291 -401.903759) (xy 379.5866 -401.94495) (xy 379.545409 -401.980641) (xy 379.499559 -402.010107)
			(xy 379.449982 -402.032749) (xy 379.397687 -402.048104) (xy 379.343739 -402.05586) (xy 379.289237 -402.05586)
			(xy 379.235289 -402.048104) (xy 379.182994 -402.032749) (xy 379.133417 -402.010107) (xy 379.087567 -401.980641)
			(xy 379.046376 -401.94495) (xy 379.010685 -401.903759) (xy 378.981219 -401.857909) (xy 378.958577 -401.808332)
			(xy 378.943222 -401.756037) (xy 378.935466 -401.702089) (xy 378.93498 -401.674838) (xy 378.4981 -401.674838)
			(xy 378.497614 -401.702089) (xy 378.489858 -401.756037) (xy 378.474503 -401.808332) (xy 378.451861 -401.857909)
			(xy 378.422395 -401.903759) (xy 378.386704 -401.94495) (xy 378.345513 -401.980641) (xy 378.299663 -402.010107)
			(xy 378.250086 -402.032749) (xy 378.197791 -402.048104) (xy 378.143843 -402.05586) (xy 378.089341 -402.05586)
			(xy 378.035393 -402.048104) (xy 377.983098 -402.032749) (xy 377.933521 -402.010107) (xy 377.887671 -401.980641)
			(xy 377.84648 -401.94495) (xy 377.810789 -401.903759) (xy 377.781323 -401.857909) (xy 377.758681 -401.808332)
			(xy 377.743326 -401.756037) (xy 377.73557 -401.702089) (xy 377.735084 -401.674838) (xy 377.298204 -401.674838)
			(xy 377.297718 -401.702107) (xy 377.289956 -401.756091) (xy 377.274591 -401.808421) (xy 377.251934 -401.858031)
			(xy 377.222448 -401.903912) (xy 377.186733 -401.945129) (xy 377.145516 -401.980844) (xy 377.099635 -402.01033)
			(xy 377.050025 -402.032987) (xy 376.997695 -402.048352) (xy 376.943711 -402.056114) (xy 376.889173 -402.056114)
			(xy 376.835189 -402.048352) (xy 376.782859 -402.032987) (xy 376.733249 -402.01033) (xy 376.687368 -401.980844)
			(xy 376.646151 -401.945129) (xy 376.610436 -401.903912) (xy 376.58095 -401.858031) (xy 376.558293 -401.808421)
			(xy 376.542928 -401.756091) (xy 376.535166 -401.702107) (xy 376.53468 -401.674838) (xy 376.098308 -401.674838)
			(xy 376.097822 -401.702107) (xy 376.09006 -401.756091) (xy 376.074695 -401.808421) (xy 376.052038 -401.858031)
			(xy 376.022552 -401.903912) (xy 375.986837 -401.945129) (xy 375.94562 -401.980844) (xy 375.899739 -402.01033)
			(xy 375.850129 -402.032987) (xy 375.797799 -402.048352) (xy 375.743815 -402.056114) (xy 375.689277 -402.056114)
			(xy 375.635293 -402.048352) (xy 375.582963 -402.032987) (xy 375.533353 -402.01033) (xy 375.487472 -401.980844)
			(xy 375.446255 -401.945129) (xy 375.41054 -401.903912) (xy 375.381054 -401.858031) (xy 375.358397 -401.808421)
			(xy 375.343032 -401.756091) (xy 375.33527 -401.702107) (xy 375.334784 -401.674838) (xy 374.897904 -401.674838)
			(xy 374.897418 -401.702089) (xy 374.889662 -401.756037) (xy 374.874307 -401.808332) (xy 374.851665 -401.857909)
			(xy 374.822199 -401.903759) (xy 374.786508 -401.94495) (xy 374.745317 -401.980641) (xy 374.699467 -402.010107)
			(xy 374.64989 -402.032749) (xy 374.597595 -402.048104) (xy 374.543647 -402.05586) (xy 374.489145 -402.05586)
			(xy 374.435197 -402.048104) (xy 374.382902 -402.032749) (xy 374.333325 -402.010107) (xy 374.287475 -401.980641)
			(xy 374.246284 -401.94495) (xy 374.210593 -401.903759) (xy 374.181127 -401.857909) (xy 374.158485 -401.808332)
			(xy 374.14313 -401.756037) (xy 374.135374 -401.702089) (xy 374.134888 -401.674838) (xy 373.698008 -401.674838)
			(xy 373.697522 -401.702089) (xy 373.689766 -401.756037) (xy 373.674411 -401.808332) (xy 373.651769 -401.857909)
			(xy 373.622303 -401.903759) (xy 373.586612 -401.94495) (xy 373.545421 -401.980641) (xy 373.499571 -402.010107)
			(xy 373.449994 -402.032749) (xy 373.397699 -402.048104) (xy 373.343751 -402.05586) (xy 373.289249 -402.05586)
			(xy 373.235301 -402.048104) (xy 373.183006 -402.032749) (xy 373.133429 -402.010107) (xy 373.087579 -401.980641)
			(xy 373.046388 -401.94495) (xy 373.010697 -401.903759) (xy 372.981231 -401.857909) (xy 372.958589 -401.808332)
			(xy 372.943234 -401.756037) (xy 372.935478 -401.702089) (xy 372.934992 -401.674838) (xy 372.498112 -401.674838)
			(xy 372.497626 -401.702107) (xy 372.489864 -401.756091) (xy 372.474499 -401.808421) (xy 372.451842 -401.858031)
			(xy 372.422356 -401.903912) (xy 372.386641 -401.945129) (xy 372.345424 -401.980844) (xy 372.299543 -402.01033)
			(xy 372.249933 -402.032987) (xy 372.197603 -402.048352) (xy 372.143619 -402.056114) (xy 372.089081 -402.056114)
			(xy 372.035097 -402.048352) (xy 371.982767 -402.032987) (xy 371.933157 -402.01033) (xy 371.887276 -401.980844)
			(xy 371.846059 -401.945129) (xy 371.810344 -401.903912) (xy 371.780858 -401.858031) (xy 371.758201 -401.808421)
			(xy 371.742836 -401.756091) (xy 371.735074 -401.702107) (xy 371.734588 -401.674838) (xy 371.298216 -401.674838)
			(xy 371.29773 -401.702107) (xy 371.289968 -401.756091) (xy 371.274603 -401.808421) (xy 371.251946 -401.858031)
			(xy 371.22246 -401.903912) (xy 371.186745 -401.945129) (xy 371.145528 -401.980844) (xy 371.099647 -402.01033)
			(xy 371.050037 -402.032987) (xy 370.997707 -402.048352) (xy 370.943723 -402.056114) (xy 370.889185 -402.056114)
			(xy 370.835201 -402.048352) (xy 370.782871 -402.032987) (xy 370.733261 -402.01033) (xy 370.68738 -401.980844)
			(xy 370.646163 -401.945129) (xy 370.610448 -401.903912) (xy 370.580962 -401.858031) (xy 370.558305 -401.808421)
			(xy 370.54294 -401.756091) (xy 370.535178 -401.702107) (xy 370.534692 -401.674838) (xy 354.725732 -401.674838)
			(xy 354.725246 -401.702107) (xy 354.717484 -401.756091) (xy 354.702119 -401.808421) (xy 354.679462 -401.858031)
			(xy 354.649976 -401.903912) (xy 354.614261 -401.945129) (xy 354.573044 -401.980844) (xy 354.527163 -402.01033)
			(xy 354.477553 -402.032987) (xy 354.425223 -402.048352) (xy 354.371239 -402.056114) (xy 354.316701 -402.056114)
			(xy 354.262717 -402.048352) (xy 354.210387 -402.032987) (xy 354.160777 -402.01033) (xy 354.114896 -401.980844)
			(xy 354.073679 -401.945129) (xy 354.037964 -401.903912) (xy 354.008478 -401.858031) (xy 353.985821 -401.808421)
			(xy 353.970456 -401.756091) (xy 353.962694 -401.702107) (xy 353.962208 -401.674838) (xy 353.525836 -401.674838)
			(xy 353.52535 -401.702107) (xy 353.517588 -401.756091) (xy 353.502223 -401.808421) (xy 353.479566 -401.858031)
			(xy 353.45008 -401.903912) (xy 353.414365 -401.945129) (xy 353.373148 -401.980844) (xy 353.327267 -402.01033)
			(xy 353.277657 -402.032987) (xy 353.225327 -402.048352) (xy 353.171343 -402.056114) (xy 353.116805 -402.056114)
			(xy 353.062821 -402.048352) (xy 353.010491 -402.032987) (xy 352.960881 -402.01033) (xy 352.915 -401.980844)
			(xy 352.873783 -401.945129) (xy 352.838068 -401.903912) (xy 352.808582 -401.858031) (xy 352.785925 -401.808421)
			(xy 352.77056 -401.756091) (xy 352.762798 -401.702107) (xy 352.762312 -401.674838) (xy 352.325432 -401.674838)
			(xy 352.324946 -401.702089) (xy 352.31719 -401.756037) (xy 352.301835 -401.808332) (xy 352.279193 -401.857909)
			(xy 352.249727 -401.903759) (xy 352.214036 -401.94495) (xy 352.172845 -401.980641) (xy 352.126995 -402.010107)
			(xy 352.077418 -402.032749) (xy 352.025123 -402.048104) (xy 351.971175 -402.05586) (xy 351.916673 -402.05586)
			(xy 351.862725 -402.048104) (xy 351.81043 -402.032749) (xy 351.760853 -402.010107) (xy 351.715003 -401.980641)
			(xy 351.673812 -401.94495) (xy 351.638121 -401.903759) (xy 351.608655 -401.857909) (xy 351.586013 -401.808332)
			(xy 351.570658 -401.756037) (xy 351.562902 -401.702089) (xy 351.562416 -401.674838) (xy 351.125536 -401.674838)
			(xy 351.12505 -401.702089) (xy 351.117294 -401.756037) (xy 351.101939 -401.808332) (xy 351.079297 -401.857909)
			(xy 351.049831 -401.903759) (xy 351.01414 -401.94495) (xy 350.972949 -401.980641) (xy 350.927099 -402.010107)
			(xy 350.877522 -402.032749) (xy 350.825227 -402.048104) (xy 350.771279 -402.05586) (xy 350.716777 -402.05586)
			(xy 350.662829 -402.048104) (xy 350.610534 -402.032749) (xy 350.560957 -402.010107) (xy 350.515107 -401.980641)
			(xy 350.473916 -401.94495) (xy 350.438225 -401.903759) (xy 350.408759 -401.857909) (xy 350.386117 -401.808332)
			(xy 350.370762 -401.756037) (xy 350.363006 -401.702089) (xy 350.36252 -401.674838) (xy 349.92564 -401.674838)
			(xy 349.925154 -401.702089) (xy 349.917398 -401.756037) (xy 349.902043 -401.808332) (xy 349.879401 -401.857909)
			(xy 349.849935 -401.903759) (xy 349.814244 -401.94495) (xy 349.773053 -401.980641) (xy 349.727203 -402.010107)
			(xy 349.677626 -402.032749) (xy 349.625331 -402.048104) (xy 349.571383 -402.05586) (xy 349.516881 -402.05586)
			(xy 349.462933 -402.048104) (xy 349.410638 -402.032749) (xy 349.361061 -402.010107) (xy 349.315211 -401.980641)
			(xy 349.27402 -401.94495) (xy 349.238329 -401.903759) (xy 349.208863 -401.857909) (xy 349.186221 -401.808332)
			(xy 349.170866 -401.756037) (xy 349.16311 -401.702089) (xy 349.162624 -401.674838) (xy 348.725744 -401.674838)
			(xy 348.725258 -401.702089) (xy 348.717502 -401.756037) (xy 348.702147 -401.808332) (xy 348.679505 -401.857909)
			(xy 348.650039 -401.903759) (xy 348.614348 -401.94495) (xy 348.573157 -401.980641) (xy 348.527307 -402.010107)
			(xy 348.47773 -402.032749) (xy 348.425435 -402.048104) (xy 348.371487 -402.05586) (xy 348.316985 -402.05586)
			(xy 348.263037 -402.048104) (xy 348.210742 -402.032749) (xy 348.161165 -402.010107) (xy 348.115315 -401.980641)
			(xy 348.074124 -401.94495) (xy 348.038433 -401.903759) (xy 348.008967 -401.857909) (xy 347.986325 -401.808332)
			(xy 347.97097 -401.756037) (xy 347.963214 -401.702089) (xy 347.962728 -401.674838) (xy 347.525848 -401.674838)
			(xy 347.525362 -401.702107) (xy 347.5176 -401.756091) (xy 347.502235 -401.808421) (xy 347.479578 -401.858031)
			(xy 347.450092 -401.903912) (xy 347.414377 -401.945129) (xy 347.37316 -401.980844) (xy 347.327279 -402.01033)
			(xy 347.277669 -402.032987) (xy 347.225339 -402.048352) (xy 347.171355 -402.056114) (xy 347.116817 -402.056114)
			(xy 347.062833 -402.048352) (xy 347.010503 -402.032987) (xy 346.960893 -402.01033) (xy 346.915012 -401.980844)
			(xy 346.873795 -401.945129) (xy 346.83808 -401.903912) (xy 346.808594 -401.858031) (xy 346.785937 -401.808421)
			(xy 346.770572 -401.756091) (xy 346.76281 -401.702107) (xy 346.762324 -401.674838) (xy 346.325952 -401.674838)
			(xy 346.325466 -401.702107) (xy 346.317704 -401.756091) (xy 346.302339 -401.808421) (xy 346.279682 -401.858031)
			(xy 346.250196 -401.903912) (xy 346.214481 -401.945129) (xy 346.173264 -401.980844) (xy 346.127383 -402.01033)
			(xy 346.077773 -402.032987) (xy 346.025443 -402.048352) (xy 345.971459 -402.056114) (xy 345.916921 -402.056114)
			(xy 345.862937 -402.048352) (xy 345.810607 -402.032987) (xy 345.760997 -402.01033) (xy 345.715116 -401.980844)
			(xy 345.673899 -401.945129) (xy 345.638184 -401.903912) (xy 345.608698 -401.858031) (xy 345.586041 -401.808421)
			(xy 345.570676 -401.756091) (xy 345.562914 -401.702107) (xy 345.562428 -401.674838) (xy 345.125548 -401.674838)
			(xy 345.125062 -401.702089) (xy 345.117306 -401.756037) (xy 345.101951 -401.808332) (xy 345.079309 -401.857909)
			(xy 345.049843 -401.903759) (xy 345.014152 -401.94495) (xy 344.972961 -401.980641) (xy 344.927111 -402.010107)
			(xy 344.877534 -402.032749) (xy 344.825239 -402.048104) (xy 344.771291 -402.05586) (xy 344.716789 -402.05586)
			(xy 344.662841 -402.048104) (xy 344.610546 -402.032749) (xy 344.560969 -402.010107) (xy 344.515119 -401.980641)
			(xy 344.473928 -401.94495) (xy 344.438237 -401.903759) (xy 344.408771 -401.857909) (xy 344.386129 -401.808332)
			(xy 344.370774 -401.756037) (xy 344.363018 -401.702089) (xy 344.362532 -401.674838) (xy 343.925652 -401.674838)
			(xy 343.925166 -401.702089) (xy 343.91741 -401.756037) (xy 343.902055 -401.808332) (xy 343.879413 -401.857909)
			(xy 343.849947 -401.903759) (xy 343.814256 -401.94495) (xy 343.773065 -401.980641) (xy 343.727215 -402.010107)
			(xy 343.677638 -402.032749) (xy 343.625343 -402.048104) (xy 343.571395 -402.05586) (xy 343.516893 -402.05586)
			(xy 343.462945 -402.048104) (xy 343.41065 -402.032749) (xy 343.361073 -402.010107) (xy 343.315223 -401.980641)
			(xy 343.274032 -401.94495) (xy 343.238341 -401.903759) (xy 343.208875 -401.857909) (xy 343.186233 -401.808332)
			(xy 343.170878 -401.756037) (xy 343.163122 -401.702089) (xy 343.162636 -401.674838) (xy 342.725756 -401.674838)
			(xy 342.72527 -401.702107) (xy 342.717508 -401.756091) (xy 342.702143 -401.808421) (xy 342.679486 -401.858031)
			(xy 342.65 -401.903912) (xy 342.614285 -401.945129) (xy 342.573068 -401.980844) (xy 342.527187 -402.01033)
			(xy 342.477577 -402.032987) (xy 342.425247 -402.048352) (xy 342.371263 -402.056114) (xy 342.316725 -402.056114)
			(xy 342.262741 -402.048352) (xy 342.210411 -402.032987) (xy 342.160801 -402.01033) (xy 342.11492 -401.980844)
			(xy 342.073703 -401.945129) (xy 342.037988 -401.903912) (xy 342.008502 -401.858031) (xy 341.985845 -401.808421)
			(xy 341.97048 -401.756091) (xy 341.962718 -401.702107) (xy 341.962232 -401.674838) (xy 341.52586 -401.674838)
			(xy 341.525374 -401.702107) (xy 341.517612 -401.756091) (xy 341.502247 -401.808421) (xy 341.47959 -401.858031)
			(xy 341.450104 -401.903912) (xy 341.414389 -401.945129) (xy 341.373172 -401.980844) (xy 341.327291 -402.01033)
			(xy 341.277681 -402.032987) (xy 341.225351 -402.048352) (xy 341.171367 -402.056114) (xy 341.116829 -402.056114)
			(xy 341.062845 -402.048352) (xy 341.010515 -402.032987) (xy 340.960905 -402.01033) (xy 340.915024 -401.980844)
			(xy 340.873807 -401.945129) (xy 340.838092 -401.903912) (xy 340.808606 -401.858031) (xy 340.785949 -401.808421)
			(xy 340.770584 -401.756091) (xy 340.762822 -401.702107) (xy 340.762336 -401.674838) (xy 340.325456 -401.674838)
			(xy 340.32497 -401.702089) (xy 340.317214 -401.756037) (xy 340.301859 -401.808332) (xy 340.279217 -401.857909)
			(xy 340.249751 -401.903759) (xy 340.21406 -401.94495) (xy 340.172869 -401.980641) (xy 340.127019 -402.010107)
			(xy 340.077442 -402.032749) (xy 340.025147 -402.048104) (xy 339.971199 -402.05586) (xy 339.916697 -402.05586)
			(xy 339.862749 -402.048104) (xy 339.810454 -402.032749) (xy 339.760877 -402.010107) (xy 339.715027 -401.980641)
			(xy 339.673836 -401.94495) (xy 339.638145 -401.903759) (xy 339.608679 -401.857909) (xy 339.586037 -401.808332)
			(xy 339.570682 -401.756037) (xy 339.562926 -401.702089) (xy 339.56244 -401.674838) (xy 339.12556 -401.674838)
			(xy 339.125074 -401.702089) (xy 339.117318 -401.756037) (xy 339.101963 -401.808332) (xy 339.079321 -401.857909)
			(xy 339.049855 -401.903759) (xy 339.014164 -401.94495) (xy 338.972973 -401.980641) (xy 338.927123 -402.010107)
			(xy 338.877546 -402.032749) (xy 338.825251 -402.048104) (xy 338.771303 -402.05586) (xy 338.716801 -402.05586)
			(xy 338.662853 -402.048104) (xy 338.610558 -402.032749) (xy 338.560981 -402.010107) (xy 338.515131 -401.980641)
			(xy 338.47394 -401.94495) (xy 338.438249 -401.903759) (xy 338.408783 -401.857909) (xy 338.386141 -401.808332)
			(xy 338.370786 -401.756037) (xy 338.36303 -401.702089) (xy 338.362544 -401.674838) (xy 337.925664 -401.674838)
			(xy 337.925178 -401.702107) (xy 337.917416 -401.756091) (xy 337.902051 -401.808421) (xy 337.879394 -401.858031)
			(xy 337.849908 -401.903912) (xy 337.814193 -401.945129) (xy 337.772976 -401.980844) (xy 337.727095 -402.01033)
			(xy 337.677485 -402.032987) (xy 337.625155 -402.048352) (xy 337.571171 -402.056114) (xy 337.516633 -402.056114)
			(xy 337.462649 -402.048352) (xy 337.410319 -402.032987) (xy 337.360709 -402.01033) (xy 337.314828 -401.980844)
			(xy 337.273611 -401.945129) (xy 337.237896 -401.903912) (xy 337.20841 -401.858031) (xy 337.185753 -401.808421)
			(xy 337.170388 -401.756091) (xy 337.162626 -401.702107) (xy 337.16214 -401.674838) (xy 336.725768 -401.674838)
			(xy 336.725282 -401.702107) (xy 336.71752 -401.756091) (xy 336.702155 -401.808421) (xy 336.679498 -401.858031)
			(xy 336.650012 -401.903912) (xy 336.614297 -401.945129) (xy 336.57308 -401.980844) (xy 336.527199 -402.01033)
			(xy 336.477589 -402.032987) (xy 336.425259 -402.048352) (xy 336.371275 -402.056114) (xy 336.316737 -402.056114)
			(xy 336.262753 -402.048352) (xy 336.210423 -402.032987) (xy 336.160813 -402.01033) (xy 336.114932 -401.980844)
			(xy 336.073715 -401.945129) (xy 336.038 -401.903912) (xy 336.008514 -401.858031) (xy 335.985857 -401.808421)
			(xy 335.970492 -401.756091) (xy 335.96273 -401.702107) (xy 335.962244 -401.674838) (xy 322.197984 -401.674838)
			(xy 322.197498 -401.702107) (xy 322.189736 -401.756091) (xy 322.174371 -401.808421) (xy 322.151714 -401.858031)
			(xy 322.122228 -401.903912) (xy 322.086513 -401.945129) (xy 322.045296 -401.980844) (xy 321.999415 -402.01033)
			(xy 321.949805 -402.032987) (xy 321.897475 -402.048352) (xy 321.843491 -402.056114) (xy 321.788953 -402.056114)
			(xy 321.734969 -402.048352) (xy 321.682639 -402.032987) (xy 321.633029 -402.01033) (xy 321.587148 -401.980844)
			(xy 321.545931 -401.945129) (xy 321.510216 -401.903912) (xy 321.48073 -401.858031) (xy 321.458073 -401.808421)
			(xy 321.442708 -401.756091) (xy 321.434946 -401.702107) (xy 321.43446 -401.674838) (xy 320.998088 -401.674838)
			(xy 320.997602 -401.702107) (xy 320.98984 -401.756091) (xy 320.974475 -401.808421) (xy 320.951818 -401.858031)
			(xy 320.922332 -401.903912) (xy 320.886617 -401.945129) (xy 320.8454 -401.980844) (xy 320.799519 -402.01033)
			(xy 320.749909 -402.032987) (xy 320.697579 -402.048352) (xy 320.643595 -402.056114) (xy 320.589057 -402.056114)
			(xy 320.535073 -402.048352) (xy 320.482743 -402.032987) (xy 320.433133 -402.01033) (xy 320.387252 -401.980844)
			(xy 320.346035 -401.945129) (xy 320.31032 -401.903912) (xy 320.280834 -401.858031) (xy 320.258177 -401.808421)
			(xy 320.242812 -401.756091) (xy 320.23505 -401.702107) (xy 320.234564 -401.674838) (xy 319.797684 -401.674838)
			(xy 319.797198 -401.702089) (xy 319.789442 -401.756037) (xy 319.774087 -401.808332) (xy 319.751445 -401.857909)
			(xy 319.721979 -401.903759) (xy 319.686288 -401.94495) (xy 319.645097 -401.980641) (xy 319.599247 -402.010107)
			(xy 319.54967 -402.032749) (xy 319.497375 -402.048104) (xy 319.443427 -402.05586) (xy 319.388925 -402.05586)
			(xy 319.334977 -402.048104) (xy 319.282682 -402.032749) (xy 319.233105 -402.010107) (xy 319.187255 -401.980641)
			(xy 319.146064 -401.94495) (xy 319.110373 -401.903759) (xy 319.080907 -401.857909) (xy 319.058265 -401.808332)
			(xy 319.04291 -401.756037) (xy 319.035154 -401.702089) (xy 319.034668 -401.674838) (xy 318.597788 -401.674838)
			(xy 318.597302 -401.702089) (xy 318.589546 -401.756037) (xy 318.574191 -401.808332) (xy 318.551549 -401.857909)
			(xy 318.522083 -401.903759) (xy 318.486392 -401.94495) (xy 318.445201 -401.980641) (xy 318.399351 -402.010107)
			(xy 318.349774 -402.032749) (xy 318.297479 -402.048104) (xy 318.243531 -402.05586) (xy 318.189029 -402.05586)
			(xy 318.135081 -402.048104) (xy 318.082786 -402.032749) (xy 318.033209 -402.010107) (xy 317.987359 -401.980641)
			(xy 317.946168 -401.94495) (xy 317.910477 -401.903759) (xy 317.881011 -401.857909) (xy 317.858369 -401.808332)
			(xy 317.843014 -401.756037) (xy 317.835258 -401.702089) (xy 317.834772 -401.674838) (xy 317.397892 -401.674838)
			(xy 317.397406 -401.702089) (xy 317.38965 -401.756037) (xy 317.374295 -401.808332) (xy 317.351653 -401.857909)
			(xy 317.322187 -401.903759) (xy 317.286496 -401.94495) (xy 317.245305 -401.980641) (xy 317.199455 -402.010107)
			(xy 317.149878 -402.032749) (xy 317.097583 -402.048104) (xy 317.043635 -402.05586) (xy 316.989133 -402.05586)
			(xy 316.935185 -402.048104) (xy 316.88289 -402.032749) (xy 316.833313 -402.010107) (xy 316.787463 -401.980641)
			(xy 316.746272 -401.94495) (xy 316.710581 -401.903759) (xy 316.681115 -401.857909) (xy 316.658473 -401.808332)
			(xy 316.643118 -401.756037) (xy 316.635362 -401.702089) (xy 316.634876 -401.674838) (xy 316.197996 -401.674838)
			(xy 316.19751 -401.702089) (xy 316.189754 -401.756037) (xy 316.174399 -401.808332) (xy 316.151757 -401.857909)
			(xy 316.122291 -401.903759) (xy 316.0866 -401.94495) (xy 316.045409 -401.980641) (xy 315.999559 -402.010107)
			(xy 315.949982 -402.032749) (xy 315.897687 -402.048104) (xy 315.843739 -402.05586) (xy 315.789237 -402.05586)
			(xy 315.735289 -402.048104) (xy 315.682994 -402.032749) (xy 315.633417 -402.010107) (xy 315.587567 -401.980641)
			(xy 315.546376 -401.94495) (xy 315.510685 -401.903759) (xy 315.481219 -401.857909) (xy 315.458577 -401.808332)
			(xy 315.443222 -401.756037) (xy 315.435466 -401.702089) (xy 315.43498 -401.674838) (xy 314.9981 -401.674838)
			(xy 314.997614 -401.702107) (xy 314.989852 -401.756091) (xy 314.974487 -401.808421) (xy 314.95183 -401.858031)
			(xy 314.922344 -401.903912) (xy 314.886629 -401.945129) (xy 314.845412 -401.980844) (xy 314.799531 -402.01033)
			(xy 314.749921 -402.032987) (xy 314.697591 -402.048352) (xy 314.643607 -402.056114) (xy 314.589069 -402.056114)
			(xy 314.535085 -402.048352) (xy 314.482755 -402.032987) (xy 314.433145 -402.01033) (xy 314.387264 -401.980844)
			(xy 314.346047 -401.945129) (xy 314.310332 -401.903912) (xy 314.280846 -401.858031) (xy 314.258189 -401.808421)
			(xy 314.242824 -401.756091) (xy 314.235062 -401.702107) (xy 314.234576 -401.674838) (xy 313.798204 -401.674838)
			(xy 313.797718 -401.702107) (xy 313.789956 -401.756091) (xy 313.774591 -401.808421) (xy 313.751934 -401.858031)
			(xy 313.722448 -401.903912) (xy 313.686733 -401.945129) (xy 313.645516 -401.980844) (xy 313.599635 -402.01033)
			(xy 313.550025 -402.032987) (xy 313.497695 -402.048352) (xy 313.443711 -402.056114) (xy 313.389173 -402.056114)
			(xy 313.335189 -402.048352) (xy 313.282859 -402.032987) (xy 313.233249 -402.01033) (xy 313.187368 -401.980844)
			(xy 313.146151 -401.945129) (xy 313.110436 -401.903912) (xy 313.08095 -401.858031) (xy 313.058293 -401.808421)
			(xy 313.042928 -401.756091) (xy 313.035166 -401.702107) (xy 313.03468 -401.674838) (xy 312.5978 -401.674838)
			(xy 312.597314 -401.702089) (xy 312.589558 -401.756037) (xy 312.574203 -401.808332) (xy 312.551561 -401.857909)
			(xy 312.522095 -401.903759) (xy 312.486404 -401.94495) (xy 312.445213 -401.980641) (xy 312.399363 -402.010107)
			(xy 312.349786 -402.032749) (xy 312.297491 -402.048104) (xy 312.243543 -402.05586) (xy 312.189041 -402.05586)
			(xy 312.135093 -402.048104) (xy 312.082798 -402.032749) (xy 312.033221 -402.010107) (xy 311.987371 -401.980641)
			(xy 311.94618 -401.94495) (xy 311.910489 -401.903759) (xy 311.881023 -401.857909) (xy 311.858381 -401.808332)
			(xy 311.843026 -401.756037) (xy 311.83527 -401.702089) (xy 311.834784 -401.674838) (xy 311.397904 -401.674838)
			(xy 311.397418 -401.702089) (xy 311.389662 -401.756037) (xy 311.374307 -401.808332) (xy 311.351665 -401.857909)
			(xy 311.322199 -401.903759) (xy 311.286508 -401.94495) (xy 311.245317 -401.980641) (xy 311.199467 -402.010107)
			(xy 311.14989 -402.032749) (xy 311.097595 -402.048104) (xy 311.043647 -402.05586) (xy 310.989145 -402.05586)
			(xy 310.935197 -402.048104) (xy 310.882902 -402.032749) (xy 310.833325 -402.010107) (xy 310.787475 -401.980641)
			(xy 310.746284 -401.94495) (xy 310.710593 -401.903759) (xy 310.681127 -401.857909) (xy 310.658485 -401.808332)
			(xy 310.64313 -401.756037) (xy 310.635374 -401.702089) (xy 310.634888 -401.674838) (xy 310.198008 -401.674838)
			(xy 310.197522 -401.702107) (xy 310.18976 -401.756091) (xy 310.174395 -401.808421) (xy 310.151738 -401.858031)
			(xy 310.122252 -401.903912) (xy 310.086537 -401.945129) (xy 310.04532 -401.980844) (xy 309.999439 -402.01033)
			(xy 309.949829 -402.032987) (xy 309.897499 -402.048352) (xy 309.843515 -402.056114) (xy 309.788977 -402.056114)
			(xy 309.734993 -402.048352) (xy 309.682663 -402.032987) (xy 309.633053 -402.01033) (xy 309.587172 -401.980844)
			(xy 309.545955 -401.945129) (xy 309.51024 -401.903912) (xy 309.480754 -401.858031) (xy 309.458097 -401.808421)
			(xy 309.442732 -401.756091) (xy 309.43497 -401.702107) (xy 309.434484 -401.674838) (xy 308.998112 -401.674838)
			(xy 308.997626 -401.702107) (xy 308.989864 -401.756091) (xy 308.974499 -401.808421) (xy 308.951842 -401.858031)
			(xy 308.922356 -401.903912) (xy 308.886641 -401.945129) (xy 308.845424 -401.980844) (xy 308.799543 -402.01033)
			(xy 308.749933 -402.032987) (xy 308.697603 -402.048352) (xy 308.643619 -402.056114) (xy 308.589081 -402.056114)
			(xy 308.535097 -402.048352) (xy 308.482767 -402.032987) (xy 308.433157 -402.01033) (xy 308.387276 -401.980844)
			(xy 308.346059 -401.945129) (xy 308.310344 -401.903912) (xy 308.280858 -401.858031) (xy 308.258201 -401.808421)
			(xy 308.242836 -401.756091) (xy 308.235074 -401.702107) (xy 308.234588 -401.674838) (xy 307.797708 -401.674838)
			(xy 307.797222 -401.702089) (xy 307.789466 -401.756037) (xy 307.774111 -401.808332) (xy 307.751469 -401.857909)
			(xy 307.722003 -401.903759) (xy 307.686312 -401.94495) (xy 307.645121 -401.980641) (xy 307.599271 -402.010107)
			(xy 307.549694 -402.032749) (xy 307.497399 -402.048104) (xy 307.443451 -402.05586) (xy 307.388949 -402.05586)
			(xy 307.335001 -402.048104) (xy 307.282706 -402.032749) (xy 307.233129 -402.010107) (xy 307.187279 -401.980641)
			(xy 307.146088 -401.94495) (xy 307.110397 -401.903759) (xy 307.080931 -401.857909) (xy 307.058289 -401.808332)
			(xy 307.042934 -401.756037) (xy 307.035178 -401.702089) (xy 307.034692 -401.674838) (xy 306.597812 -401.674838)
			(xy 306.597326 -401.702089) (xy 306.58957 -401.756037) (xy 306.574215 -401.808332) (xy 306.551573 -401.857909)
			(xy 306.522107 -401.903759) (xy 306.486416 -401.94495) (xy 306.445225 -401.980641) (xy 306.399375 -402.010107)
			(xy 306.349798 -402.032749) (xy 306.297503 -402.048104) (xy 306.243555 -402.05586) (xy 306.189053 -402.05586)
			(xy 306.135105 -402.048104) (xy 306.08281 -402.032749) (xy 306.033233 -402.010107) (xy 305.987383 -401.980641)
			(xy 305.946192 -401.94495) (xy 305.910501 -401.903759) (xy 305.881035 -401.857909) (xy 305.858393 -401.808332)
			(xy 305.843038 -401.756037) (xy 305.835282 -401.702089) (xy 305.834796 -401.674838) (xy 305.397916 -401.674838)
			(xy 305.39743 -401.702107) (xy 305.389668 -401.756091) (xy 305.374303 -401.808421) (xy 305.351646 -401.858031)
			(xy 305.32216 -401.903912) (xy 305.286445 -401.945129) (xy 305.245228 -401.980844) (xy 305.199347 -402.01033)
			(xy 305.149737 -402.032987) (xy 305.097407 -402.048352) (xy 305.043423 -402.056114) (xy 304.988885 -402.056114)
			(xy 304.934901 -402.048352) (xy 304.882571 -402.032987) (xy 304.832961 -402.01033) (xy 304.78708 -401.980844)
			(xy 304.745863 -401.945129) (xy 304.710148 -401.903912) (xy 304.680662 -401.858031) (xy 304.658005 -401.808421)
			(xy 304.64264 -401.756091) (xy 304.634878 -401.702107) (xy 304.634392 -401.674838) (xy 304.19802 -401.674838)
			(xy 304.197534 -401.702107) (xy 304.189772 -401.756091) (xy 304.174407 -401.808421) (xy 304.15175 -401.858031)
			(xy 304.122264 -401.903912) (xy 304.086549 -401.945129) (xy 304.045332 -401.980844) (xy 303.999451 -402.01033)
			(xy 303.949841 -402.032987) (xy 303.897511 -402.048352) (xy 303.843527 -402.056114) (xy 303.788989 -402.056114)
			(xy 303.735005 -402.048352) (xy 303.682675 -402.032987) (xy 303.633065 -402.01033) (xy 303.587184 -401.980844)
			(xy 303.545967 -401.945129) (xy 303.510252 -401.903912) (xy 303.480766 -401.858031) (xy 303.458109 -401.808421)
			(xy 303.442744 -401.756091) (xy 303.434982 -401.702107) (xy 303.434496 -401.674838) (xy 280.68524 -401.674838)
			(xy 280.68524 -404.215092) (xy 283.62402 -404.215092) (xy 283.62402 -403.351492) (xy 283.624506 -403.324223)
			(xy 283.632268 -403.270239) (xy 283.647633 -403.217909) (xy 283.67029 -403.168299) (xy 283.699776 -403.122418)
			(xy 283.735491 -403.081201) (xy 283.776708 -403.045486) (xy 283.822589 -403.016) (xy 283.872199 -402.993343)
			(xy 283.924529 -402.977978) (xy 283.978513 -402.970216) (xy 284.033051 -402.970216) (xy 284.087035 -402.977978)
			(xy 284.139365 -402.993343) (xy 284.188975 -403.016) (xy 284.203533 -403.025356) (xy 289.919156 -403.025356)
			(xy 289.919156 -402.161756) (xy 289.919642 -402.134487) (xy 289.927404 -402.080503) (xy 289.942769 -402.028173)
			(xy 289.965426 -401.978563) (xy 289.994912 -401.932682) (xy 290.030627 -401.891465) (xy 290.071844 -401.85575)
			(xy 290.117725 -401.826264) (xy 290.167335 -401.803607) (xy 290.219665 -401.788242) (xy 290.273649 -401.78048)
			(xy 290.328187 -401.78048) (xy 290.382171 -401.788242) (xy 290.434501 -401.803607) (xy 290.484111 -401.826264)
			(xy 290.529992 -401.85575) (xy 290.571209 -401.891465) (xy 290.606924 -401.932682) (xy 290.63641 -401.978563)
			(xy 290.659067 -402.028173) (xy 290.674432 -402.080503) (xy 290.682194 -402.134487) (xy 290.68268 -402.161756)
			(xy 290.68268 -403.025356) (xy 290.682194 -403.052625) (xy 290.674432 -403.106609) (xy 290.659067 -403.158939)
			(xy 290.63641 -403.208549) (xy 290.606924 -403.25443) (xy 290.571209 -403.295647) (xy 290.529992 -403.331362)
			(xy 290.484111 -403.360848) (xy 290.434501 -403.383505) (xy 290.382171 -403.39887) (xy 290.328187 -403.406632)
			(xy 290.273649 -403.406632) (xy 290.219665 -403.39887) (xy 290.167335 -403.383505) (xy 290.117725 -403.360848)
			(xy 290.071844 -403.331362) (xy 290.030627 -403.295647) (xy 289.994912 -403.25443) (xy 289.965426 -403.208549)
			(xy 289.942769 -403.158939) (xy 289.927404 -403.106609) (xy 289.919642 -403.052625) (xy 289.919156 -403.025356)
			(xy 284.203533 -403.025356) (xy 284.234856 -403.045486) (xy 284.276073 -403.081201) (xy 284.311788 -403.122418)
			(xy 284.341274 -403.168299) (xy 284.363931 -403.217909) (xy 284.379296 -403.270239) (xy 284.387058 -403.324223)
			(xy 284.387544 -403.351492) (xy 284.387544 -404.215092) (xy 284.387058 -404.242361) (xy 284.379296 -404.296345)
			(xy 284.363931 -404.348675) (xy 284.341274 -404.398285) (xy 284.311788 -404.444166) (xy 284.276073 -404.485383)
			(xy 284.234856 -404.521098) (xy 284.188975 -404.550584) (xy 284.139365 -404.573241) (xy 284.087035 -404.588606)
			(xy 284.033051 -404.596368) (xy 283.978513 -404.596368) (xy 283.924529 -404.588606) (xy 283.872199 -404.573241)
			(xy 283.822589 -404.550584) (xy 283.776708 -404.521098) (xy 283.735491 -404.485383) (xy 283.699776 -404.444166)
			(xy 283.67029 -404.398285) (xy 283.647633 -404.348675) (xy 283.632268 -404.296345) (xy 283.624506 -404.242361)
			(xy 283.62402 -404.215092) (xy 280.68524 -404.215092) (xy 280.68524 -407.583953) (xy 282.536071 -407.583953)
			(xy 282.536071 -407.529447) (xy 282.543829 -407.475495) (xy 282.559186 -407.423196) (xy 282.581831 -407.373615)
			(xy 282.611301 -407.327762) (xy 282.646997 -407.28657) (xy 282.688193 -407.250878) (xy 282.734049 -407.221412)
			(xy 282.783632 -407.198773) (xy 282.835932 -407.183421) (xy 282.889885 -407.175669) (xy 282.917138 -407.175208)
			(xy 283.780738 -407.175208) (xy 283.807989 -407.175664) (xy 283.861934 -407.183426) (xy 283.914227 -407.198785)
			(xy 283.963801 -407.221429) (xy 284.009649 -407.250898) (xy 284.050836 -407.286591) (xy 284.086525 -407.327782)
			(xy 284.115989 -407.373632) (xy 284.134525 -407.414222) (xy 287.101788 -407.414222) (xy 287.101788 -406.550622)
			(xy 287.102274 -406.523371) (xy 287.11003 -406.469423) (xy 287.125385 -406.417128) (xy 287.148027 -406.367551)
			(xy 287.177493 -406.321701) (xy 287.213184 -406.28051) (xy 287.254375 -406.244819) (xy 287.300225 -406.215353)
			(xy 287.349802 -406.192711) (xy 287.402097 -406.177356) (xy 287.456045 -406.1696) (xy 287.510547 -406.1696)
			(xy 287.564495 -406.177356) (xy 287.61679 -406.192711) (xy 287.666367 -406.215353) (xy 287.712217 -406.244819)
			(xy 287.753408 -406.28051) (xy 287.789099 -406.321701) (xy 287.818565 -406.367551) (xy 287.841207 -406.417128)
			(xy 287.856562 -406.469423) (xy 287.864318 -406.523371) (xy 287.864804 -406.550622) (xy 287.864804 -407.414222)
			(xy 287.864318 -407.441473) (xy 287.856562 -407.495421) (xy 287.841207 -407.547716) (xy 287.818565 -407.597293)
			(xy 287.789099 -407.643143) (xy 287.753408 -407.684334) (xy 287.712217 -407.720025) (xy 287.666367 -407.749491)
			(xy 287.61679 -407.772133) (xy 287.564495 -407.787488) (xy 287.510547 -407.795244) (xy 287.456045 -407.795244)
			(xy 287.402097 -407.787488) (xy 287.349802 -407.772133) (xy 287.300225 -407.749491) (xy 287.254375 -407.720025)
			(xy 287.213184 -407.684334) (xy 287.177493 -407.643143) (xy 287.148027 -407.597293) (xy 287.125385 -407.547716)
			(xy 287.11003 -407.495421) (xy 287.102274 -407.441473) (xy 287.101788 -407.414222) (xy 284.134525 -407.414222)
			(xy 284.138629 -407.423209) (xy 284.153982 -407.475503) (xy 284.161738 -407.529449) (xy 284.161738 -407.583951)
			(xy 284.153982 -407.637897) (xy 284.138629 -407.690191) (xy 284.115989 -407.739768) (xy 284.086525 -407.785619)
			(xy 284.050836 -407.826809) (xy 284.009649 -407.862502) (xy 283.963801 -407.891971) (xy 283.914227 -407.914615)
			(xy 283.861934 -407.929974) (xy 283.807989 -407.937736) (xy 283.780738 -407.938224) (xy 282.917138 -407.938224)
			(xy 282.889885 -407.937731) (xy 282.835932 -407.929979) (xy 282.783632 -407.914627) (xy 282.734049 -407.891988)
			(xy 282.688193 -407.862522) (xy 282.646997 -407.82683) (xy 282.611301 -407.785638) (xy 282.581831 -407.739785)
			(xy 282.559186 -407.690204) (xy 282.543829 -407.637905) (xy 282.536071 -407.583953) (xy 280.68524 -407.583953)
			(xy 280.68524 -409.10256) (xy 280.684766 -409.12751) (xy 280.676946 -409.176794) (xy 280.661524 -409.224251)
			(xy 280.638877 -409.268716) (xy 280.609563 -409.309098) (xy 280.592276 -409.327096) (xy 276.749256 -413.170116)
			(xy 293.568894 -413.170116) (xy 293.572866 -412.991873) (xy 293.584774 -412.813984) (xy 293.604595 -412.636802)
			(xy 293.632289 -412.460678) (xy 293.667801 -412.285963) (xy 293.711061 -412.113004) (xy 293.761983 -411.942143)
			(xy 293.820466 -411.773721) (xy 293.886393 -411.608071) (xy 293.959634 -411.445522) (xy 294.040044 -411.286397)
			(xy 294.127462 -411.131012) (xy 294.221715 -410.979676) (xy 294.322616 -410.832688) (xy 294.429965 -410.690341)
			(xy 294.543548 -410.552918) (xy 294.663141 -410.420691) (xy 294.788505 -410.293922) (xy 294.919392 -410.172864)
			(xy 295.055541 -410.057757) (xy 295.196683 -409.948829) (xy 295.342538 -409.846297) (xy 295.492815 -409.750363)
			(xy 295.647216 -409.66122) (xy 295.805435 -409.579043) (xy 295.967158 -409.503995) (xy 296.132063 -409.436227)
			(xy 296.299824 -409.375871) (xy 296.470107 -409.323049) (xy 296.642574 -409.277865) (xy 296.816882 -409.240408)
			(xy 296.992686 -409.210754) (xy 297.169636 -409.188961) (xy 297.347382 -409.175071) (xy 297.525569 -409.169114)
			(xy 297.703846 -409.1711) (xy 297.881857 -409.181026) (xy 298.059249 -409.198872) (xy 298.235669 -409.224602)
			(xy 298.410769 -409.258166) (xy 298.5842 -409.299496) (xy 298.755617 -409.348512) (xy 298.92468 -409.405114)
			(xy 299.091055 -409.469192) (xy 299.254409 -409.540618) (xy 299.41442 -409.61925) (xy 299.570769 -409.704931)
			(xy 299.723146 -409.797493) (xy 299.871249 -409.89675) (xy 300.014783 -410.002507) (xy 300.153463 -410.114552)
			(xy 300.287014 -410.232664) (xy 300.415171 -410.356608) (xy 300.53768 -410.486138) (xy 300.654297 -410.620997)
			(xy 300.76479 -410.760917) (xy 300.868941 -410.90562) (xy 300.966543 -411.054819) (xy 301.057401 -411.208218)
			(xy 301.141335 -411.365512) (xy 301.21818 -411.526388) (xy 301.287781 -411.690529) (xy 301.350002 -411.857606)
			(xy 301.404718 -412.02729) (xy 301.45182 -412.199243) (xy 301.491216 -412.373123) (xy 301.522827 -412.548586)
			(xy 301.546591 -412.725282) (xy 301.559858 -412.873752) (xy 303.412875 -412.873752) (xy 303.412875 -412.819248)
			(xy 303.420632 -412.7653) (xy 303.435988 -412.713004) (xy 303.458629 -412.663426) (xy 303.488096 -412.617575)
			(xy 303.523789 -412.576384) (xy 303.56498 -412.540693) (xy 303.610831 -412.511226) (xy 303.66041 -412.488585)
			(xy 303.712706 -412.473231) (xy 303.766654 -412.465475) (xy 303.793906 -412.465012) (xy 304.657506 -412.465012)
			(xy 304.684758 -412.465458) (xy 304.738708 -412.473216) (xy 304.791005 -412.488572) (xy 304.840584 -412.511215)
			(xy 304.886436 -412.540683) (xy 304.927628 -412.576376) (xy 304.963321 -412.617569) (xy 304.992788 -412.663421)
			(xy 305.01543 -412.713001) (xy 305.030785 -412.765298) (xy 305.038542 -412.819248) (xy 305.038542 -412.873752)
			(xy 305.038542 -412.873754) (xy 306.476075 -412.873754) (xy 306.476075 -412.819246) (xy 306.483833 -412.765294)
			(xy 306.499191 -412.712996) (xy 306.521835 -412.663415) (xy 306.551306 -412.617562) (xy 306.587003 -412.57637)
			(xy 306.628199 -412.540679) (xy 306.674055 -412.511213) (xy 306.723639 -412.488575) (xy 306.775939 -412.473223)
			(xy 306.829892 -412.465472) (xy 306.857146 -412.465012) (xy 307.720746 -412.465012) (xy 307.747997 -412.465461)
			(xy 307.801942 -412.473223) (xy 307.854234 -412.488583) (xy 307.903808 -412.511228) (xy 307.949655 -412.540697)
			(xy 307.990842 -412.576391) (xy 308.02653 -412.617582) (xy 308.055994 -412.663432) (xy 308.078633 -412.713009)
			(xy 308.093987 -412.765303) (xy 308.101742 -412.819249) (xy 308.101742 -412.873749) (xy 309.539398 -412.873749)
			(xy 309.539398 -412.819251) (xy 309.547154 -412.765307) (xy 309.562508 -412.713016) (xy 309.585146 -412.663443)
			(xy 309.61461 -412.617596) (xy 309.650298 -412.576408) (xy 309.691484 -412.540718) (xy 309.73733 -412.511253)
			(xy 309.786903 -412.488612) (xy 309.839194 -412.473257) (xy 309.893137 -412.465499) (xy 309.920386 -412.465012)
			(xy 310.783986 -412.465012) (xy 310.811241 -412.465434) (xy 310.865196 -412.47319) (xy 310.917499 -412.488545)
			(xy 310.967083 -412.511188) (xy 311.012941 -412.540657) (xy 311.054137 -412.576353) (xy 311.089834 -412.617548)
			(xy 311.119305 -412.663405) (xy 311.14195 -412.712988) (xy 311.157307 -412.76529) (xy 311.165065 -412.819245)
			(xy 311.165065 -412.873753) (xy 312.602575 -412.873753) (xy 312.602575 -412.819247) (xy 312.610333 -412.765297)
			(xy 312.625689 -412.713) (xy 312.648332 -412.663421) (xy 312.677801 -412.617569) (xy 312.713496 -412.576377)
			(xy 312.754689 -412.540686) (xy 312.800543 -412.51122) (xy 312.850124 -412.48858) (xy 312.902422 -412.473227)
			(xy 312.956373 -412.465474) (xy 312.983626 -412.465012) (xy 313.847226 -412.465012) (xy 313.874477 -412.46546)
			(xy 313.928425 -412.47322) (xy 313.98072 -412.488578) (xy 314.030296 -412.511222) (xy 314.076146 -412.54069)
			(xy 314.117335 -412.576383) (xy 314.153026 -412.617575) (xy 314.182491 -412.663427) (xy 314.205131 -412.713005)
			(xy 314.220486 -412.7653) (xy 314.228242 -412.819249) (xy 314.228242 -412.873748) (xy 315.665898 -412.873748)
			(xy 315.665898 -412.819252) (xy 315.673653 -412.76531) (xy 315.689006 -412.713021) (xy 315.711643 -412.663448)
			(xy 315.741105 -412.617602) (xy 315.776791 -412.576415) (xy 315.817975 -412.540725) (xy 315.863818 -412.51126)
			(xy 315.913389 -412.488618) (xy 315.965677 -412.473261) (xy 316.019618 -412.465501) (xy 316.046866 -412.465012)
			(xy 316.910466 -412.465012) (xy 316.937722 -412.465433) (xy 316.991679 -412.473186) (xy 317.043984 -412.48854)
			(xy 317.093571 -412.511182) (xy 317.139431 -412.54065) (xy 317.18063 -412.576346) (xy 317.216329 -412.617542)
			(xy 317.245802 -412.663399) (xy 317.268448 -412.712984) (xy 317.283807 -412.765287) (xy 317.291565 -412.819244)
			(xy 317.291565 -412.873752) (xy 318.729075 -412.873752) (xy 318.729075 -412.819248) (xy 318.736832 -412.7653)
			(xy 318.752188 -412.713004) (xy 318.774829 -412.663426) (xy 318.804296 -412.617575) (xy 318.839989 -412.576384)
			(xy 318.88118 -412.540693) (xy 318.927031 -412.511226) (xy 318.97661 -412.488585) (xy 319.028906 -412.473231)
			(xy 319.082854 -412.465475) (xy 319.110106 -412.465012) (xy 319.973706 -412.465012) (xy 320.000958 -412.465458)
			(xy 320.054908 -412.473216) (xy 320.107205 -412.488572) (xy 320.156784 -412.511215) (xy 320.202636 -412.540683)
			(xy 320.243828 -412.576376) (xy 320.279521 -412.617569) (xy 320.308988 -412.663421) (xy 320.33163 -412.713001)
			(xy 320.346985 -412.765298) (xy 320.354742 -412.819248) (xy 320.354742 -412.873752) (xy 320.354742 -412.873754)
			(xy 321.792275 -412.873754) (xy 321.792275 -412.819246) (xy 321.800033 -412.765294) (xy 321.815391 -412.712996)
			(xy 321.838035 -412.663415) (xy 321.867506 -412.617562) (xy 321.903203 -412.57637) (xy 321.944399 -412.540679)
			(xy 321.990255 -412.511213) (xy 322.039839 -412.488575) (xy 322.092139 -412.473223) (xy 322.146092 -412.465472)
			(xy 322.173346 -412.465012) (xy 323.036946 -412.465012) (xy 323.064197 -412.465461) (xy 323.118142 -412.473223)
			(xy 323.170434 -412.488583) (xy 323.220008 -412.511228) (xy 323.265855 -412.540697) (xy 323.307042 -412.576391)
			(xy 323.34273 -412.617582) (xy 323.372194 -412.663432) (xy 323.394833 -412.713009) (xy 323.410187 -412.765303)
			(xy 323.417942 -412.819249) (xy 323.417942 -412.873749) (xy 324.855598 -412.873749) (xy 324.855598 -412.819251)
			(xy 324.863354 -412.765307) (xy 324.878708 -412.713016) (xy 324.901346 -412.663443) (xy 324.93081 -412.617596)
			(xy 324.966498 -412.576408) (xy 325.007684 -412.540718) (xy 325.05353 -412.511253) (xy 325.103103 -412.488612)
			(xy 325.155394 -412.473257) (xy 325.209337 -412.465499) (xy 325.236586 -412.465012) (xy 326.100186 -412.465012)
			(xy 326.127441 -412.465434) (xy 326.181396 -412.47319) (xy 326.233699 -412.488545) (xy 326.283283 -412.511188)
			(xy 326.329141 -412.540657) (xy 326.370337 -412.576353) (xy 326.406034 -412.617548) (xy 326.435505 -412.663405)
			(xy 326.45815 -412.712988) (xy 326.473507 -412.76529) (xy 326.481265 -412.819245) (xy 326.481265 -412.873753)
			(xy 327.918775 -412.873753) (xy 327.918775 -412.819247) (xy 327.926533 -412.765297) (xy 327.941889 -412.713)
			(xy 327.964532 -412.663421) (xy 327.994001 -412.617569) (xy 328.029696 -412.576377) (xy 328.070889 -412.540686)
			(xy 328.116743 -412.51122) (xy 328.166324 -412.48858) (xy 328.218622 -412.473227) (xy 328.272573 -412.465474)
			(xy 328.299826 -412.465012) (xy 329.163426 -412.465012) (xy 329.190677 -412.46546) (xy 329.244625 -412.47322)
			(xy 329.29692 -412.488578) (xy 329.346496 -412.511222) (xy 329.392346 -412.54069) (xy 329.433535 -412.576383)
			(xy 329.469226 -412.617575) (xy 329.498691 -412.663427) (xy 329.521331 -412.713005) (xy 329.536686 -412.7653)
			(xy 329.544442 -412.819249) (xy 329.544442 -412.873748) (xy 330.982098 -412.873748) (xy 330.982098 -412.819252)
			(xy 330.989853 -412.76531) (xy 331.005206 -412.713021) (xy 331.027843 -412.663448) (xy 331.057305 -412.617602)
			(xy 331.092991 -412.576415) (xy 331.134175 -412.540725) (xy 331.180018 -412.51126) (xy 331.229589 -412.488618)
			(xy 331.281877 -412.473261) (xy 331.335818 -412.465501) (xy 331.363066 -412.465012) (xy 332.226666 -412.465012)
			(xy 332.253922 -412.465433) (xy 332.307879 -412.473186) (xy 332.360184 -412.48854) (xy 332.409771 -412.511182)
			(xy 332.455631 -412.54065) (xy 332.49683 -412.576346) (xy 332.532529 -412.617542) (xy 332.562002 -412.663399)
			(xy 332.584648 -412.712984) (xy 332.600007 -412.765287) (xy 332.607765 -412.819244) (xy 332.607765 -412.873752)
			(xy 334.045275 -412.873752) (xy 334.045275 -412.819248) (xy 334.053032 -412.7653) (xy 334.068388 -412.713004)
			(xy 334.091029 -412.663426) (xy 334.120496 -412.617575) (xy 334.156189 -412.576384) (xy 334.19738 -412.540693)
			(xy 334.243231 -412.511226) (xy 334.29281 -412.488585) (xy 334.345106 -412.473231) (xy 334.399054 -412.465475)
			(xy 334.426306 -412.465012) (xy 335.289906 -412.465012) (xy 335.317158 -412.465458) (xy 335.371108 -412.473216)
			(xy 335.423405 -412.488572) (xy 335.472984 -412.511215) (xy 335.518836 -412.540683) (xy 335.560028 -412.576376)
			(xy 335.595721 -412.617569) (xy 335.625188 -412.663421) (xy 335.64783 -412.713001) (xy 335.663185 -412.765298)
			(xy 335.670942 -412.819248) (xy 335.670942 -412.873752) (xy 335.670942 -412.873754) (xy 337.108475 -412.873754)
			(xy 337.108475 -412.819246) (xy 337.116233 -412.765294) (xy 337.131591 -412.712996) (xy 337.154235 -412.663415)
			(xy 337.183706 -412.617562) (xy 337.219403 -412.57637) (xy 337.260599 -412.540679) (xy 337.306455 -412.511213)
			(xy 337.356039 -412.488575) (xy 337.408339 -412.473223) (xy 337.462292 -412.465472) (xy 337.489546 -412.465012)
			(xy 338.353146 -412.465012) (xy 338.380397 -412.465461) (xy 338.434342 -412.473223) (xy 338.486634 -412.488583)
			(xy 338.536208 -412.511228) (xy 338.582055 -412.540697) (xy 338.623242 -412.576391) (xy 338.65893 -412.617582)
			(xy 338.688394 -412.663432) (xy 338.711033 -412.713009) (xy 338.726387 -412.765303) (xy 338.734142 -412.819249)
			(xy 338.734142 -412.873749) (xy 340.171798 -412.873749) (xy 340.171798 -412.819251) (xy 340.179554 -412.765307)
			(xy 340.194908 -412.713016) (xy 340.217546 -412.663443) (xy 340.24701 -412.617596) (xy 340.282698 -412.576408)
			(xy 340.323884 -412.540718) (xy 340.36973 -412.511253) (xy 340.419303 -412.488612) (xy 340.471594 -412.473257)
			(xy 340.525537 -412.465499) (xy 340.552786 -412.465012) (xy 341.416386 -412.465012) (xy 341.443641 -412.465434)
			(xy 341.497596 -412.47319) (xy 341.549899 -412.488545) (xy 341.599483 -412.511188) (xy 341.645341 -412.540657)
			(xy 341.686537 -412.576353) (xy 341.722234 -412.617548) (xy 341.751705 -412.663405) (xy 341.77435 -412.712988)
			(xy 341.789707 -412.76529) (xy 341.797465 -412.819245) (xy 341.797465 -412.873753) (xy 343.234975 -412.873753)
			(xy 343.234975 -412.819247) (xy 343.242733 -412.765297) (xy 343.258089 -412.713) (xy 343.280732 -412.663421)
			(xy 343.310201 -412.617569) (xy 343.345896 -412.576377) (xy 343.387089 -412.540686) (xy 343.432943 -412.51122)
			(xy 343.482524 -412.48858) (xy 343.534822 -412.473227) (xy 343.588773 -412.465474) (xy 343.616026 -412.465012)
			(xy 344.479626 -412.465012) (xy 344.506877 -412.46546) (xy 344.560825 -412.47322) (xy 344.61312 -412.488578)
			(xy 344.662696 -412.511222) (xy 344.708546 -412.54069) (xy 344.749735 -412.576383) (xy 344.785426 -412.617575)
			(xy 344.814891 -412.663427) (xy 344.837531 -412.713005) (xy 344.852886 -412.7653) (xy 344.860642 -412.819249)
			(xy 344.860642 -412.873748) (xy 346.298298 -412.873748) (xy 346.298298 -412.819252) (xy 346.306053 -412.76531)
			(xy 346.321406 -412.713021) (xy 346.344043 -412.663448) (xy 346.373505 -412.617602) (xy 346.409191 -412.576415)
			(xy 346.450375 -412.540725) (xy 346.496218 -412.51126) (xy 346.545789 -412.488618) (xy 346.598077 -412.473261)
			(xy 346.652018 -412.465501) (xy 346.679266 -412.465012) (xy 347.542866 -412.465012) (xy 347.570122 -412.465433)
			(xy 347.624079 -412.473186) (xy 347.676384 -412.48854) (xy 347.725971 -412.511182) (xy 347.771831 -412.54065)
			(xy 347.81303 -412.576346) (xy 347.848729 -412.617542) (xy 347.878202 -412.663399) (xy 347.900848 -412.712984)
			(xy 347.916207 -412.765287) (xy 347.923965 -412.819244) (xy 347.923965 -412.873752) (xy 349.361475 -412.873752)
			(xy 349.361475 -412.819248) (xy 349.369232 -412.7653) (xy 349.384588 -412.713004) (xy 349.407229 -412.663426)
			(xy 349.436696 -412.617575) (xy 349.472389 -412.576384) (xy 349.51358 -412.540693) (xy 349.559431 -412.511226)
			(xy 349.60901 -412.488585) (xy 349.661306 -412.473231) (xy 349.715254 -412.465475) (xy 349.742506 -412.465012)
			(xy 350.606106 -412.465012) (xy 350.633358 -412.465458) (xy 350.687308 -412.473216) (xy 350.739605 -412.488572)
			(xy 350.789184 -412.511215) (xy 350.835036 -412.540683) (xy 350.876228 -412.576376) (xy 350.911921 -412.617569)
			(xy 350.941388 -412.663421) (xy 350.96403 -412.713001) (xy 350.979385 -412.765298) (xy 350.987142 -412.819248)
			(xy 350.987142 -412.873752) (xy 370.513075 -412.873752) (xy 370.513075 -412.819248) (xy 370.520832 -412.7653)
			(xy 370.536187 -412.713005) (xy 370.558829 -412.663427) (xy 370.588295 -412.617576) (xy 370.623987 -412.576386)
			(xy 370.665178 -412.540694) (xy 370.711029 -412.511228) (xy 370.760607 -412.488587) (xy 370.812902 -412.473231)
			(xy 370.86685 -412.465475) (xy 370.894102 -412.465012) (xy 371.757702 -412.465012) (xy 371.784955 -412.465458)
			(xy 371.838905 -412.473215) (xy 371.891202 -412.488571) (xy 371.940782 -412.511214) (xy 371.986634 -412.540682)
			(xy 372.027826 -412.576375) (xy 372.06352 -412.617567) (xy 372.092987 -412.66342) (xy 372.115629 -412.713)
			(xy 372.130985 -412.765297) (xy 372.138742 -412.819247) (xy 372.138742 -412.873753) (xy 373.576275 -412.873753)
			(xy 373.576275 -412.819247) (xy 373.584033 -412.765295) (xy 373.59939 -412.712996) (xy 373.622035 -412.663416)
			(xy 373.651505 -412.617563) (xy 373.687201 -412.576372) (xy 373.728397 -412.54068) (xy 373.774253 -412.511215)
			(xy 373.823836 -412.488576) (xy 373.876136 -412.473224) (xy 373.930089 -412.465472) (xy 373.957342 -412.465012)
			(xy 374.820942 -412.465012) (xy 374.848193 -412.465461) (xy 374.902139 -412.473222) (xy 374.954431 -412.488582)
			(xy 375.004006 -412.511227) (xy 375.049853 -412.540696) (xy 375.091041 -412.576389) (xy 375.126729 -412.61758)
			(xy 375.156193 -412.663431) (xy 375.178833 -412.713008) (xy 375.194186 -412.765302) (xy 375.201942 -412.819249)
			(xy 375.201942 -412.873749) (xy 376.639598 -412.873749) (xy 376.639598 -412.819251) (xy 376.647354 -412.765308)
			(xy 376.662707 -412.713017) (xy 376.685346 -412.663444) (xy 376.714809 -412.617597) (xy 376.750497 -412.576409)
			(xy 376.791682 -412.54072) (xy 376.837528 -412.511254) (xy 376.8871 -412.488613) (xy 376.93939 -412.473258)
			(xy 376.993333 -412.465499) (xy 377.020582 -412.465012) (xy 377.884182 -412.465012) (xy 377.911437 -412.465434)
			(xy 377.965393 -412.473189) (xy 378.017696 -412.488544) (xy 378.067281 -412.511187) (xy 378.113139 -412.540656)
			(xy 378.154336 -412.576352) (xy 378.190033 -412.617547) (xy 378.219504 -412.663403) (xy 378.242149 -412.712987)
			(xy 378.257507 -412.765289) (xy 378.265265 -412.819245) (xy 378.265265 -412.873752) (xy 379.702775 -412.873752)
			(xy 379.702775 -412.819248) (xy 379.710532 -412.765298) (xy 379.725889 -412.713001) (xy 379.748532 -412.663422)
			(xy 379.778 -412.61757) (xy 379.813694 -412.576379) (xy 379.854888 -412.540687) (xy 379.900741 -412.511221)
			(xy 379.950321 -412.488581) (xy 380.002619 -412.473228) (xy 380.05657 -412.465474) (xy 380.083822 -412.465012)
			(xy 380.947422 -412.465012) (xy 380.974674 -412.465459) (xy 381.028622 -412.473219) (xy 381.080917 -412.488577)
			(xy 381.130494 -412.51122) (xy 381.176344 -412.540689) (xy 381.217534 -412.576382) (xy 381.253225 -412.617574)
			(xy 381.28269 -412.663426) (xy 381.305331 -412.713004) (xy 381.320686 -412.7653) (xy 381.328442 -412.819248)
			(xy 381.328442 -412.873748) (xy 382.766098 -412.873748) (xy 382.766098 -412.819252) (xy 382.773853 -412.76531)
			(xy 382.789206 -412.713022) (xy 382.811843 -412.663449) (xy 382.841304 -412.617603) (xy 382.876989 -412.576416)
			(xy 382.918173 -412.540727) (xy 382.964016 -412.511261) (xy 383.013586 -412.488619) (xy 383.065873 -412.473261)
			(xy 383.119814 -412.465501) (xy 383.147062 -412.465012) (xy 384.010662 -412.465012) (xy 384.037918 -412.465432)
			(xy 384.091876 -412.473185) (xy 384.144181 -412.488539) (xy 384.193769 -412.51118) (xy 384.239629 -412.540649)
			(xy 384.280829 -412.576345) (xy 384.316528 -412.61754) (xy 384.346001 -412.663398) (xy 384.368648 -412.712983)
			(xy 384.384007 -412.765287) (xy 384.391765 -412.819244) (xy 384.391765 -412.873752) (xy 385.829275 -412.873752)
			(xy 385.829275 -412.819248) (xy 385.837032 -412.7653) (xy 385.852387 -412.713005) (xy 385.875029 -412.663427)
			(xy 385.904495 -412.617576) (xy 385.940187 -412.576386) (xy 385.981378 -412.540694) (xy 386.027229 -412.511228)
			(xy 386.076807 -412.488587) (xy 386.129102 -412.473231) (xy 386.18305 -412.465475) (xy 386.210302 -412.465012)
			(xy 387.073902 -412.465012) (xy 387.101155 -412.465458) (xy 387.155105 -412.473215) (xy 387.207402 -412.488571)
			(xy 387.256982 -412.511214) (xy 387.302834 -412.540682) (xy 387.344026 -412.576375) (xy 387.37972 -412.617567)
			(xy 387.409187 -412.66342) (xy 387.431829 -412.713) (xy 387.447185 -412.765297) (xy 387.454942 -412.819247)
			(xy 387.454942 -412.873753) (xy 388.892475 -412.873753) (xy 388.892475 -412.819247) (xy 388.900233 -412.765295)
			(xy 388.91559 -412.712996) (xy 388.938235 -412.663416) (xy 388.967705 -412.617563) (xy 389.003401 -412.576372)
			(xy 389.044597 -412.54068) (xy 389.090453 -412.511215) (xy 389.140036 -412.488576) (xy 389.192336 -412.473224)
			(xy 389.246289 -412.465472) (xy 389.273542 -412.465012) (xy 390.137142 -412.465012) (xy 390.164393 -412.465461)
			(xy 390.218339 -412.473222) (xy 390.270631 -412.488582) (xy 390.320206 -412.511227) (xy 390.366053 -412.540696)
			(xy 390.407241 -412.576389) (xy 390.442929 -412.61758) (xy 390.472393 -412.663431) (xy 390.495033 -412.713008)
			(xy 390.510386 -412.765302) (xy 390.518142 -412.819249) (xy 390.518142 -412.873749) (xy 391.955798 -412.873749)
			(xy 391.955798 -412.819251) (xy 391.963554 -412.765308) (xy 391.978907 -412.713017) (xy 392.001546 -412.663444)
			(xy 392.031009 -412.617597) (xy 392.066697 -412.576409) (xy 392.107882 -412.54072) (xy 392.153728 -412.511254)
			(xy 392.2033 -412.488613) (xy 392.25559 -412.473258) (xy 392.309533 -412.465499) (xy 392.336782 -412.465012)
			(xy 393.200382 -412.465012) (xy 393.227637 -412.465434) (xy 393.281593 -412.473189) (xy 393.333896 -412.488544)
			(xy 393.383481 -412.511187) (xy 393.429339 -412.540656) (xy 393.470536 -412.576352) (xy 393.506233 -412.617547)
			(xy 393.535704 -412.663403) (xy 393.558349 -412.712987) (xy 393.573707 -412.765289) (xy 393.581465 -412.819245)
			(xy 393.581465 -412.873752) (xy 395.018975 -412.873752) (xy 395.018975 -412.819248) (xy 395.026732 -412.765298)
			(xy 395.042089 -412.713001) (xy 395.064732 -412.663422) (xy 395.0942 -412.61757) (xy 395.129894 -412.576379)
			(xy 395.171088 -412.540687) (xy 395.216941 -412.511221) (xy 395.266521 -412.488581) (xy 395.318819 -412.473228)
			(xy 395.37277 -412.465474) (xy 395.400022 -412.465012) (xy 396.263622 -412.465012) (xy 396.290874 -412.465459)
			(xy 396.344822 -412.473219) (xy 396.397117 -412.488577) (xy 396.446694 -412.51122) (xy 396.492544 -412.540689)
			(xy 396.533734 -412.576382) (xy 396.569425 -412.617574) (xy 396.59889 -412.663426) (xy 396.621531 -412.713004)
			(xy 396.636886 -412.7653) (xy 396.644642 -412.819248) (xy 396.644642 -412.873748) (xy 398.082298 -412.873748)
			(xy 398.082298 -412.819252) (xy 398.090053 -412.76531) (xy 398.105406 -412.713022) (xy 398.128043 -412.663449)
			(xy 398.157504 -412.617603) (xy 398.193189 -412.576416) (xy 398.234373 -412.540727) (xy 398.280216 -412.511261)
			(xy 398.329786 -412.488619) (xy 398.382073 -412.473261) (xy 398.436014 -412.465501) (xy 398.463262 -412.465012)
			(xy 399.326862 -412.465012) (xy 399.354118 -412.465432) (xy 399.408076 -412.473185) (xy 399.460381 -412.488539)
			(xy 399.509969 -412.51118) (xy 399.555829 -412.540649) (xy 399.597029 -412.576345) (xy 399.632728 -412.61754)
			(xy 399.662201 -412.663398) (xy 399.684848 -412.712983) (xy 399.700207 -412.765287) (xy 399.707965 -412.819244)
			(xy 399.707965 -412.873752) (xy 401.145475 -412.873752) (xy 401.145475 -412.819248) (xy 401.153232 -412.7653)
			(xy 401.168587 -412.713005) (xy 401.191229 -412.663427) (xy 401.220695 -412.617576) (xy 401.256387 -412.576386)
			(xy 401.297578 -412.540694) (xy 401.343429 -412.511228) (xy 401.393007 -412.488587) (xy 401.445302 -412.473231)
			(xy 401.49925 -412.465475) (xy 401.526502 -412.465012) (xy 402.390102 -412.465012) (xy 402.417355 -412.465458)
			(xy 402.471305 -412.473215) (xy 402.523602 -412.488571) (xy 402.573182 -412.511214) (xy 402.619034 -412.540682)
			(xy 402.660226 -412.576375) (xy 402.69592 -412.617567) (xy 402.725387 -412.66342) (xy 402.748029 -412.713)
			(xy 402.763385 -412.765297) (xy 402.771142 -412.819247) (xy 402.771142 -412.873753) (xy 404.208675 -412.873753)
			(xy 404.208675 -412.819247) (xy 404.216433 -412.765295) (xy 404.23179 -412.712996) (xy 404.254435 -412.663416)
			(xy 404.283905 -412.617563) (xy 404.319601 -412.576372) (xy 404.360797 -412.54068) (xy 404.406653 -412.511215)
			(xy 404.456236 -412.488576) (xy 404.508536 -412.473224) (xy 404.562489 -412.465472) (xy 404.589742 -412.465012)
			(xy 405.453342 -412.465012) (xy 405.480593 -412.465461) (xy 405.534539 -412.473222) (xy 405.586831 -412.488582)
			(xy 405.636406 -412.511227) (xy 405.682253 -412.540696) (xy 405.723441 -412.576389) (xy 405.759129 -412.61758)
			(xy 405.788593 -412.663431) (xy 405.811233 -412.713008) (xy 405.826586 -412.765302) (xy 405.834342 -412.819249)
			(xy 405.834342 -412.873749) (xy 407.271998 -412.873749) (xy 407.271998 -412.819251) (xy 407.279754 -412.765308)
			(xy 407.295107 -412.713017) (xy 407.317746 -412.663444) (xy 407.347209 -412.617597) (xy 407.382897 -412.576409)
			(xy 407.424082 -412.54072) (xy 407.469928 -412.511254) (xy 407.5195 -412.488613) (xy 407.57179 -412.473258)
			(xy 407.625733 -412.465499) (xy 407.652982 -412.465012) (xy 408.516582 -412.465012) (xy 408.543837 -412.465434)
			(xy 408.597793 -412.473189) (xy 408.650096 -412.488544) (xy 408.699681 -412.511187) (xy 408.745539 -412.540656)
			(xy 408.786736 -412.576352) (xy 408.822433 -412.617547) (xy 408.851904 -412.663403) (xy 408.874549 -412.712987)
			(xy 408.889907 -412.765289) (xy 408.897665 -412.819245) (xy 408.897665 -412.873752) (xy 410.335175 -412.873752)
			(xy 410.335175 -412.819248) (xy 410.342932 -412.765298) (xy 410.358289 -412.713001) (xy 410.380932 -412.663422)
			(xy 410.4104 -412.61757) (xy 410.446094 -412.576379) (xy 410.487288 -412.540687) (xy 410.533141 -412.511221)
			(xy 410.582721 -412.488581) (xy 410.635019 -412.473228) (xy 410.68897 -412.465474) (xy 410.716222 -412.465012)
			(xy 411.579822 -412.465012) (xy 411.607074 -412.465459) (xy 411.661022 -412.473219) (xy 411.713317 -412.488577)
			(xy 411.762894 -412.51122) (xy 411.808744 -412.540689) (xy 411.849934 -412.576382) (xy 411.885625 -412.617574)
			(xy 411.91509 -412.663426) (xy 411.937731 -412.713004) (xy 411.953086 -412.7653) (xy 411.960842 -412.819248)
			(xy 411.960842 -412.873748) (xy 413.398498 -412.873748) (xy 413.398498 -412.819252) (xy 413.406253 -412.76531)
			(xy 413.421606 -412.713022) (xy 413.444243 -412.663449) (xy 413.473704 -412.617603) (xy 413.509389 -412.576416)
			(xy 413.550573 -412.540727) (xy 413.596416 -412.511261) (xy 413.645986 -412.488619) (xy 413.698273 -412.473261)
			(xy 413.752214 -412.465501) (xy 413.779462 -412.465012) (xy 414.643062 -412.465012) (xy 414.670318 -412.465432)
			(xy 414.724276 -412.473185) (xy 414.776581 -412.488539) (xy 414.826169 -412.51118) (xy 414.872029 -412.540649)
			(xy 414.913229 -412.576345) (xy 414.948928 -412.61754) (xy 414.978401 -412.663398) (xy 415.001048 -412.712983)
			(xy 415.016407 -412.765287) (xy 415.024165 -412.819244) (xy 415.024165 -412.873752) (xy 416.461675 -412.873752)
			(xy 416.461675 -412.819248) (xy 416.469432 -412.7653) (xy 416.484787 -412.713005) (xy 416.507429 -412.663427)
			(xy 416.536895 -412.617576) (xy 416.572587 -412.576386) (xy 416.613778 -412.540694) (xy 416.659629 -412.511228)
			(xy 416.709207 -412.488587) (xy 416.761502 -412.473231) (xy 416.81545 -412.465475) (xy 416.842702 -412.465012)
			(xy 417.706302 -412.465012) (xy 417.733555 -412.465458) (xy 417.787505 -412.473215) (xy 417.839802 -412.488571)
			(xy 417.889382 -412.511214) (xy 417.935234 -412.540682) (xy 417.976426 -412.576375) (xy 418.01212 -412.617567)
			(xy 418.041587 -412.66342) (xy 418.064229 -412.713) (xy 418.079585 -412.765297) (xy 418.087342 -412.819247)
			(xy 418.087342 -412.873753) (xy 418.079585 -412.927703) (xy 418.064229 -412.98) (xy 418.041587 -413.02958)
			(xy 418.01212 -413.075433) (xy 417.976426 -413.116625) (xy 417.935234 -413.152318) (xy 417.90754 -413.170116)
			(xy 422.998658 -413.170116) (xy 423.00263 -412.991873) (xy 423.014538 -412.813984) (xy 423.034359 -412.636802)
			(xy 423.062053 -412.460678) (xy 423.097565 -412.285963) (xy 423.140825 -412.113004) (xy 423.191747 -411.942143)
			(xy 423.25023 -411.773721) (xy 423.316157 -411.608071) (xy 423.389398 -411.445522) (xy 423.469808 -411.286397)
			(xy 423.557226 -411.131012) (xy 423.651479 -410.979676) (xy 423.75238 -410.832688) (xy 423.859729 -410.690341)
			(xy 423.973312 -410.552918) (xy 424.092905 -410.420691) (xy 424.218269 -410.293922) (xy 424.349156 -410.172864)
			(xy 424.485305 -410.057757) (xy 424.626447 -409.948829) (xy 424.772302 -409.846297) (xy 424.922579 -409.750363)
			(xy 425.07698 -409.66122) (xy 425.235199 -409.579043) (xy 425.396922 -409.503995) (xy 425.561827 -409.436227)
			(xy 425.729588 -409.375871) (xy 425.899871 -409.323049) (xy 426.072338 -409.277865) (xy 426.246646 -409.240408)
			(xy 426.42245 -409.210754) (xy 426.5994 -409.188961) (xy 426.777146 -409.175071) (xy 426.955333 -409.169114)
			(xy 427.13361 -409.1711) (xy 427.311621 -409.181026) (xy 427.489013 -409.198872) (xy 427.665433 -409.224602)
			(xy 427.840533 -409.258166) (xy 428.013964 -409.299496) (xy 428.185381 -409.348512) (xy 428.354444 -409.405114)
			(xy 428.520819 -409.469192) (xy 428.684173 -409.540618) (xy 428.844184 -409.61925) (xy 429.000533 -409.704931)
			(xy 429.15291 -409.797493) (xy 429.301013 -409.89675) (xy 429.444547 -410.002507) (xy 429.583227 -410.114552)
			(xy 429.716778 -410.232664) (xy 429.844935 -410.356608) (xy 429.967444 -410.486138) (xy 430.084061 -410.620997)
			(xy 430.194554 -410.760917) (xy 430.298705 -410.90562) (xy 430.396307 -411.054819) (xy 430.487165 -411.208218)
			(xy 430.571099 -411.365512) (xy 430.647944 -411.526388) (xy 430.717545 -411.690529) (xy 430.779766 -411.857606)
			(xy 430.834482 -412.02729) (xy 430.881584 -412.199243) (xy 430.92098 -412.373123) (xy 430.952591 -412.548586)
			(xy 430.976355 -412.725282) (xy 430.992223 -412.902862) (xy 431.000165 -413.080972) (xy 431.000662 -413.170116)
			(xy 431.000165 -413.25926) (xy 430.992223 -413.43737) (xy 430.976355 -413.61495) (xy 430.952591 -413.791646)
			(xy 430.92098 -413.967109) (xy 430.881584 -414.140989) (xy 430.834482 -414.312942) (xy 430.779766 -414.482626)
			(xy 430.717545 -414.649703) (xy 430.647944 -414.813844) (xy 430.571099 -414.97472) (xy 430.487165 -415.132014)
			(xy 430.396307 -415.285413) (xy 430.298705 -415.434612) (xy 430.194554 -415.579315) (xy 430.084061 -415.719235)
			(xy 429.967444 -415.854094) (xy 429.844935 -415.983624) (xy 429.716778 -416.107568) (xy 429.583227 -416.22568)
			(xy 429.444547 -416.337725) (xy 429.301013 -416.443482) (xy 429.15291 -416.542739) (xy 429.000533 -416.635301)
			(xy 428.844184 -416.720982) (xy 428.684173 -416.799614) (xy 428.520819 -416.87104) (xy 428.354444 -416.935118)
			(xy 428.185381 -416.99172) (xy 428.013964 -417.040736) (xy 427.840533 -417.082066) (xy 427.665433 -417.11563)
			(xy 427.489013 -417.14136) (xy 427.311621 -417.159206) (xy 427.13361 -417.169132) (xy 426.955333 -417.171118)
			(xy 426.777146 -417.165161) (xy 426.5994 -417.151271) (xy 426.42245 -417.129478) (xy 426.246646 -417.099824)
			(xy 426.072338 -417.062367) (xy 425.899871 -417.017183) (xy 425.729588 -416.964361) (xy 425.561827 -416.904005)
			(xy 425.396922 -416.836237) (xy 425.235199 -416.761189) (xy 425.07698 -416.679012) (xy 424.922579 -416.589869)
			(xy 424.772302 -416.493935) (xy 424.626447 -416.391403) (xy 424.485305 -416.282475) (xy 424.349156 -416.167368)
			(xy 424.218269 -416.04631) (xy 424.092905 -415.919541) (xy 423.973312 -415.787314) (xy 423.859729 -415.649891)
			(xy 423.75238 -415.507544) (xy 423.651479 -415.360556) (xy 423.557226 -415.20922) (xy 423.469808 -415.053835)
			(xy 423.389398 -414.89471) (xy 423.316157 -414.732161) (xy 423.25023 -414.566511) (xy 423.191747 -414.398089)
			(xy 423.140825 -414.227228) (xy 423.097565 -414.054269) (xy 423.062053 -413.879554) (xy 423.034359 -413.70343)
			(xy 423.014538 -413.526248) (xy 423.00263 -413.348359) (xy 422.998658 -413.170116) (xy 417.90754 -413.170116)
			(xy 417.889382 -413.181786) (xy 417.839802 -413.204429) (xy 417.787505 -413.219785) (xy 417.733555 -413.227542)
			(xy 417.706302 -413.228028) (xy 416.842702 -413.228028) (xy 416.81545 -413.227525) (xy 416.761502 -413.219769)
			(xy 416.709207 -413.204413) (xy 416.659629 -413.181772) (xy 416.613778 -413.152306) (xy 416.572587 -413.116614)
			(xy 416.536895 -413.075424) (xy 416.507429 -413.029573) (xy 416.484787 -412.979995) (xy 416.469432 -412.9277)
			(xy 416.461675 -412.873752) (xy 415.024165 -412.873752) (xy 415.024165 -412.873756) (xy 415.016407 -412.927713)
			(xy 415.001048 -412.980017) (xy 414.978401 -413.029602) (xy 414.948928 -413.07546) (xy 414.913229 -413.116655)
			(xy 414.872029 -413.152351) (xy 414.826169 -413.18182) (xy 414.776581 -413.204461) (xy 414.724276 -413.219815)
			(xy 414.670318 -413.227568) (xy 414.643062 -413.228028) (xy 413.779462 -413.228028) (xy 413.752214 -413.227499)
			(xy 413.698273 -413.219739) (xy 413.645986 -413.204381) (xy 413.596416 -413.181739) (xy 413.550573 -413.152273)
			(xy 413.509389 -413.116584) (xy 413.473704 -413.075397) (xy 413.444243 -413.029551) (xy 413.421606 -412.979978)
			(xy 413.406253 -412.92769) (xy 413.398498 -412.873748) (xy 411.960842 -412.873748) (xy 411.960842 -412.873752)
			(xy 411.953086 -412.9277) (xy 411.937731 -412.979996) (xy 411.91509 -413.029574) (xy 411.885625 -413.075426)
			(xy 411.849934 -413.116618) (xy 411.808744 -413.152311) (xy 411.762894 -413.18178) (xy 411.713317 -413.204423)
			(xy 411.661022 -413.219781) (xy 411.607074 -413.227541) (xy 411.579822 -413.228028) (xy 410.716222 -413.228028)
			(xy 410.68897 -413.227526) (xy 410.635019 -413.219772) (xy 410.582721 -413.204419) (xy 410.533141 -413.181779)
			(xy 410.487288 -413.152313) (xy 410.446094 -413.116621) (xy 410.4104 -413.07543) (xy 410.380932 -413.029578)
			(xy 410.358289 -412.979999) (xy 410.342932 -412.927702) (xy 410.335175 -412.873752) (xy 408.897665 -412.873752)
			(xy 408.897665 -412.873755) (xy 408.889907 -412.927711) (xy 408.874549 -412.980013) (xy 408.851904 -413.029597)
			(xy 408.822433 -413.075453) (xy 408.786736 -413.116648) (xy 408.745539 -413.152344) (xy 408.699681 -413.181813)
			(xy 408.650096 -413.204456) (xy 408.597793 -413.219811) (xy 408.543837 -413.227566) (xy 408.516582 -413.228028)
			(xy 407.652982 -413.228028) (xy 407.625733 -413.227501) (xy 407.57179 -413.219742) (xy 407.5195 -413.204387)
			(xy 407.469928 -413.181746) (xy 407.424082 -413.15228) (xy 407.382897 -413.116591) (xy 407.347209 -413.075403)
			(xy 407.317746 -413.029556) (xy 407.295107 -412.979983) (xy 407.279754 -412.927692) (xy 407.271998 -412.873749)
			(xy 405.834342 -412.873749) (xy 405.834342 -412.873751) (xy 405.826586 -412.927698) (xy 405.811233 -412.979992)
			(xy 405.788593 -413.029569) (xy 405.759129 -413.07542) (xy 405.723441 -413.116611) (xy 405.682253 -413.152304)
			(xy 405.636406 -413.181773) (xy 405.586831 -413.204418) (xy 405.534539 -413.219778) (xy 405.480593 -413.227539)
			(xy 405.453342 -413.228028) (xy 404.589742 -413.228028) (xy 404.562489 -413.227528) (xy 404.508536 -413.219776)
			(xy 404.456236 -413.204424) (xy 404.406653 -413.181785) (xy 404.360797 -413.15232) (xy 404.319601 -413.116628)
			(xy 404.283905 -413.075437) (xy 404.254435 -413.029584) (xy 404.23179 -412.980004) (xy 404.216433 -412.927705)
			(xy 404.208675 -412.873753) (xy 402.771142 -412.873753) (xy 402.763385 -412.927703) (xy 402.748029 -412.98)
			(xy 402.725387 -413.02958) (xy 402.69592 -413.075433) (xy 402.660226 -413.116625) (xy 402.619034 -413.152318)
			(xy 402.573182 -413.181786) (xy 402.523602 -413.204429) (xy 402.471305 -413.219785) (xy 402.417355 -413.227542)
			(xy 402.390102 -413.228028) (xy 401.526502 -413.228028) (xy 401.49925 -413.227525) (xy 401.445302 -413.219769)
			(xy 401.393007 -413.204413) (xy 401.343429 -413.181772) (xy 401.297578 -413.152306) (xy 401.256387 -413.116614)
			(xy 401.220695 -413.075424) (xy 401.191229 -413.029573) (xy 401.168587 -412.979995) (xy 401.153232 -412.9277)
			(xy 401.145475 -412.873752) (xy 399.707965 -412.873752) (xy 399.707965 -412.873756) (xy 399.700207 -412.927713)
			(xy 399.684848 -412.980017) (xy 399.662201 -413.029602) (xy 399.632728 -413.07546) (xy 399.597029 -413.116655)
			(xy 399.555829 -413.152351) (xy 399.509969 -413.18182) (xy 399.460381 -413.204461) (xy 399.408076 -413.219815)
			(xy 399.354118 -413.227568) (xy 399.326862 -413.228028) (xy 398.463262 -413.228028) (xy 398.436014 -413.227499)
			(xy 398.382073 -413.219739) (xy 398.329786 -413.204381) (xy 398.280216 -413.181739) (xy 398.234373 -413.152273)
			(xy 398.193189 -413.116584) (xy 398.157504 -413.075397) (xy 398.128043 -413.029551) (xy 398.105406 -412.979978)
			(xy 398.090053 -412.92769) (xy 398.082298 -412.873748) (xy 396.644642 -412.873748) (xy 396.644642 -412.873752)
			(xy 396.636886 -412.9277) (xy 396.621531 -412.979996) (xy 396.59889 -413.029574) (xy 396.569425 -413.075426)
			(xy 396.533734 -413.116618) (xy 396.492544 -413.152311) (xy 396.446694 -413.18178) (xy 396.397117 -413.204423)
			(xy 396.344822 -413.219781) (xy 396.290874 -413.227541) (xy 396.263622 -413.228028) (xy 395.400022 -413.228028)
			(xy 395.37277 -413.227526) (xy 395.318819 -413.219772) (xy 395.266521 -413.204419) (xy 395.216941 -413.181779)
			(xy 395.171088 -413.152313) (xy 395.129894 -413.116621) (xy 395.0942 -413.07543) (xy 395.064732 -413.029578)
			(xy 395.042089 -412.979999) (xy 395.026732 -412.927702) (xy 395.018975 -412.873752) (xy 393.581465 -412.873752)
			(xy 393.581465 -412.873755) (xy 393.573707 -412.927711) (xy 393.558349 -412.980013) (xy 393.535704 -413.029597)
			(xy 393.506233 -413.075453) (xy 393.470536 -413.116648) (xy 393.429339 -413.152344) (xy 393.383481 -413.181813)
			(xy 393.333896 -413.204456) (xy 393.281593 -413.219811) (xy 393.227637 -413.227566) (xy 393.200382 -413.228028)
			(xy 392.336782 -413.228028) (xy 392.309533 -413.227501) (xy 392.25559 -413.219742) (xy 392.2033 -413.204387)
			(xy 392.153728 -413.181746) (xy 392.107882 -413.15228) (xy 392.066697 -413.116591) (xy 392.031009 -413.075403)
			(xy 392.001546 -413.029556) (xy 391.978907 -412.979983) (xy 391.963554 -412.927692) (xy 391.955798 -412.873749)
			(xy 390.518142 -412.873749) (xy 390.518142 -412.873751) (xy 390.510386 -412.927698) (xy 390.495033 -412.979992)
			(xy 390.472393 -413.029569) (xy 390.442929 -413.07542) (xy 390.407241 -413.116611) (xy 390.366053 -413.152304)
			(xy 390.320206 -413.181773) (xy 390.270631 -413.204418) (xy 390.218339 -413.219778) (xy 390.164393 -413.227539)
			(xy 390.137142 -413.228028) (xy 389.273542 -413.228028) (xy 389.246289 -413.227528) (xy 389.192336 -413.219776)
			(xy 389.140036 -413.204424) (xy 389.090453 -413.181785) (xy 389.044597 -413.15232) (xy 389.003401 -413.116628)
			(xy 388.967705 -413.075437) (xy 388.938235 -413.029584) (xy 388.91559 -412.980004) (xy 388.900233 -412.927705)
			(xy 388.892475 -412.873753) (xy 387.454942 -412.873753) (xy 387.447185 -412.927703) (xy 387.431829 -412.98)
			(xy 387.409187 -413.02958) (xy 387.37972 -413.075433) (xy 387.344026 -413.116625) (xy 387.302834 -413.152318)
			(xy 387.256982 -413.181786) (xy 387.207402 -413.204429) (xy 387.155105 -413.219785) (xy 387.101155 -413.227542)
			(xy 387.073902 -413.228028) (xy 386.210302 -413.228028) (xy 386.18305 -413.227525) (xy 386.129102 -413.219769)
			(xy 386.076807 -413.204413) (xy 386.027229 -413.181772) (xy 385.981378 -413.152306) (xy 385.940187 -413.116614)
			(xy 385.904495 -413.075424) (xy 385.875029 -413.029573) (xy 385.852387 -412.979995) (xy 385.837032 -412.9277)
			(xy 385.829275 -412.873752) (xy 384.391765 -412.873752) (xy 384.391765 -412.873756) (xy 384.384007 -412.927713)
			(xy 384.368648 -412.980017) (xy 384.346001 -413.029602) (xy 384.316528 -413.07546) (xy 384.280829 -413.116655)
			(xy 384.239629 -413.152351) (xy 384.193769 -413.18182) (xy 384.144181 -413.204461) (xy 384.091876 -413.219815)
			(xy 384.037918 -413.227568) (xy 384.010662 -413.228028) (xy 383.147062 -413.228028) (xy 383.119814 -413.227499)
			(xy 383.065873 -413.219739) (xy 383.013586 -413.204381) (xy 382.964016 -413.181739) (xy 382.918173 -413.152273)
			(xy 382.876989 -413.116584) (xy 382.841304 -413.075397) (xy 382.811843 -413.029551) (xy 382.789206 -412.979978)
			(xy 382.773853 -412.92769) (xy 382.766098 -412.873748) (xy 381.328442 -412.873748) (xy 381.328442 -412.873752)
			(xy 381.320686 -412.9277) (xy 381.305331 -412.979996) (xy 381.28269 -413.029574) (xy 381.253225 -413.075426)
			(xy 381.217534 -413.116618) (xy 381.176344 -413.152311) (xy 381.130494 -413.18178) (xy 381.080917 -413.204423)
			(xy 381.028622 -413.219781) (xy 380.974674 -413.227541) (xy 380.947422 -413.228028) (xy 380.083822 -413.228028)
			(xy 380.05657 -413.227526) (xy 380.002619 -413.219772) (xy 379.950321 -413.204419) (xy 379.900741 -413.181779)
			(xy 379.854888 -413.152313) (xy 379.813694 -413.116621) (xy 379.778 -413.07543) (xy 379.748532 -413.029578)
			(xy 379.725889 -412.979999) (xy 379.710532 -412.927702) (xy 379.702775 -412.873752) (xy 378.265265 -412.873752)
			(xy 378.265265 -412.873755) (xy 378.257507 -412.927711) (xy 378.242149 -412.980013) (xy 378.219504 -413.029597)
			(xy 378.190033 -413.075453) (xy 378.154336 -413.116648) (xy 378.113139 -413.152344) (xy 378.067281 -413.181813)
			(xy 378.017696 -413.204456) (xy 377.965393 -413.219811) (xy 377.911437 -413.227566) (xy 377.884182 -413.228028)
			(xy 377.020582 -413.228028) (xy 376.993333 -413.227501) (xy 376.93939 -413.219742) (xy 376.8871 -413.204387)
			(xy 376.837528 -413.181746) (xy 376.791682 -413.15228) (xy 376.750497 -413.116591) (xy 376.714809 -413.075403)
			(xy 376.685346 -413.029556) (xy 376.662707 -412.979983) (xy 376.647354 -412.927692) (xy 376.639598 -412.873749)
			(xy 375.201942 -412.873749) (xy 375.201942 -412.873751) (xy 375.194186 -412.927698) (xy 375.178833 -412.979992)
			(xy 375.156193 -413.029569) (xy 375.126729 -413.07542) (xy 375.091041 -413.116611) (xy 375.049853 -413.152304)
			(xy 375.004006 -413.181773) (xy 374.954431 -413.204418) (xy 374.902139 -413.219778) (xy 374.848193 -413.227539)
			(xy 374.820942 -413.228028) (xy 373.957342 -413.228028) (xy 373.930089 -413.227528) (xy 373.876136 -413.219776)
			(xy 373.823836 -413.204424) (xy 373.774253 -413.181785) (xy 373.728397 -413.15232) (xy 373.687201 -413.116628)
			(xy 373.651505 -413.075437) (xy 373.622035 -413.029584) (xy 373.59939 -412.980004) (xy 373.584033 -412.927705)
			(xy 373.576275 -412.873753) (xy 372.138742 -412.873753) (xy 372.130985 -412.927703) (xy 372.115629 -412.98)
			(xy 372.092987 -413.02958) (xy 372.06352 -413.075433) (xy 372.027826 -413.116625) (xy 371.986634 -413.152318)
			(xy 371.940782 -413.181786) (xy 371.891202 -413.204429) (xy 371.838905 -413.219785) (xy 371.784955 -413.227542)
			(xy 371.757702 -413.228028) (xy 370.894102 -413.228028) (xy 370.86685 -413.227525) (xy 370.812902 -413.219769)
			(xy 370.760607 -413.204413) (xy 370.711029 -413.181772) (xy 370.665178 -413.152306) (xy 370.623987 -413.116614)
			(xy 370.588295 -413.075424) (xy 370.558829 -413.029573) (xy 370.536187 -412.979995) (xy 370.520832 -412.9277)
			(xy 370.513075 -412.873752) (xy 350.987142 -412.873752) (xy 350.979385 -412.927702) (xy 350.96403 -412.979999)
			(xy 350.941388 -413.029579) (xy 350.911921 -413.075431) (xy 350.876228 -413.116624) (xy 350.835036 -413.152317)
			(xy 350.789184 -413.181785) (xy 350.739605 -413.204428) (xy 350.687308 -413.219784) (xy 350.633358 -413.227542)
			(xy 350.606106 -413.228028) (xy 349.742506 -413.228028) (xy 349.715254 -413.227525) (xy 349.661306 -413.219769)
			(xy 349.60901 -413.204415) (xy 349.559431 -413.181774) (xy 349.51358 -413.152307) (xy 349.472389 -413.116616)
			(xy 349.436696 -413.075425) (xy 349.407229 -413.029574) (xy 349.384588 -412.979996) (xy 349.369232 -412.9277)
			(xy 349.361475 -412.873752) (xy 347.923965 -412.873752) (xy 347.923965 -412.873756) (xy 347.916207 -412.927713)
			(xy 347.900848 -412.980016) (xy 347.878202 -413.029601) (xy 347.848729 -413.075458) (xy 347.81303 -413.116654)
			(xy 347.771831 -413.15235) (xy 347.725971 -413.181818) (xy 347.676384 -413.20446) (xy 347.624079 -413.219814)
			(xy 347.570122 -413.227567) (xy 347.542866 -413.228028) (xy 346.679266 -413.228028) (xy 346.652018 -413.227499)
			(xy 346.598077 -413.219739) (xy 346.545789 -413.204382) (xy 346.496218 -413.18174) (xy 346.450375 -413.152275)
			(xy 346.409191 -413.116585) (xy 346.373505 -413.075398) (xy 346.344043 -413.029552) (xy 346.321406 -412.979979)
			(xy 346.306053 -412.92769) (xy 346.298298 -412.873748) (xy 344.860642 -412.873748) (xy 344.860642 -412.873751)
			(xy 344.852886 -412.9277) (xy 344.837531 -412.979995) (xy 344.814891 -413.029573) (xy 344.785426 -413.075425)
			(xy 344.749735 -413.116617) (xy 344.708546 -413.15231) (xy 344.662696 -413.181778) (xy 344.61312 -413.204422)
			(xy 344.560825 -413.21978) (xy 344.506877 -413.22754) (xy 344.479626 -413.228028) (xy 343.616026 -413.228028)
			(xy 343.588773 -413.227526) (xy 343.534822 -413.219773) (xy 343.482524 -413.20442) (xy 343.432943 -413.18178)
			(xy 343.387089 -413.152314) (xy 343.345896 -413.116623) (xy 343.310201 -413.075431) (xy 343.280732 -413.029579)
			(xy 343.258089 -412.98) (xy 343.242733 -412.927703) (xy 343.234975 -412.873753) (xy 341.797465 -412.873753)
			(xy 341.797465 -412.873755) (xy 341.789707 -412.92771) (xy 341.77435 -412.980012) (xy 341.751705 -413.029595)
			(xy 341.722234 -413.075452) (xy 341.686537 -413.116647) (xy 341.645341 -413.152343) (xy 341.599483 -413.181812)
			(xy 341.549899 -413.204455) (xy 341.497596 -413.21981) (xy 341.443641 -413.227566) (xy 341.416386 -413.228028)
			(xy 340.552786 -413.228028) (xy 340.525537 -413.227501) (xy 340.471594 -413.219743) (xy 340.419303 -413.204388)
			(xy 340.36973 -413.181747) (xy 340.323884 -413.152282) (xy 340.282698 -413.116592) (xy 340.24701 -413.075404)
			(xy 340.217546 -413.029557) (xy 340.194908 -412.979984) (xy 340.179554 -412.927693) (xy 340.171798 -412.873749)
			(xy 338.734142 -412.873749) (xy 338.734142 -412.873751) (xy 338.726387 -412.927697) (xy 338.711033 -412.979991)
			(xy 338.688394 -413.029568) (xy 338.65893 -413.075418) (xy 338.623242 -413.116609) (xy 338.582055 -413.152303)
			(xy 338.536208 -413.181772) (xy 338.486634 -413.204417) (xy 338.434342 -413.219777) (xy 338.380397 -413.227539)
			(xy 338.353146 -413.228028) (xy 337.489546 -413.228028) (xy 337.462292 -413.227528) (xy 337.408339 -413.219777)
			(xy 337.356039 -413.204425) (xy 337.306455 -413.181787) (xy 337.260599 -413.152321) (xy 337.219403 -413.11663)
			(xy 337.183706 -413.075438) (xy 337.154235 -413.029585) (xy 337.131591 -412.980004) (xy 337.116233 -412.927706)
			(xy 337.108475 -412.873754) (xy 335.670942 -412.873754) (xy 335.663185 -412.927702) (xy 335.64783 -412.979999)
			(xy 335.625188 -413.029579) (xy 335.595721 -413.075431) (xy 335.560028 -413.116624) (xy 335.518836 -413.152317)
			(xy 335.472984 -413.181785) (xy 335.423405 -413.204428) (xy 335.371108 -413.219784) (xy 335.317158 -413.227542)
			(xy 335.289906 -413.228028) (xy 334.426306 -413.228028) (xy 334.399054 -413.227525) (xy 334.345106 -413.219769)
			(xy 334.29281 -413.204415) (xy 334.243231 -413.181774) (xy 334.19738 -413.152307) (xy 334.156189 -413.116616)
			(xy 334.120496 -413.075425) (xy 334.091029 -413.029574) (xy 334.068388 -412.979996) (xy 334.053032 -412.9277)
			(xy 334.045275 -412.873752) (xy 332.607765 -412.873752) (xy 332.607765 -412.873756) (xy 332.600007 -412.927713)
			(xy 332.584648 -412.980016) (xy 332.562002 -413.029601) (xy 332.532529 -413.075458) (xy 332.49683 -413.116654)
			(xy 332.455631 -413.15235) (xy 332.409771 -413.181818) (xy 332.360184 -413.20446) (xy 332.307879 -413.219814)
			(xy 332.253922 -413.227567) (xy 332.226666 -413.228028) (xy 331.363066 -413.228028) (xy 331.335818 -413.227499)
			(xy 331.281877 -413.219739) (xy 331.229589 -413.204382) (xy 331.180018 -413.18174) (xy 331.134175 -413.152275)
			(xy 331.092991 -413.116585) (xy 331.057305 -413.075398) (xy 331.027843 -413.029552) (xy 331.005206 -412.979979)
			(xy 330.989853 -412.92769) (xy 330.982098 -412.873748) (xy 329.544442 -412.873748) (xy 329.544442 -412.873751)
			(xy 329.536686 -412.9277) (xy 329.521331 -412.979995) (xy 329.498691 -413.029573) (xy 329.469226 -413.075425)
			(xy 329.433535 -413.116617) (xy 329.392346 -413.15231) (xy 329.346496 -413.181778) (xy 329.29692 -413.204422)
			(xy 329.244625 -413.21978) (xy 329.190677 -413.22754) (xy 329.163426 -413.228028) (xy 328.299826 -413.228028)
			(xy 328.272573 -413.227526) (xy 328.218622 -413.219773) (xy 328.166324 -413.20442) (xy 328.116743 -413.18178)
			(xy 328.070889 -413.152314) (xy 328.029696 -413.116623) (xy 327.994001 -413.075431) (xy 327.964532 -413.029579)
			(xy 327.941889 -412.98) (xy 327.926533 -412.927703) (xy 327.918775 -412.873753) (xy 326.481265 -412.873753)
			(xy 326.481265 -412.873755) (xy 326.473507 -412.92771) (xy 326.45815 -412.980012) (xy 326.435505 -413.029595)
			(xy 326.406034 -413.075452) (xy 326.370337 -413.116647) (xy 326.329141 -413.152343) (xy 326.283283 -413.181812)
			(xy 326.233699 -413.204455) (xy 326.181396 -413.21981) (xy 326.127441 -413.227566) (xy 326.100186 -413.228028)
			(xy 325.236586 -413.228028) (xy 325.209337 -413.227501) (xy 325.155394 -413.219743) (xy 325.103103 -413.204388)
			(xy 325.05353 -413.181747) (xy 325.007684 -413.152282) (xy 324.966498 -413.116592) (xy 324.93081 -413.075404)
			(xy 324.901346 -413.029557) (xy 324.878708 -412.979984) (xy 324.863354 -412.927693) (xy 324.855598 -412.873749)
			(xy 323.417942 -412.873749) (xy 323.417942 -412.873751) (xy 323.410187 -412.927697) (xy 323.394833 -412.979991)
			(xy 323.372194 -413.029568) (xy 323.34273 -413.075418) (xy 323.307042 -413.116609) (xy 323.265855 -413.152303)
			(xy 323.220008 -413.181772) (xy 323.170434 -413.204417) (xy 323.118142 -413.219777) (xy 323.064197 -413.227539)
			(xy 323.036946 -413.228028) (xy 322.173346 -413.228028) (xy 322.146092 -413.227528) (xy 322.092139 -413.219777)
			(xy 322.039839 -413.204425) (xy 321.990255 -413.181787) (xy 321.944399 -413.152321) (xy 321.903203 -413.11663)
			(xy 321.867506 -413.075438) (xy 321.838035 -413.029585) (xy 321.815391 -412.980004) (xy 321.800033 -412.927706)
			(xy 321.792275 -412.873754) (xy 320.354742 -412.873754) (xy 320.346985 -412.927702) (xy 320.33163 -412.979999)
			(xy 320.308988 -413.029579) (xy 320.279521 -413.075431) (xy 320.243828 -413.116624) (xy 320.202636 -413.152317)
			(xy 320.156784 -413.181785) (xy 320.107205 -413.204428) (xy 320.054908 -413.219784) (xy 320.000958 -413.227542)
			(xy 319.973706 -413.228028) (xy 319.110106 -413.228028) (xy 319.082854 -413.227525) (xy 319.028906 -413.219769)
			(xy 318.97661 -413.204415) (xy 318.927031 -413.181774) (xy 318.88118 -413.152307) (xy 318.839989 -413.116616)
			(xy 318.804296 -413.075425) (xy 318.774829 -413.029574) (xy 318.752188 -412.979996) (xy 318.736832 -412.9277)
			(xy 318.729075 -412.873752) (xy 317.291565 -412.873752) (xy 317.291565 -412.873756) (xy 317.283807 -412.927713)
			(xy 317.268448 -412.980016) (xy 317.245802 -413.029601) (xy 317.216329 -413.075458) (xy 317.18063 -413.116654)
			(xy 317.139431 -413.15235) (xy 317.093571 -413.181818) (xy 317.043984 -413.20446) (xy 316.991679 -413.219814)
			(xy 316.937722 -413.227567) (xy 316.910466 -413.228028) (xy 316.046866 -413.228028) (xy 316.019618 -413.227499)
			(xy 315.965677 -413.219739) (xy 315.913389 -413.204382) (xy 315.863818 -413.18174) (xy 315.817975 -413.152275)
			(xy 315.776791 -413.116585) (xy 315.741105 -413.075398) (xy 315.711643 -413.029552) (xy 315.689006 -412.979979)
			(xy 315.673653 -412.92769) (xy 315.665898 -412.873748) (xy 314.228242 -412.873748) (xy 314.228242 -412.873751)
			(xy 314.220486 -412.9277) (xy 314.205131 -412.979995) (xy 314.182491 -413.029573) (xy 314.153026 -413.075425)
			(xy 314.117335 -413.116617) (xy 314.076146 -413.15231) (xy 314.030296 -413.181778) (xy 313.98072 -413.204422)
			(xy 313.928425 -413.21978) (xy 313.874477 -413.22754) (xy 313.847226 -413.228028) (xy 312.983626 -413.228028)
			(xy 312.956373 -413.227526) (xy 312.902422 -413.219773) (xy 312.850124 -413.20442) (xy 312.800543 -413.18178)
			(xy 312.754689 -413.152314) (xy 312.713496 -413.116623) (xy 312.677801 -413.075431) (xy 312.648332 -413.029579)
			(xy 312.625689 -412.98) (xy 312.610333 -412.927703) (xy 312.602575 -412.873753) (xy 311.165065 -412.873753)
			(xy 311.165065 -412.873755) (xy 311.157307 -412.92771) (xy 311.14195 -412.980012) (xy 311.119305 -413.029595)
			(xy 311.089834 -413.075452) (xy 311.054137 -413.116647) (xy 311.012941 -413.152343) (xy 310.967083 -413.181812)
			(xy 310.917499 -413.204455) (xy 310.865196 -413.21981) (xy 310.811241 -413.227566) (xy 310.783986 -413.228028)
			(xy 309.920386 -413.228028) (xy 309.893137 -413.227501) (xy 309.839194 -413.219743) (xy 309.786903 -413.204388)
			(xy 309.73733 -413.181747) (xy 309.691484 -413.152282) (xy 309.650298 -413.116592) (xy 309.61461 -413.075404)
			(xy 309.585146 -413.029557) (xy 309.562508 -412.979984) (xy 309.547154 -412.927693) (xy 309.539398 -412.873749)
			(xy 308.101742 -412.873749) (xy 308.101742 -412.873751) (xy 308.093987 -412.927697) (xy 308.078633 -412.979991)
			(xy 308.055994 -413.029568) (xy 308.02653 -413.075418) (xy 307.990842 -413.116609) (xy 307.949655 -413.152303)
			(xy 307.903808 -413.181772) (xy 307.854234 -413.204417) (xy 307.801942 -413.219777) (xy 307.747997 -413.227539)
			(xy 307.720746 -413.228028) (xy 306.857146 -413.228028) (xy 306.829892 -413.227528) (xy 306.775939 -413.219777)
			(xy 306.723639 -413.204425) (xy 306.674055 -413.181787) (xy 306.628199 -413.152321) (xy 306.587003 -413.11663)
			(xy 306.551306 -413.075438) (xy 306.521835 -413.029585) (xy 306.499191 -412.980004) (xy 306.483833 -412.927706)
			(xy 306.476075 -412.873754) (xy 305.038542 -412.873754) (xy 305.030785 -412.927702) (xy 305.01543 -412.979999)
			(xy 304.992788 -413.029579) (xy 304.963321 -413.075431) (xy 304.927628 -413.116624) (xy 304.886436 -413.152317)
			(xy 304.840584 -413.181785) (xy 304.791005 -413.204428) (xy 304.738708 -413.219784) (xy 304.684758 -413.227542)
			(xy 304.657506 -413.228028) (xy 303.793906 -413.228028) (xy 303.766654 -413.227525) (xy 303.712706 -413.219769)
			(xy 303.66041 -413.204415) (xy 303.610831 -413.181774) (xy 303.56498 -413.152307) (xy 303.523789 -413.116616)
			(xy 303.488096 -413.075425) (xy 303.458629 -413.029574) (xy 303.435988 -412.979996) (xy 303.420632 -412.9277)
			(xy 303.412875 -412.873752) (xy 301.559858 -412.873752) (xy 301.562459 -412.902862) (xy 301.570401 -413.080972)
			(xy 301.570898 -413.170116) (xy 301.570401 -413.25926) (xy 301.562459 -413.43737) (xy 301.546591 -413.61495)
			(xy 301.522827 -413.791646) (xy 301.491216 -413.967109) (xy 301.45182 -414.140989) (xy 301.404718 -414.312942)
			(xy 301.350002 -414.482626) (xy 301.287781 -414.649703) (xy 301.21818 -414.813844) (xy 301.141335 -414.97472)
			(xy 301.057401 -415.132014) (xy 300.966543 -415.285413) (xy 300.882586 -415.413753) (xy 304.944475 -415.413753)
			(xy 304.944475 -415.359247) (xy 304.952233 -415.305297) (xy 304.967589 -415.253) (xy 304.990232 -415.203421)
			(xy 305.019701 -415.157569) (xy 305.055396 -415.116377) (xy 305.096589 -415.080686) (xy 305.142443 -415.05122)
			(xy 305.192024 -415.02858) (xy 305.244322 -415.013227) (xy 305.298273 -415.005474) (xy 305.325526 -415.005012)
			(xy 306.189126 -415.005012) (xy 306.216377 -415.00546) (xy 306.270325 -415.01322) (xy 306.32262 -415.028578)
			(xy 306.372196 -415.051222) (xy 306.418046 -415.08069) (xy 306.459235 -415.116383) (xy 306.494926 -415.157575)
			(xy 306.524391 -415.203427) (xy 306.547031 -415.253005) (xy 306.562386 -415.3053) (xy 306.570142 -415.359249)
			(xy 306.570142 -415.413748) (xy 308.007798 -415.413748) (xy 308.007798 -415.359252) (xy 308.015553 -415.30531)
			(xy 308.030906 -415.253021) (xy 308.053543 -415.203448) (xy 308.083005 -415.157602) (xy 308.118691 -415.116415)
			(xy 308.159875 -415.080725) (xy 308.205718 -415.05126) (xy 308.255289 -415.028618) (xy 308.307577 -415.013261)
			(xy 308.361518 -415.005501) (xy 308.388766 -415.005012) (xy 309.252366 -415.005012) (xy 309.279622 -415.005433)
			(xy 309.333579 -415.013186) (xy 309.385884 -415.02854) (xy 309.435471 -415.051182) (xy 309.481331 -415.08065)
			(xy 309.52253 -415.116346) (xy 309.558229 -415.157542) (xy 309.587702 -415.203399) (xy 309.610348 -415.252984)
			(xy 309.625707 -415.305287) (xy 309.633465 -415.359244) (xy 309.633465 -415.413752) (xy 311.070975 -415.413752)
			(xy 311.070975 -415.359248) (xy 311.078732 -415.3053) (xy 311.094088 -415.253004) (xy 311.116729 -415.203426)
			(xy 311.146196 -415.157575) (xy 311.181889 -415.116384) (xy 311.22308 -415.080693) (xy 311.268931 -415.051226)
			(xy 311.31851 -415.028585) (xy 311.370806 -415.013231) (xy 311.424754 -415.005475) (xy 311.452006 -415.005012)
			(xy 312.315606 -415.005012) (xy 312.342858 -415.005458) (xy 312.396808 -415.013216) (xy 312.449105 -415.028572)
			(xy 312.498684 -415.051215) (xy 312.544536 -415.080683) (xy 312.585728 -415.116376) (xy 312.621421 -415.157569)
			(xy 312.650888 -415.203421) (xy 312.67353 -415.253001) (xy 312.688885 -415.305298) (xy 312.696642 -415.359248)
			(xy 312.696642 -415.413752) (xy 312.696642 -415.413754) (xy 314.134175 -415.413754) (xy 314.134175 -415.359246)
			(xy 314.141933 -415.305294) (xy 314.157291 -415.252996) (xy 314.179935 -415.203415) (xy 314.209406 -415.157562)
			(xy 314.245103 -415.11637) (xy 314.286299 -415.080679) (xy 314.332155 -415.051213) (xy 314.381739 -415.028575)
			(xy 314.434039 -415.013223) (xy 314.487992 -415.005472) (xy 314.515246 -415.005012) (xy 315.378846 -415.005012)
			(xy 315.406097 -415.005461) (xy 315.460042 -415.013223) (xy 315.512334 -415.028583) (xy 315.561908 -415.051228)
			(xy 315.607755 -415.080697) (xy 315.648942 -415.116391) (xy 315.68463 -415.157582) (xy 315.714094 -415.203432)
			(xy 315.736733 -415.253009) (xy 315.752087 -415.305303) (xy 315.759842 -415.359249) (xy 315.759842 -415.413749)
			(xy 317.197498 -415.413749) (xy 317.197498 -415.359251) (xy 317.205254 -415.305307) (xy 317.220608 -415.253016)
			(xy 317.243246 -415.203443) (xy 317.27271 -415.157596) (xy 317.308398 -415.116408) (xy 317.349584 -415.080718)
			(xy 317.39543 -415.051253) (xy 317.445003 -415.028612) (xy 317.497294 -415.013257) (xy 317.551237 -415.005499)
			(xy 317.578486 -415.005012) (xy 318.442086 -415.005012) (xy 318.469341 -415.005434) (xy 318.523296 -415.01319)
			(xy 318.575599 -415.028545) (xy 318.625183 -415.051188) (xy 318.671041 -415.080657) (xy 318.712237 -415.116353)
			(xy 318.747934 -415.157548) (xy 318.777405 -415.203405) (xy 318.80005 -415.252988) (xy 318.815407 -415.30529)
			(xy 318.823165 -415.359245) (xy 318.823165 -415.413753) (xy 320.260675 -415.413753) (xy 320.260675 -415.359247)
			(xy 320.268433 -415.305297) (xy 320.283789 -415.253) (xy 320.306432 -415.203421) (xy 320.335901 -415.157569)
			(xy 320.371596 -415.116377) (xy 320.412789 -415.080686) (xy 320.458643 -415.05122) (xy 320.508224 -415.02858)
			(xy 320.560522 -415.013227) (xy 320.614473 -415.005474) (xy 320.641726 -415.005012) (xy 321.505326 -415.005012)
			(xy 321.532577 -415.00546) (xy 321.586525 -415.01322) (xy 321.63882 -415.028578) (xy 321.688396 -415.051222)
			(xy 321.734246 -415.08069) (xy 321.775435 -415.116383) (xy 321.811126 -415.157575) (xy 321.840591 -415.203427)
			(xy 321.863231 -415.253005) (xy 321.878586 -415.3053) (xy 321.886342 -415.359249) (xy 321.886342 -415.413748)
			(xy 323.323998 -415.413748) (xy 323.323998 -415.359252) (xy 323.331753 -415.30531) (xy 323.347106 -415.253021)
			(xy 323.369743 -415.203448) (xy 323.399205 -415.157602) (xy 323.434891 -415.116415) (xy 323.476075 -415.080725)
			(xy 323.521918 -415.05126) (xy 323.571489 -415.028618) (xy 323.623777 -415.013261) (xy 323.677718 -415.005501)
			(xy 323.704966 -415.005012) (xy 324.568566 -415.005012) (xy 324.595822 -415.005433) (xy 324.649779 -415.013186)
			(xy 324.702084 -415.02854) (xy 324.751671 -415.051182) (xy 324.797531 -415.08065) (xy 324.83873 -415.116346)
			(xy 324.874429 -415.157542) (xy 324.903902 -415.203399) (xy 324.926548 -415.252984) (xy 324.941907 -415.305287)
			(xy 324.949665 -415.359244) (xy 324.949665 -415.413752) (xy 326.387175 -415.413752) (xy 326.387175 -415.359248)
			(xy 326.394932 -415.3053) (xy 326.410288 -415.253004) (xy 326.432929 -415.203426) (xy 326.462396 -415.157575)
			(xy 326.498089 -415.116384) (xy 326.53928 -415.080693) (xy 326.585131 -415.051226) (xy 326.63471 -415.028585)
			(xy 326.687006 -415.013231) (xy 326.740954 -415.005475) (xy 326.768206 -415.005012) (xy 327.631806 -415.005012)
			(xy 327.659058 -415.005458) (xy 327.713008 -415.013216) (xy 327.765305 -415.028572) (xy 327.814884 -415.051215)
			(xy 327.860736 -415.080683) (xy 327.901928 -415.116376) (xy 327.937621 -415.157569) (xy 327.967088 -415.203421)
			(xy 327.98973 -415.253001) (xy 328.005085 -415.305298) (xy 328.012842 -415.359248) (xy 328.012842 -415.413752)
			(xy 328.012842 -415.413754) (xy 329.450375 -415.413754) (xy 329.450375 -415.359246) (xy 329.458133 -415.305294)
			(xy 329.473491 -415.252996) (xy 329.496135 -415.203415) (xy 329.525606 -415.157562) (xy 329.561303 -415.11637)
			(xy 329.602499 -415.080679) (xy 329.648355 -415.051213) (xy 329.697939 -415.028575) (xy 329.750239 -415.013223)
			(xy 329.804192 -415.005472) (xy 329.831446 -415.005012) (xy 330.695046 -415.005012) (xy 330.722297 -415.005461)
			(xy 330.776242 -415.013223) (xy 330.828534 -415.028583) (xy 330.878108 -415.051228) (xy 330.923955 -415.080697)
			(xy 330.965142 -415.116391) (xy 331.00083 -415.157582) (xy 331.030294 -415.203432) (xy 331.052933 -415.253009)
			(xy 331.068287 -415.305303) (xy 331.076042 -415.359249) (xy 331.076042 -415.413749) (xy 332.513698 -415.413749)
			(xy 332.513698 -415.359251) (xy 332.521454 -415.305307) (xy 332.536808 -415.253016) (xy 332.559446 -415.203443)
			(xy 332.58891 -415.157596) (xy 332.624598 -415.116408) (xy 332.665784 -415.080718) (xy 332.71163 -415.051253)
			(xy 332.761203 -415.028612) (xy 332.813494 -415.013257) (xy 332.867437 -415.005499) (xy 332.894686 -415.005012)
			(xy 333.758286 -415.005012) (xy 333.785541 -415.005434) (xy 333.839496 -415.01319) (xy 333.891799 -415.028545)
			(xy 333.941383 -415.051188) (xy 333.987241 -415.080657) (xy 334.028437 -415.116353) (xy 334.064134 -415.157548)
			(xy 334.093605 -415.203405) (xy 334.11625 -415.252988) (xy 334.131607 -415.30529) (xy 334.139365 -415.359245)
			(xy 334.139365 -415.413753) (xy 335.576875 -415.413753) (xy 335.576875 -415.359247) (xy 335.584633 -415.305297)
			(xy 335.599989 -415.253) (xy 335.622632 -415.203421) (xy 335.652101 -415.157569) (xy 335.687796 -415.116377)
			(xy 335.728989 -415.080686) (xy 335.774843 -415.05122) (xy 335.824424 -415.02858) (xy 335.876722 -415.013227)
			(xy 335.930673 -415.005474) (xy 335.957926 -415.005012) (xy 336.821526 -415.005012) (xy 336.848777 -415.00546)
			(xy 336.902725 -415.01322) (xy 336.95502 -415.028578) (xy 337.004596 -415.051222) (xy 337.050446 -415.08069)
			(xy 337.091635 -415.116383) (xy 337.127326 -415.157575) (xy 337.156791 -415.203427) (xy 337.179431 -415.253005)
			(xy 337.194786 -415.3053) (xy 337.202542 -415.359249) (xy 337.202542 -415.413748) (xy 338.640198 -415.413748)
			(xy 338.640198 -415.359252) (xy 338.647953 -415.30531) (xy 338.663306 -415.253021) (xy 338.685943 -415.203448)
			(xy 338.715405 -415.157602) (xy 338.751091 -415.116415) (xy 338.792275 -415.080725) (xy 338.838118 -415.05126)
			(xy 338.887689 -415.028618) (xy 338.939977 -415.013261) (xy 338.993918 -415.005501) (xy 339.021166 -415.005012)
			(xy 339.884766 -415.005012) (xy 339.912022 -415.005433) (xy 339.965979 -415.013186) (xy 340.018284 -415.02854)
			(xy 340.067871 -415.051182) (xy 340.113731 -415.08065) (xy 340.15493 -415.116346) (xy 340.190629 -415.157542)
			(xy 340.220102 -415.203399) (xy 340.242748 -415.252984) (xy 340.258107 -415.305287) (xy 340.265865 -415.359244)
			(xy 340.265865 -415.413752) (xy 341.703375 -415.413752) (xy 341.703375 -415.359248) (xy 341.711132 -415.3053)
			(xy 341.726488 -415.253004) (xy 341.749129 -415.203426) (xy 341.778596 -415.157575) (xy 341.814289 -415.116384)
			(xy 341.85548 -415.080693) (xy 341.901331 -415.051226) (xy 341.95091 -415.028585) (xy 342.003206 -415.013231)
			(xy 342.057154 -415.005475) (xy 342.084406 -415.005012) (xy 342.948006 -415.005012) (xy 342.975258 -415.005458)
			(xy 343.029208 -415.013216) (xy 343.081505 -415.028572) (xy 343.131084 -415.051215) (xy 343.176936 -415.080683)
			(xy 343.218128 -415.116376) (xy 343.253821 -415.157569) (xy 343.283288 -415.203421) (xy 343.30593 -415.253001)
			(xy 343.321285 -415.305298) (xy 343.329042 -415.359248) (xy 343.329042 -415.413752) (xy 343.329042 -415.413754)
			(xy 344.766575 -415.413754) (xy 344.766575 -415.359246) (xy 344.774333 -415.305294) (xy 344.789691 -415.252996)
			(xy 344.812335 -415.203415) (xy 344.841806 -415.157562) (xy 344.877503 -415.11637) (xy 344.918699 -415.080679)
			(xy 344.964555 -415.051213) (xy 345.014139 -415.028575) (xy 345.066439 -415.013223) (xy 345.120392 -415.005472)
			(xy 345.147646 -415.005012) (xy 346.011246 -415.005012) (xy 346.038497 -415.005461) (xy 346.092442 -415.013223)
			(xy 346.144734 -415.028583) (xy 346.194308 -415.051228) (xy 346.240155 -415.080697) (xy 346.281342 -415.116391)
			(xy 346.31703 -415.157582) (xy 346.346494 -415.203432) (xy 346.369133 -415.253009) (xy 346.384487 -415.305303)
			(xy 346.392242 -415.359249) (xy 346.392242 -415.413749) (xy 347.829898 -415.413749) (xy 347.829898 -415.359251)
			(xy 347.837654 -415.305307) (xy 347.853008 -415.253016) (xy 347.875646 -415.203443) (xy 347.90511 -415.157596)
			(xy 347.940798 -415.116408) (xy 347.981984 -415.080718) (xy 348.02783 -415.051253) (xy 348.077403 -415.028612)
			(xy 348.129694 -415.013257) (xy 348.183637 -415.005499) (xy 348.210886 -415.005012) (xy 349.074486 -415.005012)
			(xy 349.101741 -415.005434) (xy 349.155696 -415.01319) (xy 349.207999 -415.028545) (xy 349.257583 -415.051188)
			(xy 349.303441 -415.080657) (xy 349.344637 -415.116353) (xy 349.380334 -415.157548) (xy 349.409805 -415.203405)
			(xy 349.43245 -415.252988) (xy 349.447807 -415.30529) (xy 349.455565 -415.359245) (xy 349.455565 -415.413753)
			(xy 350.893075 -415.413753) (xy 350.893075 -415.359247) (xy 350.900833 -415.305297) (xy 350.916189 -415.253)
			(xy 350.938832 -415.203421) (xy 350.968301 -415.157569) (xy 351.003996 -415.116377) (xy 351.045189 -415.080686)
			(xy 351.091043 -415.05122) (xy 351.140624 -415.02858) (xy 351.192922 -415.013227) (xy 351.246873 -415.005474)
			(xy 351.274126 -415.005012) (xy 352.137726 -415.005012) (xy 352.164977 -415.00546) (xy 352.218925 -415.01322)
			(xy 352.27122 -415.028578) (xy 352.320796 -415.051222) (xy 352.366646 -415.08069) (xy 352.407835 -415.116383)
			(xy 352.443526 -415.157575) (xy 352.472991 -415.203427) (xy 352.495631 -415.253005) (xy 352.510986 -415.3053)
			(xy 352.518742 -415.359249) (xy 352.518742 -415.413751) (xy 352.518742 -415.413752) (xy 372.044675 -415.413752)
			(xy 372.044675 -415.359248) (xy 372.052432 -415.305298) (xy 372.067789 -415.253001) (xy 372.090432 -415.203422)
			(xy 372.1199 -415.15757) (xy 372.155594 -415.116379) (xy 372.196788 -415.080687) (xy 372.242641 -415.051221)
			(xy 372.292221 -415.028581) (xy 372.344519 -415.013228) (xy 372.39847 -415.005474) (xy 372.425722 -415.005012)
			(xy 373.289322 -415.005012) (xy 373.316574 -415.005459) (xy 373.370522 -415.013219) (xy 373.422817 -415.028577)
			(xy 373.472394 -415.05122) (xy 373.518244 -415.080689) (xy 373.559434 -415.116382) (xy 373.595125 -415.157574)
			(xy 373.62459 -415.203426) (xy 373.647231 -415.253004) (xy 373.662586 -415.3053) (xy 373.670342 -415.359248)
			(xy 373.670342 -415.413748) (xy 375.107998 -415.413748) (xy 375.107998 -415.359252) (xy 375.115753 -415.30531)
			(xy 375.131106 -415.253022) (xy 375.153743 -415.203449) (xy 375.183204 -415.157603) (xy 375.218889 -415.116416)
			(xy 375.260073 -415.080727) (xy 375.305916 -415.051261) (xy 375.355486 -415.028619) (xy 375.407773 -415.013261)
			(xy 375.461714 -415.005501) (xy 375.488962 -415.005012) (xy 376.352562 -415.005012) (xy 376.379818 -415.005432)
			(xy 376.433776 -415.013185) (xy 376.486081 -415.028539) (xy 376.535669 -415.05118) (xy 376.581529 -415.080649)
			(xy 376.622729 -415.116345) (xy 376.658428 -415.15754) (xy 376.687901 -415.203398) (xy 376.710548 -415.252983)
			(xy 376.725907 -415.305287) (xy 376.733665 -415.359244) (xy 376.733665 -415.413752) (xy 378.171175 -415.413752)
			(xy 378.171175 -415.359248) (xy 378.178932 -415.3053) (xy 378.194287 -415.253005) (xy 378.216929 -415.203427)
			(xy 378.246395 -415.157576) (xy 378.282087 -415.116386) (xy 378.323278 -415.080694) (xy 378.369129 -415.051228)
			(xy 378.418707 -415.028587) (xy 378.471002 -415.013231) (xy 378.52495 -415.005475) (xy 378.552202 -415.005012)
			(xy 379.415802 -415.005012) (xy 379.443055 -415.005458) (xy 379.497005 -415.013215) (xy 379.549302 -415.028571)
			(xy 379.598882 -415.051214) (xy 379.644734 -415.080682) (xy 379.685926 -415.116375) (xy 379.72162 -415.157567)
			(xy 379.751087 -415.20342) (xy 379.773729 -415.253) (xy 379.789085 -415.305297) (xy 379.796842 -415.359247)
			(xy 379.796842 -415.413753) (xy 381.234375 -415.413753) (xy 381.234375 -415.359247) (xy 381.242133 -415.305295)
			(xy 381.25749 -415.252996) (xy 381.280135 -415.203416) (xy 381.309605 -415.157563) (xy 381.345301 -415.116372)
			(xy 381.386497 -415.08068) (xy 381.432353 -415.051215) (xy 381.481936 -415.028576) (xy 381.534236 -415.013224)
			(xy 381.588189 -415.005472) (xy 381.615442 -415.005012) (xy 382.479042 -415.005012) (xy 382.506293 -415.005461)
			(xy 382.560239 -415.013222) (xy 382.612531 -415.028582) (xy 382.662106 -415.051227) (xy 382.707953 -415.080696)
			(xy 382.749141 -415.116389) (xy 382.784829 -415.15758) (xy 382.814293 -415.203431) (xy 382.836933 -415.253008)
			(xy 382.852286 -415.305302) (xy 382.860042 -415.359249) (xy 382.860042 -415.413749) (xy 384.297698 -415.413749)
			(xy 384.297698 -415.359251) (xy 384.305454 -415.305308) (xy 384.320807 -415.253017) (xy 384.343446 -415.203444)
			(xy 384.372909 -415.157597) (xy 384.408597 -415.116409) (xy 384.449782 -415.08072) (xy 384.495628 -415.051254)
			(xy 384.5452 -415.028613) (xy 384.59749 -415.013258) (xy 384.651433 -415.005499) (xy 384.678682 -415.005012)
			(xy 385.542282 -415.005012) (xy 385.569537 -415.005434) (xy 385.623493 -415.013189) (xy 385.675796 -415.028544)
			(xy 385.725381 -415.051187) (xy 385.771239 -415.080656) (xy 385.812436 -415.116352) (xy 385.848133 -415.157547)
			(xy 385.877604 -415.203403) (xy 385.900249 -415.252987) (xy 385.915607 -415.305289) (xy 385.923365 -415.359245)
			(xy 385.923365 -415.413752) (xy 387.360875 -415.413752) (xy 387.360875 -415.359248) (xy 387.368632 -415.305298)
			(xy 387.383989 -415.253001) (xy 387.406632 -415.203422) (xy 387.4361 -415.15757) (xy 387.471794 -415.116379)
			(xy 387.512988 -415.080687) (xy 387.558841 -415.051221) (xy 387.608421 -415.028581) (xy 387.660719 -415.013228)
			(xy 387.71467 -415.005474) (xy 387.741922 -415.005012) (xy 388.605522 -415.005012) (xy 388.632774 -415.005459)
			(xy 388.686722 -415.013219) (xy 388.739017 -415.028577) (xy 388.788594 -415.05122) (xy 388.834444 -415.080689)
			(xy 388.875634 -415.116382) (xy 388.911325 -415.157574) (xy 388.94079 -415.203426) (xy 388.963431 -415.253004)
			(xy 388.978786 -415.3053) (xy 388.986542 -415.359248) (xy 388.986542 -415.413748) (xy 390.424198 -415.413748)
			(xy 390.424198 -415.359252) (xy 390.431953 -415.30531) (xy 390.447306 -415.253022) (xy 390.469943 -415.203449)
			(xy 390.499404 -415.157603) (xy 390.535089 -415.116416) (xy 390.576273 -415.080727) (xy 390.622116 -415.051261)
			(xy 390.671686 -415.028619) (xy 390.723973 -415.013261) (xy 390.777914 -415.005501) (xy 390.805162 -415.005012)
			(xy 391.668762 -415.005012) (xy 391.696018 -415.005432) (xy 391.749976 -415.013185) (xy 391.802281 -415.028539)
			(xy 391.851869 -415.05118) (xy 391.897729 -415.080649) (xy 391.938929 -415.116345) (xy 391.974628 -415.15754)
			(xy 392.004101 -415.203398) (xy 392.026748 -415.252983) (xy 392.042107 -415.305287) (xy 392.049865 -415.359244)
			(xy 392.049865 -415.413752) (xy 393.487375 -415.413752) (xy 393.487375 -415.359248) (xy 393.495132 -415.3053)
			(xy 393.510487 -415.253005) (xy 393.533129 -415.203427) (xy 393.562595 -415.157576) (xy 393.598287 -415.116386)
			(xy 393.639478 -415.080694) (xy 393.685329 -415.051228) (xy 393.734907 -415.028587) (xy 393.787202 -415.013231)
			(xy 393.84115 -415.005475) (xy 393.868402 -415.005012) (xy 394.732002 -415.005012) (xy 394.759255 -415.005458)
			(xy 394.813205 -415.013215) (xy 394.865502 -415.028571) (xy 394.915082 -415.051214) (xy 394.960934 -415.080682)
			(xy 395.002126 -415.116375) (xy 395.03782 -415.157567) (xy 395.067287 -415.20342) (xy 395.089929 -415.253)
			(xy 395.105285 -415.305297) (xy 395.113042 -415.359247) (xy 395.113042 -415.413753) (xy 396.550575 -415.413753)
			(xy 396.550575 -415.359247) (xy 396.558333 -415.305295) (xy 396.57369 -415.252996) (xy 396.596335 -415.203416)
			(xy 396.625805 -415.157563) (xy 396.661501 -415.116372) (xy 396.702697 -415.08068) (xy 396.748553 -415.051215)
			(xy 396.798136 -415.028576) (xy 396.850436 -415.013224) (xy 396.904389 -415.005472) (xy 396.931642 -415.005012)
			(xy 397.795242 -415.005012) (xy 397.822493 -415.005461) (xy 397.876439 -415.013222) (xy 397.928731 -415.028582)
			(xy 397.978306 -415.051227) (xy 398.024153 -415.080696) (xy 398.065341 -415.116389) (xy 398.101029 -415.15758)
			(xy 398.130493 -415.203431) (xy 398.153133 -415.253008) (xy 398.168486 -415.305302) (xy 398.176242 -415.359249)
			(xy 398.176242 -415.413749) (xy 399.613898 -415.413749) (xy 399.613898 -415.359251) (xy 399.621654 -415.305308)
			(xy 399.637007 -415.253017) (xy 399.659646 -415.203444) (xy 399.689109 -415.157597) (xy 399.724797 -415.116409)
			(xy 399.765982 -415.08072) (xy 399.811828 -415.051254) (xy 399.8614 -415.028613) (xy 399.91369 -415.013258)
			(xy 399.967633 -415.005499) (xy 399.994882 -415.005012) (xy 400.858482 -415.005012) (xy 400.885737 -415.005434)
			(xy 400.939693 -415.013189) (xy 400.991996 -415.028544) (xy 401.041581 -415.051187) (xy 401.087439 -415.080656)
			(xy 401.128636 -415.116352) (xy 401.164333 -415.157547) (xy 401.193804 -415.203403) (xy 401.216449 -415.252987)
			(xy 401.231807 -415.305289) (xy 401.239565 -415.359245) (xy 401.239565 -415.413752) (xy 402.677075 -415.413752)
			(xy 402.677075 -415.359248) (xy 402.684832 -415.305298) (xy 402.700189 -415.253001) (xy 402.722832 -415.203422)
			(xy 402.7523 -415.15757) (xy 402.787994 -415.116379) (xy 402.829188 -415.080687) (xy 402.875041 -415.051221)
			(xy 402.924621 -415.028581) (xy 402.976919 -415.013228) (xy 403.03087 -415.005474) (xy 403.058122 -415.005012)
			(xy 403.921722 -415.005012) (xy 403.948974 -415.005459) (xy 404.002922 -415.013219) (xy 404.055217 -415.028577)
			(xy 404.104794 -415.05122) (xy 404.150644 -415.080689) (xy 404.191834 -415.116382) (xy 404.227525 -415.157574)
			(xy 404.25699 -415.203426) (xy 404.279631 -415.253004) (xy 404.294986 -415.3053) (xy 404.302742 -415.359248)
			(xy 404.302742 -415.413748) (xy 405.740398 -415.413748) (xy 405.740398 -415.359252) (xy 405.748153 -415.30531)
			(xy 405.763506 -415.253022) (xy 405.786143 -415.203449) (xy 405.815604 -415.157603) (xy 405.851289 -415.116416)
			(xy 405.892473 -415.080727) (xy 405.938316 -415.051261) (xy 405.987886 -415.028619) (xy 406.040173 -415.013261)
			(xy 406.094114 -415.005501) (xy 406.121362 -415.005012) (xy 406.984962 -415.005012) (xy 407.012218 -415.005432)
			(xy 407.066176 -415.013185) (xy 407.118481 -415.028539) (xy 407.168069 -415.05118) (xy 407.213929 -415.080649)
			(xy 407.255129 -415.116345) (xy 407.290828 -415.15754) (xy 407.320301 -415.203398) (xy 407.342948 -415.252983)
			(xy 407.358307 -415.305287) (xy 407.366065 -415.359244) (xy 407.366065 -415.413752) (xy 408.803575 -415.413752)
			(xy 408.803575 -415.359248) (xy 408.811332 -415.3053) (xy 408.826687 -415.253005) (xy 408.849329 -415.203427)
			(xy 408.878795 -415.157576) (xy 408.914487 -415.116386) (xy 408.955678 -415.080694) (xy 409.001529 -415.051228)
			(xy 409.051107 -415.028587) (xy 409.103402 -415.013231) (xy 409.15735 -415.005475) (xy 409.184602 -415.005012)
			(xy 410.048202 -415.005012) (xy 410.075455 -415.005458) (xy 410.129405 -415.013215) (xy 410.181702 -415.028571)
			(xy 410.231282 -415.051214) (xy 410.277134 -415.080682) (xy 410.318326 -415.116375) (xy 410.35402 -415.157567)
			(xy 410.383487 -415.20342) (xy 410.406129 -415.253) (xy 410.421485 -415.305297) (xy 410.429242 -415.359247)
			(xy 410.429242 -415.413753) (xy 411.866775 -415.413753) (xy 411.866775 -415.359247) (xy 411.874533 -415.305295)
			(xy 411.88989 -415.252996) (xy 411.912535 -415.203416) (xy 411.942005 -415.157563) (xy 411.977701 -415.116372)
			(xy 412.018897 -415.08068) (xy 412.064753 -415.051215) (xy 412.114336 -415.028576) (xy 412.166636 -415.013224)
			(xy 412.220589 -415.005472) (xy 412.247842 -415.005012) (xy 413.111442 -415.005012) (xy 413.138693 -415.005461)
			(xy 413.192639 -415.013222) (xy 413.244931 -415.028582) (xy 413.294506 -415.051227) (xy 413.340353 -415.080696)
			(xy 413.381541 -415.116389) (xy 413.417229 -415.15758) (xy 413.446693 -415.203431) (xy 413.469333 -415.253008)
			(xy 413.484686 -415.305302) (xy 413.492442 -415.359249) (xy 413.492442 -415.413749) (xy 414.930098 -415.413749)
			(xy 414.930098 -415.359251) (xy 414.937854 -415.305308) (xy 414.953207 -415.253017) (xy 414.975846 -415.203444)
			(xy 415.005309 -415.157597) (xy 415.040997 -415.116409) (xy 415.082182 -415.08072) (xy 415.128028 -415.051254)
			(xy 415.1776 -415.028613) (xy 415.22989 -415.013258) (xy 415.283833 -415.005499) (xy 415.311082 -415.005012)
			(xy 416.174682 -415.005012) (xy 416.201937 -415.005434) (xy 416.255893 -415.013189) (xy 416.308196 -415.028544)
			(xy 416.357781 -415.051187) (xy 416.403639 -415.080656) (xy 416.444836 -415.116352) (xy 416.480533 -415.157547)
			(xy 416.510004 -415.203403) (xy 416.532649 -415.252987) (xy 416.548007 -415.305289) (xy 416.555765 -415.359245)
			(xy 416.555765 -415.413752) (xy 417.993275 -415.413752) (xy 417.993275 -415.359248) (xy 418.001032 -415.305298)
			(xy 418.016389 -415.253001) (xy 418.039032 -415.203422) (xy 418.0685 -415.15757) (xy 418.104194 -415.116379)
			(xy 418.145388 -415.080687) (xy 418.191241 -415.051221) (xy 418.240821 -415.028581) (xy 418.293119 -415.013228)
			(xy 418.34707 -415.005474) (xy 418.374322 -415.005012) (xy 419.237922 -415.005012) (xy 419.265174 -415.005459)
			(xy 419.319122 -415.013219) (xy 419.371417 -415.028577) (xy 419.420994 -415.05122) (xy 419.466844 -415.080689)
			(xy 419.508034 -415.116382) (xy 419.543725 -415.157574) (xy 419.57319 -415.203426) (xy 419.595831 -415.253004)
			(xy 419.611186 -415.3053) (xy 419.618942 -415.359248) (xy 419.618942 -415.413752) (xy 419.611186 -415.4677)
			(xy 419.595831 -415.519996) (xy 419.57319 -415.569574) (xy 419.543725 -415.615426) (xy 419.508034 -415.656618)
			(xy 419.466844 -415.692311) (xy 419.420994 -415.72178) (xy 419.371417 -415.744423) (xy 419.319122 -415.759781)
			(xy 419.265174 -415.767541) (xy 419.237922 -415.768028) (xy 418.374322 -415.768028) (xy 418.34707 -415.767526)
			(xy 418.293119 -415.759772) (xy 418.240821 -415.744419) (xy 418.191241 -415.721779) (xy 418.145388 -415.692313)
			(xy 418.104194 -415.656621) (xy 418.0685 -415.61543) (xy 418.039032 -415.569578) (xy 418.016389 -415.519999)
			(xy 418.001032 -415.467702) (xy 417.993275 -415.413752) (xy 416.555765 -415.413752) (xy 416.555765 -415.413755)
			(xy 416.548007 -415.467711) (xy 416.532649 -415.520013) (xy 416.510004 -415.569597) (xy 416.480533 -415.615453)
			(xy 416.444836 -415.656648) (xy 416.403639 -415.692344) (xy 416.357781 -415.721813) (xy 416.308196 -415.744456)
			(xy 416.255893 -415.759811) (xy 416.201937 -415.767566) (xy 416.174682 -415.768028) (xy 415.311082 -415.768028)
			(xy 415.283833 -415.767501) (xy 415.22989 -415.759742) (xy 415.1776 -415.744387) (xy 415.128028 -415.721746)
			(xy 415.082182 -415.69228) (xy 415.040997 -415.656591) (xy 415.005309 -415.615403) (xy 414.975846 -415.569556)
			(xy 414.953207 -415.519983) (xy 414.937854 -415.467692) (xy 414.930098 -415.413749) (xy 413.492442 -415.413749)
			(xy 413.492442 -415.413751) (xy 413.484686 -415.467698) (xy 413.469333 -415.519992) (xy 413.446693 -415.569569)
			(xy 413.417229 -415.61542) (xy 413.381541 -415.656611) (xy 413.340353 -415.692304) (xy 413.294506 -415.721773)
			(xy 413.244931 -415.744418) (xy 413.192639 -415.759778) (xy 413.138693 -415.767539) (xy 413.111442 -415.768028)
			(xy 412.247842 -415.768028) (xy 412.220589 -415.767528) (xy 412.166636 -415.759776) (xy 412.114336 -415.744424)
			(xy 412.064753 -415.721785) (xy 412.018897 -415.69232) (xy 411.977701 -415.656628) (xy 411.942005 -415.615437)
			(xy 411.912535 -415.569584) (xy 411.88989 -415.520004) (xy 411.874533 -415.467705) (xy 411.866775 -415.413753)
			(xy 410.429242 -415.413753) (xy 410.421485 -415.467703) (xy 410.406129 -415.52) (xy 410.383487 -415.56958)
			(xy 410.35402 -415.615433) (xy 410.318326 -415.656625) (xy 410.277134 -415.692318) (xy 410.231282 -415.721786)
			(xy 410.181702 -415.744429) (xy 410.129405 -415.759785) (xy 410.075455 -415.767542) (xy 410.048202 -415.768028)
			(xy 409.184602 -415.768028) (xy 409.15735 -415.767525) (xy 409.103402 -415.759769) (xy 409.051107 -415.744413)
			(xy 409.001529 -415.721772) (xy 408.955678 -415.692306) (xy 408.914487 -415.656614) (xy 408.878795 -415.615424)
			(xy 408.849329 -415.569573) (xy 408.826687 -415.519995) (xy 408.811332 -415.4677) (xy 408.803575 -415.413752)
			(xy 407.366065 -415.413752) (xy 407.366065 -415.413756) (xy 407.358307 -415.467713) (xy 407.342948 -415.520017)
			(xy 407.320301 -415.569602) (xy 407.290828 -415.61546) (xy 407.255129 -415.656655) (xy 407.213929 -415.692351)
			(xy 407.168069 -415.72182) (xy 407.118481 -415.744461) (xy 407.066176 -415.759815) (xy 407.012218 -415.767568)
			(xy 406.984962 -415.768028) (xy 406.121362 -415.768028) (xy 406.094114 -415.767499) (xy 406.040173 -415.759739)
			(xy 405.987886 -415.744381) (xy 405.938316 -415.721739) (xy 405.892473 -415.692273) (xy 405.851289 -415.656584)
			(xy 405.815604 -415.615397) (xy 405.786143 -415.569551) (xy 405.763506 -415.519978) (xy 405.748153 -415.46769)
			(xy 405.740398 -415.413748) (xy 404.302742 -415.413748) (xy 404.302742 -415.413752) (xy 404.294986 -415.4677)
			(xy 404.279631 -415.519996) (xy 404.25699 -415.569574) (xy 404.227525 -415.615426) (xy 404.191834 -415.656618)
			(xy 404.150644 -415.692311) (xy 404.104794 -415.72178) (xy 404.055217 -415.744423) (xy 404.002922 -415.759781)
			(xy 403.948974 -415.767541) (xy 403.921722 -415.768028) (xy 403.058122 -415.768028) (xy 403.03087 -415.767526)
			(xy 402.976919 -415.759772) (xy 402.924621 -415.744419) (xy 402.875041 -415.721779) (xy 402.829188 -415.692313)
			(xy 402.787994 -415.656621) (xy 402.7523 -415.61543) (xy 402.722832 -415.569578) (xy 402.700189 -415.519999)
			(xy 402.684832 -415.467702) (xy 402.677075 -415.413752) (xy 401.239565 -415.413752) (xy 401.239565 -415.413755)
			(xy 401.231807 -415.467711) (xy 401.216449 -415.520013) (xy 401.193804 -415.569597) (xy 401.164333 -415.615453)
			(xy 401.128636 -415.656648) (xy 401.087439 -415.692344) (xy 401.041581 -415.721813) (xy 400.991996 -415.744456)
			(xy 400.939693 -415.759811) (xy 400.885737 -415.767566) (xy 400.858482 -415.768028) (xy 399.994882 -415.768028)
			(xy 399.967633 -415.767501) (xy 399.91369 -415.759742) (xy 399.8614 -415.744387) (xy 399.811828 -415.721746)
			(xy 399.765982 -415.69228) (xy 399.724797 -415.656591) (xy 399.689109 -415.615403) (xy 399.659646 -415.569556)
			(xy 399.637007 -415.519983) (xy 399.621654 -415.467692) (xy 399.613898 -415.413749) (xy 398.176242 -415.413749)
			(xy 398.176242 -415.413751) (xy 398.168486 -415.467698) (xy 398.153133 -415.519992) (xy 398.130493 -415.569569)
			(xy 398.101029 -415.61542) (xy 398.065341 -415.656611) (xy 398.024153 -415.692304) (xy 397.978306 -415.721773)
			(xy 397.928731 -415.744418) (xy 397.876439 -415.759778) (xy 397.822493 -415.767539) (xy 397.795242 -415.768028)
			(xy 396.931642 -415.768028) (xy 396.904389 -415.767528) (xy 396.850436 -415.759776) (xy 396.798136 -415.744424)
			(xy 396.748553 -415.721785) (xy 396.702697 -415.69232) (xy 396.661501 -415.656628) (xy 396.625805 -415.615437)
			(xy 396.596335 -415.569584) (xy 396.57369 -415.520004) (xy 396.558333 -415.467705) (xy 396.550575 -415.413753)
			(xy 395.113042 -415.413753) (xy 395.105285 -415.467703) (xy 395.089929 -415.52) (xy 395.067287 -415.56958)
			(xy 395.03782 -415.615433) (xy 395.002126 -415.656625) (xy 394.960934 -415.692318) (xy 394.915082 -415.721786)
			(xy 394.865502 -415.744429) (xy 394.813205 -415.759785) (xy 394.759255 -415.767542) (xy 394.732002 -415.768028)
			(xy 393.868402 -415.768028) (xy 393.84115 -415.767525) (xy 393.787202 -415.759769) (xy 393.734907 -415.744413)
			(xy 393.685329 -415.721772) (xy 393.639478 -415.692306) (xy 393.598287 -415.656614) (xy 393.562595 -415.615424)
			(xy 393.533129 -415.569573) (xy 393.510487 -415.519995) (xy 393.495132 -415.4677) (xy 393.487375 -415.413752)
			(xy 392.049865 -415.413752) (xy 392.049865 -415.413756) (xy 392.042107 -415.467713) (xy 392.026748 -415.520017)
			(xy 392.004101 -415.569602) (xy 391.974628 -415.61546) (xy 391.938929 -415.656655) (xy 391.897729 -415.692351)
			(xy 391.851869 -415.72182) (xy 391.802281 -415.744461) (xy 391.749976 -415.759815) (xy 391.696018 -415.767568)
			(xy 391.668762 -415.768028) (xy 390.805162 -415.768028) (xy 390.777914 -415.767499) (xy 390.723973 -415.759739)
			(xy 390.671686 -415.744381) (xy 390.622116 -415.721739) (xy 390.576273 -415.692273) (xy 390.535089 -415.656584)
			(xy 390.499404 -415.615397) (xy 390.469943 -415.569551) (xy 390.447306 -415.519978) (xy 390.431953 -415.46769)
			(xy 390.424198 -415.413748) (xy 388.986542 -415.413748) (xy 388.986542 -415.413752) (xy 388.978786 -415.4677)
			(xy 388.963431 -415.519996) (xy 388.94079 -415.569574) (xy 388.911325 -415.615426) (xy 388.875634 -415.656618)
			(xy 388.834444 -415.692311) (xy 388.788594 -415.72178) (xy 388.739017 -415.744423) (xy 388.686722 -415.759781)
			(xy 388.632774 -415.767541) (xy 388.605522 -415.768028) (xy 387.741922 -415.768028) (xy 387.71467 -415.767526)
			(xy 387.660719 -415.759772) (xy 387.608421 -415.744419) (xy 387.558841 -415.721779) (xy 387.512988 -415.692313)
			(xy 387.471794 -415.656621) (xy 387.4361 -415.61543) (xy 387.406632 -415.569578) (xy 387.383989 -415.519999)
			(xy 387.368632 -415.467702) (xy 387.360875 -415.413752) (xy 385.923365 -415.413752) (xy 385.923365 -415.413755)
			(xy 385.915607 -415.467711) (xy 385.900249 -415.520013) (xy 385.877604 -415.569597) (xy 385.848133 -415.615453)
			(xy 385.812436 -415.656648) (xy 385.771239 -415.692344) (xy 385.725381 -415.721813) (xy 385.675796 -415.744456)
			(xy 385.623493 -415.759811) (xy 385.569537 -415.767566) (xy 385.542282 -415.768028) (xy 384.678682 -415.768028)
			(xy 384.651433 -415.767501) (xy 384.59749 -415.759742) (xy 384.5452 -415.744387) (xy 384.495628 -415.721746)
			(xy 384.449782 -415.69228) (xy 384.408597 -415.656591) (xy 384.372909 -415.615403) (xy 384.343446 -415.569556)
			(xy 384.320807 -415.519983) (xy 384.305454 -415.467692) (xy 384.297698 -415.413749) (xy 382.860042 -415.413749)
			(xy 382.860042 -415.413751) (xy 382.852286 -415.467698) (xy 382.836933 -415.519992) (xy 382.814293 -415.569569)
			(xy 382.784829 -415.61542) (xy 382.749141 -415.656611) (xy 382.707953 -415.692304) (xy 382.662106 -415.721773)
			(xy 382.612531 -415.744418) (xy 382.560239 -415.759778) (xy 382.506293 -415.767539) (xy 382.479042 -415.768028)
			(xy 381.615442 -415.768028) (xy 381.588189 -415.767528) (xy 381.534236 -415.759776) (xy 381.481936 -415.744424)
			(xy 381.432353 -415.721785) (xy 381.386497 -415.69232) (xy 381.345301 -415.656628) (xy 381.309605 -415.615437)
			(xy 381.280135 -415.569584) (xy 381.25749 -415.520004) (xy 381.242133 -415.467705) (xy 381.234375 -415.413753)
			(xy 379.796842 -415.413753) (xy 379.789085 -415.467703) (xy 379.773729 -415.52) (xy 379.751087 -415.56958)
			(xy 379.72162 -415.615433) (xy 379.685926 -415.656625) (xy 379.644734 -415.692318) (xy 379.598882 -415.721786)
			(xy 379.549302 -415.744429) (xy 379.497005 -415.759785) (xy 379.443055 -415.767542) (xy 379.415802 -415.768028)
			(xy 378.552202 -415.768028) (xy 378.52495 -415.767525) (xy 378.471002 -415.759769) (xy 378.418707 -415.744413)
			(xy 378.369129 -415.721772) (xy 378.323278 -415.692306) (xy 378.282087 -415.656614) (xy 378.246395 -415.615424)
			(xy 378.216929 -415.569573) (xy 378.194287 -415.519995) (xy 378.178932 -415.4677) (xy 378.171175 -415.413752)
			(xy 376.733665 -415.413752) (xy 376.733665 -415.413756) (xy 376.725907 -415.467713) (xy 376.710548 -415.520017)
			(xy 376.687901 -415.569602) (xy 376.658428 -415.61546) (xy 376.622729 -415.656655) (xy 376.581529 -415.692351)
			(xy 376.535669 -415.72182) (xy 376.486081 -415.744461) (xy 376.433776 -415.759815) (xy 376.379818 -415.767568)
			(xy 376.352562 -415.768028) (xy 375.488962 -415.768028) (xy 375.461714 -415.767499) (xy 375.407773 -415.759739)
			(xy 375.355486 -415.744381) (xy 375.305916 -415.721739) (xy 375.260073 -415.692273) (xy 375.218889 -415.656584)
			(xy 375.183204 -415.615397) (xy 375.153743 -415.569551) (xy 375.131106 -415.519978) (xy 375.115753 -415.46769)
			(xy 375.107998 -415.413748) (xy 373.670342 -415.413748) (xy 373.670342 -415.413752) (xy 373.662586 -415.4677)
			(xy 373.647231 -415.519996) (xy 373.62459 -415.569574) (xy 373.595125 -415.615426) (xy 373.559434 -415.656618)
			(xy 373.518244 -415.692311) (xy 373.472394 -415.72178) (xy 373.422817 -415.744423) (xy 373.370522 -415.759781)
			(xy 373.316574 -415.767541) (xy 373.289322 -415.768028) (xy 372.425722 -415.768028) (xy 372.39847 -415.767526)
			(xy 372.344519 -415.759772) (xy 372.292221 -415.744419) (xy 372.242641 -415.721779) (xy 372.196788 -415.692313)
			(xy 372.155594 -415.656621) (xy 372.1199 -415.61543) (xy 372.090432 -415.569578) (xy 372.067789 -415.519999)
			(xy 372.052432 -415.467702) (xy 372.044675 -415.413752) (xy 352.518742 -415.413752) (xy 352.510986 -415.4677)
			(xy 352.495631 -415.519995) (xy 352.472991 -415.569573) (xy 352.443526 -415.615425) (xy 352.407835 -415.656617)
			(xy 352.366646 -415.69231) (xy 352.320796 -415.721778) (xy 352.27122 -415.744422) (xy 352.218925 -415.75978)
			(xy 352.164977 -415.76754) (xy 352.137726 -415.768028) (xy 351.274126 -415.768028) (xy 351.246873 -415.767526)
			(xy 351.192922 -415.759773) (xy 351.140624 -415.74442) (xy 351.091043 -415.72178) (xy 351.045189 -415.692314)
			(xy 351.003996 -415.656623) (xy 350.968301 -415.615431) (xy 350.938832 -415.569579) (xy 350.916189 -415.52)
			(xy 350.900833 -415.467703) (xy 350.893075 -415.413753) (xy 349.455565 -415.413753) (xy 349.455565 -415.413755)
			(xy 349.447807 -415.46771) (xy 349.43245 -415.520012) (xy 349.409805 -415.569595) (xy 349.380334 -415.615452)
			(xy 349.344637 -415.656647) (xy 349.303441 -415.692343) (xy 349.257583 -415.721812) (xy 349.207999 -415.744455)
			(xy 349.155696 -415.75981) (xy 349.101741 -415.767566) (xy 349.074486 -415.768028) (xy 348.210886 -415.768028)
			(xy 348.183637 -415.767501) (xy 348.129694 -415.759743) (xy 348.077403 -415.744388) (xy 348.02783 -415.721747)
			(xy 347.981984 -415.692282) (xy 347.940798 -415.656592) (xy 347.90511 -415.615404) (xy 347.875646 -415.569557)
			(xy 347.853008 -415.519984) (xy 347.837654 -415.467693) (xy 347.829898 -415.413749) (xy 346.392242 -415.413749)
			(xy 346.392242 -415.413751) (xy 346.384487 -415.467697) (xy 346.369133 -415.519991) (xy 346.346494 -415.569568)
			(xy 346.31703 -415.615418) (xy 346.281342 -415.656609) (xy 346.240155 -415.692303) (xy 346.194308 -415.721772)
			(xy 346.144734 -415.744417) (xy 346.092442 -415.759777) (xy 346.038497 -415.767539) (xy 346.011246 -415.768028)
			(xy 345.147646 -415.768028) (xy 345.120392 -415.767528) (xy 345.066439 -415.759777) (xy 345.014139 -415.744425)
			(xy 344.964555 -415.721787) (xy 344.918699 -415.692321) (xy 344.877503 -415.65663) (xy 344.841806 -415.615438)
			(xy 344.812335 -415.569585) (xy 344.789691 -415.520004) (xy 344.774333 -415.467706) (xy 344.766575 -415.413754)
			(xy 343.329042 -415.413754) (xy 343.321285 -415.467702) (xy 343.30593 -415.519999) (xy 343.283288 -415.569579)
			(xy 343.253821 -415.615431) (xy 343.218128 -415.656624) (xy 343.176936 -415.692317) (xy 343.131084 -415.721785)
			(xy 343.081505 -415.744428) (xy 343.029208 -415.759784) (xy 342.975258 -415.767542) (xy 342.948006 -415.768028)
			(xy 342.084406 -415.768028) (xy 342.057154 -415.767525) (xy 342.003206 -415.759769) (xy 341.95091 -415.744415)
			(xy 341.901331 -415.721774) (xy 341.85548 -415.692307) (xy 341.814289 -415.656616) (xy 341.778596 -415.615425)
			(xy 341.749129 -415.569574) (xy 341.726488 -415.519996) (xy 341.711132 -415.4677) (xy 341.703375 -415.413752)
			(xy 340.265865 -415.413752) (xy 340.265865 -415.413756) (xy 340.258107 -415.467713) (xy 340.242748 -415.520016)
			(xy 340.220102 -415.569601) (xy 340.190629 -415.615458) (xy 340.15493 -415.656654) (xy 340.113731 -415.69235)
			(xy 340.067871 -415.721818) (xy 340.018284 -415.74446) (xy 339.965979 -415.759814) (xy 339.912022 -415.767567)
			(xy 339.884766 -415.768028) (xy 339.021166 -415.768028) (xy 338.993918 -415.767499) (xy 338.939977 -415.759739)
			(xy 338.887689 -415.744382) (xy 338.838118 -415.72174) (xy 338.792275 -415.692275) (xy 338.751091 -415.656585)
			(xy 338.715405 -415.615398) (xy 338.685943 -415.569552) (xy 338.663306 -415.519979) (xy 338.647953 -415.46769)
			(xy 338.640198 -415.413748) (xy 337.202542 -415.413748) (xy 337.202542 -415.413751) (xy 337.194786 -415.4677)
			(xy 337.179431 -415.519995) (xy 337.156791 -415.569573) (xy 337.127326 -415.615425) (xy 337.091635 -415.656617)
			(xy 337.050446 -415.69231) (xy 337.004596 -415.721778) (xy 336.95502 -415.744422) (xy 336.902725 -415.75978)
			(xy 336.848777 -415.76754) (xy 336.821526 -415.768028) (xy 335.957926 -415.768028) (xy 335.930673 -415.767526)
			(xy 335.876722 -415.759773) (xy 335.824424 -415.74442) (xy 335.774843 -415.72178) (xy 335.728989 -415.692314)
			(xy 335.687796 -415.656623) (xy 335.652101 -415.615431) (xy 335.622632 -415.569579) (xy 335.599989 -415.52)
			(xy 335.584633 -415.467703) (xy 335.576875 -415.413753) (xy 334.139365 -415.413753) (xy 334.139365 -415.413755)
			(xy 334.131607 -415.46771) (xy 334.11625 -415.520012) (xy 334.093605 -415.569595) (xy 334.064134 -415.615452)
			(xy 334.028437 -415.656647) (xy 333.987241 -415.692343) (xy 333.941383 -415.721812) (xy 333.891799 -415.744455)
			(xy 333.839496 -415.75981) (xy 333.785541 -415.767566) (xy 333.758286 -415.768028) (xy 332.894686 -415.768028)
			(xy 332.867437 -415.767501) (xy 332.813494 -415.759743) (xy 332.761203 -415.744388) (xy 332.71163 -415.721747)
			(xy 332.665784 -415.692282) (xy 332.624598 -415.656592) (xy 332.58891 -415.615404) (xy 332.559446 -415.569557)
			(xy 332.536808 -415.519984) (xy 332.521454 -415.467693) (xy 332.513698 -415.413749) (xy 331.076042 -415.413749)
			(xy 331.076042 -415.413751) (xy 331.068287 -415.467697) (xy 331.052933 -415.519991) (xy 331.030294 -415.569568)
			(xy 331.00083 -415.615418) (xy 330.965142 -415.656609) (xy 330.923955 -415.692303) (xy 330.878108 -415.721772)
			(xy 330.828534 -415.744417) (xy 330.776242 -415.759777) (xy 330.722297 -415.767539) (xy 330.695046 -415.768028)
			(xy 329.831446 -415.768028) (xy 329.804192 -415.767528) (xy 329.750239 -415.759777) (xy 329.697939 -415.744425)
			(xy 329.648355 -415.721787) (xy 329.602499 -415.692321) (xy 329.561303 -415.65663) (xy 329.525606 -415.615438)
			(xy 329.496135 -415.569585) (xy 329.473491 -415.520004) (xy 329.458133 -415.467706) (xy 329.450375 -415.413754)
			(xy 328.012842 -415.413754) (xy 328.005085 -415.467702) (xy 327.98973 -415.519999) (xy 327.967088 -415.569579)
			(xy 327.937621 -415.615431) (xy 327.901928 -415.656624) (xy 327.860736 -415.692317) (xy 327.814884 -415.721785)
			(xy 327.765305 -415.744428) (xy 327.713008 -415.759784) (xy 327.659058 -415.767542) (xy 327.631806 -415.768028)
			(xy 326.768206 -415.768028) (xy 326.740954 -415.767525) (xy 326.687006 -415.759769) (xy 326.63471 -415.744415)
			(xy 326.585131 -415.721774) (xy 326.53928 -415.692307) (xy 326.498089 -415.656616) (xy 326.462396 -415.615425)
			(xy 326.432929 -415.569574) (xy 326.410288 -415.519996) (xy 326.394932 -415.4677) (xy 326.387175 -415.413752)
			(xy 324.949665 -415.413752) (xy 324.949665 -415.413756) (xy 324.941907 -415.467713) (xy 324.926548 -415.520016)
			(xy 324.903902 -415.569601) (xy 324.874429 -415.615458) (xy 324.83873 -415.656654) (xy 324.797531 -415.69235)
			(xy 324.751671 -415.721818) (xy 324.702084 -415.74446) (xy 324.649779 -415.759814) (xy 324.595822 -415.767567)
			(xy 324.568566 -415.768028) (xy 323.704966 -415.768028) (xy 323.677718 -415.767499) (xy 323.623777 -415.759739)
			(xy 323.571489 -415.744382) (xy 323.521918 -415.72174) (xy 323.476075 -415.692275) (xy 323.434891 -415.656585)
			(xy 323.399205 -415.615398) (xy 323.369743 -415.569552) (xy 323.347106 -415.519979) (xy 323.331753 -415.46769)
			(xy 323.323998 -415.413748) (xy 321.886342 -415.413748) (xy 321.886342 -415.413751) (xy 321.878586 -415.4677)
			(xy 321.863231 -415.519995) (xy 321.840591 -415.569573) (xy 321.811126 -415.615425) (xy 321.775435 -415.656617)
			(xy 321.734246 -415.69231) (xy 321.688396 -415.721778) (xy 321.63882 -415.744422) (xy 321.586525 -415.75978)
			(xy 321.532577 -415.76754) (xy 321.505326 -415.768028) (xy 320.641726 -415.768028) (xy 320.614473 -415.767526)
			(xy 320.560522 -415.759773) (xy 320.508224 -415.74442) (xy 320.458643 -415.72178) (xy 320.412789 -415.692314)
			(xy 320.371596 -415.656623) (xy 320.335901 -415.615431) (xy 320.306432 -415.569579) (xy 320.283789 -415.52)
			(xy 320.268433 -415.467703) (xy 320.260675 -415.413753) (xy 318.823165 -415.413753) (xy 318.823165 -415.413755)
			(xy 318.815407 -415.46771) (xy 318.80005 -415.520012) (xy 318.777405 -415.569595) (xy 318.747934 -415.615452)
			(xy 318.712237 -415.656647) (xy 318.671041 -415.692343) (xy 318.625183 -415.721812) (xy 318.575599 -415.744455)
			(xy 318.523296 -415.75981) (xy 318.469341 -415.767566) (xy 318.442086 -415.768028) (xy 317.578486 -415.768028)
			(xy 317.551237 -415.767501) (xy 317.497294 -415.759743) (xy 317.445003 -415.744388) (xy 317.39543 -415.721747)
			(xy 317.349584 -415.692282) (xy 317.308398 -415.656592) (xy 317.27271 -415.615404) (xy 317.243246 -415.569557)
			(xy 317.220608 -415.519984) (xy 317.205254 -415.467693) (xy 317.197498 -415.413749) (xy 315.759842 -415.413749)
			(xy 315.759842 -415.413751) (xy 315.752087 -415.467697) (xy 315.736733 -415.519991) (xy 315.714094 -415.569568)
			(xy 315.68463 -415.615418) (xy 315.648942 -415.656609) (xy 315.607755 -415.692303) (xy 315.561908 -415.721772)
			(xy 315.512334 -415.744417) (xy 315.460042 -415.759777) (xy 315.406097 -415.767539) (xy 315.378846 -415.768028)
			(xy 314.515246 -415.768028) (xy 314.487992 -415.767528) (xy 314.434039 -415.759777) (xy 314.381739 -415.744425)
			(xy 314.332155 -415.721787) (xy 314.286299 -415.692321) (xy 314.245103 -415.65663) (xy 314.209406 -415.615438)
			(xy 314.179935 -415.569585) (xy 314.157291 -415.520004) (xy 314.141933 -415.467706) (xy 314.134175 -415.413754)
			(xy 312.696642 -415.413754) (xy 312.688885 -415.467702) (xy 312.67353 -415.519999) (xy 312.650888 -415.569579)
			(xy 312.621421 -415.615431) (xy 312.585728 -415.656624) (xy 312.544536 -415.692317) (xy 312.498684 -415.721785)
			(xy 312.449105 -415.744428) (xy 312.396808 -415.759784) (xy 312.342858 -415.767542) (xy 312.315606 -415.768028)
			(xy 311.452006 -415.768028) (xy 311.424754 -415.767525) (xy 311.370806 -415.759769) (xy 311.31851 -415.744415)
			(xy 311.268931 -415.721774) (xy 311.22308 -415.692307) (xy 311.181889 -415.656616) (xy 311.146196 -415.615425)
			(xy 311.116729 -415.569574) (xy 311.094088 -415.519996) (xy 311.078732 -415.4677) (xy 311.070975 -415.413752)
			(xy 309.633465 -415.413752) (xy 309.633465 -415.413756) (xy 309.625707 -415.467713) (xy 309.610348 -415.520016)
			(xy 309.587702 -415.569601) (xy 309.558229 -415.615458) (xy 309.52253 -415.656654) (xy 309.481331 -415.69235)
			(xy 309.435471 -415.721818) (xy 309.385884 -415.74446) (xy 309.333579 -415.759814) (xy 309.279622 -415.767567)
			(xy 309.252366 -415.768028) (xy 308.388766 -415.768028) (xy 308.361518 -415.767499) (xy 308.307577 -415.759739)
			(xy 308.255289 -415.744382) (xy 308.205718 -415.72174) (xy 308.159875 -415.692275) (xy 308.118691 -415.656585)
			(xy 308.083005 -415.615398) (xy 308.053543 -415.569552) (xy 308.030906 -415.519979) (xy 308.015553 -415.46769)
			(xy 308.007798 -415.413748) (xy 306.570142 -415.413748) (xy 306.570142 -415.413751) (xy 306.562386 -415.4677)
			(xy 306.547031 -415.519995) (xy 306.524391 -415.569573) (xy 306.494926 -415.615425) (xy 306.459235 -415.656617)
			(xy 306.418046 -415.69231) (xy 306.372196 -415.721778) (xy 306.32262 -415.744422) (xy 306.270325 -415.75978)
			(xy 306.216377 -415.76754) (xy 306.189126 -415.768028) (xy 305.325526 -415.768028) (xy 305.298273 -415.767526)
			(xy 305.244322 -415.759773) (xy 305.192024 -415.74442) (xy 305.142443 -415.72178) (xy 305.096589 -415.692314)
			(xy 305.055396 -415.656623) (xy 305.019701 -415.615431) (xy 304.990232 -415.569579) (xy 304.967589 -415.52)
			(xy 304.952233 -415.467703) (xy 304.944475 -415.413753) (xy 300.882586 -415.413753) (xy 300.868941 -415.434612)
			(xy 300.76479 -415.579315) (xy 300.654297 -415.719235) (xy 300.53768 -415.854094) (xy 300.415171 -415.983624)
			(xy 300.287014 -416.107568) (xy 300.153463 -416.22568) (xy 300.014783 -416.337725) (xy 299.871249 -416.443482)
			(xy 299.723146 -416.542739) (xy 299.570769 -416.635301) (xy 299.41442 -416.720982) (xy 299.254409 -416.799614)
			(xy 299.091055 -416.87104) (xy 298.92468 -416.935118) (xy 298.755617 -416.99172) (xy 298.5842 -417.040736)
			(xy 298.410769 -417.082066) (xy 298.235669 -417.11563) (xy 298.059249 -417.14136) (xy 297.881857 -417.159206)
			(xy 297.703846 -417.169132) (xy 297.525569 -417.171118) (xy 297.347382 -417.165161) (xy 297.169636 -417.151271)
			(xy 296.992686 -417.129478) (xy 296.816882 -417.099824) (xy 296.642574 -417.062367) (xy 296.470107 -417.017183)
			(xy 296.299824 -416.964361) (xy 296.132063 -416.904005) (xy 295.967158 -416.836237) (xy 295.805435 -416.761189)
			(xy 295.647216 -416.679012) (xy 295.492815 -416.589869) (xy 295.342538 -416.493935) (xy 295.196683 -416.391403)
			(xy 295.055541 -416.282475) (xy 294.919392 -416.167368) (xy 294.788505 -416.04631) (xy 294.663141 -415.919541)
			(xy 294.543548 -415.787314) (xy 294.429965 -415.649891) (xy 294.322616 -415.507544) (xy 294.221715 -415.360556)
			(xy 294.127462 -415.20922) (xy 294.040044 -415.053835) (xy 293.959634 -414.89471) (xy 293.886393 -414.732161)
			(xy 293.820466 -414.566511) (xy 293.761983 -414.398089) (xy 293.711061 -414.227228) (xy 293.667801 -414.054269)
			(xy 293.632289 -413.879554) (xy 293.604595 -413.70343) (xy 293.584774 -413.526248) (xy 293.572866 -413.348359)
			(xy 293.568894 -413.170116) (xy 276.749256 -413.170116) (xy 272.414746 -417.504626) (xy 272.396783 -417.521953)
			(xy 272.356401 -417.55128) (xy 272.311928 -417.573928) (xy 272.264459 -417.589339) (xy 272.215164 -417.597133)
			(xy 272.19021 -417.59759) (xy 235.05033 -417.59759) (xy 235.040259 -417.598007) (xy 235.02166 -417.605731)
			(xy 235.014262 -417.612576) (xy 233.545126 -419.081712) (xy 276.721824 -419.081712) (xy 276.721824 -418.218112)
			(xy 276.72231 -418.190861) (xy 276.730066 -418.136913) (xy 276.745421 -418.084618) (xy 276.768063 -418.035041)
			(xy 276.797529 -417.989191) (xy 276.83322 -417.948) (xy 276.874411 -417.912309) (xy 276.920261 -417.882843)
			(xy 276.969838 -417.860201) (xy 277.022133 -417.844846) (xy 277.076081 -417.83709) (xy 277.130583 -417.83709)
			(xy 277.184531 -417.844846) (xy 277.236826 -417.860201) (xy 277.286403 -417.882843) (xy 277.332253 -417.912309)
			(xy 277.373444 -417.948) (xy 277.409135 -417.989191) (xy 277.438601 -418.035041) (xy 277.461243 -418.084618)
			(xy 277.476598 -418.136913) (xy 277.484354 -418.190861) (xy 277.48484 -418.218112) (xy 277.48484 -418.254688)
			(xy 289.453828 -418.254688) (xy 289.453828 -417.391088) (xy 289.454314 -417.363837) (xy 289.46207 -417.309889)
			(xy 289.477425 -417.257594) (xy 289.500067 -417.208017) (xy 289.529533 -417.162167) (xy 289.565224 -417.120976)
			(xy 289.606415 -417.085285) (xy 289.652265 -417.055819) (xy 289.701842 -417.033177) (xy 289.754137 -417.017822)
			(xy 289.808085 -417.010066) (xy 289.862587 -417.010066) (xy 289.916535 -417.017822) (xy 289.96883 -417.033177)
			(xy 290.018407 -417.055819) (xy 290.064257 -417.085285) (xy 290.105448 -417.120976) (xy 290.141139 -417.162167)
			(xy 290.170605 -417.208017) (xy 290.193247 -417.257594) (xy 290.208602 -417.309889) (xy 290.216358 -417.363837)
			(xy 290.216844 -417.391088) (xy 290.216844 -418.254688) (xy 290.216358 -418.281939) (xy 290.208602 -418.335887)
			(xy 290.193247 -418.388182) (xy 290.170605 -418.437759) (xy 290.169514 -418.439456) (xy 304.944423 -418.439456)
			(xy 304.944423 -418.384944) (xy 304.952181 -418.330986) (xy 304.96754 -418.278681) (xy 304.990186 -418.229095)
			(xy 305.019659 -418.183237) (xy 305.055359 -418.14204) (xy 305.096558 -418.106344) (xy 305.142418 -418.076874)
			(xy 305.192006 -418.054231) (xy 305.244311 -418.038876) (xy 305.29827 -418.031121) (xy 305.325526 -418.03066)
			(xy 306.189126 -418.03066) (xy 306.216374 -418.031212) (xy 306.270314 -418.038971) (xy 306.322601 -418.054327)
			(xy 306.372171 -418.076968) (xy 306.418014 -418.106432) (xy 306.459198 -418.142121) (xy 306.494884 -418.183307)
			(xy 306.524345 -418.229152) (xy 306.546982 -418.278723) (xy 306.562335 -418.331011) (xy 306.57009 -418.384952)
			(xy 306.57009 -418.439448) (xy 306.570089 -418.439452) (xy 308.007746 -418.439452) (xy 308.007746 -418.384948)
			(xy 308.015502 -418.330999) (xy 308.030857 -418.278702) (xy 308.053497 -418.229123) (xy 308.082963 -418.183271)
			(xy 308.118654 -418.142078) (xy 308.159843 -418.106383) (xy 308.205693 -418.076914) (xy 308.25527 -418.054269)
			(xy 308.307565 -418.038909) (xy 308.361514 -418.031148) (xy 308.388766 -418.03066) (xy 309.252366 -418.03066)
			(xy 309.279618 -418.031185) (xy 309.333568 -418.038937) (xy 309.385866 -418.054289) (xy 309.435446 -418.076928)
			(xy 309.4813 -418.106392) (xy 309.522493 -418.142083) (xy 309.558187 -418.183273) (xy 309.587656 -418.229124)
			(xy 309.610299 -418.278702) (xy 309.625655 -418.330999) (xy 309.633413 -418.384948) (xy 309.633413 -418.439452)
			(xy 309.633413 -418.439455) (xy 311.070923 -418.439455) (xy 311.070923 -418.384945) (xy 311.078681 -418.330989)
			(xy 311.094038 -418.278686) (xy 311.116683 -418.229101) (xy 311.146154 -418.183244) (xy 311.181852 -418.142047)
			(xy 311.223049 -418.106351) (xy 311.268906 -418.07688) (xy 311.318491 -418.054236) (xy 311.370794 -418.038879)
			(xy 311.424751 -418.031123) (xy 311.452006 -418.03066) (xy 312.315606 -418.03066) (xy 312.342855 -418.031211)
			(xy 312.396797 -418.038967) (xy 312.449087 -418.054321) (xy 312.498659 -418.076961) (xy 312.544505 -418.106425)
			(xy 312.585691 -418.142113) (xy 312.621379 -418.1833) (xy 312.650842 -418.229146) (xy 312.673481 -418.278719)
			(xy 312.688834 -418.331009) (xy 312.69659 -418.384951) (xy 312.69659 -418.439449) (xy 312.696589 -418.439457)
			(xy 314.134123 -418.439457) (xy 314.134123 -418.384943) (xy 314.141882 -418.330983) (xy 314.157242 -418.278677)
			(xy 314.179889 -418.22909) (xy 314.209364 -418.183231) (xy 314.245066 -418.142033) (xy 314.286267 -418.106337)
			(xy 314.33213 -418.076867) (xy 314.38172 -418.054225) (xy 314.434028 -418.038872) (xy 314.487989 -418.03112)
			(xy 314.515246 -418.03066) (xy 315.378846 -418.03066) (xy 315.406093 -418.031213) (xy 315.460031 -418.038975)
			(xy 315.512316 -418.054332) (xy 315.561883 -418.076974) (xy 315.607724 -418.106439) (xy 315.648905 -418.142128)
			(xy 315.684588 -418.183313) (xy 315.714048 -418.229157) (xy 315.736684 -418.278727) (xy 315.752035 -418.331014)
			(xy 315.75979 -418.384953) (xy 315.75979 -418.439447) (xy 315.759789 -418.439453) (xy 317.197446 -418.439453)
			(xy 317.197446 -418.384947) (xy 317.205203 -418.330996) (xy 317.220558 -418.278698) (xy 317.2432 -418.229118)
			(xy 317.272668 -418.183264) (xy 317.308361 -418.142071) (xy 317.349553 -418.106376) (xy 317.395405 -418.076907)
			(xy 317.444985 -418.054263) (xy 317.497282 -418.038906) (xy 317.551233 -418.031147) (xy 317.578486 -418.03066)
			(xy 318.442086 -418.03066) (xy 318.469337 -418.031186) (xy 318.523285 -418.038941) (xy 318.57558 -418.054295)
			(xy 318.625158 -418.076934) (xy 318.671009 -418.106399) (xy 318.7122 -418.14209) (xy 318.747892 -418.18328)
			(xy 318.777359 -418.22913) (xy 318.800001 -418.278707) (xy 318.815356 -418.331001) (xy 318.823113 -418.384949)
			(xy 318.823113 -418.439451) (xy 318.823112 -418.439456) (xy 320.260623 -418.439456) (xy 320.260623 -418.384944)
			(xy 320.268381 -418.330986) (xy 320.28374 -418.278681) (xy 320.306386 -418.229095) (xy 320.335859 -418.183237)
			(xy 320.371559 -418.14204) (xy 320.412758 -418.106344) (xy 320.458618 -418.076874) (xy 320.508206 -418.054231)
			(xy 320.560511 -418.038876) (xy 320.61447 -418.031121) (xy 320.641726 -418.03066) (xy 321.505326 -418.03066)
			(xy 321.532574 -418.031212) (xy 321.586514 -418.038971) (xy 321.638801 -418.054327) (xy 321.688371 -418.076968)
			(xy 321.734214 -418.106432) (xy 321.775398 -418.142121) (xy 321.811084 -418.183307) (xy 321.840545 -418.229152)
			(xy 321.863182 -418.278723) (xy 321.878535 -418.331011) (xy 321.88629 -418.384952) (xy 321.88629 -418.439448)
			(xy 321.886289 -418.439452) (xy 323.323946 -418.439452) (xy 323.323946 -418.384948) (xy 323.331702 -418.330999)
			(xy 323.347057 -418.278702) (xy 323.369697 -418.229123) (xy 323.399163 -418.183271) (xy 323.434854 -418.142078)
			(xy 323.476043 -418.106383) (xy 323.521893 -418.076914) (xy 323.57147 -418.054269) (xy 323.623765 -418.038909)
			(xy 323.677714 -418.031148) (xy 323.704966 -418.03066) (xy 324.568566 -418.03066) (xy 324.595818 -418.031185)
			(xy 324.649768 -418.038937) (xy 324.702066 -418.054289) (xy 324.751646 -418.076928) (xy 324.7975 -418.106392)
			(xy 324.838693 -418.142083) (xy 324.874387 -418.183273) (xy 324.903856 -418.229124) (xy 324.926499 -418.278702)
			(xy 324.941855 -418.330999) (xy 324.949613 -418.384948) (xy 324.949613 -418.439452) (xy 324.949613 -418.439455)
			(xy 326.387123 -418.439455) (xy 326.387123 -418.384945) (xy 326.394881 -418.330989) (xy 326.410238 -418.278686)
			(xy 326.432883 -418.229101) (xy 326.462354 -418.183244) (xy 326.498052 -418.142047) (xy 326.539249 -418.106351)
			(xy 326.585106 -418.07688) (xy 326.634691 -418.054236) (xy 326.686994 -418.038879) (xy 326.740951 -418.031123)
			(xy 326.768206 -418.03066) (xy 327.631806 -418.03066) (xy 327.659055 -418.031211) (xy 327.712997 -418.038967)
			(xy 327.765287 -418.054321) (xy 327.814859 -418.076961) (xy 327.860705 -418.106425) (xy 327.901891 -418.142113)
			(xy 327.937579 -418.1833) (xy 327.967042 -418.229146) (xy 327.989681 -418.278719) (xy 328.005034 -418.331009)
			(xy 328.01279 -418.384951) (xy 328.01279 -418.439449) (xy 328.012789 -418.439457) (xy 329.450323 -418.439457)
			(xy 329.450323 -418.384943) (xy 329.458082 -418.330983) (xy 329.473442 -418.278677) (xy 329.496089 -418.22909)
			(xy 329.525564 -418.183231) (xy 329.561266 -418.142033) (xy 329.602467 -418.106337) (xy 329.64833 -418.076867)
			(xy 329.69792 -418.054225) (xy 329.750228 -418.038872) (xy 329.804189 -418.03112) (xy 329.831446 -418.03066)
			(xy 330.695046 -418.03066) (xy 330.722293 -418.031213) (xy 330.776231 -418.038975) (xy 330.828516 -418.054332)
			(xy 330.878083 -418.076974) (xy 330.923924 -418.106439) (xy 330.965105 -418.142128) (xy 331.000788 -418.183313)
			(xy 331.030248 -418.229157) (xy 331.052884 -418.278727) (xy 331.068235 -418.331014) (xy 331.07599 -418.384953)
			(xy 331.07599 -418.439447) (xy 331.075989 -418.439453) (xy 332.513646 -418.439453) (xy 332.513646 -418.384947)
			(xy 332.521403 -418.330996) (xy 332.536758 -418.278698) (xy 332.5594 -418.229118) (xy 332.588868 -418.183264)
			(xy 332.624561 -418.142071) (xy 332.665753 -418.106376) (xy 332.711605 -418.076907) (xy 332.761185 -418.054263)
			(xy 332.813482 -418.038906) (xy 332.867433 -418.031147) (xy 332.894686 -418.03066) (xy 333.758286 -418.03066)
			(xy 333.785537 -418.031186) (xy 333.839485 -418.038941) (xy 333.89178 -418.054295) (xy 333.941358 -418.076934)
			(xy 333.987209 -418.106399) (xy 334.0284 -418.14209) (xy 334.064092 -418.18328) (xy 334.093559 -418.22913)
			(xy 334.116201 -418.278707) (xy 334.131556 -418.331001) (xy 334.139313 -418.384949) (xy 334.139313 -418.439451)
			(xy 334.139312 -418.439456) (xy 335.576823 -418.439456) (xy 335.576823 -418.384944) (xy 335.584581 -418.330986)
			(xy 335.59994 -418.278681) (xy 335.622586 -418.229095) (xy 335.652059 -418.183237) (xy 335.687759 -418.14204)
			(xy 335.728958 -418.106344) (xy 335.774818 -418.076874) (xy 335.824406 -418.054231) (xy 335.876711 -418.038876)
			(xy 335.93067 -418.031121) (xy 335.957926 -418.03066) (xy 336.821526 -418.03066) (xy 336.848774 -418.031212)
			(xy 336.902714 -418.038971) (xy 336.955001 -418.054327) (xy 337.004571 -418.076968) (xy 337.050414 -418.106432)
			(xy 337.091598 -418.142121) (xy 337.127284 -418.183307) (xy 337.156745 -418.229152) (xy 337.179382 -418.278723)
			(xy 337.194735 -418.331011) (xy 337.20249 -418.384952) (xy 337.20249 -418.439448) (xy 337.202489 -418.439452)
			(xy 338.640146 -418.439452) (xy 338.640146 -418.384948) (xy 338.647902 -418.330999) (xy 338.663257 -418.278702)
			(xy 338.685897 -418.229123) (xy 338.715363 -418.183271) (xy 338.751054 -418.142078) (xy 338.792243 -418.106383)
			(xy 338.838093 -418.076914) (xy 338.88767 -418.054269) (xy 338.939965 -418.038909) (xy 338.993914 -418.031148)
			(xy 339.021166 -418.03066) (xy 339.884766 -418.03066) (xy 339.912018 -418.031185) (xy 339.965968 -418.038937)
			(xy 340.018266 -418.054289) (xy 340.067846 -418.076928) (xy 340.1137 -418.106392) (xy 340.154893 -418.142083)
			(xy 340.190587 -418.183273) (xy 340.220056 -418.229124) (xy 340.242699 -418.278702) (xy 340.258055 -418.330999)
			(xy 340.265813 -418.384948) (xy 340.265813 -418.439452) (xy 340.265813 -418.439455) (xy 341.703323 -418.439455)
			(xy 341.703323 -418.384945) (xy 341.711081 -418.330989) (xy 341.726438 -418.278686) (xy 341.749083 -418.229101)
			(xy 341.778554 -418.183244) (xy 341.814252 -418.142047) (xy 341.855449 -418.106351) (xy 341.901306 -418.07688)
			(xy 341.950891 -418.054236) (xy 342.003194 -418.038879) (xy 342.057151 -418.031123) (xy 342.084406 -418.03066)
			(xy 342.948006 -418.03066) (xy 342.975255 -418.031211) (xy 343.029197 -418.038967) (xy 343.081487 -418.054321)
			(xy 343.131059 -418.076961) (xy 343.176905 -418.106425) (xy 343.218091 -418.142113) (xy 343.253779 -418.1833)
			(xy 343.283242 -418.229146) (xy 343.305881 -418.278719) (xy 343.321234 -418.331009) (xy 343.32899 -418.384951)
			(xy 343.32899 -418.439449) (xy 343.328989 -418.439457) (xy 344.766523 -418.439457) (xy 344.766523 -418.384943)
			(xy 344.774282 -418.330983) (xy 344.789642 -418.278677) (xy 344.812289 -418.22909) (xy 344.841764 -418.183231)
			(xy 344.877466 -418.142033) (xy 344.918667 -418.106337) (xy 344.96453 -418.076867) (xy 345.01412 -418.054225)
			(xy 345.066428 -418.038872) (xy 345.120389 -418.03112) (xy 345.147646 -418.03066) (xy 346.011246 -418.03066)
			(xy 346.038493 -418.031213) (xy 346.092431 -418.038975) (xy 346.144716 -418.054332) (xy 346.194283 -418.076974)
			(xy 346.240124 -418.106439) (xy 346.281305 -418.142128) (xy 346.316988 -418.183313) (xy 346.346448 -418.229157)
			(xy 346.369084 -418.278727) (xy 346.384435 -418.331014) (xy 346.39219 -418.384953) (xy 346.39219 -418.439447)
			(xy 346.392189 -418.439453) (xy 347.829846 -418.439453) (xy 347.829846 -418.384947) (xy 347.837603 -418.330996)
			(xy 347.852958 -418.278698) (xy 347.8756 -418.229118) (xy 347.905068 -418.183264) (xy 347.940761 -418.142071)
			(xy 347.981953 -418.106376) (xy 348.027805 -418.076907) (xy 348.077385 -418.054263) (xy 348.129682 -418.038906)
			(xy 348.183633 -418.031147) (xy 348.210886 -418.03066) (xy 349.074486 -418.03066) (xy 349.101737 -418.031186)
			(xy 349.155685 -418.038941) (xy 349.20798 -418.054295) (xy 349.257558 -418.076934) (xy 349.303409 -418.106399)
			(xy 349.3446 -418.14209) (xy 349.380292 -418.18328) (xy 349.409759 -418.22913) (xy 349.432401 -418.278707)
			(xy 349.447756 -418.331001) (xy 349.455513 -418.384949) (xy 349.455513 -418.439451) (xy 349.455512 -418.439456)
			(xy 350.893023 -418.439456) (xy 350.893023 -418.384944) (xy 350.900781 -418.330986) (xy 350.91614 -418.278681)
			(xy 350.938786 -418.229095) (xy 350.968259 -418.183237) (xy 351.003959 -418.14204) (xy 351.045158 -418.106344)
			(xy 351.091018 -418.076874) (xy 351.140606 -418.054231) (xy 351.192911 -418.038876) (xy 351.24687 -418.031121)
			(xy 351.274126 -418.03066) (xy 352.137726 -418.03066) (xy 352.164974 -418.031212) (xy 352.218914 -418.038971)
			(xy 352.271201 -418.054327) (xy 352.320771 -418.076968) (xy 352.366614 -418.106432) (xy 352.407798 -418.142121)
			(xy 352.443484 -418.183307) (xy 352.472945 -418.229152) (xy 352.495582 -418.278723) (xy 352.510935 -418.331011)
			(xy 352.51869 -418.384952) (xy 352.51869 -418.439448) (xy 352.510935 -418.493389) (xy 352.495582 -418.545677)
			(xy 352.472945 -418.595248) (xy 352.443484 -418.641093) (xy 352.407798 -418.682279) (xy 352.366614 -418.717968)
			(xy 352.320771 -418.747432) (xy 352.271201 -418.770073) (xy 352.218914 -418.785429) (xy 352.164974 -418.793188)
			(xy 352.137726 -418.793676) (xy 351.274126 -418.793676) (xy 351.24687 -418.793279) (xy 351.192911 -418.785524)
			(xy 351.140606 -418.770169) (xy 351.091018 -418.747526) (xy 351.045158 -418.718056) (xy 351.003959 -418.68236)
			(xy 350.968259 -418.641163) (xy 350.938786 -418.595305) (xy 350.91614 -418.545719) (xy 350.900781 -418.493414)
			(xy 350.893023 -418.439456) (xy 349.455512 -418.439456) (xy 349.447756 -418.493399) (xy 349.432401 -418.545693)
			(xy 349.409759 -418.59527) (xy 349.380292 -418.64112) (xy 349.3446 -418.68231) (xy 349.303409 -418.718001)
			(xy 349.257558 -418.747466) (xy 349.20798 -418.770105) (xy 349.155685 -418.785459) (xy 349.101737 -418.793214)
			(xy 349.074486 -418.793676) (xy 348.210886 -418.793676) (xy 348.183633 -418.793253) (xy 348.129682 -418.785494)
			(xy 348.077385 -418.770137) (xy 348.027805 -418.747493) (xy 347.981953 -418.718024) (xy 347.940761 -418.682329)
			(xy 347.905068 -418.641136) (xy 347.8756 -418.595282) (xy 347.852958 -418.545702) (xy 347.837603 -418.493404)
			(xy 347.829846 -418.439453) (xy 346.392189 -418.439453) (xy 346.384435 -418.493386) (xy 346.369084 -418.545673)
			(xy 346.346448 -418.595243) (xy 346.316988 -418.641087) (xy 346.281305 -418.682272) (xy 346.240124 -418.717961)
			(xy 346.194283 -418.747426) (xy 346.144716 -418.770068) (xy 346.092431 -418.785425) (xy 346.038493 -418.793187)
			(xy 346.011246 -418.793676) (xy 345.147646 -418.793676) (xy 345.120389 -418.79328) (xy 345.066428 -418.785528)
			(xy 345.01412 -418.770175) (xy 344.96453 -418.747533) (xy 344.918667 -418.718063) (xy 344.877466 -418.682367)
			(xy 344.841764 -418.641169) (xy 344.812289 -418.59531) (xy 344.789642 -418.545723) (xy 344.774282 -418.493417)
			(xy 344.766523 -418.439457) (xy 343.328989 -418.439457) (xy 343.321234 -418.493391) (xy 343.305881 -418.545681)
			(xy 343.283242 -418.595254) (xy 343.253779 -418.6411) (xy 343.218091 -418.682287) (xy 343.176905 -418.717975)
			(xy 343.131059 -418.747439) (xy 343.081487 -418.770079) (xy 343.029197 -418.785433) (xy 342.975255 -418.793189)
			(xy 342.948006 -418.793676) (xy 342.084406 -418.793676) (xy 342.057151 -418.793277) (xy 342.003194 -418.785521)
			(xy 341.950891 -418.770164) (xy 341.901306 -418.74752) (xy 341.855449 -418.718049) (xy 341.814252 -418.682353)
			(xy 341.778554 -418.641156) (xy 341.749083 -418.595299) (xy 341.726438 -418.545714) (xy 341.711081 -418.493411)
			(xy 341.703323 -418.439455) (xy 340.265813 -418.439455) (xy 340.258055 -418.493402) (xy 340.242699 -418.545698)
			(xy 340.220056 -418.595276) (xy 340.190587 -418.641127) (xy 340.154893 -418.682317) (xy 340.1137 -418.718008)
			(xy 340.067846 -418.747472) (xy 340.018266 -418.770111) (xy 339.965968 -418.785463) (xy 339.912018 -418.793215)
			(xy 339.884766 -418.793676) (xy 339.021166 -418.793676) (xy 338.993914 -418.793252) (xy 338.939965 -418.785491)
			(xy 338.88767 -418.770131) (xy 338.838093 -418.747486) (xy 338.792243 -418.718017) (xy 338.751054 -418.682322)
			(xy 338.715363 -418.641129) (xy 338.685897 -418.595277) (xy 338.663257 -418.545698) (xy 338.647902 -418.493401)
			(xy 338.640146 -418.439452) (xy 337.202489 -418.439452) (xy 337.194735 -418.493389) (xy 337.179382 -418.545677)
			(xy 337.156745 -418.595248) (xy 337.127284 -418.641093) (xy 337.091598 -418.682279) (xy 337.050414 -418.717968)
			(xy 337.004571 -418.747432) (xy 336.955001 -418.770073) (xy 336.902714 -418.785429) (xy 336.848774 -418.793188)
			(xy 336.821526 -418.793676) (xy 335.957926 -418.793676) (xy 335.93067 -418.793279) (xy 335.876711 -418.785524)
			(xy 335.824406 -418.770169) (xy 335.774818 -418.747526) (xy 335.728958 -418.718056) (xy 335.687759 -418.68236)
			(xy 335.652059 -418.641163) (xy 335.622586 -418.595305) (xy 335.59994 -418.545719) (xy 335.584581 -418.493414)
			(xy 335.576823 -418.439456) (xy 334.139312 -418.439456) (xy 334.131556 -418.493399) (xy 334.116201 -418.545693)
			(xy 334.093559 -418.59527) (xy 334.064092 -418.64112) (xy 334.0284 -418.68231) (xy 333.987209 -418.718001)
			(xy 333.941358 -418.747466) (xy 333.89178 -418.770105) (xy 333.839485 -418.785459) (xy 333.785537 -418.793214)
			(xy 333.758286 -418.793676) (xy 332.894686 -418.793676) (xy 332.867433 -418.793253) (xy 332.813482 -418.785494)
			(xy 332.761185 -418.770137) (xy 332.711605 -418.747493) (xy 332.665753 -418.718024) (xy 332.624561 -418.682329)
			(xy 332.588868 -418.641136) (xy 332.5594 -418.595282) (xy 332.536758 -418.545702) (xy 332.521403 -418.493404)
			(xy 332.513646 -418.439453) (xy 331.075989 -418.439453) (xy 331.068235 -418.493386) (xy 331.052884 -418.545673)
			(xy 331.030248 -418.595243) (xy 331.000788 -418.641087) (xy 330.965105 -418.682272) (xy 330.923924 -418.717961)
			(xy 330.878083 -418.747426) (xy 330.828516 -418.770068) (xy 330.776231 -418.785425) (xy 330.722293 -418.793187)
			(xy 330.695046 -418.793676) (xy 329.831446 -418.793676) (xy 329.804189 -418.79328) (xy 329.750228 -418.785528)
			(xy 329.69792 -418.770175) (xy 329.64833 -418.747533) (xy 329.602467 -418.718063) (xy 329.561266 -418.682367)
			(xy 329.525564 -418.641169) (xy 329.496089 -418.59531) (xy 329.473442 -418.545723) (xy 329.458082 -418.493417)
			(xy 329.450323 -418.439457) (xy 328.012789 -418.439457) (xy 328.005034 -418.493391) (xy 327.989681 -418.545681)
			(xy 327.967042 -418.595254) (xy 327.937579 -418.6411) (xy 327.901891 -418.682287) (xy 327.860705 -418.717975)
			(xy 327.814859 -418.747439) (xy 327.765287 -418.770079) (xy 327.712997 -418.785433) (xy 327.659055 -418.793189)
			(xy 327.631806 -418.793676) (xy 326.768206 -418.793676) (xy 326.740951 -418.793277) (xy 326.686994 -418.785521)
			(xy 326.634691 -418.770164) (xy 326.585106 -418.74752) (xy 326.539249 -418.718049) (xy 326.498052 -418.682353)
			(xy 326.462354 -418.641156) (xy 326.432883 -418.595299) (xy 326.410238 -418.545714) (xy 326.394881 -418.493411)
			(xy 326.387123 -418.439455) (xy 324.949613 -418.439455) (xy 324.941855 -418.493402) (xy 324.926499 -418.545698)
			(xy 324.903856 -418.595276) (xy 324.874387 -418.641127) (xy 324.838693 -418.682317) (xy 324.7975 -418.718008)
			(xy 324.751646 -418.747472) (xy 324.702066 -418.770111) (xy 324.649768 -418.785463) (xy 324.595818 -418.793215)
			(xy 324.568566 -418.793676) (xy 323.704966 -418.793676) (xy 323.677714 -418.793252) (xy 323.623765 -418.785491)
			(xy 323.57147 -418.770131) (xy 323.521893 -418.747486) (xy 323.476043 -418.718017) (xy 323.434854 -418.682322)
			(xy 323.399163 -418.641129) (xy 323.369697 -418.595277) (xy 323.347057 -418.545698) (xy 323.331702 -418.493401)
			(xy 323.323946 -418.439452) (xy 321.886289 -418.439452) (xy 321.878535 -418.493389) (xy 321.863182 -418.545677)
			(xy 321.840545 -418.595248) (xy 321.811084 -418.641093) (xy 321.775398 -418.682279) (xy 321.734214 -418.717968)
			(xy 321.688371 -418.747432) (xy 321.638801 -418.770073) (xy 321.586514 -418.785429) (xy 321.532574 -418.793188)
			(xy 321.505326 -418.793676) (xy 320.641726 -418.793676) (xy 320.61447 -418.793279) (xy 320.560511 -418.785524)
			(xy 320.508206 -418.770169) (xy 320.458618 -418.747526) (xy 320.412758 -418.718056) (xy 320.371559 -418.68236)
			(xy 320.335859 -418.641163) (xy 320.306386 -418.595305) (xy 320.28374 -418.545719) (xy 320.268381 -418.493414)
			(xy 320.260623 -418.439456) (xy 318.823112 -418.439456) (xy 318.815356 -418.493399) (xy 318.800001 -418.545693)
			(xy 318.777359 -418.59527) (xy 318.747892 -418.64112) (xy 318.7122 -418.68231) (xy 318.671009 -418.718001)
			(xy 318.625158 -418.747466) (xy 318.57558 -418.770105) (xy 318.523285 -418.785459) (xy 318.469337 -418.793214)
			(xy 318.442086 -418.793676) (xy 317.578486 -418.793676) (xy 317.551233 -418.793253) (xy 317.497282 -418.785494)
			(xy 317.444985 -418.770137) (xy 317.395405 -418.747493) (xy 317.349553 -418.718024) (xy 317.308361 -418.682329)
			(xy 317.272668 -418.641136) (xy 317.2432 -418.595282) (xy 317.220558 -418.545702) (xy 317.205203 -418.493404)
			(xy 317.197446 -418.439453) (xy 315.759789 -418.439453) (xy 315.752035 -418.493386) (xy 315.736684 -418.545673)
			(xy 315.714048 -418.595243) (xy 315.684588 -418.641087) (xy 315.648905 -418.682272) (xy 315.607724 -418.717961)
			(xy 315.561883 -418.747426) (xy 315.512316 -418.770068) (xy 315.460031 -418.785425) (xy 315.406093 -418.793187)
			(xy 315.378846 -418.793676) (xy 314.515246 -418.793676) (xy 314.487989 -418.79328) (xy 314.434028 -418.785528)
			(xy 314.38172 -418.770175) (xy 314.33213 -418.747533) (xy 314.286267 -418.718063) (xy 314.245066 -418.682367)
			(xy 314.209364 -418.641169) (xy 314.179889 -418.59531) (xy 314.157242 -418.545723) (xy 314.141882 -418.493417)
			(xy 314.134123 -418.439457) (xy 312.696589 -418.439457) (xy 312.688834 -418.493391) (xy 312.673481 -418.545681)
			(xy 312.650842 -418.595254) (xy 312.621379 -418.6411) (xy 312.585691 -418.682287) (xy 312.544505 -418.717975)
			(xy 312.498659 -418.747439) (xy 312.449087 -418.770079) (xy 312.396797 -418.785433) (xy 312.342855 -418.793189)
			(xy 312.315606 -418.793676) (xy 311.452006 -418.793676) (xy 311.424751 -418.793277) (xy 311.370794 -418.785521)
			(xy 311.318491 -418.770164) (xy 311.268906 -418.74752) (xy 311.223049 -418.718049) (xy 311.181852 -418.682353)
			(xy 311.146154 -418.641156) (xy 311.116683 -418.595299) (xy 311.094038 -418.545714) (xy 311.078681 -418.493411)
			(xy 311.070923 -418.439455) (xy 309.633413 -418.439455) (xy 309.625655 -418.493402) (xy 309.610299 -418.545698)
			(xy 309.587656 -418.595276) (xy 309.558187 -418.641127) (xy 309.522493 -418.682317) (xy 309.4813 -418.718008)
			(xy 309.435446 -418.747472) (xy 309.385866 -418.770111) (xy 309.333568 -418.785463) (xy 309.279618 -418.793215)
			(xy 309.252366 -418.793676) (xy 308.388766 -418.793676) (xy 308.361514 -418.793252) (xy 308.307565 -418.785491)
			(xy 308.25527 -418.770131) (xy 308.205693 -418.747486) (xy 308.159843 -418.718017) (xy 308.118654 -418.682322)
			(xy 308.082963 -418.641129) (xy 308.053497 -418.595277) (xy 308.030857 -418.545698) (xy 308.015502 -418.493401)
			(xy 308.007746 -418.439452) (xy 306.570089 -418.439452) (xy 306.562335 -418.493389) (xy 306.546982 -418.545677)
			(xy 306.524345 -418.595248) (xy 306.494884 -418.641093) (xy 306.459198 -418.682279) (xy 306.418014 -418.717968)
			(xy 306.372171 -418.747432) (xy 306.322601 -418.770073) (xy 306.270314 -418.785429) (xy 306.216374 -418.793188)
			(xy 306.189126 -418.793676) (xy 305.325526 -418.793676) (xy 305.29827 -418.793279) (xy 305.244311 -418.785524)
			(xy 305.192006 -418.770169) (xy 305.142418 -418.747526) (xy 305.096558 -418.718056) (xy 305.055359 -418.68236)
			(xy 305.019659 -418.641163) (xy 304.990186 -418.595305) (xy 304.96754 -418.545719) (xy 304.952181 -418.493414)
			(xy 304.944423 -418.439456) (xy 290.169514 -418.439456) (xy 290.141139 -418.483609) (xy 290.105448 -418.5248)
			(xy 290.064257 -418.560491) (xy 290.018407 -418.589957) (xy 289.96883 -418.612599) (xy 289.916535 -418.627954)
			(xy 289.862587 -418.63571) (xy 289.808085 -418.63571) (xy 289.754137 -418.627954) (xy 289.701842 -418.612599)
			(xy 289.652265 -418.589957) (xy 289.606415 -418.560491) (xy 289.565224 -418.5248) (xy 289.529533 -418.483609)
			(xy 289.500067 -418.437759) (xy 289.477425 -418.388182) (xy 289.46207 -418.335887) (xy 289.454314 -418.281939)
			(xy 289.453828 -418.254688) (xy 277.48484 -418.254688) (xy 277.48484 -419.081712) (xy 277.484354 -419.108963)
			(xy 277.476598 -419.162911) (xy 277.461243 -419.215206) (xy 277.438601 -419.264783) (xy 277.409135 -419.310633)
			(xy 277.373444 -419.351824) (xy 277.332253 -419.387515) (xy 277.286403 -419.416981) (xy 277.236826 -419.439623)
			(xy 277.184531 -419.454978) (xy 277.130583 -419.462734) (xy 277.076081 -419.462734) (xy 277.022133 -419.454978)
			(xy 276.969838 -419.439623) (xy 276.920261 -419.416981) (xy 276.874411 -419.387515) (xy 276.83322 -419.351824)
			(xy 276.797529 -419.310633) (xy 276.768063 -419.264783) (xy 276.745421 -419.215206) (xy 276.730066 -419.162911)
			(xy 276.72231 -419.108963) (xy 276.721824 -419.081712) (xy 233.545126 -419.081712) (xy 232.102406 -420.524432)
			(xy 290.829492 -420.524432) (xy 290.829492 -419.660832) (xy 290.829978 -419.633563) (xy 290.83774 -419.579579)
			(xy 290.853105 -419.527249) (xy 290.875762 -419.477639) (xy 290.905248 -419.431758) (xy 290.940963 -419.390541)
			(xy 290.98218 -419.354826) (xy 291.028061 -419.32534) (xy 291.077671 -419.302683) (xy 291.130001 -419.287318)
			(xy 291.183985 -419.279556) (xy 291.238523 -419.279556) (xy 291.292507 -419.287318) (xy 291.344837 -419.302683)
			(xy 291.394447 -419.32534) (xy 291.440328 -419.354826) (xy 291.481545 -419.390541) (xy 291.51726 -419.431758)
			(xy 291.546746 -419.477639) (xy 291.569403 -419.527249) (xy 291.584768 -419.579579) (xy 291.59253 -419.633563)
			(xy 291.593016 -419.660832) (xy 291.593016 -420.524432) (xy 291.59253 -420.551701) (xy 291.584768 -420.605685)
			(xy 291.569403 -420.658015) (xy 291.546746 -420.707625) (xy 291.51726 -420.753506) (xy 291.481545 -420.794723)
			(xy 291.440328 -420.830438) (xy 291.394447 -420.859924) (xy 291.344837 -420.882581) (xy 291.292507 -420.897946)
			(xy 291.238523 -420.905708) (xy 291.183985 -420.905708) (xy 291.130001 -420.897946) (xy 291.077671 -420.882581)
			(xy 291.028061 -420.859924) (xy 290.98218 -420.830438) (xy 290.940963 -420.794723) (xy 290.905248 -420.753506)
			(xy 290.875762 -420.707625) (xy 290.853105 -420.658015) (xy 290.83774 -420.605685) (xy 290.829978 -420.551701)
			(xy 290.829492 -420.524432) (xy 232.102406 -420.524432) (xy 231.647383 -420.979455) (xy 303.412823 -420.979455)
			(xy 303.412823 -420.924945) (xy 303.420581 -420.870989) (xy 303.435938 -420.818686) (xy 303.458583 -420.769101)
			(xy 303.488054 -420.723244) (xy 303.523752 -420.682047) (xy 303.564949 -420.646351) (xy 303.610806 -420.61688)
			(xy 303.660391 -420.594236) (xy 303.712694 -420.578879) (xy 303.766651 -420.571123) (xy 303.793906 -420.57066)
			(xy 304.657506 -420.57066) (xy 304.684755 -420.571211) (xy 304.738697 -420.578967) (xy 304.790987 -420.594321)
			(xy 304.840559 -420.616961) (xy 304.886405 -420.646425) (xy 304.927591 -420.682113) (xy 304.963279 -420.7233)
			(xy 304.992742 -420.769146) (xy 305.015381 -420.818719) (xy 305.030734 -420.871009) (xy 305.03849 -420.924951)
			(xy 305.03849 -420.979449) (xy 305.038489 -420.979457) (xy 306.476023 -420.979457) (xy 306.476023 -420.924943)
			(xy 306.483782 -420.870983) (xy 306.499142 -420.818677) (xy 306.521789 -420.76909) (xy 306.551264 -420.723231)
			(xy 306.586966 -420.682033) (xy 306.628167 -420.646337) (xy 306.67403 -420.616867) (xy 306.72362 -420.594225)
			(xy 306.775928 -420.578872) (xy 306.829889 -420.57112) (xy 306.857146 -420.57066) (xy 307.720746 -420.57066)
			(xy 307.747993 -420.571213) (xy 307.801931 -420.578975) (xy 307.854216 -420.594332) (xy 307.903783 -420.616974)
			(xy 307.949624 -420.646439) (xy 307.990805 -420.682128) (xy 308.026488 -420.723313) (xy 308.055948 -420.769157)
			(xy 308.078584 -420.818727) (xy 308.093935 -420.871014) (xy 308.10169 -420.924953) (xy 308.10169 -420.979447)
			(xy 308.101689 -420.979453) (xy 309.539346 -420.979453) (xy 309.539346 -420.924947) (xy 309.547103 -420.870996)
			(xy 309.562458 -420.818698) (xy 309.5851 -420.769118) (xy 309.614568 -420.723264) (xy 309.650261 -420.682071)
			(xy 309.691453 -420.646376) (xy 309.737305 -420.616907) (xy 309.786885 -420.594263) (xy 309.839182 -420.578906)
			(xy 309.893133 -420.571147) (xy 309.920386 -420.57066) (xy 310.783986 -420.57066) (xy 310.811237 -420.571186)
			(xy 310.865185 -420.578941) (xy 310.91748 -420.594295) (xy 310.967058 -420.616934) (xy 311.012909 -420.646399)
			(xy 311.0541 -420.68209) (xy 311.089792 -420.72328) (xy 311.119259 -420.76913) (xy 311.141901 -420.818707)
			(xy 311.157256 -420.871001) (xy 311.165013 -420.924949) (xy 311.165013 -420.979451) (xy 311.165012 -420.979456)
			(xy 312.602523 -420.979456) (xy 312.602523 -420.924944) (xy 312.610281 -420.870986) (xy 312.62564 -420.818681)
			(xy 312.648286 -420.769095) (xy 312.677759 -420.723237) (xy 312.713459 -420.68204) (xy 312.754658 -420.646344)
			(xy 312.800518 -420.616874) (xy 312.850106 -420.594231) (xy 312.902411 -420.578876) (xy 312.95637 -420.571121)
			(xy 312.983626 -420.57066) (xy 313.847226 -420.57066) (xy 313.874474 -420.571212) (xy 313.928414 -420.578971)
			(xy 313.980701 -420.594327) (xy 314.030271 -420.616968) (xy 314.076114 -420.646432) (xy 314.117298 -420.682121)
			(xy 314.152984 -420.723307) (xy 314.182445 -420.769152) (xy 314.205082 -420.818723) (xy 314.220435 -420.871011)
			(xy 314.22819 -420.924952) (xy 314.22819 -420.979448) (xy 314.228189 -420.979452) (xy 315.665846 -420.979452)
			(xy 315.665846 -420.924948) (xy 315.673602 -420.870999) (xy 315.688957 -420.818702) (xy 315.711597 -420.769123)
			(xy 315.741063 -420.723271) (xy 315.776754 -420.682078) (xy 315.817943 -420.646383) (xy 315.863793 -420.616914)
			(xy 315.91337 -420.594269) (xy 315.965665 -420.578909) (xy 316.019614 -420.571148) (xy 316.046866 -420.57066)
			(xy 316.910466 -420.57066) (xy 316.937718 -420.571185) (xy 316.991668 -420.578937) (xy 317.043966 -420.594289)
			(xy 317.093546 -420.616928) (xy 317.1394 -420.646392) (xy 317.180593 -420.682083) (xy 317.216287 -420.723273)
			(xy 317.245756 -420.769124) (xy 317.268399 -420.818702) (xy 317.283755 -420.870999) (xy 317.291513 -420.924948)
			(xy 317.291513 -420.979452) (xy 317.291513 -420.979455) (xy 318.729023 -420.979455) (xy 318.729023 -420.924945)
			(xy 318.736781 -420.870989) (xy 318.752138 -420.818686) (xy 318.774783 -420.769101) (xy 318.804254 -420.723244)
			(xy 318.839952 -420.682047) (xy 318.881149 -420.646351) (xy 318.927006 -420.61688) (xy 318.976591 -420.594236)
			(xy 319.028894 -420.578879) (xy 319.082851 -420.571123) (xy 319.110106 -420.57066) (xy 319.973706 -420.57066)
			(xy 320.000955 -420.571211) (xy 320.054897 -420.578967) (xy 320.107187 -420.594321) (xy 320.156759 -420.616961)
			(xy 320.202605 -420.646425) (xy 320.243791 -420.682113) (xy 320.279479 -420.7233) (xy 320.308942 -420.769146)
			(xy 320.331581 -420.818719) (xy 320.346934 -420.871009) (xy 320.35469 -420.924951) (xy 320.35469 -420.979449)
			(xy 320.354689 -420.979457) (xy 321.792223 -420.979457) (xy 321.792223 -420.924943) (xy 321.799982 -420.870983)
			(xy 321.815342 -420.818677) (xy 321.837989 -420.76909) (xy 321.867464 -420.723231) (xy 321.903166 -420.682033)
			(xy 321.944367 -420.646337) (xy 321.99023 -420.616867) (xy 322.03982 -420.594225) (xy 322.092128 -420.578872)
			(xy 322.146089 -420.57112) (xy 322.173346 -420.57066) (xy 323.036946 -420.57066) (xy 323.064193 -420.571213)
			(xy 323.118131 -420.578975) (xy 323.170416 -420.594332) (xy 323.219983 -420.616974) (xy 323.265824 -420.646439)
			(xy 323.307005 -420.682128) (xy 323.342688 -420.723313) (xy 323.372148 -420.769157) (xy 323.394784 -420.818727)
			(xy 323.410135 -420.871014) (xy 323.41789 -420.924953) (xy 323.41789 -420.979447) (xy 323.417889 -420.979453)
			(xy 324.855546 -420.979453) (xy 324.855546 -420.924947) (xy 324.863303 -420.870996) (xy 324.878658 -420.818698)
			(xy 324.9013 -420.769118) (xy 324.930768 -420.723264) (xy 324.966461 -420.682071) (xy 325.007653 -420.646376)
			(xy 325.053505 -420.616907) (xy 325.103085 -420.594263) (xy 325.155382 -420.578906) (xy 325.209333 -420.571147)
			(xy 325.236586 -420.57066) (xy 326.100186 -420.57066) (xy 326.127437 -420.571186) (xy 326.181385 -420.578941)
			(xy 326.23368 -420.594295) (xy 326.283258 -420.616934) (xy 326.329109 -420.646399) (xy 326.3703 -420.68209)
			(xy 326.405992 -420.72328) (xy 326.435459 -420.76913) (xy 326.458101 -420.818707) (xy 326.473456 -420.871001)
			(xy 326.481213 -420.924949) (xy 326.481213 -420.979451) (xy 326.481212 -420.979456) (xy 327.918723 -420.979456)
			(xy 327.918723 -420.924944) (xy 327.926481 -420.870986) (xy 327.94184 -420.818681) (xy 327.964486 -420.769095)
			(xy 327.993959 -420.723237) (xy 328.029659 -420.68204) (xy 328.070858 -420.646344) (xy 328.116718 -420.616874)
			(xy 328.166306 -420.594231) (xy 328.218611 -420.578876) (xy 328.27257 -420.571121) (xy 328.299826 -420.57066)
			(xy 329.163426 -420.57066) (xy 329.190674 -420.571212) (xy 329.244614 -420.578971) (xy 329.296901 -420.594327)
			(xy 329.346471 -420.616968) (xy 329.392314 -420.646432) (xy 329.433498 -420.682121) (xy 329.469184 -420.723307)
			(xy 329.498645 -420.769152) (xy 329.521282 -420.818723) (xy 329.536635 -420.871011) (xy 329.54439 -420.924952)
			(xy 329.54439 -420.979448) (xy 329.544389 -420.979452) (xy 330.982046 -420.979452) (xy 330.982046 -420.924948)
			(xy 330.989802 -420.870999) (xy 331.005157 -420.818702) (xy 331.027797 -420.769123) (xy 331.057263 -420.723271)
			(xy 331.092954 -420.682078) (xy 331.134143 -420.646383) (xy 331.179993 -420.616914) (xy 331.22957 -420.594269)
			(xy 331.281865 -420.578909) (xy 331.335814 -420.571148) (xy 331.363066 -420.57066) (xy 332.226666 -420.57066)
			(xy 332.253918 -420.571185) (xy 332.307868 -420.578937) (xy 332.360166 -420.594289) (xy 332.409746 -420.616928)
			(xy 332.4556 -420.646392) (xy 332.496793 -420.682083) (xy 332.532487 -420.723273) (xy 332.561956 -420.769124)
			(xy 332.584599 -420.818702) (xy 332.599955 -420.870999) (xy 332.607713 -420.924948) (xy 332.607713 -420.979452)
			(xy 332.607713 -420.979455) (xy 334.045223 -420.979455) (xy 334.045223 -420.924945) (xy 334.052981 -420.870989)
			(xy 334.068338 -420.818686) (xy 334.090983 -420.769101) (xy 334.120454 -420.723244) (xy 334.156152 -420.682047)
			(xy 334.197349 -420.646351) (xy 334.243206 -420.61688) (xy 334.292791 -420.594236) (xy 334.345094 -420.578879)
			(xy 334.399051 -420.571123) (xy 334.426306 -420.57066) (xy 335.289906 -420.57066) (xy 335.317155 -420.571211)
			(xy 335.371097 -420.578967) (xy 335.423387 -420.594321) (xy 335.472959 -420.616961) (xy 335.518805 -420.646425)
			(xy 335.559991 -420.682113) (xy 335.595679 -420.7233) (xy 335.625142 -420.769146) (xy 335.647781 -420.818719)
			(xy 335.663134 -420.871009) (xy 335.67089 -420.924951) (xy 335.67089 -420.979449) (xy 335.670889 -420.979457)
			(xy 337.108423 -420.979457) (xy 337.108423 -420.924943) (xy 337.116182 -420.870983) (xy 337.131542 -420.818677)
			(xy 337.154189 -420.76909) (xy 337.183664 -420.723231) (xy 337.219366 -420.682033) (xy 337.260567 -420.646337)
			(xy 337.30643 -420.616867) (xy 337.35602 -420.594225) (xy 337.408328 -420.578872) (xy 337.462289 -420.57112)
			(xy 337.489546 -420.57066) (xy 338.353146 -420.57066) (xy 338.380393 -420.571213) (xy 338.434331 -420.578975)
			(xy 338.486616 -420.594332) (xy 338.536183 -420.616974) (xy 338.582024 -420.646439) (xy 338.623205 -420.682128)
			(xy 338.658888 -420.723313) (xy 338.688348 -420.769157) (xy 338.710984 -420.818727) (xy 338.726335 -420.871014)
			(xy 338.73409 -420.924953) (xy 338.73409 -420.979447) (xy 338.734089 -420.979453) (xy 340.171746 -420.979453)
			(xy 340.171746 -420.924947) (xy 340.179503 -420.870996) (xy 340.194858 -420.818698) (xy 340.2175 -420.769118)
			(xy 340.246968 -420.723264) (xy 340.282661 -420.682071) (xy 340.323853 -420.646376) (xy 340.369705 -420.616907)
			(xy 340.419285 -420.594263) (xy 340.471582 -420.578906) (xy 340.525533 -420.571147) (xy 340.552786 -420.57066)
			(xy 341.416386 -420.57066) (xy 341.443637 -420.571186) (xy 341.497585 -420.578941) (xy 341.54988 -420.594295)
			(xy 341.599458 -420.616934) (xy 341.645309 -420.646399) (xy 341.6865 -420.68209) (xy 341.722192 -420.72328)
			(xy 341.751659 -420.76913) (xy 341.774301 -420.818707) (xy 341.789656 -420.871001) (xy 341.797413 -420.924949)
			(xy 341.797413 -420.979451) (xy 341.797412 -420.979456) (xy 343.234923 -420.979456) (xy 343.234923 -420.924944)
			(xy 343.242681 -420.870986) (xy 343.25804 -420.818681) (xy 343.280686 -420.769095) (xy 343.310159 -420.723237)
			(xy 343.345859 -420.68204) (xy 343.387058 -420.646344) (xy 343.432918 -420.616874) (xy 343.482506 -420.594231)
			(xy 343.534811 -420.578876) (xy 343.58877 -420.571121) (xy 343.616026 -420.57066) (xy 344.479626 -420.57066)
			(xy 344.506874 -420.571212) (xy 344.560814 -420.578971) (xy 344.613101 -420.594327) (xy 344.662671 -420.616968)
			(xy 344.708514 -420.646432) (xy 344.749698 -420.682121) (xy 344.785384 -420.723307) (xy 344.814845 -420.769152)
			(xy 344.837482 -420.818723) (xy 344.852835 -420.871011) (xy 344.86059 -420.924952) (xy 344.86059 -420.979448)
			(xy 344.860589 -420.979452) (xy 346.298246 -420.979452) (xy 346.298246 -420.924948) (xy 346.306002 -420.870999)
			(xy 346.321357 -420.818702) (xy 346.343997 -420.769123) (xy 346.373463 -420.723271) (xy 346.409154 -420.682078)
			(xy 346.450343 -420.646383) (xy 346.496193 -420.616914) (xy 346.54577 -420.594269) (xy 346.598065 -420.578909)
			(xy 346.652014 -420.571148) (xy 346.679266 -420.57066) (xy 347.542866 -420.57066) (xy 347.570118 -420.571185)
			(xy 347.624068 -420.578937) (xy 347.676366 -420.594289) (xy 347.725946 -420.616928) (xy 347.7718 -420.646392)
			(xy 347.812993 -420.682083) (xy 347.848687 -420.723273) (xy 347.878156 -420.769124) (xy 347.900799 -420.818702)
			(xy 347.916155 -420.870999) (xy 347.923913 -420.924948) (xy 347.923913 -420.979452) (xy 347.923913 -420.979455)
			(xy 349.361423 -420.979455) (xy 349.361423 -420.924945) (xy 349.369181 -420.870989) (xy 349.384538 -420.818686)
			(xy 349.407183 -420.769101) (xy 349.436654 -420.723244) (xy 349.472352 -420.682047) (xy 349.513549 -420.646351)
			(xy 349.559406 -420.61688) (xy 349.608991 -420.594236) (xy 349.661294 -420.578879) (xy 349.715251 -420.571123)
			(xy 349.742506 -420.57066) (xy 350.606106 -420.57066) (xy 350.633355 -420.571211) (xy 350.687297 -420.578967)
			(xy 350.739587 -420.594321) (xy 350.789159 -420.616961) (xy 350.835005 -420.646425) (xy 350.876191 -420.682113)
			(xy 350.911879 -420.7233) (xy 350.941342 -420.769146) (xy 350.963981 -420.818719) (xy 350.979334 -420.871009)
			(xy 350.98709 -420.924951) (xy 350.98709 -420.979449) (xy 350.979334 -421.033391) (xy 350.963981 -421.085681)
			(xy 350.941342 -421.135254) (xy 350.911879 -421.1811) (xy 350.876191 -421.222287) (xy 350.835005 -421.257975)
			(xy 350.789159 -421.287439) (xy 350.739587 -421.310079) (xy 350.687297 -421.325433) (xy 350.633355 -421.333189)
			(xy 350.606106 -421.333676) (xy 349.742506 -421.333676) (xy 349.715251 -421.333277) (xy 349.661294 -421.325521)
			(xy 349.608991 -421.310164) (xy 349.559406 -421.28752) (xy 349.513549 -421.258049) (xy 349.472352 -421.222353)
			(xy 349.436654 -421.181156) (xy 349.407183 -421.135299) (xy 349.384538 -421.085714) (xy 349.369181 -421.033411)
			(xy 349.361423 -420.979455) (xy 347.923913 -420.979455) (xy 347.916155 -421.033402) (xy 347.900799 -421.085698)
			(xy 347.878156 -421.135276) (xy 347.848687 -421.181127) (xy 347.812993 -421.222317) (xy 347.7718 -421.258008)
			(xy 347.725946 -421.287472) (xy 347.676366 -421.310111) (xy 347.624068 -421.325463) (xy 347.570118 -421.333215)
			(xy 347.542866 -421.333676) (xy 346.679266 -421.333676) (xy 346.652014 -421.333252) (xy 346.598065 -421.325491)
			(xy 346.54577 -421.310131) (xy 346.496193 -421.287486) (xy 346.450343 -421.258017) (xy 346.409154 -421.222322)
			(xy 346.373463 -421.181129) (xy 346.343997 -421.135277) (xy 346.321357 -421.085698) (xy 346.306002 -421.033401)
			(xy 346.298246 -420.979452) (xy 344.860589 -420.979452) (xy 344.852835 -421.033389) (xy 344.837482 -421.085677)
			(xy 344.814845 -421.135248) (xy 344.785384 -421.181093) (xy 344.749698 -421.222279) (xy 344.708514 -421.257968)
			(xy 344.662671 -421.287432) (xy 344.613101 -421.310073) (xy 344.560814 -421.325429) (xy 344.506874 -421.333188)
			(xy 344.479626 -421.333676) (xy 343.616026 -421.333676) (xy 343.58877 -421.333279) (xy 343.534811 -421.325524)
			(xy 343.482506 -421.310169) (xy 343.432918 -421.287526) (xy 343.387058 -421.258056) (xy 343.345859 -421.22236)
			(xy 343.310159 -421.181163) (xy 343.280686 -421.135305) (xy 343.25804 -421.085719) (xy 343.242681 -421.033414)
			(xy 343.234923 -420.979456) (xy 341.797412 -420.979456) (xy 341.789656 -421.033399) (xy 341.774301 -421.085693)
			(xy 341.751659 -421.13527) (xy 341.722192 -421.18112) (xy 341.6865 -421.22231) (xy 341.645309 -421.258001)
			(xy 341.599458 -421.287466) (xy 341.54988 -421.310105) (xy 341.497585 -421.325459) (xy 341.443637 -421.333214)
			(xy 341.416386 -421.333676) (xy 340.552786 -421.333676) (xy 340.525533 -421.333253) (xy 340.471582 -421.325494)
			(xy 340.419285 -421.310137) (xy 340.369705 -421.287493) (xy 340.323853 -421.258024) (xy 340.282661 -421.222329)
			(xy 340.246968 -421.181136) (xy 340.2175 -421.135282) (xy 340.194858 -421.085702) (xy 340.179503 -421.033404)
			(xy 340.171746 -420.979453) (xy 338.734089 -420.979453) (xy 338.726335 -421.033386) (xy 338.710984 -421.085673)
			(xy 338.688348 -421.135243) (xy 338.658888 -421.181087) (xy 338.623205 -421.222272) (xy 338.582024 -421.257961)
			(xy 338.536183 -421.287426) (xy 338.486616 -421.310068) (xy 338.434331 -421.325425) (xy 338.380393 -421.333187)
			(xy 338.353146 -421.333676) (xy 337.489546 -421.333676) (xy 337.462289 -421.33328) (xy 337.408328 -421.325528)
			(xy 337.35602 -421.310175) (xy 337.30643 -421.287533) (xy 337.260567 -421.258063) (xy 337.219366 -421.222367)
			(xy 337.183664 -421.181169) (xy 337.154189 -421.13531) (xy 337.131542 -421.085723) (xy 337.116182 -421.033417)
			(xy 337.108423 -420.979457) (xy 335.670889 -420.979457) (xy 335.663134 -421.033391) (xy 335.647781 -421.085681)
			(xy 335.625142 -421.135254) (xy 335.595679 -421.1811) (xy 335.559991 -421.222287) (xy 335.518805 -421.257975)
			(xy 335.472959 -421.287439) (xy 335.423387 -421.310079) (xy 335.371097 -421.325433) (xy 335.317155 -421.333189)
			(xy 335.289906 -421.333676) (xy 334.426306 -421.333676) (xy 334.399051 -421.333277) (xy 334.345094 -421.325521)
			(xy 334.292791 -421.310164) (xy 334.243206 -421.28752) (xy 334.197349 -421.258049) (xy 334.156152 -421.222353)
			(xy 334.120454 -421.181156) (xy 334.090983 -421.135299) (xy 334.068338 -421.085714) (xy 334.052981 -421.033411)
			(xy 334.045223 -420.979455) (xy 332.607713 -420.979455) (xy 332.599955 -421.033402) (xy 332.584599 -421.085698)
			(xy 332.561956 -421.135276) (xy 332.532487 -421.181127) (xy 332.496793 -421.222317) (xy 332.4556 -421.258008)
			(xy 332.409746 -421.287472) (xy 332.360166 -421.310111) (xy 332.307868 -421.325463) (xy 332.253918 -421.333215)
			(xy 332.226666 -421.333676) (xy 331.363066 -421.333676) (xy 331.335814 -421.333252) (xy 331.281865 -421.325491)
			(xy 331.22957 -421.310131) (xy 331.179993 -421.287486) (xy 331.134143 -421.258017) (xy 331.092954 -421.222322)
			(xy 331.057263 -421.181129) (xy 331.027797 -421.135277) (xy 331.005157 -421.085698) (xy 330.989802 -421.033401)
			(xy 330.982046 -420.979452) (xy 329.544389 -420.979452) (xy 329.536635 -421.033389) (xy 329.521282 -421.085677)
			(xy 329.498645 -421.135248) (xy 329.469184 -421.181093) (xy 329.433498 -421.222279) (xy 329.392314 -421.257968)
			(xy 329.346471 -421.287432) (xy 329.296901 -421.310073) (xy 329.244614 -421.325429) (xy 329.190674 -421.333188)
			(xy 329.163426 -421.333676) (xy 328.299826 -421.333676) (xy 328.27257 -421.333279) (xy 328.218611 -421.325524)
			(xy 328.166306 -421.310169) (xy 328.116718 -421.287526) (xy 328.070858 -421.258056) (xy 328.029659 -421.22236)
			(xy 327.993959 -421.181163) (xy 327.964486 -421.135305) (xy 327.94184 -421.085719) (xy 327.926481 -421.033414)
			(xy 327.918723 -420.979456) (xy 326.481212 -420.979456) (xy 326.473456 -421.033399) (xy 326.458101 -421.085693)
			(xy 326.435459 -421.13527) (xy 326.405992 -421.18112) (xy 326.3703 -421.22231) (xy 326.329109 -421.258001)
			(xy 326.283258 -421.287466) (xy 326.23368 -421.310105) (xy 326.181385 -421.325459) (xy 326.127437 -421.333214)
			(xy 326.100186 -421.333676) (xy 325.236586 -421.333676) (xy 325.209333 -421.333253) (xy 325.155382 -421.325494)
			(xy 325.103085 -421.310137) (xy 325.053505 -421.287493) (xy 325.007653 -421.258024) (xy 324.966461 -421.222329)
			(xy 324.930768 -421.181136) (xy 324.9013 -421.135282) (xy 324.878658 -421.085702) (xy 324.863303 -421.033404)
			(xy 324.855546 -420.979453) (xy 323.417889 -420.979453) (xy 323.410135 -421.033386) (xy 323.394784 -421.085673)
			(xy 323.372148 -421.135243) (xy 323.342688 -421.181087) (xy 323.307005 -421.222272) (xy 323.265824 -421.257961)
			(xy 323.219983 -421.287426) (xy 323.170416 -421.310068) (xy 323.118131 -421.325425) (xy 323.064193 -421.333187)
			(xy 323.036946 -421.333676) (xy 322.173346 -421.333676) (xy 322.146089 -421.33328) (xy 322.092128 -421.325528)
			(xy 322.03982 -421.310175) (xy 321.99023 -421.287533) (xy 321.944367 -421.258063) (xy 321.903166 -421.222367)
			(xy 321.867464 -421.181169) (xy 321.837989 -421.13531) (xy 321.815342 -421.085723) (xy 321.799982 -421.033417)
			(xy 321.792223 -420.979457) (xy 320.354689 -420.979457) (xy 320.346934 -421.033391) (xy 320.331581 -421.085681)
			(xy 320.308942 -421.135254) (xy 320.279479 -421.1811) (xy 320.243791 -421.222287) (xy 320.202605 -421.257975)
			(xy 320.156759 -421.287439) (xy 320.107187 -421.310079) (xy 320.054897 -421.325433) (xy 320.000955 -421.333189)
			(xy 319.973706 -421.333676) (xy 319.110106 -421.333676) (xy 319.082851 -421.333277) (xy 319.028894 -421.325521)
			(xy 318.976591 -421.310164) (xy 318.927006 -421.28752) (xy 318.881149 -421.258049) (xy 318.839952 -421.222353)
			(xy 318.804254 -421.181156) (xy 318.774783 -421.135299) (xy 318.752138 -421.085714) (xy 318.736781 -421.033411)
			(xy 318.729023 -420.979455) (xy 317.291513 -420.979455) (xy 317.283755 -421.033402) (xy 317.268399 -421.085698)
			(xy 317.245756 -421.135276) (xy 317.216287 -421.181127) (xy 317.180593 -421.222317) (xy 317.1394 -421.258008)
			(xy 317.093546 -421.287472) (xy 317.043966 -421.310111) (xy 316.991668 -421.325463) (xy 316.937718 -421.333215)
			(xy 316.910466 -421.333676) (xy 316.046866 -421.333676) (xy 316.019614 -421.333252) (xy 315.965665 -421.325491)
			(xy 315.91337 -421.310131) (xy 315.863793 -421.287486) (xy 315.817943 -421.258017) (xy 315.776754 -421.222322)
			(xy 315.741063 -421.181129) (xy 315.711597 -421.135277) (xy 315.688957 -421.085698) (xy 315.673602 -421.033401)
			(xy 315.665846 -420.979452) (xy 314.228189 -420.979452) (xy 314.220435 -421.033389) (xy 314.205082 -421.085677)
			(xy 314.182445 -421.135248) (xy 314.152984 -421.181093) (xy 314.117298 -421.222279) (xy 314.076114 -421.257968)
			(xy 314.030271 -421.287432) (xy 313.980701 -421.310073) (xy 313.928414 -421.325429) (xy 313.874474 -421.333188)
			(xy 313.847226 -421.333676) (xy 312.983626 -421.333676) (xy 312.95637 -421.333279) (xy 312.902411 -421.325524)
			(xy 312.850106 -421.310169) (xy 312.800518 -421.287526) (xy 312.754658 -421.258056) (xy 312.713459 -421.22236)
			(xy 312.677759 -421.181163) (xy 312.648286 -421.135305) (xy 312.62564 -421.085719) (xy 312.610281 -421.033414)
			(xy 312.602523 -420.979456) (xy 311.165012 -420.979456) (xy 311.157256 -421.033399) (xy 311.141901 -421.085693)
			(xy 311.119259 -421.13527) (xy 311.089792 -421.18112) (xy 311.0541 -421.22231) (xy 311.012909 -421.258001)
			(xy 310.967058 -421.287466) (xy 310.91748 -421.310105) (xy 310.865185 -421.325459) (xy 310.811237 -421.333214)
			(xy 310.783986 -421.333676) (xy 309.920386 -421.333676) (xy 309.893133 -421.333253) (xy 309.839182 -421.325494)
			(xy 309.786885 -421.310137) (xy 309.737305 -421.287493) (xy 309.691453 -421.258024) (xy 309.650261 -421.222329)
			(xy 309.614568 -421.181136) (xy 309.5851 -421.135282) (xy 309.562458 -421.085702) (xy 309.547103 -421.033404)
			(xy 309.539346 -420.979453) (xy 308.101689 -420.979453) (xy 308.093935 -421.033386) (xy 308.078584 -421.085673)
			(xy 308.055948 -421.135243) (xy 308.026488 -421.181087) (xy 307.990805 -421.222272) (xy 307.949624 -421.257961)
			(xy 307.903783 -421.287426) (xy 307.854216 -421.310068) (xy 307.801931 -421.325425) (xy 307.747993 -421.333187)
			(xy 307.720746 -421.333676) (xy 306.857146 -421.333676) (xy 306.829889 -421.33328) (xy 306.775928 -421.325528)
			(xy 306.72362 -421.310175) (xy 306.67403 -421.287533) (xy 306.628167 -421.258063) (xy 306.586966 -421.222367)
			(xy 306.551264 -421.181169) (xy 306.521789 -421.13531) (xy 306.499142 -421.085723) (xy 306.483782 -421.033417)
			(xy 306.476023 -420.979457) (xy 305.038489 -420.979457) (xy 305.030734 -421.033391) (xy 305.015381 -421.085681)
			(xy 304.992742 -421.135254) (xy 304.963279 -421.1811) (xy 304.927591 -421.222287) (xy 304.886405 -421.257975)
			(xy 304.840559 -421.287439) (xy 304.790987 -421.310079) (xy 304.738697 -421.325433) (xy 304.684755 -421.333189)
			(xy 304.657506 -421.333676) (xy 303.793906 -421.333676) (xy 303.766651 -421.333277) (xy 303.712694 -421.325521)
			(xy 303.660391 -421.310164) (xy 303.610806 -421.28752) (xy 303.564949 -421.258049) (xy 303.523752 -421.222353)
			(xy 303.488054 -421.181156) (xy 303.458583 -421.135299) (xy 303.435938 -421.085714) (xy 303.420581 -421.033411)
			(xy 303.412823 -420.979455) (xy 231.647383 -420.979455) (xy 230.329486 -422.297352) (xy 230.322673 -422.304773)
			(xy 230.314938 -422.323356) (xy 230.3145 -422.33342) (xy 230.3145 -422.354375) (xy 285.567772 -422.354375)
			(xy 285.567772 -422.299825) (xy 285.575535 -422.245831) (xy 285.590905 -422.193491) (xy 285.613567 -422.143872)
			(xy 285.64306 -422.097983) (xy 285.678784 -422.056759) (xy 285.720012 -422.021038) (xy 285.765903 -421.991549)
			(xy 285.815525 -421.968892) (xy 285.867866 -421.953528) (xy 285.921861 -421.945769) (xy 285.949136 -421.945308)
			(xy 286.812736 -421.945308) (xy 286.840002 -421.945857) (xy 286.893977 -421.953622) (xy 286.946298 -421.968989)
			(xy 286.9959 -421.991646) (xy 287.041773 -422.02113) (xy 287.082983 -422.056843) (xy 287.118691 -422.098056)
			(xy 287.148172 -422.143932) (xy 287.170823 -422.193536) (xy 287.186186 -422.245858) (xy 287.193946 -422.299834)
			(xy 287.193946 -422.354366) (xy 287.186186 -422.408342) (xy 287.170823 -422.460664) (xy 287.148172 -422.510268)
			(xy 287.118691 -422.556144) (xy 287.082983 -422.597357) (xy 287.041773 -422.63307) (xy 286.9959 -422.662554)
			(xy 286.946298 -422.685211) (xy 286.893977 -422.700578) (xy 286.840002 -422.708343) (xy 286.812736 -422.708832)
			(xy 285.949136 -422.708832) (xy 285.921861 -422.708431) (xy 285.867866 -422.700672) (xy 285.815525 -422.685308)
			(xy 285.765903 -422.662651) (xy 285.720012 -422.633162) (xy 285.678784 -422.597441) (xy 285.64306 -422.556217)
			(xy 285.613567 -422.510328) (xy 285.590905 -422.460709) (xy 285.575535 -422.408369) (xy 285.567772 -422.354375)
			(xy 230.3145 -422.354375) (xy 230.3145 -424.80464) (xy 357.679233 -424.80464) (xy 357.679233 -424.6755)
			(xy 357.687183 -424.546605) (xy 357.703053 -424.418445) (xy 357.726782 -424.291504) (xy 357.758281 -424.166265)
			(xy 357.79743 -424.043202) (xy 357.844081 -423.922783) (xy 357.898056 -423.805464) (xy 357.959151 -423.69169)
			(xy 358.027134 -423.581893) (xy 358.101748 -423.47649) (xy 358.182709 -423.37588) (xy 358.269709 -423.280445)
			(xy 358.36242 -423.190546) (xy 358.46049 -423.106525) (xy 358.563545 -423.028701) (xy 358.671196 -422.957369)
			(xy 358.783035 -422.892799) (xy 358.898636 -422.835237) (xy 359.017561 -422.7849) (xy 359.13936 -422.74198)
			(xy 359.26357 -422.706639) (xy 359.389719 -422.679012) (xy 359.517331 -422.659203) (xy 359.64592 -422.647287)
			(xy 359.774998 -422.643311) (xy 359.904076 -422.647287) (xy 360.032665 -422.659203) (xy 360.160277 -422.679012)
			(xy 360.222212 -422.692576) (xy 365.310928 -422.692576) (xy 365.310928 -415.898584) (xy 365.3113 -415.888356)
			(xy 365.319137 -415.86946) (xy 365.33361 -415.855003) (xy 365.352515 -415.847188) (xy 365.362744 -415.846768)
			(xy 370.261388 -415.846768) (xy 370.271593 -415.847291) (xy 370.290451 -415.855097) (xy 370.304887 -415.869525)
			(xy 370.312703 -415.888379) (xy 370.313204 -415.898584) (xy 370.313204 -418.439456) (xy 372.044623 -418.439456)
			(xy 372.044623 -418.384944) (xy 372.052381 -418.330986) (xy 372.06774 -418.278682) (xy 372.090386 -418.229097)
			(xy 372.119858 -418.183238) (xy 372.155557 -418.142042) (xy 372.196756 -418.106345) (xy 372.242616 -418.076875)
			(xy 372.292203 -418.054232) (xy 372.344508 -418.038877) (xy 372.398466 -418.031121) (xy 372.425722 -418.03066)
			(xy 373.289322 -418.03066) (xy 373.31657 -418.031212) (xy 373.370511 -418.03897) (xy 373.422798 -418.054326)
			(xy 373.472369 -418.076966) (xy 373.518212 -418.106431) (xy 373.559396 -418.142119) (xy 373.595083 -418.183305)
			(xy 373.624544 -418.229151) (xy 373.647182 -418.278722) (xy 373.662535 -418.331011) (xy 373.67029 -418.384952)
			(xy 373.67029 -418.439448) (xy 373.670289 -418.439452) (xy 375.107946 -418.439452) (xy 375.107946 -418.384948)
			(xy 375.115702 -418.330999) (xy 375.131056 -418.278703) (xy 375.153697 -418.229124) (xy 375.183162 -418.183272)
			(xy 375.218852 -418.142079) (xy 375.260041 -418.106385) (xy 375.305891 -418.076915) (xy 375.355468 -418.05427)
			(xy 375.407762 -418.03891) (xy 375.46171 -418.031148) (xy 375.488962 -418.03066) (xy 376.352562 -418.03066)
			(xy 376.379814 -418.031185) (xy 376.433765 -418.038937) (xy 376.486063 -418.054288) (xy 376.535644 -418.076926)
			(xy 376.581498 -418.106391) (xy 376.622691 -418.142082) (xy 376.658386 -418.183272) (xy 376.687855 -418.229123)
			(xy 376.710499 -418.278701) (xy 376.725855 -418.330998) (xy 376.733613 -418.384948) (xy 376.733613 -418.439452)
			(xy 376.733613 -418.439455) (xy 378.171123 -418.439455) (xy 378.171123 -418.384945) (xy 378.178881 -418.330989)
			(xy 378.194238 -418.278687) (xy 378.216883 -418.229102) (xy 378.246353 -418.183245) (xy 378.28205 -418.142049)
			(xy 378.323247 -418.106352) (xy 378.369104 -418.076882) (xy 378.418688 -418.054237) (xy 378.470991 -418.03888)
			(xy 378.524947 -418.031123) (xy 378.552202 -418.03066) (xy 379.415802 -418.03066) (xy 379.443051 -418.03121)
			(xy 379.496994 -418.038966) (xy 379.549284 -418.05432) (xy 379.598857 -418.07696) (xy 379.644703 -418.106424)
			(xy 379.685889 -418.142112) (xy 379.721578 -418.183299) (xy 379.751041 -418.229145) (xy 379.77368 -418.278718)
			(xy 379.789034 -418.331008) (xy 379.79679 -418.384951) (xy 379.79679 -418.439449) (xy 379.796789 -418.439457)
			(xy 381.234323 -418.439457) (xy 381.234323 -418.384943) (xy 381.242082 -418.330984) (xy 381.257441 -418.278678)
			(xy 381.280089 -418.229091) (xy 381.309563 -418.183232) (xy 381.345264 -418.142035) (xy 381.386466 -418.106338)
			(xy 381.432328 -418.076869) (xy 381.481917 -418.054227) (xy 381.534225 -418.038873) (xy 381.588185 -418.03112)
			(xy 381.615442 -418.03066) (xy 382.479042 -418.03066) (xy 382.506289 -418.031213) (xy 382.560228 -418.038974)
			(xy 382.612513 -418.054331) (xy 382.662081 -418.076973) (xy 382.707922 -418.106438) (xy 382.749103 -418.142126)
			(xy 382.784787 -418.183312) (xy 382.814247 -418.229156) (xy 382.836883 -418.278727) (xy 382.852235 -418.331014)
			(xy 382.85999 -418.384953) (xy 382.85999 -418.439447) (xy 382.859989 -418.439453) (xy 384.297646 -418.439453)
			(xy 384.297646 -418.384947) (xy 384.305403 -418.330997) (xy 384.320758 -418.278699) (xy 384.3434 -418.229119)
			(xy 384.372867 -418.183265) (xy 384.408559 -418.142072) (xy 384.449751 -418.106378) (xy 384.495603 -418.076908)
			(xy 384.545182 -418.054264) (xy 384.597479 -418.038906) (xy 384.651429 -418.031147) (xy 384.678682 -418.03066)
			(xy 385.542282 -418.03066) (xy 385.569533 -418.031186) (xy 385.623482 -418.03894) (xy 385.675777 -418.054293)
			(xy 385.725356 -418.076933) (xy 385.771207 -418.106398) (xy 385.812399 -418.142089) (xy 385.848091 -418.183278)
			(xy 385.877558 -418.229129) (xy 385.9002 -418.278706) (xy 385.915556 -418.331001) (xy 385.923313 -418.384949)
			(xy 385.923313 -418.439451) (xy 385.923312 -418.439456) (xy 387.360823 -418.439456) (xy 387.360823 -418.384944)
			(xy 387.368581 -418.330986) (xy 387.38394 -418.278682) (xy 387.406586 -418.229097) (xy 387.436058 -418.183238)
			(xy 387.471757 -418.142042) (xy 387.512956 -418.106345) (xy 387.558816 -418.076875) (xy 387.608403 -418.054232)
			(xy 387.660708 -418.038877) (xy 387.714666 -418.031121) (xy 387.741922 -418.03066) (xy 388.605522 -418.03066)
			(xy 388.63277 -418.031212) (xy 388.686711 -418.03897) (xy 388.738998 -418.054326) (xy 388.788569 -418.076966)
			(xy 388.834412 -418.106431) (xy 388.875596 -418.142119) (xy 388.911283 -418.183305) (xy 388.940744 -418.229151)
			(xy 388.963382 -418.278722) (xy 388.978735 -418.331011) (xy 388.98649 -418.384952) (xy 388.98649 -418.439448)
			(xy 388.986489 -418.439452) (xy 390.424146 -418.439452) (xy 390.424146 -418.384948) (xy 390.431902 -418.330999)
			(xy 390.447256 -418.278703) (xy 390.469897 -418.229124) (xy 390.499362 -418.183272) (xy 390.535052 -418.142079)
			(xy 390.576241 -418.106385) (xy 390.622091 -418.076915) (xy 390.671668 -418.05427) (xy 390.723962 -418.03891)
			(xy 390.77791 -418.031148) (xy 390.805162 -418.03066) (xy 391.668762 -418.03066) (xy 391.696014 -418.031185)
			(xy 391.749965 -418.038937) (xy 391.802263 -418.054288) (xy 391.851844 -418.076926) (xy 391.897698 -418.106391)
			(xy 391.938891 -418.142082) (xy 391.974586 -418.183272) (xy 392.004055 -418.229123) (xy 392.026699 -418.278701)
			(xy 392.042055 -418.330998) (xy 392.049813 -418.384948) (xy 392.049813 -418.439452) (xy 392.049813 -418.439455)
			(xy 393.487323 -418.439455) (xy 393.487323 -418.384945) (xy 393.495081 -418.330989) (xy 393.510438 -418.278687)
			(xy 393.533083 -418.229102) (xy 393.562553 -418.183245) (xy 393.59825 -418.142049) (xy 393.639447 -418.106352)
			(xy 393.685304 -418.076882) (xy 393.734888 -418.054237) (xy 393.787191 -418.03888) (xy 393.841147 -418.031123)
			(xy 393.868402 -418.03066) (xy 394.732002 -418.03066) (xy 394.759251 -418.03121) (xy 394.813194 -418.038966)
			(xy 394.865484 -418.05432) (xy 394.915057 -418.07696) (xy 394.960903 -418.106424) (xy 395.002089 -418.142112)
			(xy 395.037778 -418.183299) (xy 395.067241 -418.229145) (xy 395.08988 -418.278718) (xy 395.105234 -418.331008)
			(xy 395.11299 -418.384951) (xy 395.11299 -418.439449) (xy 395.112989 -418.439457) (xy 396.550523 -418.439457)
			(xy 396.550523 -418.384943) (xy 396.558282 -418.330984) (xy 396.573641 -418.278678) (xy 396.596289 -418.229091)
			(xy 396.625763 -418.183232) (xy 396.661464 -418.142035) (xy 396.702666 -418.106338) (xy 396.748528 -418.076869)
			(xy 396.798117 -418.054227) (xy 396.850425 -418.038873) (xy 396.904385 -418.03112) (xy 396.931642 -418.03066)
			(xy 397.795242 -418.03066) (xy 397.822489 -418.031213) (xy 397.876428 -418.038974) (xy 397.928713 -418.054331)
			(xy 397.978281 -418.076973) (xy 398.024122 -418.106438) (xy 398.065303 -418.142126) (xy 398.100987 -418.183312)
			(xy 398.130447 -418.229156) (xy 398.153083 -418.278727) (xy 398.168435 -418.331014) (xy 398.17619 -418.384953)
			(xy 398.17619 -418.439447) (xy 398.176189 -418.439453) (xy 399.613846 -418.439453) (xy 399.613846 -418.384947)
			(xy 399.621603 -418.330997) (xy 399.636958 -418.278699) (xy 399.6596 -418.229119) (xy 399.689067 -418.183265)
			(xy 399.724759 -418.142072) (xy 399.765951 -418.106378) (xy 399.811803 -418.076908) (xy 399.861382 -418.054264)
			(xy 399.913679 -418.038906) (xy 399.967629 -418.031147) (xy 399.994882 -418.03066) (xy 400.858482 -418.03066)
			(xy 400.885733 -418.031186) (xy 400.939682 -418.03894) (xy 400.991977 -418.054293) (xy 401.041556 -418.076933)
			(xy 401.087407 -418.106398) (xy 401.128599 -418.142089) (xy 401.164291 -418.183278) (xy 401.193758 -418.229129)
			(xy 401.2164 -418.278706) (xy 401.231756 -418.331001) (xy 401.239513 -418.384949) (xy 401.239513 -418.439451)
			(xy 401.239512 -418.439456) (xy 402.677023 -418.439456) (xy 402.677023 -418.384944) (xy 402.684781 -418.330986)
			(xy 402.70014 -418.278682) (xy 402.722786 -418.229097) (xy 402.752258 -418.183238) (xy 402.787957 -418.142042)
			(xy 402.829156 -418.106345) (xy 402.875016 -418.076875) (xy 402.924603 -418.054232) (xy 402.976908 -418.038877)
			(xy 403.030866 -418.031121) (xy 403.058122 -418.03066) (xy 403.921722 -418.03066) (xy 403.94897 -418.031212)
			(xy 404.002911 -418.03897) (xy 404.055198 -418.054326) (xy 404.104769 -418.076966) (xy 404.150612 -418.106431)
			(xy 404.191796 -418.142119) (xy 404.227483 -418.183305) (xy 404.256944 -418.229151) (xy 404.279582 -418.278722)
			(xy 404.294935 -418.331011) (xy 404.30269 -418.384952) (xy 404.30269 -418.439448) (xy 404.302689 -418.439452)
			(xy 405.740346 -418.439452) (xy 405.740346 -418.384948) (xy 405.748102 -418.330999) (xy 405.763456 -418.278703)
			(xy 405.786097 -418.229124) (xy 405.815562 -418.183272) (xy 405.851252 -418.142079) (xy 405.892441 -418.106385)
			(xy 405.938291 -418.076915) (xy 405.987868 -418.05427) (xy 406.040162 -418.03891) (xy 406.09411 -418.031148)
			(xy 406.121362 -418.03066) (xy 406.984962 -418.03066) (xy 407.012214 -418.031185) (xy 407.066165 -418.038937)
			(xy 407.118463 -418.054288) (xy 407.168044 -418.076926) (xy 407.213898 -418.106391) (xy 407.255091 -418.142082)
			(xy 407.290786 -418.183272) (xy 407.320255 -418.229123) (xy 407.342899 -418.278701) (xy 407.358255 -418.330998)
			(xy 407.366013 -418.384948) (xy 407.366013 -418.439452) (xy 407.366013 -418.439455) (xy 408.803523 -418.439455)
			(xy 408.803523 -418.384945) (xy 408.811281 -418.330989) (xy 408.826638 -418.278687) (xy 408.849283 -418.229102)
			(xy 408.878753 -418.183245) (xy 408.91445 -418.142049) (xy 408.955647 -418.106352) (xy 409.001504 -418.076882)
			(xy 409.051088 -418.054237) (xy 409.103391 -418.03888) (xy 409.157347 -418.031123) (xy 409.184602 -418.03066)
			(xy 410.048202 -418.03066) (xy 410.075451 -418.03121) (xy 410.129394 -418.038966) (xy 410.181684 -418.05432)
			(xy 410.231257 -418.07696) (xy 410.277103 -418.106424) (xy 410.318289 -418.142112) (xy 410.353978 -418.183299)
			(xy 410.383441 -418.229145) (xy 410.40608 -418.278718) (xy 410.421434 -418.331008) (xy 410.42919 -418.384951)
			(xy 410.42919 -418.439449) (xy 410.429189 -418.439457) (xy 411.866723 -418.439457) (xy 411.866723 -418.384943)
			(xy 411.874482 -418.330984) (xy 411.889841 -418.278678) (xy 411.912489 -418.229091) (xy 411.941963 -418.183232)
			(xy 411.977664 -418.142035) (xy 412.018866 -418.106338) (xy 412.064728 -418.076869) (xy 412.114317 -418.054227)
			(xy 412.166625 -418.038873) (xy 412.220585 -418.03112) (xy 412.247842 -418.03066) (xy 413.111442 -418.03066)
			(xy 413.138689 -418.031213) (xy 413.192628 -418.038974) (xy 413.244913 -418.054331) (xy 413.294481 -418.076973)
			(xy 413.340322 -418.106438) (xy 413.381503 -418.142126) (xy 413.417187 -418.183312) (xy 413.446647 -418.229156)
			(xy 413.469283 -418.278727) (xy 413.484635 -418.331014) (xy 413.49239 -418.384953) (xy 413.49239 -418.439447)
			(xy 413.492389 -418.439453) (xy 414.930046 -418.439453) (xy 414.930046 -418.384947) (xy 414.937803 -418.330997)
			(xy 414.953158 -418.278699) (xy 414.9758 -418.229119) (xy 415.005267 -418.183265) (xy 415.040959 -418.142072)
			(xy 415.082151 -418.106378) (xy 415.128003 -418.076908) (xy 415.177582 -418.054264) (xy 415.229879 -418.038906)
			(xy 415.283829 -418.031147) (xy 415.311082 -418.03066) (xy 416.174682 -418.03066) (xy 416.201933 -418.031186)
			(xy 416.255882 -418.03894) (xy 416.308177 -418.054293) (xy 416.357756 -418.076933) (xy 416.403607 -418.106398)
			(xy 416.444799 -418.142089) (xy 416.480491 -418.183278) (xy 416.509958 -418.229129) (xy 416.5326 -418.278706)
			(xy 416.547956 -418.331001) (xy 416.555713 -418.384949) (xy 416.555713 -418.439451) (xy 416.555712 -418.439456)
			(xy 417.993223 -418.439456) (xy 417.993223 -418.384944) (xy 418.000981 -418.330986) (xy 418.01634 -418.278682)
			(xy 418.038986 -418.229097) (xy 418.068458 -418.183238) (xy 418.104157 -418.142042) (xy 418.145356 -418.106345)
			(xy 418.191216 -418.076875) (xy 418.240803 -418.054232) (xy 418.293108 -418.038877) (xy 418.347066 -418.031121)
			(xy 418.374322 -418.03066) (xy 419.237922 -418.03066) (xy 419.26517 -418.031212) (xy 419.319111 -418.03897)
			(xy 419.371398 -418.054326) (xy 419.420969 -418.076966) (xy 419.466812 -418.106431) (xy 419.507996 -418.142119)
			(xy 419.543683 -418.183305) (xy 419.573144 -418.229151) (xy 419.595782 -418.278722) (xy 419.611135 -418.331011)
			(xy 419.61889 -418.384952) (xy 419.61889 -418.439448) (xy 419.611135 -418.493389) (xy 419.595782 -418.545678)
			(xy 419.573144 -418.595249) (xy 419.543683 -418.641095) (xy 419.507996 -418.682281) (xy 419.466812 -418.717969)
			(xy 419.420969 -418.747434) (xy 419.371398 -418.770074) (xy 419.319111 -418.78543) (xy 419.26517 -418.793188)
			(xy 419.237922 -418.793676) (xy 418.374322 -418.793676) (xy 418.347066 -418.793279) (xy 418.293108 -418.785523)
			(xy 418.240803 -418.770168) (xy 418.191216 -418.747525) (xy 418.145356 -418.718055) (xy 418.104157 -418.682358)
			(xy 418.068458 -418.641162) (xy 418.038986 -418.595303) (xy 418.01634 -418.545718) (xy 418.000981 -418.493414)
			(xy 417.993223 -418.439456) (xy 416.555712 -418.439456) (xy 416.547956 -418.493399) (xy 416.5326 -418.545694)
			(xy 416.509958 -418.595271) (xy 416.480491 -418.641122) (xy 416.444799 -418.682311) (xy 416.403607 -418.718002)
			(xy 416.357756 -418.747467) (xy 416.308177 -418.770107) (xy 416.255882 -418.78546) (xy 416.201933 -418.793214)
			(xy 416.174682 -418.793676) (xy 415.311082 -418.793676) (xy 415.283829 -418.793253) (xy 415.229879 -418.785494)
			(xy 415.177582 -418.770136) (xy 415.128003 -418.747492) (xy 415.082151 -418.718022) (xy 415.040959 -418.682328)
			(xy 415.005267 -418.641135) (xy 414.9758 -418.595281) (xy 414.953158 -418.545701) (xy 414.937803 -418.493403)
			(xy 414.930046 -418.439453) (xy 413.492389 -418.439453) (xy 413.484635 -418.493386) (xy 413.469283 -418.545673)
			(xy 413.446647 -418.595244) (xy 413.417187 -418.641088) (xy 413.381503 -418.682274) (xy 413.340322 -418.717962)
			(xy 413.294481 -418.747427) (xy 413.244913 -418.770069) (xy 413.192628 -418.785426) (xy 413.138689 -418.793187)
			(xy 413.111442 -418.793676) (xy 412.247842 -418.793676) (xy 412.220585 -418.79328) (xy 412.166625 -418.785527)
			(xy 412.114317 -418.770173) (xy 412.064728 -418.747531) (xy 412.018866 -418.718062) (xy 411.977664 -418.682365)
			(xy 411.941963 -418.641168) (xy 411.912489 -418.595309) (xy 411.889841 -418.545722) (xy 411.874482 -418.493416)
			(xy 411.866723 -418.439457) (xy 410.429189 -418.439457) (xy 410.421434 -418.493392) (xy 410.40608 -418.545682)
			(xy 410.383441 -418.595255) (xy 410.353978 -418.641101) (xy 410.318289 -418.682288) (xy 410.277103 -418.717976)
			(xy 410.231257 -418.74744) (xy 410.181684 -418.77008) (xy 410.129394 -418.785434) (xy 410.075451 -418.79319)
			(xy 410.048202 -418.793676) (xy 409.184602 -418.793676) (xy 409.157347 -418.793277) (xy 409.103391 -418.78552)
			(xy 409.051088 -418.770163) (xy 409.001504 -418.747518) (xy 408.955647 -418.718048) (xy 408.91445 -418.682351)
			(xy 408.878753 -418.641155) (xy 408.849283 -418.595298) (xy 408.826638 -418.545713) (xy 408.811281 -418.493411)
			(xy 408.803523 -418.439455) (xy 407.366013 -418.439455) (xy 407.358255 -418.493402) (xy 407.342899 -418.545699)
			(xy 407.320255 -418.595277) (xy 407.290786 -418.641128) (xy 407.255091 -418.682318) (xy 407.213898 -418.718009)
			(xy 407.168044 -418.747474) (xy 407.118463 -418.770112) (xy 407.066165 -418.785463) (xy 407.012214 -418.793215)
			(xy 406.984962 -418.793676) (xy 406.121362 -418.793676) (xy 406.09411 -418.793252) (xy 406.040162 -418.78549)
			(xy 405.987868 -418.77013) (xy 405.938291 -418.747485) (xy 405.892441 -418.718015) (xy 405.851252 -418.682321)
			(xy 405.815562 -418.641128) (xy 405.786097 -418.595276) (xy 405.763456 -418.545697) (xy 405.748102 -418.493401)
			(xy 405.740346 -418.439452) (xy 404.302689 -418.439452) (xy 404.294935 -418.493389) (xy 404.279582 -418.545678)
			(xy 404.256944 -418.595249) (xy 404.227483 -418.641095) (xy 404.191796 -418.682281) (xy 404.150612 -418.717969)
			(xy 404.104769 -418.747434) (xy 404.055198 -418.770074) (xy 404.002911 -418.78543) (xy 403.94897 -418.793188)
			(xy 403.921722 -418.793676) (xy 403.058122 -418.793676) (xy 403.030866 -418.793279) (xy 402.976908 -418.785523)
			(xy 402.924603 -418.770168) (xy 402.875016 -418.747525) (xy 402.829156 -418.718055) (xy 402.787957 -418.682358)
			(xy 402.752258 -418.641162) (xy 402.722786 -418.595303) (xy 402.70014 -418.545718) (xy 402.684781 -418.493414)
			(xy 402.677023 -418.439456) (xy 401.239512 -418.439456) (xy 401.231756 -418.493399) (xy 401.2164 -418.545694)
			(xy 401.193758 -418.595271) (xy 401.164291 -418.641122) (xy 401.128599 -418.682311) (xy 401.087407 -418.718002)
			(xy 401.041556 -418.747467) (xy 400.991977 -418.770107) (xy 400.939682 -418.78546) (xy 400.885733 -418.793214)
			(xy 400.858482 -418.793676) (xy 399.994882 -418.793676) (xy 399.967629 -418.793253) (xy 399.913679 -418.785494)
			(xy 399.861382 -418.770136) (xy 399.811803 -418.747492) (xy 399.765951 -418.718022) (xy 399.724759 -418.682328)
			(xy 399.689067 -418.641135) (xy 399.6596 -418.595281) (xy 399.636958 -418.545701) (xy 399.621603 -418.493403)
			(xy 399.613846 -418.439453) (xy 398.176189 -418.439453) (xy 398.168435 -418.493386) (xy 398.153083 -418.545673)
			(xy 398.130447 -418.595244) (xy 398.100987 -418.641088) (xy 398.065303 -418.682274) (xy 398.024122 -418.717962)
			(xy 397.978281 -418.747427) (xy 397.928713 -418.770069) (xy 397.876428 -418.785426) (xy 397.822489 -418.793187)
			(xy 397.795242 -418.793676) (xy 396.931642 -418.793676) (xy 396.904385 -418.79328) (xy 396.850425 -418.785527)
			(xy 396.798117 -418.770173) (xy 396.748528 -418.747531) (xy 396.702666 -418.718062) (xy 396.661464 -418.682365)
			(xy 396.625763 -418.641168) (xy 396.596289 -418.595309) (xy 396.573641 -418.545722) (xy 396.558282 -418.493416)
			(xy 396.550523 -418.439457) (xy 395.112989 -418.439457) (xy 395.105234 -418.493392) (xy 395.08988 -418.545682)
			(xy 395.067241 -418.595255) (xy 395.037778 -418.641101) (xy 395.002089 -418.682288) (xy 394.960903 -418.717976)
			(xy 394.915057 -418.74744) (xy 394.865484 -418.77008) (xy 394.813194 -418.785434) (xy 394.759251 -418.79319)
			(xy 394.732002 -418.793676) (xy 393.868402 -418.793676) (xy 393.841147 -418.793277) (xy 393.787191 -418.78552)
			(xy 393.734888 -418.770163) (xy 393.685304 -418.747518) (xy 393.639447 -418.718048) (xy 393.59825 -418.682351)
			(xy 393.562553 -418.641155) (xy 393.533083 -418.595298) (xy 393.510438 -418.545713) (xy 393.495081 -418.493411)
			(xy 393.487323 -418.439455) (xy 392.049813 -418.439455) (xy 392.042055 -418.493402) (xy 392.026699 -418.545699)
			(xy 392.004055 -418.595277) (xy 391.974586 -418.641128) (xy 391.938891 -418.682318) (xy 391.897698 -418.718009)
			(xy 391.851844 -418.747474) (xy 391.802263 -418.770112) (xy 391.749965 -418.785463) (xy 391.696014 -418.793215)
			(xy 391.668762 -418.793676) (xy 390.805162 -418.793676) (xy 390.77791 -418.793252) (xy 390.723962 -418.78549)
			(xy 390.671668 -418.77013) (xy 390.622091 -418.747485) (xy 390.576241 -418.718015) (xy 390.535052 -418.682321)
			(xy 390.499362 -418.641128) (xy 390.469897 -418.595276) (xy 390.447256 -418.545697) (xy 390.431902 -418.493401)
			(xy 390.424146 -418.439452) (xy 388.986489 -418.439452) (xy 388.978735 -418.493389) (xy 388.963382 -418.545678)
			(xy 388.940744 -418.595249) (xy 388.911283 -418.641095) (xy 388.875596 -418.682281) (xy 388.834412 -418.717969)
			(xy 388.788569 -418.747434) (xy 388.738998 -418.770074) (xy 388.686711 -418.78543) (xy 388.63277 -418.793188)
			(xy 388.605522 -418.793676) (xy 387.741922 -418.793676) (xy 387.714666 -418.793279) (xy 387.660708 -418.785523)
			(xy 387.608403 -418.770168) (xy 387.558816 -418.747525) (xy 387.512956 -418.718055) (xy 387.471757 -418.682358)
			(xy 387.436058 -418.641162) (xy 387.406586 -418.595303) (xy 387.38394 -418.545718) (xy 387.368581 -418.493414)
			(xy 387.360823 -418.439456) (xy 385.923312 -418.439456) (xy 385.915556 -418.493399) (xy 385.9002 -418.545694)
			(xy 385.877558 -418.595271) (xy 385.848091 -418.641122) (xy 385.812399 -418.682311) (xy 385.771207 -418.718002)
			(xy 385.725356 -418.747467) (xy 385.675777 -418.770107) (xy 385.623482 -418.78546) (xy 385.569533 -418.793214)
			(xy 385.542282 -418.793676) (xy 384.678682 -418.793676) (xy 384.651429 -418.793253) (xy 384.597479 -418.785494)
			(xy 384.545182 -418.770136) (xy 384.495603 -418.747492) (xy 384.449751 -418.718022) (xy 384.408559 -418.682328)
			(xy 384.372867 -418.641135) (xy 384.3434 -418.595281) (xy 384.320758 -418.545701) (xy 384.305403 -418.493403)
			(xy 384.297646 -418.439453) (xy 382.859989 -418.439453) (xy 382.852235 -418.493386) (xy 382.836883 -418.545673)
			(xy 382.814247 -418.595244) (xy 382.784787 -418.641088) (xy 382.749103 -418.682274) (xy 382.707922 -418.717962)
			(xy 382.662081 -418.747427) (xy 382.612513 -418.770069) (xy 382.560228 -418.785426) (xy 382.506289 -418.793187)
			(xy 382.479042 -418.793676) (xy 381.615442 -418.793676) (xy 381.588185 -418.79328) (xy 381.534225 -418.785527)
			(xy 381.481917 -418.770173) (xy 381.432328 -418.747531) (xy 381.386466 -418.718062) (xy 381.345264 -418.682365)
			(xy 381.309563 -418.641168) (xy 381.280089 -418.595309) (xy 381.257441 -418.545722) (xy 381.242082 -418.493416)
			(xy 381.234323 -418.439457) (xy 379.796789 -418.439457) (xy 379.789034 -418.493392) (xy 379.77368 -418.545682)
			(xy 379.751041 -418.595255) (xy 379.721578 -418.641101) (xy 379.685889 -418.682288) (xy 379.644703 -418.717976)
			(xy 379.598857 -418.74744) (xy 379.549284 -418.77008) (xy 379.496994 -418.785434) (xy 379.443051 -418.79319)
			(xy 379.415802 -418.793676) (xy 378.552202 -418.793676) (xy 378.524947 -418.793277) (xy 378.470991 -418.78552)
			(xy 378.418688 -418.770163) (xy 378.369104 -418.747518) (xy 378.323247 -418.718048) (xy 378.28205 -418.682351)
			(xy 378.246353 -418.641155) (xy 378.216883 -418.595298) (xy 378.194238 -418.545713) (xy 378.178881 -418.493411)
			(xy 378.171123 -418.439455) (xy 376.733613 -418.439455) (xy 376.725855 -418.493402) (xy 376.710499 -418.545699)
			(xy 376.687855 -418.595277) (xy 376.658386 -418.641128) (xy 376.622691 -418.682318) (xy 376.581498 -418.718009)
			(xy 376.535644 -418.747474) (xy 376.486063 -418.770112) (xy 376.433765 -418.785463) (xy 376.379814 -418.793215)
			(xy 376.352562 -418.793676) (xy 375.488962 -418.793676) (xy 375.46171 -418.793252) (xy 375.407762 -418.78549)
			(xy 375.355468 -418.77013) (xy 375.305891 -418.747485) (xy 375.260041 -418.718015) (xy 375.218852 -418.682321)
			(xy 375.183162 -418.641128) (xy 375.153697 -418.595276) (xy 375.131056 -418.545697) (xy 375.115702 -418.493401)
			(xy 375.107946 -418.439452) (xy 373.670289 -418.439452) (xy 373.662535 -418.493389) (xy 373.647182 -418.545678)
			(xy 373.624544 -418.595249) (xy 373.595083 -418.641095) (xy 373.559396 -418.682281) (xy 373.518212 -418.717969)
			(xy 373.472369 -418.747434) (xy 373.422798 -418.770074) (xy 373.370511 -418.78543) (xy 373.31657 -418.793188)
			(xy 373.289322 -418.793676) (xy 372.425722 -418.793676) (xy 372.398466 -418.793279) (xy 372.344508 -418.785523)
			(xy 372.292203 -418.770168) (xy 372.242616 -418.747525) (xy 372.196756 -418.718055) (xy 372.155557 -418.682358)
			(xy 372.119858 -418.641162) (xy 372.090386 -418.595303) (xy 372.06774 -418.545718) (xy 372.052381 -418.493414)
			(xy 372.044623 -418.439456) (xy 370.313204 -418.439456) (xy 370.313204 -420.692072) (xy 370.313204 -420.739316)
			(xy 370.262404 -420.739316) (xy 370.16182 -420.739316) (xy 370.150438 -420.74117) (xy 370.131001 -420.753543)
			(xy 370.118864 -420.773128) (xy 370.117116 -420.784528) (xy 370.117116 -420.979455) (xy 370.513023 -420.979455)
			(xy 370.513023 -420.924945) (xy 370.520781 -420.870989) (xy 370.536138 -420.818687) (xy 370.558783 -420.769102)
			(xy 370.588253 -420.723245) (xy 370.62395 -420.682049) (xy 370.665147 -420.646352) (xy 370.711004 -420.616882)
			(xy 370.760588 -420.594237) (xy 370.812891 -420.57888) (xy 370.866847 -420.571123) (xy 370.894102 -420.57066)
			(xy 371.757702 -420.57066) (xy 371.784951 -420.57121) (xy 371.838894 -420.578966) (xy 371.891184 -420.59432)
			(xy 371.940757 -420.61696) (xy 371.986603 -420.646424) (xy 372.027789 -420.682112) (xy 372.063478 -420.723299)
			(xy 372.092941 -420.769145) (xy 372.11558 -420.818718) (xy 372.130934 -420.871008) (xy 372.13869 -420.924951)
			(xy 372.13869 -420.979449) (xy 372.138689 -420.979457) (xy 373.576223 -420.979457) (xy 373.576223 -420.924943)
			(xy 373.583982 -420.870984) (xy 373.599341 -420.818678) (xy 373.621989 -420.769091) (xy 373.651463 -420.723232)
			(xy 373.687164 -420.682035) (xy 373.728366 -420.646338) (xy 373.774228 -420.616869) (xy 373.823817 -420.594227)
			(xy 373.876125 -420.578873) (xy 373.930085 -420.57112) (xy 373.957342 -420.57066) (xy 374.820942 -420.57066)
			(xy 374.848189 -420.571213) (xy 374.902128 -420.578974) (xy 374.954413 -420.594331) (xy 375.003981 -420.616973)
			(xy 375.049822 -420.646438) (xy 375.091003 -420.682126) (xy 375.126687 -420.723312) (xy 375.156147 -420.769156)
			(xy 375.178783 -420.818727) (xy 375.194135 -420.871014) (xy 375.20189 -420.924953) (xy 375.20189 -420.979447)
			(xy 375.201889 -420.979453) (xy 376.639546 -420.979453) (xy 376.639546 -420.924947) (xy 376.647303 -420.870997)
			(xy 376.662658 -420.818699) (xy 376.6853 -420.769119) (xy 376.714767 -420.723265) (xy 376.750459 -420.682072)
			(xy 376.791651 -420.646378) (xy 376.837503 -420.616908) (xy 376.887082 -420.594264) (xy 376.939379 -420.578906)
			(xy 376.993329 -420.571147) (xy 377.020582 -420.57066) (xy 377.884182 -420.57066) (xy 377.911433 -420.571186)
			(xy 377.965382 -420.57894) (xy 378.017677 -420.594293) (xy 378.067256 -420.616933) (xy 378.113107 -420.646398)
			(xy 378.154299 -420.682089) (xy 378.189991 -420.723278) (xy 378.219458 -420.769129) (xy 378.2421 -420.818706)
			(xy 378.257456 -420.871001) (xy 378.265213 -420.924949) (xy 378.265213 -420.979451) (xy 378.265212 -420.979456)
			(xy 379.702723 -420.979456) (xy 379.702723 -420.924944) (xy 379.710481 -420.870986) (xy 379.72584 -420.818682)
			(xy 379.748486 -420.769097) (xy 379.777958 -420.723238) (xy 379.813657 -420.682042) (xy 379.854856 -420.646345)
			(xy 379.900716 -420.616875) (xy 379.950303 -420.594232) (xy 380.002608 -420.578877) (xy 380.056566 -420.571121)
			(xy 380.083822 -420.57066) (xy 380.947422 -420.57066) (xy 380.97467 -420.571212) (xy 381.028611 -420.57897)
			(xy 381.080898 -420.594326) (xy 381.130469 -420.616966) (xy 381.176312 -420.646431) (xy 381.217496 -420.682119)
			(xy 381.253183 -420.723305) (xy 381.282644 -420.769151) (xy 381.305282 -420.818722) (xy 381.320635 -420.871011)
			(xy 381.32839 -420.924952) (xy 381.32839 -420.979448) (xy 381.328389 -420.979452) (xy 382.766046 -420.979452)
			(xy 382.766046 -420.924948) (xy 382.773802 -420.870999) (xy 382.789156 -420.818703) (xy 382.811797 -420.769124)
			(xy 382.841262 -420.723272) (xy 382.876952 -420.682079) (xy 382.918141 -420.646385) (xy 382.963991 -420.616915)
			(xy 383.013568 -420.59427) (xy 383.065862 -420.57891) (xy 383.11981 -420.571148) (xy 383.147062 -420.57066)
			(xy 384.010662 -420.57066) (xy 384.037914 -420.571185) (xy 384.091865 -420.578937) (xy 384.144163 -420.594288)
			(xy 384.193744 -420.616926) (xy 384.239598 -420.646391) (xy 384.280791 -420.682082) (xy 384.316486 -420.723272)
			(xy 384.345955 -420.769123) (xy 384.368599 -420.818701) (xy 384.383955 -420.870998) (xy 384.391713 -420.924948)
			(xy 384.391713 -420.979452) (xy 384.391713 -420.979455) (xy 385.829223 -420.979455) (xy 385.829223 -420.924945)
			(xy 385.836981 -420.870989) (xy 385.852338 -420.818687) (xy 385.874983 -420.769102) (xy 385.904453 -420.723245)
			(xy 385.94015 -420.682049) (xy 385.981347 -420.646352) (xy 386.027204 -420.616882) (xy 386.076788 -420.594237)
			(xy 386.129091 -420.57888) (xy 386.183047 -420.571123) (xy 386.210302 -420.57066) (xy 387.073902 -420.57066)
			(xy 387.101151 -420.57121) (xy 387.155094 -420.578966) (xy 387.207384 -420.59432) (xy 387.256957 -420.61696)
			(xy 387.302803 -420.646424) (xy 387.343989 -420.682112) (xy 387.379678 -420.723299) (xy 387.409141 -420.769145)
			(xy 387.43178 -420.818718) (xy 387.447134 -420.871008) (xy 387.45489 -420.924951) (xy 387.45489 -420.979449)
			(xy 387.454889 -420.979457) (xy 388.892423 -420.979457) (xy 388.892423 -420.924943) (xy 388.900182 -420.870984)
			(xy 388.915541 -420.818678) (xy 388.938189 -420.769091) (xy 388.967663 -420.723232) (xy 389.003364 -420.682035)
			(xy 389.044566 -420.646338) (xy 389.090428 -420.616869) (xy 389.140017 -420.594227) (xy 389.192325 -420.578873)
			(xy 389.246285 -420.57112) (xy 389.273542 -420.57066) (xy 390.137142 -420.57066) (xy 390.164389 -420.571213)
			(xy 390.218328 -420.578974) (xy 390.270613 -420.594331) (xy 390.320181 -420.616973) (xy 390.366022 -420.646438)
			(xy 390.407203 -420.682126) (xy 390.442887 -420.723312) (xy 390.472347 -420.769156) (xy 390.494983 -420.818727)
			(xy 390.510335 -420.871014) (xy 390.51809 -420.924953) (xy 390.51809 -420.979447) (xy 390.518089 -420.979453)
			(xy 391.955746 -420.979453) (xy 391.955746 -420.924947) (xy 391.963503 -420.870997) (xy 391.978858 -420.818699)
			(xy 392.0015 -420.769119) (xy 392.030967 -420.723265) (xy 392.066659 -420.682072) (xy 392.107851 -420.646378)
			(xy 392.153703 -420.616908) (xy 392.203282 -420.594264) (xy 392.255579 -420.578906) (xy 392.309529 -420.571147)
			(xy 392.336782 -420.57066) (xy 393.200382 -420.57066) (xy 393.227633 -420.571186) (xy 393.281582 -420.57894)
			(xy 393.333877 -420.594293) (xy 393.383456 -420.616933) (xy 393.429307 -420.646398) (xy 393.470499 -420.682089)
			(xy 393.506191 -420.723278) (xy 393.535658 -420.769129) (xy 393.5583 -420.818706) (xy 393.573656 -420.871001)
			(xy 393.581413 -420.924949) (xy 393.581413 -420.979451) (xy 393.581412 -420.979456) (xy 395.018923 -420.979456)
			(xy 395.018923 -420.924944) (xy 395.026681 -420.870986) (xy 395.04204 -420.818682) (xy 395.064686 -420.769097)
			(xy 395.094158 -420.723238) (xy 395.129857 -420.682042) (xy 395.171056 -420.646345) (xy 395.216916 -420.616875)
			(xy 395.266503 -420.594232) (xy 395.318808 -420.578877) (xy 395.372766 -420.571121) (xy 395.400022 -420.57066)
			(xy 396.263622 -420.57066) (xy 396.29087 -420.571212) (xy 396.344811 -420.57897) (xy 396.397098 -420.594326)
			(xy 396.446669 -420.616966) (xy 396.492512 -420.646431) (xy 396.533696 -420.682119) (xy 396.569383 -420.723305)
			(xy 396.598844 -420.769151) (xy 396.621482 -420.818722) (xy 396.636835 -420.871011) (xy 396.64459 -420.924952)
			(xy 396.64459 -420.979448) (xy 396.644589 -420.979452) (xy 398.082246 -420.979452) (xy 398.082246 -420.924948)
			(xy 398.090002 -420.870999) (xy 398.105356 -420.818703) (xy 398.127997 -420.769124) (xy 398.157462 -420.723272)
			(xy 398.193152 -420.682079) (xy 398.234341 -420.646385) (xy 398.280191 -420.616915) (xy 398.329768 -420.59427)
			(xy 398.382062 -420.57891) (xy 398.43601 -420.571148) (xy 398.463262 -420.57066) (xy 399.326862 -420.57066)
			(xy 399.354114 -420.571185) (xy 399.408065 -420.578937) (xy 399.460363 -420.594288) (xy 399.509944 -420.616926)
			(xy 399.555798 -420.646391) (xy 399.596991 -420.682082) (xy 399.632686 -420.723272) (xy 399.662155 -420.769123)
			(xy 399.684799 -420.818701) (xy 399.700155 -420.870998) (xy 399.707913 -420.924948) (xy 399.707913 -420.979452)
			(xy 399.707913 -420.979455) (xy 401.145423 -420.979455) (xy 401.145423 -420.924945) (xy 401.153181 -420.870989)
			(xy 401.168538 -420.818687) (xy 401.191183 -420.769102) (xy 401.220653 -420.723245) (xy 401.25635 -420.682049)
			(xy 401.297547 -420.646352) (xy 401.343404 -420.616882) (xy 401.392988 -420.594237) (xy 401.445291 -420.57888)
			(xy 401.499247 -420.571123) (xy 401.526502 -420.57066) (xy 402.390102 -420.57066) (xy 402.417351 -420.57121)
			(xy 402.471294 -420.578966) (xy 402.523584 -420.59432) (xy 402.573157 -420.61696) (xy 402.619003 -420.646424)
			(xy 402.660189 -420.682112) (xy 402.695878 -420.723299) (xy 402.725341 -420.769145) (xy 402.74798 -420.818718)
			(xy 402.763334 -420.871008) (xy 402.77109 -420.924951) (xy 402.77109 -420.979449) (xy 402.771089 -420.979457)
			(xy 404.208623 -420.979457) (xy 404.208623 -420.924943) (xy 404.216382 -420.870984) (xy 404.231741 -420.818678)
			(xy 404.254389 -420.769091) (xy 404.283863 -420.723232) (xy 404.319564 -420.682035) (xy 404.360766 -420.646338)
			(xy 404.406628 -420.616869) (xy 404.456217 -420.594227) (xy 404.508525 -420.578873) (xy 404.562485 -420.57112)
			(xy 404.589742 -420.57066) (xy 405.453342 -420.57066) (xy 405.480589 -420.571213) (xy 405.534528 -420.578974)
			(xy 405.586813 -420.594331) (xy 405.636381 -420.616973) (xy 405.682222 -420.646438) (xy 405.723403 -420.682126)
			(xy 405.759087 -420.723312) (xy 405.788547 -420.769156) (xy 405.811183 -420.818727) (xy 405.826535 -420.871014)
			(xy 405.83429 -420.924953) (xy 405.83429 -420.979447) (xy 405.834289 -420.979453) (xy 407.271946 -420.979453)
			(xy 407.271946 -420.924947) (xy 407.279703 -420.870997) (xy 407.295058 -420.818699) (xy 407.3177 -420.769119)
			(xy 407.347167 -420.723265) (xy 407.382859 -420.682072) (xy 407.424051 -420.646378) (xy 407.469903 -420.616908)
			(xy 407.519482 -420.594264) (xy 407.571779 -420.578906) (xy 407.625729 -420.571147) (xy 407.652982 -420.57066)
			(xy 408.516582 -420.57066) (xy 408.543833 -420.571186) (xy 408.597782 -420.57894) (xy 408.650077 -420.594293)
			(xy 408.699656 -420.616933) (xy 408.745507 -420.646398) (xy 408.786699 -420.682089) (xy 408.822391 -420.723278)
			(xy 408.851858 -420.769129) (xy 408.8745 -420.818706) (xy 408.889856 -420.871001) (xy 408.897613 -420.924949)
			(xy 408.897613 -420.979451) (xy 408.897612 -420.979456) (xy 410.335123 -420.979456) (xy 410.335123 -420.924944)
			(xy 410.342881 -420.870986) (xy 410.35824 -420.818682) (xy 410.380886 -420.769097) (xy 410.410358 -420.723238)
			(xy 410.446057 -420.682042) (xy 410.487256 -420.646345) (xy 410.533116 -420.616875) (xy 410.582703 -420.594232)
			(xy 410.635008 -420.578877) (xy 410.688966 -420.571121) (xy 410.716222 -420.57066) (xy 411.579822 -420.57066)
			(xy 411.60707 -420.571212) (xy 411.661011 -420.57897) (xy 411.713298 -420.594326) (xy 411.762869 -420.616966)
			(xy 411.808712 -420.646431) (xy 411.849896 -420.682119) (xy 411.885583 -420.723305) (xy 411.915044 -420.769151)
			(xy 411.937682 -420.818722) (xy 411.953035 -420.871011) (xy 411.96079 -420.924952) (xy 411.96079 -420.979448)
			(xy 411.960789 -420.979452) (xy 413.398446 -420.979452) (xy 413.398446 -420.924948) (xy 413.406202 -420.870999)
			(xy 413.421556 -420.818703) (xy 413.444197 -420.769124) (xy 413.473662 -420.723272) (xy 413.509352 -420.682079)
			(xy 413.550541 -420.646385) (xy 413.596391 -420.616915) (xy 413.645968 -420.59427) (xy 413.698262 -420.57891)
			(xy 413.75221 -420.571148) (xy 413.779462 -420.57066) (xy 414.643062 -420.57066) (xy 414.670314 -420.571185)
			(xy 414.724265 -420.578937) (xy 414.776563 -420.594288) (xy 414.826144 -420.616926) (xy 414.871998 -420.646391)
			(xy 414.913191 -420.682082) (xy 414.948886 -420.723272) (xy 414.978355 -420.769123) (xy 415.000999 -420.818701)
			(xy 415.016355 -420.870998) (xy 415.024113 -420.924948) (xy 415.024113 -420.979452) (xy 415.024113 -420.979455)
			(xy 416.461623 -420.979455) (xy 416.461623 -420.924945) (xy 416.469381 -420.870989) (xy 416.484738 -420.818687)
			(xy 416.507383 -420.769102) (xy 416.536853 -420.723245) (xy 416.57255 -420.682049) (xy 416.613747 -420.646352)
			(xy 416.659604 -420.616882) (xy 416.709188 -420.594237) (xy 416.761491 -420.57888) (xy 416.815447 -420.571123)
			(xy 416.842702 -420.57066) (xy 417.706302 -420.57066) (xy 417.733551 -420.57121) (xy 417.787494 -420.578966)
			(xy 417.839784 -420.59432) (xy 417.889357 -420.61696) (xy 417.935203 -420.646424) (xy 417.976389 -420.682112)
			(xy 418.012078 -420.723299) (xy 418.041541 -420.769145) (xy 418.06418 -420.818718) (xy 418.079534 -420.871008)
			(xy 418.08729 -420.924951) (xy 418.08729 -420.979449) (xy 418.079534 -421.033392) (xy 418.06418 -421.085682)
			(xy 418.041541 -421.135255) (xy 418.012078 -421.181101) (xy 417.976389 -421.222288) (xy 417.935203 -421.257976)
			(xy 417.889357 -421.28744) (xy 417.839784 -421.31008) (xy 417.787494 -421.325434) (xy 417.733551 -421.33319)
			(xy 417.706302 -421.333676) (xy 416.842702 -421.333676) (xy 416.815447 -421.333277) (xy 416.761491 -421.32552)
			(xy 416.709188 -421.310163) (xy 416.659604 -421.287518) (xy 416.613747 -421.258048) (xy 416.57255 -421.222351)
			(xy 416.536853 -421.181155) (xy 416.507383 -421.135298) (xy 416.484738 -421.085713) (xy 416.469381 -421.033411)
			(xy 416.461623 -420.979455) (xy 415.024113 -420.979455) (xy 415.016355 -421.033402) (xy 415.000999 -421.085699)
			(xy 414.978355 -421.135277) (xy 414.948886 -421.181128) (xy 414.913191 -421.222318) (xy 414.871998 -421.258009)
			(xy 414.826144 -421.287474) (xy 414.776563 -421.310112) (xy 414.724265 -421.325463) (xy 414.670314 -421.333215)
			(xy 414.643062 -421.333676) (xy 413.779462 -421.333676) (xy 413.75221 -421.333252) (xy 413.698262 -421.32549)
			(xy 413.645968 -421.31013) (xy 413.596391 -421.287485) (xy 413.550541 -421.258015) (xy 413.509352 -421.222321)
			(xy 413.473662 -421.181128) (xy 413.444197 -421.135276) (xy 413.421556 -421.085697) (xy 413.406202 -421.033401)
			(xy 413.398446 -420.979452) (xy 411.960789 -420.979452) (xy 411.953035 -421.033389) (xy 411.937682 -421.085678)
			(xy 411.915044 -421.135249) (xy 411.885583 -421.181095) (xy 411.849896 -421.222281) (xy 411.808712 -421.257969)
			(xy 411.762869 -421.287434) (xy 411.713298 -421.310074) (xy 411.661011 -421.32543) (xy 411.60707 -421.333188)
			(xy 411.579822 -421.333676) (xy 410.716222 -421.333676) (xy 410.688966 -421.333279) (xy 410.635008 -421.325523)
			(xy 410.582703 -421.310168) (xy 410.533116 -421.287525) (xy 410.487256 -421.258055) (xy 410.446057 -421.222358)
			(xy 410.410358 -421.181162) (xy 410.380886 -421.135303) (xy 410.35824 -421.085718) (xy 410.342881 -421.033414)
			(xy 410.335123 -420.979456) (xy 408.897612 -420.979456) (xy 408.889856 -421.033399) (xy 408.8745 -421.085694)
			(xy 408.851858 -421.135271) (xy 408.822391 -421.181122) (xy 408.786699 -421.222311) (xy 408.745507 -421.258002)
			(xy 408.699656 -421.287467) (xy 408.650077 -421.310107) (xy 408.597782 -421.32546) (xy 408.543833 -421.333214)
			(xy 408.516582 -421.333676) (xy 407.652982 -421.333676) (xy 407.625729 -421.333253) (xy 407.571779 -421.325494)
			(xy 407.519482 -421.310136) (xy 407.469903 -421.287492) (xy 407.424051 -421.258022) (xy 407.382859 -421.222328)
			(xy 407.347167 -421.181135) (xy 407.3177 -421.135281) (xy 407.295058 -421.085701) (xy 407.279703 -421.033403)
			(xy 407.271946 -420.979453) (xy 405.834289 -420.979453) (xy 405.826535 -421.033386) (xy 405.811183 -421.085673)
			(xy 405.788547 -421.135244) (xy 405.759087 -421.181088) (xy 405.723403 -421.222274) (xy 405.682222 -421.257962)
			(xy 405.636381 -421.287427) (xy 405.586813 -421.310069) (xy 405.534528 -421.325426) (xy 405.480589 -421.333187)
			(xy 405.453342 -421.333676) (xy 404.589742 -421.333676) (xy 404.562485 -421.33328) (xy 404.508525 -421.325527)
			(xy 404.456217 -421.310173) (xy 404.406628 -421.287531) (xy 404.360766 -421.258062) (xy 404.319564 -421.222365)
			(xy 404.283863 -421.181168) (xy 404.254389 -421.135309) (xy 404.231741 -421.085722) (xy 404.216382 -421.033416)
			(xy 404.208623 -420.979457) (xy 402.771089 -420.979457) (xy 402.763334 -421.033392) (xy 402.74798 -421.085682)
			(xy 402.725341 -421.135255) (xy 402.695878 -421.181101) (xy 402.660189 -421.222288) (xy 402.619003 -421.257976)
			(xy 402.573157 -421.28744) (xy 402.523584 -421.31008) (xy 402.471294 -421.325434) (xy 402.417351 -421.33319)
			(xy 402.390102 -421.333676) (xy 401.526502 -421.333676) (xy 401.499247 -421.333277) (xy 401.445291 -421.32552)
			(xy 401.392988 -421.310163) (xy 401.343404 -421.287518) (xy 401.297547 -421.258048) (xy 401.25635 -421.222351)
			(xy 401.220653 -421.181155) (xy 401.191183 -421.135298) (xy 401.168538 -421.085713) (xy 401.153181 -421.033411)
			(xy 401.145423 -420.979455) (xy 399.707913 -420.979455) (xy 399.700155 -421.033402) (xy 399.684799 -421.085699)
			(xy 399.662155 -421.135277) (xy 399.632686 -421.181128) (xy 399.596991 -421.222318) (xy 399.555798 -421.258009)
			(xy 399.509944 -421.287474) (xy 399.460363 -421.310112) (xy 399.408065 -421.325463) (xy 399.354114 -421.333215)
			(xy 399.326862 -421.333676) (xy 398.463262 -421.333676) (xy 398.43601 -421.333252) (xy 398.382062 -421.32549)
			(xy 398.329768 -421.31013) (xy 398.280191 -421.287485) (xy 398.234341 -421.258015) (xy 398.193152 -421.222321)
			(xy 398.157462 -421.181128) (xy 398.127997 -421.135276) (xy 398.105356 -421.085697) (xy 398.090002 -421.033401)
			(xy 398.082246 -420.979452) (xy 396.644589 -420.979452) (xy 396.636835 -421.033389) (xy 396.621482 -421.085678)
			(xy 396.598844 -421.135249) (xy 396.569383 -421.181095) (xy 396.533696 -421.222281) (xy 396.492512 -421.257969)
			(xy 396.446669 -421.287434) (xy 396.397098 -421.310074) (xy 396.344811 -421.32543) (xy 396.29087 -421.333188)
			(xy 396.263622 -421.333676) (xy 395.400022 -421.333676) (xy 395.372766 -421.333279) (xy 395.318808 -421.325523)
			(xy 395.266503 -421.310168) (xy 395.216916 -421.287525) (xy 395.171056 -421.258055) (xy 395.129857 -421.222358)
			(xy 395.094158 -421.181162) (xy 395.064686 -421.135303) (xy 395.04204 -421.085718) (xy 395.026681 -421.033414)
			(xy 395.018923 -420.979456) (xy 393.581412 -420.979456) (xy 393.573656 -421.033399) (xy 393.5583 -421.085694)
			(xy 393.535658 -421.135271) (xy 393.506191 -421.181122) (xy 393.470499 -421.222311) (xy 393.429307 -421.258002)
			(xy 393.383456 -421.287467) (xy 393.333877 -421.310107) (xy 393.281582 -421.32546) (xy 393.227633 -421.333214)
			(xy 393.200382 -421.333676) (xy 392.336782 -421.333676) (xy 392.309529 -421.333253) (xy 392.255579 -421.325494)
			(xy 392.203282 -421.310136) (xy 392.153703 -421.287492) (xy 392.107851 -421.258022) (xy 392.066659 -421.222328)
			(xy 392.030967 -421.181135) (xy 392.0015 -421.135281) (xy 391.978858 -421.085701) (xy 391.963503 -421.033403)
			(xy 391.955746 -420.979453) (xy 390.518089 -420.979453) (xy 390.510335 -421.033386) (xy 390.494983 -421.085673)
			(xy 390.472347 -421.135244) (xy 390.442887 -421.181088) (xy 390.407203 -421.222274) (xy 390.366022 -421.257962)
			(xy 390.320181 -421.287427) (xy 390.270613 -421.310069) (xy 390.218328 -421.325426) (xy 390.164389 -421.333187)
			(xy 390.137142 -421.333676) (xy 389.273542 -421.333676) (xy 389.246285 -421.33328) (xy 389.192325 -421.325527)
			(xy 389.140017 -421.310173) (xy 389.090428 -421.287531) (xy 389.044566 -421.258062) (xy 389.003364 -421.222365)
			(xy 388.967663 -421.181168) (xy 388.938189 -421.135309) (xy 388.915541 -421.085722) (xy 388.900182 -421.033416)
			(xy 388.892423 -420.979457) (xy 387.454889 -420.979457) (xy 387.447134 -421.033392) (xy 387.43178 -421.085682)
			(xy 387.409141 -421.135255) (xy 387.379678 -421.181101) (xy 387.343989 -421.222288) (xy 387.302803 -421.257976)
			(xy 387.256957 -421.28744) (xy 387.207384 -421.31008) (xy 387.155094 -421.325434) (xy 387.101151 -421.33319)
			(xy 387.073902 -421.333676) (xy 386.210302 -421.333676) (xy 386.183047 -421.333277) (xy 386.129091 -421.32552)
			(xy 386.076788 -421.310163) (xy 386.027204 -421.287518) (xy 385.981347 -421.258048) (xy 385.94015 -421.222351)
			(xy 385.904453 -421.181155) (xy 385.874983 -421.135298) (xy 385.852338 -421.085713) (xy 385.836981 -421.033411)
			(xy 385.829223 -420.979455) (xy 384.391713 -420.979455) (xy 384.383955 -421.033402) (xy 384.368599 -421.085699)
			(xy 384.345955 -421.135277) (xy 384.316486 -421.181128) (xy 384.280791 -421.222318) (xy 384.239598 -421.258009)
			(xy 384.193744 -421.287474) (xy 384.144163 -421.310112) (xy 384.091865 -421.325463) (xy 384.037914 -421.333215)
			(xy 384.010662 -421.333676) (xy 383.147062 -421.333676) (xy 383.11981 -421.333252) (xy 383.065862 -421.32549)
			(xy 383.013568 -421.31013) (xy 382.963991 -421.287485) (xy 382.918141 -421.258015) (xy 382.876952 -421.222321)
			(xy 382.841262 -421.181128) (xy 382.811797 -421.135276) (xy 382.789156 -421.085697) (xy 382.773802 -421.033401)
			(xy 382.766046 -420.979452) (xy 381.328389 -420.979452) (xy 381.320635 -421.033389) (xy 381.305282 -421.085678)
			(xy 381.282644 -421.135249) (xy 381.253183 -421.181095) (xy 381.217496 -421.222281) (xy 381.176312 -421.257969)
			(xy 381.130469 -421.287434) (xy 381.080898 -421.310074) (xy 381.028611 -421.32543) (xy 380.97467 -421.333188)
			(xy 380.947422 -421.333676) (xy 380.083822 -421.333676) (xy 380.056566 -421.333279) (xy 380.002608 -421.325523)
			(xy 379.950303 -421.310168) (xy 379.900716 -421.287525) (xy 379.854856 -421.258055) (xy 379.813657 -421.222358)
			(xy 379.777958 -421.181162) (xy 379.748486 -421.135303) (xy 379.72584 -421.085718) (xy 379.710481 -421.033414)
			(xy 379.702723 -420.979456) (xy 378.265212 -420.979456) (xy 378.257456 -421.033399) (xy 378.2421 -421.085694)
			(xy 378.219458 -421.135271) (xy 378.189991 -421.181122) (xy 378.154299 -421.222311) (xy 378.113107 -421.258002)
			(xy 378.067256 -421.287467) (xy 378.017677 -421.310107) (xy 377.965382 -421.32546) (xy 377.911433 -421.333214)
			(xy 377.884182 -421.333676) (xy 377.020582 -421.333676) (xy 376.993329 -421.333253) (xy 376.939379 -421.325494)
			(xy 376.887082 -421.310136) (xy 376.837503 -421.287492) (xy 376.791651 -421.258022) (xy 376.750459 -421.222328)
			(xy 376.714767 -421.181135) (xy 376.6853 -421.135281) (xy 376.662658 -421.085701) (xy 376.647303 -421.033403)
			(xy 376.639546 -420.979453) (xy 375.201889 -420.979453) (xy 375.194135 -421.033386) (xy 375.178783 -421.085673)
			(xy 375.156147 -421.135244) (xy 375.126687 -421.181088) (xy 375.091003 -421.222274) (xy 375.049822 -421.257962)
			(xy 375.003981 -421.287427) (xy 374.954413 -421.310069) (xy 374.902128 -421.325426) (xy 374.848189 -421.333187)
			(xy 374.820942 -421.333676) (xy 373.957342 -421.333676) (xy 373.930085 -421.33328) (xy 373.876125 -421.325527)
			(xy 373.823817 -421.310173) (xy 373.774228 -421.287531) (xy 373.728366 -421.258062) (xy 373.687164 -421.222365)
			(xy 373.651463 -421.181168) (xy 373.621989 -421.135309) (xy 373.599341 -421.085722) (xy 373.583982 -421.033416)
			(xy 373.576223 -420.979457) (xy 372.138689 -420.979457) (xy 372.130934 -421.033392) (xy 372.11558 -421.085682)
			(xy 372.092941 -421.135255) (xy 372.063478 -421.181101) (xy 372.027789 -421.222288) (xy 371.986603 -421.257976)
			(xy 371.940757 -421.28744) (xy 371.891184 -421.31008) (xy 371.838894 -421.325434) (xy 371.784951 -421.33319)
			(xy 371.757702 -421.333676) (xy 370.894102 -421.333676) (xy 370.866847 -421.333277) (xy 370.812891 -421.32552)
			(xy 370.760588 -421.310163) (xy 370.711004 -421.287518) (xy 370.665147 -421.258048) (xy 370.62395 -421.222351)
			(xy 370.588253 -421.181155) (xy 370.558783 -421.135298) (xy 370.536138 -421.085713) (xy 370.520781 -421.033411)
			(xy 370.513023 -420.979455) (xy 370.117116 -420.979455) (xy 370.117116 -421.134032) (xy 370.118827 -421.145443)
			(xy 370.130963 -421.165042) (xy 370.150431 -421.17739) (xy 370.16182 -421.179244) (xy 370.26596 -421.179244)
			(xy 370.313204 -421.179244) (xy 370.313204 -421.230044) (xy 370.313204 -422.692576) (xy 370.312768 -422.702798)
			(xy 370.30495 -422.721687) (xy 370.290497 -422.736144) (xy 370.27161 -422.743966) (xy 370.261388 -422.744392)
			(xy 365.362744 -422.744392) (xy 365.352522 -422.743952) (xy 365.333631 -422.736138) (xy 365.319173 -422.721686)
			(xy 365.311352 -422.702798) (xy 365.310928 -422.692576) (xy 360.222212 -422.692576) (xy 360.286426 -422.706639)
			(xy 360.410636 -422.74198) (xy 360.532435 -422.7849) (xy 360.65136 -422.835237) (xy 360.766961 -422.892799)
			(xy 360.8788 -422.957369) (xy 360.986451 -423.028701) (xy 361.089506 -423.106525) (xy 361.187576 -423.190546)
			(xy 361.280287 -423.280445) (xy 361.367287 -423.37588) (xy 361.448248 -423.47649) (xy 361.505055 -423.556738)
			(xy 456.285335 -423.556738) (xy 456.285335 -423.427598) (xy 456.293285 -423.298703) (xy 456.309155 -423.170543)
			(xy 456.332884 -423.043602) (xy 456.364383 -422.918363) (xy 456.403532 -422.7953) (xy 456.450183 -422.674881)
			(xy 456.504158 -422.557562) (xy 456.565253 -422.443788) (xy 456.633236 -422.333991) (xy 456.70785 -422.228588)
			(xy 456.788811 -422.127978) (xy 456.875811 -422.032543) (xy 456.968522 -421.942644) (xy 457.066592 -421.858623)
			(xy 457.169647 -421.780799) (xy 457.277298 -421.709467) (xy 457.389137 -421.644897) (xy 457.504738 -421.587335)
			(xy 457.623663 -421.536998) (xy 457.745462 -421.494078) (xy 457.869672 -421.458737) (xy 457.995821 -421.43111)
			(xy 458.123433 -421.411301) (xy 458.252022 -421.399385) (xy 458.3811 -421.395409) (xy 458.510178 -421.399385)
			(xy 458.638767 -421.411301) (xy 458.766379 -421.43111) (xy 458.892528 -421.458737) (xy 459.016738 -421.494078)
			(xy 459.138537 -421.536998) (xy 459.257462 -421.587335) (xy 459.373063 -421.644897) (xy 459.484902 -421.709467)
			(xy 459.592553 -421.780799) (xy 459.695608 -421.858623) (xy 459.793678 -421.942644) (xy 459.886389 -422.032543)
			(xy 459.973389 -422.127978) (xy 460.05435 -422.228588) (xy 460.128964 -422.333991) (xy 460.196947 -422.443788)
			(xy 460.258042 -422.557562) (xy 460.312017 -422.674881) (xy 460.358668 -422.7953) (xy 460.397817 -422.918363)
			(xy 460.429316 -423.043602) (xy 460.453045 -423.170543) (xy 460.468915 -423.298703) (xy 460.476865 -423.427598)
			(xy 460.477362 -423.492168) (xy 460.476865 -423.556738) (xy 460.468915 -423.685633) (xy 460.453045 -423.813793)
			(xy 460.429316 -423.940734) (xy 460.397817 -424.065973) (xy 460.358668 -424.189036) (xy 460.312017 -424.309455)
			(xy 460.258042 -424.426774) (xy 460.196947 -424.540548) (xy 460.128964 -424.650345) (xy 460.05435 -424.755748)
			(xy 459.973389 -424.856358) (xy 459.886389 -424.951793) (xy 459.793678 -425.041692) (xy 459.695608 -425.125713)
			(xy 459.592553 -425.203537) (xy 459.484902 -425.274869) (xy 459.373063 -425.339439) (xy 459.257462 -425.397001)
			(xy 459.138537 -425.447338) (xy 459.016738 -425.490258) (xy 458.892528 -425.525599) (xy 458.766379 -425.553226)
			(xy 458.638767 -425.573035) (xy 458.510178 -425.584951) (xy 458.3811 -425.588928) (xy 458.252022 -425.584951)
			(xy 458.123433 -425.573035) (xy 457.995821 -425.553226) (xy 457.869672 -425.525599) (xy 457.745462 -425.490258)
			(xy 457.623663 -425.447338) (xy 457.504738 -425.397001) (xy 457.389137 -425.339439) (xy 457.277298 -425.274869)
			(xy 457.169647 -425.203537) (xy 457.066592 -425.125713) (xy 456.968522 -425.041692) (xy 456.875811 -424.951793)
			(xy 456.788811 -424.856358) (xy 456.70785 -424.755748) (xy 456.633236 -424.650345) (xy 456.565253 -424.540548)
			(xy 456.504158 -424.426774) (xy 456.450183 -424.309455) (xy 456.403532 -424.189036) (xy 456.364383 -424.065973)
			(xy 456.332884 -423.940734) (xy 456.309155 -423.813793) (xy 456.293285 -423.685633) (xy 456.285335 -423.556738)
			(xy 361.505055 -423.556738) (xy 361.522862 -423.581893) (xy 361.590845 -423.69169) (xy 361.65194 -423.805464)
			(xy 361.705915 -423.922783) (xy 361.752566 -424.043202) (xy 361.791715 -424.166265) (xy 361.823214 -424.291504)
			(xy 361.846943 -424.418445) (xy 361.862813 -424.546605) (xy 361.870763 -424.6755) (xy 361.87126 -424.74007)
			(xy 361.870763 -424.80464) (xy 361.862813 -424.933535) (xy 361.846943 -425.061695) (xy 361.823214 -425.188636)
			(xy 361.791715 -425.313875) (xy 361.752566 -425.436938) (xy 361.705915 -425.557357) (xy 361.65194 -425.674676)
			(xy 361.590845 -425.78845) (xy 361.522862 -425.898247) (xy 361.448248 -426.00365) (xy 361.367287 -426.10426)
			(xy 361.280287 -426.199695) (xy 361.187576 -426.289594) (xy 361.089506 -426.373615) (xy 360.986451 -426.451439)
			(xy 360.8788 -426.522771) (xy 360.766961 -426.587341) (xy 360.65136 -426.644903) (xy 360.532435 -426.69524)
			(xy 360.410636 -426.73816) (xy 360.286426 -426.773501) (xy 360.160277 -426.801128) (xy 360.032665 -426.820937)
			(xy 359.904076 -426.832853) (xy 359.774998 -426.83683) (xy 359.64592 -426.832853) (xy 359.517331 -426.820937)
			(xy 359.389719 -426.801128) (xy 359.26357 -426.773501) (xy 359.13936 -426.73816) (xy 359.017561 -426.69524)
			(xy 358.898636 -426.644903) (xy 358.783035 -426.587341) (xy 358.671196 -426.522771) (xy 358.563545 -426.451439)
			(xy 358.46049 -426.373615) (xy 358.36242 -426.289594) (xy 358.269709 -426.199695) (xy 358.182709 -426.10426)
			(xy 358.101748 -426.00365) (xy 358.027134 -425.898247) (xy 357.959151 -425.78845) (xy 357.898056 -425.674676)
			(xy 357.844081 -425.557357) (xy 357.79743 -425.436938) (xy 357.758281 -425.313875) (xy 357.726782 -425.188636)
			(xy 357.703053 -425.061695) (xy 357.687183 -424.933535) (xy 357.679233 -424.80464) (xy 230.3145 -424.80464)
			(xy 230.3145 -427.960536) (xy 314.141104 -427.960536) (xy 314.141104 -425.419012) (xy 314.141523 -425.406929)
			(xy 314.148989 -425.383944) (xy 314.163193 -425.364393) (xy 314.182744 -425.350189) (xy 314.205729 -425.342723)
			(xy 314.217812 -425.342304) (xy 315.157612 -425.342304) (xy 315.169688 -425.342754) (xy 315.192658 -425.350222)
			(xy 315.212196 -425.364421) (xy 315.226389 -425.383964) (xy 315.233849 -425.406935) (xy 315.23432 -425.419012)
			(xy 315.23432 -427.960536) (xy 315.233867 -427.972611) (xy 315.226396 -427.995578) (xy 315.212196 -428.015113)
			(xy 315.192656 -428.029307) (xy 315.169687 -428.036771) (xy 315.157612 -428.037244) (xy 314.217812 -428.037244)
			(xy 314.205742 -428.036726) (xy 314.182781 -428.029271) (xy 314.163247 -428.015087) (xy 314.149051 -427.995562)
			(xy 314.141581 -427.972606) (xy 314.141104 -427.960536) (xy 230.3145 -427.960536) (xy 230.3145 -433.130695)
			(xy 266.885917 -433.130695) (xy 266.885917 -432.953425) (xy 266.89387 -432.776334) (xy 266.909761 -432.599778)
			(xy 266.933556 -432.424113) (xy 266.965209 -432.249692) (xy 267.004655 -432.076867) (xy 267.051815 -431.905986)
			(xy 267.106594 -431.737392) (xy 267.168882 -431.571427) (xy 267.238554 -431.408422) (xy 267.315468 -431.248708)
			(xy 267.399471 -431.092605) (xy 267.490392 -430.940428) (xy 267.588049 -430.792484) (xy 267.692246 -430.64907)
			(xy 267.802772 -430.510475) (xy 267.919404 -430.376978) (xy 268.041909 -430.248849) (xy 268.170038 -430.126344)
			(xy 268.303535 -430.009712) (xy 268.44213 -429.899186) (xy 268.585544 -429.794989) (xy 268.733488 -429.697332)
			(xy 268.885665 -429.606411) (xy 269.041768 -429.522408) (xy 269.201482 -429.445494) (xy 269.364487 -429.375822)
			(xy 269.530452 -429.313534) (xy 269.699046 -429.258755) (xy 269.869927 -429.211595) (xy 270.042752 -429.172149)
			(xy 270.217173 -429.140496) (xy 270.392838 -429.116701) (xy 270.569394 -429.10081) (xy 270.746485 -429.092857)
			(xy 270.923755 -429.092857) (xy 271.100846 -429.10081) (xy 271.277402 -429.116701) (xy 271.453067 -429.140496)
			(xy 271.627488 -429.172149) (xy 271.800313 -429.211595) (xy 271.971194 -429.258755) (xy 272.139788 -429.313534)
			(xy 272.305753 -429.375822) (xy 272.468758 -429.445494) (xy 272.628472 -429.522408) (xy 272.784575 -429.606411)
			(xy 272.936752 -429.697332) (xy 273.084696 -429.794989) (xy 273.22811 -429.899186) (xy 273.366705 -430.009712)
			(xy 273.500202 -430.126344) (xy 273.628331 -430.248849) (xy 273.750836 -430.376978) (xy 273.867468 -430.510475)
			(xy 273.977994 -430.64907) (xy 274.082191 -430.792484) (xy 274.179848 -430.940428) (xy 274.270769 -431.092605)
			(xy 274.354772 -431.248708) (xy 274.431686 -431.408422) (xy 274.496678 -431.560478) (xy 314.141104 -431.560478)
			(xy 314.141104 -429.018954) (xy 314.141572 -429.00684) (xy 314.149068 -428.983801) (xy 314.163312 -428.964203)
			(xy 314.182912 -428.949962) (xy 314.205952 -428.94247) (xy 314.218066 -428.941992) (xy 315.157866 -428.941992)
			(xy 315.169974 -428.94254) (xy 315.193009 -428.950012) (xy 315.207506 -428.960534) (xy 316.1411 -428.960534)
			(xy 316.1411 -426.41901) (xy 316.141615 -426.406925) (xy 316.149064 -426.383931) (xy 316.16324 -426.364355)
			(xy 316.182761 -426.350103) (xy 316.205725 -426.342563) (xy 316.217808 -426.342048) (xy 317.157608 -426.342048)
			(xy 317.169712 -426.342509) (xy 317.192731 -426.350004) (xy 317.212299 -426.364256) (xy 317.226496 -426.383865)
			(xy 317.233925 -426.406905) (xy 317.234316 -426.41901) (xy 317.234316 -427.960536) (xy 318.141096 -427.960536)
			(xy 318.141096 -425.419012) (xy 318.141523 -425.40693) (xy 318.148988 -425.383947) (xy 318.16319 -425.364396)
			(xy 318.182739 -425.350191) (xy 318.205722 -425.342724) (xy 318.217804 -425.342304) (xy 319.157604 -425.342304)
			(xy 319.169688 -425.342709) (xy 319.192673 -425.350179) (xy 319.212224 -425.364387) (xy 319.226428 -425.383941)
			(xy 319.233893 -425.406928) (xy 319.234312 -425.419012) (xy 319.234312 -427.960536) (xy 319.233867 -427.972612)
			(xy 319.226395 -427.99558) (xy 319.212193 -428.015116) (xy 319.192651 -428.029309) (xy 319.16968 -428.036772)
			(xy 319.157604 -428.037244) (xy 318.217804 -428.037244) (xy 318.205733 -428.036733) (xy 318.182772 -428.029276)
			(xy 318.163238 -428.01509) (xy 318.149042 -427.995564) (xy 318.141573 -427.972607) (xy 318.141096 -427.960536)
			(xy 317.234316 -427.960536) (xy 317.234316 -428.960534) (xy 317.233921 -428.97263) (xy 317.226449 -428.995639)
			(xy 317.212246 -429.015222) (xy 317.192695 -429.02947) (xy 317.169703 -429.036993) (xy 317.157608 -429.037496)
			(xy 316.217808 -429.037496) (xy 316.205699 -429.037077) (xy 316.182671 -429.029579) (xy 316.163098 -429.015319)
			(xy 316.148903 -428.995697) (xy 316.141483 -428.972644) (xy 316.1411 -428.960534) (xy 315.207506 -428.960534)
			(xy 315.212607 -428.964236) (xy 315.226851 -428.98382) (xy 315.234347 -429.006846) (xy 315.234828 -429.018954)
			(xy 315.234828 -431.560478) (xy 315.234421 -431.572603) (xy 315.22693 -431.595667) (xy 315.212677 -431.615285)
			(xy 315.193056 -431.629536) (xy 315.169991 -431.637023) (xy 315.157866 -431.63744) (xy 314.218066 -431.63744)
			(xy 314.205947 -431.637017) (xy 314.182899 -431.629518) (xy 314.163296 -431.615264) (xy 314.149057 -431.59565)
			(xy 314.141574 -431.572597) (xy 314.141104 -431.560478) (xy 274.496678 -431.560478) (xy 274.501358 -431.571427)
			(xy 274.563646 -431.737392) (xy 274.618425 -431.905986) (xy 274.665585 -432.076867) (xy 274.705031 -432.249692)
			(xy 274.736684 -432.424113) (xy 274.760479 -432.599778) (xy 274.77637 -432.776334) (xy 274.784323 -432.953425)
			(xy 274.78482 -433.04206) (xy 274.784323 -433.130695) (xy 274.77637 -433.307786) (xy 274.760479 -433.484342)
			(xy 274.736684 -433.660007) (xy 274.705031 -433.834428) (xy 274.665585 -434.007253) (xy 274.618425 -434.178134)
			(xy 274.563646 -434.346728) (xy 274.501358 -434.512693) (xy 274.431686 -434.675698) (xy 274.354772 -434.835412)
			(xy 274.270769 -434.991515) (xy 274.179848 -435.143692) (xy 274.168638 -435.160674) (xy 314.141104 -435.160674)
			(xy 314.141104 -432.61915) (xy 314.141569 -432.607036) (xy 314.149065 -432.583997) (xy 314.163311 -432.564399)
			(xy 314.182911 -432.550158) (xy 314.205952 -432.542666) (xy 314.218066 -432.542188) (xy 315.157866 -432.542188)
			(xy 315.169974 -432.54274) (xy 315.193008 -432.550212) (xy 315.207151 -432.560476) (xy 316.1411 -432.560476)
			(xy 316.1411 -430.018952) (xy 316.141476 -430.006841) (xy 316.148988 -429.983812) (xy 316.16326 -429.96424)
			(xy 316.18289 -429.950047) (xy 316.205949 -429.942627) (xy 316.218062 -429.942244) (xy 317.157862 -429.942244)
			(xy 317.16995 -429.94274) (xy 317.19295 -429.950187) (xy 317.212531 -429.964366) (xy 317.226783 -429.983894)
			(xy 317.234315 -430.006866) (xy 317.234824 -430.018952) (xy 317.234824 -431.560478) (xy 318.141096 -431.560478)
			(xy 318.141096 -429.018954) (xy 318.141572 -429.006841) (xy 318.149067 -428.983804) (xy 318.163309 -428.964206)
			(xy 318.182907 -428.949965) (xy 318.205945 -428.942471) (xy 318.218058 -428.941992) (xy 319.157858 -428.941992)
			(xy 319.169966 -428.942547) (xy 319.193 -428.950017) (xy 319.207492 -428.960534) (xy 320.141092 -428.960534)
			(xy 320.141092 -426.41901) (xy 320.141615 -426.406926) (xy 320.149063 -426.383934) (xy 320.163237 -426.364358)
			(xy 320.182756 -426.350105) (xy 320.205718 -426.342564) (xy 320.2178 -426.342048) (xy 321.1576 -426.342048)
			(xy 321.169704 -426.342515) (xy 321.192722 -426.350009) (xy 321.212291 -426.364259) (xy 321.226487 -426.383866)
			(xy 321.233917 -426.406905) (xy 321.234308 -426.41901) (xy 321.234308 -427.960536) (xy 322.141088 -427.960536)
			(xy 322.141088 -425.419012) (xy 322.141523 -425.40693) (xy 322.148987 -425.383949) (xy 322.163187 -425.364399)
			(xy 322.182734 -425.350194) (xy 322.205714 -425.342726) (xy 322.217796 -425.342304) (xy 323.157596 -425.342304)
			(xy 323.16968 -425.342716) (xy 323.192664 -425.350184) (xy 323.212216 -425.36439) (xy 323.22642 -425.383943)
			(xy 323.233885 -425.406928) (xy 323.234304 -425.419012) (xy 323.234304 -427.960536) (xy 323.233867 -427.972613)
			(xy 323.226394 -427.995582) (xy 323.21219 -428.015119) (xy 323.192646 -428.029312) (xy 323.169673 -428.036773)
			(xy 323.157596 -428.037244) (xy 322.217796 -428.037244) (xy 322.205725 -428.03674) (xy 322.182764 -428.02928)
			(xy 322.16323 -428.015093) (xy 322.149034 -427.995565) (xy 322.141565 -427.972607) (xy 322.141088 -427.960536)
			(xy 321.234308 -427.960536) (xy 321.234308 -428.960534) (xy 321.233823 -428.972621) (xy 321.226362 -428.995614)
			(xy 321.212179 -429.01519) (xy 321.192653 -429.029441) (xy 321.169685 -429.03698) (xy 321.1576 -429.037496)
			(xy 320.2178 -429.037496) (xy 320.205691 -429.037084) (xy 320.182663 -429.029584) (xy 320.163089 -429.015321)
			(xy 320.148895 -428.995699) (xy 320.141475 -428.972645) (xy 320.141092 -428.960534) (xy 319.207492 -428.960534)
			(xy 319.212598 -428.964239) (xy 319.226843 -428.983821) (xy 319.234339 -429.006847) (xy 319.23482 -429.018954)
			(xy 319.23482 -431.560478) (xy 319.234421 -431.572604) (xy 319.226929 -431.595669) (xy 319.212674 -431.615288)
			(xy 319.193051 -431.629538) (xy 319.169984 -431.637024) (xy 319.157858 -431.63744) (xy 318.218058 -431.63744)
			(xy 318.205939 -431.637024) (xy 318.182891 -431.629522) (xy 318.163288 -431.615267) (xy 318.149048 -431.595652)
			(xy 318.141566 -431.572597) (xy 318.141096 -431.560478) (xy 317.234824 -431.560478) (xy 317.234824 -432.560476)
			(xy 317.234363 -432.572581) (xy 317.226874 -432.595604) (xy 317.212623 -432.615175) (xy 317.193012 -432.629371)
			(xy 317.169968 -432.636797) (xy 317.157862 -432.637184) (xy 316.218062 -432.637184) (xy 316.205973 -432.636726)
			(xy 316.182975 -432.629261) (xy 316.163398 -432.615072) (xy 316.149148 -432.595538) (xy 316.141612 -432.572564)
			(xy 316.1411 -432.560476) (xy 315.207151 -432.560476) (xy 315.212606 -432.564435) (xy 315.22685 -432.584017)
			(xy 315.234347 -432.607043) (xy 315.234828 -432.61915) (xy 315.234828 -435.160674) (xy 315.234417 -435.172799)
			(xy 315.226928 -435.195863) (xy 315.212675 -435.215481) (xy 315.193055 -435.229732) (xy 315.169991 -435.237219)
			(xy 315.157866 -435.237636) (xy 314.218066 -435.237636) (xy 314.205947 -435.237217) (xy 314.182898 -435.229717)
			(xy 314.163295 -435.215462) (xy 314.149055 -435.195848) (xy 314.141574 -435.172793) (xy 314.141104 -435.160674)
			(xy 274.168638 -435.160674) (xy 274.082191 -435.291636) (xy 273.977994 -435.43505) (xy 273.867468 -435.573645)
			(xy 273.750836 -435.707142) (xy 273.628331 -435.835271) (xy 273.500202 -435.957776) (xy 273.366705 -436.074408)
			(xy 273.22811 -436.184934) (xy 273.084696 -436.289131) (xy 272.936752 -436.386788) (xy 272.784575 -436.477709)
			(xy 272.628472 -436.561712) (xy 272.468758 -436.638626) (xy 272.305753 -436.708298) (xy 272.139788 -436.770586)
			(xy 271.971194 -436.825365) (xy 271.800313 -436.872525) (xy 271.627488 -436.911971) (xy 271.453067 -436.943624)
			(xy 271.277402 -436.967419) (xy 271.100846 -436.98331) (xy 270.923755 -436.991263) (xy 270.746485 -436.991263)
			(xy 270.569394 -436.98331) (xy 270.392838 -436.967419) (xy 270.217173 -436.943624) (xy 270.042752 -436.911971)
			(xy 269.869927 -436.872525) (xy 269.699046 -436.825365) (xy 269.530452 -436.770586) (xy 269.364487 -436.708298)
			(xy 269.201482 -436.638626) (xy 269.041768 -436.561712) (xy 268.885665 -436.477709) (xy 268.733488 -436.386788)
			(xy 268.585544 -436.289131) (xy 268.44213 -436.184934) (xy 268.303535 -436.074408) (xy 268.170038 -435.957776)
			(xy 268.041909 -435.835271) (xy 267.919404 -435.707142) (xy 267.802772 -435.573645) (xy 267.692246 -435.43505)
			(xy 267.588049 -435.291636) (xy 267.490392 -435.143692) (xy 267.399471 -434.991515) (xy 267.315468 -434.835412)
			(xy 267.238554 -434.675698) (xy 267.168882 -434.512693) (xy 267.106594 -434.346728) (xy 267.051815 -434.178134)
			(xy 267.004655 -434.007253) (xy 266.965209 -433.834428) (xy 266.933556 -433.660007) (xy 266.909761 -433.484342)
			(xy 266.89387 -433.307786) (xy 266.885917 -433.130695) (xy 230.3145 -433.130695) (xy 230.3145 -435.873652)
			(xy 230.314033 -435.898602) (xy 230.306213 -435.947887) (xy 230.29079 -435.995345) (xy 230.268141 -436.03981)
			(xy 230.238824 -436.080191) (xy 230.221536 -436.098188) (xy 229.299008 -437.020716) (xy 229.281016 -437.03801)
			(xy 229.240639 -437.067332) (xy 229.196172 -437.089979) (xy 229.148711 -437.105393) (xy 229.099423 -437.113193)
			(xy 229.074472 -437.11368) (xy 207.302608 -437.11368) (xy 207.27766 -437.113152) (xy 207.22838 -437.105344)
			(xy 207.180923 -437.089933) (xy 207.136457 -437.067299) (xy 207.096072 -437.037997) (xy 207.078072 -437.020716)
			(xy 205.512924 -435.455568) (xy 205.495618 -435.437587) (xy 205.466295 -435.397208) (xy 205.44365 -435.352738)
			(xy 205.42824 -435.305274) (xy 205.420444 -435.255984) (xy 205.41996 -435.231032) (xy 205.41996 -431.836068)
			(xy 205.419562 -431.825996) (xy 205.411823 -431.807397) (xy 205.404974 -431.8) (xy 204.586586 -430.981612)
			(xy 204.579871 -430.975414) (xy 204.563254 -430.96784) (xy 204.545036 -430.96659) (xy 204.52754 -430.971821)
			(xy 204.520038 -430.97704) (xy 204.424534 -431.04943) (xy 204.416914 -431.086514) (xy 204.426312 -431.103278)
			(xy 204.471058 -431.183788) (xy 204.553904 -431.348323) (xy 204.628987 -431.516542) (xy 204.696145 -431.688079)
			(xy 204.75523 -431.862561) (xy 204.806115 -432.039609) (xy 204.848688 -432.218837) (xy 204.882858 -432.399855)
			(xy 204.908549 -432.58227) (xy 204.925705 -432.765684) (xy 204.934291 -432.949699) (xy 204.93482 -433.041806)
			(xy 204.93482 -433.04206) (xy 204.934323 -433.130695) (xy 204.92637 -433.307786) (xy 204.910479 -433.484342)
			(xy 204.886684 -433.660007) (xy 204.855031 -433.834428) (xy 204.815585 -434.007253) (xy 204.768425 -434.178134)
			(xy 204.713646 -434.346728) (xy 204.651358 -434.512693) (xy 204.581686 -434.675698) (xy 204.504772 -434.835412)
			(xy 204.420769 -434.991515) (xy 204.329848 -435.143692) (xy 204.232191 -435.291636) (xy 204.127994 -435.43505)
			(xy 204.017468 -435.573645) (xy 203.900836 -435.707142) (xy 203.778331 -435.835271) (xy 203.650202 -435.957776)
			(xy 203.516705 -436.074408) (xy 203.37811 -436.184934) (xy 203.234696 -436.289131) (xy 203.086752 -436.386788)
			(xy 202.934575 -436.477709) (xy 202.778472 -436.561712) (xy 202.618758 -436.638626) (xy 202.455753 -436.708298)
			(xy 202.289788 -436.770586) (xy 202.121194 -436.825365) (xy 201.950313 -436.872525) (xy 201.777488 -436.911971)
			(xy 201.603067 -436.943624) (xy 201.427402 -436.967419) (xy 201.250846 -436.98331) (xy 201.073755 -436.991263)
			(xy 200.896485 -436.991263) (xy 200.719394 -436.98331) (xy 200.542838 -436.967419) (xy 200.367173 -436.943624)
			(xy 200.192752 -436.911971) (xy 200.019927 -436.872525) (xy 199.849046 -436.825365) (xy 199.680452 -436.770586)
			(xy 199.514487 -436.708298) (xy 199.351482 -436.638626) (xy 199.191768 -436.561712) (xy 199.035665 -436.477709)
			(xy 198.883488 -436.386788) (xy 198.735544 -436.289131) (xy 198.59213 -436.184934) (xy 198.453535 -436.074408)
			(xy 198.320038 -435.957776) (xy 198.191909 -435.835271) (xy 198.069404 -435.707142) (xy 197.952772 -435.573645)
			(xy 197.842246 -435.43505) (xy 197.738049 -435.291636) (xy 197.640392 -435.143692) (xy 197.549471 -434.991515)
			(xy 197.465468 -434.835412) (xy 197.388554 -434.675698) (xy 197.318882 -434.512693) (xy 197.256594 -434.346728)
			(xy 197.201815 -434.178134) (xy 197.154655 -434.007253) (xy 197.115209 -433.834428) (xy 197.083556 -433.660007)
			(xy 197.059761 -433.484342) (xy 197.04387 -433.307786) (xy 197.035917 -433.130695) (xy 197.035917 -432.953425)
			(xy 197.04387 -432.776334) (xy 197.059761 -432.599778) (xy 197.083556 -432.424113) (xy 197.115209 -432.249692)
			(xy 197.154655 -432.076867) (xy 197.201815 -431.905986) (xy 197.256594 -431.737392) (xy 197.318882 -431.571427)
			(xy 197.388554 -431.408422) (xy 197.465468 -431.248708) (xy 197.549471 -431.092605) (xy 197.640392 -430.940428)
			(xy 197.738049 -430.792484) (xy 197.842246 -430.64907) (xy 197.952772 -430.510475) (xy 198.069404 -430.376978)
			(xy 198.191909 -430.248849) (xy 198.320038 -430.126344) (xy 198.453535 -430.009712) (xy 198.59213 -429.899186)
			(xy 198.735544 -429.794989) (xy 198.883488 -429.697332) (xy 199.035665 -429.606411) (xy 199.191768 -429.522408)
			(xy 199.351482 -429.445494) (xy 199.514487 -429.375822) (xy 199.680452 -429.313534) (xy 199.849046 -429.258755)
			(xy 200.019927 -429.211595) (xy 200.192752 -429.172149) (xy 200.367173 -429.140496) (xy 200.542838 -429.116701)
			(xy 200.719394 -429.10081) (xy 200.896485 -429.092857) (xy 200.98512 -429.09236) (xy 200.985374 -429.09236)
			(xy 201.07748 -429.092926) (xy 201.261492 -429.101525) (xy 201.444903 -429.118692) (xy 201.627315 -429.144389)
			(xy 201.80833 -429.17856) (xy 201.987556 -429.221132) (xy 202.164603 -429.272011) (xy 202.339086 -429.331088)
			(xy 202.510625 -429.398233) (xy 202.678849 -429.4733) (xy 202.84339 -429.556127) (xy 202.923902 -429.600868)
			(xy 202.932044 -429.605072) (xy 202.950138 -429.607899) (xy 202.968075 -429.604204) (xy 202.983579 -429.594457)
			(xy 202.989434 -429.587406) (xy 203.05014 -429.507396) (xy 203.055391 -429.49992) (xy 203.060685 -429.482447)
			(xy 203.059501 -429.464229) (xy 203.05199 -429.447588) (xy 203.045822 -429.440848) (xy 194.790822 -421.185594)
			(xy 194.763915 -421.158053) (xy 194.715832 -421.097913) (xy 194.674792 -421.032763) (xy 194.641312 -420.963424)
			(xy 194.615814 -420.89077) (xy 194.598619 -420.815716) (xy 194.589944 -420.739207) (xy 194.5894 -420.700708)
			(xy 102.15118 -420.700708) (xy 102.15118 -421.122094) (xy 102.150662 -421.132249) (xy 102.142893 -421.151015)
			(xy 102.128535 -421.16538) (xy 102.109773 -421.173157) (xy 102.099618 -421.173656) (xy 97.200974 -421.173656)
			(xy 97.190814 -421.173188) (xy 97.172043 -421.165404) (xy 97.157678 -421.15103) (xy 97.149906 -421.132255)
			(xy 97.149412 -421.122094) (xy 75.844472 -421.122094) (xy 75.826048 -421.150762) (xy 75.790333 -421.191979)
			(xy 75.749116 -421.227694) (xy 75.703235 -421.25718) (xy 75.653625 -421.279837) (xy 75.601295 -421.295202)
			(xy 75.547311 -421.302964) (xy 75.492773 -421.302964) (xy 75.438789 -421.295202) (xy 75.386459 -421.279837)
			(xy 75.336849 -421.25718) (xy 75.290968 -421.227694) (xy 75.249751 -421.191979) (xy 75.214036 -421.150762)
			(xy 75.18455 -421.104881) (xy 75.161893 -421.055271) (xy 75.146528 -421.002941) (xy 75.138766 -420.948957)
			(xy 75.13828 -420.921688) (xy 73.234804 -420.921688) (xy 73.234804 -421.760396) (xy 73.234381 -421.772504)
			(xy 73.226883 -421.795531) (xy 73.212623 -421.815104) (xy 73.193003 -421.829299) (xy 73.169952 -421.83672)
			(xy 73.157842 -421.837104) (xy 72.218042 -421.837104) (xy 72.205959 -421.836558) (xy 72.182967 -421.829118)
			(xy 72.16339 -421.81495) (xy 72.149137 -421.795436) (xy 72.141596 -421.772477) (xy 72.14108 -421.760396)
			(xy 71.207209 -421.760396) (xy 71.212598 -421.764313) (xy 71.226839 -421.783915) (xy 71.23433 -421.806956)
			(xy 71.234808 -421.81907) (xy 71.234808 -424.360594) (xy 71.234284 -424.372704) (xy 71.226804 -424.395739)
			(xy 71.212574 -424.415337) (xy 71.192985 -424.42958) (xy 71.169955 -424.437076) (xy 71.157846 -424.437556)
			(xy 70.218046 -424.437556) (xy 70.205925 -424.437101) (xy 70.182867 -424.429621) (xy 70.16325 -424.415378)
			(xy 70.148998 -424.395769) (xy 70.141505 -424.372715) (xy 70.141084 -424.360594) (xy 69.234812 -424.360594)
			(xy 69.234812 -425.360592) (xy 69.234377 -425.372699) (xy 69.226881 -425.395724) (xy 69.212624 -425.415297)
			(xy 69.193007 -425.429492) (xy 69.169959 -425.436915) (xy 69.15785 -425.4373) (xy 68.21805 -425.4373)
			(xy 68.205967 -425.436751) (xy 68.182975 -425.429313) (xy 68.163397 -425.415146) (xy 68.149144 -425.395632)
			(xy 68.141603 -425.372673) (xy 68.141088 -425.360592) (xy 67.207172 -425.360592) (xy 67.212508 -425.364454)
			(xy 67.226762 -425.38397) (xy 67.234301 -425.40693) (xy 67.234816 -425.419012) (xy 67.234816 -427.960536)
			(xy 67.234415 -427.972645) (xy 67.226907 -427.995671) (xy 67.212641 -428.015242) (xy 67.193018 -428.029436)
			(xy 67.169965 -428.036859) (xy 67.157854 -428.037244) (xy 66.218054 -428.037244) (xy 66.20596 -428.036832)
			(xy 66.182956 -428.02936) (xy 66.163375 -428.01516) (xy 66.149127 -427.995615) (xy 66.141599 -427.972628)
			(xy 66.141092 -427.960536) (xy 65.23482 -427.960536) (xy 65.23482 -428.960534) (xy 65.234469 -428.972663)
			(xy 65.226962 -428.99573) (xy 65.212694 -429.015348) (xy 65.193062 -429.029597) (xy 65.169987 -429.03708)
			(xy 65.157858 -429.037496) (xy 64.218058 -429.037496) (xy 64.205945 -429.037025) (xy 64.182906 -429.02953)
			(xy 64.163308 -429.015287) (xy 64.149066 -428.995687) (xy 64.141574 -428.972647) (xy 64.141096 -428.960534)
			(xy 63.207499 -428.960534) (xy 63.212603 -428.964238) (xy 63.226847 -428.98382) (xy 63.234343 -429.006847)
			(xy 63.234824 -429.018954) (xy 63.234824 -431.560478) (xy 63.234421 -431.572603) (xy 63.22693 -431.595668)
			(xy 63.212675 -431.615287) (xy 63.193054 -431.629537) (xy 63.169987 -431.637023) (xy 63.157862 -431.63744)
			(xy 62.218062 -431.63744) (xy 62.205943 -431.63702) (xy 62.182895 -431.62952) (xy 62.163292 -431.615265)
			(xy 62.149053 -431.595651) (xy 62.14157 -431.572597) (xy 62.1411 -431.560478) (xy 61.234828 -431.560478)
			(xy 61.234828 -432.560476) (xy 61.234363 -432.572581) (xy 61.226874 -432.595602) (xy 61.212624 -432.615174)
			(xy 61.193014 -432.62937) (xy 61.169972 -432.636796) (xy 61.157866 -432.637184) (xy 60.218066 -432.637184)
			(xy 60.205977 -432.636722) (xy 60.182979 -432.629259) (xy 60.163402 -432.61507) (xy 60.149152 -432.595538)
			(xy 60.141616 -432.572563) (xy 60.141104 -432.560476) (xy 59.207307 -432.560476) (xy 59.212555 -432.564278)
			(xy 59.226805 -432.58382) (xy 59.234329 -432.606805) (xy 59.234832 -432.618896) (xy 59.234832 -435.16042)
			(xy 59.234401 -435.172527) (xy 59.2269 -435.195549) (xy 59.212641 -435.215119) (xy 59.193025 -435.229314)
			(xy 59.169978 -435.23674) (xy 59.15787 -435.237128) (xy 58.21807 -435.237128) (xy 58.205976 -435.236718)
			(xy 58.182969 -435.229249) (xy 58.163386 -435.215049) (xy 58.149138 -435.195502) (xy 58.141612 -435.172513)
			(xy 58.141108 -435.16042) (xy 7.00913 -435.16042) (xy 7.00913 -438.760616) (xy 58.141108 -438.760616)
			(xy 58.141108 -436.219092) (xy 58.141509 -436.206982) (xy 58.149012 -436.183953) (xy 58.163277 -436.164379)
			(xy 58.182902 -436.150185) (xy 58.205958 -436.142766) (xy 58.21807 -436.142384) (xy 59.15787 -436.142384)
			(xy 59.169962 -436.142834) (xy 59.192969 -436.150288) (xy 59.206951 -436.160418) (xy 60.141104 -436.160418)
			(xy 60.141104 -433.618894) (xy 60.141606 -433.606783) (xy 60.149091 -433.583745) (xy 60.163326 -433.564146)
			(xy 60.18292 -433.549904) (xy 60.205955 -433.542411) (xy 60.218066 -433.541932) (xy 61.157866 -433.541932)
			(xy 61.169986 -433.542389) (xy 61.193043 -433.549871) (xy 61.212658 -433.564113) (xy 61.226911 -433.583721)
			(xy 61.234405 -433.606774) (xy 61.234828 -433.618894) (xy 61.234828 -435.16042) (xy 62.1411 -435.16042)
			(xy 62.1411 -432.618896) (xy 62.141513 -432.606787) (xy 62.149013 -432.583759) (xy 62.163276 -432.564186)
			(xy 62.182898 -432.549992) (xy 62.205952 -432.542571) (xy 62.218062 -432.542188) (xy 63.157862 -432.542188)
			(xy 63.169954 -432.542641) (xy 63.192962 -432.550093) (xy 63.207295 -432.560476) (xy 64.141096 -432.560476)
			(xy 64.141096 -430.018952) (xy 64.141476 -430.006841) (xy 64.148988 -429.983813) (xy 64.163259 -429.964241)
			(xy 64.182888 -429.950048) (xy 64.205945 -429.942628) (xy 64.218058 -429.942244) (xy 65.157858 -429.942244)
			(xy 65.169946 -429.942743) (xy 65.192946 -429.950189) (xy 65.212527 -429.964367) (xy 65.226779 -429.983894)
			(xy 65.234311 -430.006866) (xy 65.23482 -430.018952) (xy 65.23482 -431.560478) (xy 66.141092 -431.560478)
			(xy 66.141092 -429.018954) (xy 66.141572 -429.006842) (xy 66.149066 -428.983805) (xy 66.163308 -428.964208)
			(xy 66.182905 -428.949966) (xy 66.205942 -428.942472) (xy 66.218054 -428.941992) (xy 67.157854 -428.941992)
			(xy 67.169962 -428.94255) (xy 67.192996 -428.950019) (xy 67.207487 -428.960534) (xy 68.141088 -428.960534)
			(xy 68.141088 -426.41901) (xy 68.14162 -426.406901) (xy 68.149098 -426.383867) (xy 68.163326 -426.364269)
			(xy 68.182913 -426.350025) (xy 68.205941 -426.342529) (xy 68.21805 -426.342048) (xy 69.15785 -426.342048)
			(xy 69.169968 -426.342469) (xy 69.193015 -426.349972) (xy 69.212616 -426.364226) (xy 69.226856 -426.383839)
			(xy 69.23434 -426.406891) (xy 69.234812 -426.41901) (xy 69.234812 -427.960536) (xy 70.141084 -427.960536)
			(xy 70.141084 -425.419012) (xy 70.141527 -425.406905) (xy 70.149021 -425.383881) (xy 70.163276 -425.364309)
			(xy 70.182891 -425.350114) (xy 70.205938 -425.34269) (xy 70.218046 -425.342304) (xy 71.157846 -425.342304)
			(xy 71.169934 -425.342767) (xy 71.19293 -425.350232) (xy 71.207224 -425.360592) (xy 72.14108 -425.360592)
			(xy 72.14108 -422.819068) (xy 72.141489 -422.806959) (xy 72.148995 -422.783935) (xy 72.163259 -422.764364)
			(xy 72.18288 -422.75017) (xy 72.205932 -422.742746) (xy 72.218042 -422.74236) (xy 73.157842 -422.74236)
			(xy 73.169936 -422.742772) (xy 73.192941 -422.750243) (xy 73.212522 -422.764443) (xy 73.226771 -422.783989)
			(xy 73.234298 -422.806975) (xy 73.234804 -422.819068) (xy 73.234804 -424.80464) (xy 109.929157 -424.80464)
			(xy 109.929157 -424.6755) (xy 109.937107 -424.546605) (xy 109.952977 -424.418445) (xy 109.976706 -424.291504)
			(xy 110.008205 -424.166265) (xy 110.047354 -424.043202) (xy 110.094005 -423.922783) (xy 110.14798 -423.805464)
			(xy 110.209075 -423.69169) (xy 110.277058 -423.581893) (xy 110.351672 -423.47649) (xy 110.432633 -423.37588)
			(xy 110.519633 -423.280445) (xy 110.612344 -423.190546) (xy 110.710414 -423.106525) (xy 110.813469 -423.028701)
			(xy 110.92112 -422.957369) (xy 111.032959 -422.892799) (xy 111.14856 -422.835237) (xy 111.267485 -422.7849)
			(xy 111.389284 -422.74198) (xy 111.513494 -422.706639) (xy 111.639643 -422.679012) (xy 111.767255 -422.659203)
			(xy 111.895844 -422.647287) (xy 112.024922 -422.643311) (xy 112.154 -422.647287) (xy 112.282589 -422.659203)
			(xy 112.410201 -422.679012) (xy 112.53635 -422.706639) (xy 112.66056 -422.74198) (xy 112.782359 -422.7849)
			(xy 112.901284 -422.835237) (xy 113.016885 -422.892799) (xy 113.128724 -422.957369) (xy 113.236375 -423.028701)
			(xy 113.33943 -423.106525) (xy 113.4375 -423.190546) (xy 113.530211 -423.280445) (xy 113.617211 -423.37588)
			(xy 113.698172 -423.47649) (xy 113.772786 -423.581893) (xy 113.840769 -423.69169) (xy 113.901864 -423.805464)
			(xy 113.955839 -423.922783) (xy 114.00249 -424.043202) (xy 114.041639 -424.166265) (xy 114.073138 -424.291504)
			(xy 114.096867 -424.418445) (xy 114.112737 -424.546605) (xy 114.120687 -424.6755) (xy 114.121184 -424.74007)
			(xy 114.120687 -424.80464) (xy 114.112737 -424.933535) (xy 114.096867 -425.061695) (xy 114.073138 -425.188636)
			(xy 114.041639 -425.313875) (xy 114.00249 -425.436938) (xy 113.955839 -425.557357) (xy 113.901864 -425.674676)
			(xy 113.840769 -425.78845) (xy 113.772786 -425.898247) (xy 113.698172 -426.00365) (xy 113.617211 -426.10426)
			(xy 113.530211 -426.199695) (xy 113.4375 -426.289594) (xy 113.33943 -426.373615) (xy 113.236375 -426.451439)
			(xy 113.128724 -426.522771) (xy 113.016885 -426.587341) (xy 112.901284 -426.644903) (xy 112.782359 -426.69524)
			(xy 112.66056 -426.73816) (xy 112.53635 -426.773501) (xy 112.410201 -426.801128) (xy 112.282589 -426.820937)
			(xy 112.154 -426.832853) (xy 112.024922 -426.83683) (xy 111.895844 -426.832853) (xy 111.767255 -426.820937)
			(xy 111.639643 -426.801128) (xy 111.513494 -426.773501) (xy 111.389284 -426.73816) (xy 111.267485 -426.69524)
			(xy 111.14856 -426.644903) (xy 111.032959 -426.587341) (xy 110.92112 -426.522771) (xy 110.813469 -426.451439)
			(xy 110.710414 -426.373615) (xy 110.612344 -426.289594) (xy 110.519633 -426.199695) (xy 110.432633 -426.10426)
			(xy 110.351672 -426.00365) (xy 110.277058 -425.898247) (xy 110.209075 -425.78845) (xy 110.14798 -425.674676)
			(xy 110.094005 -425.557357) (xy 110.047354 -425.436938) (xy 110.008205 -425.313875) (xy 109.976706 -425.188636)
			(xy 109.952977 -425.061695) (xy 109.937107 -424.933535) (xy 109.929157 -424.80464) (xy 73.234804 -424.80464)
			(xy 73.234804 -425.360592) (xy 73.234377 -425.3727) (xy 73.22688 -425.395727) (xy 73.212621 -425.415299)
			(xy 73.193002 -425.429495) (xy 73.169951 -425.436916) (xy 73.157842 -425.4373) (xy 72.218042 -425.4373)
			(xy 72.205959 -425.436758) (xy 72.182966 -425.429317) (xy 72.163389 -425.415149) (xy 72.149135 -425.395633)
			(xy 72.141595 -425.372673) (xy 72.14108 -425.360592) (xy 71.207224 -425.360592) (xy 71.212507 -425.364421)
			(xy 71.226757 -425.383953) (xy 71.234294 -425.406925) (xy 71.234808 -425.419012) (xy 71.234808 -427.960536)
			(xy 71.234414 -427.972646) (xy 71.226906 -427.995673) (xy 71.212638 -428.015245) (xy 71.193013 -428.029438)
			(xy 71.169957 -428.03686) (xy 71.157846 -428.037244) (xy 70.218046 -428.037244) (xy 70.205957 -428.036753)
			(xy 70.182955 -428.029307) (xy 70.163373 -428.015127) (xy 70.149122 -427.995597) (xy 70.141591 -427.972623)
			(xy 70.141084 -427.960536) (xy 69.234812 -427.960536) (xy 69.234812 -428.960534) (xy 69.234318 -428.972645)
			(xy 69.226828 -428.995681) (xy 69.21259 -429.015278) (xy 69.192996 -429.02952) (xy 69.169961 -429.037016)
			(xy 69.15785 -429.037496) (xy 68.21805 -429.037496) (xy 68.205936 -429.037031) (xy 68.182897 -429.029535)
			(xy 68.163299 -429.015289) (xy 68.149058 -428.995689) (xy 68.141566 -428.972648) (xy 68.141088 -428.960534)
			(xy 67.207487 -428.960534) (xy 67.212594 -428.96424) (xy 67.226839 -428.983822) (xy 67.234335 -429.006847)
			(xy 67.234816 -429.018954) (xy 67.234816 -431.560478) (xy 67.234421 -431.572604) (xy 67.226929 -431.59567)
			(xy 67.212672 -431.61529) (xy 67.193049 -431.62954) (xy 67.16998 -431.637024) (xy 67.157854 -431.63744)
			(xy 66.218054 -431.63744) (xy 66.205935 -431.637027) (xy 66.182886 -431.629525) (xy 66.163284 -431.615268)
			(xy 66.149044 -431.595653) (xy 66.141562 -431.572598) (xy 66.141092 -431.560478) (xy 65.23482 -431.560478)
			(xy 65.23482 -432.560476) (xy 65.234363 -432.572582) (xy 65.226873 -432.595605) (xy 65.212621 -432.615176)
			(xy 65.193009 -432.629373) (xy 65.169965 -432.636797) (xy 65.157858 -432.637184) (xy 64.218058 -432.637184)
			(xy 64.205969 -432.636729) (xy 64.182971 -432.629264) (xy 64.163393 -432.615073) (xy 64.149143 -432.595539)
			(xy 64.141608 -432.572564) (xy 64.141096 -432.560476) (xy 63.207295 -432.560476) (xy 63.212547 -432.564281)
			(xy 63.226797 -432.583821) (xy 63.234321 -432.606805) (xy 63.234824 -432.618896) (xy 63.234824 -435.16042)
			(xy 63.234401 -435.172528) (xy 63.226899 -435.195551) (xy 63.212638 -435.215122) (xy 63.19302 -435.229317)
			(xy 63.169971 -435.236741) (xy 63.157862 -435.237128) (xy 62.218062 -435.237128) (xy 62.205967 -435.236724)
			(xy 62.18296 -435.229253) (xy 62.163378 -435.215052) (xy 62.14913 -435.195503) (xy 62.141604 -435.172514)
			(xy 62.1411 -435.16042) (xy 61.234828 -435.16042) (xy 61.234828 -436.160418) (xy 61.234455 -436.172545)
			(xy 61.226953 -436.19561) (xy 61.212691 -436.215228) (xy 61.193064 -436.229477) (xy 61.169993 -436.236963)
			(xy 61.157866 -436.23738) (xy 60.218066 -436.23738) (xy 60.205951 -436.236918) (xy 60.18291 -436.229423)
			(xy 60.16331 -436.215178) (xy 60.149069 -436.195576) (xy 60.14158 -436.172533) (xy 60.141104 -436.160418)
			(xy 59.206951 -436.160418) (xy 59.212554 -436.164477) (xy 59.226804 -436.184017) (xy 59.234329 -436.207001)
			(xy 59.234832 -436.219092) (xy 59.234832 -438.760616) (xy 59.234398 -438.772723) (xy 59.226898 -438.795745)
			(xy 59.21264 -438.815315) (xy 59.193024 -438.82951) (xy 59.169978 -438.836936) (xy 59.15787 -438.837324)
			(xy 58.21807 -438.837324) (xy 58.205975 -438.836918) (xy 58.182968 -438.829448) (xy 58.163385 -438.815247)
			(xy 58.149137 -438.795699) (xy 58.141612 -438.77271) (xy 58.141108 -438.760616) (xy 7.00913 -438.760616)
			(xy 7.00913 -439.760614) (xy 60.141104 -439.760614) (xy 60.141104 -437.21909) (xy 60.141603 -437.206978)
			(xy 60.149089 -437.183941) (xy 60.163325 -437.164342) (xy 60.182919 -437.1501) (xy 60.205954 -437.142607)
			(xy 60.218066 -437.142128) (xy 61.157866 -437.142128) (xy 61.169986 -437.142589) (xy 61.193042 -437.15007)
			(xy 61.212657 -437.164312) (xy 61.22691 -437.183918) (xy 61.234404 -437.20697) (xy 61.234828 -437.21909)
			(xy 61.234828 -438.760616) (xy 62.1411 -438.760616) (xy 62.1411 -436.219092) (xy 62.141509 -436.206983)
			(xy 62.149011 -436.183955) (xy 62.163274 -436.164382) (xy 62.182897 -436.150188) (xy 62.205951 -436.142767)
			(xy 62.218062 -436.142384) (xy 63.157862 -436.142384) (xy 63.169954 -436.142841) (xy 63.192961 -436.150292)
			(xy 63.206938 -436.160418) (xy 64.141096 -436.160418) (xy 64.141096 -433.618894) (xy 64.141606 -433.606783)
			(xy 64.14909 -433.583747) (xy 64.163324 -433.564149) (xy 64.182915 -433.549906) (xy 64.205948 -433.542412)
			(xy 64.218058 -433.541932) (xy 65.157858 -433.541932) (xy 65.169978 -433.542396) (xy 65.193034 -433.549876)
			(xy 65.21265 -433.564116) (xy 65.226903 -433.583722) (xy 65.234397 -433.606774) (xy 65.23482 -433.618894)
			(xy 65.23482 -435.16042) (xy 66.141092 -435.16042) (xy 66.141092 -432.618896) (xy 66.141513 -432.606788)
			(xy 66.149012 -432.583762) (xy 66.163273 -432.564189) (xy 66.182893 -432.549994) (xy 66.205944 -432.542572)
			(xy 66.218054 -432.542188) (xy 67.157854 -432.542188) (xy 67.169946 -432.542647) (xy 67.192953 -432.550097)
			(xy 67.207281 -432.560476) (xy 68.141088 -432.560476) (xy 68.141088 -430.018952) (xy 68.141475 -430.006842)
			(xy 68.148987 -429.983815) (xy 68.163256 -429.964244) (xy 68.182883 -429.95005) (xy 68.205938 -429.942629)
			(xy 68.21805 -429.942244) (xy 69.15785 -429.942244) (xy 69.169937 -429.94275) (xy 69.192937 -429.950193)
			(xy 69.212518 -429.96437) (xy 69.22677 -429.983896) (xy 69.234303 -430.006866) (xy 69.234812 -430.018952)
			(xy 69.234812 -431.560478) (xy 70.141084 -431.560478) (xy 70.141084 -429.018954) (xy 70.141473 -429.006832)
			(xy 70.148979 -428.98378) (xy 70.16324 -428.964175) (xy 70.182862 -428.949937) (xy 70.205924 -428.942459)
			(xy 70.218046 -428.941992) (xy 71.157846 -428.941992) (xy 71.169958 -428.942472) (xy 71.192995 -428.949966)
			(xy 71.207537 -428.960534) (xy 72.14108 -428.960534) (xy 72.14108 -426.41901) (xy 72.141469 -426.406884)
			(xy 72.148964 -426.383818) (xy 72.163222 -426.364199) (xy 72.182847 -426.349949) (xy 72.205915 -426.342464)
			(xy 72.218042 -426.342048) (xy 73.157842 -426.342048) (xy 73.16996 -426.342476) (xy 73.193006 -426.349976)
			(xy 73.212608 -426.364229) (xy 73.226848 -426.383841) (xy 73.234332 -426.406892) (xy 73.234804 -426.41901)
			(xy 73.234804 -427.960536) (xy 75.141328 -427.960536) (xy 75.141328 -425.419012) (xy 75.141724 -425.406926)
			(xy 75.149192 -425.383938) (xy 75.163402 -425.364384) (xy 75.18296 -425.350181) (xy 75.20595 -425.34272)
			(xy 75.218036 -425.342304) (xy 76.157836 -425.342304) (xy 76.169914 -425.342734) (xy 76.192884 -425.350207)
			(xy 76.212422 -425.364413) (xy 76.226615 -425.383959) (xy 76.234074 -425.406934) (xy 76.234544 -425.419012)
			(xy 76.234544 -427.960536) (xy 76.234067 -427.972609) (xy 76.226599 -427.995571) (xy 76.212405 -428.015105)
			(xy 76.192871 -428.029299) (xy 76.169909 -428.036767) (xy 76.157836 -428.037244) (xy 75.218036 -428.037244)
			(xy 75.205967 -428.036706) (xy 75.183007 -428.029258) (xy 75.163472 -428.015079) (xy 75.149275 -427.995558)
			(xy 75.141806 -427.972605) (xy 75.141328 -427.960536) (xy 73.234804 -427.960536) (xy 73.234804 -428.960534)
			(xy 73.234318 -428.972646) (xy 73.226827 -428.995683) (xy 73.212587 -429.015281) (xy 73.192991 -429.029523)
			(xy 73.169954 -429.037017) (xy 73.157842 -429.037496) (xy 72.218042 -429.037496) (xy 72.205925 -429.037005)
			(xy 72.182873 -429.029528) (xy 72.16326 -429.015294) (xy 72.149006 -428.995695) (xy 72.141507 -428.972651)
			(xy 72.14108 -428.960534) (xy 71.207537 -428.960534) (xy 71.212592 -428.964208) (xy 71.226834 -428.983805)
			(xy 71.234328 -429.006842) (xy 71.234808 -429.018954) (xy 71.234808 -431.560478) (xy 71.23427 -431.572587)
			(xy 71.226795 -431.595622) (xy 71.212568 -431.61522) (xy 71.192983 -431.629464) (xy 71.169954 -431.636959)
			(xy 71.157846 -431.63744) (xy 70.218046 -431.63744) (xy 70.205923 -431.637001) (xy 70.182862 -431.629518)
			(xy 70.163245 -431.615273) (xy 70.148993 -431.595659) (xy 70.141503 -431.5726) (xy 70.141084 -431.560478)
			(xy 69.234812 -431.560478) (xy 69.234812 -432.560476) (xy 69.234363 -432.572582) (xy 69.226872 -432.595607)
			(xy 69.212618 -432.615179) (xy 69.193004 -432.629375) (xy 69.169958 -432.636799) (xy 69.15785 -432.637184)
			(xy 68.21805 -432.637184) (xy 68.205965 -432.636651) (xy 68.18297 -432.62921) (xy 68.163392 -432.61504)
			(xy 68.149139 -432.595522) (xy 68.141601 -432.572559) (xy 68.141088 -432.560476) (xy 67.207281 -432.560476)
			(xy 67.212538 -432.564284) (xy 67.226788 -432.583823) (xy 67.234313 -432.606806) (xy 67.234816 -432.618896)
			(xy 67.234816 -435.16042) (xy 67.234401 -435.172528) (xy 67.226898 -435.195554) (xy 67.212636 -435.215125)
			(xy 67.193015 -435.229319) (xy 67.169964 -435.236743) (xy 67.157854 -435.237128) (xy 66.218054 -435.237128)
			(xy 66.205959 -435.236731) (xy 66.182951 -435.229258) (xy 66.163369 -435.215054) (xy 66.149122 -435.195505)
			(xy 66.141596 -435.172514) (xy 66.141092 -435.16042) (xy 65.23482 -435.16042) (xy 65.23482 -436.160418)
			(xy 65.234454 -436.172546) (xy 65.226952 -436.195612) (xy 65.212688 -436.215231) (xy 65.193058 -436.22948)
			(xy 65.169986 -436.236964) (xy 65.157858 -436.23738) (xy 64.218058 -436.23738) (xy 64.205943 -436.236924)
			(xy 64.182901 -436.229428) (xy 64.163302 -436.215181) (xy 64.149061 -436.195577) (xy 64.141572 -436.172533)
			(xy 64.141096 -436.160418) (xy 63.206938 -436.160418) (xy 63.212545 -436.16448) (xy 63.226795 -436.184019)
			(xy 63.234321 -436.207002) (xy 63.234824 -436.219092) (xy 63.234824 -438.760616) (xy 63.234398 -438.772723)
			(xy 63.226897 -438.795747) (xy 63.212637 -438.815318) (xy 63.193019 -438.829513) (xy 63.169971 -438.836937)
			(xy 63.157862 -438.837324) (xy 62.218062 -438.837324) (xy 62.205967 -438.836924) (xy 62.182959 -438.829453)
			(xy 62.163377 -438.81525) (xy 62.149129 -438.795701) (xy 62.141604 -438.77271) (xy 62.1411 -438.760616)
			(xy 61.234828 -438.760616) (xy 61.234828 -439.760614) (xy 64.141096 -439.760614) (xy 64.141096 -437.21909)
			(xy 64.141603 -437.206979) (xy 64.149088 -437.183943) (xy 64.163322 -437.164345) (xy 64.182914 -437.150102)
			(xy 64.205947 -437.142608) (xy 64.218058 -437.142128) (xy 65.157858 -437.142128) (xy 65.169978 -437.142595)
			(xy 65.193033 -437.150075) (xy 65.212648 -437.164315) (xy 65.226901 -437.18392) (xy 65.234396 -437.206971)
			(xy 65.23482 -437.21909) (xy 65.23482 -438.760616) (xy 66.141092 -438.760616) (xy 66.141092 -436.219092)
			(xy 66.141509 -436.206983) (xy 66.14901 -436.183957) (xy 66.163272 -436.164385) (xy 66.182892 -436.15019)
			(xy 66.205944 -436.142768) (xy 66.218054 -436.142384) (xy 67.157854 -436.142384) (xy 67.169946 -436.142847)
			(xy 67.192952 -436.150297) (xy 67.206925 -436.160418) (xy 68.141088 -436.160418) (xy 68.141088 -433.618894)
			(xy 68.141606 -433.606784) (xy 68.149089 -433.583749) (xy 68.163321 -433.564152) (xy 68.18291 -433.549909)
			(xy 68.20594 -433.542413) (xy 68.21805 -433.541932) (xy 69.15785 -433.541932) (xy 69.169967 -433.542369)
			(xy 69.19301 -433.549869) (xy 69.212611 -433.564121) (xy 69.226851 -433.583729) (xy 69.234338 -433.606777)
			(xy 69.234812 -433.618894) (xy 69.234812 -435.16042) (xy 70.141084 -435.16042) (xy 70.141084 -432.618896)
			(xy 70.141513 -432.606789) (xy 70.149011 -432.583764) (xy 70.16327 -432.564192) (xy 70.182888 -432.549997)
			(xy 70.205937 -432.542573) (xy 70.218046 -432.542188) (xy 71.157846 -432.542188) (xy 71.169943 -432.542569)
			(xy 71.192953 -432.550044) (xy 71.207333 -432.560476) (xy 72.14108 -432.560476) (xy 72.14108 -430.018952)
			(xy 72.141475 -430.006843) (xy 72.148986 -429.983817) (xy 72.163253 -429.964247) (xy 72.182877 -429.950053)
			(xy 72.205931 -429.94263) (xy 72.218042 -429.942244) (xy 73.157842 -429.942244) (xy 73.169934 -429.942672)
			(xy 73.192937 -429.95014) (xy 73.212516 -429.964337) (xy 73.226765 -429.983879) (xy 73.234296 -430.006861)
			(xy 73.234804 -430.018952) (xy 73.234804 -431.560478) (xy 75.141328 -431.560478) (xy 75.141328 -429.018954)
			(xy 75.141768 -429.006863) (xy 75.149236 -428.983863) (xy 75.16343 -428.964285) (xy 75.182968 -428.950036)
			(xy 75.205947 -428.942503) (xy 75.218036 -428.941992) (xy 76.157836 -428.941992) (xy 76.169946 -428.942386)
			(xy 76.192973 -428.949894) (xy 76.207568 -428.960534) (xy 77.141324 -428.960534) (xy 77.141324 -426.41901)
			(xy 77.141816 -426.406923) (xy 77.149268 -426.383925) (xy 77.163449 -426.364346) (xy 77.182976 -426.350095)
			(xy 77.205946 -426.34256) (xy 77.218032 -426.342048) (xy 78.157832 -426.342048) (xy 78.169937 -426.342488)
			(xy 78.192957 -426.34999) (xy 78.212525 -426.364248) (xy 78.22672 -426.38386) (xy 78.234149 -426.406903)
			(xy 78.23454 -426.41901) (xy 78.23454 -427.960536) (xy 79.14132 -427.960536) (xy 79.14132 -425.419012)
			(xy 79.141724 -425.406927) (xy 79.149191 -425.38394) (xy 79.163399 -425.364387) (xy 79.182954 -425.350184)
			(xy 79.205943 -425.342721) (xy 79.218028 -425.342304) (xy 80.157828 -425.342304) (xy 80.169905 -425.34274)
			(xy 80.192875 -425.350212) (xy 80.212413 -425.364415) (xy 80.226606 -425.38396) (xy 80.234066 -425.406935)
			(xy 80.234536 -425.419012) (xy 80.234536 -427.960536) (xy 80.234067 -427.97261) (xy 80.226598 -427.995573)
			(xy 80.212402 -428.015107) (xy 80.192866 -428.029302) (xy 80.169902 -428.036768) (xy 80.157828 -428.037244)
			(xy 79.218028 -428.037244) (xy 79.205958 -428.036713) (xy 79.182998 -428.029262) (xy 79.163464 -428.015082)
			(xy 79.149267 -427.995559) (xy 79.141797 -427.972605) (xy 79.14132 -427.960536) (xy 78.23454 -427.960536)
			(xy 78.23454 -428.960534) (xy 78.234121 -428.972627) (xy 78.226653 -428.995632) (xy 78.212454 -429.015214)
			(xy 78.19291 -429.029462) (xy 78.169924 -429.03699) (xy 78.157832 -429.037496) (xy 77.218032 -429.037496)
			(xy 77.205924 -429.037056) (xy 77.182898 -429.029565) (xy 77.163324 -429.01531) (xy 77.149128 -428.995692)
			(xy 77.141707 -428.972643) (xy 77.141324 -428.960534) (xy 76.207568 -428.960534) (xy 76.212545 -428.964162)
			(xy 76.226738 -428.983787) (xy 76.23416 -429.006843) (xy 76.234544 -429.018954) (xy 76.234544 -431.560478)
			(xy 76.234074 -431.572568) (xy 76.226621 -431.595571) (xy 76.212436 -431.615152) (xy 76.192902 -431.629403)
			(xy 76.169924 -431.636933) (xy 76.157836 -431.63744) (xy 75.218036 -431.63744) (xy 75.205933 -431.636953)
			(xy 75.182914 -431.629469) (xy 75.163344 -431.615224) (xy 75.149146 -431.595619) (xy 75.141718 -431.572582)
			(xy 75.141328 -431.560478) (xy 73.234804 -431.560478) (xy 73.234804 -432.560476) (xy 73.234363 -432.572583)
			(xy 73.226871 -432.595609) (xy 73.212615 -432.615182) (xy 73.192999 -432.629378) (xy 73.16995 -432.6368)
			(xy 73.157842 -432.637184) (xy 72.218042 -432.637184) (xy 72.205957 -432.636657) (xy 72.182962 -432.629215)
			(xy 72.163383 -432.615043) (xy 72.14913 -432.595523) (xy 72.141593 -432.572559) (xy 72.14108 -432.560476)
			(xy 71.207333 -432.560476) (xy 71.212536 -432.564251) (xy 71.226784 -432.583805) (xy 71.234306 -432.6068)
			(xy 71.234808 -432.618896) (xy 71.234808 -435.16042) (xy 71.234401 -435.172529) (xy 71.226897 -435.195556)
			(xy 71.212633 -435.215128) (xy 71.19301 -435.229322) (xy 71.169957 -435.236744) (xy 71.157846 -435.237128)
			(xy 70.218046 -435.237128) (xy 70.205956 -435.236653) (xy 70.182951 -435.229205) (xy 70.163368 -435.215022)
			(xy 70.149117 -435.195487) (xy 70.141589 -435.172509) (xy 70.141084 -435.16042) (xy 69.234812 -435.16042)
			(xy 69.234812 -436.160418) (xy 69.234305 -436.172529) (xy 69.226818 -436.195564) (xy 69.212584 -436.215161)
			(xy 69.192993 -436.229404) (xy 69.16996 -436.2369) (xy 69.15785 -436.23738) (xy 68.21805 -436.23738)
			(xy 68.205935 -436.236931) (xy 68.182893 -436.229432) (xy 68.163293 -436.215184) (xy 68.149053 -436.195578)
			(xy 68.141564 -436.172534) (xy 68.141088 -436.160418) (xy 67.206925 -436.160418) (xy 67.212537 -436.164483)
			(xy 67.226787 -436.18402) (xy 67.234312 -436.207002) (xy 67.234816 -436.219092) (xy 67.234816 -438.760616)
			(xy 67.234398 -438.772724) (xy 67.226896 -438.795749) (xy 67.212634 -438.815321) (xy 67.193014 -438.829515)
			(xy 67.169963 -438.836939) (xy 67.157854 -438.837324) (xy 66.218054 -438.837324) (xy 66.205958 -438.836931)
			(xy 66.18295 -438.829457) (xy 66.163368 -438.815253) (xy 66.14912 -438.795702) (xy 66.141596 -438.77271)
			(xy 66.141092 -438.760616) (xy 65.23482 -438.760616) (xy 65.23482 -439.760614) (xy 68.141088 -439.760614)
			(xy 68.141088 -437.21909) (xy 68.141603 -437.20698) (xy 68.149087 -437.183945) (xy 68.163319 -437.164348)
			(xy 68.182909 -437.150105) (xy 68.20594 -437.142609) (xy 68.21805 -437.142128) (xy 69.15785 -437.142128)
			(xy 69.169966 -437.142569) (xy 69.193009 -437.150069) (xy 69.212609 -437.164319) (xy 69.22685 -437.183927)
			(xy 69.234337 -437.206974) (xy 69.234812 -437.21909) (xy 69.234812 -438.760616) (xy 70.141084 -438.760616)
			(xy 70.141084 -436.219092) (xy 70.141509 -436.206984) (xy 70.149009 -436.183959) (xy 70.163269 -436.164388)
			(xy 70.182887 -436.150193) (xy 70.205937 -436.142769) (xy 70.218046 -436.142384) (xy 71.157846 -436.142384)
			(xy 71.169942 -436.142769) (xy 71.192952 -436.150244) (xy 71.206977 -436.160418) (xy 72.14108 -436.160418)
			(xy 72.14108 -433.618894) (xy 72.141456 -433.606767) (xy 72.148955 -433.583701) (xy 72.163216 -433.564082)
			(xy 72.182844 -433.549833) (xy 72.205915 -433.542348) (xy 72.218042 -433.541932) (xy 73.157842 -433.541932)
			(xy 73.169958 -433.542376) (xy 73.193002 -433.549874) (xy 73.212602 -433.564123) (xy 73.226843 -433.583731)
			(xy 73.23433 -433.606778) (xy 73.234804 -433.618894) (xy 73.234804 -435.16042) (xy 75.141328 -435.16042)
			(xy 75.141328 -432.618896) (xy 75.14171 -432.606809) (xy 75.149183 -432.58382) (xy 75.163396 -432.564267)
			(xy 75.182956 -432.550064) (xy 75.205949 -432.542603) (xy 75.218036 -432.542188) (xy 76.157836 -432.542188)
			(xy 76.169912 -432.542633) (xy 76.19288 -432.550105) (xy 76.207146 -432.560476) (xy 77.141324 -432.560476)
			(xy 77.141324 -430.018952) (xy 77.141724 -430.006872) (xy 77.149203 -429.983898) (xy 77.163415 -429.964358)
			(xy 77.182969 -429.950167) (xy 77.205951 -429.942711) (xy 77.218032 -429.942244) (xy 78.157832 -429.942244)
			(xy 78.169903 -429.942736) (xy 78.192864 -429.950201) (xy 78.212396 -429.964393) (xy 78.226591 -429.983922)
			(xy 78.234062 -430.006881) (xy 78.23454 -430.018952) (xy 78.23454 -431.560478) (xy 79.14132 -431.560478)
			(xy 79.14132 -429.018954) (xy 79.141768 -429.006864) (xy 79.149235 -428.983865) (xy 79.163427 -428.964288)
			(xy 79.182963 -428.950038) (xy 79.205939 -428.942504) (xy 79.218028 -428.941992) (xy 80.157828 -428.941992)
			(xy 80.169938 -428.942392) (xy 80.192964 -428.949899) (xy 80.207555 -428.960534) (xy 81.141316 -428.960534)
			(xy 81.141316 -426.41901) (xy 81.141816 -426.406923) (xy 81.149267 -426.383927) (xy 81.163446 -426.364349)
			(xy 81.182971 -426.350097) (xy 81.205939 -426.342561) (xy 81.218024 -426.342048) (xy 82.157824 -426.342048)
			(xy 82.169929 -426.342495) (xy 82.192948 -426.349995) (xy 82.212516 -426.36425) (xy 82.226712 -426.383862)
			(xy 82.234141 -426.406904) (xy 82.234532 -426.41901) (xy 82.234532 -427.960536) (xy 83.141312 -427.960536)
			(xy 83.141312 -425.419012) (xy 83.141723 -425.406928) (xy 83.14919 -425.383942) (xy 83.163396 -425.36439)
			(xy 83.182949 -425.350186) (xy 83.205936 -425.342722) (xy 83.21802 -425.342304) (xy 84.15782 -425.342304)
			(xy 84.169897 -425.342748) (xy 84.192867 -425.350217) (xy 84.212404 -425.364419) (xy 84.226598 -425.383962)
			(xy 84.234057 -425.406935) (xy 84.234528 -425.419012) (xy 84.234528 -427.960536) (xy 84.234067 -427.97261)
			(xy 84.226597 -427.995576) (xy 84.212399 -428.01511) (xy 84.192861 -428.029304) (xy 84.169895 -428.036769)
			(xy 84.15782 -428.037244) (xy 83.21802 -428.037244) (xy 83.20595 -428.036719) (xy 83.18299 -428.029267)
			(xy 83.163455 -428.015085) (xy 83.149259 -427.995561) (xy 83.141789 -427.972606) (xy 83.141312 -427.960536)
			(xy 82.234532 -427.960536) (xy 82.234532 -428.960534) (xy 82.234121 -428.972628) (xy 82.226652 -428.995635)
			(xy 82.212452 -429.015216) (xy 82.192905 -429.029465) (xy 82.169917 -429.036991) (xy 82.157824 -429.037496)
			(xy 81.218024 -429.037496) (xy 81.205916 -429.037063) (xy 81.182889 -429.02957) (xy 81.163315 -429.015313)
			(xy 81.14912 -428.995694) (xy 81.141699 -428.972643) (xy 81.141316 -428.960534) (xy 80.207555 -428.960534)
			(xy 80.212536 -428.964165) (xy 80.22673 -428.983789) (xy 80.234152 -429.006843) (xy 80.234536 -429.018954)
			(xy 80.234536 -431.560478) (xy 80.234073 -431.572569) (xy 80.22662 -431.595573) (xy 80.212433 -431.615155)
			(xy 80.192897 -431.629405) (xy 80.169917 -431.636934) (xy 80.157828 -431.63744) (xy 79.218028 -431.63744)
			(xy 79.205925 -431.63696) (xy 79.182905 -431.629473) (xy 79.163335 -431.615227) (xy 79.149138 -431.595621)
			(xy 79.141709 -431.572582) (xy 79.14132 -431.560478) (xy 78.23454 -431.560478) (xy 78.23454 -432.560476)
			(xy 78.234016 -432.572546) (xy 78.226564 -432.595507) (xy 78.212382 -432.615042) (xy 78.192857 -432.629238)
			(xy 78.169902 -432.636707) (xy 78.157832 -432.637184) (xy 77.218032 -432.637184) (xy 77.205949 -432.63676)
			(xy 77.182963 -432.629298) (xy 77.16341 -432.615096) (xy 77.149206 -432.595544) (xy 77.141742 -432.572559)
			(xy 77.141324 -432.560476) (xy 76.207146 -432.560476) (xy 76.212416 -432.564307) (xy 76.226609 -432.583849)
			(xy 76.234072 -432.60682) (xy 76.234544 -432.618896) (xy 76.234544 -435.16042) (xy 76.234053 -435.172492)
			(xy 76.22659 -435.195454) (xy 76.212399 -435.214987) (xy 76.192868 -435.229182) (xy 76.169908 -435.236651)
			(xy 76.157836 -435.237128) (xy 75.218036 -435.237128) (xy 75.205957 -435.236657) (xy 75.182979 -435.229202)
			(xy 75.16343 -435.21501) (xy 75.149224 -435.195471) (xy 75.141752 -435.172499) (xy 75.141328 -435.16042)
			(xy 73.234804 -435.16042) (xy 73.234804 -436.160418) (xy 73.234304 -436.172529) (xy 73.226817 -436.195566)
			(xy 73.212581 -436.215164) (xy 73.192988 -436.229406) (xy 73.169953 -436.236901) (xy 73.157842 -436.23738)
			(xy 72.218042 -436.23738) (xy 72.205923 -436.236905) (xy 72.182869 -436.229426) (xy 72.163255 -436.215188)
			(xy 72.149001 -436.195585) (xy 72.141505 -436.172536) (xy 72.14108 -436.160418) (xy 71.206977 -436.160418)
			(xy 71.212535 -436.16445) (xy 71.226782 -436.184003) (xy 71.234305 -436.206997) (xy 71.234808 -436.219092)
			(xy 71.234808 -438.760616) (xy 71.234398 -438.772725) (xy 71.226895 -438.795751) (xy 71.212631 -438.815324)
			(xy 71.193009 -438.829518) (xy 71.169956 -438.83694) (xy 71.157846 -438.837324) (xy 70.218046 -438.837324)
			(xy 70.205955 -438.836853) (xy 70.18295 -438.829404) (xy 70.163366 -438.81522) (xy 70.149115 -438.795685)
			(xy 70.141589 -438.772705) (xy 70.141084 -438.760616) (xy 69.234812 -438.760616) (xy 69.234812 -439.760614)
			(xy 72.14108 -439.760614) (xy 72.14108 -437.21909) (xy 72.141452 -437.206963) (xy 72.148952 -437.183896)
			(xy 72.163215 -437.164278) (xy 72.182843 -437.150029) (xy 72.205914 -437.142544) (xy 72.218042 -437.142128)
			(xy 73.157842 -437.142128) (xy 73.169958 -437.142576) (xy 73.193001 -437.150073) (xy 73.212601 -437.164322)
			(xy 73.226841 -437.183928) (xy 73.234329 -437.206974) (xy 73.234804 -437.21909) (xy 73.234804 -438.760616)
			(xy 75.141328 -438.760616) (xy 75.141328 -436.219092) (xy 75.141706 -436.207005) (xy 75.14918 -436.184016)
			(xy 75.163394 -436.164463) (xy 75.182956 -436.15026) (xy 75.205949 -436.142799) (xy 75.218036 -436.142384)
			(xy 76.157836 -436.142384) (xy 76.169912 -436.142833) (xy 76.192879 -436.150305) (xy 76.206792 -436.160418)
			(xy 77.141324 -436.160418) (xy 77.141324 -433.618894) (xy 77.141802 -433.606806) (xy 77.149259 -433.583808)
			(xy 77.163443 -433.564229) (xy 77.182973 -433.549978) (xy 77.205945 -433.542444) (xy 77.218032 -433.541932)
			(xy 78.157832 -433.541932) (xy 78.169946 -433.542289) (xy 78.19298 -433.549802) (xy 78.212555 -433.564077)
			(xy 78.226747 -433.583713) (xy 78.234161 -433.606779) (xy 78.23454 -433.618894) (xy 78.23454 -435.16042)
			(xy 79.14132 -435.16042) (xy 79.14132 -432.618896) (xy 79.141709 -432.60681) (xy 79.149182 -432.583823)
			(xy 79.163393 -432.56427) (xy 79.182951 -432.550067) (xy 79.205942 -432.542604) (xy 79.218028 -432.542188)
			(xy 80.157828 -432.542188) (xy 80.169904 -432.54264) (xy 80.192871 -432.55011) (xy 80.207132 -432.560476)
			(xy 81.141316 -432.560476) (xy 81.141316 -430.018952) (xy 81.141724 -430.006873) (xy 81.149202 -429.9839)
			(xy 81.163413 -429.964361) (xy 81.182964 -429.950169) (xy 81.205944 -429.942712) (xy 81.218024 -429.942244)
			(xy 82.157824 -429.942244) (xy 82.169895 -429.942743) (xy 82.192855 -429.950206) (xy 82.212387 -429.964396)
			(xy 82.226583 -429.983924) (xy 82.234053 -430.006881) (xy 82.234532 -430.018952) (xy 82.234532 -431.560478)
			(xy 83.141312 -431.560478) (xy 83.141312 -429.018954) (xy 83.141768 -429.006865) (xy 83.149234 -428.983867)
			(xy 83.163424 -428.964291) (xy 83.182958 -428.950041) (xy 83.205932 -428.942505) (xy 83.21802 -428.941992)
			(xy 84.15782 -428.941992) (xy 84.169929 -428.942399) (xy 84.192956 -428.949903) (xy 84.207543 -428.960534)
			(xy 85.141308 -428.960534) (xy 85.141308 -426.41901) (xy 85.141815 -426.406924) (xy 85.149265 -426.383929)
			(xy 85.163443 -426.364352) (xy 85.182966 -426.3501) (xy 85.205932 -426.342562) (xy 85.218016 -426.342048)
			(xy 86.157816 -426.342048) (xy 86.169921 -426.342502) (xy 86.192939 -426.349999) (xy 86.212508 -426.364253)
			(xy 86.226704 -426.383863) (xy 86.234133 -426.406904) (xy 86.234524 -426.41901) (xy 86.234524 -427.960536)
			(xy 87.141304 -427.960536) (xy 87.141304 -425.419012) (xy 87.141723 -425.406929) (xy 87.149189 -425.383944)
			(xy 87.163393 -425.364393) (xy 87.182944 -425.350189) (xy 87.205929 -425.342723) (xy 87.218012 -425.342304)
			(xy 88.157812 -425.342304) (xy 88.169888 -425.342754) (xy 88.192858 -425.350222) (xy 88.212396 -425.364421)
			(xy 88.226589 -425.383964) (xy 88.234049 -425.406935) (xy 88.23452 -425.419012) (xy 88.23452 -427.960536)
			(xy 88.234067 -427.972611) (xy 88.226596 -427.995578) (xy 88.212396 -428.015113) (xy 88.192856 -428.029307)
			(xy 88.169887 -428.036771) (xy 88.157812 -428.037244) (xy 87.218012 -428.037244) (xy 87.205942 -428.036726)
			(xy 87.182981 -428.029271) (xy 87.163447 -428.015087) (xy 87.149251 -427.995562) (xy 87.141781 -427.972606)
			(xy 87.141304 -427.960536) (xy 86.234524 -427.960536) (xy 86.234524 -428.960534) (xy 86.234121 -428.972629)
			(xy 86.226651 -428.995637) (xy 86.212449 -429.015219) (xy 86.1929 -429.029467) (xy 86.16991 -429.036992)
			(xy 86.157816 -429.037496) (xy 85.218016 -429.037496) (xy 85.205908 -429.03707) (xy 85.18288 -429.029574)
			(xy 85.163307 -429.015315) (xy 85.149112 -428.995695) (xy 85.141691 -428.972644) (xy 85.141308 -428.960534)
			(xy 84.207543 -428.960534) (xy 84.212528 -428.964167) (xy 84.226722 -428.98379) (xy 84.234144 -429.006843)
			(xy 84.234528 -429.018954) (xy 84.234528 -431.560478) (xy 84.234073 -431.57257) (xy 84.226619 -431.595575)
			(xy 84.21243 -431.615158) (xy 84.192892 -431.629408) (xy 84.16991 -431.636935) (xy 84.15782 -431.63744)
			(xy 83.21802 -431.63744) (xy 83.205916 -431.636967) (xy 83.182896 -431.629478) (xy 83.163327 -431.61523)
			(xy 83.14913 -431.595622) (xy 83.141701 -431.572583) (xy 83.141312 -431.560478) (xy 82.234532 -431.560478)
			(xy 82.234532 -432.560476) (xy 82.234016 -432.572547) (xy 82.226563 -432.595509) (xy 82.212379 -432.615045)
			(xy 82.192852 -432.629241) (xy 82.169895 -432.636708) (xy 82.157824 -432.637184) (xy 81.218024 -432.637184)
			(xy 81.20594 -432.636766) (xy 81.182954 -432.629303) (xy 81.163401 -432.615099) (xy 81.149197 -432.595546)
			(xy 81.141734 -432.57256) (xy 81.141316 -432.560476) (xy 80.207132 -432.560476) (xy 80.212407 -432.56431)
			(xy 80.226601 -432.58385) (xy 80.234064 -432.60682) (xy 80.234536 -432.618896) (xy 80.234536 -435.16042)
			(xy 80.234053 -435.172493) (xy 80.226588 -435.195456) (xy 80.212396 -435.21499) (xy 80.192863 -435.229185)
			(xy 80.169901 -435.236652) (xy 80.157828 -435.237128) (xy 79.218028 -435.237128) (xy 79.205949 -435.236664)
			(xy 79.18297 -435.229206) (xy 79.163421 -435.215013) (xy 79.149216 -435.195473) (xy 79.141744 -435.172499)
			(xy 79.14132 -435.16042) (xy 78.23454 -435.16042) (xy 78.23454 -436.160418) (xy 78.234108 -436.172511)
			(xy 78.226644 -436.195515) (xy 78.212449 -436.215097) (xy 78.192907 -436.229346) (xy 78.169923 -436.236874)
			(xy 78.157832 -436.23738) (xy 77.218032 -436.23738) (xy 77.205923 -436.236956) (xy 77.182893 -436.229463)
			(xy 77.163318 -436.215204) (xy 77.149123 -436.195582) (xy 77.141705 -436.172528) (xy 77.141324 -436.160418)
			(xy 76.206792 -436.160418) (xy 76.212415 -436.164505) (xy 76.226608 -436.184046) (xy 76.234071 -436.207016)
			(xy 76.234544 -436.219092) (xy 76.234544 -438.760616) (xy 76.23405 -438.772688) (xy 76.226587 -438.795649)
			(xy 76.212397 -438.815183) (xy 76.192867 -438.829378) (xy 76.169908 -438.836847) (xy 76.157836 -438.837324)
			(xy 75.218036 -438.837324) (xy 75.205957 -438.836857) (xy 75.182978 -438.829401) (xy 75.163428 -438.815209)
			(xy 75.149223 -438.795669) (xy 75.141751 -438.772695) (xy 75.141328 -438.760616) (xy 73.234804 -438.760616)
			(xy 73.234804 -439.760614) (xy 77.141324 -439.760614) (xy 77.141324 -437.21909) (xy 77.141799 -437.207002)
			(xy 77.149256 -437.184003) (xy 77.163441 -437.164425) (xy 77.182972 -437.150174) (xy 77.205945 -437.14264)
			(xy 77.218032 -437.142128) (xy 78.157832 -437.142128) (xy 78.169945 -437.142489) (xy 78.192978 -437.150001)
			(xy 78.212553 -437.164276) (xy 78.226746 -437.183911) (xy 78.234161 -437.206975) (xy 78.23454 -437.21909)
			(xy 78.23454 -438.760616) (xy 79.14132 -438.760616) (xy 79.14132 -436.219092) (xy 79.141706 -436.207006)
			(xy 79.149179 -436.184018) (xy 79.163391 -436.164466) (xy 79.182951 -436.150263) (xy 79.205942 -436.1428)
			(xy 79.218028 -436.142384) (xy 80.157828 -436.142384) (xy 80.169903 -436.14284) (xy 80.19287 -436.150309)
			(xy 80.206779 -436.160418) (xy 81.141316 -436.160418) (xy 81.141316 -433.618894) (xy 81.141802 -433.606807)
			(xy 81.149257 -433.58381) (xy 81.16344 -433.564232) (xy 81.182968 -433.549981) (xy 81.205938 -433.542445)
			(xy 81.218024 -433.541932) (xy 82.157824 -433.541932) (xy 82.169937 -433.542296) (xy 82.192971 -433.549806)
			(xy 82.212546 -433.56408) (xy 82.226739 -433.583715) (xy 82.234153 -433.606779) (xy 82.234532 -433.618894)
			(xy 82.234532 -435.16042) (xy 83.141312 -435.16042) (xy 83.141312 -432.618896) (xy 83.141709 -432.606811)
			(xy 83.14918 -432.583825) (xy 83.16339 -432.564273) (xy 83.182946 -432.550069) (xy 83.205935 -432.542606)
			(xy 83.21802 -432.542188) (xy 84.15782 -432.542188) (xy 84.169895 -432.542647) (xy 84.192862 -432.550115)
			(xy 84.207119 -432.560476) (xy 85.141308 -432.560476) (xy 85.141308 -430.018952) (xy 85.141723 -430.006873)
			(xy 85.149201 -429.983902) (xy 85.16341 -429.964364) (xy 85.182959 -429.950172) (xy 85.205937 -429.942713)
			(xy 85.218016 -429.942244) (xy 86.157816 -429.942244) (xy 86.169887 -429.94275) (xy 86.192846 -429.950211)
			(xy 86.212379 -429.964399) (xy 86.226574 -429.983925) (xy 86.234045 -430.006882) (xy 86.234524 -430.018952)
			(xy 86.234524 -431.560478) (xy 87.141304 -431.560478) (xy 87.141304 -429.018954) (xy 87.141767 -429.006866)
			(xy 87.149232 -428.98387) (xy 87.163421 -428.964293) (xy 87.182953 -428.950043) (xy 87.205925 -428.942506)
			(xy 87.218012 -428.941992) (xy 88.157812 -428.941992) (xy 88.169921 -428.942406) (xy 88.192947 -428.949908)
			(xy 88.207529 -428.960534) (xy 89.1413 -428.960534) (xy 89.1413 -426.41901) (xy 89.141815 -426.406925)
			(xy 89.149264 -426.383931) (xy 89.16344 -426.364355) (xy 89.182961 -426.350103) (xy 89.205925 -426.342563)
			(xy 89.218008 -426.342048) (xy 90.157808 -426.342048) (xy 90.169912 -426.342509) (xy 90.192931 -426.350004)
			(xy 90.212499 -426.364256) (xy 90.226696 -426.383865) (xy 90.234125 -426.406905) (xy 90.234516 -426.41901)
			(xy 90.234516 -428.960534) (xy 90.234121 -428.97263) (xy 90.226649 -428.995639) (xy 90.212446 -429.015222)
			(xy 90.192895 -429.02947) (xy 90.169903 -429.036993) (xy 90.157808 -429.037496) (xy 89.218008 -429.037496)
			(xy 89.205899 -429.037077) (xy 89.182871 -429.029579) (xy 89.163298 -429.015319) (xy 89.149103 -428.995697)
			(xy 89.141683 -428.972644) (xy 89.1413 -428.960534) (xy 88.207529 -428.960534) (xy 88.212519 -428.96417)
			(xy 88.226714 -428.983792) (xy 88.234136 -429.006844) (xy 88.23452 -429.018954) (xy 88.23452 -431.560478)
			(xy 88.234073 -431.57257) (xy 88.226618 -431.595577) (xy 88.212427 -431.615161) (xy 88.192887 -431.629411)
			(xy 88.169903 -431.636936) (xy 88.157812 -431.63744) (xy 87.218012 -431.63744) (xy 87.205908 -431.636974)
			(xy 87.182888 -431.629483) (xy 87.163318 -431.615232) (xy 87.149122 -431.595624) (xy 87.141693 -431.572583)
			(xy 87.141304 -431.560478) (xy 86.234524 -431.560478) (xy 86.234524 -432.560476) (xy 86.234067 -432.572556)
			(xy 86.226608 -432.595535) (xy 86.212413 -432.615084) (xy 86.192871 -432.62929) (xy 86.169896 -432.636761)
			(xy 86.157816 -432.637184) (xy 85.218016 -432.637184) (xy 85.205932 -432.636773) (xy 85.182946 -432.629307)
			(xy 85.163393 -432.615101) (xy 85.149189 -432.595547) (xy 85.141726 -432.57256) (xy 85.141308 -432.560476)
			(xy 84.207119 -432.560476) (xy 84.212399 -432.564313) (xy 84.226593 -432.583852) (xy 84.234055 -432.606821)
			(xy 84.234528 -432.618896) (xy 84.234528 -435.16042) (xy 84.234053 -435.172494) (xy 84.226587 -435.195458)
			(xy 84.212393 -435.214993) (xy 84.192858 -435.229187) (xy 84.169894 -435.236653) (xy 84.15782 -435.237128)
			(xy 83.21802 -435.237128) (xy 83.205948 -435.236619) (xy 83.182985 -435.229165) (xy 83.16345 -435.214979)
			(xy 83.149254 -435.195451) (xy 83.141787 -435.172491) (xy 83.141312 -435.16042) (xy 82.234532 -435.16042)
			(xy 82.234532 -436.160418) (xy 82.234108 -436.172511) (xy 82.226643 -436.195517) (xy 82.212446 -436.215099)
			(xy 82.192902 -436.229348) (xy 82.169916 -436.236875) (xy 82.157824 -436.23738) (xy 81.218024 -436.23738)
			(xy 81.205914 -436.236963) (xy 81.182885 -436.229468) (xy 81.163309 -436.215207) (xy 81.149115 -436.195584)
			(xy 81.141697 -436.172529) (xy 81.141316 -436.160418) (xy 80.206779 -436.160418) (xy 80.212406 -436.164508)
			(xy 80.2266 -436.184048) (xy 80.234063 -436.207017) (xy 80.234536 -436.219092) (xy 80.234536 -438.760616)
			(xy 80.23405 -438.772689) (xy 80.226586 -438.795651) (xy 80.212394 -438.815186) (xy 80.192862 -438.829381)
			(xy 80.169901 -438.836848) (xy 80.157828 -438.837324) (xy 79.218028 -438.837324) (xy 79.205948 -438.836864)
			(xy 79.182969 -438.829406) (xy 79.16342 -438.815211) (xy 79.149214 -438.79567) (xy 79.141743 -438.772695)
			(xy 79.14132 -438.760616) (xy 78.23454 -438.760616) (xy 78.23454 -439.760614) (xy 81.141316 -439.760614)
			(xy 81.141316 -437.21909) (xy 81.141799 -437.207002) (xy 81.149255 -437.184006) (xy 81.163439 -437.164428)
			(xy 81.182967 -437.150177) (xy 81.205938 -437.142641) (xy 81.218024 -437.142128) (xy 82.157824 -437.142128)
			(xy 82.169937 -437.142496) (xy 82.19297 -437.150006) (xy 82.212545 -437.164279) (xy 82.226738 -437.183912)
			(xy 82.234153 -437.206975) (xy 82.234532 -437.21909) (xy 82.234532 -438.760616) (xy 83.141312 -438.760616)
			(xy 83.141312 -436.219092) (xy 83.141706 -436.207007) (xy 83.149178 -436.18402) (xy 83.163388 -436.164469)
			(xy 83.182946 -436.150265) (xy 83.205935 -436.142802) (xy 83.21802 -436.142384) (xy 84.15782 -436.142384)
			(xy 84.169895 -436.142847) (xy 84.192861 -436.150314) (xy 84.206765 -436.160418) (xy 85.141308 -436.160418)
			(xy 85.141308 -433.618894) (xy 85.141802 -433.606807) (xy 85.149256 -433.583812) (xy 85.163437 -433.564235)
			(xy 85.182963 -433.549984) (xy 85.205931 -433.542446) (xy 85.218016 -433.541932) (xy 86.157816 -433.541932)
			(xy 86.169929 -433.542303) (xy 86.192962 -433.549811) (xy 86.212538 -433.564083) (xy 86.226731 -433.583716)
			(xy 86.234145 -433.606779) (xy 86.234524 -433.618894) (xy 86.234524 -435.16042) (xy 87.141304 -435.16042)
			(xy 87.141304 -432.618896) (xy 87.141709 -432.606812) (xy 87.149179 -432.583827) (xy 87.163387 -432.564276)
			(xy 87.182941 -432.550072) (xy 87.205928 -432.542607) (xy 87.218012 -432.542188) (xy 88.157812 -432.542188)
			(xy 88.169887 -432.542654) (xy 88.192854 -432.550119) (xy 88.207106 -432.560476) (xy 89.1413 -432.560476)
			(xy 89.1413 -430.018952) (xy 89.141723 -430.006874) (xy 89.1492 -429.983904) (xy 89.163407 -429.964367)
			(xy 89.182954 -429.950174) (xy 89.20593 -429.942714) (xy 89.218008 -429.942244) (xy 90.157808 -429.942244)
			(xy 90.169878 -429.942757) (xy 90.192837 -429.950216) (xy 90.21237 -429.964401) (xy 90.226566 -429.983927)
			(xy 90.234037 -430.006882) (xy 90.234516 -430.018952) (xy 90.234516 -431.360072) (xy 108.40466 -431.360072)
			(xy 108.405158 -431.275192) (xy 108.413115 -431.105619) (xy 108.429011 -430.936605) (xy 108.452812 -430.768522)
			(xy 108.484466 -430.601739) (xy 108.523902 -430.436623) (xy 108.571034 -430.273538) (xy 108.625758 -430.11284)
			(xy 108.687955 -429.954885) (xy 108.757487 -429.800018) (xy 108.834202 -429.648581) (xy 108.91793 -429.500905)
			(xy 109.008488 -429.357317) (xy 109.105677 -429.218131) (xy 109.209284 -429.083654) (xy 109.319079 -428.954181)
			(xy 109.434823 -428.829996) (xy 109.55626 -428.711373) (xy 109.683124 -428.598572) (xy 109.815135 -428.491842)
			(xy 109.952005 -428.391417) (xy 110.09343 -428.297518) (xy 110.239102 -428.21035) (xy 110.3887 -428.130107)
			(xy 110.541894 -428.056963) (xy 110.698348 -427.991081) (xy 110.857718 -427.932604) (xy 111.019654 -427.881662)
			(xy 111.1838 -427.838366) (xy 111.349795 -427.802811) (xy 111.517274 -427.775076) (xy 111.685869 -427.755222)
			(xy 111.855209 -427.743292) (xy 112.024922 -427.739313) (xy 112.194635 -427.743292) (xy 112.363975 -427.755222)
			(xy 112.53257 -427.775076) (xy 112.700049 -427.802811) (xy 112.866044 -427.838366) (xy 113.03019 -427.881662)
			(xy 113.192126 -427.932604) (xy 113.26825 -427.960536) (xy 125.241304 -427.960536) (xy 125.241304 -425.419012)
			(xy 125.241723 -425.406929) (xy 125.249189 -425.383944) (xy 125.263393 -425.364393) (xy 125.282944 -425.350189)
			(xy 125.305929 -425.342723) (xy 125.318012 -425.342304) (xy 126.257812 -425.342304) (xy 126.269888 -425.342754)
			(xy 126.292858 -425.350222) (xy 126.312396 -425.364421) (xy 126.326589 -425.383964) (xy 126.334049 -425.406935)
			(xy 126.33452 -425.419012) (xy 126.33452 -427.960536) (xy 126.334067 -427.972611) (xy 126.326596 -427.995578)
			(xy 126.312396 -428.015113) (xy 126.292856 -428.029307) (xy 126.269887 -428.036771) (xy 126.257812 -428.037244)
			(xy 125.318012 -428.037244) (xy 125.305942 -428.036726) (xy 125.282981 -428.029271) (xy 125.263447 -428.015087)
			(xy 125.249251 -427.995562) (xy 125.241781 -427.972606) (xy 125.241304 -427.960536) (xy 113.26825 -427.960536)
			(xy 113.351496 -427.991081) (xy 113.50795 -428.056963) (xy 113.661144 -428.130107) (xy 113.810742 -428.21035)
			(xy 113.956414 -428.297518) (xy 114.097839 -428.391417) (xy 114.234709 -428.491842) (xy 114.36672 -428.598572)
			(xy 114.493584 -428.711373) (xy 114.615021 -428.829996) (xy 114.730765 -428.954181) (xy 114.84056 -429.083654)
			(xy 114.944167 -429.218131) (xy 115.041356 -429.357317) (xy 115.131914 -429.500905) (xy 115.215642 -429.648581)
			(xy 115.292357 -429.800018) (xy 115.361889 -429.954885) (xy 115.424086 -430.11284) (xy 115.47881 -430.273538)
			(xy 115.525942 -430.436623) (xy 115.565378 -430.601739) (xy 115.597032 -430.768522) (xy 115.620833 -430.936605)
			(xy 115.636729 -431.105619) (xy 115.644686 -431.275192) (xy 115.645184 -431.360072) (xy 115.644698 -431.445674)
			(xy 115.639268 -431.560478) (xy 125.241304 -431.560478) (xy 125.241304 -429.018954) (xy 125.241767 -429.006866)
			(xy 125.249232 -428.98387) (xy 125.263421 -428.964293) (xy 125.282953 -428.950043) (xy 125.305925 -428.942506)
			(xy 125.318012 -428.941992) (xy 126.257812 -428.941992) (xy 126.269921 -428.942406) (xy 126.292947 -428.949908)
			(xy 126.307529 -428.960534) (xy 127.2413 -428.960534) (xy 127.2413 -426.41901) (xy 127.241815 -426.406925)
			(xy 127.249264 -426.383931) (xy 127.26344 -426.364355) (xy 127.282961 -426.350103) (xy 127.305925 -426.342563)
			(xy 127.318008 -426.342048) (xy 128.257808 -426.342048) (xy 128.269912 -426.342509) (xy 128.292931 -426.350004)
			(xy 128.312499 -426.364256) (xy 128.326696 -426.383865) (xy 128.334125 -426.406905) (xy 128.334516 -426.41901)
			(xy 128.334516 -427.960536) (xy 129.241296 -427.960536) (xy 129.241296 -425.419012) (xy 129.241723 -425.40693)
			(xy 129.249188 -425.383947) (xy 129.26339 -425.364396) (xy 129.282939 -425.350191) (xy 129.305922 -425.342724)
			(xy 129.318004 -425.342304) (xy 130.257804 -425.342304) (xy 130.269888 -425.342709) (xy 130.292873 -425.350179)
			(xy 130.312424 -425.364387) (xy 130.326628 -425.383941) (xy 130.334093 -425.406928) (xy 130.334512 -425.419012)
			(xy 130.334512 -427.960536) (xy 130.334067 -427.972612) (xy 130.326595 -427.99558) (xy 130.312393 -428.015116)
			(xy 130.292851 -428.029309) (xy 130.26988 -428.036772) (xy 130.257804 -428.037244) (xy 129.318004 -428.037244)
			(xy 129.305933 -428.036733) (xy 129.282972 -428.029276) (xy 129.263438 -428.01509) (xy 129.249242 -427.995564)
			(xy 129.241773 -427.972607) (xy 129.241296 -427.960536) (xy 128.334516 -427.960536) (xy 128.334516 -428.960534)
			(xy 128.334121 -428.97263) (xy 128.326649 -428.995639) (xy 128.312446 -429.015222) (xy 128.292895 -429.02947)
			(xy 128.269903 -429.036993) (xy 128.257808 -429.037496) (xy 127.318008 -429.037496) (xy 127.305899 -429.037077)
			(xy 127.282871 -429.029579) (xy 127.263298 -429.015319) (xy 127.249103 -428.995697) (xy 127.241683 -428.972644)
			(xy 127.2413 -428.960534) (xy 126.307529 -428.960534) (xy 126.312519 -428.96417) (xy 126.326714 -428.983792)
			(xy 126.334136 -429.006844) (xy 126.33452 -429.018954) (xy 126.33452 -431.560478) (xy 126.334073 -431.57257)
			(xy 126.326618 -431.595577) (xy 126.312427 -431.615161) (xy 126.292887 -431.629411) (xy 126.269903 -431.636936)
			(xy 126.257812 -431.63744) (xy 125.318012 -431.63744) (xy 125.305908 -431.636974) (xy 125.282888 -431.629483)
			(xy 125.263318 -431.615232) (xy 125.249122 -431.595624) (xy 125.241693 -431.572583) (xy 125.241304 -431.560478)
			(xy 115.639268 -431.560478) (xy 115.63661 -431.616688) (xy 115.620446 -431.787128) (xy 115.596243 -431.956613)
			(xy 115.564055 -432.124765) (xy 115.523953 -432.291207) (xy 115.476027 -432.455567) (xy 115.420385 -432.617477)
			(xy 115.35715 -432.776576) (xy 115.286464 -432.932508) (xy 115.208486 -433.084923) (xy 115.12339 -433.233482)
			(xy 115.031365 -433.377851) (xy 114.932619 -433.517709) (xy 114.82737 -433.652742) (xy 114.715856 -433.782648)
			(xy 114.598325 -433.907137) (xy 114.47504 -434.02593) (xy 114.346277 -434.138763) (xy 114.212324 -434.245381)
			(xy 114.07348 -434.345548) (xy 113.930056 -434.439039) (xy 113.782372 -434.525645) (xy 113.630759 -434.605172)
			(xy 113.475556 -434.677443) (xy 113.396522 -434.710332) (xy 113.388621 -434.713964) (xy 113.375731 -434.725623)
			(xy 113.367472 -434.740915) (xy 113.365788 -434.749448) (xy 113.35004 -434.849016) (xy 113.359438 -434.873654)
			(xy 113.369852 -434.88229) (xy 113.419298 -434.924299) (xy 113.513487 -435.013553) (xy 113.601975 -435.108462)
			(xy 113.644727 -435.16042) (xy 125.241304 -435.16042) (xy 125.241304 -432.618896) (xy 125.241709 -432.606812)
			(xy 125.249179 -432.583827) (xy 125.263387 -432.564276) (xy 125.282941 -432.550072) (xy 125.305928 -432.542607)
			(xy 125.318012 -432.542188) (xy 126.257812 -432.542188) (xy 126.269887 -432.542654) (xy 126.292854 -432.550119)
			(xy 126.307106 -432.560476) (xy 127.2413 -432.560476) (xy 127.2413 -430.018952) (xy 127.241723 -430.006874)
			(xy 127.2492 -429.983904) (xy 127.263407 -429.964367) (xy 127.282954 -429.950174) (xy 127.30593 -429.942714)
			(xy 127.318008 -429.942244) (xy 128.257808 -429.942244) (xy 128.269878 -429.942757) (xy 128.292837 -429.950216)
			(xy 128.31237 -429.964401) (xy 128.326566 -429.983927) (xy 128.334037 -430.006882) (xy 128.334516 -430.018952)
			(xy 128.334516 -431.560478) (xy 129.241296 -431.560478) (xy 129.241296 -429.018954) (xy 129.241767 -429.006866)
			(xy 129.249231 -428.983872) (xy 129.263418 -428.964296) (xy 129.282948 -428.950046) (xy 129.305918 -428.942507)
			(xy 129.318004 -428.941992) (xy 130.257804 -428.941992) (xy 130.269912 -428.942413) (xy 130.292938 -428.949912)
			(xy 130.307517 -428.960534) (xy 131.241292 -428.960534) (xy 131.241292 -426.41901) (xy 131.241815 -426.406926)
			(xy 131.249263 -426.383934) (xy 131.263437 -426.364358) (xy 131.282956 -426.350105) (xy 131.305918 -426.342564)
			(xy 131.318 -426.342048) (xy 132.2578 -426.342048) (xy 132.269904 -426.342515) (xy 132.292922 -426.350009)
			(xy 132.312491 -426.364259) (xy 132.326687 -426.383866) (xy 132.334117 -426.406905) (xy 132.334508 -426.41901)
			(xy 132.334508 -427.960536) (xy 133.241288 -427.960536) (xy 133.241288 -425.419012) (xy 133.241723 -425.40693)
			(xy 133.249187 -425.383949) (xy 133.263387 -425.364399) (xy 133.282934 -425.350194) (xy 133.305914 -425.342726)
			(xy 133.317996 -425.342304) (xy 134.257796 -425.342304) (xy 134.26988 -425.342716) (xy 134.292864 -425.350184)
			(xy 134.312416 -425.36439) (xy 134.32662 -425.383943) (xy 134.334085 -425.406928) (xy 134.334504 -425.419012)
			(xy 134.334504 -427.960536) (xy 134.334067 -427.972613) (xy 134.326594 -427.995582) (xy 134.31239 -428.015119)
			(xy 134.292846 -428.029312) (xy 134.269873 -428.036773) (xy 134.257796 -428.037244) (xy 133.317996 -428.037244)
			(xy 133.305925 -428.03674) (xy 133.282964 -428.02928) (xy 133.26343 -428.015093) (xy 133.249234 -427.995565)
			(xy 133.241765 -427.972607) (xy 133.241288 -427.960536) (xy 132.334508 -427.960536) (xy 132.334508 -428.960534)
			(xy 132.334023 -428.972621) (xy 132.326562 -428.995614) (xy 132.312379 -429.01519) (xy 132.292853 -429.029441)
			(xy 132.269885 -429.03698) (xy 132.2578 -429.037496) (xy 131.318 -429.037496) (xy 131.305891 -429.037084)
			(xy 131.282863 -429.029584) (xy 131.263289 -429.015321) (xy 131.249095 -428.995699) (xy 131.241675 -428.972645)
			(xy 131.241292 -428.960534) (xy 130.307517 -428.960534) (xy 130.312511 -428.964173) (xy 130.326706 -428.983793)
			(xy 130.334128 -429.006844) (xy 130.334512 -429.018954) (xy 130.334512 -431.560478) (xy 130.334073 -431.572571)
			(xy 130.326616 -431.595579) (xy 130.312424 -431.615164) (xy 130.292882 -431.629413) (xy 130.269896 -431.636937)
			(xy 130.257804 -431.63744) (xy 129.318004 -431.63744) (xy 129.305899 -431.636981) (xy 129.282879 -431.629488)
			(xy 129.263309 -431.615236) (xy 129.249113 -431.595625) (xy 129.241685 -431.572584) (xy 129.241296 -431.560478)
			(xy 128.334516 -431.560478) (xy 128.334516 -432.560476) (xy 128.334067 -432.572557) (xy 128.326607 -432.595537)
			(xy 128.31241 -432.615087) (xy 128.292866 -432.629292) (xy 128.269888 -432.636762) (xy 128.257808 -432.637184)
			(xy 127.318008 -432.637184) (xy 127.305923 -432.63678) (xy 127.282937 -432.629312) (xy 127.263384 -432.615105)
			(xy 127.249181 -432.595549) (xy 127.241717 -432.572561) (xy 127.2413 -432.560476) (xy 126.307106 -432.560476)
			(xy 126.31239 -432.564316) (xy 126.326584 -432.583854) (xy 126.334047 -432.606821) (xy 126.33452 -432.618896)
			(xy 126.33452 -435.16042) (xy 126.334053 -435.172494) (xy 126.326586 -435.19546) (xy 126.31239 -435.214996)
			(xy 126.292853 -435.22919) (xy 126.269886 -435.236654) (xy 126.257812 -435.237128) (xy 125.318012 -435.237128)
			(xy 125.30594 -435.236626) (xy 125.282977 -435.229169) (xy 125.263441 -435.214982) (xy 125.249246 -435.195452)
			(xy 125.241779 -435.172492) (xy 125.241304 -435.16042) (xy 113.644727 -435.16042) (xy 113.684422 -435.208663)
			(xy 113.760513 -435.313772) (xy 113.829956 -435.423387) (xy 113.892486 -435.537087) (xy 113.947862 -435.654438)
			(xy 113.995874 -435.77499) (xy 114.036336 -435.89828) (xy 114.069094 -436.023838) (xy 114.094022 -436.151181)
			(xy 114.111025 -436.279823) (xy 114.120038 -436.40927) (xy 114.121027 -436.539027) (xy 114.113986 -436.668596)
			(xy 114.098945 -436.797482) (xy 114.075959 -436.92519) (xy 114.045118 -437.051232) (xy 114.006538 -437.175125)
			(xy 113.960369 -437.296394) (xy 113.906786 -437.414574) (xy 113.845996 -437.529214) (xy 113.77823 -437.639874)
			(xy 113.703749 -437.74613) (xy 113.622838 -437.847575) (xy 113.535806 -437.943821) (xy 113.442988 -438.034499)
			(xy 113.344738 -438.119261) (xy 113.241432 -438.197784) (xy 113.133467 -438.269766) (xy 113.021257 -438.334931)
			(xy 112.90523 -438.39303) (xy 112.785831 -438.443841) (xy 112.663518 -438.487169) (xy 112.538759 -438.522847)
			(xy 112.412032 -438.550739) (xy 112.283822 -438.570739) (xy 112.15462 -438.58277) (xy 112.024922 -438.586785)
			(xy 111.895224 -438.58277) (xy 111.766022 -438.570739) (xy 111.637812 -438.550739) (xy 111.511085 -438.522847)
			(xy 111.386326 -438.487169) (xy 111.264013 -438.443841) (xy 111.144614 -438.39303) (xy 111.028587 -438.334931)
			(xy 110.916377 -438.269766) (xy 110.808412 -438.197784) (xy 110.705106 -438.119261) (xy 110.606856 -438.034499)
			(xy 110.514038 -437.943821) (xy 110.427006 -437.847575) (xy 110.346095 -437.74613) (xy 110.271614 -437.639874)
			(xy 110.203848 -437.529214) (xy 110.143058 -437.414574) (xy 110.089475 -437.296394) (xy 110.043306 -437.175125)
			(xy 110.004726 -437.051232) (xy 109.973885 -436.92519) (xy 109.950899 -436.797482) (xy 109.935858 -436.668596)
			(xy 109.928817 -436.539027) (xy 109.929806 -436.40927) (xy 109.938819 -436.279823) (xy 109.955822 -436.151181)
			(xy 109.98075 -436.023838) (xy 110.013508 -435.89828) (xy 110.05397 -435.77499) (xy 110.101982 -435.654438)
			(xy 110.157358 -435.537087) (xy 110.219888 -435.423387) (xy 110.289331 -435.313772) (xy 110.365422 -435.208663)
			(xy 110.447869 -435.108462) (xy 110.536357 -435.013553) (xy 110.630546 -434.924299) (xy 110.679992 -434.88229)
			(xy 110.690406 -434.873654) (xy 110.699804 -434.849016) (xy 110.682024 -434.73624) (xy 110.665768 -434.715412)
			(xy 110.653322 -434.710332) (xy 110.574304 -434.677407) (xy 110.419107 -434.605131) (xy 110.267499 -434.5256)
			(xy 110.119821 -434.438991) (xy 109.976402 -434.345497) (xy 109.837562 -434.245328) (xy 109.703613 -434.138709)
			(xy 109.574854 -434.025876) (xy 109.451573 -433.907083) (xy 109.334045 -433.782595) (xy 109.222533 -433.65269)
			(xy 109.117287 -433.517659) (xy 109.018541 -433.377804) (xy 108.926517 -433.233438) (xy 108.84142 -433.084883)
			(xy 108.763441 -432.932471) (xy 108.692754 -432.776543) (xy 108.629516 -432.617449) (xy 108.57387 -432.455542)
			(xy 108.52594 -432.291187) (xy 108.485833 -432.124749) (xy 108.453638 -431.956601) (xy 108.429428 -431.78712)
			(xy 108.413257 -431.616683) (xy 108.405161 -431.445673) (xy 108.40466 -431.360072) (xy 90.234516 -431.360072)
			(xy 90.234516 -432.560476) (xy 90.234067 -432.572557) (xy 90.226607 -432.595537) (xy 90.21241 -432.615087)
			(xy 90.192866 -432.629292) (xy 90.169888 -432.636762) (xy 90.157808 -432.637184) (xy 89.218008 -432.637184)
			(xy 89.205923 -432.63678) (xy 89.182937 -432.629312) (xy 89.163384 -432.615105) (xy 89.149181 -432.595549)
			(xy 89.141717 -432.572561) (xy 89.1413 -432.560476) (xy 88.207106 -432.560476) (xy 88.21239 -432.564316)
			(xy 88.226584 -432.583854) (xy 88.234047 -432.606821) (xy 88.23452 -432.618896) (xy 88.23452 -435.16042)
			(xy 88.234053 -435.172494) (xy 88.226586 -435.19546) (xy 88.21239 -435.214996) (xy 88.192853 -435.22919)
			(xy 88.169886 -435.236654) (xy 88.157812 -435.237128) (xy 87.218012 -435.237128) (xy 87.20594 -435.236626)
			(xy 87.182977 -435.229169) (xy 87.163441 -435.214982) (xy 87.149246 -435.195452) (xy 87.141779 -435.172492)
			(xy 87.141304 -435.16042) (xy 86.234524 -435.16042) (xy 86.234524 -436.160418) (xy 86.234107 -436.172512)
			(xy 86.226641 -436.195519) (xy 86.212443 -436.215102) (xy 86.192897 -436.229351) (xy 86.169909 -436.236876)
			(xy 86.157816 -436.23738) (xy 85.218016 -436.23738) (xy 85.205906 -436.23697) (xy 85.182876 -436.229472)
			(xy 85.163301 -436.21521) (xy 85.149106 -436.195585) (xy 85.141689 -436.172529) (xy 85.141308 -436.160418)
			(xy 84.206765 -436.160418) (xy 84.212397 -436.164511) (xy 84.226591 -436.18405) (xy 84.234055 -436.207017)
			(xy 84.234528 -436.219092) (xy 84.234528 -438.760616) (xy 84.23405 -438.772689) (xy 84.226585 -438.795654)
			(xy 84.212391 -438.815189) (xy 84.192857 -438.829383) (xy 84.169893 -438.836849) (xy 84.15782 -438.837324)
			(xy 83.21802 -438.837324) (xy 83.20594 -438.83687) (xy 83.182961 -438.82941) (xy 83.163411 -438.815214)
			(xy 83.149206 -438.795672) (xy 83.141735 -438.772696) (xy 83.141312 -438.760616) (xy 82.234532 -438.760616)
			(xy 82.234532 -439.760614) (xy 85.141308 -439.760614) (xy 85.141308 -437.21909) (xy 85.141798 -437.207003)
			(xy 85.149254 -437.184008) (xy 85.163436 -437.164431) (xy 85.182962 -437.150179) (xy 85.205931 -437.142642)
			(xy 85.218016 -437.142128) (xy 86.157816 -437.142128) (xy 86.169929 -437.142503) (xy 86.192961 -437.15001)
			(xy 86.212536 -437.164281) (xy 86.226729 -437.183914) (xy 86.234145 -437.206976) (xy 86.234524 -437.21909)
			(xy 86.234524 -438.760616) (xy 87.141304 -438.760616) (xy 87.141304 -436.219092) (xy 87.141706 -436.207008)
			(xy 87.149177 -436.184023) (xy 87.163386 -436.164471) (xy 87.182941 -436.150268) (xy 87.205928 -436.142803)
			(xy 87.218012 -436.142384) (xy 88.157812 -436.142384) (xy 88.169886 -436.142854) (xy 88.192853 -436.150319)
			(xy 88.206752 -436.160418) (xy 89.1413 -436.160418) (xy 89.1413 -433.618894) (xy 89.141802 -433.606808)
			(xy 89.149255 -433.583814) (xy 89.163434 -433.564238) (xy 89.182958 -433.549986) (xy 89.205924 -433.542447)
			(xy 89.218008 -433.541932) (xy 90.157808 -433.541932) (xy 90.169921 -433.54231) (xy 90.192954 -433.549815)
			(xy 90.212529 -433.564086) (xy 90.226723 -433.583717) (xy 90.234137 -433.60678) (xy 90.234516 -433.618894)
			(xy 90.234516 -436.160418) (xy 90.234107 -436.172513) (xy 90.22664 -436.195522) (xy 90.21244 -436.215105)
			(xy 90.192892 -436.229353) (xy 90.169902 -436.236877) (xy 90.157808 -436.23738) (xy 89.218008 -436.23738)
			(xy 89.205898 -436.236977) (xy 89.182867 -436.229477) (xy 89.163292 -436.215213) (xy 89.149098 -436.195587)
			(xy 89.14168 -436.17253) (xy 89.1413 -436.160418) (xy 88.206752 -436.160418) (xy 88.212389 -436.164514)
			(xy 88.226583 -436.184051) (xy 88.234047 -436.207018) (xy 88.23452 -436.219092) (xy 88.23452 -438.760616)
			(xy 88.234049 -438.77269) (xy 88.226584 -438.795656) (xy 88.212389 -438.815191) (xy 88.192852 -438.829386)
			(xy 88.169886 -438.83685) (xy 88.157812 -438.837324) (xy 87.218012 -438.837324) (xy 87.20594 -438.836826)
			(xy 87.182976 -438.829369) (xy 87.16344 -438.81518) (xy 87.149244 -438.79565) (xy 87.141779 -438.772688)
			(xy 87.141304 -438.760616) (xy 86.234524 -438.760616) (xy 86.234524 -439.760614) (xy 89.1413 -439.760614)
			(xy 89.1413 -437.21909) (xy 89.141798 -437.207004) (xy 89.149253 -437.18401) (xy 89.163433 -437.164434)
			(xy 89.182957 -437.150182) (xy 89.205924 -437.142643) (xy 89.218008 -437.142128) (xy 90.157808 -437.142128)
			(xy 90.16992 -437.14251) (xy 90.192952 -437.150015) (xy 90.212528 -437.164284) (xy 90.226721 -437.183915)
			(xy 90.234137 -437.206976) (xy 90.234516 -437.21909) (xy 90.234516 -438.760362) (xy 125.241304 -438.760362)
			(xy 125.241304 -436.218838) (xy 125.241839 -436.206754) (xy 125.249281 -436.183761) (xy 125.263451 -436.164183)
			(xy 125.282968 -436.14993) (xy 125.30593 -436.142391) (xy 125.318012 -436.141876) (xy 126.257812 -436.141876)
			(xy 126.269919 -436.142306) (xy 126.292943 -436.149805) (xy 126.30751 -436.160418) (xy 127.2413 -436.160418)
			(xy 127.2413 -433.618894) (xy 127.241802 -433.606808) (xy 127.249255 -433.583814) (xy 127.263434 -433.564238)
			(xy 127.282958 -433.549986) (xy 127.305924 -433.542447) (xy 127.318008 -433.541932) (xy 128.257808 -433.541932)
			(xy 128.269921 -433.54231) (xy 128.292954 -433.549815) (xy 128.312529 -433.564086) (xy 128.326723 -433.583717)
			(xy 128.334137 -433.60678) (xy 128.334516 -433.618894) (xy 128.334516 -435.16042) (xy 129.241296 -435.16042)
			(xy 129.241296 -432.618896) (xy 129.241761 -432.606821) (xy 129.249225 -432.583853) (xy 129.263421 -432.564316)
			(xy 129.28296 -432.550121) (xy 129.305929 -432.54266) (xy 129.318004 -432.542188) (xy 130.257804 -432.542188)
			(xy 130.269878 -432.542661) (xy 130.292845 -432.550124) (xy 130.307094 -432.560476) (xy 131.241292 -432.560476)
			(xy 131.241292 -430.018952) (xy 131.241723 -430.006875) (xy 131.249199 -429.983906) (xy 131.263404 -429.96437)
			(xy 131.282949 -429.950177) (xy 131.305923 -429.942716) (xy 131.318 -429.942244) (xy 132.2578 -429.942244)
			(xy 132.26987 -429.942764) (xy 132.292829 -429.95022) (xy 132.312362 -429.964404) (xy 132.326558 -429.983928)
			(xy 132.334029 -430.006883) (xy 132.334508 -430.018952) (xy 132.334508 -431.560478) (xy 133.241288 -431.560478)
			(xy 133.241288 -429.018954) (xy 133.241669 -429.006857) (xy 133.249144 -428.983847) (xy 133.263351 -428.964264)
			(xy 133.282905 -428.950016) (xy 133.3059 -428.942494) (xy 133.317996 -428.941992) (xy 134.257796 -428.941992)
			(xy 134.269904 -428.942419) (xy 134.29293 -428.949917) (xy 134.307503 -428.960534) (xy 135.241284 -428.960534)
			(xy 135.241284 -426.41901) (xy 135.241717 -426.406917) (xy 135.249176 -426.383909) (xy 135.26337 -426.364325)
			(xy 135.282914 -426.350076) (xy 135.3059 -426.342551) (xy 135.317992 -426.342048) (xy 136.257792 -426.342048)
			(xy 136.269895 -426.342522) (xy 136.292914 -426.350013) (xy 136.312482 -426.364262) (xy 136.326679 -426.383868)
			(xy 136.334109 -426.406906) (xy 136.3345 -426.41901) (xy 136.3345 -427.960536) (xy 137.24128 -427.960536)
			(xy 137.24128 -425.419012) (xy 137.241774 -425.406939) (xy 137.249232 -425.383974) (xy 137.263421 -425.364438)
			(xy 137.282953 -425.350243) (xy 137.305915 -425.342778) (xy 137.317988 -425.342304) (xy 138.257788 -425.342304)
			(xy 138.269871 -425.342723) (xy 138.292856 -425.350189) (xy 138.312407 -425.364393) (xy 138.326611 -425.383944)
			(xy 138.334077 -425.406929) (xy 138.334496 -425.419012) (xy 138.334496 -427.960536) (xy 138.334066 -427.972614)
			(xy 138.326593 -427.995584) (xy 138.312387 -428.015122) (xy 138.292841 -428.029315) (xy 138.269866 -428.036774)
			(xy 138.257788 -428.037244) (xy 137.317988 -428.037244) (xy 137.305916 -428.036746) (xy 137.282955 -428.029285)
			(xy 137.263421 -428.015096) (xy 137.249226 -427.995567) (xy 137.241757 -427.972607) (xy 137.24128 -427.960536)
			(xy 136.3345 -427.960536) (xy 136.3345 -428.960534) (xy 136.334022 -428.972621) (xy 136.326561 -428.995616)
			(xy 136.312376 -429.015192) (xy 136.292848 -429.029443) (xy 136.269878 -429.036981) (xy 136.257792 -429.037496)
			(xy 135.317992 -429.037496) (xy 135.305882 -429.037091) (xy 135.282854 -429.029588) (xy 135.263281 -429.015324)
			(xy 135.249086 -428.9957) (xy 135.241667 -428.972645) (xy 135.241284 -428.960534) (xy 134.307503 -428.960534)
			(xy 134.312502 -428.964176) (xy 134.326697 -428.983795) (xy 134.33412 -429.006845) (xy 134.334504 -429.018954)
			(xy 134.334504 -431.560478) (xy 134.333975 -431.572562) (xy 134.326529 -431.595555) (xy 134.312357 -431.615131)
			(xy 134.29284 -431.629384) (xy 134.269878 -431.636924) (xy 134.257796 -431.63744) (xy 133.317996 -431.63744)
			(xy 133.305891 -431.636988) (xy 133.28287 -431.629492) (xy 133.263301 -431.615238) (xy 133.249105 -431.595627)
			(xy 133.241677 -431.572584) (xy 133.241288 -431.560478) (xy 132.334508 -431.560478) (xy 132.334508 -432.560476)
			(xy 132.334067 -432.572557) (xy 132.326606 -432.595539) (xy 132.312407 -432.61509) (xy 132.292861 -432.629295)
			(xy 132.269881 -432.636763) (xy 132.2578 -432.637184) (xy 131.318 -432.637184) (xy 131.305915 -432.636787)
			(xy 131.282928 -432.629317) (xy 131.263376 -432.615107) (xy 131.249172 -432.59555) (xy 131.241709 -432.572561)
			(xy 131.241292 -432.560476) (xy 130.307094 -432.560476) (xy 130.312382 -432.564318) (xy 130.326576 -432.583855)
			(xy 130.334039 -432.606822) (xy 130.334512 -432.618896) (xy 130.334512 -435.16042) (xy 130.334053 -435.172495)
			(xy 130.326585 -435.195462) (xy 130.312387 -435.214999) (xy 130.292848 -435.229193) (xy 130.269879 -435.236655)
			(xy 130.257804 -435.237128) (xy 129.318004 -435.237128) (xy 129.305932 -435.236633) (xy 129.282968 -435.229174)
			(xy 129.263433 -435.214984) (xy 129.249237 -435.195454) (xy 129.241771 -435.172492) (xy 129.241296 -435.16042)
			(xy 128.334516 -435.16042) (xy 128.334516 -436.160418) (xy 128.334107 -436.172513) (xy 128.32664 -436.195522)
			(xy 128.31244 -436.215105) (xy 128.292892 -436.229353) (xy 128.269902 -436.236877) (xy 128.257808 -436.23738)
			(xy 127.318008 -436.23738) (xy 127.305898 -436.236977) (xy 127.282867 -436.229477) (xy 127.263292 -436.215213)
			(xy 127.249098 -436.195587) (xy 127.24168 -436.17253) (xy 127.2413 -436.160418) (xy 126.30751 -436.160418)
			(xy 126.312514 -436.164064) (xy 126.326709 -436.183682) (xy 126.334133 -436.20673) (xy 126.33452 -436.218838)
			(xy 126.33452 -438.760362) (xy 126.33406 -438.772454) (xy 126.326608 -438.79546) (xy 126.312422 -438.815044)
			(xy 126.292884 -438.829294) (xy 126.269902 -438.83682) (xy 126.257812 -438.837324) (xy 125.318012 -438.837324)
			(xy 125.305906 -438.836874) (xy 125.282883 -438.82938) (xy 125.263312 -438.815127) (xy 125.249116 -438.795514)
			(xy 125.241691 -438.772469) (xy 125.241304 -438.760362) (xy 90.234516 -438.760362) (xy 90.234516 -439.76036)
			(xy 127.2413 -439.76036) (xy 127.2413 -437.218836) (xy 127.241744 -437.206754) (xy 127.249202 -437.183771)
			(xy 127.2634 -437.16422) (xy 127.282946 -437.150015) (xy 127.305927 -437.142548) (xy 127.318008 -437.142128)
			(xy 128.257808 -437.142128) (xy 128.269895 -437.142506) (xy 128.292884 -437.14998) (xy 128.312437 -437.164194)
			(xy 128.32664 -437.183756) (xy 128.334101 -437.206749) (xy 128.334516 -437.218836) (xy 128.334516 -438.760362)
			(xy 129.241296 -438.760362) (xy 129.241296 -436.218838) (xy 129.241839 -436.206755) (xy 129.24928 -436.183763)
			(xy 129.263448 -436.164186) (xy 129.282963 -436.149933) (xy 129.305923 -436.142392) (xy 129.318004 -436.141876)
			(xy 130.257804 -436.141876) (xy 130.269911 -436.142312) (xy 130.292934 -436.14981) (xy 130.307496 -436.160418)
			(xy 131.241292 -436.160418) (xy 131.241292 -433.618894) (xy 131.241802 -433.606809) (xy 131.249254 -433.583816)
			(xy 131.263431 -433.564241) (xy 131.282953 -433.549989) (xy 131.305917 -433.542448) (xy 131.318 -433.541932)
			(xy 132.2578 -433.541932) (xy 132.269912 -433.542317) (xy 132.292945 -433.54982) (xy 132.312521 -433.564088)
			(xy 132.326714 -433.583719) (xy 132.334129 -433.60678) (xy 132.334508 -433.618894) (xy 132.334508 -435.16042)
			(xy 133.241288 -435.16042) (xy 133.241288 -432.618896) (xy 133.241761 -432.606822) (xy 133.249224 -432.583855)
			(xy 133.263418 -432.564318) (xy 133.282955 -432.550124) (xy 133.305922 -432.542661) (xy 133.317996 -432.542188)
			(xy 134.257796 -432.542188) (xy 134.26987 -432.542668) (xy 134.292836 -432.550129) (xy 134.30708 -432.560476)
			(xy 135.241284 -432.560476) (xy 135.241284 -430.018952) (xy 135.241723 -430.006876) (xy 135.249198 -429.983908)
			(xy 135.263401 -429.964373) (xy 135.282944 -429.95018) (xy 135.305915 -429.942717) (xy 135.317992 -429.942244)
			(xy 136.257792 -429.942244) (xy 136.269861 -429.94277) (xy 136.29282 -429.950225) (xy 136.312353 -429.964407)
			(xy 136.32655 -429.98393) (xy 136.334021 -430.006883) (xy 136.3345 -430.018952) (xy 136.3345 -431.560478)
			(xy 137.24128 -431.560478) (xy 137.24128 -429.018954) (xy 137.241669 -429.006858) (xy 137.249143 -428.983849)
			(xy 137.263348 -428.964267) (xy 137.2829 -428.950019) (xy 137.305893 -428.942495) (xy 137.317988 -428.941992)
			(xy 138.257788 -428.941992) (xy 138.269895 -428.942427) (xy 138.292921 -428.949922) (xy 138.307489 -428.960534)
			(xy 139.241276 -428.960534) (xy 139.241276 -426.41901) (xy 139.241717 -426.406917) (xy 139.249175 -426.383911)
			(xy 139.263367 -426.364328) (xy 139.282909 -426.350078) (xy 139.305893 -426.342553) (xy 139.317984 -426.342048)
			(xy 140.257784 -426.342048) (xy 140.269887 -426.342529) (xy 140.292905 -426.350018) (xy 140.312473 -426.364265)
			(xy 140.32667 -426.383869) (xy 140.334101 -426.406906) (xy 140.334492 -426.41901) (xy 140.334492 -427.960536)
			(xy 142.241016 -427.960536) (xy 142.241016 -425.419012) (xy 142.241427 -425.406902) (xy 142.248925 -425.383873)
			(xy 142.263187 -425.364298) (xy 142.282811 -425.350104) (xy 142.305867 -425.342685) (xy 142.317978 -425.342304)
			(xy 143.257778 -425.342304) (xy 143.269863 -425.342825) (xy 143.292857 -425.350272) (xy 143.312434 -425.364446)
			(xy 143.326686 -425.383966) (xy 143.334225 -425.406929) (xy 143.33474 -425.419012) (xy 143.33474 -427.960536)
			(xy 143.334315 -427.972643) (xy 143.32681 -427.995664) (xy 143.31255 -428.015233) (xy 143.292933 -428.029428)
			(xy 143.269886 -428.036855) (xy 143.257778 -428.037244) (xy 142.317978 -428.037244) (xy 142.305886 -428.036811)
			(xy 142.282882 -428.029347) (xy 142.263301 -428.015152) (xy 142.249051 -427.99561) (xy 142.241523 -427.972627)
			(xy 142.241016 -427.960536) (xy 140.334492 -427.960536) (xy 140.334492 -428.960534) (xy 140.334022 -428.972622)
			(xy 140.32656 -428.995619) (xy 140.312373 -429.015195) (xy 140.292843 -429.029446) (xy 140.269871 -429.036983)
			(xy 140.257784 -429.037496) (xy 139.317984 -429.037496) (xy 139.305874 -429.037097) (xy 139.282845 -429.029593)
			(xy 139.263272 -429.015327) (xy 139.249078 -428.995702) (xy 139.241659 -428.972646) (xy 139.241276 -428.960534)
			(xy 138.307489 -428.960534) (xy 138.312493 -428.964179) (xy 138.326689 -428.983796) (xy 138.334111 -429.006845)
			(xy 138.334496 -429.018954) (xy 138.334496 -431.560478) (xy 138.333975 -431.572563) (xy 138.326528 -431.595557)
			(xy 138.312354 -431.615134) (xy 138.292834 -431.629386) (xy 138.269871 -431.636925) (xy 138.257788 -431.63744)
			(xy 137.317988 -431.63744) (xy 137.305882 -431.636995) (xy 137.282862 -431.629497) (xy 137.263292 -431.615241)
			(xy 137.249096 -431.595628) (xy 137.241669 -431.572585) (xy 137.24128 -431.560478) (xy 136.3345 -431.560478)
			(xy 136.3345 -432.560476) (xy 136.334067 -432.572558) (xy 136.326605 -432.595542) (xy 136.312404 -432.615093)
			(xy 136.292856 -432.629297) (xy 136.269874 -432.636764) (xy 136.257792 -432.637184) (xy 135.317992 -432.637184)
			(xy 135.305906 -432.636794) (xy 135.282919 -432.629321) (xy 135.263367 -432.61511) (xy 135.249164 -432.595552)
			(xy 135.241701 -432.572562) (xy 135.241284 -432.560476) (xy 134.30708 -432.560476) (xy 134.312373 -432.564321)
			(xy 134.326568 -432.583857) (xy 134.334031 -432.606822) (xy 134.334504 -432.618896) (xy 134.334504 -435.16042)
			(xy 134.334053 -435.172496) (xy 134.326584 -435.195464) (xy 134.312384 -435.215001) (xy 134.292843 -435.229195)
			(xy 134.269872 -435.236656) (xy 134.257796 -435.237128) (xy 133.317996 -435.237128) (xy 133.305923 -435.236639)
			(xy 133.282959 -435.229178) (xy 133.263424 -435.214987) (xy 133.249229 -435.195455) (xy 133.241763 -435.172493)
			(xy 133.241288 -435.16042) (xy 132.334508 -435.16042) (xy 132.334508 -436.160418) (xy 132.334009 -436.172504)
			(xy 132.326553 -436.195497) (xy 132.312373 -436.215072) (xy 132.29285 -436.229324) (xy 132.269884 -436.236864)
			(xy 132.2578 -436.23738) (xy 131.318 -436.23738) (xy 131.305889 -436.236984) (xy 131.282858 -436.229482)
			(xy 131.263283 -436.215216) (xy 131.24909 -436.195589) (xy 131.241672 -436.17253) (xy 131.241292 -436.160418)
			(xy 130.307496 -436.160418) (xy 130.312505 -436.164067) (xy 130.3267 -436.183683) (xy 130.334125 -436.20673)
			(xy 130.334512 -436.218838) (xy 130.334512 -438.760362) (xy 130.334059 -438.772454) (xy 130.326607 -438.795462)
			(xy 130.312419 -438.815047) (xy 130.292879 -438.829297) (xy 130.269895 -438.836821) (xy 130.257804 -438.837324)
			(xy 129.318004 -438.837324) (xy 129.305898 -438.836881) (xy 129.282875 -438.829385) (xy 129.263303 -438.81513)
			(xy 129.249108 -438.795515) (xy 129.241683 -438.77247) (xy 129.241296 -438.760362) (xy 128.334516 -438.760362)
			(xy 128.334516 -439.76036) (xy 131.241292 -439.76036) (xy 131.241292 -437.218836) (xy 131.241743 -437.206755)
			(xy 131.249201 -437.183774) (xy 131.263397 -437.164223) (xy 131.282941 -437.150017) (xy 131.305919 -437.142549)
			(xy 131.318 -437.142128) (xy 132.2578 -437.142128) (xy 132.269886 -437.142513) (xy 132.292875 -437.149985)
			(xy 132.312429 -437.164197) (xy 132.326632 -437.183757) (xy 132.334093 -437.206749) (xy 132.334508 -437.218836)
			(xy 132.334508 -438.760362) (xy 133.241288 -438.760362) (xy 133.241288 -436.218838) (xy 133.241741 -436.206746)
			(xy 133.249193 -436.183738) (xy 133.263381 -436.164153) (xy 133.282921 -436.149903) (xy 133.305905 -436.142379)
			(xy 133.317996 -436.141876) (xy 134.257796 -436.141876) (xy 134.269902 -436.142319) (xy 134.292925 -436.149815)
			(xy 134.307483 -436.160418) (xy 135.241284 -436.160418) (xy 135.241284 -433.618894) (xy 135.241703 -433.6068)
			(xy 135.249167 -433.583792) (xy 135.263364 -433.564208) (xy 135.282911 -433.549959) (xy 135.305899 -433.542435)
			(xy 135.317992 -433.541932) (xy 136.257792 -433.541932) (xy 136.269904 -433.542323) (xy 136.292936 -433.549824)
			(xy 136.312512 -433.564091) (xy 136.326706 -433.58372) (xy 136.334121 -433.606781) (xy 136.3345 -433.618894)
			(xy 136.3345 -435.16042) (xy 137.24128 -435.16042) (xy 137.24128 -432.618896) (xy 137.241761 -432.606822)
			(xy 137.249223 -432.583857) (xy 137.263416 -432.564321) (xy 137.28295 -432.550126) (xy 137.305914 -432.542662)
			(xy 137.317988 -432.542188) (xy 138.257788 -432.542188) (xy 138.26987 -432.542623) (xy 138.292851 -432.550087)
			(xy 138.307154 -432.560476) (xy 139.241276 -432.560476) (xy 139.241276 -430.018952) (xy 139.241723 -430.006877)
			(xy 139.249197 -429.98391) (xy 139.263398 -429.964376) (xy 139.282939 -429.950182) (xy 139.305908 -429.942718)
			(xy 139.317984 -429.942244) (xy 140.257784 -429.942244) (xy 140.269853 -429.942777) (xy 140.292812 -429.950229)
			(xy 140.312345 -429.96441) (xy 140.326541 -429.983931) (xy 140.334013 -430.006883) (xy 140.334492 -430.018952)
			(xy 140.334492 -431.560478) (xy 142.241016 -431.560478) (xy 142.241016 -429.018954) (xy 142.241472 -429.006839)
			(xy 142.248969 -428.983798) (xy 142.263216 -428.964199) (xy 142.28282 -428.949958) (xy 142.305863 -428.942468)
			(xy 142.317978 -428.941992) (xy 143.257778 -428.941992) (xy 143.269887 -428.94253) (xy 143.292922 -428.950005)
			(xy 143.307426 -428.960534) (xy 144.241012 -428.960534) (xy 144.241012 -426.41901) (xy 144.24152 -426.406899)
			(xy 144.249001 -426.38386) (xy 144.263235 -426.36426) (xy 144.282828 -426.350018) (xy 144.305863 -426.342526)
			(xy 144.317974 -426.342048) (xy 145.257774 -426.342048) (xy 145.269896 -426.342482) (xy 145.292956 -426.349969)
			(xy 145.312572 -426.364216) (xy 145.326824 -426.38383) (xy 145.334315 -426.406888) (xy 145.334736 -426.41901)
			(xy 145.334736 -427.960536) (xy 146.241008 -427.960536) (xy 146.241008 -425.419012) (xy 146.241427 -425.406903)
			(xy 146.248924 -425.383875) (xy 146.263185 -425.364301) (xy 146.282806 -425.350106) (xy 146.30586 -425.342687)
			(xy 146.31797 -425.342304) (xy 147.25777 -425.342304) (xy 147.269854 -425.342832) (xy 147.292848 -425.350276)
			(xy 147.312425 -425.364448) (xy 147.326678 -425.383967) (xy 147.334217 -425.40693) (xy 147.334732 -425.419012)
			(xy 147.334732 -427.960536) (xy 147.334315 -427.972644) (xy 147.326809 -427.995667) (xy 147.312547 -428.015236)
			(xy 147.292928 -428.029431) (xy 147.269879 -428.036856) (xy 147.25777 -428.037244) (xy 146.31797 -428.037244)
			(xy 146.305877 -428.036818) (xy 146.282873 -428.029351) (xy 146.263292 -428.015154) (xy 146.249043 -427.995612)
			(xy 146.241515 -427.972627) (xy 146.241008 -427.960536) (xy 145.334736 -427.960536) (xy 145.334736 -428.960534)
			(xy 145.334317 -428.972653) (xy 145.326817 -428.995702) (xy 145.312562 -429.015305) (xy 145.292948 -429.029545)
			(xy 145.269893 -429.037026) (xy 145.257774 -429.037496) (xy 144.317974 -429.037496) (xy 144.305861 -429.037011)
			(xy 144.282823 -429.029521) (xy 144.263225 -429.015281) (xy 144.248983 -428.995684) (xy 144.24149 -428.972646)
			(xy 144.241012 -428.960534) (xy 143.307426 -428.960534) (xy 143.31252 -428.964232) (xy 143.326764 -428.983817)
			(xy 143.334259 -429.006846) (xy 143.33474 -429.018954) (xy 143.33474 -431.560478) (xy 143.334321 -431.572602)
			(xy 143.326832 -431.595664) (xy 143.312581 -431.615281) (xy 143.292964 -431.629532) (xy 143.269902 -431.637021)
			(xy 143.257778 -431.63744) (xy 142.317978 -431.63744) (xy 142.30586 -431.637007) (xy 142.282812 -431.629511)
			(xy 142.263209 -431.61526) (xy 142.248969 -431.595648) (xy 142.241486 -431.572596) (xy 142.241016 -431.560478)
			(xy 140.334492 -431.560478) (xy 140.334492 -432.560476) (xy 140.334067 -432.572559) (xy 140.326604 -432.595544)
			(xy 140.312401 -432.615096) (xy 140.292851 -432.6293) (xy 140.269867 -432.636765) (xy 140.257784 -432.637184)
			(xy 139.317984 -432.637184) (xy 139.305898 -432.636801) (xy 139.282911 -432.629326) (xy 139.263359 -432.615113)
			(xy 139.249156 -432.595553) (xy 139.241693 -432.572562) (xy 139.241276 -432.560476) (xy 138.307154 -432.560476)
			(xy 138.312401 -432.564287) (xy 138.326606 -432.583834) (xy 138.334074 -432.606814) (xy 138.334496 -432.618896)
			(xy 138.334496 -435.16042) (xy 138.334052 -435.172497) (xy 138.326583 -435.195467) (xy 138.312381 -435.215004)
			(xy 138.292838 -435.229198) (xy 138.269865 -435.236657) (xy 138.257788 -435.237128) (xy 137.317988 -435.237128)
			(xy 137.305915 -435.236646) (xy 137.282951 -435.229183) (xy 137.263416 -435.21499) (xy 137.249221 -435.195456)
			(xy 137.241755 -435.172493) (xy 137.24128 -435.16042) (xy 136.3345 -435.16042) (xy 136.3345 -436.160418)
			(xy 136.334009 -436.172505) (xy 136.326552 -436.195499) (xy 136.31237 -436.215075) (xy 136.292845 -436.229327)
			(xy 136.269877 -436.236865) (xy 136.257792 -436.23738) (xy 135.317992 -436.23738) (xy 135.305881 -436.23699)
			(xy 135.28285 -436.229486) (xy 135.263275 -436.215219) (xy 135.249081 -436.19559) (xy 135.241664 -436.172531)
			(xy 135.241284 -436.160418) (xy 134.307483 -436.160418) (xy 134.312497 -436.16407) (xy 134.326692 -436.183685)
			(xy 134.334117 -436.20673) (xy 134.334504 -436.218838) (xy 134.334504 -438.760362) (xy 134.333961 -438.772445)
			(xy 134.32652 -438.795437) (xy 134.312352 -438.815014) (xy 134.292837 -438.829267) (xy 134.269877 -438.836808)
			(xy 134.257796 -438.837324) (xy 133.317996 -438.837324) (xy 133.305889 -438.836888) (xy 133.282866 -438.82939)
			(xy 133.263295 -438.815133) (xy 133.2491 -438.795517) (xy 133.241675 -438.77247) (xy 133.241288 -438.760362)
			(xy 132.334508 -438.760362) (xy 132.334508 -439.76036) (xy 135.241284 -439.76036) (xy 135.241284 -437.218836)
			(xy 135.241743 -437.206756) (xy 135.2492 -437.183776) (xy 135.263394 -437.164226) (xy 135.282936 -437.15002)
			(xy 135.305912 -437.14255) (xy 135.317992 -437.142128) (xy 136.257792 -437.142128) (xy 136.269878 -437.14252)
			(xy 136.292867 -437.149989) (xy 136.31242 -437.1642) (xy 136.326623 -437.183759) (xy 136.334085 -437.20675)
			(xy 136.3345 -437.218836) (xy 136.3345 -438.760362) (xy 137.24128 -438.760362) (xy 137.24128 -436.218838)
			(xy 137.24174 -436.206746) (xy 137.249192 -436.18374) (xy 137.263378 -436.164156) (xy 137.282916 -436.149906)
			(xy 137.305898 -436.14238) (xy 137.317988 -436.141876) (xy 138.257788 -436.141876) (xy 138.269894 -436.142326)
			(xy 138.292917 -436.14982) (xy 138.307469 -436.160418) (xy 139.241276 -436.160418) (xy 139.241276 -433.618894)
			(xy 139.241703 -433.606801) (xy 139.249166 -433.583794) (xy 139.263361 -433.564211) (xy 139.282906 -433.549962)
			(xy 139.305892 -433.542436) (xy 139.317984 -433.541932) (xy 140.257784 -433.541932) (xy 140.269895 -433.542331)
			(xy 140.292927 -433.549829) (xy 140.312503 -433.564094) (xy 140.326697 -433.583722) (xy 140.334113 -433.606781)
			(xy 140.334492 -433.618894) (xy 140.334492 -435.16042) (xy 142.241016 -435.16042) (xy 142.241016 -432.618896)
			(xy 142.241413 -432.606785) (xy 142.248915 -432.583755) (xy 142.263181 -432.564181) (xy 142.282808 -432.549987)
			(xy 142.305866 -432.542569) (xy 142.317978 -432.542188) (xy 143.257778 -432.542188) (xy 143.269871 -432.542627)
			(xy 143.292879 -432.550084) (xy 143.30722 -432.560476) (xy 144.241012 -432.560476) (xy 144.241012 -430.018952)
			(xy 144.241376 -430.006839) (xy 144.24889 -429.983809) (xy 144.263165 -429.964235) (xy 144.282798 -429.950043)
			(xy 144.30586 -429.942625) (xy 144.317974 -429.942244) (xy 145.257774 -429.942244) (xy 145.269863 -429.94273)
			(xy 145.292863 -429.95018) (xy 145.312444 -429.964361) (xy 145.326695 -429.983891) (xy 145.334227 -430.006865)
			(xy 145.334736 -430.018952) (xy 145.334736 -431.560478) (xy 146.241008 -431.560478) (xy 146.241008 -429.018954)
			(xy 146.241472 -429.00684) (xy 146.248968 -428.9838) (xy 146.263213 -428.964202) (xy 146.282815 -428.949961)
			(xy 146.305856 -428.94247) (xy 146.31797 -428.941992) (xy 147.25777 -428.941992) (xy 147.269878 -428.942537)
			(xy 147.292913 -428.95001) (xy 147.307412 -428.960534) (xy 148.241004 -428.960534) (xy 148.241004 -426.41901)
			(xy 148.24152 -426.406899) (xy 148.249 -426.383862) (xy 148.263232 -426.364263) (xy 148.282823 -426.35002)
			(xy 148.305856 -426.342527) (xy 148.317966 -426.342048) (xy 149.257766 -426.342048) (xy 149.269888 -426.342489)
			(xy 149.292947 -426.349973) (xy 149.312564 -426.364219) (xy 149.326816 -426.383831) (xy 149.334307 -426.406888)
			(xy 149.334728 -426.41901) (xy 149.334728 -427.960536) (xy 150.241 -427.960536) (xy 150.241 -425.419012)
			(xy 150.241427 -425.406904) (xy 150.248923 -425.383877) (xy 150.263182 -425.364304) (xy 150.282801 -425.350109)
			(xy 150.305852 -425.342688) (xy 150.317962 -425.342304) (xy 151.257762 -425.342304) (xy 151.269846 -425.342839)
			(xy 151.292839 -425.350281) (xy 151.312417 -425.364451) (xy 151.32667 -425.383968) (xy 151.334209 -425.40693)
			(xy 151.334724 -425.419012) (xy 151.334724 -427.960536) (xy 151.334315 -427.972644) (xy 151.326808 -427.995669)
			(xy 151.312544 -428.015239) (xy 151.292923 -428.029433) (xy 151.269872 -428.036857) (xy 151.257762 -428.037244)
			(xy 150.317962 -428.037244) (xy 150.305869 -428.036825) (xy 150.282864 -428.029356) (xy 150.263284 -428.015157)
			(xy 150.249035 -427.995613) (xy 150.241507 -427.972628) (xy 150.241 -427.960536) (xy 149.334728 -427.960536)
			(xy 149.334728 -428.960534) (xy 149.334317 -428.972654) (xy 149.326816 -428.995704) (xy 149.31256 -429.015308)
			(xy 149.292943 -429.029547) (xy 149.269886 -429.037027) (xy 149.257766 -429.037496) (xy 148.317966 -429.037496)
			(xy 148.305853 -429.037018) (xy 148.282814 -429.029525) (xy 148.263216 -429.015284) (xy 148.248975 -428.995686)
			(xy 148.241482 -428.972647) (xy 148.241004 -428.960534) (xy 147.307412 -428.960534) (xy 147.312511 -428.964235)
			(xy 147.326755 -428.983819) (xy 147.334251 -429.006846) (xy 147.334732 -429.018954) (xy 147.334732 -431.560478)
			(xy 147.334321 -431.572603) (xy 147.326831 -431.595666) (xy 147.312578 -431.615284) (xy 147.292959 -431.629535)
			(xy 147.269895 -431.637022) (xy 147.25777 -431.63744) (xy 146.31797 -431.63744) (xy 146.305852 -431.637014)
			(xy 146.282804 -431.629515) (xy 146.263201 -431.615262) (xy 146.248961 -431.59565) (xy 146.241478 -431.572597)
			(xy 146.241008 -431.560478) (xy 145.334736 -431.560478) (xy 145.334736 -432.560476) (xy 145.334264 -432.57258)
			(xy 145.326775 -432.5956) (xy 145.312527 -432.615171) (xy 145.292919 -432.629367) (xy 145.269879 -432.636795)
			(xy 145.257774 -432.637184) (xy 144.317974 -432.637184) (xy 144.305885 -432.636715) (xy 144.282888 -432.629254)
			(xy 144.263311 -432.615067) (xy 144.24906 -432.595536) (xy 144.241524 -432.572563) (xy 144.241012 -432.560476)
			(xy 143.30722 -432.560476) (xy 143.312464 -432.564276) (xy 143.326713 -432.583818) (xy 143.334237 -432.606804)
			(xy 143.33474 -432.618896) (xy 143.33474 -435.16042) (xy 143.334301 -435.172526) (xy 143.326801 -435.195547)
			(xy 143.312544 -435.215116) (xy 143.29293 -435.229312) (xy 143.269885 -435.236739) (xy 143.257778 -435.237128)
			(xy 142.317978 -435.237128) (xy 142.305884 -435.236711) (xy 142.282877 -435.229244) (xy 142.263295 -435.215046)
			(xy 142.249046 -435.1955) (xy 142.24152 -435.172513) (xy 142.241016 -435.16042) (xy 140.334492 -435.16042)
			(xy 140.334492 -436.160418) (xy 140.334009 -436.172505) (xy 140.326551 -436.195501) (xy 140.312367 -436.215078)
			(xy 140.29284 -436.229329) (xy 140.26987 -436.236866) (xy 140.257784 -436.23738) (xy 139.317984 -436.23738)
			(xy 139.305872 -436.236997) (xy 139.282841 -436.229491) (xy 139.263266 -436.215221) (xy 139.249073 -436.195592)
			(xy 139.241656 -436.172531) (xy 139.241276 -436.160418) (xy 138.307469 -436.160418) (xy 138.312488 -436.164073)
			(xy 138.326684 -436.183686) (xy 138.334109 -436.206731) (xy 138.334496 -436.218838) (xy 138.334496 -438.760362)
			(xy 138.333961 -438.772446) (xy 138.326519 -438.795439) (xy 138.312349 -438.815017) (xy 138.292832 -438.82927)
			(xy 138.26987 -438.836809) (xy 138.257788 -438.837324) (xy 137.317988 -438.837324) (xy 137.305881 -438.836894)
			(xy 137.282857 -438.829395) (xy 137.263286 -438.815136) (xy 137.249091 -438.795518) (xy 137.241667 -438.77247)
			(xy 137.24128 -438.760362) (xy 136.3345 -438.760362) (xy 136.3345 -439.76036) (xy 139.241276 -439.76036)
			(xy 139.241276 -437.218836) (xy 139.241743 -437.206757) (xy 139.249199 -437.183778) (xy 139.263391 -437.164228)
			(xy 139.282931 -437.150023) (xy 139.305905 -437.142551) (xy 139.317984 -437.142128) (xy 140.257784 -437.142128)
			(xy 140.269869 -437.142527) (xy 140.292858 -437.149995) (xy 140.312411 -437.164203) (xy 140.326615 -437.18376)
			(xy 140.334076 -437.20675) (xy 140.334492 -437.218836) (xy 140.334492 -438.760362) (xy 142.241016 -438.760362)
			(xy 142.241016 -436.218838) (xy 142.241492 -436.206719) (xy 142.248971 -436.183665) (xy 142.263209 -436.164052)
			(xy 142.282812 -436.149798) (xy 142.30586 -436.142301) (xy 142.317978 -436.141876) (xy 143.257778 -436.141876)
			(xy 143.269903 -436.142279) (xy 143.292968 -436.14977) (xy 143.307623 -436.160418) (xy 144.241012 -436.160418)
			(xy 144.241012 -433.618894) (xy 144.241506 -433.606782) (xy 144.248992 -433.583743) (xy 144.263229 -433.564143)
			(xy 144.282825 -433.549901) (xy 144.305862 -433.54241) (xy 144.317974 -433.541932) (xy 145.257774 -433.541932)
			(xy 145.269895 -433.542382) (xy 145.292952 -433.549866) (xy 145.312567 -433.56411) (xy 145.326819 -433.58372)
			(xy 145.334313 -433.606773) (xy 145.334736 -433.618894) (xy 145.334736 -435.16042) (xy 146.241008 -435.16042)
			(xy 146.241008 -432.618896) (xy 146.241413 -432.606786) (xy 146.248914 -432.583757) (xy 146.263179 -432.564184)
			(xy 146.282803 -432.549989) (xy 146.305859 -432.54257) (xy 146.31797 -432.542188) (xy 147.25777 -432.542188)
			(xy 147.269863 -432.542634) (xy 147.29287 -432.550088) (xy 147.307207 -432.560476) (xy 148.241004 -432.560476)
			(xy 148.241004 -430.018952) (xy 148.241376 -430.00684) (xy 148.248889 -429.983811) (xy 148.263162 -429.964238)
			(xy 148.282793 -429.950045) (xy 148.305853 -429.942626) (xy 148.317966 -429.942244) (xy 149.257766 -429.942244)
			(xy 149.269854 -429.942736) (xy 149.292854 -429.950184) (xy 149.312435 -429.964364) (xy 149.326687 -429.983893)
			(xy 149.334219 -430.006866) (xy 149.334728 -430.018952) (xy 149.334728 -431.560478) (xy 150.241 -431.560478)
			(xy 150.241 -429.018954) (xy 150.241472 -429.006841) (xy 150.248967 -428.983803) (xy 150.263211 -428.964205)
			(xy 150.28281 -428.949964) (xy 150.305849 -428.942471) (xy 150.317962 -428.941992) (xy 151.257762 -428.941992)
			(xy 151.26987 -428.942543) (xy 151.292904 -428.950015) (xy 151.307399 -428.960534) (xy 152.240996 -428.960534)
			(xy 152.240996 -426.41901) (xy 152.24152 -426.4069) (xy 152.248999 -426.383864) (xy 152.263229 -426.364266)
			(xy 152.282818 -426.350023) (xy 152.305848 -426.342528) (xy 152.317958 -426.342048) (xy 153.257758 -426.342048)
			(xy 153.26988 -426.342496) (xy 153.292939 -426.349978) (xy 153.312555 -426.364222) (xy 153.326808 -426.383833)
			(xy 153.334299 -426.406889) (xy 153.33472 -426.41901) (xy 153.33472 -427.960536) (xy 154.240992 -427.960536)
			(xy 154.240992 -425.419012) (xy 154.241427 -425.406905) (xy 154.248922 -425.383879) (xy 154.263179 -425.364307)
			(xy 154.282796 -425.350111) (xy 154.305845 -425.342689) (xy 154.317954 -425.342304) (xy 155.257754 -425.342304)
			(xy 155.269838 -425.342846) (xy 155.292831 -425.350286) (xy 155.312408 -425.364454) (xy 155.326662 -425.38397)
			(xy 155.334201 -425.40693) (xy 155.334716 -425.419012) (xy 155.334716 -427.960536) (xy 155.334315 -427.972645)
			(xy 155.326807 -427.995671) (xy 155.312541 -428.015242) (xy 155.292918 -428.029436) (xy 155.269865 -428.036859)
			(xy 155.257754 -428.037244) (xy 154.317954 -428.037244) (xy 154.30586 -428.036832) (xy 154.282856 -428.02936)
			(xy 154.263275 -428.01516) (xy 154.249027 -427.995615) (xy 154.241499 -427.972628) (xy 154.240992 -427.960536)
			(xy 153.33472 -427.960536) (xy 153.33472 -428.960534) (xy 153.334369 -428.972663) (xy 153.326862 -428.99573)
			(xy 153.312594 -429.015348) (xy 153.292962 -429.029597) (xy 153.269887 -429.03708) (xy 153.257758 -429.037496)
			(xy 152.317958 -429.037496) (xy 152.305845 -429.037025) (xy 152.282806 -429.02953) (xy 152.263208 -429.015287)
			(xy 152.248966 -428.995687) (xy 152.241474 -428.972647) (xy 152.240996 -428.960534) (xy 151.307399 -428.960534)
			(xy 151.312503 -428.964238) (xy 151.326747 -428.98382) (xy 151.334243 -429.006847) (xy 151.334724 -429.018954)
			(xy 151.334724 -431.560478) (xy 151.334321 -431.572603) (xy 151.32683 -431.595668) (xy 151.312575 -431.615287)
			(xy 151.292954 -431.629537) (xy 151.269887 -431.637023) (xy 151.257762 -431.63744) (xy 150.317962 -431.63744)
			(xy 150.305843 -431.63702) (xy 150.282795 -431.62952) (xy 150.263192 -431.615265) (xy 150.248953 -431.595651)
			(xy 150.24147 -431.572597) (xy 150.241 -431.560478) (xy 149.334728 -431.560478) (xy 149.334728 -432.560476)
			(xy 149.334263 -432.572581) (xy 149.326774 -432.595602) (xy 149.312524 -432.615174) (xy 149.292914 -432.62937)
			(xy 149.269872 -432.636796) (xy 149.257766 -432.637184) (xy 148.317966 -432.637184) (xy 148.305877 -432.636722)
			(xy 148.282879 -432.629259) (xy 148.263302 -432.61507) (xy 148.249052 -432.595538) (xy 148.241516 -432.572563)
			(xy 148.241004 -432.560476) (xy 147.307207 -432.560476) (xy 147.312455 -432.564278) (xy 147.326705 -432.58382)
			(xy 147.334229 -432.606805) (xy 147.334732 -432.618896) (xy 147.334732 -435.16042) (xy 147.334301 -435.172527)
			(xy 147.3268 -435.195549) (xy 147.312541 -435.215119) (xy 147.292925 -435.229314) (xy 147.269878 -435.23674)
			(xy 147.25777 -435.237128) (xy 146.31797 -435.237128) (xy 146.305876 -435.236718) (xy 146.282869 -435.229249)
			(xy 146.263286 -435.215049) (xy 146.249038 -435.195502) (xy 146.241512 -435.172513) (xy 146.241008 -435.16042)
			(xy 145.334736 -435.16042) (xy 145.334736 -436.160418) (xy 145.334355 -436.172544) (xy 145.326854 -436.195608)
			(xy 145.312594 -436.215225) (xy 145.292969 -436.229474) (xy 145.2699 -436.236962) (xy 145.257774 -436.23738)
			(xy 144.317974 -436.23738) (xy 144.30586 -436.236911) (xy 144.282819 -436.229419) (xy 144.263219 -436.215175)
			(xy 144.248978 -436.195574) (xy 144.241488 -436.172532) (xy 144.241012 -436.160418) (xy 143.307623 -436.160418)
			(xy 143.312587 -436.164025) (xy 143.326837 -436.183646) (xy 143.334323 -436.206713) (xy 143.33474 -436.218838)
			(xy 143.33474 -438.760362) (xy 143.334307 -438.772485) (xy 143.326823 -438.795546) (xy 143.312575 -438.815164)
			(xy 143.292961 -438.829416) (xy 143.269901 -438.836905) (xy 143.257778 -438.837324) (xy 142.317978 -438.837324)
			(xy 142.30585 -438.836958) (xy 142.282784 -438.829455) (xy 142.263167 -438.815191) (xy 142.248918 -438.795562)
			(xy 142.241433 -438.77249) (xy 142.241016 -438.760362) (xy 140.334492 -438.760362) (xy 140.334492 -439.76036)
			(xy 144.241012 -439.76036) (xy 144.241012 -437.218836) (xy 144.241447 -437.206728) (xy 144.248938 -437.1837)
			(xy 144.263194 -437.164125) (xy 144.282813 -437.14993) (xy 144.305865 -437.14251) (xy 144.317974 -437.142128)
			(xy 145.257774 -437.142128) (xy 145.269861 -437.142629) (xy 145.292859 -437.150077) (xy 145.312438 -437.164256)
			(xy 145.32669 -437.183781) (xy 145.334225 -437.206751) (xy 145.334736 -437.218836) (xy 145.334736 -438.760362)
			(xy 146.241008 -438.760362) (xy 146.241008 -436.218838) (xy 146.241492 -436.20672) (xy 146.24897 -436.183668)
			(xy 146.263206 -436.164055) (xy 146.282807 -436.149801) (xy 146.305853 -436.142302) (xy 146.31797 -436.141876)
			(xy 147.25777 -436.141876) (xy 147.269895 -436.142286) (xy 147.292959 -436.149775) (xy 147.307609 -436.160418)
			(xy 148.241004 -436.160418) (xy 148.241004 -433.618894) (xy 148.241506 -433.606783) (xy 148.248991 -433.583745)
			(xy 148.263226 -433.564146) (xy 148.28282 -433.549904) (xy 148.305855 -433.542411) (xy 148.317966 -433.541932)
			(xy 149.257766 -433.541932) (xy 149.269886 -433.542389) (xy 149.292943 -433.549871) (xy 149.312558 -433.564113)
			(xy 149.326811 -433.583721) (xy 149.334305 -433.606774) (xy 149.334728 -433.618894) (xy 149.334728 -435.16042)
			(xy 150.241 -435.16042) (xy 150.241 -432.618896) (xy 150.241413 -432.606787) (xy 150.248913 -432.583759)
			(xy 150.263176 -432.564186) (xy 150.282798 -432.549992) (xy 150.305852 -432.542571) (xy 150.317962 -432.542188)
			(xy 151.257762 -432.542188) (xy 151.269854 -432.542641) (xy 151.292862 -432.550093) (xy 151.307195 -432.560476)
			(xy 152.240996 -432.560476) (xy 152.240996 -430.018952) (xy 152.241376 -430.006841) (xy 152.248888 -429.983813)
			(xy 152.263159 -429.964241) (xy 152.282788 -429.950048) (xy 152.305845 -429.942628) (xy 152.317958 -429.942244)
			(xy 153.257758 -429.942244) (xy 153.269846 -429.942743) (xy 153.292846 -429.950189) (xy 153.312427 -429.964367)
			(xy 153.326679 -429.983894) (xy 153.334211 -430.006866) (xy 153.33472 -430.018952) (xy 153.33472 -431.560478)
			(xy 154.240992 -431.560478) (xy 154.240992 -429.018954) (xy 154.241472 -429.006842) (xy 154.248966 -428.983805)
			(xy 154.263208 -428.964208) (xy 154.282805 -428.949966) (xy 154.305842 -428.942472) (xy 154.317954 -428.941992)
			(xy 155.257754 -428.941992) (xy 155.269862 -428.94255) (xy 155.292896 -428.950019) (xy 155.307387 -428.960534)
			(xy 156.240988 -428.960534) (xy 156.240988 -426.41901) (xy 156.24152 -426.406901) (xy 156.248998 -426.383867)
			(xy 156.263226 -426.364269) (xy 156.282813 -426.350025) (xy 156.305841 -426.342529) (xy 156.31795 -426.342048)
			(xy 157.25775 -426.342048) (xy 157.269868 -426.342469) (xy 157.292915 -426.349972) (xy 157.312516 -426.364226)
			(xy 157.326756 -426.383839) (xy 157.33424 -426.406891) (xy 157.334712 -426.41901) (xy 157.334712 -428.960534)
			(xy 157.334218 -428.972645) (xy 157.326728 -428.995681) (xy 157.31249 -429.015278) (xy 157.292896 -429.02952)
			(xy 157.269861 -429.037016) (xy 157.25775 -429.037496) (xy 156.31795 -429.037496) (xy 156.305836 -429.037031)
			(xy 156.282797 -429.029535) (xy 156.263199 -429.015289) (xy 156.248958 -428.995689) (xy 156.241466 -428.972648)
			(xy 156.240988 -428.960534) (xy 155.307387 -428.960534) (xy 155.312494 -428.96424) (xy 155.326739 -428.983822)
			(xy 155.334235 -429.006847) (xy 155.334716 -429.018954) (xy 155.334716 -431.560478) (xy 155.334321 -431.572604)
			(xy 155.326829 -431.59567) (xy 155.312572 -431.61529) (xy 155.292949 -431.62954) (xy 155.26988 -431.637024)
			(xy 155.257754 -431.63744) (xy 154.317954 -431.63744) (xy 154.305835 -431.637027) (xy 154.282786 -431.629525)
			(xy 154.263184 -431.615268) (xy 154.248944 -431.595653) (xy 154.241462 -431.572598) (xy 154.240992 -431.560478)
			(xy 153.33472 -431.560478) (xy 153.33472 -432.560476) (xy 153.334263 -432.572582) (xy 153.326773 -432.595605)
			(xy 153.312521 -432.615176) (xy 153.292909 -432.629373) (xy 153.269865 -432.636797) (xy 153.257758 -432.637184)
			(xy 152.317958 -432.637184) (xy 152.305869 -432.636729) (xy 152.282871 -432.629264) (xy 152.263293 -432.615073)
			(xy 152.249043 -432.595539) (xy 152.241508 -432.572564) (xy 152.240996 -432.560476) (xy 151.307195 -432.560476)
			(xy 151.312447 -432.564281) (xy 151.326697 -432.583821) (xy 151.334221 -432.606805) (xy 151.334724 -432.618896)
			(xy 151.334724 -435.16042) (xy 151.334301 -435.172528) (xy 151.326799 -435.195551) (xy 151.312538 -435.215122)
			(xy 151.29292 -435.229317) (xy 151.269871 -435.236741) (xy 151.257762 -435.237128) (xy 150.317962 -435.237128)
			(xy 150.305867 -435.236724) (xy 150.28286 -435.229253) (xy 150.263278 -435.215052) (xy 150.24903 -435.195503)
			(xy 150.241504 -435.172514) (xy 150.241 -435.16042) (xy 149.334728 -435.16042) (xy 149.334728 -436.160418)
			(xy 149.334355 -436.172545) (xy 149.326853 -436.19561) (xy 149.312591 -436.215228) (xy 149.292964 -436.229477)
			(xy 149.269893 -436.236963) (xy 149.257766 -436.23738) (xy 148.317966 -436.23738) (xy 148.305851 -436.236918)
			(xy 148.28281 -436.229423) (xy 148.26321 -436.215178) (xy 148.248969 -436.195576) (xy 148.24148 -436.172533)
			(xy 148.241004 -436.160418) (xy 147.307609 -436.160418) (xy 147.312578 -436.164028) (xy 147.326829 -436.183648)
			(xy 147.334315 -436.206713) (xy 147.334732 -436.218838) (xy 147.334732 -438.760362) (xy 147.334307 -438.772486)
			(xy 147.326822 -438.795549) (xy 147.312573 -438.815167) (xy 147.292956 -438.829418) (xy 147.269894 -438.836906)
			(xy 147.25777 -438.837324) (xy 146.31797 -438.837324) (xy 146.305842 -438.836965) (xy 146.282776 -438.82946)
			(xy 146.263158 -438.815194) (xy 146.248909 -438.795563) (xy 146.241424 -438.772491) (xy 146.241008 -438.760362)
			(xy 145.334736 -438.760362) (xy 145.334736 -439.76036) (xy 148.241004 -439.76036) (xy 148.241004 -437.218836)
			(xy 148.241447 -437.206729) (xy 148.248937 -437.183702) (xy 148.263192 -437.164128) (xy 148.282808 -437.149932)
			(xy 148.305857 -437.142511) (xy 148.317966 -437.142128) (xy 149.257766 -437.142128) (xy 149.269853 -437.142636)
			(xy 149.29285 -437.150082) (xy 149.31243 -437.164258) (xy 149.326682 -437.183783) (xy 149.334217 -437.206751)
			(xy 149.334728 -437.218836) (xy 149.334728 -438.760362) (xy 150.241 -438.760362) (xy 150.241 -436.218838)
			(xy 150.241543 -436.206729) (xy 150.249016 -436.183694) (xy 150.26324 -436.164094) (xy 150.282825 -436.14985)
			(xy 150.305854 -436.142355) (xy 150.317962 -436.141876) (xy 151.257762 -436.141876) (xy 151.269887 -436.142293)
			(xy 151.292951 -436.149779) (xy 151.307597 -436.160418) (xy 152.240996 -436.160418) (xy 152.240996 -433.618894)
			(xy 152.241506 -433.606783) (xy 152.24899 -433.583747) (xy 152.263224 -433.564149) (xy 152.282815 -433.549906)
			(xy 152.305848 -433.542412) (xy 152.317958 -433.541932) (xy 153.257758 -433.541932) (xy 153.269878 -433.542396)
			(xy 153.292934 -433.549876) (xy 153.31255 -433.564116) (xy 153.326803 -433.583722) (xy 153.334297 -433.606774)
			(xy 153.33472 -433.618894) (xy 153.33472 -435.16042) (xy 154.240992 -435.16042) (xy 154.240992 -432.618896)
			(xy 154.241413 -432.606788) (xy 154.248912 -432.583762) (xy 154.263173 -432.564189) (xy 154.282793 -432.549994)
			(xy 154.305844 -432.542572) (xy 154.317954 -432.542188) (xy 155.257754 -432.542188) (xy 155.269846 -432.542647)
			(xy 155.292853 -432.550097) (xy 155.307181 -432.560476) (xy 156.240988 -432.560476) (xy 156.240988 -430.018952)
			(xy 156.241375 -430.006842) (xy 156.248887 -429.983815) (xy 156.263156 -429.964244) (xy 156.282783 -429.95005)
			(xy 156.305838 -429.942629) (xy 156.31795 -429.942244) (xy 157.25775 -429.942244) (xy 157.269837 -429.94275)
			(xy 157.292837 -429.950193) (xy 157.312418 -429.96437) (xy 157.32667 -429.983896) (xy 157.334203 -430.006866)
			(xy 157.334712 -430.018952) (xy 157.334712 -432.560476) (xy 157.334263 -432.572582) (xy 157.326772 -432.595607)
			(xy 157.312518 -432.615179) (xy 157.292904 -432.629375) (xy 157.269858 -432.636799) (xy 157.25775 -432.637184)
			(xy 156.31795 -432.637184) (xy 156.305865 -432.636651) (xy 156.28287 -432.62921) (xy 156.263292 -432.61504)
			(xy 156.249039 -432.595522) (xy 156.241501 -432.572559) (xy 156.240988 -432.560476) (xy 155.307181 -432.560476)
			(xy 155.312438 -432.564284) (xy 155.326688 -432.583823) (xy 155.334213 -432.606806) (xy 155.334716 -432.618896)
			(xy 155.334716 -435.16042) (xy 155.334301 -435.172528) (xy 155.326798 -435.195554) (xy 155.312536 -435.215125)
			(xy 155.292915 -435.229319) (xy 155.269864 -435.236743) (xy 155.257754 -435.237128) (xy 154.317954 -435.237128)
			(xy 154.305859 -435.236731) (xy 154.282851 -435.229258) (xy 154.263269 -435.215054) (xy 154.249022 -435.195505)
			(xy 154.241496 -435.172514) (xy 154.240992 -435.16042) (xy 153.33472 -435.16042) (xy 153.33472 -436.160418)
			(xy 153.334354 -436.172546) (xy 153.326852 -436.195612) (xy 153.312588 -436.215231) (xy 153.292958 -436.22948)
			(xy 153.269886 -436.236964) (xy 153.257758 -436.23738) (xy 152.317958 -436.23738) (xy 152.305843 -436.236924)
			(xy 152.282801 -436.229428) (xy 152.263202 -436.215181) (xy 152.248961 -436.195577) (xy 152.241472 -436.172533)
			(xy 152.240996 -436.160418) (xy 151.307597 -436.160418) (xy 151.31257 -436.16403) (xy 151.326821 -436.183649)
			(xy 151.334307 -436.206713) (xy 151.334724 -436.218838) (xy 151.334724 -438.760362) (xy 151.334307 -438.772487)
			(xy 151.326821 -438.795551) (xy 151.31257 -438.81517) (xy 151.292951 -438.829421) (xy 151.269887 -438.836907)
			(xy 151.257762 -438.837324) (xy 150.317962 -438.837324) (xy 150.305842 -438.83692) (xy 150.282791 -438.829418)
			(xy 150.263186 -438.81516) (xy 150.248947 -438.795541) (xy 150.241468 -438.772483) (xy 150.241 -438.760362)
			(xy 149.334728 -438.760362) (xy 149.334728 -439.76036) (xy 152.240996 -439.76036) (xy 152.240996 -437.218836)
			(xy 152.241447 -437.206729) (xy 152.248936 -437.183704) (xy 152.263189 -437.164131) (xy 152.282803 -437.149935)
			(xy 152.30585 -437.142512) (xy 152.317958 -437.142128) (xy 153.257758 -437.142128) (xy 153.269844 -437.142643)
			(xy 153.292841 -437.150087) (xy 153.312421 -437.164261) (xy 153.326673 -437.183784) (xy 153.334209 -437.206752)
			(xy 153.33472 -437.218836) (xy 153.33472 -438.760362) (xy 154.240992 -438.760362) (xy 154.240992 -436.218838)
			(xy 154.241543 -436.20673) (xy 154.249015 -436.183696) (xy 154.263238 -436.164097) (xy 154.28282 -436.149853)
			(xy 154.305847 -436.142357) (xy 154.317954 -436.141876) (xy 155.257754 -436.141876) (xy 155.269878 -436.1423)
			(xy 155.292942 -436.149784) (xy 155.307584 -436.160418) (xy 156.240988 -436.160418) (xy 156.240988 -433.618894)
			(xy 156.241506 -433.606784) (xy 156.248989 -433.583749) (xy 156.263221 -433.564152) (xy 156.28281 -433.549909)
			(xy 156.30584 -433.542413) (xy 156.31795 -433.541932) (xy 157.25775 -433.541932) (xy 157.269867 -433.542369)
			(xy 157.29291 -433.549869) (xy 157.312511 -433.564121) (xy 157.326751 -433.583729) (xy 157.334238 -433.606777)
			(xy 157.334712 -433.618894) (xy 157.334712 -436.160418) (xy 157.334205 -436.172529) (xy 157.326718 -436.195564)
			(xy 157.312484 -436.215161) (xy 157.292893 -436.229404) (xy 157.26986 -436.2369) (xy 157.25775 -436.23738)
			(xy 156.31795 -436.23738) (xy 156.305835 -436.236931) (xy 156.282793 -436.229432) (xy 156.263193 -436.215184)
			(xy 156.248953 -436.195578) (xy 156.241464 -436.172534) (xy 156.240988 -436.160418) (xy 155.307584 -436.160418)
			(xy 155.312561 -436.164033) (xy 155.326813 -436.183651) (xy 155.334299 -436.206714) (xy 155.334716 -436.218838)
			(xy 155.334716 -438.760362) (xy 155.334307 -438.772487) (xy 155.32682 -438.795553) (xy 155.312567 -438.815173)
			(xy 155.292946 -438.829423) (xy 155.269879 -438.836908) (xy 155.257754 -438.837324) (xy 154.317954 -438.837324)
			(xy 154.305833 -438.836927) (xy 154.282782 -438.829422) (xy 154.263178 -438.815162) (xy 154.248939 -438.795543)
			(xy 154.24146 -438.772483) (xy 154.240992 -438.760362) (xy 153.33472 -438.760362) (xy 153.33472 -439.76036)
			(xy 156.240988 -439.76036) (xy 156.240988 -437.218836) (xy 156.241447 -437.20673) (xy 156.248935 -437.183706)
			(xy 156.263186 -437.164134) (xy 156.282798 -437.149937) (xy 156.305843 -437.142514) (xy 156.31795 -437.142128)
			(xy 157.25775 -437.142128) (xy 157.269836 -437.14265) (xy 157.292833 -437.150091) (xy 157.312413 -437.164264)
			(xy 157.326665 -437.183786) (xy 157.334201 -437.206752) (xy 157.334712 -437.218836) (xy 157.334712 -438.760616)
			(xy 314.141104 -438.760616) (xy 314.141104 -436.219092) (xy 314.141509 -436.206982) (xy 314.149012 -436.183954)
			(xy 314.163276 -436.164381) (xy 314.1829 -436.150186) (xy 314.205955 -436.142767) (xy 314.218066 -436.142384)
			(xy 315.157866 -436.142384) (xy 315.169958 -436.142837) (xy 315.192965 -436.15029) (xy 315.207295 -436.160672)
			(xy 316.1411 -436.160672) (xy 316.1411 -433.619148) (xy 316.141557 -433.607042) (xy 316.149043 -433.584016)
			(xy 316.163294 -433.564442) (xy 316.182908 -433.550246) (xy 316.205955 -433.542824) (xy 316.218062 -433.54244)
			(xy 317.157862 -433.54244) (xy 317.16995 -433.54294) (xy 317.192949 -433.550386) (xy 317.21253 -433.564564)
			(xy 317.226781 -433.584091) (xy 317.234314 -433.607062) (xy 317.234824 -433.619148) (xy 317.234824 -435.160674)
			(xy 318.141096 -435.160674) (xy 318.141096 -432.61915) (xy 318.141568 -432.607037) (xy 318.149064 -432.583999)
			(xy 318.163308 -432.564402) (xy 318.182906 -432.550161) (xy 318.205945 -432.542667) (xy 318.218058 -432.542188)
			(xy 319.157858 -432.542188) (xy 319.169965 -432.542747) (xy 319.192999 -432.550216) (xy 319.207137 -432.560476)
			(xy 320.141092 -432.560476) (xy 320.141092 -430.018952) (xy 320.141475 -430.006841) (xy 320.148987 -429.983814)
			(xy 320.163258 -429.964242) (xy 320.182885 -429.950049) (xy 320.205942 -429.942628) (xy 320.218054 -429.942244)
			(xy 321.157854 -429.942244) (xy 321.169942 -429.942747) (xy 321.192941 -429.950191) (xy 321.212522 -429.964368)
			(xy 321.226774 -429.983895) (xy 321.234307 -430.006866) (xy 321.234816 -430.018952) (xy 321.234816 -431.560478)
			(xy 322.141088 -431.560478) (xy 322.141088 -429.018954) (xy 322.141572 -429.006842) (xy 322.149066 -428.983806)
			(xy 322.163306 -428.964209) (xy 322.182902 -428.949967) (xy 322.205938 -428.942472) (xy 322.21805 -428.941992)
			(xy 323.15785 -428.941992) (xy 323.169963 -428.942468) (xy 323.193 -428.949964) (xy 323.207544 -428.960534)
			(xy 324.141084 -428.960534) (xy 324.141084 -426.41901) (xy 324.141517 -426.406917) (xy 324.148976 -426.383909)
			(xy 324.16317 -426.364325) (xy 324.182714 -426.350076) (xy 324.2057 -426.342551) (xy 324.217792 -426.342048)
			(xy 325.157592 -426.342048) (xy 325.169695 -426.342522) (xy 325.192714 -426.350013) (xy 325.212282 -426.364262)
			(xy 325.226479 -426.383868) (xy 325.233909 -426.406906) (xy 325.2343 -426.41901) (xy 325.2343 -427.960536)
			(xy 326.14108 -427.960536) (xy 326.14108 -425.419012) (xy 326.141574 -425.406939) (xy 326.149032 -425.383974)
			(xy 326.163221 -425.364438) (xy 326.182753 -425.350243) (xy 326.205715 -425.342778) (xy 326.217788 -425.342304)
			(xy 327.157588 -425.342304) (xy 327.169671 -425.342723) (xy 327.192656 -425.350189) (xy 327.212207 -425.364393)
			(xy 327.226411 -425.383944) (xy 327.233877 -425.406929) (xy 327.234296 -425.419012) (xy 327.234296 -427.960536)
			(xy 327.233866 -427.972614) (xy 327.226393 -427.995584) (xy 327.212187 -428.015122) (xy 327.192641 -428.029315)
			(xy 327.169666 -428.036774) (xy 327.157588 -428.037244) (xy 326.217788 -428.037244) (xy 326.205716 -428.036746)
			(xy 326.182755 -428.029285) (xy 326.163221 -428.015096) (xy 326.149026 -427.995567) (xy 326.141557 -427.972607)
			(xy 326.14108 -427.960536) (xy 325.2343 -427.960536) (xy 325.2343 -428.960534) (xy 325.233822 -428.972621)
			(xy 325.226361 -428.995616) (xy 325.212176 -429.015192) (xy 325.192648 -429.029443) (xy 325.169678 -429.036981)
			(xy 325.157592 -429.037496) (xy 324.217792 -429.037496) (xy 324.205682 -429.037091) (xy 324.182654 -429.029588)
			(xy 324.163081 -429.015324) (xy 324.148886 -428.9957) (xy 324.141467 -428.972645) (xy 324.141084 -428.960534)
			(xy 323.207544 -428.960534) (xy 323.212597 -428.964206) (xy 323.226838 -428.983804) (xy 323.234332 -429.006841)
			(xy 323.234812 -429.018954) (xy 323.234812 -431.560478) (xy 323.23427 -431.572586) (xy 323.226795 -431.59562)
			(xy 323.212569 -431.615218) (xy 323.192985 -431.629462) (xy 323.169958 -431.636959) (xy 323.15785 -431.63744)
			(xy 322.21805 -431.63744) (xy 322.205931 -431.63703) (xy 322.182882 -431.629527) (xy 322.163279 -431.615269)
			(xy 322.14904 -431.595653) (xy 322.141558 -431.572598) (xy 322.141088 -431.560478) (xy 321.234816 -431.560478)
			(xy 321.234816 -432.560476) (xy 321.234363 -432.572582) (xy 321.226872 -432.595606) (xy 321.21262 -432.615178)
			(xy 321.193006 -432.629374) (xy 321.169961 -432.636798) (xy 321.157854 -432.637184) (xy 320.218054 -432.637184)
			(xy 320.205964 -432.636732) (xy 320.182966 -432.629266) (xy 320.163389 -432.615074) (xy 320.149139 -432.59554)
			(xy 320.141604 -432.572564) (xy 320.141092 -432.560476) (xy 319.207137 -432.560476) (xy 319.212597 -432.564438)
			(xy 319.226842 -432.584019) (xy 319.234339 -432.607043) (xy 319.23482 -432.61915) (xy 319.23482 -435.160674)
			(xy 319.234417 -435.1728) (xy 319.226927 -435.195865) (xy 319.212672 -435.215484) (xy 319.19305 -435.229734)
			(xy 319.169984 -435.23722) (xy 319.157858 -435.237636) (xy 318.218058 -435.237636) (xy 318.205939 -435.237224)
			(xy 318.18289 -435.229722) (xy 318.163286 -435.215465) (xy 318.149047 -435.195849) (xy 318.141566 -435.172794)
			(xy 318.141096 -435.160674) (xy 317.234824 -435.160674) (xy 317.234824 -436.160672) (xy 317.23436 -436.172777)
			(xy 317.226871 -436.195799) (xy 317.212621 -436.215371) (xy 317.193011 -436.229567) (xy 317.169968 -436.236993)
			(xy 317.157862 -436.23738) (xy 316.218062 -436.23738) (xy 316.205972 -436.236925) (xy 316.182974 -436.229461)
			(xy 316.163396 -436.21527) (xy 316.149146 -436.195736) (xy 316.141612 -436.17276) (xy 316.1411 -436.160672)
			(xy 315.207295 -436.160672) (xy 315.212549 -436.164478) (xy 315.2268 -436.184018) (xy 315.234325 -436.207001)
			(xy 315.234828 -436.219092) (xy 315.234828 -438.760616) (xy 315.234398 -438.772723) (xy 315.226897 -438.795746)
			(xy 315.212638 -438.815316) (xy 315.193022 -438.829511) (xy 315.169974 -438.836937) (xy 315.157866 -438.837324)
			(xy 314.218066 -438.837324) (xy 314.205971 -438.836921) (xy 314.182963 -438.829451) (xy 314.163381 -438.815249)
			(xy 314.149133 -438.7957) (xy 314.141608 -438.77271) (xy 314.141104 -438.760616) (xy 157.334712 -438.760616)
			(xy 157.334712 -439.76036) (xy 157.334702 -439.760614) (xy 316.1411 -439.760614) (xy 316.1411 -437.21909)
			(xy 316.141603 -437.206979) (xy 316.149088 -437.183942) (xy 316.163324 -437.164343) (xy 316.182917 -437.150101)
			(xy 316.205951 -437.142607) (xy 316.218062 -437.142128) (xy 317.157862 -437.142128) (xy 317.169982 -437.142592)
			(xy 317.193038 -437.150073) (xy 317.212653 -437.164313) (xy 317.226905 -437.183919) (xy 317.2344 -437.20697)
			(xy 317.234824 -437.21909) (xy 317.234824 -438.760616) (xy 318.141096 -438.760616) (xy 318.141096 -436.219092)
			(xy 318.141509 -436.206983) (xy 318.14901 -436.183956) (xy 318.163273 -436.164384) (xy 318.182895 -436.150189)
			(xy 318.205948 -436.142768) (xy 318.218058 -436.142384) (xy 319.157858 -436.142384) (xy 319.16995 -436.142844)
			(xy 319.192956 -436.150294) (xy 319.207283 -436.160672) (xy 320.141092 -436.160672) (xy 320.141092 -433.619148)
			(xy 320.141557 -433.607042) (xy 320.149042 -433.584018) (xy 320.163292 -433.564445) (xy 320.182903 -433.550248)
			(xy 320.205947 -433.542825) (xy 320.218054 -433.54244) (xy 321.157854 -433.54244) (xy 321.169941 -433.542947)
			(xy 321.19294 -433.550391) (xy 321.212521 -433.564567) (xy 321.226773 -433.584093) (xy 321.234306 -433.607063)
			(xy 321.234816 -433.619148) (xy 321.234816 -435.160674) (xy 322.141088 -435.160674) (xy 322.141088 -432.61915)
			(xy 322.141568 -432.607038) (xy 322.149063 -432.584001) (xy 322.163305 -432.564405) (xy 322.182901 -432.550163)
			(xy 322.205938 -432.542668) (xy 322.21805 -432.542188) (xy 323.15785 -432.542188) (xy 323.169962 -432.542668)
			(xy 323.192999 -432.550163) (xy 323.207189 -432.560476) (xy 324.141084 -432.560476) (xy 324.141084 -430.018952)
			(xy 324.141475 -430.006842) (xy 324.148986 -429.983816) (xy 324.163255 -429.964245) (xy 324.18288 -429.950052)
			(xy 324.205935 -429.942629) (xy 324.218046 -429.942244) (xy 325.157846 -429.942244) (xy 325.169938 -429.942668)
			(xy 325.192941 -429.950138) (xy 325.212521 -429.964336) (xy 325.22677 -429.983878) (xy 325.2343 -430.006861)
			(xy 325.234808 -430.018952) (xy 325.234808 -431.560478) (xy 326.14108 -431.560478) (xy 326.14108 -429.018954)
			(xy 326.141473 -429.006833) (xy 326.148978 -428.983781) (xy 326.163239 -428.964176) (xy 326.18286 -428.949938)
			(xy 326.20592 -428.942459) (xy 326.218042 -428.941992) (xy 327.157842 -428.941992) (xy 327.169954 -428.942475)
			(xy 327.192991 -428.949968) (xy 327.207531 -428.960534) (xy 328.141076 -428.960534) (xy 328.141076 -426.41901)
			(xy 328.141517 -426.406917) (xy 328.148975 -426.383911) (xy 328.163167 -426.364328) (xy 328.182709 -426.350078)
			(xy 328.205693 -426.342553) (xy 328.217784 -426.342048) (xy 329.157584 -426.342048) (xy 329.169687 -426.342529)
			(xy 329.192705 -426.350018) (xy 329.212273 -426.364265) (xy 329.22647 -426.383869) (xy 329.233901 -426.406906)
			(xy 329.234292 -426.41901) (xy 329.234292 -427.960536) (xy 331.140816 -427.960536) (xy 331.140816 -425.419012)
			(xy 331.141227 -425.406902) (xy 331.148725 -425.383873) (xy 331.162987 -425.364298) (xy 331.182611 -425.350104)
			(xy 331.205667 -425.342685) (xy 331.217778 -425.342304) (xy 332.157578 -425.342304) (xy 332.169663 -425.342825)
			(xy 332.192657 -425.350272) (xy 332.212234 -425.364446) (xy 332.226486 -425.383966) (xy 332.234025 -425.406929)
			(xy 332.23454 -425.419012) (xy 332.23454 -427.960536) (xy 332.234115 -427.972643) (xy 332.22661 -427.995664)
			(xy 332.21235 -428.015233) (xy 332.192733 -428.029428) (xy 332.169686 -428.036855) (xy 332.157578 -428.037244)
			(xy 331.217778 -428.037244) (xy 331.205686 -428.036811) (xy 331.182682 -428.029347) (xy 331.163101 -428.015152)
			(xy 331.148851 -427.99561) (xy 331.141323 -427.972627) (xy 331.140816 -427.960536) (xy 329.234292 -427.960536)
			(xy 329.234292 -428.960534) (xy 329.233822 -428.972622) (xy 329.22636 -428.995619) (xy 329.212173 -429.015195)
			(xy 329.192643 -429.029446) (xy 329.169671 -429.036983) (xy 329.157584 -429.037496) (xy 328.217784 -429.037496)
			(xy 328.205674 -429.037097) (xy 328.182645 -429.029593) (xy 328.163072 -429.015327) (xy 328.148878 -428.995702)
			(xy 328.141459 -428.972646) (xy 328.141076 -428.960534) (xy 327.207531 -428.960534) (xy 327.212588 -428.964209)
			(xy 327.22683 -428.983805) (xy 327.234324 -429.006842) (xy 327.234804 -429.018954) (xy 327.234804 -431.560478)
			(xy 327.23427 -431.572587) (xy 327.226794 -431.595623) (xy 327.212567 -431.615221) (xy 327.19298 -431.629465)
			(xy 327.169951 -431.63696) (xy 327.157842 -431.63744) (xy 326.218042 -431.63744) (xy 326.205919 -431.637004)
			(xy 326.182858 -431.629521) (xy 326.16324 -431.615274) (xy 326.148988 -431.59566) (xy 326.141499 -431.572601)
			(xy 326.14108 -431.560478) (xy 325.234808 -431.560478) (xy 325.234808 -432.560476) (xy 325.234363 -432.572583)
			(xy 325.226871 -432.595608) (xy 325.212617 -432.615181) (xy 325.193001 -432.629376) (xy 325.169954 -432.636799)
			(xy 325.157846 -432.637184) (xy 324.218046 -432.637184) (xy 324.205961 -432.636654) (xy 324.182966 -432.629213)
			(xy 324.163387 -432.615042) (xy 324.149134 -432.595522) (xy 324.141597 -432.572559) (xy 324.141084 -432.560476)
			(xy 323.207189 -432.560476) (xy 323.212595 -432.564405) (xy 323.226837 -432.584001) (xy 323.234332 -432.607038)
			(xy 323.234812 -432.61915) (xy 323.234812 -435.160674) (xy 323.234267 -435.172782) (xy 323.226793 -435.195816)
			(xy 323.212568 -435.215414) (xy 323.192984 -435.229658) (xy 323.169958 -435.237155) (xy 323.15785 -435.237636)
			(xy 322.21805 -435.237636) (xy 322.20593 -435.23723) (xy 322.182881 -435.229726) (xy 322.163278 -435.215468)
			(xy 322.149039 -435.195851) (xy 322.141558 -435.172794) (xy 322.141088 -435.160674) (xy 321.234816 -435.160674)
			(xy 321.234816 -436.160672) (xy 321.23436 -436.172778) (xy 321.22687 -436.195801) (xy 321.212618 -436.215374)
			(xy 321.193006 -436.22957) (xy 321.169961 -436.236994) (xy 321.157854 -436.23738) (xy 320.218054 -436.23738)
			(xy 320.205964 -436.236932) (xy 320.182965 -436.229465) (xy 320.163388 -436.215273) (xy 320.149138 -436.195737)
			(xy 320.141604 -436.172761) (xy 320.141092 -436.160672) (xy 319.207283 -436.160672) (xy 319.212541 -436.164481)
			(xy 319.226791 -436.184019) (xy 319.234316 -436.207002) (xy 319.23482 -436.219092) (xy 319.23482 -438.760616)
			(xy 319.234398 -438.772724) (xy 319.226896 -438.795748) (xy 319.212636 -438.815319) (xy 319.193017 -438.829514)
			(xy 319.169967 -438.836938) (xy 319.157858 -438.837324) (xy 318.218058 -438.837324) (xy 318.205963 -438.836928)
			(xy 318.182955 -438.829455) (xy 318.163372 -438.815252) (xy 318.149124 -438.795701) (xy 318.1416 -438.77271)
			(xy 318.141096 -438.760616) (xy 317.234824 -438.760616) (xy 317.234824 -439.760614) (xy 320.141092 -439.760614)
			(xy 320.141092 -437.21909) (xy 320.141603 -437.20698) (xy 320.149087 -437.183944) (xy 320.163321 -437.164346)
			(xy 320.182912 -437.150104) (xy 320.205944 -437.142608) (xy 320.218054 -437.142128) (xy 321.157854 -437.142128)
			(xy 321.169973 -437.142599) (xy 321.193029 -437.150077) (xy 321.212644 -437.164316) (xy 321.226897 -437.183921)
			(xy 321.234392 -437.206971) (xy 321.234816 -437.21909) (xy 321.234816 -438.760616) (xy 322.141088 -438.760616)
			(xy 322.141088 -436.219092) (xy 322.141509 -436.206984) (xy 322.149009 -436.183958) (xy 322.16327 -436.164386)
			(xy 322.18289 -436.150192) (xy 322.205941 -436.142769) (xy 322.21805 -436.142384) (xy 323.15785 -436.142384)
			(xy 323.169941 -436.142851) (xy 323.192948 -436.150299) (xy 323.207269 -436.160672) (xy 324.141084 -436.160672)
			(xy 324.141084 -433.619148) (xy 324.141557 -433.607043) (xy 324.149041 -433.58402) (xy 324.163289 -433.564448)
			(xy 324.182898 -433.550251) (xy 324.20594 -433.542826) (xy 324.218046 -433.54244) (xy 325.157846 -433.54244)
			(xy 325.169938 -433.542868) (xy 325.19294 -433.550338) (xy 325.212519 -433.564534) (xy 325.226768 -433.584075)
			(xy 325.234299 -433.607057) (xy 325.234808 -433.619148) (xy 325.234808 -435.160674) (xy 326.14108 -435.160674)
			(xy 326.14108 -432.61915) (xy 326.14147 -432.607029) (xy 326.148976 -432.583977) (xy 326.163238 -432.564372)
			(xy 326.182859 -432.550134) (xy 326.20592 -432.542655) (xy 326.218042 -432.542188) (xy 327.157842 -432.542188)
			(xy 327.169954 -432.542675) (xy 327.19299 -432.550168) (xy 327.207176 -432.560476) (xy 328.141076 -432.560476)
			(xy 328.141076 -430.018952) (xy 328.141475 -430.006843) (xy 328.148985 -429.983818) (xy 328.163252 -429.964248)
			(xy 328.182875 -429.950054) (xy 328.205928 -429.94263) (xy 328.218038 -429.942244) (xy 329.157838 -429.942244)
			(xy 329.16993 -429.942675) (xy 329.192933 -429.950143) (xy 329.212512 -429.964338) (xy 329.226761 -429.983879)
			(xy 329.234292 -430.006861) (xy 329.2348 -430.018952) (xy 329.2348 -431.560478) (xy 331.141324 -431.560478)
			(xy 331.141324 -429.018954) (xy 331.141768 -429.006864) (xy 331.149235 -428.983864) (xy 331.163428 -428.964286)
			(xy 331.182965 -428.950037) (xy 331.205943 -428.942503) (xy 331.218032 -428.941992) (xy 332.157832 -428.941992)
			(xy 332.169942 -428.942389) (xy 332.192969 -428.949896) (xy 332.207563 -428.960534) (xy 333.140812 -428.960534)
			(xy 333.140812 -426.41901) (xy 333.14132 -426.406899) (xy 333.148801 -426.38386) (xy 333.163035 -426.36426)
			(xy 333.182628 -426.350018) (xy 333.205663 -426.342526) (xy 333.217774 -426.342048) (xy 334.157574 -426.342048)
			(xy 334.169696 -426.342482) (xy 334.192756 -426.349969) (xy 334.212372 -426.364216) (xy 334.226624 -426.38383)
			(xy 334.234115 -426.406888) (xy 334.234536 -426.41901) (xy 334.234536 -427.960536) (xy 335.140808 -427.960536)
			(xy 335.140808 -425.419012) (xy 335.141227 -425.406903) (xy 335.148724 -425.383875) (xy 335.162985 -425.364301)
			(xy 335.182606 -425.350106) (xy 335.20566 -425.342687) (xy 335.21777 -425.342304) (xy 336.15757 -425.342304)
			(xy 336.169654 -425.342832) (xy 336.192648 -425.350276) (xy 336.212225 -425.364448) (xy 336.226478 -425.383967)
			(xy 336.234017 -425.40693) (xy 336.234532 -425.419012) (xy 336.234532 -427.960536) (xy 336.234115 -427.972644)
			(xy 336.226609 -427.995667) (xy 336.212347 -428.015236) (xy 336.192728 -428.029431) (xy 336.169679 -428.036856)
			(xy 336.15757 -428.037244) (xy 335.21777 -428.037244) (xy 335.205677 -428.036818) (xy 335.182673 -428.029351)
			(xy 335.163092 -428.015154) (xy 335.148843 -427.995612) (xy 335.141315 -427.972627) (xy 335.140808 -427.960536)
			(xy 334.234536 -427.960536) (xy 334.234536 -428.960534) (xy 334.234117 -428.972653) (xy 334.226617 -428.995702)
			(xy 334.212362 -429.015305) (xy 334.192748 -429.029545) (xy 334.169693 -429.037026) (xy 334.157574 -429.037496)
			(xy 333.217774 -429.037496) (xy 333.205661 -429.037011) (xy 333.182623 -429.029521) (xy 333.163025 -429.015281)
			(xy 333.148783 -428.995684) (xy 333.14129 -428.972646) (xy 333.140812 -428.960534) (xy 332.207563 -428.960534)
			(xy 332.212541 -428.964163) (xy 332.226734 -428.983788) (xy 332.234156 -429.006843) (xy 332.23454 -429.018954)
			(xy 332.23454 -431.560478) (xy 332.234073 -431.572568) (xy 332.22662 -431.595572) (xy 332.212434 -431.615154)
			(xy 332.192899 -431.629404) (xy 332.169921 -431.636933) (xy 332.157832 -431.63744) (xy 331.218032 -431.63744)
			(xy 331.205929 -431.636957) (xy 331.182909 -431.629471) (xy 331.163339 -431.615225) (xy 331.149142 -431.59562)
			(xy 331.141713 -431.572582) (xy 331.141324 -431.560478) (xy 329.2348 -431.560478) (xy 329.2348 -432.560476)
			(xy 329.234363 -432.572584) (xy 329.22687 -432.59561) (xy 329.212614 -432.615184) (xy 329.192996 -432.629379)
			(xy 329.169947 -432.6368) (xy 329.157838 -432.637184) (xy 328.218038 -432.637184) (xy 328.205953 -432.636661)
			(xy 328.182957 -432.629217) (xy 328.163379 -432.615044) (xy 328.149126 -432.595524) (xy 328.141589 -432.572559)
			(xy 328.141076 -432.560476) (xy 327.207176 -432.560476) (xy 327.212587 -432.564408) (xy 327.226829 -432.584003)
			(xy 327.234324 -432.607038) (xy 327.234804 -432.61915) (xy 327.234804 -435.160674) (xy 327.234267 -435.172783)
			(xy 327.226792 -435.195818) (xy 327.212565 -435.215417) (xy 327.192979 -435.229661) (xy 327.169951 -435.237156)
			(xy 327.157842 -435.237636) (xy 326.218042 -435.237636) (xy 326.205919 -435.237204) (xy 326.182857 -435.22972)
			(xy 326.163239 -435.215473) (xy 326.148987 -435.195857) (xy 326.141499 -435.172797) (xy 326.14108 -435.160674)
			(xy 325.234808 -435.160674) (xy 325.234808 -436.160672) (xy 325.23436 -436.172779) (xy 325.226869 -436.195804)
			(xy 325.212615 -436.215376) (xy 325.193001 -436.229572) (xy 325.169954 -436.236995) (xy 325.157846 -436.23738)
			(xy 324.218046 -436.23738) (xy 324.205961 -436.236854) (xy 324.182965 -436.229412) (xy 324.163386 -436.21524)
			(xy 324.149133 -436.19572) (xy 324.141597 -436.172755) (xy 324.141084 -436.160672) (xy 323.207269 -436.160672)
			(xy 323.212532 -436.164484) (xy 323.226783 -436.184021) (xy 323.234308 -436.207002) (xy 323.234812 -436.219092)
			(xy 323.234812 -438.760616) (xy 323.234398 -438.772725) (xy 323.226895 -438.79575) (xy 323.212633 -438.815322)
			(xy 323.193012 -438.829517) (xy 323.16996 -438.836939) (xy 323.15785 -438.837324) (xy 322.21805 -438.837324)
			(xy 322.205959 -438.836849) (xy 322.182954 -438.829402) (xy 322.16337 -438.815219) (xy 322.149119 -438.795684)
			(xy 322.141593 -438.772705) (xy 322.141088 -438.760616) (xy 321.234816 -438.760616) (xy 321.234816 -439.760614)
			(xy 324.141084 -439.760614) (xy 324.141084 -437.21909) (xy 324.141452 -437.206962) (xy 324.148953 -437.183895)
			(xy 324.163216 -437.164276) (xy 324.182845 -437.150027) (xy 324.205918 -437.142544) (xy 324.218046 -437.142128)
			(xy 325.157846 -437.142128) (xy 325.169962 -437.142572) (xy 325.193005 -437.150071) (xy 325.212605 -437.164321)
			(xy 325.226845 -437.183927) (xy 325.234333 -437.206974) (xy 325.234808 -437.21909) (xy 325.234808 -438.760616)
			(xy 326.14108 -438.760616) (xy 326.14108 -436.219092) (xy 326.141509 -436.206985) (xy 326.149008 -436.183961)
			(xy 326.163267 -436.164389) (xy 326.182885 -436.150194) (xy 326.205933 -436.14277) (xy 326.218042 -436.142384)
			(xy 327.157842 -436.142384) (xy 327.169938 -436.142772) (xy 327.192948 -436.150246) (xy 327.207321 -436.160672)
			(xy 328.141076 -436.160672) (xy 328.141076 -433.619148) (xy 328.141557 -433.607044) (xy 328.14904 -433.584022)
			(xy 328.163286 -433.564451) (xy 328.182893 -433.550253) (xy 328.205933 -433.542827) (xy 328.218038 -433.54244)
			(xy 329.157838 -433.54244) (xy 329.16993 -433.542875) (xy 329.192931 -433.550342) (xy 329.212511 -433.564537)
			(xy 329.22676 -433.584077) (xy 329.234291 -433.607058) (xy 329.2348 -433.619148) (xy 329.2348 -435.160674)
			(xy 331.141324 -435.160674) (xy 331.141324 -432.61915) (xy 331.14185 -432.607065) (xy 331.149291 -432.584068)
			(xy 331.163463 -432.564489) (xy 331.182983 -432.550236) (xy 331.205949 -432.5427) (xy 331.218032 -432.542188)
			(xy 332.157832 -432.542188) (xy 332.169941 -432.542589) (xy 332.192968 -432.550096) (xy 332.207208 -432.560476)
			(xy 333.14132 -432.560476) (xy 333.14132 -430.018952) (xy 333.141724 -430.006872) (xy 333.149203 -429.983899)
			(xy 333.163414 -429.96436) (xy 333.182967 -429.950168) (xy 333.205948 -429.942712) (xy 333.218028 -429.942244)
			(xy 334.157828 -429.942244) (xy 334.169899 -429.942739) (xy 334.192859 -429.950204) (xy 334.212392 -429.964394)
			(xy 334.226587 -429.983923) (xy 334.234058 -430.006881) (xy 334.234536 -430.018952) (xy 334.234536 -431.560478)
			(xy 335.141316 -431.560478) (xy 335.141316 -429.018954) (xy 335.141768 -429.006864) (xy 335.149234 -428.983866)
			(xy 335.163426 -428.964289) (xy 335.18296 -428.950039) (xy 335.205936 -428.942504) (xy 335.218024 -428.941992)
			(xy 336.157824 -428.941992) (xy 336.169933 -428.942396) (xy 336.19296 -428.949901) (xy 336.207549 -428.960534)
			(xy 337.140804 -428.960534) (xy 337.140804 -426.41901) (xy 337.14132 -426.406899) (xy 337.1488 -426.383862)
			(xy 337.163032 -426.364263) (xy 337.182623 -426.35002) (xy 337.205656 -426.342527) (xy 337.217766 -426.342048)
			(xy 338.157566 -426.342048) (xy 338.169688 -426.342489) (xy 338.192747 -426.349973) (xy 338.212364 -426.364219)
			(xy 338.226616 -426.383831) (xy 338.234107 -426.406888) (xy 338.234528 -426.41901) (xy 338.234528 -427.960536)
			(xy 339.1408 -427.960536) (xy 339.1408 -425.419012) (xy 339.141227 -425.406904) (xy 339.148723 -425.383877)
			(xy 339.162982 -425.364304) (xy 339.182601 -425.350109) (xy 339.205652 -425.342688) (xy 339.217762 -425.342304)
			(xy 340.157562 -425.342304) (xy 340.169646 -425.342839) (xy 340.192639 -425.350281) (xy 340.212217 -425.364451)
			(xy 340.22647 -425.383968) (xy 340.234009 -425.40693) (xy 340.234524 -425.419012) (xy 340.234524 -427.960536)
			(xy 340.234115 -427.972644) (xy 340.226608 -427.995669) (xy 340.212344 -428.015239) (xy 340.192723 -428.029433)
			(xy 340.169672 -428.036857) (xy 340.157562 -428.037244) (xy 339.217762 -428.037244) (xy 339.205669 -428.036825)
			(xy 339.182664 -428.029356) (xy 339.163084 -428.015157) (xy 339.148835 -427.995613) (xy 339.141307 -427.972628)
			(xy 339.1408 -427.960536) (xy 338.234528 -427.960536) (xy 338.234528 -428.960534) (xy 338.234117 -428.972654)
			(xy 338.226616 -428.995704) (xy 338.21236 -429.015308) (xy 338.192743 -429.029547) (xy 338.169686 -429.037027)
			(xy 338.157566 -429.037496) (xy 337.217766 -429.037496) (xy 337.205653 -429.037018) (xy 337.182614 -429.029525)
			(xy 337.163016 -429.015284) (xy 337.148775 -428.995686) (xy 337.141282 -428.972647) (xy 337.140804 -428.960534)
			(xy 336.207549 -428.960534) (xy 336.212532 -428.964166) (xy 336.226726 -428.983789) (xy 336.234148 -429.006843)
			(xy 336.234532 -429.018954) (xy 336.234532 -431.560478) (xy 336.234073 -431.572569) (xy 336.226619 -431.595574)
			(xy 336.212432 -431.615156) (xy 336.192894 -431.629407) (xy 336.169914 -431.636934) (xy 336.157824 -431.63744)
			(xy 335.218024 -431.63744) (xy 335.20592 -431.636964) (xy 335.182901 -431.629476) (xy 335.163331 -431.615228)
			(xy 335.149134 -431.595622) (xy 335.141705 -431.572583) (xy 335.141316 -431.560478) (xy 334.234536 -431.560478)
			(xy 334.234536 -432.560476) (xy 334.234016 -432.572547) (xy 334.226563 -432.595508) (xy 334.21238 -432.615043)
			(xy 334.192855 -432.62924) (xy 334.169898 -432.636708) (xy 334.157828 -432.637184) (xy 333.218028 -432.637184)
			(xy 333.205944 -432.636763) (xy 333.182959 -432.6293) (xy 333.163406 -432.615097) (xy 333.149202 -432.595545)
			(xy 333.141738 -432.57256) (xy 333.14132 -432.560476) (xy 332.207208 -432.560476) (xy 332.212539 -432.564362)
			(xy 332.226733 -432.583985) (xy 332.234155 -432.607039) (xy 332.23454 -432.61915) (xy 332.23454 -435.160674)
			(xy 332.23407 -435.172764) (xy 332.226618 -435.195767) (xy 332.212433 -435.215349) (xy 332.192899 -435.2296)
			(xy 332.169921 -435.237129) (xy 332.157832 -435.237636) (xy 331.218032 -435.237636) (xy 331.205928 -435.237157)
			(xy 331.182908 -435.229671) (xy 331.163338 -435.215424) (xy 331.149141 -435.195818) (xy 331.141713 -435.172779)
			(xy 331.141324 -435.160674) (xy 329.2348 -435.160674) (xy 329.2348 -436.160672) (xy 329.23436 -436.172779)
			(xy 329.226868 -436.195806) (xy 329.212613 -436.215379) (xy 329.192996 -436.229575) (xy 329.169947 -436.236996)
			(xy 329.157838 -436.23738) (xy 328.218038 -436.23738) (xy 328.205952 -436.236861) (xy 328.182956 -436.229417)
			(xy 328.163378 -436.215243) (xy 328.149125 -436.195721) (xy 328.141589 -436.172756) (xy 328.141076 -436.160672)
			(xy 327.207321 -436.160672) (xy 327.212531 -436.164451) (xy 327.226778 -436.184004) (xy 327.234301 -436.206997)
			(xy 327.234804 -436.219092) (xy 327.234804 -438.760616) (xy 327.234397 -438.772725) (xy 327.226894 -438.795752)
			(xy 327.21263 -438.815325) (xy 327.193007 -438.829519) (xy 327.169953 -438.83694) (xy 327.157842 -438.837324)
			(xy 326.218042 -438.837324) (xy 326.205951 -438.836856) (xy 326.182946 -438.829407) (xy 326.163362 -438.815222)
			(xy 326.149111 -438.795686) (xy 326.141585 -438.772705) (xy 326.14108 -438.760616) (xy 325.234808 -438.760616)
			(xy 325.234808 -439.760614) (xy 328.141076 -439.760614) (xy 328.141076 -437.21909) (xy 328.141452 -437.206963)
			(xy 328.148952 -437.183897) (xy 328.163213 -437.164279) (xy 328.18284 -437.15003) (xy 328.205911 -437.142545)
			(xy 328.218038 -437.142128) (xy 329.157838 -437.142128) (xy 329.169954 -437.142579) (xy 329.192996 -437.150076)
			(xy 329.212597 -437.164323) (xy 329.226837 -437.183929) (xy 329.234325 -437.206974) (xy 329.2348 -437.21909)
			(xy 329.2348 -438.760616) (xy 331.141324 -438.760616) (xy 331.141324 -436.219092) (xy 331.141706 -436.207006)
			(xy 331.14918 -436.184017) (xy 331.163393 -436.164464) (xy 331.182953 -436.150262) (xy 331.205945 -436.1428)
			(xy 331.218032 -436.142384) (xy 332.157832 -436.142384) (xy 332.169907 -436.142837) (xy 332.192874 -436.150307)
			(xy 332.207134 -436.160672) (xy 333.14132 -436.160672) (xy 333.14132 -433.619148) (xy 333.141754 -433.607065)
			(xy 333.149212 -433.584079) (xy 333.163411 -433.564526) (xy 333.182961 -433.550321) (xy 333.205945 -433.542857)
			(xy 333.218028 -433.54244) (xy 334.157828 -433.54244) (xy 334.169917 -433.542789) (xy 334.192909 -433.550271)
			(xy 334.212463 -433.564491) (xy 334.226664 -433.584059) (xy 334.234122 -433.607059) (xy 334.234536 -433.619148)
			(xy 334.234536 -435.160674) (xy 335.141316 -435.160674) (xy 335.141316 -432.61915) (xy 335.141849 -432.607065)
			(xy 335.14929 -432.58407) (xy 335.16346 -432.564492) (xy 335.182978 -432.550239) (xy 335.205941 -432.542701)
			(xy 335.218024 -432.542188) (xy 336.157824 -432.542188) (xy 336.169933 -432.542596) (xy 336.192959 -432.5501)
			(xy 336.207195 -432.560476) (xy 337.141312 -432.560476) (xy 337.141312 -430.018952) (xy 337.141724 -430.006873)
			(xy 337.149202 -429.983901) (xy 337.163411 -429.964363) (xy 337.182962 -429.950171) (xy 337.205941 -429.942713)
			(xy 337.21802 -429.942244) (xy 338.15782 -429.942244) (xy 338.169891 -429.942747) (xy 338.19285 -429.950209)
			(xy 338.212383 -429.964397) (xy 338.226578 -429.983924) (xy 338.234049 -430.006881) (xy 338.234528 -430.018952)
			(xy 338.234528 -431.560478) (xy 339.141308 -431.560478) (xy 339.141308 -429.018954) (xy 339.141768 -429.006865)
			(xy 339.149233 -428.983868) (xy 339.163423 -428.964292) (xy 339.182955 -428.950042) (xy 339.205929 -428.942505)
			(xy 339.218016 -428.941992) (xy 340.157816 -428.941992) (xy 340.169925 -428.942402) (xy 340.192951 -428.949905)
			(xy 340.207536 -428.960534) (xy 341.140796 -428.960534) (xy 341.140796 -426.41901) (xy 341.14132 -426.4069)
			(xy 341.148799 -426.383864) (xy 341.163029 -426.364266) (xy 341.182618 -426.350023) (xy 341.205648 -426.342528)
			(xy 341.217758 -426.342048) (xy 342.157558 -426.342048) (xy 342.16968 -426.342496) (xy 342.192739 -426.349978)
			(xy 342.212355 -426.364222) (xy 342.226608 -426.383833) (xy 342.234099 -426.406889) (xy 342.23452 -426.41901)
			(xy 342.23452 -427.960536) (xy 343.140792 -427.960536) (xy 343.140792 -425.419012) (xy 343.141227 -425.406905)
			(xy 343.148722 -425.383879) (xy 343.162979 -425.364307) (xy 343.182596 -425.350111) (xy 343.205645 -425.342689)
			(xy 343.217754 -425.342304) (xy 344.157554 -425.342304) (xy 344.169638 -425.342846) (xy 344.192631 -425.350286)
			(xy 344.212208 -425.364454) (xy 344.226462 -425.38397) (xy 344.234001 -425.40693) (xy 344.234516 -425.419012)
			(xy 344.234516 -427.960536) (xy 344.234115 -427.972645) (xy 344.226607 -427.995671) (xy 344.212341 -428.015242)
			(xy 344.192718 -428.029436) (xy 344.169665 -428.036859) (xy 344.157554 -428.037244) (xy 343.217754 -428.037244)
			(xy 343.20566 -428.036832) (xy 343.182656 -428.02936) (xy 343.163075 -428.01516) (xy 343.148827 -427.995615)
			(xy 343.141299 -427.972628) (xy 343.140792 -427.960536) (xy 342.23452 -427.960536) (xy 342.23452 -428.960534)
			(xy 342.234169 -428.972663) (xy 342.226662 -428.99573) (xy 342.212394 -429.015348) (xy 342.192762 -429.029597)
			(xy 342.169687 -429.03708) (xy 342.157558 -429.037496) (xy 341.217758 -429.037496) (xy 341.205645 -429.037025)
			(xy 341.182606 -429.02953) (xy 341.163008 -429.015287) (xy 341.148766 -428.995687) (xy 341.141274 -428.972647)
			(xy 341.140796 -428.960534) (xy 340.207536 -428.960534) (xy 340.212524 -428.964169) (xy 340.226718 -428.983791)
			(xy 340.23414 -429.006844) (xy 340.234524 -429.018954) (xy 340.234524 -431.560478) (xy 340.234073 -431.57257)
			(xy 340.226618 -431.595576) (xy 340.212429 -431.615159) (xy 340.192889 -431.629409) (xy 340.169906 -431.636935)
			(xy 340.157816 -431.63744) (xy 339.218016 -431.63744) (xy 339.205912 -431.63697) (xy 339.182892 -431.62948)
			(xy 339.163322 -431.615231) (xy 339.149126 -431.595623) (xy 339.141697 -431.572583) (xy 339.141308 -431.560478)
			(xy 338.234528 -431.560478) (xy 338.234528 -432.560476) (xy 338.234067 -432.572555) (xy 338.226609 -432.595534)
			(xy 338.212414 -432.615083) (xy 338.192873 -432.629288) (xy 338.169899 -432.63676) (xy 338.15782 -432.637184)
			(xy 337.21802 -432.637184) (xy 337.205936 -432.63677) (xy 337.18295 -432.629305) (xy 337.163397 -432.6151)
			(xy 337.149193 -432.595547) (xy 337.14173 -432.57256) (xy 337.141312 -432.560476) (xy 336.207195 -432.560476)
			(xy 336.212531 -432.564365) (xy 336.226725 -432.583987) (xy 336.234147 -432.60704) (xy 336.234532 -432.61915)
			(xy 336.234532 -435.160674) (xy 336.23407 -435.172765) (xy 336.226617 -435.195769) (xy 336.21243 -435.215352)
			(xy 336.192894 -435.229603) (xy 336.169913 -435.23713) (xy 336.157824 -435.237636) (xy 335.218024 -435.237636)
			(xy 335.20592 -435.237164) (xy 335.1829 -435.229675) (xy 335.163329 -435.215427) (xy 335.149133 -435.195819)
			(xy 335.141705 -435.172779) (xy 335.141316 -435.160674) (xy 334.234536 -435.160674) (xy 334.234536 -436.160672)
			(xy 334.234012 -436.172742) (xy 334.226561 -436.195704) (xy 334.212379 -436.215239) (xy 334.192854 -436.229435)
			(xy 334.169898 -436.236904) (xy 334.157828 -436.23738) (xy 333.218028 -436.23738) (xy 333.205944 -436.236963)
			(xy 333.182957 -436.2295) (xy 333.163404 -436.215296) (xy 333.1492 -436.195743) (xy 333.141737 -436.172756)
			(xy 333.14132 -436.160672) (xy 332.207134 -436.160672) (xy 332.21241 -436.164507) (xy 332.226604 -436.184047)
			(xy 332.234067 -436.207016) (xy 332.23454 -436.219092) (xy 332.23454 -438.760616) (xy 332.23405 -438.772688)
			(xy 332.226587 -438.79565) (xy 332.212396 -438.815184) (xy 332.192865 -438.829379) (xy 332.169904 -438.836847)
			(xy 332.157832 -438.837324) (xy 331.218032 -438.837324) (xy 331.205953 -438.83686) (xy 331.182974 -438.829403)
			(xy 331.163424 -438.81521) (xy 331.149218 -438.795669) (xy 331.141747 -438.772695) (xy 331.141324 -438.760616)
			(xy 329.2348 -438.760616) (xy 329.2348 -439.760614) (xy 333.14132 -439.760614) (xy 333.14132 -437.21909)
			(xy 333.141799 -437.207002) (xy 333.149256 -437.184004) (xy 333.16344 -437.164426) (xy 333.18297 -437.150176)
			(xy 333.205942 -437.14264) (xy 333.218028 -437.142128) (xy 334.157828 -437.142128) (xy 334.169941 -437.142493)
			(xy 334.192974 -437.150003) (xy 334.212549 -437.164277) (xy 334.226742 -437.183911) (xy 334.234157 -437.206975)
			(xy 334.234536 -437.21909) (xy 334.234536 -438.760616) (xy 335.141316 -438.760616) (xy 335.141316 -436.219092)
			(xy 335.141706 -436.207006) (xy 335.149179 -436.184019) (xy 335.16339 -436.164467) (xy 335.182948 -436.150264)
			(xy 335.205938 -436.142801) (xy 335.218024 -436.142384) (xy 336.157824 -436.142384) (xy 336.169899 -436.142844)
			(xy 336.192866 -436.150312) (xy 336.20712 -436.160672) (xy 337.141312 -436.160672) (xy 337.141312 -433.619148)
			(xy 337.141754 -433.607066) (xy 337.149211 -433.584081) (xy 337.163408 -433.564528) (xy 337.182956 -433.550323)
			(xy 337.205938 -433.542858) (xy 337.21802 -433.54244) (xy 338.15782 -433.54244) (xy 338.169909 -433.542796)
			(xy 338.1929 -433.550275) (xy 338.212454 -433.564494) (xy 338.226656 -433.584061) (xy 338.234114 -433.607059)
			(xy 338.234528 -433.619148) (xy 338.234528 -435.160674) (xy 339.141308 -435.160674) (xy 339.141308 -432.61915)
			(xy 339.141849 -432.607066) (xy 339.149288 -432.584073) (xy 339.163457 -432.564495) (xy 339.182973 -432.550241)
			(xy 339.205934 -432.542702) (xy 339.218016 -432.542188) (xy 340.157816 -432.542188) (xy 340.169925 -432.542602)
			(xy 340.19295 -432.550105) (xy 340.207182 -432.560476) (xy 341.141304 -432.560476) (xy 341.141304 -430.018952)
			(xy 341.141723 -430.006874) (xy 341.149201 -429.983903) (xy 341.163408 -429.964366) (xy 341.182957 -429.950173)
			(xy 341.205933 -429.942714) (xy 341.218012 -429.942244) (xy 342.157812 -429.942244) (xy 342.169882 -429.942753)
			(xy 342.192842 -429.950213) (xy 342.212374 -429.9644) (xy 342.22657 -429.983926) (xy 342.234041 -430.006882)
			(xy 342.23452 -430.018952) (xy 342.23452 -431.560478) (xy 343.1413 -431.560478) (xy 343.1413 -429.018954)
			(xy 343.141767 -429.006866) (xy 343.149232 -428.983871) (xy 343.16342 -428.964295) (xy 343.18295 -428.950044)
			(xy 343.205922 -428.942507) (xy 343.218008 -428.941992) (xy 344.157808 -428.941992) (xy 344.169917 -428.942409)
			(xy 344.192943 -428.94991) (xy 344.207523 -428.960534) (xy 345.140788 -428.960534) (xy 345.140788 -426.41901)
			(xy 345.14132 -426.406901) (xy 345.148798 -426.383867) (xy 345.163026 -426.364269) (xy 345.182613 -426.350025)
			(xy 345.205641 -426.342529) (xy 345.21775 -426.342048) (xy 346.15755 -426.342048) (xy 346.169668 -426.342469)
			(xy 346.192715 -426.349972) (xy 346.212316 -426.364226) (xy 346.226556 -426.383839) (xy 346.23404 -426.406891)
			(xy 346.234512 -426.41901) (xy 346.234512 -428.960534) (xy 346.234018 -428.972645) (xy 346.226528 -428.995681)
			(xy 346.21229 -429.015278) (xy 346.192696 -429.02952) (xy 346.169661 -429.037016) (xy 346.15755 -429.037496)
			(xy 345.21775 -429.037496) (xy 345.205636 -429.037031) (xy 345.182597 -429.029535) (xy 345.162999 -429.015289)
			(xy 345.148758 -428.995689) (xy 345.141266 -428.972648) (xy 345.140788 -428.960534) (xy 344.207523 -428.960534)
			(xy 344.212515 -428.964172) (xy 344.22671 -428.983792) (xy 344.234132 -429.006844) (xy 344.234516 -429.018954)
			(xy 344.234516 -431.560478) (xy 344.234073 -431.572571) (xy 344.226617 -431.595578) (xy 344.212426 -431.615162)
			(xy 344.192884 -431.629412) (xy 344.169899 -431.636937) (xy 344.157808 -431.63744) (xy 343.218008 -431.63744)
			(xy 343.205904 -431.636978) (xy 343.182883 -431.629485) (xy 343.163313 -431.615234) (xy 343.149117 -431.595625)
			(xy 343.141689 -431.572584) (xy 343.1413 -431.560478) (xy 342.23452 -431.560478) (xy 342.23452 -432.560476)
			(xy 342.234067 -432.572556) (xy 342.226607 -432.595536) (xy 342.212411 -432.615086) (xy 342.192868 -432.629291)
			(xy 342.169892 -432.636761) (xy 342.157812 -432.637184) (xy 341.218012 -432.637184) (xy 341.205928 -432.636777)
			(xy 341.182941 -432.629309) (xy 341.163389 -432.615103) (xy 341.149185 -432.595548) (xy 341.141722 -432.572561)
			(xy 341.141304 -432.560476) (xy 340.207182 -432.560476) (xy 340.212522 -432.564367) (xy 340.226717 -432.583988)
			(xy 340.234139 -432.60704) (xy 340.234524 -432.61915) (xy 340.234524 -435.160674) (xy 340.23407 -435.172766)
			(xy 340.226616 -435.195772) (xy 340.212427 -435.215355) (xy 340.192889 -435.229605) (xy 340.169906 -435.237131)
			(xy 340.157816 -435.237636) (xy 339.218016 -435.237636) (xy 339.205912 -435.23717) (xy 339.182891 -435.22968)
			(xy 339.163321 -435.21543) (xy 339.149124 -435.195821) (xy 339.141697 -435.172779) (xy 339.141308 -435.160674)
			(xy 338.234528 -435.160674) (xy 338.234528 -436.160672) (xy 338.234064 -436.172751) (xy 338.226606 -436.19573)
			(xy 338.212413 -436.215279) (xy 338.192873 -436.229484) (xy 338.169899 -436.236956) (xy 338.15782 -436.23738)
			(xy 337.21802 -436.23738) (xy 337.205936 -436.23697) (xy 337.182949 -436.229504) (xy 337.163396 -436.215299)
			(xy 337.149192 -436.195744) (xy 337.141729 -436.172756) (xy 337.141312 -436.160672) (xy 336.20712 -436.160672)
			(xy 336.212401 -436.16451) (xy 336.226595 -436.184049) (xy 336.234059 -436.207017) (xy 336.234532 -436.219092)
			(xy 336.234532 -438.760616) (xy 336.23405 -438.772689) (xy 336.226586 -438.795653) (xy 336.212393 -438.815187)
			(xy 336.19286 -438.829382) (xy 336.169897 -438.836848) (xy 336.157824 -438.837324) (xy 335.218024 -438.837324)
			(xy 335.205944 -438.836867) (xy 335.182965 -438.829408) (xy 335.163416 -438.815213) (xy 335.14921 -438.795671)
			(xy 335.141739 -438.772696) (xy 335.141316 -438.760616) (xy 334.234536 -438.760616) (xy 334.234536 -439.760614)
			(xy 337.141312 -439.760614) (xy 337.141312 -437.21909) (xy 337.141799 -437.207003) (xy 337.149255 -437.184007)
			(xy 337.163437 -437.164429) (xy 337.182965 -437.150178) (xy 337.205934 -437.142641) (xy 337.21802 -437.142128)
			(xy 338.15782 -437.142128) (xy 338.169933 -437.1425) (xy 338.192965 -437.150008) (xy 338.212541 -437.16428)
			(xy 338.226734 -437.183913) (xy 338.234149 -437.206976) (xy 338.234528 -437.21909) (xy 338.234528 -438.760616)
			(xy 339.141308 -438.760616) (xy 339.141308 -436.219092) (xy 339.141706 -436.207007) (xy 339.149178 -436.184021)
			(xy 339.163387 -436.16447) (xy 339.182943 -436.150267) (xy 339.205931 -436.142802) (xy 339.218016 -436.142384)
			(xy 340.157816 -436.142384) (xy 340.169891 -436.142851) (xy 340.192857 -436.150317) (xy 340.207107 -436.160672)
			(xy 341.141304 -436.160672) (xy 341.141304 -433.619148) (xy 341.141754 -433.607067) (xy 341.14921 -433.584083)
			(xy 341.163406 -433.564531) (xy 341.182951 -433.550326) (xy 341.205931 -433.542859) (xy 341.218012 -433.54244)
			(xy 342.157812 -433.54244) (xy 342.1699 -433.542803) (xy 342.192891 -433.55028) (xy 342.212446 -433.564497)
			(xy 342.226648 -433.584062) (xy 342.234106 -433.60706) (xy 342.23452 -433.619148) (xy 342.23452 -435.160674)
			(xy 343.1413 -435.160674) (xy 343.1413 -432.61915) (xy 343.141849 -432.607067) (xy 343.149287 -432.584075)
			(xy 343.163454 -432.564497) (xy 343.182968 -432.550244) (xy 343.205927 -432.542703) (xy 343.218008 -432.542188)
			(xy 344.157808 -432.542188) (xy 344.169916 -432.542609) (xy 344.192942 -432.550109) (xy 344.20717 -432.560476)
			(xy 345.141296 -432.560476) (xy 345.141296 -430.018952) (xy 345.141723 -430.006875) (xy 345.149199 -429.983905)
			(xy 345.163405 -429.964368) (xy 345.182952 -429.950176) (xy 345.205926 -429.942715) (xy 345.218004 -429.942244)
			(xy 346.157804 -429.942244) (xy 346.169874 -429.94276) (xy 346.192833 -429.950218) (xy 346.212366 -429.964403)
			(xy 346.226562 -429.983927) (xy 346.234033 -430.006882) (xy 346.234512 -430.018952) (xy 346.234512 -431.360072)
			(xy 356.154736 -431.360072) (xy 356.155234 -431.275192) (xy 356.163191 -431.105619) (xy 356.179087 -430.936605)
			(xy 356.202888 -430.768522) (xy 356.234542 -430.601739) (xy 356.273978 -430.436623) (xy 356.32111 -430.273538)
			(xy 356.375834 -430.11284) (xy 356.438031 -429.954885) (xy 356.507563 -429.800018) (xy 356.584278 -429.648581)
			(xy 356.668006 -429.500905) (xy 356.758564 -429.357317) (xy 356.855753 -429.218131) (xy 356.95936 -429.083654)
			(xy 357.069155 -428.954181) (xy 357.184899 -428.829996) (xy 357.306336 -428.711373) (xy 357.4332 -428.598572)
			(xy 357.565211 -428.491842) (xy 357.702081 -428.391417) (xy 357.843506 -428.297518) (xy 357.989178 -428.21035)
			(xy 358.138776 -428.130107) (xy 358.29197 -428.056963) (xy 358.448424 -427.991081) (xy 358.607794 -427.932604)
			(xy 358.76973 -427.881662) (xy 358.933876 -427.838366) (xy 359.099871 -427.802811) (xy 359.26735 -427.775076)
			(xy 359.435945 -427.755222) (xy 359.605285 -427.743292) (xy 359.774998 -427.739313) (xy 359.944711 -427.743292)
			(xy 360.114051 -427.755222) (xy 360.282646 -427.775076) (xy 360.450125 -427.802811) (xy 360.61612 -427.838366)
			(xy 360.780266 -427.881662) (xy 360.942202 -427.932604) (xy 361.018326 -427.960536) (xy 381.2413 -427.960536)
			(xy 381.2413 -425.419012) (xy 381.241723 -425.406929) (xy 381.249188 -425.383946) (xy 381.263392 -425.364394)
			(xy 381.282942 -425.35019) (xy 381.305925 -425.342724) (xy 381.318008 -425.342304) (xy 382.257808 -425.342304)
			(xy 382.269892 -425.342706) (xy 382.292877 -425.350177) (xy 382.312429 -425.364386) (xy 382.326632 -425.383941)
			(xy 382.334097 -425.406928) (xy 382.334516 -425.419012) (xy 382.334516 -427.960536) (xy 382.334067 -427.972612)
			(xy 382.326595 -427.995579) (xy 382.312395 -428.015115) (xy 382.292854 -428.029308) (xy 382.269884 -428.036771)
			(xy 382.257808 -428.037244) (xy 381.318008 -428.037244) (xy 381.305937 -428.03673) (xy 381.282977 -428.029274)
			(xy 381.263443 -428.015089) (xy 381.249247 -427.995563) (xy 381.241777 -427.972606) (xy 381.2413 -427.960536)
			(xy 361.018326 -427.960536) (xy 361.101572 -427.991081) (xy 361.258026 -428.056963) (xy 361.41122 -428.130107)
			(xy 361.560818 -428.21035) (xy 361.70649 -428.297518) (xy 361.847915 -428.391417) (xy 361.984785 -428.491842)
			(xy 362.116796 -428.598572) (xy 362.24366 -428.711373) (xy 362.365097 -428.829996) (xy 362.480841 -428.954181)
			(xy 362.590636 -429.083654) (xy 362.694243 -429.218131) (xy 362.791432 -429.357317) (xy 362.88199 -429.500905)
			(xy 362.965718 -429.648581) (xy 363.042433 -429.800018) (xy 363.111965 -429.954885) (xy 363.174162 -430.11284)
			(xy 363.228886 -430.273538) (xy 363.276018 -430.436623) (xy 363.315454 -430.601739) (xy 363.347108 -430.768522)
			(xy 363.370909 -430.936605) (xy 363.386805 -431.105619) (xy 363.394762 -431.275192) (xy 363.39526 -431.360072)
			(xy 363.394788 -431.445675) (xy 363.389359 -431.560478) (xy 381.2413 -431.560478) (xy 381.2413 -429.018954)
			(xy 381.241767 -429.006866) (xy 381.249232 -428.983871) (xy 381.26342 -428.964295) (xy 381.28295 -428.950044)
			(xy 381.305922 -428.942507) (xy 381.318008 -428.941992) (xy 382.257808 -428.941992) (xy 382.269917 -428.942409)
			(xy 382.292943 -428.94991) (xy 382.307523 -428.960534) (xy 383.241296 -428.960534) (xy 383.241296 -426.41901)
			(xy 383.241815 -426.406925) (xy 383.249264 -426.383932) (xy 383.263439 -426.364356) (xy 383.282958 -426.350104)
			(xy 383.305921 -426.342564) (xy 383.318004 -426.342048) (xy 384.257804 -426.342048) (xy 384.269908 -426.342512)
			(xy 384.292927 -426.350006) (xy 384.312495 -426.364257) (xy 384.326691 -426.383866) (xy 384.334121 -426.406905)
			(xy 384.334512 -426.41901) (xy 384.334512 -427.960536) (xy 385.241292 -427.960536) (xy 385.241292 -425.419012)
			(xy 385.241723 -425.40693) (xy 385.249187 -425.383948) (xy 385.263389 -425.364397) (xy 385.282937 -425.350193)
			(xy 385.305918 -425.342725) (xy 385.318 -425.342304) (xy 386.2578 -425.342304) (xy 386.269884 -425.342713)
			(xy 386.292869 -425.350182) (xy 386.31242 -425.364388) (xy 386.326624 -425.383942) (xy 386.334089 -425.406928)
			(xy 386.334508 -425.419012) (xy 386.334508 -427.960536) (xy 386.334067 -427.972612) (xy 386.326594 -427.995581)
			(xy 386.312392 -428.015117) (xy 386.292849 -428.029311) (xy 386.269877 -428.036772) (xy 386.2578 -428.037244)
			(xy 385.318 -428.037244) (xy 385.305929 -428.036736) (xy 385.282968 -428.029278) (xy 385.263434 -428.015092)
			(xy 385.249238 -427.995564) (xy 385.241769 -427.972607) (xy 385.241292 -427.960536) (xy 384.334512 -427.960536)
			(xy 384.334512 -428.960534) (xy 384.334121 -428.97263) (xy 384.326649 -428.99564) (xy 384.312444 -429.015223)
			(xy 384.292892 -429.029471) (xy 384.269899 -429.036994) (xy 384.257804 -429.037496) (xy 383.318004 -429.037496)
			(xy 383.305895 -429.03708) (xy 383.282867 -429.029582) (xy 383.263293 -429.01532) (xy 383.249099 -428.995698)
			(xy 383.241679 -428.972644) (xy 383.241296 -428.960534) (xy 382.307523 -428.960534) (xy 382.312515 -428.964172)
			(xy 382.32671 -428.983792) (xy 382.334132 -429.006844) (xy 382.334516 -429.018954) (xy 382.334516 -431.560478)
			(xy 382.334073 -431.572571) (xy 382.326617 -431.595578) (xy 382.312426 -431.615162) (xy 382.292884 -431.629412)
			(xy 382.269899 -431.636937) (xy 382.257808 -431.63744) (xy 381.318008 -431.63744) (xy 381.305904 -431.636978)
			(xy 381.282883 -431.629485) (xy 381.263313 -431.615234) (xy 381.249117 -431.595625) (xy 381.241689 -431.572584)
			(xy 381.2413 -431.560478) (xy 363.389359 -431.560478) (xy 363.386701 -431.616689) (xy 363.370537 -431.787129)
			(xy 363.346334 -431.956615) (xy 363.314145 -432.124767) (xy 363.274043 -432.291209) (xy 363.226117 -432.455569)
			(xy 363.170474 -432.61748) (xy 363.107239 -432.776579) (xy 363.036553 -432.932511) (xy 362.958574 -433.084927)
			(xy 362.873477 -433.233486) (xy 362.781452 -433.377855) (xy 362.682704 -433.517713) (xy 362.577455 -433.652746)
			(xy 362.46594 -433.782652) (xy 362.348408 -433.907141) (xy 362.225123 -434.025934) (xy 362.096359 -434.138766)
			(xy 361.962404 -434.245385) (xy 361.82356 -434.345551) (xy 361.680135 -434.439042) (xy 361.53245 -434.525647)
			(xy 361.380836 -434.605174) (xy 361.225632 -434.677444) (xy 361.146598 -434.710332) (xy 361.138713 -434.713995)
			(xy 361.125816 -434.725637) (xy 361.117551 -434.740919) (xy 361.115864 -434.749448) (xy 361.100116 -434.849016)
			(xy 361.109514 -434.873654) (xy 361.119928 -434.88229) (xy 361.169374 -434.924299) (xy 361.263563 -435.013553)
			(xy 361.352051 -435.108462) (xy 361.394803 -435.16042) (xy 381.2413 -435.16042) (xy 381.2413 -432.618896)
			(xy 381.241709 -432.606812) (xy 381.249179 -432.583828) (xy 381.263386 -432.564277) (xy 381.282939 -432.550073)
			(xy 381.305924 -432.542607) (xy 381.318008 -432.542188) (xy 382.257808 -432.542188) (xy 382.269883 -432.542657)
			(xy 382.292849 -432.550122) (xy 382.3071 -432.560476) (xy 383.241296 -432.560476) (xy 383.241296 -430.018952)
			(xy 383.241723 -430.006875) (xy 383.249199 -429.983905) (xy 383.263405 -429.964368) (xy 383.282952 -429.950176)
			(xy 383.305926 -429.942715) (xy 383.318004 -429.942244) (xy 384.257804 -429.942244) (xy 384.269874 -429.94276)
			(xy 384.292833 -429.950218) (xy 384.312366 -429.964403) (xy 384.326562 -429.983927) (xy 384.334033 -430.006882)
			(xy 384.334512 -430.018952) (xy 384.334512 -431.560478) (xy 385.241292 -431.560478) (xy 385.241292 -429.018954)
			(xy 385.241767 -429.006867) (xy 385.249231 -428.983873) (xy 385.263417 -428.964298) (xy 385.282945 -428.950047)
			(xy 385.305914 -428.942508) (xy 385.318 -428.941992) (xy 386.2578 -428.941992) (xy 386.269908 -428.942416)
			(xy 386.292934 -428.949914) (xy 386.307511 -428.960534) (xy 387.241288 -428.960534) (xy 387.241288 -426.41901)
			(xy 387.241717 -426.406916) (xy 387.249177 -426.383908) (xy 387.263371 -426.364324) (xy 387.282916 -426.350075)
			(xy 387.305904 -426.342551) (xy 387.317996 -426.342048) (xy 388.257796 -426.342048) (xy 388.269899 -426.342519)
			(xy 388.292918 -426.350011) (xy 388.312487 -426.36426) (xy 388.326683 -426.383867) (xy 388.334113 -426.406905)
			(xy 388.334504 -426.41901) (xy 388.334504 -427.960536) (xy 389.241284 -427.960536) (xy 389.241284 -425.419012)
			(xy 389.241723 -425.406931) (xy 389.249186 -425.38395) (xy 389.263386 -425.3644) (xy 389.282932 -425.350195)
			(xy 389.305911 -425.342726) (xy 389.317992 -425.342304) (xy 390.257792 -425.342304) (xy 390.269876 -425.342719)
			(xy 390.29286 -425.350186) (xy 390.312412 -425.364391) (xy 390.326616 -425.383943) (xy 390.334081 -425.406928)
			(xy 390.3345 -425.419012) (xy 390.3345 -427.960536) (xy 390.334067 -427.972613) (xy 390.326593 -427.995583)
			(xy 390.312389 -428.01512) (xy 390.292844 -428.029313) (xy 390.26987 -428.036773) (xy 390.257792 -428.037244)
			(xy 389.317992 -428.037244) (xy 389.305921 -428.036743) (xy 389.282959 -428.029283) (xy 389.263426 -428.015094)
			(xy 389.24923 -427.995566) (xy 389.241761 -427.972607) (xy 389.241284 -427.960536) (xy 388.334504 -427.960536)
			(xy 388.334504 -428.960534) (xy 388.334023 -428.972621) (xy 388.326562 -428.995615) (xy 388.312377 -429.015191)
			(xy 388.29285 -429.029442) (xy 388.269881 -429.036981) (xy 388.257796 -429.037496) (xy 387.317996 -429.037496)
			(xy 387.305887 -429.037087) (xy 387.282858 -429.029586) (xy 387.263285 -429.015323) (xy 387.249091 -428.995699)
			(xy 387.241671 -428.972645) (xy 387.241288 -428.960534) (xy 386.307511 -428.960534) (xy 386.312507 -428.964174)
			(xy 386.326701 -428.983794) (xy 386.334124 -429.006845) (xy 386.334508 -429.018954) (xy 386.334508 -431.560478)
			(xy 386.333975 -431.572562) (xy 386.32653 -431.595553) (xy 386.312359 -431.61513) (xy 386.292842 -431.629383)
			(xy 386.269882 -431.636924) (xy 386.2578 -431.63744) (xy 385.318 -431.63744) (xy 385.305895 -431.636984)
			(xy 385.282875 -431.62949) (xy 385.263305 -431.615237) (xy 385.249109 -431.595626) (xy 385.241681 -431.572584)
			(xy 385.241292 -431.560478) (xy 384.334512 -431.560478) (xy 384.334512 -432.560476) (xy 384.334067 -432.572557)
			(xy 384.326606 -432.595538) (xy 384.312409 -432.615089) (xy 384.292863 -432.629294) (xy 384.269885 -432.636762)
			(xy 384.257804 -432.637184) (xy 383.318004 -432.637184) (xy 383.305919 -432.636784) (xy 383.282932 -432.629314)
			(xy 383.26338 -432.615106) (xy 383.249176 -432.59555) (xy 383.241713 -432.572561) (xy 383.241296 -432.560476)
			(xy 382.3071 -432.560476) (xy 382.312386 -432.564317) (xy 382.32658 -432.583854) (xy 382.334043 -432.606821)
			(xy 382.334516 -432.618896) (xy 382.334516 -435.16042) (xy 382.334053 -435.172495) (xy 382.326586 -435.195461)
			(xy 382.312389 -435.214997) (xy 382.29285 -435.229191) (xy 382.269883 -435.236655) (xy 382.257808 -435.237128)
			(xy 381.318008 -435.237128) (xy 381.305936 -435.236629) (xy 381.282972 -435.229171) (xy 381.263437 -435.214983)
			(xy 381.249241 -435.195453) (xy 381.241775 -435.172492) (xy 381.2413 -435.16042) (xy 361.394803 -435.16042)
			(xy 361.434498 -435.208663) (xy 361.510589 -435.313772) (xy 361.580032 -435.423387) (xy 361.642562 -435.537087)
			(xy 361.697938 -435.654438) (xy 361.74595 -435.77499) (xy 361.786412 -435.89828) (xy 361.81917 -436.023838)
			(xy 361.844098 -436.151181) (xy 361.861101 -436.279823) (xy 361.870114 -436.40927) (xy 361.871103 -436.539027)
			(xy 361.864062 -436.668596) (xy 361.849021 -436.797482) (xy 361.826035 -436.92519) (xy 361.795194 -437.051232)
			(xy 361.756614 -437.175125) (xy 361.710445 -437.296394) (xy 361.656862 -437.414574) (xy 361.596072 -437.529214)
			(xy 361.528306 -437.639874) (xy 361.453825 -437.74613) (xy 361.372914 -437.847575) (xy 361.285882 -437.943821)
			(xy 361.193064 -438.034499) (xy 361.094814 -438.119261) (xy 360.991508 -438.197784) (xy 360.883543 -438.269766)
			(xy 360.771333 -438.334931) (xy 360.655306 -438.39303) (xy 360.535907 -438.443841) (xy 360.413594 -438.487169)
			(xy 360.288835 -438.522847) (xy 360.162108 -438.550739) (xy 360.033898 -438.570739) (xy 359.904696 -438.58277)
			(xy 359.774998 -438.586785) (xy 359.6453 -438.58277) (xy 359.516098 -438.570739) (xy 359.387888 -438.550739)
			(xy 359.261161 -438.522847) (xy 359.136402 -438.487169) (xy 359.014089 -438.443841) (xy 358.89469 -438.39303)
			(xy 358.778663 -438.334931) (xy 358.666453 -438.269766) (xy 358.558488 -438.197784) (xy 358.455182 -438.119261)
			(xy 358.356932 -438.034499) (xy 358.264114 -437.943821) (xy 358.177082 -437.847575) (xy 358.096171 -437.74613)
			(xy 358.02169 -437.639874) (xy 357.953924 -437.529214) (xy 357.893134 -437.414574) (xy 357.839551 -437.296394)
			(xy 357.793382 -437.175125) (xy 357.754802 -437.051232) (xy 357.723961 -436.92519) (xy 357.700975 -436.797482)
			(xy 357.685934 -436.668596) (xy 357.678893 -436.539027) (xy 357.679882 -436.40927) (xy 357.688895 -436.279823)
			(xy 357.705898 -436.151181) (xy 357.730826 -436.023838) (xy 357.763584 -435.89828) (xy 357.804046 -435.77499)
			(xy 357.852058 -435.654438) (xy 357.907434 -435.537087) (xy 357.969964 -435.423387) (xy 358.039407 -435.313772)
			(xy 358.115498 -435.208663) (xy 358.197945 -435.108462) (xy 358.286433 -435.013553) (xy 358.380622 -434.924299)
			(xy 358.430068 -434.88229) (xy 358.440228 -434.873908) (xy 358.449626 -434.849016) (xy 358.4321 -434.73624)
			(xy 358.415844 -434.715412) (xy 358.403398 -434.710332) (xy 358.325295 -434.677853) (xy 358.1719 -434.606515)
			(xy 358.022004 -434.52809) (xy 357.875935 -434.44275) (xy 357.734012 -434.350681) (xy 357.596544 -434.252083)
			(xy 357.463831 -434.147172) (xy 357.336162 -434.036176) (xy 357.213818 -433.919339) (xy 357.097064 -433.796915)
			(xy 356.986156 -433.669172) (xy 356.881335 -433.536387) (xy 356.782831 -433.398852) (xy 356.690858 -433.256866)
			(xy 356.605617 -433.110739) (xy 356.527295 -432.96079) (xy 356.456061 -432.807346) (xy 356.392073 -432.650743)
			(xy 356.335468 -432.491322) (xy 356.286372 -432.329431) (xy 356.244891 -432.165424) (xy 356.211115 -431.999658)
			(xy 356.185119 -431.832496) (xy 356.166958 -431.664301) (xy 356.156674 -431.495443) (xy 356.15499 -431.410872)
			(xy 356.155244 -431.410872) (xy 356.154736 -431.360072) (xy 346.234512 -431.360072) (xy 346.234512 -432.560476)
			(xy 346.234067 -432.572557) (xy 346.226606 -432.595538) (xy 346.212409 -432.615089) (xy 346.192863 -432.629294)
			(xy 346.169885 -432.636762) (xy 346.157804 -432.637184) (xy 345.218004 -432.637184) (xy 345.205919 -432.636784)
			(xy 345.182932 -432.629314) (xy 345.16338 -432.615106) (xy 345.149176 -432.59555) (xy 345.141713 -432.572561)
			(xy 345.141296 -432.560476) (xy 344.20717 -432.560476) (xy 344.212514 -432.56437) (xy 344.226708 -432.58399)
			(xy 344.234131 -432.607041) (xy 344.234516 -432.61915) (xy 344.234516 -435.160674) (xy 344.23407 -435.172767)
			(xy 344.226615 -435.195774) (xy 344.212424 -435.215358) (xy 344.192883 -435.229608) (xy 344.169899 -435.237133)
			(xy 344.157808 -435.237636) (xy 343.218008 -435.237636) (xy 343.205903 -435.237178) (xy 343.182882 -435.229685)
			(xy 343.163312 -435.215433) (xy 343.149116 -435.195822) (xy 343.141688 -435.17278) (xy 343.1413 -435.160674)
			(xy 342.23452 -435.160674) (xy 342.23452 -436.160672) (xy 342.234064 -436.172752) (xy 342.226605 -436.195732)
			(xy 342.21241 -436.215281) (xy 342.192868 -436.229487) (xy 342.169892 -436.236957) (xy 342.157812 -436.23738)
			(xy 341.218012 -436.23738) (xy 341.205927 -436.236976) (xy 341.18294 -436.229509) (xy 341.163387 -436.215301)
			(xy 341.149184 -436.195746) (xy 341.141721 -436.172757) (xy 341.141304 -436.160672) (xy 340.207107 -436.160672)
			(xy 340.212393 -436.164513) (xy 340.226587 -436.18405) (xy 340.234051 -436.207017) (xy 340.234524 -436.219092)
			(xy 340.234524 -438.760616) (xy 340.23405 -438.77269) (xy 340.226585 -438.795655) (xy 340.21239 -438.81519)
			(xy 340.192855 -438.829385) (xy 340.16989 -438.83685) (xy 340.157816 -438.837324) (xy 339.218016 -438.837324)
			(xy 339.205944 -438.836822) (xy 339.18298 -438.829366) (xy 339.163444 -438.815179) (xy 339.149248 -438.795649)
			(xy 339.141783 -438.772688) (xy 339.141308 -438.760616) (xy 338.234528 -438.760616) (xy 338.234528 -439.760614)
			(xy 341.141304 -439.760614) (xy 341.141304 -437.21909) (xy 341.141798 -437.207004) (xy 341.149253 -437.184009)
			(xy 341.163434 -437.164432) (xy 341.18296 -437.150181) (xy 341.205927 -437.142643) (xy 341.218012 -437.142128)
			(xy 342.157812 -437.142128) (xy 342.169924 -437.142506) (xy 342.192957 -437.150012) (xy 342.212532 -437.164283)
			(xy 342.226725 -437.183914) (xy 342.234141 -437.206976) (xy 342.23452 -437.21909) (xy 342.23452 -438.760616)
			(xy 343.1413 -438.760616) (xy 343.1413 -436.219092) (xy 343.141758 -436.207016) (xy 343.149223 -436.184047)
			(xy 343.163421 -436.16451) (xy 343.182962 -436.150316) (xy 343.205932 -436.142855) (xy 343.218008 -436.142384)
			(xy 344.157808 -436.142384) (xy 344.169882 -436.142857) (xy 344.192848 -436.150321) (xy 344.207094 -436.160672)
			(xy 345.141296 -436.160672) (xy 345.141296 -433.619148) (xy 345.141754 -433.607067) (xy 345.149208 -433.584086)
			(xy 345.163403 -433.564534) (xy 345.182946 -433.550329) (xy 345.205924 -433.542861) (xy 345.218004 -433.54244)
			(xy 346.157804 -433.54244) (xy 346.169892 -433.54281) (xy 346.192883 -433.550284) (xy 346.212437 -433.5645)
			(xy 346.226639 -433.584064) (xy 346.234098 -433.60706) (xy 346.234512 -433.619148) (xy 346.234512 -436.160672)
			(xy 346.234063 -436.172753) (xy 346.226604 -436.195734) (xy 346.212407 -436.215284) (xy 346.192863 -436.229489)
			(xy 346.169885 -436.236958) (xy 346.157804 -436.23738) (xy 345.218004 -436.23738) (xy 345.205919 -436.236984)
			(xy 345.182931 -436.229514) (xy 345.163378 -436.215304) (xy 345.149175 -436.195747) (xy 345.141712 -436.172757)
			(xy 345.141296 -436.160672) (xy 344.207094 -436.160672) (xy 344.212384 -436.164516) (xy 344.226579 -436.184052)
			(xy 344.234043 -436.207018) (xy 344.234516 -436.219092) (xy 344.234516 -438.760616) (xy 344.234049 -438.772691)
			(xy 344.226583 -438.795657) (xy 344.212387 -438.815193) (xy 344.19285 -438.829387) (xy 344.169883 -438.836851)
			(xy 344.157808 -438.837324) (xy 343.218008 -438.837324) (xy 343.205935 -438.836829) (xy 343.182971 -438.829371)
			(xy 343.163435 -438.815182) (xy 343.14924 -438.79565) (xy 343.141775 -438.772688) (xy 343.1413 -438.760616)
			(xy 342.23452 -438.760616) (xy 342.23452 -439.760614) (xy 345.141296 -439.760614) (xy 345.141296 -437.21909)
			(xy 345.141798 -437.207004) (xy 345.149252 -437.184011) (xy 345.163431 -437.164435) (xy 345.182955 -437.150183)
			(xy 345.20592 -437.142644) (xy 345.218004 -437.142128) (xy 346.157804 -437.142128) (xy 346.169916 -437.142513)
			(xy 346.192948 -437.150017) (xy 346.212524 -437.164286) (xy 346.226717 -437.183916) (xy 346.234133 -437.206977)
			(xy 346.234512 -437.21909) (xy 346.234512 -438.760362) (xy 381.2413 -438.760362) (xy 381.2413 -436.218838)
			(xy 381.241839 -436.206754) (xy 381.24928 -436.183762) (xy 381.26345 -436.164185) (xy 381.282966 -436.149931)
			(xy 381.305926 -436.142391) (xy 381.318008 -436.141876) (xy 382.257808 -436.141876) (xy 382.269915 -436.142309)
			(xy 382.292938 -436.149808) (xy 382.307502 -436.160418) (xy 383.241296 -436.160418) (xy 383.241296 -433.618894)
			(xy 383.241802 -433.606809) (xy 383.249255 -433.583815) (xy 383.263433 -433.564239) (xy 383.282955 -433.549987)
			(xy 383.30592 -433.542448) (xy 383.318004 -433.541932) (xy 384.257804 -433.541932) (xy 384.269916 -433.542313)
			(xy 384.292949 -433.549818) (xy 384.312525 -433.564087) (xy 384.326718 -433.583718) (xy 384.334133 -433.60678)
			(xy 384.334512 -433.618894) (xy 384.334512 -435.16042) (xy 385.241292 -435.16042) (xy 385.241292 -432.618896)
			(xy 385.241761 -432.606821) (xy 385.249224 -432.583854) (xy 385.26342 -432.564317) (xy 385.282958 -432.550123)
			(xy 385.305925 -432.54266) (xy 385.318 -432.542188) (xy 386.2578 -432.542188) (xy 386.269874 -432.542664)
			(xy 386.292841 -432.550126) (xy 386.307086 -432.560476) (xy 387.241288 -432.560476) (xy 387.241288 -430.018952)
			(xy 387.241723 -430.006875) (xy 387.249198 -429.983907) (xy 387.263403 -429.964371) (xy 387.282947 -429.950178)
			(xy 387.305919 -429.942716) (xy 387.317996 -429.942244) (xy 388.257796 -429.942244) (xy 388.269866 -429.942767)
			(xy 388.292824 -429.950222) (xy 388.312357 -429.964406) (xy 388.326554 -429.983929) (xy 388.334025 -430.006883)
			(xy 388.334504 -430.018952) (xy 388.334504 -431.560478) (xy 389.241284 -431.560478) (xy 389.241284 -429.018954)
			(xy 389.241669 -429.006858) (xy 389.249144 -428.983848) (xy 389.26335 -428.964265) (xy 389.282903 -428.950018)
			(xy 389.305897 -428.942495) (xy 389.317992 -428.941992) (xy 390.257792 -428.941992) (xy 390.2699 -428.942423)
			(xy 390.292925 -428.949919) (xy 390.307497 -428.960534) (xy 391.24128 -428.960534) (xy 391.24128 -426.41901)
			(xy 391.241717 -426.406917) (xy 391.249176 -426.38391) (xy 391.263369 -426.364326) (xy 391.282911 -426.350077)
			(xy 391.305896 -426.342552) (xy 391.317988 -426.342048) (xy 392.257788 -426.342048) (xy 392.269891 -426.342526)
			(xy 392.292909 -426.350016) (xy 392.312478 -426.364263) (xy 392.326675 -426.383869) (xy 392.334105 -426.406906)
			(xy 392.334496 -426.41901) (xy 392.334496 -427.960536) (xy 393.241276 -427.960536) (xy 393.241276 -425.419012)
			(xy 393.241774 -425.40694) (xy 393.249231 -425.383976) (xy 393.26342 -425.36444) (xy 393.28295 -425.350244)
			(xy 393.305912 -425.342779) (xy 393.317984 -425.342304) (xy 394.257784 -425.342304) (xy 394.269867 -425.342727)
			(xy 394.292851 -425.350191) (xy 394.312403 -425.364394) (xy 394.326607 -425.383945) (xy 394.334073 -425.406929)
			(xy 394.334492 -425.419012) (xy 394.334492 -427.960536) (xy 394.334066 -427.972614) (xy 394.326592 -427.995585)
			(xy 394.312386 -428.015123) (xy 394.292839 -428.029316) (xy 394.269862 -428.036775) (xy 394.257784 -428.037244)
			(xy 393.317984 -428.037244) (xy 393.305912 -428.03675) (xy 393.282951 -428.029287) (xy 393.263417 -428.015097)
			(xy 393.249222 -427.995567) (xy 393.241753 -427.972608) (xy 393.241276 -427.960536) (xy 392.334496 -427.960536)
			(xy 392.334496 -428.960534) (xy 392.334022 -428.972622) (xy 392.326561 -428.995617) (xy 392.312374 -429.015194)
			(xy 392.292845 -429.029444) (xy 392.269874 -429.036982) (xy 392.257788 -429.037496) (xy 391.317988 -429.037496)
			(xy 391.305878 -429.037094) (xy 391.28285 -429.029591) (xy 391.263276 -429.015326) (xy 391.249082 -428.995701)
			(xy 391.241663 -428.972645) (xy 391.24128 -428.960534) (xy 390.307497 -428.960534) (xy 390.312498 -428.964177)
			(xy 390.326693 -428.983795) (xy 390.334116 -429.006845) (xy 390.3345 -429.018954) (xy 390.3345 -431.560478)
			(xy 390.333975 -431.572562) (xy 390.326529 -431.595556) (xy 390.312356 -431.615132) (xy 390.292837 -431.629385)
			(xy 390.269874 -431.636925) (xy 390.257792 -431.63744) (xy 389.317992 -431.63744) (xy 389.305887 -431.636991)
			(xy 389.282866 -431.629494) (xy 389.263296 -431.61524) (xy 389.249101 -431.595628) (xy 389.241673 -431.572585)
			(xy 389.241284 -431.560478) (xy 388.334504 -431.560478) (xy 388.334504 -432.560476) (xy 388.334067 -432.572558)
			(xy 388.326605 -432.59554) (xy 388.312406 -432.615091) (xy 388.292858 -432.629296) (xy 388.269878 -432.636764)
			(xy 388.257796 -432.637184) (xy 387.317996 -432.637184) (xy 387.305911 -432.636791) (xy 387.282924 -432.629319)
			(xy 387.263371 -432.615109) (xy 387.249168 -432.595551) (xy 387.241705 -432.572562) (xy 387.241288 -432.560476)
			(xy 386.307086 -432.560476) (xy 386.312377 -432.56432) (xy 386.326572 -432.583856) (xy 386.334035 -432.606822)
			(xy 386.334508 -432.618896) (xy 386.334508 -435.16042) (xy 386.334053 -435.172496) (xy 386.326585 -435.195463)
			(xy 386.312386 -435.215) (xy 386.292845 -435.229194) (xy 386.269876 -435.236656) (xy 386.2578 -435.237128)
			(xy 385.318 -435.237128) (xy 385.305927 -435.236636) (xy 385.282964 -435.229176) (xy 385.263428 -435.214986)
			(xy 385.249233 -435.195454) (xy 385.241767 -435.172492) (xy 385.241292 -435.16042) (xy 384.334512 -435.16042)
			(xy 384.334512 -436.160418) (xy 384.334107 -436.172513) (xy 384.32664 -436.195523) (xy 384.312439 -436.215106)
			(xy 384.292889 -436.229355) (xy 384.269898 -436.236878) (xy 384.257804 -436.23738) (xy 383.318004 -436.23738)
			(xy 383.305893 -436.23698) (xy 383.282863 -436.229479) (xy 383.263288 -436.215214) (xy 383.249094 -436.195588)
			(xy 383.241676 -436.17253) (xy 383.241296 -436.160418) (xy 382.307502 -436.160418) (xy 382.312509 -436.164066)
			(xy 382.326705 -436.183682) (xy 382.334129 -436.20673) (xy 382.334516 -436.218838) (xy 382.334516 -438.760362)
			(xy 382.334059 -438.772454) (xy 382.326608 -438.795461) (xy 382.31242 -438.815045) (xy 382.292881 -438.829295)
			(xy 382.269898 -438.836821) (xy 382.257808 -438.837324) (xy 381.318008 -438.837324) (xy 381.305902 -438.836877)
			(xy 381.282879 -438.829383) (xy 381.263308 -438.815129) (xy 381.249112 -438.795515) (xy 381.241687 -438.772469)
			(xy 381.2413 -438.760362) (xy 346.234512 -438.760362) (xy 346.234512 -439.76036) (xy 383.241296 -439.76036)
			(xy 383.241296 -437.218836) (xy 383.241743 -437.206755) (xy 383.249202 -437.183773) (xy 383.263399 -437.164221)
			(xy 383.282944 -437.150016) (xy 383.305923 -437.142548) (xy 383.318004 -437.142128) (xy 384.257804 -437.142128)
			(xy 384.269891 -437.14251) (xy 384.29288 -437.149983) (xy 384.312433 -437.164196) (xy 384.326636 -437.183756)
			(xy 384.334097 -437.206749) (xy 384.334512 -437.218836) (xy 384.334512 -438.760362) (xy 385.241292 -438.760362)
			(xy 385.241292 -436.218838) (xy 385.241839 -436.206755) (xy 385.249279 -436.183764) (xy 385.263447 -436.164187)
			(xy 385.282961 -436.149934) (xy 385.305919 -436.142392) (xy 385.318 -436.141876) (xy 386.2578 -436.141876)
			(xy 386.269906 -436.142316) (xy 386.29293 -436.149812) (xy 386.307489 -436.160418) (xy 387.241288 -436.160418)
			(xy 387.241288 -433.618894) (xy 387.241703 -433.606799) (xy 387.249168 -433.583791) (xy 387.263366 -433.564207)
			(xy 387.282913 -433.549958) (xy 387.305903 -433.542435) (xy 387.317996 -433.541932) (xy 388.257796 -433.541932)
			(xy 388.269908 -433.54232) (xy 388.292941 -433.549822) (xy 388.312517 -433.56409) (xy 388.32671 -433.58372)
			(xy 388.334125 -433.606781) (xy 388.334504 -433.618894) (xy 388.334504 -435.16042) (xy 389.241284 -435.16042)
			(xy 389.241284 -432.618896) (xy 389.241761 -432.606822) (xy 389.249223 -432.583856) (xy 389.263417 -432.56432)
			(xy 389.282953 -432.550125) (xy 389.305918 -432.542661) (xy 389.317992 -432.542188) (xy 390.257792 -432.542188)
			(xy 390.269874 -432.542619) (xy 390.292856 -432.550084) (xy 390.307161 -432.560476) (xy 391.24128 -432.560476)
			(xy 391.24128 -430.018952) (xy 391.241723 -430.006876) (xy 391.249197 -429.983909) (xy 391.2634 -429.964374)
			(xy 391.282942 -429.950181) (xy 391.305912 -429.942717) (xy 391.317988 -429.942244) (xy 392.257788 -429.942244)
			(xy 392.269857 -429.942774) (xy 392.292816 -429.950227) (xy 392.312349 -429.964408) (xy 392.326546 -429.98393)
			(xy 392.334017 -430.006883) (xy 392.334496 -430.018952) (xy 392.334496 -431.560478) (xy 393.241276 -431.560478)
			(xy 393.241276 -429.018954) (xy 393.241669 -429.006858) (xy 393.249143 -428.98385) (xy 393.263347 -428.964268)
			(xy 393.282898 -428.95002) (xy 393.30589 -428.942496) (xy 393.317984 -428.941992) (xy 394.257784 -428.941992)
			(xy 394.269891 -428.94243) (xy 394.292917 -428.949924) (xy 394.307483 -428.960534) (xy 395.241272 -428.960534)
			(xy 395.241272 -426.41901) (xy 395.241717 -426.406918) (xy 395.249174 -426.383912) (xy 395.263366 -426.364329)
			(xy 395.282906 -426.35008) (xy 395.305889 -426.342553) (xy 395.31798 -426.342048) (xy 396.25778 -426.342048)
			(xy 396.269883 -426.342533) (xy 396.2929 -426.35002) (xy 396.312469 -426.364266) (xy 396.326666 -426.38387)
			(xy 396.334097 -426.406906) (xy 396.334488 -426.41901) (xy 396.334488 -427.960536) (xy 398.241012 -427.960536)
			(xy 398.241012 -425.419012) (xy 398.241427 -425.406903) (xy 398.248924 -425.383874) (xy 398.263186 -425.364299)
			(xy 398.282809 -425.350105) (xy 398.305863 -425.342686) (xy 398.317974 -425.342304) (xy 399.257774 -425.342304)
			(xy 399.269859 -425.342829) (xy 399.292852 -425.350274) (xy 399.31243 -425.364447) (xy 399.326682 -425.383966)
			(xy 399.334221 -425.406929) (xy 399.334736 -425.419012) (xy 399.334736 -427.960536) (xy 399.334315 -427.972643)
			(xy 399.32681 -427.995665) (xy 399.312548 -428.015235) (xy 399.29293 -428.029429) (xy 399.269883 -428.036856)
			(xy 399.257774 -428.037244) (xy 398.317974 -428.037244) (xy 398.305881 -428.036815) (xy 398.282877 -428.029349)
			(xy 398.263296 -428.015153) (xy 398.249047 -427.995611) (xy 398.241519 -427.972627) (xy 398.241012 -427.960536)
			(xy 396.334488 -427.960536) (xy 396.334488 -428.960534) (xy 396.334022 -428.972623) (xy 396.32656 -428.99562)
			(xy 396.312372 -429.015197) (xy 396.29284 -429.029447) (xy 396.269867 -429.036983) (xy 396.25778 -429.037496)
			(xy 395.31798 -429.037496) (xy 395.30587 -429.037101) (xy 395.282841 -429.029595) (xy 395.263268 -429.015328)
			(xy 395.249074 -428.995702) (xy 395.241655 -428.972646) (xy 395.241272 -428.960534) (xy 394.307483 -428.960534)
			(xy 394.312489 -428.96418) (xy 394.326685 -428.983797) (xy 394.334107 -429.006846) (xy 394.334492 -429.018954)
			(xy 394.334492 -431.560478) (xy 394.333974 -431.572563) (xy 394.326528 -431.595558) (xy 394.312353 -431.615135)
			(xy 394.292832 -431.629388) (xy 394.269867 -431.636926) (xy 394.257784 -431.63744) (xy 393.317984 -431.63744)
			(xy 393.305878 -431.636998) (xy 393.282857 -431.629499) (xy 393.263288 -431.615243) (xy 393.249092 -431.595629)
			(xy 393.241665 -431.572585) (xy 393.241276 -431.560478) (xy 392.334496 -431.560478) (xy 392.334496 -432.560476)
			(xy 392.334067 -432.572559) (xy 392.326604 -432.595543) (xy 392.312403 -432.615094) (xy 392.292853 -432.629299)
			(xy 392.269871 -432.636765) (xy 392.257788 -432.637184) (xy 391.317988 -432.637184) (xy 391.305902 -432.636797)
			(xy 391.282915 -432.629324) (xy 391.263363 -432.615112) (xy 391.24916 -432.595553) (xy 391.241697 -432.572562)
			(xy 391.24128 -432.560476) (xy 390.307161 -432.560476) (xy 390.312406 -432.564286) (xy 390.326611 -432.583833)
			(xy 390.334079 -432.606814) (xy 390.3345 -432.618896) (xy 390.3345 -435.16042) (xy 390.334053 -435.172496)
			(xy 390.326584 -435.195465) (xy 390.312383 -435.215003) (xy 390.29284 -435.229196) (xy 390.269869 -435.236657)
			(xy 390.257792 -435.237128) (xy 389.317992 -435.237128) (xy 389.305919 -435.236643) (xy 389.282955 -435.229181)
			(xy 389.26342 -435.214989) (xy 389.249225 -435.195456) (xy 389.241759 -435.172493) (xy 389.241284 -435.16042)
			(xy 388.334504 -435.16042) (xy 388.334504 -436.160418) (xy 388.334009 -436.172504) (xy 388.326553 -436.195498)
			(xy 388.312372 -436.215074) (xy 388.292847 -436.229325) (xy 388.26988 -436.236865) (xy 388.257796 -436.23738)
			(xy 387.317996 -436.23738) (xy 387.305885 -436.236987) (xy 387.282854 -436.229484) (xy 387.263279 -436.215217)
			(xy 387.249085 -436.195589) (xy 387.241668 -436.172531) (xy 387.241288 -436.160418) (xy 386.307489 -436.160418)
			(xy 386.312501 -436.164069) (xy 386.326696 -436.183684) (xy 386.334121 -436.20673) (xy 386.334508 -436.218838)
			(xy 386.334508 -438.760362) (xy 386.333961 -438.772445) (xy 386.326521 -438.795436) (xy 386.312353 -438.815013)
			(xy 386.292839 -438.829266) (xy 386.269881 -438.836808) (xy 386.2578 -438.837324) (xy 385.318 -438.837324)
			(xy 385.305894 -438.836884) (xy 385.28287 -438.829388) (xy 385.263299 -438.815131) (xy 385.249104 -438.795516)
			(xy 385.241679 -438.77247) (xy 385.241292 -438.760362) (xy 384.334512 -438.760362) (xy 384.334512 -439.76036)
			(xy 387.241288 -439.76036) (xy 387.241288 -437.218836) (xy 387.241743 -437.206756) (xy 387.2492 -437.183775)
			(xy 387.263396 -437.164224) (xy 387.282939 -437.150019) (xy 387.305916 -437.14255) (xy 387.317996 -437.142128)
			(xy 388.257796 -437.142128) (xy 388.269882 -437.142516) (xy 388.292871 -437.149987) (xy 388.312424 -437.164198)
			(xy 388.326627 -437.183758) (xy 388.334089 -437.20675) (xy 388.334504 -437.218836) (xy 388.334504 -438.760362)
			(xy 389.241284 -438.760362) (xy 389.241284 -436.218838) (xy 389.241741 -436.206746) (xy 389.249192 -436.183739)
			(xy 389.26338 -436.164155) (xy 389.282919 -436.149905) (xy 389.305902 -436.142379) (xy 389.317992 -436.141876)
			(xy 390.257792 -436.141876) (xy 390.269898 -436.142323) (xy 390.292921 -436.149817) (xy 390.307476 -436.160418)
			(xy 391.24128 -436.160418) (xy 391.24128 -433.618894) (xy 391.241703 -433.6068) (xy 391.249166 -433.583793)
			(xy 391.263363 -433.564209) (xy 391.282908 -433.549961) (xy 391.305896 -433.542436) (xy 391.317988 -433.541932)
			(xy 392.257788 -433.541932) (xy 392.269899 -433.542327) (xy 392.292932 -433.549827) (xy 392.312508 -433.564093)
			(xy 392.326702 -433.583721) (xy 392.334117 -433.606781) (xy 392.334496 -433.618894) (xy 392.334496 -435.16042)
			(xy 393.241276 -435.16042) (xy 393.241276 -432.618896) (xy 393.241761 -432.606823) (xy 393.249222 -432.583858)
			(xy 393.263414 -432.564323) (xy 393.282948 -432.550128) (xy 393.305911 -432.542663) (xy 393.317984 -432.542188)
			(xy 394.257784 -432.542188) (xy 394.269865 -432.542626) (xy 394.292847 -432.550089) (xy 394.307147 -432.560476)
			(xy 395.241272 -432.560476) (xy 395.241272 -430.018952) (xy 395.241723 -430.006877) (xy 395.249196 -429.983912)
			(xy 395.263397 -429.964377) (xy 395.282937 -429.950183) (xy 395.305905 -429.942718) (xy 395.31798 -429.942244)
			(xy 396.25778 -429.942244) (xy 396.269849 -429.94278) (xy 396.292807 -429.950232) (xy 396.31234 -429.964411)
			(xy 396.326537 -429.983932) (xy 396.334009 -430.006884) (xy 396.334488 -430.018952) (xy 396.334488 -431.560478)
			(xy 398.241012 -431.560478) (xy 398.241012 -429.018954) (xy 398.241472 -429.00684) (xy 398.248969 -428.983799)
			(xy 398.263215 -428.964201) (xy 398.282817 -428.94996) (xy 398.30586 -428.942469) (xy 398.317974 -428.941992)
			(xy 399.257774 -428.941992) (xy 399.269883 -428.942533) (xy 399.292917 -428.950008) (xy 399.307419 -428.960534)
			(xy 400.241008 -428.960534) (xy 400.241008 -426.41901) (xy 400.24152 -426.406899) (xy 400.249001 -426.383861)
			(xy 400.263233 -426.364262) (xy 400.282825 -426.350019) (xy 400.305859 -426.342526) (xy 400.31797 -426.342048)
			(xy 401.25777 -426.342048) (xy 401.269892 -426.342486) (xy 401.292952 -426.349971) (xy 401.312568 -426.364218)
			(xy 401.32682 -426.38383) (xy 401.334311 -426.406888) (xy 401.334732 -426.41901) (xy 401.334732 -427.960536)
			(xy 402.241004 -427.960536) (xy 402.241004 -425.419012) (xy 402.241427 -425.406903) (xy 402.248923 -425.383876)
			(xy 402.263183 -425.364302) (xy 402.282804 -425.350107) (xy 402.305856 -425.342687) (xy 402.317966 -425.342304)
			(xy 403.257766 -425.342304) (xy 403.26985 -425.342836) (xy 403.292844 -425.350279) (xy 403.312421 -425.36445)
			(xy 403.326674 -425.383968) (xy 403.334213 -425.40693) (xy 403.334728 -425.419012) (xy 403.334728 -427.960536)
			(xy 403.334315 -427.972644) (xy 403.326809 -427.995668) (xy 403.312545 -428.015238) (xy 403.292925 -428.029432)
			(xy 403.269875 -428.036857) (xy 403.257766 -428.037244) (xy 402.317966 -428.037244) (xy 402.305873 -428.036821)
			(xy 402.282869 -428.029353) (xy 402.263288 -428.015156) (xy 402.249039 -427.995612) (xy 402.241511 -427.972628)
			(xy 402.241004 -427.960536) (xy 401.334732 -427.960536) (xy 401.334732 -428.960534) (xy 401.334317 -428.972653)
			(xy 401.326817 -428.995703) (xy 401.312561 -429.015307) (xy 401.292945 -429.029546) (xy 401.26989 -429.037027)
			(xy 401.25777 -429.037496) (xy 400.31797 -429.037496) (xy 400.305857 -429.037014) (xy 400.282819 -429.029523)
			(xy 400.26322 -429.015282) (xy 400.248979 -428.995685) (xy 400.241486 -428.972647) (xy 400.241008 -428.960534)
			(xy 399.307419 -428.960534) (xy 399.312515 -428.964233) (xy 399.326759 -428.983818) (xy 399.334255 -429.006846)
			(xy 399.334736 -429.018954) (xy 399.334736 -431.560478) (xy 399.334321 -431.572602) (xy 399.326832 -431.595665)
			(xy 399.31258 -431.615282) (xy 399.292961 -431.629533) (xy 399.269898 -431.637022) (xy 399.257774 -431.63744)
			(xy 398.317974 -431.63744) (xy 398.305856 -431.63701) (xy 398.282808 -431.629513) (xy 398.263205 -431.615261)
			(xy 398.248965 -431.595649) (xy 398.241482 -431.572596) (xy 398.241012 -431.560478) (xy 396.334488 -431.560478)
			(xy 396.334488 -432.560476) (xy 396.334066 -432.572559) (xy 396.326603 -432.595545) (xy 396.3124 -432.615097)
			(xy 396.292848 -432.629301) (xy 396.269863 -432.636766) (xy 396.25778 -432.637184) (xy 395.31798 -432.637184)
			(xy 395.305894 -432.636804) (xy 395.282906 -432.629328) (xy 395.263354 -432.615114) (xy 395.249152 -432.595554)
			(xy 395.241689 -432.572562) (xy 395.241272 -432.560476) (xy 394.307147 -432.560476) (xy 394.312397 -432.564289)
			(xy 394.326602 -432.583835) (xy 394.33407 -432.606815) (xy 394.334492 -432.618896) (xy 394.334492 -435.16042)
			(xy 394.334052 -435.172497) (xy 394.326582 -435.195468) (xy 394.31238 -435.215006) (xy 394.292835 -435.229199)
			(xy 394.269861 -435.236658) (xy 394.257784 -435.237128) (xy 393.317984 -435.237128) (xy 393.305911 -435.23665)
			(xy 393.282946 -435.229185) (xy 393.263411 -435.214991) (xy 393.249217 -435.195457) (xy 393.241751 -435.172493)
			(xy 393.241276 -435.16042) (xy 392.334496 -435.16042) (xy 392.334496 -436.160418) (xy 392.334009 -436.172505)
			(xy 392.326552 -436.1955) (xy 392.312369 -436.215077) (xy 392.292842 -436.229328) (xy 392.269873 -436.236866)
			(xy 392.257788 -436.23738) (xy 391.317988 -436.23738) (xy 391.305876 -436.236994) (xy 391.282845 -436.229489)
			(xy 391.263271 -436.21522) (xy 391.249077 -436.195591) (xy 391.24166 -436.172531) (xy 391.24128 -436.160418)
			(xy 390.307476 -436.160418) (xy 390.312492 -436.164071) (xy 390.326688 -436.183685) (xy 390.334113 -436.206731)
			(xy 390.3345 -436.218838) (xy 390.3345 -438.760362) (xy 390.333961 -438.772446) (xy 390.32652 -438.795438)
			(xy 390.31235 -438.815015) (xy 390.292834 -438.829269) (xy 390.269874 -438.836809) (xy 390.257792 -438.837324)
			(xy 389.317992 -438.837324) (xy 389.305885 -438.836891) (xy 389.282862 -438.829392) (xy 389.263291 -438.815134)
			(xy 389.249095 -438.795518) (xy 389.241671 -438.77247) (xy 389.241284 -438.760362) (xy 388.334504 -438.760362)
			(xy 388.334504 -439.76036) (xy 391.24128 -439.76036) (xy 391.24128 -437.218836) (xy 391.241743 -437.206756)
			(xy 391.249199 -437.183777) (xy 391.263393 -437.164227) (xy 391.282934 -437.150021) (xy 391.305909 -437.142551)
			(xy 391.317988 -437.142128) (xy 392.257788 -437.142128) (xy 392.269874 -437.142524) (xy 392.292862 -437.149992)
			(xy 392.312416 -437.164202) (xy 392.326619 -437.18376) (xy 392.33408 -437.20675) (xy 392.334496 -437.218836)
			(xy 392.334496 -438.760362) (xy 393.241276 -438.760362) (xy 393.241276 -436.218838) (xy 393.24174 -436.206747)
			(xy 393.249191 -436.183741) (xy 393.263377 -436.164158) (xy 393.282914 -436.149907) (xy 393.305894 -436.142381)
			(xy 393.317984 -436.141876) (xy 394.257784 -436.141876) (xy 394.26989 -436.14233) (xy 394.292912 -436.149822)
			(xy 394.307462 -436.160418) (xy 395.241272 -436.160418) (xy 395.241272 -433.618894) (xy 395.241703 -433.606801)
			(xy 395.249165 -433.583795) (xy 395.26336 -433.564212) (xy 395.282903 -433.549963) (xy 395.305888 -433.542437)
			(xy 395.31798 -433.541932) (xy 396.25778 -433.541932) (xy 396.269891 -433.542334) (xy 396.292923 -433.549832)
			(xy 396.312499 -433.564096) (xy 396.326693 -433.583723) (xy 396.334109 -433.606782) (xy 396.334488 -433.618894)
			(xy 396.334488 -435.16042) (xy 398.241012 -435.16042) (xy 398.241012 -432.618896) (xy 398.241413 -432.606786)
			(xy 398.248915 -432.583756) (xy 398.26318 -432.564182) (xy 398.282806 -432.549988) (xy 398.305862 -432.542569)
			(xy 398.317974 -432.542188) (xy 399.257774 -432.542188) (xy 399.269867 -432.54263) (xy 399.292875 -432.550086)
			(xy 399.307214 -432.560476) (xy 400.241008 -432.560476) (xy 400.241008 -430.018952) (xy 400.241376 -430.00684)
			(xy 400.248889 -429.98381) (xy 400.263163 -429.964237) (xy 400.282795 -429.950044) (xy 400.305856 -429.942626)
			(xy 400.31797 -429.942244) (xy 401.25777 -429.942244) (xy 401.269858 -429.942733) (xy 401.292859 -429.950182)
			(xy 401.312439 -429.964363) (xy 401.326691 -429.983892) (xy 401.334223 -430.006865) (xy 401.334732 -430.018952)
			(xy 401.334732 -431.560478) (xy 402.241004 -431.560478) (xy 402.241004 -429.018954) (xy 402.241472 -429.00684)
			(xy 402.248968 -428.983801) (xy 402.263212 -428.964203) (xy 402.282812 -428.949962) (xy 402.305852 -428.94247)
			(xy 402.317966 -428.941992) (xy 403.257766 -428.941992) (xy 403.269874 -428.94254) (xy 403.292909 -428.950012)
			(xy 403.307406 -428.960534) (xy 404.241 -428.960534) (xy 404.241 -426.41901) (xy 404.24152 -426.4069)
			(xy 404.249 -426.383863) (xy 404.263231 -426.364265) (xy 404.28282 -426.350022) (xy 404.305852 -426.342527)
			(xy 404.317962 -426.342048) (xy 405.257762 -426.342048) (xy 405.269884 -426.342492) (xy 405.292943 -426.349975)
			(xy 405.31256 -426.36422) (xy 405.326812 -426.383832) (xy 405.334303 -426.406888) (xy 405.334724 -426.41901)
			(xy 405.334724 -427.960536) (xy 406.240996 -427.960536) (xy 406.240996 -425.419012) (xy 406.241427 -425.406904)
			(xy 406.248922 -425.383878) (xy 406.26318 -425.364305) (xy 406.282799 -425.35011) (xy 406.305849 -425.342688)
			(xy 406.317958 -425.342304) (xy 407.257758 -425.342304) (xy 407.269842 -425.342842) (xy 407.292835 -425.350283)
			(xy 407.312413 -425.364453) (xy 407.326666 -425.383969) (xy 407.334205 -425.40693) (xy 407.33472 -425.419012)
			(xy 407.33472 -427.960536) (xy 407.334315 -427.972645) (xy 407.326808 -427.99567) (xy 407.312543 -428.01524)
			(xy 407.29292 -428.029435) (xy 407.269868 -428.036858) (xy 407.257758 -428.037244) (xy 406.317958 -428.037244)
			(xy 406.305865 -428.036828) (xy 406.28286 -428.029358) (xy 406.263279 -428.015159) (xy 406.249031 -427.995614)
			(xy 406.241503 -427.972628) (xy 406.240996 -427.960536) (xy 405.334724 -427.960536) (xy 405.334724 -428.960534)
			(xy 405.334369 -428.972662) (xy 405.326862 -428.995729) (xy 405.312595 -429.015347) (xy 405.292964 -429.029595)
			(xy 405.269891 -429.03708) (xy 405.257762 -429.037496) (xy 404.317962 -429.037496) (xy 404.305849 -429.037021)
			(xy 404.28281 -429.029528) (xy 404.263212 -429.015285) (xy 404.24897 -428.995686) (xy 404.241478 -428.972647)
			(xy 404.241 -428.960534) (xy 403.307406 -428.960534) (xy 403.312507 -428.964236) (xy 403.326751 -428.98382)
			(xy 403.334247 -429.006846) (xy 403.334728 -429.018954) (xy 403.334728 -431.560478) (xy 403.334321 -431.572603)
			(xy 403.32683 -431.595667) (xy 403.312577 -431.615285) (xy 403.292956 -431.629536) (xy 403.269891 -431.637023)
			(xy 403.257766 -431.63744) (xy 402.317966 -431.63744) (xy 402.305847 -431.637017) (xy 402.282799 -431.629518)
			(xy 402.263196 -431.615264) (xy 402.248957 -431.59565) (xy 402.241474 -431.572597) (xy 402.241004 -431.560478)
			(xy 401.334732 -431.560478) (xy 401.334732 -432.560476) (xy 401.334263 -432.57258) (xy 401.326775 -432.595601)
			(xy 401.312525 -432.615172) (xy 401.292917 -432.629369) (xy 401.269875 -432.636796) (xy 401.25777 -432.637184)
			(xy 400.31797 -432.637184) (xy 400.305881 -432.636719) (xy 400.282884 -432.629257) (xy 400.263306 -432.615069)
			(xy 400.249056 -432.595537) (xy 400.24152 -432.572563) (xy 400.241008 -432.560476) (xy 399.307214 -432.560476)
			(xy 399.312459 -432.564277) (xy 399.326709 -432.583819) (xy 399.334233 -432.606804) (xy 399.334736 -432.618896)
			(xy 399.334736 -435.16042) (xy 399.334301 -435.172526) (xy 399.326801 -435.195548) (xy 399.312543 -435.215118)
			(xy 399.292927 -435.229313) (xy 399.269882 -435.23674) (xy 399.257774 -435.237128) (xy 398.317974 -435.237128)
			(xy 398.30588 -435.236714) (xy 398.282873 -435.229247) (xy 398.263291 -435.215047) (xy 398.249042 -435.195501)
			(xy 398.241516 -435.172513) (xy 398.241012 -435.16042) (xy 396.334488 -435.16042) (xy 396.334488 -436.160418)
			(xy 396.334009 -436.172506) (xy 396.32655 -436.195502) (xy 396.312366 -436.21508) (xy 396.292837 -436.229331)
			(xy 396.269866 -436.236867) (xy 396.25778 -436.23738) (xy 395.31798 -436.23738) (xy 395.305868 -436.237001)
			(xy 395.282837 -436.229493) (xy 395.263262 -436.215223) (xy 395.249069 -436.195592) (xy 395.241652 -436.172532)
			(xy 395.241272 -436.160418) (xy 394.307462 -436.160418) (xy 394.312483 -436.164075) (xy 394.326679 -436.183687)
			(xy 394.334105 -436.206731) (xy 394.334492 -436.218838) (xy 394.334492 -438.760362) (xy 394.333961 -438.772446)
			(xy 394.326518 -438.79544) (xy 394.312347 -438.815018) (xy 394.292829 -438.829271) (xy 394.269866 -438.83681)
			(xy 394.257784 -438.837324) (xy 393.317984 -438.837324) (xy 393.305877 -438.836898) (xy 393.282853 -438.829397)
			(xy 393.263282 -438.815137) (xy 393.249087 -438.795519) (xy 393.241663 -438.772471) (xy 393.241276 -438.760362)
			(xy 392.334496 -438.760362) (xy 392.334496 -439.76036) (xy 395.241272 -439.76036) (xy 395.241272 -437.218836)
			(xy 395.241743 -437.206757) (xy 395.249198 -437.183779) (xy 395.26339 -437.16423) (xy 395.282929 -437.150024)
			(xy 395.305901 -437.142552) (xy 395.31798 -437.142128) (xy 396.25778 -437.142128) (xy 396.269865 -437.14253)
			(xy 396.292853 -437.149997) (xy 396.312407 -437.164204) (xy 396.326611 -437.183761) (xy 396.334072 -437.206751)
			(xy 396.334488 -437.218836) (xy 396.334488 -438.760362) (xy 398.241012 -438.760362) (xy 398.241012 -436.218838)
			(xy 398.241492 -436.20672) (xy 398.24897 -436.183667) (xy 398.263208 -436.164053) (xy 398.282809 -436.1498)
			(xy 398.305856 -436.142302) (xy 398.317974 -436.141876) (xy 399.257774 -436.141876) (xy 399.269899 -436.142283)
			(xy 399.292964 -436.149772) (xy 399.307616 -436.160418) (xy 400.241008 -436.160418) (xy 400.241008 -433.618894)
			(xy 400.241506 -433.606782) (xy 400.248992 -433.583744) (xy 400.263228 -433.564145) (xy 400.282822 -433.549903)
			(xy 400.305858 -433.54241) (xy 400.31797 -433.541932) (xy 401.25777 -433.541932) (xy 401.269891 -433.542385)
			(xy 401.292947 -433.549869) (xy 401.312563 -433.564112) (xy 401.326815 -433.58372) (xy 401.334309 -433.606774)
			(xy 401.334732 -433.618894) (xy 401.334732 -435.16042) (xy 402.241004 -435.16042) (xy 402.241004 -432.618896)
			(xy 402.241413 -432.606787) (xy 402.248914 -432.583758) (xy 402.263177 -432.564185) (xy 402.282801 -432.549991)
			(xy 402.305855 -432.542571) (xy 402.317966 -432.542188) (xy 403.257766 -432.542188) (xy 403.269859 -432.542637)
			(xy 403.292866 -432.55009) (xy 403.307201 -432.560476) (xy 404.241 -432.560476) (xy 404.241 -430.018952)
			(xy 404.241376 -430.006841) (xy 404.248888 -429.983812) (xy 404.26316 -429.96424) (xy 404.28279 -429.950047)
			(xy 404.305849 -429.942627) (xy 404.317962 -429.942244) (xy 405.257762 -429.942244) (xy 405.26985 -429.94274)
			(xy 405.29285 -429.950187) (xy 405.312431 -429.964366) (xy 405.326683 -429.983894) (xy 405.334215 -430.006866)
			(xy 405.334724 -430.018952) (xy 405.334724 -431.560478) (xy 406.240996 -431.560478) (xy 406.240996 -429.018954)
			(xy 406.241472 -429.006841) (xy 406.248967 -428.983804) (xy 406.263209 -428.964206) (xy 406.282807 -428.949965)
			(xy 406.305845 -428.942471) (xy 406.317958 -428.941992) (xy 407.257758 -428.941992) (xy 407.269866 -428.942547)
			(xy 407.2929 -428.950017) (xy 407.307392 -428.960534) (xy 408.240992 -428.960534) (xy 408.240992 -426.41901)
			(xy 408.24152 -426.406901) (xy 408.248999 -426.383865) (xy 408.263228 -426.364268) (xy 408.282815 -426.350024)
			(xy 408.305845 -426.342528) (xy 408.317954 -426.342048) (xy 409.257754 -426.342048) (xy 409.269875 -426.342499)
			(xy 409.292934 -426.34998) (xy 409.312551 -426.364223) (xy 409.326804 -426.383833) (xy 409.334295 -426.406889)
			(xy 409.334716 -426.41901) (xy 409.334716 -427.960536) (xy 410.240988 -427.960536) (xy 410.240988 -425.419012)
			(xy 410.241427 -425.406905) (xy 410.248921 -425.38388) (xy 410.263177 -425.364308) (xy 410.282794 -425.350113)
			(xy 410.305842 -425.342689) (xy 410.31795 -425.342304) (xy 411.25775 -425.342304) (xy 411.269833 -425.342849)
			(xy 411.292826 -425.350288) (xy 411.312404 -425.364455) (xy 411.326658 -425.383971) (xy 411.334197 -425.406931)
			(xy 411.334712 -425.419012) (xy 411.334712 -427.960536) (xy 411.334314 -427.972646) (xy 411.326807 -427.995672)
			(xy 411.31254 -428.015243) (xy 411.292915 -428.029437) (xy 411.269861 -428.036859) (xy 411.25775 -428.037244)
			(xy 410.31795 -428.037244) (xy 410.305861 -428.03675) (xy 410.28286 -428.029305) (xy 410.263278 -428.015126)
			(xy 410.249026 -427.995597) (xy 410.241495 -427.972623) (xy 410.240988 -427.960536) (xy 409.334716 -427.960536)
			(xy 409.334716 -428.960534) (xy 409.334368 -428.972663) (xy 409.326861 -428.995731) (xy 409.312592 -429.015349)
			(xy 409.292959 -429.029598) (xy 409.269884 -429.037081) (xy 409.257754 -429.037496) (xy 408.317954 -429.037496)
			(xy 408.30584 -429.037028) (xy 408.282801 -429.029532) (xy 408.263203 -429.015288) (xy 408.248962 -428.995688)
			(xy 408.24147 -428.972648) (xy 408.240992 -428.960534) (xy 407.307392 -428.960534) (xy 407.312498 -428.964239)
			(xy 407.326743 -428.983821) (xy 407.334239 -429.006847) (xy 407.33472 -429.018954) (xy 407.33472 -431.560478)
			(xy 407.334321 -431.572604) (xy 407.326829 -431.595669) (xy 407.312574 -431.615288) (xy 407.292951 -431.629538)
			(xy 407.269884 -431.637024) (xy 407.257758 -431.63744) (xy 406.317958 -431.63744) (xy 406.305839 -431.637024)
			(xy 406.282791 -431.629522) (xy 406.263188 -431.615267) (xy 406.248948 -431.595652) (xy 406.241466 -431.572597)
			(xy 406.240996 -431.560478) (xy 405.334724 -431.560478) (xy 405.334724 -432.560476) (xy 405.334263 -432.572581)
			(xy 405.326774 -432.595604) (xy 405.312523 -432.615175) (xy 405.292912 -432.629371) (xy 405.269868 -432.636797)
			(xy 405.257762 -432.637184) (xy 404.317962 -432.637184) (xy 404.305873 -432.636726) (xy 404.282875 -432.629261)
			(xy 404.263298 -432.615072) (xy 404.249048 -432.595538) (xy 404.241512 -432.572564) (xy 404.241 -432.560476)
			(xy 403.307201 -432.560476) (xy 403.312451 -432.56428) (xy 403.326701 -432.583821) (xy 403.334225 -432.606805)
			(xy 403.334728 -432.618896) (xy 403.334728 -435.16042) (xy 403.334301 -435.172527) (xy 403.3268 -435.19555)
			(xy 403.31254 -435.215121) (xy 403.292922 -435.229316) (xy 403.269874 -435.236741) (xy 403.257766 -435.237128)
			(xy 402.317966 -435.237128) (xy 402.305871 -435.236721) (xy 402.282864 -435.229251) (xy 402.263282 -435.21505)
			(xy 402.249034 -435.195502) (xy 402.241508 -435.172513) (xy 402.241004 -435.16042) (xy 401.334732 -435.16042)
			(xy 401.334732 -436.160418) (xy 401.334355 -436.172545) (xy 401.326854 -436.195609) (xy 401.312592 -436.215226)
			(xy 401.292966 -436.229476) (xy 401.269897 -436.236962) (xy 401.25777 -436.23738) (xy 400.31797 -436.23738)
			(xy 400.305856 -436.236914) (xy 400.282814 -436.229421) (xy 400.263215 -436.215177) (xy 400.248974 -436.195575)
			(xy 400.241484 -436.172532) (xy 400.241008 -436.160418) (xy 399.307616 -436.160418) (xy 399.312582 -436.164026)
			(xy 399.326833 -436.183647) (xy 399.334319 -436.206713) (xy 399.334736 -436.218838) (xy 399.334736 -438.760362)
			(xy 399.334307 -438.772485) (xy 399.326822 -438.795547) (xy 399.312574 -438.815165) (xy 399.292958 -438.829417)
			(xy 399.269897 -438.836905) (xy 399.257774 -438.837324) (xy 398.317974 -438.837324) (xy 398.305846 -438.836962)
			(xy 398.28278 -438.829458) (xy 398.263162 -438.815192) (xy 398.248913 -438.795563) (xy 398.241428 -438.77249)
			(xy 398.241012 -438.760362) (xy 396.334488 -438.760362) (xy 396.334488 -439.76036) (xy 400.241008 -439.76036)
			(xy 400.241008 -437.218836) (xy 400.241447 -437.206728) (xy 400.248938 -437.183701) (xy 400.263193 -437.164126)
			(xy 400.282811 -437.149931) (xy 400.305861 -437.142511) (xy 400.31797 -437.142128) (xy 401.25777 -437.142128)
			(xy 401.269857 -437.142633) (xy 401.292854 -437.15008) (xy 401.312434 -437.164257) (xy 401.326686 -437.183782)
			(xy 401.334221 -437.206751) (xy 401.334732 -437.218836) (xy 401.334732 -438.760362) (xy 402.241004 -438.760362)
			(xy 402.241004 -436.218838) (xy 402.241492 -436.206721) (xy 402.248969 -436.183669) (xy 402.263205 -436.164056)
			(xy 402.282804 -436.149802) (xy 402.305849 -436.142303) (xy 402.317966 -436.141876) (xy 403.257766 -436.141876)
			(xy 403.269891 -436.142289) (xy 403.292955 -436.149777) (xy 403.307603 -436.160418) (xy 404.241 -436.160418)
			(xy 404.241 -433.618894) (xy 404.241506 -433.606783) (xy 404.24899 -433.583746) (xy 404.263225 -433.564148)
			(xy 404.282817 -433.549905) (xy 404.305851 -433.542411) (xy 404.317962 -433.541932) (xy 405.257762 -433.541932)
			(xy 405.269882 -433.542392) (xy 405.292939 -433.549873) (xy 405.312554 -433.564115) (xy 405.326807 -433.583722)
			(xy 405.334301 -433.606774) (xy 405.334724 -433.618894) (xy 405.334724 -435.16042) (xy 406.240996 -435.16042)
			(xy 406.240996 -432.618896) (xy 406.241413 -432.606787) (xy 406.248913 -432.583761) (xy 406.263174 -432.564188)
			(xy 406.282796 -432.549993) (xy 406.305848 -432.542572) (xy 406.317958 -432.542188) (xy 407.257758 -432.542188)
			(xy 407.26985 -432.542644) (xy 407.292858 -432.550095) (xy 407.307187 -432.560476) (xy 408.240992 -432.560476)
			(xy 408.240992 -430.018952) (xy 408.241375 -430.006841) (xy 408.248887 -429.983814) (xy 408.263158 -429.964242)
			(xy 408.282785 -429.950049) (xy 408.305842 -429.942628) (xy 408.317954 -429.942244) (xy 409.257754 -429.942244)
			(xy 409.269842 -429.942747) (xy 409.292841 -429.950191) (xy 409.312422 -429.964368) (xy 409.326674 -429.983895)
			(xy 409.334207 -430.006866) (xy 409.334716 -430.018952) (xy 409.334716 -431.560478) (xy 410.240988 -431.560478)
			(xy 410.240988 -429.018954) (xy 410.241472 -429.006842) (xy 410.248966 -428.983806) (xy 410.263206 -428.964209)
			(xy 410.282802 -428.949967) (xy 410.305838 -428.942472) (xy 410.31795 -428.941992) (xy 411.25775 -428.941992)
			(xy 411.269863 -428.942468) (xy 411.2929 -428.949964) (xy 411.307444 -428.960534) (xy 412.240984 -428.960534)
			(xy 412.240984 -426.41901) (xy 412.241369 -426.406883) (xy 412.248864 -426.383817) (xy 412.263123 -426.364198)
			(xy 412.282749 -426.349948) (xy 412.305819 -426.342464) (xy 412.317946 -426.342048) (xy 413.257746 -426.342048)
			(xy 413.269864 -426.342473) (xy 413.29291 -426.349974) (xy 413.312512 -426.364228) (xy 413.326752 -426.38384)
			(xy 413.334236 -426.406892) (xy 413.334708 -426.41901) (xy 413.334708 -428.960534) (xy 413.334218 -428.972646)
			(xy 413.326727 -428.995682) (xy 413.312488 -429.01528) (xy 413.292893 -429.029522) (xy 413.269858 -429.037016)
			(xy 413.257746 -429.037496) (xy 412.317946 -429.037496) (xy 412.305829 -429.037002) (xy 412.282777 -429.029526)
			(xy 412.263164 -429.015292) (xy 412.248911 -428.995694) (xy 412.241411 -428.972651) (xy 412.240984 -428.960534)
			(xy 411.307444 -428.960534) (xy 411.312497 -428.964206) (xy 411.326738 -428.983804) (xy 411.334232 -429.006841)
			(xy 411.334712 -429.018954) (xy 411.334712 -431.560478) (xy 411.33417 -431.572586) (xy 411.326695 -431.59562)
			(xy 411.312469 -431.615218) (xy 411.292885 -431.629462) (xy 411.269858 -431.636959) (xy 411.25775 -431.63744)
			(xy 410.31795 -431.63744) (xy 410.305831 -431.63703) (xy 410.282782 -431.629527) (xy 410.263179 -431.615269)
			(xy 410.24894 -431.595653) (xy 410.241458 -431.572598) (xy 410.240988 -431.560478) (xy 409.334716 -431.560478)
			(xy 409.334716 -432.560476) (xy 409.334263 -432.572582) (xy 409.326772 -432.595606) (xy 409.31252 -432.615178)
			(xy 409.292906 -432.629374) (xy 409.269861 -432.636798) (xy 409.257754 -432.637184) (xy 408.317954 -432.637184)
			(xy 408.305864 -432.636732) (xy 408.282866 -432.629266) (xy 408.263289 -432.615074) (xy 408.249039 -432.59554)
			(xy 408.241504 -432.572564) (xy 408.240992 -432.560476) (xy 407.307187 -432.560476) (xy 407.312442 -432.564283)
			(xy 407.326693 -432.583822) (xy 407.334217 -432.606805) (xy 407.33472 -432.618896) (xy 407.33472 -435.16042)
			(xy 407.334301 -435.172528) (xy 407.326799 -435.195552) (xy 407.312537 -435.215123) (xy 407.292917 -435.229318)
			(xy 407.269867 -435.236742) (xy 407.257758 -435.237128) (xy 406.317958 -435.237128) (xy 406.305863 -435.236728)
			(xy 406.282856 -435.229256) (xy 406.263274 -435.215053) (xy 406.249026 -435.195504) (xy 406.2415 -435.172514)
			(xy 406.240996 -435.16042) (xy 405.334724 -435.16042) (xy 405.334724 -436.160418) (xy 405.334355 -436.172545)
			(xy 405.326853 -436.195611) (xy 405.312589 -436.215229) (xy 405.292961 -436.229478) (xy 405.26989 -436.236963)
			(xy 405.257762 -436.23738) (xy 404.317962 -436.23738) (xy 404.305847 -436.236921) (xy 404.282806 -436.229425)
			(xy 404.263206 -436.21518) (xy 404.248965 -436.195576) (xy 404.241476 -436.172533) (xy 404.241 -436.160418)
			(xy 403.307603 -436.160418) (xy 403.312574 -436.164029) (xy 403.326825 -436.183649) (xy 403.334311 -436.206713)
			(xy 403.334728 -436.218838) (xy 403.334728 -438.760362) (xy 403.334307 -438.772486) (xy 403.326821 -438.79555)
			(xy 403.312571 -438.815168) (xy 403.292953 -438.829419) (xy 403.26989 -438.836907) (xy 403.257766 -438.837324)
			(xy 402.317966 -438.837324) (xy 402.305838 -438.836969) (xy 402.282771 -438.829462) (xy 402.263153 -438.815195)
			(xy 402.248905 -438.795564) (xy 402.24142 -438.772491) (xy 402.241004 -438.760362) (xy 401.334732 -438.760362)
			(xy 401.334732 -439.76036) (xy 404.241 -439.76036) (xy 404.241 -437.218836) (xy 404.241447 -437.206729)
			(xy 404.248937 -437.183703) (xy 404.26319 -437.164129) (xy 404.282806 -437.149933) (xy 404.305854 -437.142512)
			(xy 404.317962 -437.142128) (xy 405.257762 -437.142128) (xy 405.269848 -437.14264) (xy 405.292846 -437.150084)
			(xy 405.312425 -437.16426) (xy 405.326678 -437.183784) (xy 405.334213 -437.206752) (xy 405.334724 -437.218836)
			(xy 405.334724 -438.760362) (xy 406.240996 -438.760362) (xy 406.240996 -436.218838) (xy 406.241543 -436.20673)
			(xy 406.249015 -436.183695) (xy 406.263239 -436.164096) (xy 406.282823 -436.149852) (xy 406.30585 -436.142356)
			(xy 406.317958 -436.141876) (xy 407.257758 -436.141876) (xy 407.269882 -436.142296) (xy 407.292946 -436.149782)
			(xy 407.307589 -436.160418) (xy 408.240992 -436.160418) (xy 408.240992 -433.618894) (xy 408.241506 -433.606784)
			(xy 408.248989 -433.583748) (xy 408.263222 -433.564151) (xy 408.282812 -433.549908) (xy 408.305844 -433.542412)
			(xy 408.317954 -433.541932) (xy 409.257754 -433.541932) (xy 409.269874 -433.542399) (xy 409.29293 -433.549878)
			(xy 409.312546 -433.564117) (xy 409.326798 -433.583723) (xy 409.334293 -433.606775) (xy 409.334716 -433.618894)
			(xy 409.334716 -435.16042) (xy 410.240988 -435.16042) (xy 410.240988 -432.618896) (xy 410.241413 -432.606788)
			(xy 410.248912 -432.583763) (xy 410.263172 -432.564191) (xy 410.282791 -432.549996) (xy 410.305841 -432.542573)
			(xy 410.31795 -432.542188) (xy 411.25775 -432.542188) (xy 411.269842 -432.542651) (xy 411.292849 -432.5501)
			(xy 411.307175 -432.560476) (xy 412.240984 -432.560476) (xy 412.240984 -430.018952) (xy 412.241375 -430.006842)
			(xy 412.248886 -429.983816) (xy 412.263155 -429.964245) (xy 412.28278 -429.950052) (xy 412.305835 -429.942629)
			(xy 412.317946 -429.942244) (xy 413.257746 -429.942244) (xy 413.269838 -429.942668) (xy 413.292841 -429.950138)
			(xy 413.312421 -429.964336) (xy 413.32667 -429.983878) (xy 413.3342 -430.006861) (xy 413.334708 -430.018952)
			(xy 413.334708 -432.560476) (xy 413.334263 -432.572583) (xy 413.326771 -432.595608) (xy 413.312517 -432.615181)
			(xy 413.292901 -432.629376) (xy 413.269854 -432.636799) (xy 413.257746 -432.637184) (xy 412.317946 -432.637184)
			(xy 412.305861 -432.636654) (xy 412.282866 -432.629213) (xy 412.263287 -432.615042) (xy 412.249034 -432.595522)
			(xy 412.241497 -432.572559) (xy 412.240984 -432.560476) (xy 411.307175 -432.560476) (xy 411.312434 -432.564285)
			(xy 411.326684 -432.583823) (xy 411.334209 -432.606806) (xy 411.334712 -432.618896) (xy 411.334712 -435.16042)
			(xy 411.334301 -435.172529) (xy 411.326797 -435.195555) (xy 411.312534 -435.215126) (xy 411.292912 -435.229321)
			(xy 411.26986 -435.236743) (xy 411.25775 -435.237128) (xy 410.31795 -435.237128) (xy 410.30586 -435.23665)
			(xy 410.282855 -435.229203) (xy 410.263272 -435.21502) (xy 410.249021 -435.195487) (xy 410.241493 -435.172508)
			(xy 410.240988 -435.16042) (xy 409.334716 -435.16042) (xy 409.334716 -436.160418) (xy 409.334354 -436.172546)
			(xy 409.326852 -436.195613) (xy 409.312586 -436.215232) (xy 409.292956 -436.229481) (xy 409.269883 -436.236965)
			(xy 409.257754 -436.23738) (xy 408.317954 -436.23738) (xy 408.305839 -436.236928) (xy 408.282797 -436.22943)
			(xy 408.263198 -436.215182) (xy 408.248957 -436.195578) (xy 408.241468 -436.172533) (xy 408.240992 -436.160418)
			(xy 407.307589 -436.160418) (xy 407.312565 -436.164032) (xy 407.326817 -436.18365) (xy 407.334303 -436.206714)
			(xy 407.33472 -436.218838) (xy 407.33472 -438.760362) (xy 407.334307 -438.772487) (xy 407.32682 -438.795552)
			(xy 407.312568 -438.815171) (xy 407.292948 -438.829422) (xy 407.269883 -438.836908) (xy 407.257758 -438.837324)
			(xy 406.317958 -438.837324) (xy 406.305837 -438.836923) (xy 406.282786 -438.82942) (xy 406.263182 -438.815161)
			(xy 406.248943 -438.795542) (xy 406.241464 -438.772483) (xy 406.240996 -438.760362) (xy 405.334724 -438.760362)
			(xy 405.334724 -439.76036) (xy 408.240992 -439.76036) (xy 408.240992 -437.218836) (xy 408.241447 -437.20673)
			(xy 408.248935 -437.183705) (xy 408.263187 -437.164132) (xy 408.282801 -437.149936) (xy 408.305847 -437.142513)
			(xy 408.317954 -437.142128) (xy 409.257754 -437.142128) (xy 409.26984 -437.142646) (xy 409.292837 -437.150089)
			(xy 409.312417 -437.164263) (xy 409.326669 -437.183785) (xy 409.334205 -437.206752) (xy 409.334716 -437.218836)
			(xy 409.334716 -438.760362) (xy 410.240988 -438.760362) (xy 410.240988 -436.218838) (xy 410.241543 -436.20673)
			(xy 410.249014 -436.183697) (xy 410.263236 -436.164099) (xy 410.282818 -436.149854) (xy 410.305843 -436.142357)
			(xy 410.31795 -436.141876) (xy 411.25775 -436.141876) (xy 411.269871 -436.14227) (xy 411.292922 -436.149775)
			(xy 411.307552 -436.160418) (xy 412.240984 -436.160418) (xy 412.240984 -433.618894) (xy 412.241356 -433.606766)
			(xy 412.248855 -433.5837) (xy 412.263118 -433.564081) (xy 412.282746 -433.549831) (xy 412.305818 -433.542348)
			(xy 412.317946 -433.541932) (xy 413.257746 -433.541932) (xy 413.269862 -433.542372) (xy 413.292906 -433.549872)
			(xy 413.312507 -433.564122) (xy 413.326747 -433.58373) (xy 413.334234 -433.606777) (xy 413.334708 -433.618894)
			(xy 413.334708 -435.59984) (xy 446.741306 -435.59984) (xy 446.745288 -435.471854) (xy 446.75722 -435.344363)
			(xy 446.777054 -435.21786) (xy 446.804715 -435.092835) (xy 446.840095 -434.969772) (xy 446.883057 -434.849146)
			(xy 446.933435 -434.731425) (xy 446.991035 -434.617063) (xy 447.055633 -434.506504) (xy 447.12698 -434.400174)
			(xy 447.204799 -434.298486) (xy 447.288789 -434.201832) (xy 447.378626 -434.110587) (xy 447.473962 -434.025104)
			(xy 447.574427 -433.945713) (xy 447.679635 -433.872721) (xy 447.789176 -433.806412) (xy 447.902628 -433.747041)
			(xy 448.019552 -433.694837) (xy 448.139495 -433.650004) (xy 448.261993 -433.612715) (xy 448.386573 -433.583113)
			(xy 448.512751 -433.561314) (xy 448.640041 -433.547401) (xy 448.76795 -433.541429) (xy 448.895983 -433.54342)
			(xy 449.023644 -433.553368) (xy 449.15044 -433.571232) (xy 449.275879 -433.596945) (xy 449.399478 -433.630407)
			(xy 449.520757 -433.671488) (xy 449.639248 -433.72003) (xy 449.754492 -433.775844) (xy 449.866042 -433.838715)
			(xy 449.973469 -433.908399) (xy 450.076355 -433.984627) (xy 450.174303 -434.067104) (xy 450.266934 -434.155511)
			(xy 450.35389 -434.249506) (xy 450.434834 -434.348725) (xy 450.509453 -434.452784) (xy 450.577458 -434.561281)
			(xy 450.638586 -434.673796) (xy 450.692601 -434.789894) (xy 450.739294 -434.909125) (xy 450.778484 -435.031029)
			(xy 450.81002 -435.155133) (xy 450.833779 -435.280957) (xy 450.849669 -435.408016) (xy 450.85763 -435.535816)
			(xy 450.858128 -435.59984) (xy 450.85763 -435.663864) (xy 450.849669 -435.791664) (xy 450.833779 -435.918723)
			(xy 450.81002 -436.044547) (xy 450.778484 -436.168651) (xy 450.739294 -436.290555) (xy 450.692601 -436.409786)
			(xy 450.638586 -436.525884) (xy 450.577458 -436.638399) (xy 450.509453 -436.746896) (xy 450.434834 -436.850955)
			(xy 450.35389 -436.950174) (xy 450.266934 -437.044169) (xy 450.174303 -437.132576) (xy 450.076355 -437.215053)
			(xy 449.973469 -437.291281) (xy 449.866042 -437.360965) (xy 449.754492 -437.423836) (xy 449.639248 -437.47965)
			(xy 449.520757 -437.528192) (xy 449.399478 -437.569273) (xy 449.275879 -437.602735) (xy 449.15044 -437.628448)
			(xy 449.023644 -437.646312) (xy 448.895983 -437.65626) (xy 448.76795 -437.658251) (xy 448.640041 -437.652279)
			(xy 448.512751 -437.638366) (xy 448.386573 -437.616567) (xy 448.261993 -437.586965) (xy 448.139495 -437.549676)
			(xy 448.019552 -437.504843) (xy 447.902628 -437.452639) (xy 447.789176 -437.393268) (xy 447.679635 -437.326959)
			(xy 447.574427 -437.253967) (xy 447.473962 -437.174576) (xy 447.378626 -437.089093) (xy 447.288789 -436.997848)
			(xy 447.204799 -436.901194) (xy 447.12698 -436.799506) (xy 447.055633 -436.693176) (xy 446.991035 -436.582617)
			(xy 446.933435 -436.468255) (xy 446.883057 -436.350534) (xy 446.840095 -436.229908) (xy 446.804715 -436.106845)
			(xy 446.777054 -435.98182) (xy 446.75722 -435.855317) (xy 446.745288 -435.727826) (xy 446.741306 -435.59984)
			(xy 413.334708 -435.59984) (xy 413.334708 -436.160418) (xy 413.334205 -436.172529) (xy 413.326718 -436.195565)
			(xy 413.312482 -436.215163) (xy 413.29289 -436.229405) (xy 413.269857 -436.2369) (xy 413.257746 -436.23738)
			(xy 412.317946 -436.23738) (xy 412.305827 -436.236901) (xy 412.282773 -436.229424) (xy 412.263159 -436.215187)
			(xy 412.248905 -436.195584) (xy 412.241409 -436.172536) (xy 412.240984 -436.160418) (xy 411.307552 -436.160418)
			(xy 411.312526 -436.164036) (xy 411.326765 -436.183657) (xy 411.334244 -436.206717) (xy 411.334712 -436.218838)
			(xy 411.334712 -438.760362) (xy 411.334157 -438.77247) (xy 411.326686 -438.795503) (xy 411.312464 -438.815101)
			(xy 411.292882 -438.829346) (xy 411.269857 -438.836843) (xy 411.25775 -438.837324) (xy 410.31795 -438.837324)
			(xy 410.305829 -438.83693) (xy 410.282778 -438.829425) (xy 410.263174 -438.815164) (xy 410.248935 -438.795543)
			(xy 410.241456 -438.772483) (xy 410.240988 -438.760362) (xy 409.334716 -438.760362) (xy 409.334716 -439.76036)
			(xy 412.240984 -439.76036) (xy 412.240984 -437.218836) (xy 412.241447 -437.206731) (xy 412.248934 -437.183707)
			(xy 412.263184 -437.164135) (xy 412.282796 -437.149939) (xy 412.30584 -437.142514) (xy 412.317946 -437.142128)
			(xy 413.257746 -437.142128) (xy 413.269837 -437.142568) (xy 413.292837 -437.150036) (xy 413.312415 -437.16423)
			(xy 413.326664 -437.183768) (xy 413.334197 -437.206747) (xy 413.334708 -437.218836) (xy 413.334708 -439.76036)
			(xy 413.33425 -439.772466) (xy 413.326762 -439.795491) (xy 413.312511 -439.815064) (xy 413.292899 -439.82926)
			(xy 413.269853 -439.836683) (xy 413.257746 -439.837068) (xy 412.317946 -439.837068) (xy 412.30586 -439.836554)
			(xy 412.282862 -439.829111) (xy 412.263282 -439.814936) (xy 412.249029 -439.795412) (xy 412.241495 -439.772444)
			(xy 412.240984 -439.76036) (xy 409.334716 -439.76036) (xy 409.33425 -439.772465) (xy 409.326763 -439.795488)
			(xy 409.312514 -439.815061) (xy 409.292904 -439.829257) (xy 409.26986 -439.836682) (xy 409.257754 -439.837068)
			(xy 408.317954 -439.837068) (xy 408.305863 -439.836632) (xy 408.282862 -439.829164) (xy 408.263284 -439.814969)
			(xy 408.249034 -439.79543) (xy 408.241502 -439.77245) (xy 408.240992 -439.76036) (xy 405.334724 -439.76036)
			(xy 405.33425 -439.772464) (xy 405.326764 -439.795486) (xy 405.312517 -439.815058) (xy 405.292909 -439.829255)
			(xy 405.269867 -439.836681) (xy 405.257762 -439.837068) (xy 404.317962 -439.837068) (xy 404.305871 -439.836625)
			(xy 404.282871 -439.829159) (xy 404.263292 -439.814966) (xy 404.249043 -439.795428) (xy 404.24151 -439.772449)
			(xy 404.241 -439.76036) (xy 401.334732 -439.76036) (xy 401.33425 -439.772464) (xy 401.326765 -439.795484)
			(xy 401.31252 -439.815055) (xy 401.292914 -439.829252) (xy 401.269875 -439.83668) (xy 401.25777 -439.837068)
			(xy 400.31797 -439.837068) (xy 400.30588 -439.836618) (xy 400.282879 -439.829154) (xy 400.263301 -439.814963)
			(xy 400.249051 -439.795427) (xy 400.241518 -439.772449) (xy 400.241008 -439.76036) (xy 396.334488 -439.76036)
			(xy 396.334053 -439.772443) (xy 396.326594 -439.795427) (xy 396.312394 -439.81498) (xy 396.292845 -439.829185)
			(xy 396.269863 -439.83665) (xy 396.25778 -439.837068) (xy 395.31798 -439.837068) (xy 395.305892 -439.836704)
			(xy 395.282902 -439.829226) (xy 395.263349 -439.815009) (xy 395.249147 -439.795444) (xy 395.241687 -439.772448)
			(xy 395.241272 -439.76036) (xy 392.334496 -439.76036) (xy 392.334053 -439.772442) (xy 392.326595 -439.795425)
			(xy 392.312397 -439.814977) (xy 392.29285 -439.829182) (xy 392.26987 -439.836649) (xy 392.257788 -439.837068)
			(xy 391.317988 -439.837068) (xy 391.305901 -439.836697) (xy 391.282911 -439.829221) (xy 391.263357 -439.815006)
			(xy 391.249155 -439.795443) (xy 391.241695 -439.772448) (xy 391.24128 -439.76036) (xy 388.334504 -439.76036)
			(xy 388.334053 -439.772441) (xy 388.326596 -439.795423) (xy 388.3124 -439.814974) (xy 388.292855 -439.82918)
			(xy 388.269877 -439.836648) (xy 388.257796 -439.837068) (xy 387.317996 -439.837068) (xy 387.305909 -439.83669)
			(xy 387.282919 -439.829217) (xy 387.263366 -439.815003) (xy 387.249163 -439.795441) (xy 387.241703 -439.772447)
			(xy 387.241288 -439.76036) (xy 384.334512 -439.76036) (xy 384.334053 -439.77244) (xy 384.326597 -439.795421)
			(xy 384.312403 -439.814972) (xy 384.29286 -439.829177) (xy 384.269884 -439.836646) (xy 384.257804 -439.837068)
			(xy 383.318004 -439.837068) (xy 383.305917 -439.836684) (xy 383.282928 -439.829212) (xy 383.263374 -439.815)
			(xy 383.249171 -439.79544) (xy 383.241711 -439.772447) (xy 383.241296 -439.76036) (xy 346.234512 -439.76036)
			(xy 346.234512 -439.760614) (xy 346.234104 -439.772709) (xy 346.226638 -439.795718) (xy 346.212437 -439.815302)
			(xy 346.192889 -439.829551) (xy 346.169898 -439.837074) (xy 346.157804 -439.837576) (xy 345.218004 -439.837576)
			(xy 345.205893 -439.83718) (xy 345.182862 -439.829679) (xy 345.163286 -439.815413) (xy 345.149092 -439.795785)
			(xy 345.141676 -439.772727) (xy 345.141296 -439.760614) (xy 342.23452 -439.760614) (xy 342.234104 -439.772708)
			(xy 342.226639 -439.795716) (xy 342.21244 -439.815299) (xy 342.192894 -439.829548) (xy 342.169905 -439.837073)
			(xy 342.157812 -439.837576) (xy 341.218012 -439.837576) (xy 341.205901 -439.837173) (xy 341.18287 -439.829674)
			(xy 341.163295 -439.81541) (xy 341.149101 -439.795784) (xy 341.141684 -439.772726) (xy 341.141304 -439.760614)
			(xy 338.234528 -439.760614) (xy 338.234104 -439.772708) (xy 338.22664 -439.795714) (xy 338.212443 -439.815297)
			(xy 338.192899 -439.829546) (xy 338.169912 -439.837072) (xy 338.15782 -439.837576) (xy 337.21802 -439.837576)
			(xy 337.20591 -439.837166) (xy 337.182879 -439.829669) (xy 337.163304 -439.815407) (xy 337.149109 -439.795782)
			(xy 337.141692 -439.772726) (xy 337.141312 -439.760614) (xy 334.234536 -439.760614) (xy 334.234104 -439.772707)
			(xy 334.226641 -439.795712) (xy 334.212446 -439.815294) (xy 334.192904 -439.829543) (xy 334.169919 -439.83707)
			(xy 334.157828 -439.837576) (xy 333.218028 -439.837576) (xy 333.205918 -439.837159) (xy 333.182888 -439.829665)
			(xy 333.163312 -439.815404) (xy 333.149117 -439.795781) (xy 333.1417 -439.772725) (xy 333.14132 -439.760614)
			(xy 329.2348 -439.760614) (xy 329.234301 -439.772726) (xy 329.226815 -439.795763) (xy 329.212578 -439.815361)
			(xy 329.192984 -439.829604) (xy 329.169949 -439.837097) (xy 329.157838 -439.837576) (xy 328.218038 -439.837576)
			(xy 328.205919 -439.837108) (xy 328.182863 -439.829628) (xy 328.163249 -439.815388) (xy 328.148996 -439.795783)
			(xy 328.1415 -439.772733) (xy 328.141076 -439.760614) (xy 325.234808 -439.760614) (xy 325.234301 -439.772725)
			(xy 325.226816 -439.795761) (xy 325.212581 -439.815358) (xy 325.192989 -439.829601) (xy 325.169957 -439.837096)
			(xy 325.157846 -439.837576) (xy 324.218046 -439.837576) (xy 324.205927 -439.837101) (xy 324.182872 -439.829623)
			(xy 324.163257 -439.815385) (xy 324.149004 -439.795782) (xy 324.141508 -439.772733) (xy 324.141084 -439.760614)
			(xy 321.234816 -439.760614) (xy 321.234451 -439.772742) (xy 321.226949 -439.795809) (xy 321.212685 -439.815428)
			(xy 321.193055 -439.829677) (xy 321.169982 -439.83716) (xy 321.157854 -439.837576) (xy 320.218054 -439.837576)
			(xy 320.205938 -439.837128) (xy 320.182896 -439.82963) (xy 320.163296 -439.815381) (xy 320.149056 -439.795775)
			(xy 320.141567 -439.77273) (xy 320.141092 -439.760614) (xy 317.234824 -439.760614) (xy 317.234451 -439.772741)
			(xy 317.22695 -439.795807) (xy 317.212688 -439.815425) (xy 317.19306 -439.829674) (xy 317.16999 -439.837159)
			(xy 317.157862 -439.837576) (xy 316.218062 -439.837576) (xy 316.205947 -439.837121) (xy 316.182905 -439.829625)
			(xy 316.163305 -439.815378) (xy 316.149064 -439.795774) (xy 316.141575 -439.772729) (xy 316.1411 -439.760614)
			(xy 157.334702 -439.760614) (xy 157.33425 -439.772466) (xy 157.326763 -439.79549) (xy 157.312513 -439.815062)
			(xy 157.292901 -439.829259) (xy 157.269857 -439.836682) (xy 157.25775 -439.837068) (xy 156.31795 -439.837068)
			(xy 156.305864 -439.83655) (xy 156.282866 -439.829108) (xy 156.263286 -439.814935) (xy 156.249033 -439.795412)
			(xy 156.241499 -439.772444) (xy 156.240988 -439.76036) (xy 153.33472 -439.76036) (xy 153.33425 -439.772465)
			(xy 153.326764 -439.795487) (xy 153.312516 -439.815059) (xy 153.292906 -439.829256) (xy 153.269864 -439.836681)
			(xy 153.257758 -439.837068) (xy 152.317958 -439.837068) (xy 152.305867 -439.836629) (xy 152.282866 -439.829161)
			(xy 152.263288 -439.814967) (xy 152.249038 -439.795429) (xy 152.241506 -439.77245) (xy 152.240996 -439.76036)
			(xy 149.334728 -439.76036) (xy 149.33425 -439.772464) (xy 149.326765 -439.795485) (xy 149.312518 -439.815057)
			(xy 149.292911 -439.829254) (xy 149.269871 -439.83668) (xy 149.257766 -439.837068) (xy 148.317966 -439.837068)
			(xy 148.305875 -439.836622) (xy 148.282875 -439.829157) (xy 148.263296 -439.814964) (xy 148.249047 -439.795428)
			(xy 148.241514 -439.772449) (xy 148.241004 -439.76036) (xy 145.334736 -439.76036) (xy 145.33425 -439.772463)
			(xy 145.326766 -439.795483) (xy 145.312521 -439.815054) (xy 145.292916 -439.829251) (xy 145.269878 -439.836679)
			(xy 145.257774 -439.837068) (xy 144.317974 -439.837068) (xy 144.305884 -439.836615) (xy 144.282884 -439.829152)
			(xy 144.263305 -439.814962) (xy 144.249055 -439.795426) (xy 144.241522 -439.772449) (xy 144.241012 -439.76036)
			(xy 140.334492 -439.76036) (xy 140.334053 -439.772442) (xy 140.326595 -439.795426) (xy 140.312396 -439.814979)
			(xy 140.292848 -439.829184) (xy 140.269866 -439.836649) (xy 140.257784 -439.837068) (xy 139.317984 -439.837068)
			(xy 139.305896 -439.8367) (xy 139.282906 -439.829224) (xy 139.263353 -439.815007) (xy 139.249151 -439.795443)
			(xy 139.241691 -439.772448) (xy 139.241276 -439.76036) (xy 136.3345 -439.76036) (xy 136.334053 -439.772441)
			(xy 136.326596 -439.795424) (xy 136.312399 -439.814976) (xy 136.292853 -439.829181) (xy 136.269873 -439.836648)
			(xy 136.257792 -439.837068) (xy 135.317992 -439.837068) (xy 135.305905 -439.836694) (xy 135.282915 -439.829219)
			(xy 135.263361 -439.815004) (xy 135.249159 -439.795442) (xy 135.241699 -439.772447) (xy 135.241284 -439.76036)
			(xy 132.334508 -439.76036) (xy 132.334053 -439.772441) (xy 132.326597 -439.795422) (xy 132.312401 -439.814973)
			(xy 132.292858 -439.829178) (xy 132.26988 -439.836647) (xy 132.2578 -439.837068) (xy 131.318 -439.837068)
			(xy 131.305913 -439.836687) (xy 131.282924 -439.829215) (xy 131.26337 -439.815002) (xy 131.249167 -439.79544)
			(xy 131.241707 -439.772447) (xy 131.241292 -439.76036) (xy 128.334516 -439.76036) (xy 128.334053 -439.77244)
			(xy 128.326598 -439.79542) (xy 128.312404 -439.81497) (xy 128.292863 -439.829176) (xy 128.269888 -439.836646)
			(xy 128.257808 -439.837068) (xy 127.318008 -439.837068) (xy 127.305922 -439.83668) (xy 127.282932 -439.82921)
			(xy 127.263378 -439.814999) (xy 127.249175 -439.795439) (xy 127.241715 -439.772447) (xy 127.2413 -439.76036)
			(xy 90.234516 -439.76036) (xy 90.234516 -439.760614) (xy 90.234104 -439.772709) (xy 90.226638 -439.795717)
			(xy 90.212439 -439.815301) (xy 90.192891 -439.829549) (xy 90.169901 -439.837073) (xy 90.157808 -439.837576)
			(xy 89.218008 -439.837576) (xy 89.205897 -439.837177) (xy 89.182866 -439.829677) (xy 89.163291 -439.815412)
			(xy 89.149096 -439.795785) (xy 89.14168 -439.772726) (xy 89.1413 -439.760614) (xy 86.234524 -439.760614)
			(xy 86.234104 -439.772708) (xy 86.226639 -439.795715) (xy 86.212442 -439.815298) (xy 86.192896 -439.829547)
			(xy 86.169909 -439.837072) (xy 86.157816 -439.837576) (xy 85.218016 -439.837576) (xy 85.205906 -439.83717)
			(xy 85.182875 -439.829672) (xy 85.163299 -439.815408) (xy 85.149105 -439.795783) (xy 85.141688 -439.772726)
			(xy 85.141308 -439.760614) (xy 82.234532 -439.760614) (xy 82.234104 -439.772707) (xy 82.22664 -439.795713)
			(xy 82.212445 -439.815295) (xy 82.192901 -439.829544) (xy 82.169916 -439.837071) (xy 82.157824 -439.837576)
			(xy 81.218024 -439.837576) (xy 81.205914 -439.837163) (xy 81.182883 -439.829667) (xy 81.163308 -439.815406)
			(xy 81.149113 -439.795781) (xy 81.141696 -439.772725) (xy 81.141316 -439.760614) (xy 78.23454 -439.760614)
			(xy 78.234104 -439.772706) (xy 78.226641 -439.795711) (xy 78.212447 -439.815292) (xy 78.192906 -439.829542)
			(xy 78.169923 -439.83707) (xy 78.157832 -439.837576) (xy 77.218032 -439.837576) (xy 77.205922 -439.837156)
			(xy 77.182892 -439.829663) (xy 77.163316 -439.815403) (xy 77.149122 -439.79578) (xy 77.141704 -439.772725)
			(xy 77.141324 -439.760614) (xy 73.234804 -439.760614) (xy 73.234301 -439.772725) (xy 73.226815 -439.795762)
			(xy 73.21258 -439.81536) (xy 73.192987 -439.829602) (xy 73.169953 -439.837097) (xy 73.157842 -439.837576)
			(xy 72.218042 -439.837576) (xy 72.205923 -439.837105) (xy 72.182868 -439.829626) (xy 72.163253 -439.815387)
			(xy 72.149 -439.795783) (xy 72.141504 -439.772733) (xy 72.14108 -439.760614) (xy 69.234812 -439.760614)
			(xy 69.234301 -439.772724) (xy 69.226816 -439.79576) (xy 69.212582 -439.815357) (xy 69.192992 -439.8296)
			(xy 69.16996 -439.837096) (xy 69.15785 -439.837576) (xy 68.21805 -439.837576) (xy 68.205934 -439.837131)
			(xy 68.182892 -439.829632) (xy 68.163292 -439.815382) (xy 68.149052 -439.795776) (xy 68.141563 -439.77273)
			(xy 68.141088 -439.760614) (xy 65.23482 -439.760614) (xy 65.234451 -439.772742) (xy 65.22695 -439.795808)
			(xy 65.212686 -439.815426) (xy 65.193058 -439.829675) (xy 65.169986 -439.83716) (xy 65.157858 -439.837576)
			(xy 64.218058 -439.837576) (xy 64.205943 -439.837124) (xy 64.1829 -439.829627) (xy 64.163301 -439.815379)
			(xy 64.14906 -439.795774) (xy 64.141571 -439.77273) (xy 64.141096 -439.760614) (xy 61.234828 -439.760614)
			(xy 61.234451 -439.772741) (xy 61.226951 -439.795806) (xy 61.212689 -439.815424) (xy 61.193063 -439.829673)
			(xy 61.169993 -439.837159) (xy 61.157866 -439.837576) (xy 60.218066 -439.837576) (xy 60.205951 -439.837118)
			(xy 60.182909 -439.829623) (xy 60.163309 -439.815377) (xy 60.149068 -439.795773) (xy 60.141579 -439.772729)
			(xy 60.141104 -439.760614) (xy 7.00913 -439.760614) (xy 7.00913 -439.989976) (xy 7.009638 -440.045746)
			(xy 7.017973 -440.156973) (xy 7.034597 -440.267266) (xy 7.059417 -440.376009) (xy 7.092293 -440.482593)
			(xy 7.133043 -440.586422) (xy 7.181438 -440.686915) (xy 7.237207 -440.783511) (xy 7.300039 -440.87567)
			(xy 7.369583 -440.962874) (xy 7.445449 -441.044639) (xy 7.527212 -441.120505) (xy 7.614417 -441.190048)
			(xy 7.706575 -441.252881) (xy 7.803171 -441.30865) (xy 7.903664 -441.357045) (xy 8.007493 -441.397795)
			(xy 8.114077 -441.430672) (xy 8.22282 -441.455492) (xy 8.333113 -441.472116) (xy 8.44434 -441.480451)
			(xy 8.50011 -441.480956)
		)
		(stroke
			(width 0)
			(type solid)
		)
		(fill yes)
		(layer "In3.Cu")
		(net "GND")
	)
	(gr_line
		(start 1.414272 -79.914242)
		(end 0.585724 -79.085694)
		(stroke
			(width 1.016)
			(type default)
		)
		(layer "In3.Cu")
	)
	(gr_line
		(start 1.999996 -403.371558)
		(end 1.999996 -81.328514)
		(stroke
			(width 1.016)
			(type default)
		)
		(layer "In3.Cu")
	)
	(gr_arc
		(start 1.999996 -403.371558)
		(mid 2.152159 -404.136965)
		(end 2.58572 -404.78583)
		(stroke
			(width 1.016)
			(type default)
		)
		(layer "In3.Cu")
	)
	(gr_arc
		(start 1.999996 -81.328514)
		(mid 1.847755 -80.563149)
		(end 1.414272 -79.914242)
		(stroke
			(width 1.016)
			(type default)
		)
		(layer "In3.Cu")
	)
	(gr_arc
		(start 1.999996 -11.780012)
		(mid 0.585785 -12.365797)
		(end 0 -13.780008)
		(stroke
			(width 1.016)
			(type default)
		)
		(layer "In3.Cu")
	)
	(gr_line
		(start 1.999996 -11.780012)
		(end 11.102086 -11.780012)
		(stroke
			(width 1.016)
			(type default)
		)
		(layer "In3.Cu")
	)
	(gr_line
		(start 5.914136 -408.114246)
		(end 2.58572 -404.78583)
		(stroke
			(width 1.016)
			(type default)
		)
		(layer "In3.Cu")
	)
	(gr_line
		(start 6.500114 -439.989976)
		(end 6.500114 -409.528518)
		(stroke
			(width 1.016)
			(type default)
		)
		(layer "In3.Cu")
	)
	(gr_arc
		(start 6.500114 -439.989976)
		(mid 7.085891 -441.404199)
		(end 8.50011 -441.989972)
		(stroke
			(width 1.016)
			(type default)
		)
		(layer "In3.Cu")
	)
	(gr_arc
		(start 6.500114 -409.528518)
		(mid 6.347771 -408.763109)
		(end 5.914136 -408.114246)
		(stroke
			(width 1.016)
			(type default)
		)
		(layer "In3.Cu")
	)
	(gr_arc
		(start 11.102086 -11.780012)
		(mid 12.516297 -11.194227)
		(end 13.102082 -9.780016)
		(stroke
			(width 1.016)
			(type default)
		)
		(layer "In3.Cu")
	)
	(gr_line
		(start 13.102082 -9.780016)
		(end 13.102082 -0.500126)
		(stroke
			(width 1.016)
			(type default)
		)
		(layer "In3.Cu")
	)
	(gr_arc
		(start 13.601954 0)
		(mid 13.24848 -0.146572)
		(end 13.102082 -0.500126)
		(stroke
			(width 1.016)
			(type default)
		)
		(layer "In3.Cu")
	)
	(gr_line
		(start 13.601954 0)
		(end 81.202022 0)
		(stroke
			(width 1.016)
			(type default)
		)
		(layer "In3.Cu")
	)
	(gr_circle
		(center 25.82545 -40.816276)
		(end 26.71445 -40.816276)
		(stroke
			(width 0.2)
			(type default)
		)
		(fill no)
		(layer "In3.Cu")
	)
	(gr_circle
		(center 29.291534 -348.709488)
		(end 30.171644 -348.709488)
		(stroke
			(width 0.2)
			(type default)
		)
		(fill no)
		(layer "In3.Cu")
	)
	(gr_circle
		(center 29.908754 -348.709488)
		(end 30.788864 -348.709488)
		(stroke
			(width 0.2)
			(type default)
		)
		(fill no)
		(layer "In3.Cu")
	)
	(gr_circle
		(center 30.525974 -348.709488)
		(end 31.406084 -348.709488)
		(stroke
			(width 0.2)
			(type default)
		)
		(fill no)
		(layer "In3.Cu")
	)
	(gr_circle
		(center 30.795214 -347.966538)
		(end 31.684214 -347.966538)
		(stroke
			(width 0.2)
			(type default)
		)
		(fill no)
		(layer "In3.Cu")
	)
	(gr_circle
		(center 30.795214 -347.229938)
		(end 31.684214 -347.229938)
		(stroke
			(width 0.2)
			(type default)
		)
		(fill no)
		(layer "In3.Cu")
	)
	(gr_circle
		(center 31.22803 -350.318578)
		(end 32.11703 -350.318578)
		(stroke
			(width 0.2)
			(type default)
		)
		(fill no)
		(layer "In3.Cu")
	)
	(gr_circle
		(center 31.22803 -349.581978)
		(end 32.11703 -349.581978)
		(stroke
			(width 0.2)
			(type default)
		)
		(fill no)
		(layer "In3.Cu")
	)
	(gr_circle
		(center 31.752794 -349.142558)
		(end 32.641794 -349.142558)
		(stroke
			(width 0.2)
			(type default)
		)
		(fill no)
		(layer "In3.Cu")
	)
	(gr_circle
		(center 31.778194 -349.904558)
		(end 32.667194 -349.904558)
		(stroke
			(width 0.2)
			(type default)
		)
		(fill no)
		(layer "In3.Cu")
	)
	(gr_circle
		(center 32.311594 -350.260158)
		(end 33.200594 -350.260158)
		(stroke
			(width 0.2)
			(type default)
		)
		(fill no)
		(layer "In3.Cu")
	)
	(gr_circle
		(center 32.311594 -349.523558)
		(end 33.200594 -349.523558)
		(stroke
			(width 0.2)
			(type default)
		)
		(fill no)
		(layer "In3.Cu")
	)
	(gr_circle
		(center 32.311594 -348.786958)
		(end 33.200594 -348.786958)
		(stroke
			(width 0.2)
			(type default)
		)
		(fill no)
		(layer "In3.Cu")
	)
	(gr_circle
		(center 37.571934 -348.709488)
		(end 38.452044 -348.709488)
		(stroke
			(width 0.2)
			(type default)
		)
		(fill no)
		(layer "In3.Cu")
	)
	(gr_circle
		(center 38.189154 -348.709488)
		(end 39.069264 -348.709488)
		(stroke
			(width 0.2)
			(type default)
		)
		(fill no)
		(layer "In3.Cu")
	)
	(gr_circle
		(center 38.806374 -348.709488)
		(end 39.686484 -348.709488)
		(stroke
			(width 0.2)
			(type default)
		)
		(fill no)
		(layer "In3.Cu")
	)
	(gr_circle
		(center 39.050214 -347.974158)
		(end 39.939214 -347.974158)
		(stroke
			(width 0.2)
			(type default)
		)
		(fill no)
		(layer "In3.Cu")
	)
	(gr_circle
		(center 39.050214 -347.237558)
		(end 39.939214 -347.237558)
		(stroke
			(width 0.2)
			(type default)
		)
		(fill no)
		(layer "In3.Cu")
	)
	(gr_circle
		(center 39.50843 -350.318578)
		(end 40.39743 -350.318578)
		(stroke
			(width 0.2)
			(type default)
		)
		(fill no)
		(layer "In3.Cu")
	)
	(gr_circle
		(center 39.50843 -349.581978)
		(end 40.39743 -349.581978)
		(stroke
			(width 0.2)
			(type default)
		)
		(fill no)
		(layer "In3.Cu")
	)
	(gr_circle
		(center 40.033194 -349.142558)
		(end 40.922194 -349.142558)
		(stroke
			(width 0.2)
			(type default)
		)
		(fill no)
		(layer "In3.Cu")
	)
	(gr_circle
		(center 40.058594 -349.904558)
		(end 40.947594 -349.904558)
		(stroke
			(width 0.2)
			(type default)
		)
		(fill no)
		(layer "In3.Cu")
	)
	(gr_circle
		(center 40.591994 -350.260158)
		(end 41.480994 -350.260158)
		(stroke
			(width 0.2)
			(type default)
		)
		(fill no)
		(layer "In3.Cu")
	)
	(gr_circle
		(center 40.591994 -349.523558)
		(end 41.480994 -349.523558)
		(stroke
			(width 0.2)
			(type default)
		)
		(fill no)
		(layer "In3.Cu")
	)
	(gr_circle
		(center 40.591994 -348.786958)
		(end 41.480994 -348.786958)
		(stroke
			(width 0.2)
			(type default)
		)
		(fill no)
		(layer "In3.Cu")
	)
	(gr_circle
		(center 41.369742 -358.549194)
		(end 42.258742 -358.549194)
		(stroke
			(width 0.2)
			(type default)
		)
		(fill no)
		(layer "In3.Cu")
	)
	(gr_circle
		(center 41.417494 -357.898192)
		(end 42.306494 -357.898192)
		(stroke
			(width 0.2)
			(type default)
		)
		(fill no)
		(layer "In3.Cu")
	)
	(gr_circle
		(center 41.417494 -357.263192)
		(end 42.306494 -357.263192)
		(stroke
			(width 0.2)
			(type default)
		)
		(fill no)
		(layer "In3.Cu")
	)
	(gr_circle
		(center 41.427146 -359.2576)
		(end 42.316146 -359.2576)
		(stroke
			(width 0.2)
			(type default)
		)
		(fill no)
		(layer "In3.Cu")
	)
	(gr_circle
		(center 43.935904 -358.51084)
		(end 44.824904 -358.51084)
		(stroke
			(width 0.2)
			(type default)
		)
		(fill no)
		(layer "In3.Cu")
	)
	(gr_circle
		(center 43.983656 -357.859838)
		(end 44.872656 -357.859838)
		(stroke
			(width 0.2)
			(type default)
		)
		(fill no)
		(layer "In3.Cu")
	)
	(gr_circle
		(center 43.983656 -357.224838)
		(end 44.872656 -357.224838)
		(stroke
			(width 0.2)
			(type default)
		)
		(fill no)
		(layer "In3.Cu")
	)
	(gr_circle
		(center 43.993308 -359.219246)
		(end 44.882308 -359.219246)
		(stroke
			(width 0.2)
			(type default)
		)
		(fill no)
		(layer "In3.Cu")
	)
	(gr_circle
		(center 45.877734 -348.709488)
		(end 46.757844 -348.709488)
		(stroke
			(width 0.2)
			(type default)
		)
		(fill no)
		(layer "In3.Cu")
	)
	(gr_circle
		(center 46.494954 -348.709488)
		(end 47.375064 -348.709488)
		(stroke
			(width 0.2)
			(type default)
		)
		(fill no)
		(layer "In3.Cu")
	)
	(gr_circle
		(center 47.112174 -348.709488)
		(end 47.992284 -348.709488)
		(stroke
			(width 0.2)
			(type default)
		)
		(fill no)
		(layer "In3.Cu")
	)
	(gr_circle
		(center 47.366174 -348.017338)
		(end 48.255174 -348.017338)
		(stroke
			(width 0.2)
			(type default)
		)
		(fill no)
		(layer "In3.Cu")
	)
	(gr_circle
		(center 47.366174 -347.280738)
		(end 48.255174 -347.280738)
		(stroke
			(width 0.2)
			(type default)
		)
		(fill no)
		(layer "In3.Cu")
	)
	(gr_circle
		(center 47.81423 -350.318578)
		(end 48.70323 -350.318578)
		(stroke
			(width 0.2)
			(type default)
		)
		(fill no)
		(layer "In3.Cu")
	)
	(gr_circle
		(center 47.81423 -349.581978)
		(end 48.70323 -349.581978)
		(stroke
			(width 0.2)
			(type default)
		)
		(fill no)
		(layer "In3.Cu")
	)
	(gr_circle
		(center 47.880778 -358.108504)
		(end 48.769778 -358.108504)
		(stroke
			(width 0.2)
			(type default)
		)
		(fill no)
		(layer "In3.Cu")
	)
	(gr_circle
		(center 47.92853 -357.457502)
		(end 48.81753 -357.457502)
		(stroke
			(width 0.2)
			(type default)
		)
		(fill no)
		(layer "In3.Cu")
	)
	(gr_circle
		(center 47.92853 -356.822502)
		(end 48.81753 -356.822502)
		(stroke
			(width 0.2)
			(type default)
		)
		(fill no)
		(layer "In3.Cu")
	)
	(gr_circle
		(center 48.338994 -349.142558)
		(end 49.227994 -349.142558)
		(stroke
			(width 0.2)
			(type default)
		)
		(fill no)
		(layer "In3.Cu")
	)
	(gr_circle
		(center 48.364394 -349.904558)
		(end 49.253394 -349.904558)
		(stroke
			(width 0.2)
			(type default)
		)
		(fill no)
		(layer "In3.Cu")
	)
	(gr_circle
		(center 48.718978 -358.108504)
		(end 49.607978 -358.108504)
		(stroke
			(width 0.2)
			(type default)
		)
		(fill no)
		(layer "In3.Cu")
	)
	(gr_circle
		(center 48.76673 -357.457502)
		(end 49.65573 -357.457502)
		(stroke
			(width 0.2)
			(type default)
		)
		(fill no)
		(layer "In3.Cu")
	)
	(gr_circle
		(center 48.76673 -356.822502)
		(end 49.65573 -356.822502)
		(stroke
			(width 0.2)
			(type default)
		)
		(fill no)
		(layer "In3.Cu")
	)
	(gr_circle
		(center 48.897794 -350.260158)
		(end 49.786794 -350.260158)
		(stroke
			(width 0.2)
			(type default)
		)
		(fill no)
		(layer "In3.Cu")
	)
	(gr_circle
		(center 48.897794 -349.523558)
		(end 49.786794 -349.523558)
		(stroke
			(width 0.2)
			(type default)
		)
		(fill no)
		(layer "In3.Cu")
	)
	(gr_circle
		(center 48.897794 -348.786958)
		(end 49.786794 -348.786958)
		(stroke
			(width 0.2)
			(type default)
		)
		(fill no)
		(layer "In3.Cu")
	)
	(gr_circle
		(center 49.353978 -358.108504)
		(end 50.242978 -358.108504)
		(stroke
			(width 0.2)
			(type default)
		)
		(fill no)
		(layer "In3.Cu")
	)
	(gr_circle
		(center 49.40173 -357.457502)
		(end 50.29073 -357.457502)
		(stroke
			(width 0.2)
			(type default)
		)
		(fill no)
		(layer "In3.Cu")
	)
	(gr_circle
		(center 49.40173 -356.822502)
		(end 50.29073 -356.822502)
		(stroke
			(width 0.2)
			(type default)
		)
		(fill no)
		(layer "In3.Cu")
	)
	(gr_circle
		(center 49.988978 -358.108504)
		(end 50.877978 -358.108504)
		(stroke
			(width 0.2)
			(type default)
		)
		(fill no)
		(layer "In3.Cu")
	)
	(gr_circle
		(center 50.03673 -357.457502)
		(end 50.92573 -357.457502)
		(stroke
			(width 0.2)
			(type default)
		)
		(fill no)
		(layer "In3.Cu")
	)
	(gr_circle
		(center 50.03673 -356.822502)
		(end 50.92573 -356.822502)
		(stroke
			(width 0.2)
			(type default)
		)
		(fill no)
		(layer "In3.Cu")
	)
	(gr_circle
		(center 50.623978 -358.108504)
		(end 51.512978 -358.108504)
		(stroke
			(width 0.2)
			(type default)
		)
		(fill no)
		(layer "In3.Cu")
	)
	(gr_circle
		(center 50.67173 -357.457502)
		(end 51.56073 -357.457502)
		(stroke
			(width 0.2)
			(type default)
		)
		(fill no)
		(layer "In3.Cu")
	)
	(gr_circle
		(center 50.67173 -356.822502)
		(end 51.56073 -356.822502)
		(stroke
			(width 0.2)
			(type default)
		)
		(fill no)
		(layer "In3.Cu")
	)
	(gr_circle
		(center 54.234334 -348.709488)
		(end 55.114444 -348.709488)
		(stroke
			(width 0.2)
			(type default)
		)
		(fill no)
		(layer "In3.Cu")
	)
	(gr_circle
		(center 54.851554 -348.709488)
		(end 55.731664 -348.709488)
		(stroke
			(width 0.2)
			(type default)
		)
		(fill no)
		(layer "In3.Cu")
	)
	(gr_circle
		(center 55.468774 -348.709488)
		(end 56.348884 -348.709488)
		(stroke
			(width 0.2)
			(type default)
		)
		(fill no)
		(layer "In3.Cu")
	)
	(gr_circle
		(center 55.727854 -347.997018)
		(end 56.616854 -347.997018)
		(stroke
			(width 0.2)
			(type default)
		)
		(fill no)
		(layer "In3.Cu")
	)
	(gr_circle
		(center 55.727854 -347.260418)
		(end 56.616854 -347.260418)
		(stroke
			(width 0.2)
			(type default)
		)
		(fill no)
		(layer "In3.Cu")
	)
	(gr_circle
		(center 56.17083 -350.318578)
		(end 57.05983 -350.318578)
		(stroke
			(width 0.2)
			(type default)
		)
		(fill no)
		(layer "In3.Cu")
	)
	(gr_circle
		(center 56.17083 -349.581978)
		(end 57.05983 -349.581978)
		(stroke
			(width 0.2)
			(type default)
		)
		(fill no)
		(layer "In3.Cu")
	)
	(gr_circle
		(center 56.695594 -349.142558)
		(end 57.584594 -349.142558)
		(stroke
			(width 0.2)
			(type default)
		)
		(fill no)
		(layer "In3.Cu")
	)
	(gr_circle
		(center 56.720994 -349.904558)
		(end 57.609994 -349.904558)
		(stroke
			(width 0.2)
			(type default)
		)
		(fill no)
		(layer "In3.Cu")
	)
	(gr_circle
		(center 57.254394 -350.260158)
		(end 58.143394 -350.260158)
		(stroke
			(width 0.2)
			(type default)
		)
		(fill no)
		(layer "In3.Cu")
	)
	(gr_circle
		(center 57.254394 -349.523558)
		(end 58.143394 -349.523558)
		(stroke
			(width 0.2)
			(type default)
		)
		(fill no)
		(layer "In3.Cu")
	)
	(gr_circle
		(center 57.254394 -348.786958)
		(end 58.143394 -348.786958)
		(stroke
			(width 0.2)
			(type default)
		)
		(fill no)
		(layer "In3.Cu")
	)
	(gr_circle
		(center 61.93663 -166.86276)
		(end 62.82563 -166.86276)
		(stroke
			(width 0.2)
			(type default)
		)
		(fill no)
		(layer "In3.Cu")
	)
	(gr_circle
		(center 61.93663 -166.12616)
		(end 62.82563 -166.12616)
		(stroke
			(width 0.2)
			(type default)
		)
		(fill no)
		(layer "In3.Cu")
	)
	(gr_circle
		(center 61.93663 -165.38956)
		(end 62.82563 -165.38956)
		(stroke
			(width 0.2)
			(type default)
		)
		(fill no)
		(layer "In3.Cu")
	)
	(gr_circle
		(center 62.47003 -165.74516)
		(end 63.35903 -165.74516)
		(stroke
			(width 0.2)
			(type default)
		)
		(fill no)
		(layer "In3.Cu")
	)
	(gr_circle
		(center 62.49543 -166.50716)
		(end 63.38443 -166.50716)
		(stroke
			(width 0.2)
			(type default)
		)
		(fill no)
		(layer "In3.Cu")
	)
	(gr_circle
		(center 62.565534 -348.709488)
		(end 63.445644 -348.709488)
		(stroke
			(width 0.2)
			(type default)
		)
		(fill no)
		(layer "In3.Cu")
	)
	(gr_circle
		(center 63.020194 -166.06774)
		(end 63.909194 -166.06774)
		(stroke
			(width 0.2)
			(type default)
		)
		(fill no)
		(layer "In3.Cu")
	)
	(gr_circle
		(center 63.020194 -165.33114)
		(end 63.909194 -165.33114)
		(stroke
			(width 0.2)
			(type default)
		)
		(fill no)
		(layer "In3.Cu")
	)
	(gr_circle
		(center 63.182754 -348.709488)
		(end 64.062864 -348.709488)
		(stroke
			(width 0.2)
			(type default)
		)
		(fill no)
		(layer "In3.Cu")
	)
	(gr_circle
		(center 63.199264 -12.43711)
		(end 64.088264 -12.43711)
		(stroke
			(width 0.2)
			(type default)
		)
		(fill no)
		(layer "In3.Cu")
	)
	(gr_circle
		(center 63.579248 -168.42232)
		(end 64.468248 -168.42232)
		(stroke
			(width 0.2)
			(type default)
		)
		(fill no)
		(layer "In3.Cu")
	)
	(gr_circle
		(center 63.579248 -167.68572)
		(end 64.468248 -167.68572)
		(stroke
			(width 0.2)
			(type default)
		)
		(fill no)
		(layer "In3.Cu")
	)
	(gr_circle
		(center 63.631064 -13.09751)
		(end 64.520064 -13.09751)
		(stroke
			(width 0.2)
			(type default)
		)
		(fill no)
		(layer "In3.Cu")
	)
	(gr_circle
		(center 63.72225 -166.94023)
		(end 64.60236 -166.94023)
		(stroke
			(width 0.2)
			(type default)
		)
		(fill no)
		(layer "In3.Cu")
	)
	(gr_circle
		(center 63.799974 -348.709488)
		(end 64.680084 -348.709488)
		(stroke
			(width 0.2)
			(type default)
		)
		(fill no)
		(layer "In3.Cu")
	)
	(gr_circle
		(center 64.061594 -348.038928)
		(end 64.941704 -348.038928)
		(stroke
			(width 0.2)
			(type default)
		)
		(fill no)
		(layer "In3.Cu")
	)
	(gr_circle
		(center 64.061594 -347.302328)
		(end 64.941704 -347.302328)
		(stroke
			(width 0.2)
			(type default)
		)
		(fill no)
		(layer "In3.Cu")
	)
	(gr_circle
		(center 64.088264 -12.43711)
		(end 64.977264 -12.43711)
		(stroke
			(width 0.2)
			(type default)
		)
		(fill no)
		(layer "In3.Cu")
	)
	(gr_circle
		(center 64.33947 -166.94023)
		(end 65.21958 -166.94023)
		(stroke
			(width 0.2)
			(type default)
		)
		(fill no)
		(layer "In3.Cu")
	)
	(gr_circle
		(center 64.50203 -350.318578)
		(end 65.39103 -350.318578)
		(stroke
			(width 0.2)
			(type default)
		)
		(fill no)
		(layer "In3.Cu")
	)
	(gr_circle
		(center 64.50203 -349.581978)
		(end 65.39103 -349.581978)
		(stroke
			(width 0.2)
			(type default)
		)
		(fill no)
		(layer "In3.Cu")
	)
	(gr_circle
		(center 64.520064 -13.09751)
		(end 65.409064 -13.09751)
		(stroke
			(width 0.2)
			(type default)
		)
		(fill no)
		(layer "In3.Cu")
	)
	(gr_circle
		(center 64.95669 -166.94023)
		(end 65.8368 -166.94023)
		(stroke
			(width 0.2)
			(type default)
		)
		(fill no)
		(layer "In3.Cu")
	)
	(gr_circle
		(center 64.977264 -12.43711)
		(end 65.866264 -12.43711)
		(stroke
			(width 0.2)
			(type default)
		)
		(fill no)
		(layer "In3.Cu")
	)
	(gr_circle
		(center 65.026794 -349.142558)
		(end 65.915794 -349.142558)
		(stroke
			(width 0.2)
			(type default)
		)
		(fill no)
		(layer "In3.Cu")
	)
	(gr_circle
		(center 65.052194 -349.904558)
		(end 65.941194 -349.904558)
		(stroke
			(width 0.2)
			(type default)
		)
		(fill no)
		(layer "In3.Cu")
	)
	(gr_circle
		(center 65.409064 -13.09751)
		(end 66.298064 -13.09751)
		(stroke
			(width 0.2)
			(type default)
		)
		(fill no)
		(layer "In3.Cu")
	)
	(gr_circle
		(center 65.585594 -350.260158)
		(end 66.474594 -350.260158)
		(stroke
			(width 0.2)
			(type default)
		)
		(fill no)
		(layer "In3.Cu")
	)
	(gr_circle
		(center 65.585594 -349.523558)
		(end 66.474594 -349.523558)
		(stroke
			(width 0.2)
			(type default)
		)
		(fill no)
		(layer "In3.Cu")
	)
	(gr_circle
		(center 65.585594 -348.786958)
		(end 66.474594 -348.786958)
		(stroke
			(width 0.2)
			(type default)
		)
		(fill no)
		(layer "In3.Cu")
	)
	(gr_circle
		(center 65.866264 -12.43711)
		(end 66.755264 -12.43711)
		(stroke
			(width 0.2)
			(type default)
		)
		(fill no)
		(layer "In3.Cu")
	)
	(gr_circle
		(center 66.298064 -13.09751)
		(end 67.187064 -13.09751)
		(stroke
			(width 0.2)
			(type default)
		)
		(fill no)
		(layer "In3.Cu")
	)
	(gr_circle
		(center 66.399664 -25.56891)
		(end 67.288664 -25.56891)
		(stroke
			(width 0.2)
			(type default)
		)
		(fill no)
		(layer "In3.Cu")
	)
	(gr_circle
		(center 66.501264 -12.43711)
		(end 67.390264 -12.43711)
		(stroke
			(width 0.2)
			(type default)
		)
		(fill no)
		(layer "In3.Cu")
	)
	(gr_circle
		(center 66.774822 -20.327366)
		(end 67.663822 -20.327366)
		(stroke
			(width 0.2)
			(type default)
		)
		(fill no)
		(layer "In3.Cu")
	)
	(gr_circle
		(center 66.774822 -19.692366)
		(end 67.663822 -19.692366)
		(stroke
			(width 0.2)
			(type default)
		)
		(fill no)
		(layer "In3.Cu")
	)
	(gr_circle
		(center 66.780664 -24.88311)
		(end 67.669664 -24.88311)
		(stroke
			(width 0.2)
			(type default)
		)
		(fill no)
		(layer "In3.Cu")
	)
	(gr_circle
		(center 66.848228 -18.642584)
		(end 67.737228 -18.642584)
		(stroke
			(width 0.2)
			(type default)
		)
		(fill no)
		(layer "In3.Cu")
	)
	(gr_circle
		(center 66.882264 -22.26691)
		(end 67.771264 -22.26691)
		(stroke
			(width 0.2)
			(type default)
		)
		(fill no)
		(layer "In3.Cu")
	)
	(gr_circle
		(center 66.933064 -13.09751)
		(end 67.822064 -13.09751)
		(stroke
			(width 0.2)
			(type default)
		)
		(fill no)
		(layer "In3.Cu")
	)
	(gr_circle
		(center 67.288664 -25.56891)
		(end 68.177664 -25.56891)
		(stroke
			(width 0.2)
			(type default)
		)
		(fill no)
		(layer "In3.Cu")
	)
	(gr_circle
		(center 67.40271 -12.489434)
		(end 68.29171 -12.489434)
		(stroke
			(width 0.2)
			(type default)
		)
		(fill no)
		(layer "In3.Cu")
	)
	(gr_circle
		(center 67.669664 -24.88311)
		(end 68.558664 -24.88311)
		(stroke
			(width 0.2)
			(type default)
		)
		(fill no)
		(layer "In3.Cu")
	)
	(gr_circle
		(center 68.177664 -25.56891)
		(end 69.066664 -25.56891)
		(stroke
			(width 0.2)
			(type default)
		)
		(fill no)
		(layer "In3.Cu")
	)
	(gr_circle
		(center 68.54444 -18.476214)
		(end 69.43344 -18.476214)
		(stroke
			(width 0.2)
			(type default)
		)
		(fill no)
		(layer "In3.Cu")
	)
	(gr_circle
		(center 68.558664 -24.88311)
		(end 69.447664 -24.88311)
		(stroke
			(width 0.2)
			(type default)
		)
		(fill no)
		(layer "In3.Cu")
	)
	(gr_circle
		(center 69.498464 -24.55291)
		(end 70.387464 -24.55291)
		(stroke
			(width 0.2)
			(type default)
		)
		(fill no)
		(layer "In3.Cu")
	)
	(gr_circle
		(center 70.25005 -175.559974)
		(end 71.13905 -175.559974)
		(stroke
			(width 0.2)
			(type default)
		)
		(fill no)
		(layer "In3.Cu")
	)
	(gr_circle
		(center 70.25005 -174.823374)
		(end 71.13905 -174.823374)
		(stroke
			(width 0.2)
			(type default)
		)
		(fill no)
		(layer "In3.Cu")
	)
	(gr_circle
		(center 70.25005 -174.086774)
		(end 71.13905 -174.086774)
		(stroke
			(width 0.2)
			(type default)
		)
		(fill no)
		(layer "In3.Cu")
	)
	(gr_circle
		(center 70.78345 -174.442374)
		(end 71.67245 -174.442374)
		(stroke
			(width 0.2)
			(type default)
		)
		(fill no)
		(layer "In3.Cu")
	)
	(gr_circle
		(center 70.80885 -175.204374)
		(end 71.69785 -175.204374)
		(stroke
			(width 0.2)
			(type default)
		)
		(fill no)
		(layer "In3.Cu")
	)
	(gr_circle
		(center 71.099934 -336.988404)
		(end 71.980044 -336.988404)
		(stroke
			(width 0.2)
			(type default)
		)
		(fill no)
		(layer "In3.Cu")
	)
	(gr_circle
		(center 71.333614 -174.764954)
		(end 72.222614 -174.764954)
		(stroke
			(width 0.2)
			(type default)
		)
		(fill no)
		(layer "In3.Cu")
	)
	(gr_circle
		(center 71.333614 -174.028354)
		(end 72.222614 -174.028354)
		(stroke
			(width 0.2)
			(type default)
		)
		(fill no)
		(layer "In3.Cu")
	)
	(gr_circle
		(center 71.717154 -336.988404)
		(end 72.597264 -336.988404)
		(stroke
			(width 0.2)
			(type default)
		)
		(fill no)
		(layer "In3.Cu")
	)
	(gr_circle
		(center 71.892668 -177.10912)
		(end 72.781668 -177.10912)
		(stroke
			(width 0.2)
			(type default)
		)
		(fill no)
		(layer "In3.Cu")
	)
	(gr_circle
		(center 71.892668 -176.37252)
		(end 72.781668 -176.37252)
		(stroke
			(width 0.2)
			(type default)
		)
		(fill no)
		(layer "In3.Cu")
	)
	(gr_circle
		(center 72.03567 -175.639222)
		(end 72.91578 -175.639222)
		(stroke
			(width 0.2)
			(type default)
		)
		(fill no)
		(layer "In3.Cu")
	)
	(gr_circle
		(center 72.334374 -336.988404)
		(end 73.214484 -336.988404)
		(stroke
			(width 0.2)
			(type default)
		)
		(fill no)
		(layer "In3.Cu")
	)
	(gr_circle
		(center 72.616314 -336.255868)
		(end 73.496424 -336.255868)
		(stroke
			(width 0.2)
			(type default)
		)
		(fill no)
		(layer "In3.Cu")
	)
	(gr_circle
		(center 72.616314 -335.519268)
		(end 73.496424 -335.519268)
		(stroke
			(width 0.2)
			(type default)
		)
		(fill no)
		(layer "In3.Cu")
	)
	(gr_circle
		(center 72.65289 -175.639222)
		(end 73.533 -175.639222)
		(stroke
			(width 0.2)
			(type default)
		)
		(fill no)
		(layer "In3.Cu")
	)
	(gr_circle
		(center 73.03643 -338.597494)
		(end 73.92543 -338.597494)
		(stroke
			(width 0.2)
			(type default)
		)
		(fill no)
		(layer "In3.Cu")
	)
	(gr_circle
		(center 73.03643 -337.860894)
		(end 73.92543 -337.860894)
		(stroke
			(width 0.2)
			(type default)
		)
		(fill no)
		(layer "In3.Cu")
	)
	(gr_circle
		(center 73.27011 -175.639222)
		(end 74.15022 -175.639222)
		(stroke
			(width 0.2)
			(type default)
		)
		(fill no)
		(layer "In3.Cu")
	)
	(gr_circle
		(center 73.561194 -337.421474)
		(end 74.450194 -337.421474)
		(stroke
			(width 0.2)
			(type default)
		)
		(fill no)
		(layer "In3.Cu")
	)
	(gr_circle
		(center 73.586594 -338.183474)
		(end 74.475594 -338.183474)
		(stroke
			(width 0.2)
			(type default)
		)
		(fill no)
		(layer "In3.Cu")
	)
	(gr_circle
		(center 74.119994 -338.539074)
		(end 75.008994 -338.539074)
		(stroke
			(width 0.2)
			(type default)
		)
		(fill no)
		(layer "In3.Cu")
	)
	(gr_circle
		(center 74.119994 -337.802474)
		(end 75.008994 -337.802474)
		(stroke
			(width 0.2)
			(type default)
		)
		(fill no)
		(layer "In3.Cu")
	)
	(gr_circle
		(center 74.119994 -337.065874)
		(end 75.008994 -337.065874)
		(stroke
			(width 0.2)
			(type default)
		)
		(fill no)
		(layer "In3.Cu")
	)
	(gr_circle
		(center 74.811382 -351.637854)
		(end 75.700382 -351.637854)
		(stroke
			(width 0.2)
			(type default)
		)
		(fill no)
		(layer "In3.Cu")
	)
	(gr_circle
		(center 74.849482 -353.131374)
		(end 75.738482 -353.131374)
		(stroke
			(width 0.2)
			(type default)
		)
		(fill no)
		(layer "In3.Cu")
	)
	(gr_circle
		(center 74.849736 -352.30816)
		(end 75.738736 -352.30816)
		(stroke
			(width 0.2)
			(type default)
		)
		(fill no)
		(layer "In3.Cu")
	)
	(gr_circle
		(center 74.86015 -350.929448)
		(end 75.74915 -350.929448)
		(stroke
			(width 0.2)
			(type default)
		)
		(fill no)
		(layer "In3.Cu")
	)
	(gr_circle
		(center 77.178408 -16.520668)
		(end 78.067408 -16.520668)
		(stroke
			(width 0.2)
			(type default)
		)
		(fill no)
		(layer "In3.Cu")
	)
	(gr_circle
		(center 77.473048 -351.5995)
		(end 78.362048 -351.5995)
		(stroke
			(width 0.2)
			(type default)
		)
		(fill no)
		(layer "In3.Cu")
	)
	(gr_circle
		(center 77.511402 -352.978212)
		(end 78.400402 -352.978212)
		(stroke
			(width 0.2)
			(type default)
		)
		(fill no)
		(layer "In3.Cu")
	)
	(gr_circle
		(center 77.511402 -352.269806)
		(end 78.400402 -352.269806)
		(stroke
			(width 0.2)
			(type default)
		)
		(fill no)
		(layer "In3.Cu")
	)
	(gr_circle
		(center 77.521816 -350.891094)
		(end 78.410816 -350.891094)
		(stroke
			(width 0.2)
			(type default)
		)
		(fill no)
		(layer "In3.Cu")
	)
	(gr_circle
		(center 77.84338 -16.55064)
		(end 78.73238 -16.55064)
		(stroke
			(width 0.2)
			(type default)
		)
		(fill no)
		(layer "In3.Cu")
	)
	(gr_circle
		(center 78.85303 -178.798474)
		(end 79.74203 -178.798474)
		(stroke
			(width 0.2)
			(type default)
		)
		(fill no)
		(layer "In3.Cu")
	)
	(gr_circle
		(center 78.85303 -178.036474)
		(end 79.74203 -178.036474)
		(stroke
			(width 0.2)
			(type default)
		)
		(fill no)
		(layer "In3.Cu")
	)
	(gr_circle
		(center 79.10703 -179.560474)
		(end 79.99603 -179.560474)
		(stroke
			(width 0.2)
			(type default)
		)
		(fill no)
		(layer "In3.Cu")
	)
	(gr_circle
		(center 79.13243 -180.322474)
		(end 80.02143 -180.322474)
		(stroke
			(width 0.2)
			(type default)
		)
		(fill no)
		(layer "In3.Cu")
	)
	(gr_circle
		(center 79.403194 -178.384454)
		(end 80.292194 -178.384454)
		(stroke
			(width 0.2)
			(type default)
		)
		(fill no)
		(layer "In3.Cu")
	)
	(gr_circle
		(center 79.455518 -336.981292)
		(end 80.335628 -336.981292)
		(stroke
			(width 0.2)
			(type default)
		)
		(fill no)
		(layer "In3.Cu")
	)
	(gr_circle
		(center 79.657194 -179.883054)
		(end 80.546194 -179.883054)
		(stroke
			(width 0.2)
			(type default)
		)
		(fill no)
		(layer "In3.Cu")
	)
	(gr_circle
		(center 79.657194 -179.146454)
		(end 80.546194 -179.146454)
		(stroke
			(width 0.2)
			(type default)
		)
		(fill no)
		(layer "In3.Cu")
	)
	(gr_circle
		(center 79.921862 -18.238724)
		(end 80.810862 -18.238724)
		(stroke
			(width 0.2)
			(type default)
		)
		(fill no)
		(layer "In3.Cu")
	)
	(gr_circle
		(center 79.921862 -17.502124)
		(end 80.810862 -17.502124)
		(stroke
			(width 0.2)
			(type default)
		)
		(fill no)
		(layer "In3.Cu")
	)
	(gr_circle
		(center 80.072738 -336.981292)
		(end 80.952848 -336.981292)
		(stroke
			(width 0.2)
			(type default)
		)
		(fill no)
		(layer "In3.Cu")
	)
	(gr_circle
		(center 80.241648 -182.2196)
		(end 81.130648 -182.2196)
		(stroke
			(width 0.2)
			(type default)
		)
		(fill no)
		(layer "In3.Cu")
	)
	(gr_circle
		(center 80.241648 -181.483)
		(end 81.130648 -181.483)
		(stroke
			(width 0.2)
			(type default)
		)
		(fill no)
		(layer "In3.Cu")
	)
	(gr_circle
		(center 80.35925 -180.755544)
		(end 81.23936 -180.755544)
		(stroke
			(width 0.2)
			(type default)
		)
		(fill no)
		(layer "In3.Cu")
	)
	(gr_circle
		(center 80.689958 -336.981292)
		(end 81.570068 -336.981292)
		(stroke
			(width 0.2)
			(type default)
		)
		(fill no)
		(layer "In3.Cu")
	)
	(gr_circle
		(center 80.97647 -180.755544)
		(end 81.85658 -180.755544)
		(stroke
			(width 0.2)
			(type default)
		)
		(fill no)
		(layer "In3.Cu")
	)
	(gr_circle
		(center 80.977994 -336.245708)
		(end 81.858104 -336.245708)
		(stroke
			(width 0.2)
			(type default)
		)
		(fill no)
		(layer "In3.Cu")
	)
	(gr_circle
		(center 80.977994 -335.509108)
		(end 81.858104 -335.509108)
		(stroke
			(width 0.2)
			(type default)
		)
		(fill no)
		(layer "In3.Cu")
	)
	(gr_circle
		(center 81.392014 -338.590382)
		(end 82.281014 -338.590382)
		(stroke
			(width 0.2)
			(type default)
		)
		(fill no)
		(layer "In3.Cu")
	)
	(gr_circle
		(center 81.392014 -337.853782)
		(end 82.281014 -337.853782)
		(stroke
			(width 0.2)
			(type default)
		)
		(fill no)
		(layer "In3.Cu")
	)
	(gr_circle
		(center 81.59369 -180.755544)
		(end 82.4738 -180.755544)
		(stroke
			(width 0.2)
			(type default)
		)
		(fill no)
		(layer "In3.Cu")
	)
	(gr_arc
		(start 81.701894 -9.780016)
		(mid 82.287679 -11.194227)
		(end 83.70189 -11.780012)
		(stroke
			(width 1.016)
			(type default)
		)
		(layer "In3.Cu")
	)
	(gr_arc
		(start 81.701894 -0.500126)
		(mid 81.555625 -0.146451)
		(end 81.202022 0)
		(stroke
			(width 1.016)
			(type default)
		)
		(layer "In3.Cu")
	)
	(gr_line
		(start 81.701894 -0.500126)
		(end 81.701894 -9.780016)
		(stroke
			(width 1.016)
			(type default)
		)
		(layer "In3.Cu")
	)
	(gr_circle
		(center 81.916778 -337.414362)
		(end 82.805778 -337.414362)
		(stroke
			(width 0.2)
			(type default)
		)
		(fill no)
		(layer "In3.Cu")
	)
	(gr_circle
		(center 81.942178 -338.176362)
		(end 82.831178 -338.176362)
		(stroke
			(width 0.2)
			(type default)
		)
		(fill no)
		(layer "In3.Cu")
	)
	(gr_circle
		(center 82.183986 -348.89948)
		(end 83.072986 -348.89948)
		(stroke
			(width 0.2)
			(type default)
		)
		(fill no)
		(layer "In3.Cu")
	)
	(gr_circle
		(center 82.222086 -350.393)
		(end 83.111086 -350.393)
		(stroke
			(width 0.2)
			(type default)
		)
		(fill no)
		(layer "In3.Cu")
	)
	(gr_circle
		(center 82.22234 -349.569786)
		(end 83.11134 -349.569786)
		(stroke
			(width 0.2)
			(type default)
		)
		(fill no)
		(layer "In3.Cu")
	)
	(gr_circle
		(center 82.232754 -348.191074)
		(end 83.121754 -348.191074)
		(stroke
			(width 0.2)
			(type default)
		)
		(fill no)
		(layer "In3.Cu")
	)
	(gr_circle
		(center 82.475578 -338.531962)
		(end 83.364578 -338.531962)
		(stroke
			(width 0.2)
			(type default)
		)
		(fill no)
		(layer "In3.Cu")
	)
	(gr_circle
		(center 82.475578 -337.795362)
		(end 83.364578 -337.795362)
		(stroke
			(width 0.2)
			(type default)
		)
		(fill no)
		(layer "In3.Cu")
	)
	(gr_circle
		(center 82.475578 -337.058762)
		(end 83.364578 -337.058762)
		(stroke
			(width 0.2)
			(type default)
		)
		(fill no)
		(layer "In3.Cu")
	)
	(gr_circle
		(center 82.989674 -165.962076)
		(end 84.386674 -165.962076)
		(stroke
			(width 0.2)
			(type default)
		)
		(fill no)
		(layer "In3.Cu")
	)
	(gr_line
		(start 83.70189 -11.780012)
		(end 124.102114 -11.780012)
		(stroke
			(width 1.016)
			(type default)
		)
		(layer "In3.Cu")
	)
	(gr_circle
		(center 84.845652 -348.861126)
		(end 85.734652 -348.861126)
		(stroke
			(width 0.2)
			(type default)
		)
		(fill no)
		(layer "In3.Cu")
	)
	(gr_circle
		(center 84.884006 -350.239838)
		(end 85.773006 -350.239838)
		(stroke
			(width 0.2)
			(type default)
		)
		(fill no)
		(layer "In3.Cu")
	)
	(gr_circle
		(center 84.884006 -349.531432)
		(end 85.773006 -349.531432)
		(stroke
			(width 0.2)
			(type default)
		)
		(fill no)
		(layer "In3.Cu")
	)
	(gr_circle
		(center 84.89442 -348.15272)
		(end 85.78342 -348.15272)
		(stroke
			(width 0.2)
			(type default)
		)
		(fill no)
		(layer "In3.Cu")
	)
	(gr_circle
		(center 86.97087 -180.610002)
		(end 87.85987 -180.610002)
		(stroke
			(width 0.2)
			(type default)
		)
		(fill no)
		(layer "In3.Cu")
	)
	(gr_circle
		(center 86.97087 -179.873402)
		(end 87.85987 -179.873402)
		(stroke
			(width 0.2)
			(type default)
		)
		(fill no)
		(layer "In3.Cu")
	)
	(gr_circle
		(center 86.97087 -179.136802)
		(end 87.85987 -179.136802)
		(stroke
			(width 0.2)
			(type default)
		)
		(fill no)
		(layer "In3.Cu")
	)
	(gr_circle
		(center 87.01913 -164.097716)
		(end 87.90813 -164.097716)
		(stroke
			(width 0.2)
			(type default)
		)
		(fill no)
		(layer "In3.Cu")
	)
	(gr_circle
		(center 87.03945 -163.447476)
		(end 87.92845 -163.447476)
		(stroke
			(width 0.2)
			(type default)
		)
		(fill no)
		(layer "In3.Cu")
	)
	(gr_circle
		(center 87.03945 -162.812476)
		(end 87.92845 -162.812476)
		(stroke
			(width 0.2)
			(type default)
		)
		(fill no)
		(layer "In3.Cu")
	)
	(gr_circle
		(center 87.50427 -179.492402)
		(end 88.39327 -179.492402)
		(stroke
			(width 0.2)
			(type default)
		)
		(fill no)
		(layer "In3.Cu")
	)
	(gr_circle
		(center 87.52967 -180.254402)
		(end 88.41867 -180.254402)
		(stroke
			(width 0.2)
			(type default)
		)
		(fill no)
		(layer "In3.Cu")
	)
	(gr_circle
		(center 87.65413 -164.097716)
		(end 88.54313 -164.097716)
		(stroke
			(width 0.2)
			(type default)
		)
		(fill no)
		(layer "In3.Cu")
	)
	(gr_circle
		(center 87.67445 -163.447476)
		(end 88.56345 -163.447476)
		(stroke
			(width 0.2)
			(type default)
		)
		(fill no)
		(layer "In3.Cu")
	)
	(gr_circle
		(center 87.67445 -162.812476)
		(end 88.56345 -162.812476)
		(stroke
			(width 0.2)
			(type default)
		)
		(fill no)
		(layer "In3.Cu")
	)
	(gr_circle
		(center 87.813134 -336.966814)
		(end 88.693244 -336.966814)
		(stroke
			(width 0.2)
			(type default)
		)
		(fill no)
		(layer "In3.Cu")
	)
	(gr_circle
		(center 88.054434 -179.814982)
		(end 88.943434 -179.814982)
		(stroke
			(width 0.2)
			(type default)
		)
		(fill no)
		(layer "In3.Cu")
	)
	(gr_circle
		(center 88.054434 -179.078382)
		(end 88.943434 -179.078382)
		(stroke
			(width 0.2)
			(type default)
		)
		(fill no)
		(layer "In3.Cu")
	)
	(gr_circle
		(center 88.28913 -164.097716)
		(end 89.17813 -164.097716)
		(stroke
			(width 0.2)
			(type default)
		)
		(fill no)
		(layer "In3.Cu")
	)
	(gr_circle
		(center 88.30945 -163.447476)
		(end 89.19845 -163.447476)
		(stroke
			(width 0.2)
			(type default)
		)
		(fill no)
		(layer "In3.Cu")
	)
	(gr_circle
		(center 88.30945 -162.812476)
		(end 89.19845 -162.812476)
		(stroke
			(width 0.2)
			(type default)
		)
		(fill no)
		(layer "In3.Cu")
	)
	(gr_circle
		(center 88.430354 -336.966814)
		(end 89.310464 -336.966814)
		(stroke
			(width 0.2)
			(type default)
		)
		(fill no)
		(layer "In3.Cu")
	)
	(gr_circle
		(center 88.49233 -182.13324)
		(end 89.38133 -182.13324)
		(stroke
			(width 0.2)
			(type default)
		)
		(fill no)
		(layer "In3.Cu")
	)
	(gr_circle
		(center 88.49233 -181.39664)
		(end 89.38133 -181.39664)
		(stroke
			(width 0.2)
			(type default)
		)
		(fill no)
		(layer "In3.Cu")
	)
	(gr_circle
		(center 88.75649 -180.687472)
		(end 89.6366 -180.687472)
		(stroke
			(width 0.2)
			(type default)
		)
		(fill no)
		(layer "In3.Cu")
	)
	(gr_circle
		(center 88.92413 -164.097716)
		(end 89.81313 -164.097716)
		(stroke
			(width 0.2)
			(type default)
		)
		(fill no)
		(layer "In3.Cu")
	)
	(gr_circle
		(center 88.94445 -163.447476)
		(end 89.83345 -163.447476)
		(stroke
			(width 0.2)
			(type default)
		)
		(fill no)
		(layer "In3.Cu")
	)
	(gr_circle
		(center 88.94445 -162.812476)
		(end 89.83345 -162.812476)
		(stroke
			(width 0.2)
			(type default)
		)
		(fill no)
		(layer "In3.Cu")
	)
	(gr_circle
		(center 89.047574 -336.966814)
		(end 89.927684 -336.966814)
		(stroke
			(width 0.2)
			(type default)
		)
		(fill no)
		(layer "In3.Cu")
	)
	(gr_circle
		(center 89.314528 -345.237562)
		(end 90.203528 -345.237562)
		(stroke
			(width 0.2)
			(type default)
		)
		(fill no)
		(layer "In3.Cu")
	)
	(gr_circle
		(center 89.319354 -336.255868)
		(end 90.199464 -336.255868)
		(stroke
			(width 0.2)
			(type default)
		)
		(fill no)
		(layer "In3.Cu")
	)
	(gr_circle
		(center 89.319354 -335.519268)
		(end 90.199464 -335.519268)
		(stroke
			(width 0.2)
			(type default)
		)
		(fill no)
		(layer "In3.Cu")
	)
	(gr_circle
		(center 89.350088 -345.96959)
		(end 90.239088 -345.96959)
		(stroke
			(width 0.2)
			(type default)
		)
		(fill no)
		(layer "In3.Cu")
	)
	(gr_circle
		(center 89.37371 -180.687472)
		(end 90.25382 -180.687472)
		(stroke
			(width 0.2)
			(type default)
		)
		(fill no)
		(layer "In3.Cu")
	)
	(gr_circle
		(center 89.388442 -346.639896)
		(end 90.277442 -346.639896)
		(stroke
			(width 0.2)
			(type default)
		)
		(fill no)
		(layer "In3.Cu")
	)
	(gr_circle
		(center 89.55913 -164.097716)
		(end 90.44813 -164.097716)
		(stroke
			(width 0.2)
			(type default)
		)
		(fill no)
		(layer "In3.Cu")
	)
	(gr_circle
		(center 89.57945 -163.447476)
		(end 90.46845 -163.447476)
		(stroke
			(width 0.2)
			(type default)
		)
		(fill no)
		(layer "In3.Cu")
	)
	(gr_circle
		(center 89.57945 -162.812476)
		(end 90.46845 -162.812476)
		(stroke
			(width 0.2)
			(type default)
		)
		(fill no)
		(layer "In3.Cu")
	)
	(gr_circle
		(center 89.74963 -338.575904)
		(end 90.63863 -338.575904)
		(stroke
			(width 0.2)
			(type default)
		)
		(fill no)
		(layer "In3.Cu")
	)
	(gr_circle
		(center 89.74963 -337.839304)
		(end 90.63863 -337.839304)
		(stroke
			(width 0.2)
			(type default)
		)
		(fill no)
		(layer "In3.Cu")
	)
	(gr_circle
		(center 89.983056 -345.261184)
		(end 90.872056 -345.261184)
		(stroke
			(width 0.2)
			(type default)
		)
		(fill no)
		(layer "In3.Cu")
	)
	(gr_circle
		(center 89.985088 -345.96959)
		(end 90.874088 -345.96959)
		(stroke
			(width 0.2)
			(type default)
		)
		(fill no)
		(layer "In3.Cu")
	)
	(gr_circle
		(center 89.99093 -180.687472)
		(end 90.87104 -180.687472)
		(stroke
			(width 0.2)
			(type default)
		)
		(fill no)
		(layer "In3.Cu")
	)
	(gr_circle
		(center 90.023442 -346.639896)
		(end 90.912442 -346.639896)
		(stroke
			(width 0.2)
			(type default)
		)
		(fill no)
		(layer "In3.Cu")
	)
	(gr_circle
		(center 90.21953 -164.107876)
		(end 91.10853 -164.107876)
		(stroke
			(width 0.2)
			(type default)
		)
		(fill no)
		(layer "In3.Cu")
	)
	(gr_circle
		(center 90.23985 -163.457636)
		(end 91.12885 -163.457636)
		(stroke
			(width 0.2)
			(type default)
		)
		(fill no)
		(layer "In3.Cu")
	)
	(gr_circle
		(center 90.23985 -162.822636)
		(end 91.12885 -162.822636)
		(stroke
			(width 0.2)
			(type default)
		)
		(fill no)
		(layer "In3.Cu")
	)
	(gr_circle
		(center 90.274394 -337.399884)
		(end 91.163394 -337.399884)
		(stroke
			(width 0.2)
			(type default)
		)
		(fill no)
		(layer "In3.Cu")
	)
	(gr_circle
		(center 90.299794 -338.161884)
		(end 91.188794 -338.161884)
		(stroke
			(width 0.2)
			(type default)
		)
		(fill no)
		(layer "In3.Cu")
	)
	(gr_circle
		(center 90.618056 -345.261184)
		(end 91.507056 -345.261184)
		(stroke
			(width 0.2)
			(type default)
		)
		(fill no)
		(layer "In3.Cu")
	)
	(gr_circle
		(center 90.620088 -345.96959)
		(end 91.509088 -345.96959)
		(stroke
			(width 0.2)
			(type default)
		)
		(fill no)
		(layer "In3.Cu")
	)
	(gr_circle
		(center 90.658442 -346.639896)
		(end 91.547442 -346.639896)
		(stroke
			(width 0.2)
			(type default)
		)
		(fill no)
		(layer "In3.Cu")
	)
	(gr_circle
		(center 90.833194 -338.517484)
		(end 91.722194 -338.517484)
		(stroke
			(width 0.2)
			(type default)
		)
		(fill no)
		(layer "In3.Cu")
	)
	(gr_circle
		(center 90.833194 -337.780884)
		(end 91.722194 -337.780884)
		(stroke
			(width 0.2)
			(type default)
		)
		(fill no)
		(layer "In3.Cu")
	)
	(gr_circle
		(center 90.833194 -337.044284)
		(end 91.722194 -337.044284)
		(stroke
			(width 0.2)
			(type default)
		)
		(fill no)
		(layer "In3.Cu")
	)
	(gr_circle
		(center 91.255088 -345.96959)
		(end 92.144088 -345.96959)
		(stroke
			(width 0.2)
			(type default)
		)
		(fill no)
		(layer "In3.Cu")
	)
	(gr_circle
		(center 91.293442 -346.639896)
		(end 92.182442 -346.639896)
		(stroke
			(width 0.2)
			(type default)
		)
		(fill no)
		(layer "In3.Cu")
	)
	(gr_circle
		(center 91.380056 -345.261184)
		(end 92.269056 -345.261184)
		(stroke
			(width 0.2)
			(type default)
		)
		(fill no)
		(layer "In3.Cu")
	)
	(gr_circle
		(center 91.966288 -345.96959)
		(end 92.855288 -345.96959)
		(stroke
			(width 0.2)
			(type default)
		)
		(fill no)
		(layer "In3.Cu")
	)
	(gr_circle
		(center 92.004642 -346.639896)
		(end 92.893642 -346.639896)
		(stroke
			(width 0.2)
			(type default)
		)
		(fill no)
		(layer "In3.Cu")
	)
	(gr_circle
		(center 92.015056 -345.261184)
		(end 92.904056 -345.261184)
		(stroke
			(width 0.2)
			(type default)
		)
		(fill no)
		(layer "In3.Cu")
	)
	(gr_circle
		(center 92.387674 -165.962076)
		(end 93.784674 -165.962076)
		(stroke
			(width 0.2)
			(type default)
		)
		(fill no)
		(layer "In3.Cu")
	)
	(gr_circle
		(center 92.601288 -345.96959)
		(end 93.490288 -345.96959)
		(stroke
			(width 0.2)
			(type default)
		)
		(fill no)
		(layer "In3.Cu")
	)
	(gr_circle
		(center 92.639642 -346.639896)
		(end 93.528642 -346.639896)
		(stroke
			(width 0.2)
			(type default)
		)
		(fill no)
		(layer "In3.Cu")
	)
	(gr_circle
		(center 92.650056 -345.261184)
		(end 93.539056 -345.261184)
		(stroke
			(width 0.2)
			(type default)
		)
		(fill no)
		(layer "In3.Cu")
	)
	(gr_circle
		(center 95.36303 -180.627274)
		(end 96.25203 -180.627274)
		(stroke
			(width 0.2)
			(type default)
		)
		(fill no)
		(layer "In3.Cu")
	)
	(gr_circle
		(center 95.36303 -179.890674)
		(end 96.25203 -179.890674)
		(stroke
			(width 0.2)
			(type default)
		)
		(fill no)
		(layer "In3.Cu")
	)
	(gr_circle
		(center 95.36303 -179.154074)
		(end 96.25203 -179.154074)
		(stroke
			(width 0.2)
			(type default)
		)
		(fill no)
		(layer "In3.Cu")
	)
	(gr_circle
		(center 95.89643 -179.509674)
		(end 96.78543 -179.509674)
		(stroke
			(width 0.2)
			(type default)
		)
		(fill no)
		(layer "In3.Cu")
	)
	(gr_circle
		(center 95.92183 -180.271674)
		(end 96.81083 -180.271674)
		(stroke
			(width 0.2)
			(type default)
		)
		(fill no)
		(layer "In3.Cu")
	)
	(gr_circle
		(center 96.144334 -337.017614)
		(end 97.024444 -337.017614)
		(stroke
			(width 0.2)
			(type default)
		)
		(fill no)
		(layer "In3.Cu")
	)
	(gr_circle
		(center 96.446594 -179.832254)
		(end 97.335594 -179.832254)
		(stroke
			(width 0.2)
			(type default)
		)
		(fill no)
		(layer "In3.Cu")
	)
	(gr_circle
		(center 96.446594 -179.095654)
		(end 97.335594 -179.095654)
		(stroke
			(width 0.2)
			(type default)
		)
		(fill no)
		(layer "In3.Cu")
	)
	(gr_circle
		(center 96.761554 -337.017614)
		(end 97.641664 -337.017614)
		(stroke
			(width 0.2)
			(type default)
		)
		(fill no)
		(layer "In3.Cu")
	)
	(gr_circle
		(center 96.980248 -182.13324)
		(end 97.869248 -182.13324)
		(stroke
			(width 0.2)
			(type default)
		)
		(fill no)
		(layer "In3.Cu")
	)
	(gr_circle
		(center 96.980248 -181.39664)
		(end 97.869248 -181.39664)
		(stroke
			(width 0.2)
			(type default)
		)
		(fill no)
		(layer "In3.Cu")
	)
	(gr_circle
		(center 97.14865 -180.704744)
		(end 98.02876 -180.704744)
		(stroke
			(width 0.2)
			(type default)
		)
		(fill no)
		(layer "In3.Cu")
	)
	(gr_circle
		(center 97.378774 -337.017614)
		(end 98.258884 -337.017614)
		(stroke
			(width 0.2)
			(type default)
		)
		(fill no)
		(layer "In3.Cu")
	)
	(gr_circle
		(center 97.658174 -336.319368)
		(end 98.538284 -336.319368)
		(stroke
			(width 0.2)
			(type default)
		)
		(fill no)
		(layer "In3.Cu")
	)
	(gr_circle
		(center 97.658174 -335.582768)
		(end 98.538284 -335.582768)
		(stroke
			(width 0.2)
			(type default)
		)
		(fill no)
		(layer "In3.Cu")
	)
	(gr_circle
		(center 97.76587 -180.704744)
		(end 98.64598 -180.704744)
		(stroke
			(width 0.2)
			(type default)
		)
		(fill no)
		(layer "In3.Cu")
	)
	(gr_circle
		(center 98.08083 -338.626704)
		(end 98.96983 -338.626704)
		(stroke
			(width 0.2)
			(type default)
		)
		(fill no)
		(layer "In3.Cu")
	)
	(gr_circle
		(center 98.08083 -337.890104)
		(end 98.96983 -337.890104)
		(stroke
			(width 0.2)
			(type default)
		)
		(fill no)
		(layer "In3.Cu")
	)
	(gr_circle
		(center 98.199194 -339.358224)
		(end 99.088194 -339.358224)
		(stroke
			(width 0.2)
			(type default)
		)
		(fill no)
		(layer "In3.Cu")
	)
	(gr_circle
		(center 98.38309 -180.704744)
		(end 99.2632 -180.704744)
		(stroke
			(width 0.2)
			(type default)
		)
		(fill no)
		(layer "In3.Cu")
	)
	(gr_circle
		(center 98.605594 -337.450684)
		(end 99.494594 -337.450684)
		(stroke
			(width 0.2)
			(type default)
		)
		(fill no)
		(layer "In3.Cu")
	)
	(gr_circle
		(center 98.630994 -338.212684)
		(end 99.519994 -338.212684)
		(stroke
			(width 0.2)
			(type default)
		)
		(fill no)
		(layer "In3.Cu")
	)
	(gr_circle
		(center 98.747834 -339.736684)
		(end 99.636834 -339.736684)
		(stroke
			(width 0.2)
			(type default)
		)
		(fill no)
		(layer "In3.Cu")
	)
	(gr_circle
		(center 98.747834 -338.974684)
		(end 99.636834 -338.974684)
		(stroke
			(width 0.2)
			(type default)
		)
		(fill no)
		(layer "In3.Cu")
	)
	(gr_circle
		(center 103.74503 -176.106074)
		(end 104.63403 -176.106074)
		(stroke
			(width 0.2)
			(type default)
		)
		(fill no)
		(layer "In3.Cu")
	)
	(gr_circle
		(center 103.74503 -175.369474)
		(end 104.63403 -175.369474)
		(stroke
			(width 0.2)
			(type default)
		)
		(fill no)
		(layer "In3.Cu")
	)
	(gr_circle
		(center 103.74503 -174.632874)
		(end 104.63403 -174.632874)
		(stroke
			(width 0.2)
			(type default)
		)
		(fill no)
		(layer "In3.Cu")
	)
	(gr_circle
		(center 104.27843 -174.988474)
		(end 105.16743 -174.988474)
		(stroke
			(width 0.2)
			(type default)
		)
		(fill no)
		(layer "In3.Cu")
	)
	(gr_circle
		(center 104.30383 -175.750474)
		(end 105.19283 -175.750474)
		(stroke
			(width 0.2)
			(type default)
		)
		(fill no)
		(layer "In3.Cu")
	)
	(gr_circle
		(center 104.420162 -341.927688)
		(end 105.300272 -341.927688)
		(stroke
			(width 0.2)
			(type default)
		)
		(fill no)
		(layer "In3.Cu")
	)
	(gr_circle
		(center 104.828594 -175.311054)
		(end 105.717594 -175.311054)
		(stroke
			(width 0.2)
			(type default)
		)
		(fill no)
		(layer "In3.Cu")
	)
	(gr_circle
		(center 104.828594 -174.574454)
		(end 105.717594 -174.574454)
		(stroke
			(width 0.2)
			(type default)
		)
		(fill no)
		(layer "In3.Cu")
	)
	(gr_circle
		(center 105.037382 -341.927688)
		(end 105.917492 -341.927688)
		(stroke
			(width 0.2)
			(type default)
		)
		(fill no)
		(layer "In3.Cu")
	)
	(gr_circle
		(center 105.336848 -177.65776)
		(end 106.225848 -177.65776)
		(stroke
			(width 0.2)
			(type default)
		)
		(fill no)
		(layer "In3.Cu")
	)
	(gr_circle
		(center 105.336848 -176.92116)
		(end 106.225848 -176.92116)
		(stroke
			(width 0.2)
			(type default)
		)
		(fill no)
		(layer "In3.Cu")
	)
	(gr_circle
		(center 105.53065 -176.183544)
		(end 106.41076 -176.183544)
		(stroke
			(width 0.2)
			(type default)
		)
		(fill no)
		(layer "In3.Cu")
	)
	(gr_circle
		(center 105.654602 -341.927688)
		(end 106.534712 -341.927688)
		(stroke
			(width 0.2)
			(type default)
		)
		(fill no)
		(layer "In3.Cu")
	)
	(gr_circle
		(center 105.934002 -341.229442)
		(end 106.814112 -341.229442)
		(stroke
			(width 0.2)
			(type default)
		)
		(fill no)
		(layer "In3.Cu")
	)
	(gr_circle
		(center 105.934002 -340.492842)
		(end 106.814112 -340.492842)
		(stroke
			(width 0.2)
			(type default)
		)
		(fill no)
		(layer "In3.Cu")
	)
	(gr_circle
		(center 106.14787 -176.183544)
		(end 107.02798 -176.183544)
		(stroke
			(width 0.2)
			(type default)
		)
		(fill no)
		(layer "In3.Cu")
	)
	(gr_circle
		(center 106.34345 -343.450164)
		(end 107.23245 -343.450164)
		(stroke
			(width 0.2)
			(type default)
		)
		(fill no)
		(layer "In3.Cu")
	)
	(gr_circle
		(center 106.34345 -342.713564)
		(end 107.23245 -342.713564)
		(stroke
			(width 0.2)
			(type default)
		)
		(fill no)
		(layer "In3.Cu")
	)
	(gr_circle
		(center 106.76509 -176.183544)
		(end 107.6452 -176.183544)
		(stroke
			(width 0.2)
			(type default)
		)
		(fill no)
		(layer "In3.Cu")
	)
	(gr_circle
		(center 106.98607 -342.540844)
		(end 107.87507 -342.540844)
		(stroke
			(width 0.2)
			(type default)
		)
		(fill no)
		(layer "In3.Cu")
	)
	(gr_circle
		(center 106.98607 -341.804244)
		(end 107.87507 -341.804244)
		(stroke
			(width 0.2)
			(type default)
		)
		(fill no)
		(layer "In3.Cu")
	)
	(gr_circle
		(center 107.01401 -343.986104)
		(end 107.90301 -343.986104)
		(stroke
			(width 0.2)
			(type default)
		)
		(fill no)
		(layer "In3.Cu")
	)
	(gr_circle
		(center 107.01401 -343.249504)
		(end 107.90301 -343.249504)
		(stroke
			(width 0.2)
			(type default)
		)
		(fill no)
		(layer "In3.Cu")
	)
	(gr_circle
		(center 110.140496 -150.941786)
		(end 111.537496 -150.941786)
		(stroke
			(width 0.2)
			(type default)
		)
		(fill no)
		(layer "In3.Cu")
	)
	(gr_circle
		(center 111.97463 -169.857674)
		(end 112.86363 -169.857674)
		(stroke
			(width 0.2)
			(type default)
		)
		(fill no)
		(layer "In3.Cu")
	)
	(gr_circle
		(center 111.97463 -169.121074)
		(end 112.86363 -169.121074)
		(stroke
			(width 0.2)
			(type default)
		)
		(fill no)
		(layer "In3.Cu")
	)
	(gr_circle
		(center 111.97463 -168.384474)
		(end 112.86363 -168.384474)
		(stroke
			(width 0.2)
			(type default)
		)
		(fill no)
		(layer "In3.Cu")
	)
	(gr_circle
		(center 112.50803 -168.740074)
		(end 113.39703 -168.740074)
		(stroke
			(width 0.2)
			(type default)
		)
		(fill no)
		(layer "In3.Cu")
	)
	(gr_circle
		(center 112.53343 -169.502074)
		(end 113.42243 -169.502074)
		(stroke
			(width 0.2)
			(type default)
		)
		(fill no)
		(layer "In3.Cu")
	)
	(gr_circle
		(center 113.058194 -169.062654)
		(end 113.947194 -169.062654)
		(stroke
			(width 0.2)
			(type default)
		)
		(fill no)
		(layer "In3.Cu")
	)
	(gr_circle
		(center 113.058194 -168.326054)
		(end 113.947194 -168.326054)
		(stroke
			(width 0.2)
			(type default)
		)
		(fill no)
		(layer "In3.Cu")
	)
	(gr_circle
		(center 113.591848 -171.33316)
		(end 114.480848 -171.33316)
		(stroke
			(width 0.2)
			(type default)
		)
		(fill no)
		(layer "In3.Cu")
	)
	(gr_circle
		(center 113.591848 -170.59656)
		(end 114.480848 -170.59656)
		(stroke
			(width 0.2)
			(type default)
		)
		(fill no)
		(layer "In3.Cu")
	)
	(gr_circle
		(center 113.76025 -169.935144)
		(end 114.64036 -169.935144)
		(stroke
			(width 0.2)
			(type default)
		)
		(fill no)
		(layer "In3.Cu")
	)
	(gr_circle
		(center 114.37747 -169.935144)
		(end 115.25758 -169.935144)
		(stroke
			(width 0.2)
			(type default)
		)
		(fill no)
		(layer "In3.Cu")
	)
	(gr_circle
		(center 114.99469 -169.935144)
		(end 115.8748 -169.935144)
		(stroke
			(width 0.2)
			(type default)
		)
		(fill no)
		(layer "In3.Cu")
	)
	(gr_circle
		(center 116.258594 -152.657556)
		(end 117.147594 -152.657556)
		(stroke
			(width 0.2)
			(type default)
		)
		(fill no)
		(layer "In3.Cu")
	)
	(gr_circle
		(center 116.258594 -152.022556)
		(end 117.147594 -152.022556)
		(stroke
			(width 0.2)
			(type default)
		)
		(fill no)
		(layer "In3.Cu")
	)
	(gr_circle
		(center 116.893594 -152.657556)
		(end 117.782594 -152.657556)
		(stroke
			(width 0.2)
			(type default)
		)
		(fill no)
		(layer "In3.Cu")
	)
	(gr_circle
		(center 116.893594 -152.022556)
		(end 117.782594 -152.022556)
		(stroke
			(width 0.2)
			(type default)
		)
		(fill no)
		(layer "In3.Cu")
	)
	(gr_circle
		(center 117.559074 -152.657556)
		(end 118.448074 -152.657556)
		(stroke
			(width 0.2)
			(type default)
		)
		(fill no)
		(layer "In3.Cu")
	)
	(gr_circle
		(center 117.559074 -152.022556)
		(end 118.448074 -152.022556)
		(stroke
			(width 0.2)
			(type default)
		)
		(fill no)
		(layer "In3.Cu")
	)
	(gr_circle
		(center 118.194074 -152.657556)
		(end 119.083074 -152.657556)
		(stroke
			(width 0.2)
			(type default)
		)
		(fill no)
		(layer "In3.Cu")
	)
	(gr_circle
		(center 118.194074 -152.022556)
		(end 119.083074 -152.022556)
		(stroke
			(width 0.2)
			(type default)
		)
		(fill no)
		(layer "In3.Cu")
	)
	(gr_circle
		(center 118.829074 -152.657556)
		(end 119.718074 -152.657556)
		(stroke
			(width 0.2)
			(type default)
		)
		(fill no)
		(layer "In3.Cu")
	)
	(gr_circle
		(center 118.829074 -152.022556)
		(end 119.718074 -152.022556)
		(stroke
			(width 0.2)
			(type default)
		)
		(fill no)
		(layer "In3.Cu")
	)
	(gr_circle
		(center 119.464074 -152.657556)
		(end 120.353074 -152.657556)
		(stroke
			(width 0.2)
			(type default)
		)
		(fill no)
		(layer "In3.Cu")
	)
	(gr_circle
		(center 119.464074 -152.022556)
		(end 120.353074 -152.022556)
		(stroke
			(width 0.2)
			(type default)
		)
		(fill no)
		(layer "In3.Cu")
	)
	(gr_circle
		(center 120.25503 -163.126674)
		(end 121.14403 -163.126674)
		(stroke
			(width 0.2)
			(type default)
		)
		(fill no)
		(layer "In3.Cu")
	)
	(gr_circle
		(center 120.25503 -162.390074)
		(end 121.14403 -162.390074)
		(stroke
			(width 0.2)
			(type default)
		)
		(fill no)
		(layer "In3.Cu")
	)
	(gr_circle
		(center 120.25503 -161.653474)
		(end 121.14403 -161.653474)
		(stroke
			(width 0.2)
			(type default)
		)
		(fill no)
		(layer "In3.Cu")
	)
	(gr_circle
		(center 120.78843 -162.009074)
		(end 121.67743 -162.009074)
		(stroke
			(width 0.2)
			(type default)
		)
		(fill no)
		(layer "In3.Cu")
	)
	(gr_circle
		(center 120.81383 -162.771074)
		(end 121.70283 -162.771074)
		(stroke
			(width 0.2)
			(type default)
		)
		(fill no)
		(layer "In3.Cu")
	)
	(gr_circle
		(center 121.338594 -162.331654)
		(end 122.227594 -162.331654)
		(stroke
			(width 0.2)
			(type default)
		)
		(fill no)
		(layer "In3.Cu")
	)
	(gr_circle
		(center 121.338594 -161.595054)
		(end 122.227594 -161.595054)
		(stroke
			(width 0.2)
			(type default)
		)
		(fill no)
		(layer "In3.Cu")
	)
	(gr_circle
		(center 121.872248 -164.62756)
		(end 122.761248 -164.62756)
		(stroke
			(width 0.2)
			(type default)
		)
		(fill no)
		(layer "In3.Cu")
	)
	(gr_circle
		(center 121.872248 -163.89096)
		(end 122.761248 -163.89096)
		(stroke
			(width 0.2)
			(type default)
		)
		(fill no)
		(layer "In3.Cu")
	)
	(gr_circle
		(center 122.04065 -163.204144)
		(end 122.92076 -163.204144)
		(stroke
			(width 0.2)
			(type default)
		)
		(fill no)
		(layer "In3.Cu")
	)
	(gr_circle
		(center 122.65787 -163.204144)
		(end 123.53798 -163.204144)
		(stroke
			(width 0.2)
			(type default)
		)
		(fill no)
		(layer "In3.Cu")
	)
	(gr_circle
		(center 123.27509 -163.204144)
		(end 124.1552 -163.204144)
		(stroke
			(width 0.2)
			(type default)
		)
		(fill no)
		(layer "In3.Cu")
	)
	(gr_arc
		(start 124.102114 -11.780012)
		(mid 125.516325 -11.194227)
		(end 126.10211 -9.780016)
		(stroke
			(width 1.016)
			(type default)
		)
		(layer "In3.Cu")
	)
	(gr_line
		(start 126.10211 -9.780016)
		(end 126.10211 -5.780024)
		(stroke
			(width 1.016)
			(type default)
		)
		(layer "In3.Cu")
	)
	(gr_arc
		(start 126.601982 -5.279898)
		(mid 126.248489 -5.42646)
		(end 126.10211 -5.780024)
		(stroke
			(width 1.016)
			(type default)
		)
		(layer "In3.Cu")
	)
	(gr_line
		(start 126.601982 -5.279898)
		(end 194.20205 -5.279898)
		(stroke
			(width 1.016)
			(type default)
		)
		(layer "In3.Cu")
	)
	(gr_circle
		(center 128.71323 -154.465274)
		(end 129.60223 -154.465274)
		(stroke
			(width 0.2)
			(type default)
		)
		(fill no)
		(layer "In3.Cu")
	)
	(gr_circle
		(center 128.71323 -153.728674)
		(end 129.60223 -153.728674)
		(stroke
			(width 0.2)
			(type default)
		)
		(fill no)
		(layer "In3.Cu")
	)
	(gr_circle
		(center 128.71323 -152.992074)
		(end 129.60223 -152.992074)
		(stroke
			(width 0.2)
			(type default)
		)
		(fill no)
		(layer "In3.Cu")
	)
	(gr_circle
		(center 129.24663 -153.347674)
		(end 130.13563 -153.347674)
		(stroke
			(width 0.2)
			(type default)
		)
		(fill no)
		(layer "In3.Cu")
	)
	(gr_circle
		(center 129.27203 -154.109674)
		(end 130.16103 -154.109674)
		(stroke
			(width 0.2)
			(type default)
		)
		(fill no)
		(layer "In3.Cu")
	)
	(gr_circle
		(center 129.796794 -153.670254)
		(end 130.685794 -153.670254)
		(stroke
			(width 0.2)
			(type default)
		)
		(fill no)
		(layer "In3.Cu")
	)
	(gr_circle
		(center 129.796794 -152.933654)
		(end 130.685794 -152.933654)
		(stroke
			(width 0.2)
			(type default)
		)
		(fill no)
		(layer "In3.Cu")
	)
	(gr_circle
		(center 130.305048 -155.94076)
		(end 131.194048 -155.94076)
		(stroke
			(width 0.2)
			(type default)
		)
		(fill no)
		(layer "In3.Cu")
	)
	(gr_circle
		(center 130.305048 -155.20416)
		(end 131.194048 -155.20416)
		(stroke
			(width 0.2)
			(type default)
		)
		(fill no)
		(layer "In3.Cu")
	)
	(gr_circle
		(center 130.49885 -154.542744)
		(end 131.37896 -154.542744)
		(stroke
			(width 0.2)
			(type default)
		)
		(fill no)
		(layer "In3.Cu")
	)
	(gr_circle
		(center 131.11607 -154.542744)
		(end 131.99618 -154.542744)
		(stroke
			(width 0.2)
			(type default)
		)
		(fill no)
		(layer "In3.Cu")
	)
	(gr_circle
		(center 131.73329 -154.542744)
		(end 132.6134 -154.542744)
		(stroke
			(width 0.2)
			(type default)
		)
		(fill no)
		(layer "In3.Cu")
	)
	(gr_circle
		(center 176.332134 -26.634948)
		(end 177.221134 -26.634948)
		(stroke
			(width 0.2)
			(type default)
		)
		(fill no)
		(layer "In3.Cu")
	)
	(gr_circle
		(center 176.713134 -25.949148)
		(end 177.602134 -25.949148)
		(stroke
			(width 0.2)
			(type default)
		)
		(fill no)
		(layer "In3.Cu")
	)
	(gr_circle
		(center 176.878234 -19.942048)
		(end 177.767234 -19.942048)
		(stroke
			(width 0.2)
			(type default)
		)
		(fill no)
		(layer "In3.Cu")
	)
	(gr_circle
		(center 176.968912 -21.349208)
		(end 177.857912 -21.349208)
		(stroke
			(width 0.2)
			(type default)
		)
		(fill no)
		(layer "In3.Cu")
	)
	(gr_circle
		(center 176.968912 -20.714208)
		(end 177.857912 -20.714208)
		(stroke
			(width 0.2)
			(type default)
		)
		(fill no)
		(layer "In3.Cu")
	)
	(gr_circle
		(center 177.221134 -26.634948)
		(end 178.110134 -26.634948)
		(stroke
			(width 0.2)
			(type default)
		)
		(fill no)
		(layer "In3.Cu")
	)
	(gr_circle
		(center 177.472594 -21.85289)
		(end 178.361594 -21.85289)
		(stroke
			(width 0.2)
			(type default)
		)
		(fill no)
		(layer "In3.Cu")
	)
	(gr_circle
		(center 177.602134 -25.949148)
		(end 178.491134 -25.949148)
		(stroke
			(width 0.2)
			(type default)
		)
		(fill no)
		(layer "In3.Cu")
	)
	(gr_circle
		(center 178.110134 -26.634948)
		(end 178.999134 -26.634948)
		(stroke
			(width 0.2)
			(type default)
		)
		(fill no)
		(layer "In3.Cu")
	)
	(gr_circle
		(center 178.491134 -25.949148)
		(end 179.380134 -25.949148)
		(stroke
			(width 0.2)
			(type default)
		)
		(fill no)
		(layer "In3.Cu")
	)
	(gr_circle
		(center 179.507134 -25.517348)
		(end 180.396134 -25.517348)
		(stroke
			(width 0.2)
			(type default)
		)
		(fill no)
		(layer "In3.Cu")
	)
	(gr_circle
		(center 180.921914 -27.107388)
		(end 181.810914 -27.107388)
		(stroke
			(width 0.2)
			(type default)
		)
		(fill no)
		(layer "In3.Cu")
	)
	(gr_circle
		(center 183.610758 -353.283774)
		(end 184.490868 -353.283774)
		(stroke
			(width 0.2)
			(type default)
		)
		(fill no)
		(layer "In3.Cu")
	)
	(gr_circle
		(center 184.227978 -353.283774)
		(end 185.108088 -353.283774)
		(stroke
			(width 0.2)
			(type default)
		)
		(fill no)
		(layer "In3.Cu")
	)
	(gr_circle
		(center 184.845198 -353.283774)
		(end 185.725308 -353.283774)
		(stroke
			(width 0.2)
			(type default)
		)
		(fill no)
		(layer "In3.Cu")
	)
	(gr_circle
		(center 184.85612 -403.222714)
		(end 185.74512 -403.222714)
		(stroke
			(width 0.2)
			(type default)
		)
		(fill no)
		(layer "In3.Cu")
	)
	(gr_circle
		(center 184.85612 -401.919694)
		(end 185.74512 -401.919694)
		(stroke
			(width 0.2)
			(type default)
		)
		(fill no)
		(layer "In3.Cu")
	)
	(gr_circle
		(center 184.85612 -400.616674)
		(end 185.74512 -400.616674)
		(stroke
			(width 0.2)
			(type default)
		)
		(fill no)
		(layer "In3.Cu")
	)
	(gr_circle
		(center 184.962292 -352.558604)
		(end 185.851292 -352.558604)
		(stroke
			(width 0.2)
			(type default)
		)
		(fill no)
		(layer "In3.Cu")
	)
	(gr_circle
		(center 184.962292 -351.822004)
		(end 185.851292 -351.822004)
		(stroke
			(width 0.2)
			(type default)
		)
		(fill no)
		(layer "In3.Cu")
	)
	(gr_circle
		(center 185.547254 -354.892864)
		(end 186.436254 -354.892864)
		(stroke
			(width 0.2)
			(type default)
		)
		(fill no)
		(layer "In3.Cu")
	)
	(gr_circle
		(center 185.547254 -354.156264)
		(end 186.436254 -354.156264)
		(stroke
			(width 0.2)
			(type default)
		)
		(fill no)
		(layer "In3.Cu")
	)
	(gr_circle
		(center 185.673492 -408.092402)
		(end 186.562492 -408.092402)
		(stroke
			(width 0.2)
			(type default)
		)
		(fill no)
		(layer "In3.Cu")
	)
	(gr_circle
		(center 185.673492 -407.330402)
		(end 186.562492 -407.330402)
		(stroke
			(width 0.2)
			(type default)
		)
		(fill no)
		(layer "In3.Cu")
	)
	(gr_circle
		(center 185.673492 -406.517602)
		(end 186.562492 -406.517602)
		(stroke
			(width 0.2)
			(type default)
		)
		(fill no)
		(layer "In3.Cu")
	)
	(gr_circle
		(center 185.673492 -405.755602)
		(end 186.562492 -405.755602)
		(stroke
			(width 0.2)
			(type default)
		)
		(fill no)
		(layer "In3.Cu")
	)
	(gr_circle
		(center 185.673492 -404.993602)
		(end 186.562492 -404.993602)
		(stroke
			(width 0.2)
			(type default)
		)
		(fill no)
		(layer "In3.Cu")
	)
	(gr_circle
		(center 186.034172 -362.234988)
		(end 186.923172 -362.234988)
		(stroke
			(width 0.2)
			(type default)
		)
		(fill no)
		(layer "In3.Cu")
	)
	(gr_circle
		(center 186.034172 -361.472988)
		(end 186.923172 -361.472988)
		(stroke
			(width 0.2)
			(type default)
		)
		(fill no)
		(layer "In3.Cu")
	)
	(gr_circle
		(center 186.034172 -360.710988)
		(end 186.923172 -360.710988)
		(stroke
			(width 0.2)
			(type default)
		)
		(fill no)
		(layer "In3.Cu")
	)
	(gr_circle
		(center 186.072018 -353.716844)
		(end 186.961018 -353.716844)
		(stroke
			(width 0.2)
			(type default)
		)
		(fill no)
		(layer "In3.Cu")
	)
	(gr_circle
		(center 186.097418 -354.478844)
		(end 186.986418 -354.478844)
		(stroke
			(width 0.2)
			(type default)
		)
		(fill no)
		(layer "In3.Cu")
	)
	(gr_circle
		(center 186.27852 -403.222714)
		(end 187.16752 -403.222714)
		(stroke
			(width 0.2)
			(type default)
		)
		(fill no)
		(layer "In3.Cu")
	)
	(gr_circle
		(center 186.27852 -400.616674)
		(end 187.16752 -400.616674)
		(stroke
			(width 0.2)
			(type default)
		)
		(fill no)
		(layer "In3.Cu")
	)
	(gr_circle
		(center 186.435492 -408.092402)
		(end 187.324492 -408.092402)
		(stroke
			(width 0.2)
			(type default)
		)
		(fill no)
		(layer "In3.Cu")
	)
	(gr_circle
		(center 186.435492 -407.330402)
		(end 187.324492 -407.330402)
		(stroke
			(width 0.2)
			(type default)
		)
		(fill no)
		(layer "In3.Cu")
	)
	(gr_circle
		(center 186.435492 -406.517602)
		(end 187.324492 -406.517602)
		(stroke
			(width 0.2)
			(type default)
		)
		(fill no)
		(layer "In3.Cu")
	)
	(gr_circle
		(center 186.435492 -405.755602)
		(end 187.324492 -405.755602)
		(stroke
			(width 0.2)
			(type default)
		)
		(fill no)
		(layer "In3.Cu")
	)
	(gr_circle
		(center 186.435492 -404.993602)
		(end 187.324492 -404.993602)
		(stroke
			(width 0.2)
			(type default)
		)
		(fill no)
		(layer "In3.Cu")
	)
	(gr_circle
		(center 186.630818 -354.834444)
		(end 187.519818 -354.834444)
		(stroke
			(width 0.2)
			(type default)
		)
		(fill no)
		(layer "In3.Cu")
	)
	(gr_circle
		(center 186.630818 -354.097844)
		(end 187.519818 -354.097844)
		(stroke
			(width 0.2)
			(type default)
		)
		(fill no)
		(layer "In3.Cu")
	)
	(gr_circle
		(center 186.630818 -353.361244)
		(end 187.519818 -353.361244)
		(stroke
			(width 0.2)
			(type default)
		)
		(fill no)
		(layer "In3.Cu")
	)
	(gr_circle
		(center 186.796172 -362.234988)
		(end 187.685172 -362.234988)
		(stroke
			(width 0.2)
			(type default)
		)
		(fill no)
		(layer "In3.Cu")
	)
	(gr_circle
		(center 186.796172 -361.472988)
		(end 187.685172 -361.472988)
		(stroke
			(width 0.2)
			(type default)
		)
		(fill no)
		(layer "In3.Cu")
	)
	(gr_circle
		(center 186.796172 -360.710988)
		(end 187.685172 -360.710988)
		(stroke
			(width 0.2)
			(type default)
		)
		(fill no)
		(layer "In3.Cu")
	)
	(gr_circle
		(center 187.197492 -408.092402)
		(end 188.086492 -408.092402)
		(stroke
			(width 0.2)
			(type default)
		)
		(fill no)
		(layer "In3.Cu")
	)
	(gr_circle
		(center 187.197492 -407.330402)
		(end 188.086492 -407.330402)
		(stroke
			(width 0.2)
			(type default)
		)
		(fill no)
		(layer "In3.Cu")
	)
	(gr_circle
		(center 187.197492 -406.517602)
		(end 188.086492 -406.517602)
		(stroke
			(width 0.2)
			(type default)
		)
		(fill no)
		(layer "In3.Cu")
	)
	(gr_circle
		(center 187.197492 -405.755602)
		(end 188.086492 -405.755602)
		(stroke
			(width 0.2)
			(type default)
		)
		(fill no)
		(layer "In3.Cu")
	)
	(gr_circle
		(center 187.197492 -404.993602)
		(end 188.086492 -404.993602)
		(stroke
			(width 0.2)
			(type default)
		)
		(fill no)
		(layer "In3.Cu")
	)
	(gr_circle
		(center 187.67552 -403.222714)
		(end 188.56452 -403.222714)
		(stroke
			(width 0.2)
			(type default)
		)
		(fill no)
		(layer "In3.Cu")
	)
	(gr_circle
		(center 187.67552 -401.919694)
		(end 188.56452 -401.919694)
		(stroke
			(width 0.2)
			(type default)
		)
		(fill no)
		(layer "In3.Cu")
	)
	(gr_circle
		(center 187.67552 -400.616674)
		(end 188.56452 -400.616674)
		(stroke
			(width 0.2)
			(type default)
		)
		(fill no)
		(layer "In3.Cu")
	)
	(gr_circle
		(center 187.959492 -408.092402)
		(end 188.848492 -408.092402)
		(stroke
			(width 0.2)
			(type default)
		)
		(fill no)
		(layer "In3.Cu")
	)
	(gr_circle
		(center 187.959492 -407.330402)
		(end 188.848492 -407.330402)
		(stroke
			(width 0.2)
			(type default)
		)
		(fill no)
		(layer "In3.Cu")
	)
	(gr_circle
		(center 187.959492 -406.517602)
		(end 188.848492 -406.517602)
		(stroke
			(width 0.2)
			(type default)
		)
		(fill no)
		(layer "In3.Cu")
	)
	(gr_circle
		(center 187.959492 -405.755602)
		(end 188.848492 -405.755602)
		(stroke
			(width 0.2)
			(type default)
		)
		(fill no)
		(layer "In3.Cu")
	)
	(gr_circle
		(center 187.959492 -404.993602)
		(end 188.848492 -404.993602)
		(stroke
			(width 0.2)
			(type default)
		)
		(fill no)
		(layer "In3.Cu")
	)
	(gr_circle
		(center 188.721492 -408.092402)
		(end 189.610492 -408.092402)
		(stroke
			(width 0.2)
			(type default)
		)
		(fill no)
		(layer "In3.Cu")
	)
	(gr_circle
		(center 188.721492 -407.330402)
		(end 189.610492 -407.330402)
		(stroke
			(width 0.2)
			(type default)
		)
		(fill no)
		(layer "In3.Cu")
	)
	(gr_circle
		(center 188.721492 -406.517602)
		(end 189.610492 -406.517602)
		(stroke
			(width 0.2)
			(type default)
		)
		(fill no)
		(layer "In3.Cu")
	)
	(gr_circle
		(center 188.721492 -405.755602)
		(end 189.610492 -405.755602)
		(stroke
			(width 0.2)
			(type default)
		)
		(fill no)
		(layer "In3.Cu")
	)
	(gr_circle
		(center 188.721492 -404.993602)
		(end 189.610492 -404.993602)
		(stroke
			(width 0.2)
			(type default)
		)
		(fill no)
		(layer "In3.Cu")
	)
	(gr_circle
		(center 189.483492 -408.092402)
		(end 190.372492 -408.092402)
		(stroke
			(width 0.2)
			(type default)
		)
		(fill no)
		(layer "In3.Cu")
	)
	(gr_circle
		(center 189.483492 -407.330402)
		(end 190.372492 -407.330402)
		(stroke
			(width 0.2)
			(type default)
		)
		(fill no)
		(layer "In3.Cu")
	)
	(gr_circle
		(center 189.483492 -406.517602)
		(end 190.372492 -406.517602)
		(stroke
			(width 0.2)
			(type default)
		)
		(fill no)
		(layer "In3.Cu")
	)
	(gr_circle
		(center 189.483492 -405.755602)
		(end 190.372492 -405.755602)
		(stroke
			(width 0.2)
			(type default)
		)
		(fill no)
		(layer "In3.Cu")
	)
	(gr_circle
		(center 189.483492 -404.993602)
		(end 190.372492 -404.993602)
		(stroke
			(width 0.2)
			(type default)
		)
		(fill no)
		(layer "In3.Cu")
	)
	(gr_circle
		(center 190.508636 -23.593552)
		(end 191.397636 -23.593552)
		(stroke
			(width 0.2)
			(type default)
		)
		(fill no)
		(layer "In3.Cu")
	)
	(gr_circle
		(center 190.508636 -22.856952)
		(end 191.397636 -22.856952)
		(stroke
			(width 0.2)
			(type default)
		)
		(fill no)
		(layer "In3.Cu")
	)
	(gr_circle
		(center 191.67983 -362.430568)
		(end 193.07683 -362.430568)
		(stroke
			(width 0.2)
			(type default)
		)
		(fill no)
		(layer "In3.Cu")
	)
	(gr_circle
		(center 191.927734 -13.106908)
		(end 192.816734 -13.106908)
		(stroke
			(width 0.2)
			(type default)
		)
		(fill no)
		(layer "In3.Cu")
	)
	(gr_circle
		(center 191.937386 -353.309174)
		(end 192.817496 -353.309174)
		(stroke
			(width 0.2)
			(type default)
		)
		(fill no)
		(layer "In3.Cu")
	)
	(gr_circle
		(center 192.461134 -16.416528)
		(end 193.350134 -16.416528)
		(stroke
			(width 0.2)
			(type default)
		)
		(fill no)
		(layer "In3.Cu")
	)
	(gr_circle
		(center 192.461134 -15.781528)
		(end 193.350134 -15.781528)
		(stroke
			(width 0.2)
			(type default)
		)
		(fill no)
		(layer "In3.Cu")
	)
	(gr_circle
		(center 192.554606 -353.309174)
		(end 193.434716 -353.309174)
		(stroke
			(width 0.2)
			(type default)
		)
		(fill no)
		(layer "In3.Cu")
	)
	(gr_circle
		(center 192.689734 -13.106908)
		(end 193.578734 -13.106908)
		(stroke
			(width 0.2)
			(type default)
		)
		(fill no)
		(layer "In3.Cu")
	)
	(gr_circle
		(center 193.096134 -16.416528)
		(end 193.985134 -16.416528)
		(stroke
			(width 0.2)
			(type default)
		)
		(fill no)
		(layer "In3.Cu")
	)
	(gr_circle
		(center 193.096134 -15.781528)
		(end 193.985134 -15.781528)
		(stroke
			(width 0.2)
			(type default)
		)
		(fill no)
		(layer "In3.Cu")
	)
	(gr_circle
		(center 193.171826 -353.309174)
		(end 194.051936 -353.309174)
		(stroke
			(width 0.2)
			(type default)
		)
		(fill no)
		(layer "In3.Cu")
	)
	(gr_circle
		(center 193.28892 -352.563684)
		(end 194.17792 -352.563684)
		(stroke
			(width 0.2)
			(type default)
		)
		(fill no)
		(layer "In3.Cu")
	)
	(gr_circle
		(center 193.28892 -351.827084)
		(end 194.17792 -351.827084)
		(stroke
			(width 0.2)
			(type default)
		)
		(fill no)
		(layer "In3.Cu")
	)
	(gr_circle
		(center 193.731134 -15.781528)
		(end 194.620134 -15.781528)
		(stroke
			(width 0.2)
			(type default)
		)
		(fill no)
		(layer "In3.Cu")
	)
	(gr_circle
		(center 193.858134 -16.543528)
		(end 194.747134 -16.543528)
		(stroke
			(width 0.2)
			(type default)
		)
		(fill no)
		(layer "In3.Cu")
	)
	(gr_circle
		(center 193.873882 -354.918264)
		(end 194.762882 -354.918264)
		(stroke
			(width 0.2)
			(type default)
		)
		(fill no)
		(layer "In3.Cu")
	)
	(gr_circle
		(center 193.873882 -354.181664)
		(end 194.762882 -354.181664)
		(stroke
			(width 0.2)
			(type default)
		)
		(fill no)
		(layer "In3.Cu")
	)
	(gr_circle
		(center 194.398646 -353.742244)
		(end 195.287646 -353.742244)
		(stroke
			(width 0.2)
			(type default)
		)
		(fill no)
		(layer "In3.Cu")
	)
	(gr_circle
		(center 194.424046 -354.504244)
		(end 195.313046 -354.504244)
		(stroke
			(width 0.2)
			(type default)
		)
		(fill no)
		(layer "In3.Cu")
	)
	(gr_line
		(start 194.505072 -441.989972)
		(end 8.50011 -441.989972)
		(stroke
			(width 1.016)
			(type default)
		)
		(layer "In3.Cu")
	)
	(gr_arc
		(start 194.505072 -441.989972)
		(mid 194.858553 -441.843573)
		(end 195.004944 -441.4901)
		(stroke
			(width 1.016)
			(type default)
		)
		(layer "In3.Cu")
	)
	(gr_arc
		(start 194.701922 -9.780016)
		(mid 195.287707 -11.194227)
		(end 196.701918 -11.780012)
		(stroke
			(width 1.016)
			(type default)
		)
		(layer "In3.Cu")
	)
	(gr_arc
		(start 194.701922 -5.780024)
		(mid 194.555654 -5.42634)
		(end 194.20205 -5.279898)
		(stroke
			(width 1.016)
			(type default)
		)
		(layer "In3.Cu")
	)
	(gr_line
		(start 194.701922 -5.780024)
		(end 194.701922 -9.780016)
		(stroke
			(width 1.016)
			(type default)
		)
		(layer "In3.Cu")
	)
	(gr_line
		(start 194.9069 -420.700454)
		(end 194.9069 -413.816038)
		(stroke
			(width 0.635)
			(type default)
		)
		(layer "In3.Cu")
	)
	(gr_arc
		(start 194.9069 -420.700454)
		(mid 194.935087 -420.841508)
		(end 195.015104 -420.961058)
		(stroke
			(width 0.635)
			(type default)
		)
		(layer "In3.Cu")
	)
	(gr_line
		(start 194.9069 -413.816038)
		(end 195.796408 -412.92653)
		(stroke
			(width 0.635)
			(type default)
		)
		(layer "In3.Cu")
	)
	(gr_circle
		(center 194.957446 -354.859844)
		(end 195.846446 -354.859844)
		(stroke
			(width 0.2)
			(type default)
		)
		(fill no)
		(layer "In3.Cu")
	)
	(gr_circle
		(center 194.957446 -354.123244)
		(end 195.846446 -354.123244)
		(stroke
			(width 0.2)
			(type default)
		)
		(fill no)
		(layer "In3.Cu")
	)
	(gr_circle
		(center 194.957446 -353.386644)
		(end 195.846446 -353.386644)
		(stroke
			(width 0.2)
			(type default)
		)
		(fill no)
		(layer "In3.Cu")
	)
	(gr_line
		(start 195.004944 -441.17006)
		(end 195.004944 -441.4901)
		(stroke
			(width 1.016)
			(type default)
		)
		(layer "In3.Cu")
	)
	(gr_line
		(start 195.015104 -420.961058)
		(end 205.73746 -431.683414)
		(stroke
			(width 0.635)
			(type default)
		)
		(layer "In3.Cu")
	)
	(gr_arc
		(start 195.50507 -440.669934)
		(mid 195.151428 -440.816418)
		(end 195.004944 -441.17006)
		(stroke
			(width 1.016)
			(type default)
		)
		(layer "In3.Cu")
	)
	(gr_line
		(start 195.796408 -412.92653)
		(end 226.931728 -412.92653)
		(stroke
			(width 0.635)
			(type default)
		)
		(layer "In3.Cu")
	)
	(gr_line
		(start 196.701918 -11.780012)
		(end 221.30004 -11.780012)
		(stroke
			(width 1.016)
			(type default)
		)
		(layer "In3.Cu")
	)
	(gr_circle
		(center 197.2437 -408.059382)
		(end 198.1327 -408.059382)
		(stroke
			(width 0.2)
			(type default)
		)
		(fill no)
		(layer "In3.Cu")
	)
	(gr_circle
		(center 197.2437 -407.297382)
		(end 198.1327 -407.297382)
		(stroke
			(width 0.2)
			(type default)
		)
		(fill no)
		(layer "In3.Cu")
	)
	(gr_circle
		(center 197.2437 -406.535382)
		(end 198.1327 -406.535382)
		(stroke
			(width 0.2)
			(type default)
		)
		(fill no)
		(layer "In3.Cu")
	)
	(gr_circle
		(center 197.2437 -405.773382)
		(end 198.1327 -405.773382)
		(stroke
			(width 0.2)
			(type default)
		)
		(fill no)
		(layer "In3.Cu")
	)
	(gr_circle
		(center 197.2437 -405.011382)
		(end 198.1327 -405.011382)
		(stroke
			(width 0.2)
			(type default)
		)
		(fill no)
		(layer "In3.Cu")
	)
	(gr_circle
		(center 198.0057 -408.059382)
		(end 198.8947 -408.059382)
		(stroke
			(width 0.2)
			(type default)
		)
		(fill no)
		(layer "In3.Cu")
	)
	(gr_circle
		(center 198.0057 -407.297382)
		(end 198.8947 -407.297382)
		(stroke
			(width 0.2)
			(type default)
		)
		(fill no)
		(layer "In3.Cu")
	)
	(gr_circle
		(center 198.0057 -406.535382)
		(end 198.8947 -406.535382)
		(stroke
			(width 0.2)
			(type default)
		)
		(fill no)
		(layer "In3.Cu")
	)
	(gr_circle
		(center 198.0057 -405.773382)
		(end 198.8947 -405.773382)
		(stroke
			(width 0.2)
			(type default)
		)
		(fill no)
		(layer "In3.Cu")
	)
	(gr_circle
		(center 198.0057 -405.011382)
		(end 198.8947 -405.011382)
		(stroke
			(width 0.2)
			(type default)
		)
		(fill no)
		(layer "In3.Cu")
	)
	(gr_circle
		(center 198.114158 -403.223222)
		(end 199.003158 -403.223222)
		(stroke
			(width 0.2)
			(type default)
		)
		(fill no)
		(layer "In3.Cu")
	)
	(gr_circle
		(center 198.114158 -401.920202)
		(end 199.003158 -401.920202)
		(stroke
			(width 0.2)
			(type default)
		)
		(fill no)
		(layer "In3.Cu")
	)
	(gr_circle
		(center 198.114158 -400.617182)
		(end 199.003158 -400.617182)
		(stroke
			(width 0.2)
			(type default)
		)
		(fill no)
		(layer "In3.Cu")
	)
	(gr_circle
		(center 198.160386 -37.328094)
		(end 199.049386 -37.328094)
		(stroke
			(width 0.2)
			(type default)
		)
		(fill no)
		(layer "In3.Cu")
	)
	(gr_circle
		(center 198.486014 -30.133798)
		(end 199.375014 -30.133798)
		(stroke
			(width 0.2)
			(type default)
		)
		(fill no)
		(layer "In3.Cu")
	)
	(gr_circle
		(center 198.7677 -408.059382)
		(end 199.6567 -408.059382)
		(stroke
			(width 0.2)
			(type default)
		)
		(fill no)
		(layer "In3.Cu")
	)
	(gr_circle
		(center 198.7677 -407.297382)
		(end 199.6567 -407.297382)
		(stroke
			(width 0.2)
			(type default)
		)
		(fill no)
		(layer "In3.Cu")
	)
	(gr_circle
		(center 198.7677 -406.535382)
		(end 199.6567 -406.535382)
		(stroke
			(width 0.2)
			(type default)
		)
		(fill no)
		(layer "In3.Cu")
	)
	(gr_circle
		(center 198.7677 -405.773382)
		(end 199.6567 -405.773382)
		(stroke
			(width 0.2)
			(type default)
		)
		(fill no)
		(layer "In3.Cu")
	)
	(gr_circle
		(center 198.7677 -405.011382)
		(end 199.6567 -405.011382)
		(stroke
			(width 0.2)
			(type default)
		)
		(fill no)
		(layer "In3.Cu")
	)
	(gr_circle
		(center 198.836026 -37.965634)
		(end 199.725026 -37.965634)
		(stroke
			(width 0.2)
			(type default)
		)
		(fill no)
		(layer "In3.Cu")
	)
	(gr_circle
		(center 199.121014 -30.133798)
		(end 200.010014 -30.133798)
		(stroke
			(width 0.2)
			(type default)
		)
		(fill no)
		(layer "In3.Cu")
	)
	(gr_circle
		(center 199.435974 -30.720538)
		(end 200.324974 -30.720538)
		(stroke
			(width 0.2)
			(type default)
		)
		(fill no)
		(layer "In3.Cu")
	)
	(gr_circle
		(center 199.5297 -408.059382)
		(end 200.4187 -408.059382)
		(stroke
			(width 0.2)
			(type default)
		)
		(fill no)
		(layer "In3.Cu")
	)
	(gr_circle
		(center 199.5297 -407.297382)
		(end 200.4187 -407.297382)
		(stroke
			(width 0.2)
			(type default)
		)
		(fill no)
		(layer "In3.Cu")
	)
	(gr_circle
		(center 199.5297 -406.535382)
		(end 200.4187 -406.535382)
		(stroke
			(width 0.2)
			(type default)
		)
		(fill no)
		(layer "In3.Cu")
	)
	(gr_circle
		(center 199.5297 -405.773382)
		(end 200.4187 -405.773382)
		(stroke
			(width 0.2)
			(type default)
		)
		(fill no)
		(layer "In3.Cu")
	)
	(gr_circle
		(center 199.5297 -405.011382)
		(end 200.4187 -405.011382)
		(stroke
			(width 0.2)
			(type default)
		)
		(fill no)
		(layer "In3.Cu")
	)
	(gr_circle
		(center 199.536558 -403.223222)
		(end 200.425558 -403.223222)
		(stroke
			(width 0.2)
			(type default)
		)
		(fill no)
		(layer "In3.Cu")
	)
	(gr_circle
		(center 199.536558 -400.617182)
		(end 200.425558 -400.617182)
		(stroke
			(width 0.2)
			(type default)
		)
		(fill no)
		(layer "In3.Cu")
	)
	(gr_circle
		(center 199.756014 -30.133798)
		(end 200.645014 -30.133798)
		(stroke
			(width 0.2)
			(type default)
		)
		(fill no)
		(layer "In3.Cu")
	)
	(gr_circle
		(center 200.070974 -30.720538)
		(end 200.959974 -30.720538)
		(stroke
			(width 0.2)
			(type default)
		)
		(fill no)
		(layer "In3.Cu")
	)
	(gr_circle
		(center 200.2917 -408.059382)
		(end 201.1807 -408.059382)
		(stroke
			(width 0.2)
			(type default)
		)
		(fill no)
		(layer "In3.Cu")
	)
	(gr_circle
		(center 200.2917 -407.297382)
		(end 201.1807 -407.297382)
		(stroke
			(width 0.2)
			(type default)
		)
		(fill no)
		(layer "In3.Cu")
	)
	(gr_circle
		(center 200.2917 -406.535382)
		(end 201.1807 -406.535382)
		(stroke
			(width 0.2)
			(type default)
		)
		(fill no)
		(layer "In3.Cu")
	)
	(gr_circle
		(center 200.2917 -405.773382)
		(end 201.1807 -405.773382)
		(stroke
			(width 0.2)
			(type default)
		)
		(fill no)
		(layer "In3.Cu")
	)
	(gr_circle
		(center 200.2917 -405.011382)
		(end 201.1807 -405.011382)
		(stroke
			(width 0.2)
			(type default)
		)
		(fill no)
		(layer "In3.Cu")
	)
	(gr_circle
		(center 200.33234 -378.160534)
		(end 201.22134 -378.160534)
		(stroke
			(width 0.2)
			(type default)
		)
		(fill no)
		(layer "In3.Cu")
	)
	(gr_circle
		(center 200.391014 -30.133798)
		(end 201.280014 -30.133798)
		(stroke
			(width 0.2)
			(type default)
		)
		(fill no)
		(layer "In3.Cu")
	)
	(gr_circle
		(center 200.705974 -30.720538)
		(end 201.594974 -30.720538)
		(stroke
			(width 0.2)
			(type default)
		)
		(fill no)
		(layer "In3.Cu")
	)
	(gr_circle
		(center 200.933558 -403.223222)
		(end 201.822558 -403.223222)
		(stroke
			(width 0.2)
			(type default)
		)
		(fill no)
		(layer "In3.Cu")
	)
	(gr_circle
		(center 200.933558 -401.920202)
		(end 201.822558 -401.920202)
		(stroke
			(width 0.2)
			(type default)
		)
		(fill no)
		(layer "In3.Cu")
	)
	(gr_circle
		(center 200.933558 -400.617182)
		(end 201.822558 -400.617182)
		(stroke
			(width 0.2)
			(type default)
		)
		(fill no)
		(layer "In3.Cu")
	)
	(gr_circle
		(center 201.0537 -408.059382)
		(end 201.9427 -408.059382)
		(stroke
			(width 0.2)
			(type default)
		)
		(fill no)
		(layer "In3.Cu")
	)
	(gr_circle
		(center 201.0537 -407.297382)
		(end 201.9427 -407.297382)
		(stroke
			(width 0.2)
			(type default)
		)
		(fill no)
		(layer "In3.Cu")
	)
	(gr_circle
		(center 201.0537 -406.535382)
		(end 201.9427 -406.535382)
		(stroke
			(width 0.2)
			(type default)
		)
		(fill no)
		(layer "In3.Cu")
	)
	(gr_circle
		(center 201.0537 -405.773382)
		(end 201.9427 -405.773382)
		(stroke
			(width 0.2)
			(type default)
		)
		(fill no)
		(layer "In3.Cu")
	)
	(gr_circle
		(center 201.0537 -405.011382)
		(end 201.9427 -405.011382)
		(stroke
			(width 0.2)
			(type default)
		)
		(fill no)
		(layer "In3.Cu")
	)
	(gr_circle
		(center 201.340974 -30.720538)
		(end 202.229974 -30.720538)
		(stroke
			(width 0.2)
			(type default)
		)
		(fill no)
		(layer "In3.Cu")
	)
	(gr_circle
		(center 201.745342 -346.583)
		(end 202.634342 -346.583)
		(stroke
			(width 0.2)
			(type default)
		)
		(fill no)
		(layer "In3.Cu")
	)
	(gr_circle
		(center 201.745342 -345.821)
		(end 202.634342 -345.821)
		(stroke
			(width 0.2)
			(type default)
		)
		(fill no)
		(layer "In3.Cu")
	)
	(gr_circle
		(center 201.745342 -344.8304)
		(end 202.634342 -344.8304)
		(stroke
			(width 0.2)
			(type default)
		)
		(fill no)
		(layer "In3.Cu")
	)
	(gr_circle
		(center 201.745342 -344.0684)
		(end 202.634342 -344.0684)
		(stroke
			(width 0.2)
			(type default)
		)
		(fill no)
		(layer "In3.Cu")
	)
	(gr_line
		(start 205.73746 -435.231032)
		(end 207.302608 -436.79618)
		(stroke
			(width 0.635)
			(type default)
		)
		(layer "In3.Cu")
	)
	(gr_line
		(start 205.73746 -431.683414)
		(end 205.73746 -435.231032)
		(stroke
			(width 0.635)
			(type default)
		)
		(layer "In3.Cu")
	)
	(gr_circle
		(center 207.1497 -408.059382)
		(end 208.0387 -408.059382)
		(stroke
			(width 0.2)
			(type default)
		)
		(fill no)
		(layer "In3.Cu")
	)
	(gr_line
		(start 207.302608 -436.79618)
		(end 229.074472 -436.79618)
		(stroke
			(width 0.635)
			(type default)
		)
		(layer "In3.Cu")
	)
	(gr_circle
		(center 207.9117 -408.059382)
		(end 208.8007 -408.059382)
		(stroke
			(width 0.2)
			(type default)
		)
		(fill no)
		(layer "In3.Cu")
	)
	(gr_circle
		(center 207.9117 -407.297382)
		(end 208.8007 -407.297382)
		(stroke
			(width 0.2)
			(type default)
		)
		(fill no)
		(layer "In3.Cu")
	)
	(gr_circle
		(center 208.508854 -37.366448)
		(end 209.397854 -37.366448)
		(stroke
			(width 0.2)
			(type default)
		)
		(fill no)
		(layer "In3.Cu")
	)
	(gr_circle
		(center 208.6737 -408.059382)
		(end 209.5627 -408.059382)
		(stroke
			(width 0.2)
			(type default)
		)
		(fill no)
		(layer "In3.Cu")
	)
	(gr_circle
		(center 208.6737 -407.297382)
		(end 209.5627 -407.297382)
		(stroke
			(width 0.2)
			(type default)
		)
		(fill no)
		(layer "In3.Cu")
	)
	(gr_circle
		(center 208.6737 -406.535382)
		(end 209.5627 -406.535382)
		(stroke
			(width 0.2)
			(type default)
		)
		(fill no)
		(layer "In3.Cu")
	)
	(gr_circle
		(center 208.6737 -405.773382)
		(end 209.5627 -405.773382)
		(stroke
			(width 0.2)
			(type default)
		)
		(fill no)
		(layer "In3.Cu")
	)
	(gr_circle
		(center 208.6737 -405.011382)
		(end 209.5627 -405.011382)
		(stroke
			(width 0.2)
			(type default)
		)
		(fill no)
		(layer "In3.Cu")
	)
	(gr_circle
		(center 208.782158 -403.223222)
		(end 209.671158 -403.223222)
		(stroke
			(width 0.2)
			(type default)
		)
		(fill no)
		(layer "In3.Cu")
	)
	(gr_circle
		(center 208.782158 -401.920202)
		(end 209.671158 -401.920202)
		(stroke
			(width 0.2)
			(type default)
		)
		(fill no)
		(layer "In3.Cu")
	)
	(gr_circle
		(center 208.782158 -400.617182)
		(end 209.671158 -400.617182)
		(stroke
			(width 0.2)
			(type default)
		)
		(fill no)
		(layer "In3.Cu")
	)
	(gr_circle
		(center 209.4357 -408.059382)
		(end 210.3247 -408.059382)
		(stroke
			(width 0.2)
			(type default)
		)
		(fill no)
		(layer "In3.Cu")
	)
	(gr_circle
		(center 209.4357 -407.297382)
		(end 210.3247 -407.297382)
		(stroke
			(width 0.2)
			(type default)
		)
		(fill no)
		(layer "In3.Cu")
	)
	(gr_circle
		(center 209.4357 -406.535382)
		(end 210.3247 -406.535382)
		(stroke
			(width 0.2)
			(type default)
		)
		(fill no)
		(layer "In3.Cu")
	)
	(gr_circle
		(center 209.4357 -405.773382)
		(end 210.3247 -405.773382)
		(stroke
			(width 0.2)
			(type default)
		)
		(fill no)
		(layer "In3.Cu")
	)
	(gr_circle
		(center 209.4357 -405.011382)
		(end 210.3247 -405.011382)
		(stroke
			(width 0.2)
			(type default)
		)
		(fill no)
		(layer "In3.Cu")
	)
	(gr_circle
		(center 210.1977 -408.059382)
		(end 211.0867 -408.059382)
		(stroke
			(width 0.2)
			(type default)
		)
		(fill no)
		(layer "In3.Cu")
	)
	(gr_circle
		(center 210.1977 -407.297382)
		(end 211.0867 -407.297382)
		(stroke
			(width 0.2)
			(type default)
		)
		(fill no)
		(layer "In3.Cu")
	)
	(gr_circle
		(center 210.1977 -406.535382)
		(end 211.0867 -406.535382)
		(stroke
			(width 0.2)
			(type default)
		)
		(fill no)
		(layer "In3.Cu")
	)
	(gr_circle
		(center 210.1977 -405.773382)
		(end 211.0867 -405.773382)
		(stroke
			(width 0.2)
			(type default)
		)
		(fill no)
		(layer "In3.Cu")
	)
	(gr_circle
		(center 210.1977 -405.011382)
		(end 211.0867 -405.011382)
		(stroke
			(width 0.2)
			(type default)
		)
		(fill no)
		(layer "In3.Cu")
	)
	(gr_circle
		(center 210.204558 -403.223222)
		(end 211.093558 -403.223222)
		(stroke
			(width 0.2)
			(type default)
		)
		(fill no)
		(layer "In3.Cu")
	)
	(gr_circle
		(center 210.204558 -400.617182)
		(end 211.093558 -400.617182)
		(stroke
			(width 0.2)
			(type default)
		)
		(fill no)
		(layer "In3.Cu")
	)
	(gr_circle
		(center 210.9597 -408.059382)
		(end 211.8487 -408.059382)
		(stroke
			(width 0.2)
			(type default)
		)
		(fill no)
		(layer "In3.Cu")
	)
	(gr_circle
		(center 210.9597 -407.297382)
		(end 211.8487 -407.297382)
		(stroke
			(width 0.2)
			(type default)
		)
		(fill no)
		(layer "In3.Cu")
	)
	(gr_circle
		(center 210.9597 -406.535382)
		(end 211.8487 -406.535382)
		(stroke
			(width 0.2)
			(type default)
		)
		(fill no)
		(layer "In3.Cu")
	)
	(gr_circle
		(center 210.9597 -405.773382)
		(end 211.8487 -405.773382)
		(stroke
			(width 0.2)
			(type default)
		)
		(fill no)
		(layer "In3.Cu")
	)
	(gr_circle
		(center 210.9597 -405.011382)
		(end 211.8487 -405.011382)
		(stroke
			(width 0.2)
			(type default)
		)
		(fill no)
		(layer "In3.Cu")
	)
	(gr_circle
		(center 211.601558 -403.223222)
		(end 212.490558 -403.223222)
		(stroke
			(width 0.2)
			(type default)
		)
		(fill no)
		(layer "In3.Cu")
	)
	(gr_circle
		(center 211.601558 -401.920202)
		(end 212.490558 -401.920202)
		(stroke
			(width 0.2)
			(type default)
		)
		(fill no)
		(layer "In3.Cu")
	)
	(gr_circle
		(center 211.601558 -400.617182)
		(end 212.490558 -400.617182)
		(stroke
			(width 0.2)
			(type default)
		)
		(fill no)
		(layer "In3.Cu")
	)
	(gr_circle
		(center 211.7217 -408.059382)
		(end 212.6107 -408.059382)
		(stroke
			(width 0.2)
			(type default)
		)
		(fill no)
		(layer "In3.Cu")
	)
	(gr_circle
		(center 211.7217 -407.297382)
		(end 212.6107 -407.297382)
		(stroke
			(width 0.2)
			(type default)
		)
		(fill no)
		(layer "In3.Cu")
	)
	(gr_circle
		(center 211.7217 -406.535382)
		(end 212.6107 -406.535382)
		(stroke
			(width 0.2)
			(type default)
		)
		(fill no)
		(layer "In3.Cu")
	)
	(gr_circle
		(center 211.7217 -405.773382)
		(end 212.6107 -405.773382)
		(stroke
			(width 0.2)
			(type default)
		)
		(fill no)
		(layer "In3.Cu")
	)
	(gr_circle
		(center 211.7217 -405.011382)
		(end 212.6107 -405.011382)
		(stroke
			(width 0.2)
			(type default)
		)
		(fill no)
		(layer "In3.Cu")
	)
	(gr_circle
		(center 212.4837 -408.059382)
		(end 213.3727 -408.059382)
		(stroke
			(width 0.2)
			(type default)
		)
		(fill no)
		(layer "In3.Cu")
	)
	(gr_circle
		(center 212.4837 -407.297382)
		(end 213.3727 -407.297382)
		(stroke
			(width 0.2)
			(type default)
		)
		(fill no)
		(layer "In3.Cu")
	)
	(gr_circle
		(center 217.8177 -408.059382)
		(end 218.7067 -408.059382)
		(stroke
			(width 0.2)
			(type default)
		)
		(fill no)
		(layer "In3.Cu")
	)
	(gr_circle
		(center 218.5797 -408.059382)
		(end 219.4687 -408.059382)
		(stroke
			(width 0.2)
			(type default)
		)
		(fill no)
		(layer "In3.Cu")
	)
	(gr_circle
		(center 218.5797 -407.297382)
		(end 219.4687 -407.297382)
		(stroke
			(width 0.2)
			(type default)
		)
		(fill no)
		(layer "In3.Cu")
	)
	(gr_circle
		(center 219.3417 -408.059382)
		(end 220.2307 -408.059382)
		(stroke
			(width 0.2)
			(type default)
		)
		(fill no)
		(layer "In3.Cu")
	)
	(gr_circle
		(center 219.3417 -407.297382)
		(end 220.2307 -407.297382)
		(stroke
			(width 0.2)
			(type default)
		)
		(fill no)
		(layer "In3.Cu")
	)
	(gr_circle
		(center 219.3417 -406.535382)
		(end 220.2307 -406.535382)
		(stroke
			(width 0.2)
			(type default)
		)
		(fill no)
		(layer "In3.Cu")
	)
	(gr_circle
		(center 219.3417 -405.773382)
		(end 220.2307 -405.773382)
		(stroke
			(width 0.2)
			(type default)
		)
		(fill no)
		(layer "In3.Cu")
	)
	(gr_circle
		(center 219.3417 -405.011382)
		(end 220.2307 -405.011382)
		(stroke
			(width 0.2)
			(type default)
		)
		(fill no)
		(layer "In3.Cu")
	)
	(gr_circle
		(center 219.450158 -403.223222)
		(end 220.339158 -403.223222)
		(stroke
			(width 0.2)
			(type default)
		)
		(fill no)
		(layer "In3.Cu")
	)
	(gr_circle
		(center 219.450158 -401.920202)
		(end 220.339158 -401.920202)
		(stroke
			(width 0.2)
			(type default)
		)
		(fill no)
		(layer "In3.Cu")
	)
	(gr_circle
		(center 219.450158 -400.617182)
		(end 220.339158 -400.617182)
		(stroke
			(width 0.2)
			(type default)
		)
		(fill no)
		(layer "In3.Cu")
	)
	(gr_circle
		(center 220.1037 -408.059382)
		(end 220.9927 -408.059382)
		(stroke
			(width 0.2)
			(type default)
		)
		(fill no)
		(layer "In3.Cu")
	)
	(gr_circle
		(center 220.1037 -407.297382)
		(end 220.9927 -407.297382)
		(stroke
			(width 0.2)
			(type default)
		)
		(fill no)
		(layer "In3.Cu")
	)
	(gr_circle
		(center 220.1037 -406.535382)
		(end 220.9927 -406.535382)
		(stroke
			(width 0.2)
			(type default)
		)
		(fill no)
		(layer "In3.Cu")
	)
	(gr_circle
		(center 220.1037 -405.773382)
		(end 220.9927 -405.773382)
		(stroke
			(width 0.2)
			(type default)
		)
		(fill no)
		(layer "In3.Cu")
	)
	(gr_circle
		(center 220.1037 -405.011382)
		(end 220.9927 -405.011382)
		(stroke
			(width 0.2)
			(type default)
		)
		(fill no)
		(layer "In3.Cu")
	)
	(gr_circle
		(center 220.8657 -408.059382)
		(end 221.7547 -408.059382)
		(stroke
			(width 0.2)
			(type default)
		)
		(fill no)
		(layer "In3.Cu")
	)
	(gr_circle
		(center 220.8657 -407.297382)
		(end 221.7547 -407.297382)
		(stroke
			(width 0.2)
			(type default)
		)
		(fill no)
		(layer "In3.Cu")
	)
	(gr_circle
		(center 220.8657 -406.535382)
		(end 221.7547 -406.535382)
		(stroke
			(width 0.2)
			(type default)
		)
		(fill no)
		(layer "In3.Cu")
	)
	(gr_circle
		(center 220.8657 -405.773382)
		(end 221.7547 -405.773382)
		(stroke
			(width 0.2)
			(type default)
		)
		(fill no)
		(layer "In3.Cu")
	)
	(gr_circle
		(center 220.8657 -405.011382)
		(end 221.7547 -405.011382)
		(stroke
			(width 0.2)
			(type default)
		)
		(fill no)
		(layer "In3.Cu")
	)
	(gr_circle
		(center 220.872558 -403.223222)
		(end 221.761558 -403.223222)
		(stroke
			(width 0.2)
			(type default)
		)
		(fill no)
		(layer "In3.Cu")
	)
	(gr_circle
		(center 220.872558 -400.617182)
		(end 221.761558 -400.617182)
		(stroke
			(width 0.2)
			(type default)
		)
		(fill no)
		(layer "In3.Cu")
	)
	(gr_circle
		(center 221.6277 -408.059382)
		(end 222.5167 -408.059382)
		(stroke
			(width 0.2)
			(type default)
		)
		(fill no)
		(layer "In3.Cu")
	)
	(gr_circle
		(center 221.6277 -407.297382)
		(end 222.5167 -407.297382)
		(stroke
			(width 0.2)
			(type default)
		)
		(fill no)
		(layer "In3.Cu")
	)
	(gr_circle
		(center 221.6277 -406.535382)
		(end 222.5167 -406.535382)
		(stroke
			(width 0.2)
			(type default)
		)
		(fill no)
		(layer "In3.Cu")
	)
	(gr_circle
		(center 221.6277 -405.773382)
		(end 222.5167 -405.773382)
		(stroke
			(width 0.2)
			(type default)
		)
		(fill no)
		(layer "In3.Cu")
	)
	(gr_circle
		(center 221.6277 -405.011382)
		(end 222.5167 -405.011382)
		(stroke
			(width 0.2)
			(type default)
		)
		(fill no)
		(layer "In3.Cu")
	)
	(gr_circle
		(center 222.269558 -403.223222)
		(end 223.158558 -403.223222)
		(stroke
			(width 0.2)
			(type default)
		)
		(fill no)
		(layer "In3.Cu")
	)
	(gr_circle
		(center 222.269558 -401.920202)
		(end 223.158558 -401.920202)
		(stroke
			(width 0.2)
			(type default)
		)
		(fill no)
		(layer "In3.Cu")
	)
	(gr_circle
		(center 222.269558 -400.617182)
		(end 223.158558 -400.617182)
		(stroke
			(width 0.2)
			(type default)
		)
		(fill no)
		(layer "In3.Cu")
	)
	(gr_circle
		(center 222.3897 -408.059382)
		(end 223.2787 -408.059382)
		(stroke
			(width 0.2)
			(type default)
		)
		(fill no)
		(layer "In3.Cu")
	)
	(gr_circle
		(center 222.3897 -407.297382)
		(end 223.2787 -407.297382)
		(stroke
			(width 0.2)
			(type default)
		)
		(fill no)
		(layer "In3.Cu")
	)
	(gr_circle
		(center 222.3897 -406.535382)
		(end 223.2787 -406.535382)
		(stroke
			(width 0.2)
			(type default)
		)
		(fill no)
		(layer "In3.Cu")
	)
	(gr_circle
		(center 222.3897 -405.773382)
		(end 223.2787 -405.773382)
		(stroke
			(width 0.2)
			(type default)
		)
		(fill no)
		(layer "In3.Cu")
	)
	(gr_circle
		(center 222.3897 -405.011382)
		(end 223.2787 -405.011382)
		(stroke
			(width 0.2)
			(type default)
		)
		(fill no)
		(layer "In3.Cu")
	)
	(gr_circle
		(center 223.1517 -408.059382)
		(end 224.0407 -408.059382)
		(stroke
			(width 0.2)
			(type default)
		)
		(fill no)
		(layer "In3.Cu")
	)
	(gr_circle
		(center 223.1517 -407.297382)
		(end 224.0407 -407.297382)
		(stroke
			(width 0.2)
			(type default)
		)
		(fill no)
		(layer "In3.Cu")
	)
	(gr_arc
		(start 223.300036 -34.120074)
		(mid 223.885821 -35.534285)
		(end 225.300032 -36.12007)
		(stroke
			(width 1.016)
			(type default)
		)
		(layer "In3.Cu")
	)
	(gr_arc
		(start 223.300036 -13.780008)
		(mid 222.714256 -12.365778)
		(end 221.30004 -11.780012)
		(stroke
			(width 1.016)
			(type default)
		)
		(layer "In3.Cu")
	)
	(gr_line
		(start 223.300036 -13.780008)
		(end 223.300036 -34.120074)
		(stroke
			(width 1.016)
			(type default)
		)
		(layer "In3.Cu")
	)
	(gr_line
		(start 225.300032 -36.12007)
		(end 256.800096 -36.12007)
		(stroke
			(width 1.016)
			(type default)
		)
		(layer "In3.Cu")
	)
	(gr_line
		(start 226.931728 -412.92653)
		(end 229.545642 -410.312616)
		(stroke
			(width 0.635)
			(type default)
		)
		(layer "In3.Cu")
	)
	(gr_circle
		(center 228.4857 -408.059382)
		(end 229.3747 -408.059382)
		(stroke
			(width 0.2)
			(type default)
		)
		(fill no)
		(layer "In3.Cu")
	)
	(gr_line
		(start 229.074472 -436.79618)
		(end 229.997 -435.873652)
		(stroke
			(width 0.635)
			(type default)
		)
		(layer "In3.Cu")
	)
	(gr_circle
		(center 229.2477 -408.059382)
		(end 230.1367 -408.059382)
		(stroke
			(width 0.2)
			(type default)
		)
		(fill no)
		(layer "In3.Cu")
	)
	(gr_circle
		(center 229.2477 -407.297382)
		(end 230.1367 -407.297382)
		(stroke
			(width 0.2)
			(type default)
		)
		(fill no)
		(layer "In3.Cu")
	)
	(gr_line
		(start 229.545642 -410.312616)
		(end 234.715812 -410.312616)
		(stroke
			(width 0.635)
			(type default)
		)
		(layer "In3.Cu")
	)
	(gr_line
		(start 229.997 -435.873652)
		(end 229.997 -422.180766)
		(stroke
			(width 0.635)
			(type default)
		)
		(layer "In3.Cu")
	)
	(gr_circle
		(center 230.0097 -408.059382)
		(end 230.8987 -408.059382)
		(stroke
			(width 0.2)
			(type default)
		)
		(fill no)
		(layer "In3.Cu")
	)
	(gr_circle
		(center 230.0097 -407.297382)
		(end 230.8987 -407.297382)
		(stroke
			(width 0.2)
			(type default)
		)
		(fill no)
		(layer "In3.Cu")
	)
	(gr_circle
		(center 230.0097 -406.535382)
		(end 230.8987 -406.535382)
		(stroke
			(width 0.2)
			(type default)
		)
		(fill no)
		(layer "In3.Cu")
	)
	(gr_circle
		(center 230.0097 -405.773382)
		(end 230.8987 -405.773382)
		(stroke
			(width 0.2)
			(type default)
		)
		(fill no)
		(layer "In3.Cu")
	)
	(gr_circle
		(center 230.0097 -405.011382)
		(end 230.8987 -405.011382)
		(stroke
			(width 0.2)
			(type default)
		)
		(fill no)
		(layer "In3.Cu")
	)
	(gr_circle
		(center 230.118158 -403.223222)
		(end 231.007158 -403.223222)
		(stroke
			(width 0.2)
			(type default)
		)
		(fill no)
		(layer "In3.Cu")
	)
	(gr_circle
		(center 230.118158 -401.920202)
		(end 231.007158 -401.920202)
		(stroke
			(width 0.2)
			(type default)
		)
		(fill no)
		(layer "In3.Cu")
	)
	(gr_circle
		(center 230.118158 -400.617182)
		(end 231.007158 -400.617182)
		(stroke
			(width 0.2)
			(type default)
		)
		(fill no)
		(layer "In3.Cu")
	)
	(gr_circle
		(center 230.7717 -408.059382)
		(end 231.6607 -408.059382)
		(stroke
			(width 0.2)
			(type default)
		)
		(fill no)
		(layer "In3.Cu")
	)
	(gr_circle
		(center 230.7717 -407.297382)
		(end 231.6607 -407.297382)
		(stroke
			(width 0.2)
			(type default)
		)
		(fill no)
		(layer "In3.Cu")
	)
	(gr_circle
		(center 230.7717 -406.535382)
		(end 231.6607 -406.535382)
		(stroke
			(width 0.2)
			(type default)
		)
		(fill no)
		(layer "In3.Cu")
	)
	(gr_circle
		(center 230.7717 -405.773382)
		(end 231.6607 -405.773382)
		(stroke
			(width 0.2)
			(type default)
		)
		(fill no)
		(layer "In3.Cu")
	)
	(gr_circle
		(center 230.7717 -405.011382)
		(end 231.6607 -405.011382)
		(stroke
			(width 0.2)
			(type default)
		)
		(fill no)
		(layer "In3.Cu")
	)
	(gr_circle
		(center 231.5337 -408.059382)
		(end 232.4227 -408.059382)
		(stroke
			(width 0.2)
			(type default)
		)
		(fill no)
		(layer "In3.Cu")
	)
	(gr_circle
		(center 231.5337 -407.297382)
		(end 232.4227 -407.297382)
		(stroke
			(width 0.2)
			(type default)
		)
		(fill no)
		(layer "In3.Cu")
	)
	(gr_circle
		(center 231.5337 -406.535382)
		(end 232.4227 -406.535382)
		(stroke
			(width 0.2)
			(type default)
		)
		(fill no)
		(layer "In3.Cu")
	)
	(gr_circle
		(center 231.5337 -405.773382)
		(end 232.4227 -405.773382)
		(stroke
			(width 0.2)
			(type default)
		)
		(fill no)
		(layer "In3.Cu")
	)
	(gr_circle
		(center 231.5337 -405.011382)
		(end 232.4227 -405.011382)
		(stroke
			(width 0.2)
			(type default)
		)
		(fill no)
		(layer "In3.Cu")
	)
	(gr_circle
		(center 231.540558 -403.223222)
		(end 232.429558 -403.223222)
		(stroke
			(width 0.2)
			(type default)
		)
		(fill no)
		(layer "In3.Cu")
	)
	(gr_circle
		(center 231.540558 -400.617182)
		(end 232.429558 -400.617182)
		(stroke
			(width 0.2)
			(type default)
		)
		(fill no)
		(layer "In3.Cu")
	)
	(gr_circle
		(center 232.2957 -408.059382)
		(end 233.1847 -408.059382)
		(stroke
			(width 0.2)
			(type default)
		)
		(fill no)
		(layer "In3.Cu")
	)
	(gr_circle
		(center 232.2957 -407.297382)
		(end 233.1847 -407.297382)
		(stroke
			(width 0.2)
			(type default)
		)
		(fill no)
		(layer "In3.Cu")
	)
	(gr_circle
		(center 232.2957 -406.535382)
		(end 233.1847 -406.535382)
		(stroke
			(width 0.2)
			(type default)
		)
		(fill no)
		(layer "In3.Cu")
	)
	(gr_circle
		(center 232.2957 -405.773382)
		(end 233.1847 -405.773382)
		(stroke
			(width 0.2)
			(type default)
		)
		(fill no)
		(layer "In3.Cu")
	)
	(gr_circle
		(center 232.2957 -405.011382)
		(end 233.1847 -405.011382)
		(stroke
			(width 0.2)
			(type default)
		)
		(fill no)
		(layer "In3.Cu")
	)
	(gr_circle
		(center 232.937558 -403.223222)
		(end 233.826558 -403.223222)
		(stroke
			(width 0.2)
			(type default)
		)
		(fill no)
		(layer "In3.Cu")
	)
	(gr_circle
		(center 232.937558 -401.920202)
		(end 233.826558 -401.920202)
		(stroke
			(width 0.2)
			(type default)
		)
		(fill no)
		(layer "In3.Cu")
	)
	(gr_circle
		(center 232.937558 -400.617182)
		(end 233.826558 -400.617182)
		(stroke
			(width 0.2)
			(type default)
		)
		(fill no)
		(layer "In3.Cu")
	)
	(gr_circle
		(center 233.0577 -408.059382)
		(end 233.9467 -408.059382)
		(stroke
			(width 0.2)
			(type default)
		)
		(fill no)
		(layer "In3.Cu")
	)
	(gr_circle
		(center 233.0577 -407.297382)
		(end 233.9467 -407.297382)
		(stroke
			(width 0.2)
			(type default)
		)
		(fill no)
		(layer "In3.Cu")
	)
	(gr_circle
		(center 233.0577 -406.535382)
		(end 233.9467 -406.535382)
		(stroke
			(width 0.2)
			(type default)
		)
		(fill no)
		(layer "In3.Cu")
	)
	(gr_circle
		(center 233.0577 -405.773382)
		(end 233.9467 -405.773382)
		(stroke
			(width 0.2)
			(type default)
		)
		(fill no)
		(layer "In3.Cu")
	)
	(gr_circle
		(center 233.0577 -405.011382)
		(end 233.9467 -405.011382)
		(stroke
			(width 0.2)
			(type default)
		)
		(fill no)
		(layer "In3.Cu")
	)
	(gr_circle
		(center 233.8197 -408.059382)
		(end 234.7087 -408.059382)
		(stroke
			(width 0.2)
			(type default)
		)
		(fill no)
		(layer "In3.Cu")
	)
	(gr_circle
		(center 233.8197 -407.297382)
		(end 234.7087 -407.297382)
		(stroke
			(width 0.2)
			(type default)
		)
		(fill no)
		(layer "In3.Cu")
	)
	(gr_line
		(start 234.715812 -410.312616)
		(end 238.882682 -406.145746)
		(stroke
			(width 0.635)
			(type default)
		)
		(layer "In3.Cu")
	)
	(gr_line
		(start 234.897676 -417.28009)
		(end 229.997 -422.180766)
		(stroke
			(width 0.635)
			(type default)
		)
		(layer "In3.Cu")
	)
	(gr_circle
		(center 237.629954 -44.025566)
		(end 238.518954 -44.025566)
		(stroke
			(width 0.2)
			(type default)
		)
		(fill no)
		(layer "In3.Cu")
	)
	(gr_circle
		(center 237.640114 -44.716446)
		(end 238.529114 -44.716446)
		(stroke
			(width 0.2)
			(type default)
		)
		(fill no)
		(layer "In3.Cu")
	)
	(gr_circle
		(center 238.292894 -44.802806)
		(end 239.181894 -44.802806)
		(stroke
			(width 0.2)
			(type default)
		)
		(fill no)
		(layer "In3.Cu")
	)
	(gr_circle
		(center 238.292894 -44.040806)
		(end 239.181894 -44.040806)
		(stroke
			(width 0.2)
			(type default)
		)
		(fill no)
		(layer "In3.Cu")
	)
	(gr_line
		(start 238.882682 -406.145746)
		(end 238.882682 -397.979646)
		(stroke
			(width 0.635)
			(type default)
		)
		(layer "In3.Cu")
	)
	(gr_line
		(start 238.882682 -397.979646)
		(end 239.401096 -397.461232)
		(stroke
			(width 0.635)
			(type default)
		)
		(layer "In3.Cu")
	)
	(gr_circle
		(center 238.943134 -44.802806)
		(end 239.832134 -44.802806)
		(stroke
			(width 0.2)
			(type default)
		)
		(fill no)
		(layer "In3.Cu")
	)
	(gr_circle
		(center 238.943134 -44.040806)
		(end 239.832134 -44.040806)
		(stroke
			(width 0.2)
			(type default)
		)
		(fill no)
		(layer "In3.Cu")
	)
	(gr_line
		(start 239.401096 -397.461232)
		(end 279.415748 -397.461232)
		(stroke
			(width 0.635)
			(type default)
		)
		(layer "In3.Cu")
	)
	(gr_circle
		(center 239.578134 -44.802806)
		(end 240.467134 -44.802806)
		(stroke
			(width 0.2)
			(type default)
		)
		(fill no)
		(layer "In3.Cu")
	)
	(gr_circle
		(center 239.578134 -44.040806)
		(end 240.467134 -44.040806)
		(stroke
			(width 0.2)
			(type default)
		)
		(fill no)
		(layer "In3.Cu")
	)
	(gr_circle
		(center 239.879124 -389.328914)
		(end 240.768124 -389.328914)
		(stroke
			(width 0.2)
			(type default)
		)
		(fill no)
		(layer "In3.Cu")
	)
	(gr_circle
		(center 240.213134 -44.802806)
		(end 241.102134 -44.802806)
		(stroke
			(width 0.2)
			(type default)
		)
		(fill no)
		(layer "In3.Cu")
	)
	(gr_circle
		(center 240.213134 -44.040806)
		(end 241.102134 -44.040806)
		(stroke
			(width 0.2)
			(type default)
		)
		(fill no)
		(layer "In3.Cu")
	)
	(gr_circle
		(center 240.893854 -44.830746)
		(end 241.782854 -44.830746)
		(stroke
			(width 0.2)
			(type default)
		)
		(fill no)
		(layer "In3.Cu")
	)
	(gr_circle
		(center 242.6589 -389.32104)
		(end 243.5479 -389.32104)
		(stroke
			(width 0.2)
			(type default)
		)
		(fill no)
		(layer "In3.Cu")
	)
	(gr_circle
		(center 243.4209 -389.32104)
		(end 244.3099 -389.32104)
		(stroke
			(width 0.2)
			(type default)
		)
		(fill no)
		(layer "In3.Cu")
	)
	(gr_circle
		(center 244.1829 -389.32104)
		(end 245.0719 -389.32104)
		(stroke
			(width 0.2)
			(type default)
		)
		(fill no)
		(layer "In3.Cu")
	)
	(gr_circle
		(center 244.518942 -43.246802)
		(end 245.407942 -43.246802)
		(stroke
			(width 0.2)
			(type default)
		)
		(fill no)
		(layer "In3.Cu")
	)
	(gr_circle
		(center 244.518942 -42.611802)
		(end 245.407942 -42.611802)
		(stroke
			(width 0.2)
			(type default)
		)
		(fill no)
		(layer "In3.Cu")
	)
	(gr_circle
		(center 244.63248 -387.62432)
		(end 245.52148 -387.62432)
		(stroke
			(width 0.2)
			(type default)
		)
		(fill no)
		(layer "In3.Cu")
	)
	(gr_circle
		(center 244.63248 -386.86232)
		(end 245.52148 -386.86232)
		(stroke
			(width 0.2)
			(type default)
		)
		(fill no)
		(layer "In3.Cu")
	)
	(gr_circle
		(center 244.63248 -386.10032)
		(end 245.52148 -386.10032)
		(stroke
			(width 0.2)
			(type default)
		)
		(fill no)
		(layer "In3.Cu")
	)
	(gr_circle
		(center 244.9449 -389.32104)
		(end 245.8339 -389.32104)
		(stroke
			(width 0.2)
			(type default)
		)
		(fill no)
		(layer "In3.Cu")
	)
	(gr_circle
		(center 245.7069 -389.32104)
		(end 246.5959 -389.32104)
		(stroke
			(width 0.2)
			(type default)
		)
		(fill no)
		(layer "In3.Cu")
	)
	(gr_circle
		(center 245.857522 -52.022502)
		(end 246.746522 -52.022502)
		(stroke
			(width 0.2)
			(type default)
		)
		(fill no)
		(layer "In3.Cu")
	)
	(gr_circle
		(center 246.873522 -52.022502)
		(end 247.762522 -52.022502)
		(stroke
			(width 0.2)
			(type default)
		)
		(fill no)
		(layer "In3.Cu")
	)
	(gr_circle
		(center 247.825514 -40.94988)
		(end 248.714514 -40.94988)
		(stroke
			(width 0.2)
			(type default)
		)
		(fill no)
		(layer "In3.Cu")
	)
	(gr_circle
		(center 247.840246 -51.320446)
		(end 248.729246 -51.320446)
		(stroke
			(width 0.2)
			(type default)
		)
		(fill no)
		(layer "In3.Cu")
	)
	(gr_circle
		(center 248.214134 -52.171346)
		(end 249.103134 -52.171346)
		(stroke
			(width 0.2)
			(type default)
		)
		(fill no)
		(layer "In3.Cu")
	)
	(gr_circle
		(center 248.881646 -51.320446)
		(end 249.770646 -51.320446)
		(stroke
			(width 0.2)
			(type default)
		)
		(fill no)
		(layer "In3.Cu")
	)
	(gr_circle
		(center 249.202448 -40.945816)
		(end 250.091448 -40.945816)
		(stroke
			(width 0.2)
			(type default)
		)
		(fill no)
		(layer "In3.Cu")
	)
	(gr_circle
		(center 249.905266 -51.349148)
		(end 250.794266 -51.349148)
		(stroke
			(width 0.2)
			(type default)
		)
		(fill no)
		(layer "In3.Cu")
	)
	(gr_circle
		(center 250.449334 -49.555146)
		(end 251.338334 -49.555146)
		(stroke
			(width 0.2)
			(type default)
		)
		(fill no)
		(layer "In3.Cu")
	)
	(gr_circle
		(center 250.567444 -387.62432)
		(end 251.456444 -387.62432)
		(stroke
			(width 0.2)
			(type default)
		)
		(fill no)
		(layer "In3.Cu")
	)
	(gr_circle
		(center 250.567444 -386.86232)
		(end 251.456444 -386.86232)
		(stroke
			(width 0.2)
			(type default)
		)
		(fill no)
		(layer "In3.Cu")
	)
	(gr_circle
		(center 250.567444 -386.10032)
		(end 251.456444 -386.10032)
		(stroke
			(width 0.2)
			(type default)
		)
		(fill no)
		(layer "In3.Cu")
	)
	(gr_circle
		(center 250.779534 -52.222146)
		(end 251.668534 -52.222146)
		(stroke
			(width 0.2)
			(type default)
		)
		(fill no)
		(layer "In3.Cu")
	)
	(gr_circle
		(center 250.779534 -51.333146)
		(end 251.668534 -51.333146)
		(stroke
			(width 0.2)
			(type default)
		)
		(fill no)
		(layer "In3.Cu")
	)
	(gr_circle
		(center 250.779534 -50.444146)
		(end 251.668534 -50.444146)
		(stroke
			(width 0.2)
			(type default)
		)
		(fill no)
		(layer "In3.Cu")
	)
	(gr_circle
		(center 251.02312 -389.32104)
		(end 251.91212 -389.32104)
		(stroke
			(width 0.2)
			(type default)
		)
		(fill no)
		(layer "In3.Cu")
	)
	(gr_circle
		(center 251.516134 -52.501546)
		(end 252.405134 -52.501546)
		(stroke
			(width 0.2)
			(type default)
		)
		(fill no)
		(layer "In3.Cu")
	)
	(gr_circle
		(center 251.516134 -51.612546)
		(end 252.405134 -51.612546)
		(stroke
			(width 0.2)
			(type default)
		)
		(fill no)
		(layer "In3.Cu")
	)
	(gr_circle
		(center 251.516134 -50.723546)
		(end 252.405134 -50.723546)
		(stroke
			(width 0.2)
			(type default)
		)
		(fill no)
		(layer "In3.Cu")
	)
	(gr_circle
		(center 251.78512 -389.32104)
		(end 252.67412 -389.32104)
		(stroke
			(width 0.2)
			(type default)
		)
		(fill no)
		(layer "In3.Cu")
	)
	(gr_circle
		(center 252.54712 -389.32104)
		(end 253.43612 -389.32104)
		(stroke
			(width 0.2)
			(type default)
		)
		(fill no)
		(layer "In3.Cu")
	)
	(gr_circle
		(center 253.30912 -389.32104)
		(end 254.19812 -389.32104)
		(stroke
			(width 0.2)
			(type default)
		)
		(fill no)
		(layer "In3.Cu")
	)
	(gr_circle
		(center 254.07112 -389.32104)
		(end 254.96012 -389.32104)
		(stroke
			(width 0.2)
			(type default)
		)
		(fill no)
		(layer "In3.Cu")
	)
	(gr_circle
		(center 255.347978 -39.380922)
		(end 256.236978 -39.380922)
		(stroke
			(width 0.2)
			(type default)
		)
		(fill no)
		(layer "In3.Cu")
	)
	(gr_circle
		(center 256.502408 -387.62432)
		(end 257.391408 -387.62432)
		(stroke
			(width 0.2)
			(type default)
		)
		(fill no)
		(layer "In3.Cu")
	)
	(gr_circle
		(center 256.502408 -386.86232)
		(end 257.391408 -386.86232)
		(stroke
			(width 0.2)
			(type default)
		)
		(fill no)
		(layer "In3.Cu")
	)
	(gr_circle
		(center 256.502408 -386.10032)
		(end 257.391408 -386.10032)
		(stroke
			(width 0.2)
			(type default)
		)
		(fill no)
		(layer "In3.Cu")
	)
	(gr_arc
		(start 256.800096 -36.12007)
		(mid 258.214307 -35.534285)
		(end 258.800092 -34.120074)
		(stroke
			(width 1.016)
			(type default)
		)
		(layer "In3.Cu")
	)
	(gr_line
		(start 258.800092 -34.120074)
		(end 258.800092 -13.780008)
		(stroke
			(width 1.016)
			(type default)
		)
		(layer "In3.Cu")
	)
	(gr_circle
		(center 258.93776 -389.36422)
		(end 259.82676 -389.36422)
		(stroke
			(width 0.2)
			(type default)
		)
		(fill no)
		(layer "In3.Cu")
	)
	(gr_circle
		(center 259.69976 -389.36422)
		(end 260.58876 -389.36422)
		(stroke
			(width 0.2)
			(type default)
		)
		(fill no)
		(layer "In3.Cu")
	)
	(gr_circle
		(center 260.46176 -389.36422)
		(end 261.35076 -389.36422)
		(stroke
			(width 0.2)
			(type default)
		)
		(fill no)
		(layer "In3.Cu")
	)
	(gr_arc
		(start 260.800088 -11.780012)
		(mid 259.385888 -12.365802)
		(end 258.800092 -13.780008)
		(stroke
			(width 1.016)
			(type default)
		)
		(layer "In3.Cu")
	)
	(gr_line
		(start 260.800088 -11.780012)
		(end 385.601972 -11.780012)
		(stroke
			(width 1.016)
			(type default)
		)
		(layer "In3.Cu")
	)
	(gr_circle
		(center 261.22376 -389.36422)
		(end 262.11276 -389.36422)
		(stroke
			(width 0.2)
			(type default)
		)
		(fill no)
		(layer "In3.Cu")
	)
	(gr_circle
		(center 261.98576 -389.36422)
		(end 262.87476 -389.36422)
		(stroke
			(width 0.2)
			(type default)
		)
		(fill no)
		(layer "In3.Cu")
	)
	(gr_circle
		(center 262.437372 -387.62432)
		(end 263.326372 -387.62432)
		(stroke
			(width 0.2)
			(type default)
		)
		(fill no)
		(layer "In3.Cu")
	)
	(gr_circle
		(center 262.437372 -386.86232)
		(end 263.326372 -386.86232)
		(stroke
			(width 0.2)
			(type default)
		)
		(fill no)
		(layer "In3.Cu")
	)
	(gr_circle
		(center 262.437372 -386.10032)
		(end 263.326372 -386.10032)
		(stroke
			(width 0.2)
			(type default)
		)
		(fill no)
		(layer "In3.Cu")
	)
	(gr_circle
		(center 266.98194 -389.3439)
		(end 267.87094 -389.3439)
		(stroke
			(width 0.2)
			(type default)
		)
		(fill no)
		(layer "In3.Cu")
	)
	(gr_circle
		(center 267.74394 -389.3439)
		(end 268.63294 -389.3439)
		(stroke
			(width 0.2)
			(type default)
		)
		(fill no)
		(layer "In3.Cu")
	)
	(gr_circle
		(center 268.372336 -387.62432)
		(end 269.261336 -387.62432)
		(stroke
			(width 0.2)
			(type default)
		)
		(fill no)
		(layer "In3.Cu")
	)
	(gr_circle
		(center 268.372336 -386.86232)
		(end 269.261336 -386.86232)
		(stroke
			(width 0.2)
			(type default)
		)
		(fill no)
		(layer "In3.Cu")
	)
	(gr_circle
		(center 268.372336 -386.10032)
		(end 269.261336 -386.10032)
		(stroke
			(width 0.2)
			(type default)
		)
		(fill no)
		(layer "In3.Cu")
	)
	(gr_circle
		(center 268.50594 -389.3439)
		(end 269.39494 -389.3439)
		(stroke
			(width 0.2)
			(type default)
		)
		(fill no)
		(layer "In3.Cu")
	)
	(gr_circle
		(center 269.26794 -389.3439)
		(end 270.15694 -389.3439)
		(stroke
			(width 0.2)
			(type default)
		)
		(fill no)
		(layer "In3.Cu")
	)
	(gr_circle
		(center 270.02994 -389.3439)
		(end 270.91894 -389.3439)
		(stroke
			(width 0.2)
			(type default)
		)
		(fill no)
		(layer "In3.Cu")
	)
	(gr_line
		(start 272.19021 -417.28009)
		(end 234.897676 -417.28009)
		(stroke
			(width 0.635)
			(type default)
		)
		(layer "In3.Cu")
	)
	(gr_circle
		(center 276.112986 -348.704662)
		(end 276.993096 -348.704662)
		(stroke
			(width 0.2)
			(type default)
		)
		(fill no)
		(layer "In3.Cu")
	)
	(gr_circle
		(center 276.1742 -389.29564)
		(end 277.0632 -389.29564)
		(stroke
			(width 0.2)
			(type default)
		)
		(fill no)
		(layer "In3.Cu")
	)
	(gr_line
		(start 276.314916 -440.669934)
		(end 195.50507 -440.669934)
		(stroke
			(width 1.016)
			(type default)
		)
		(layer "In3.Cu")
	)
	(gr_circle
		(center 276.730206 -348.704662)
		(end 277.610316 -348.704662)
		(stroke
			(width 0.2)
			(type default)
		)
		(fill no)
		(layer "In3.Cu")
	)
	(gr_line
		(start 276.815042 -441.4901)
		(end 276.815042 -441.17006)
		(stroke
			(width 1.016)
			(type default)
		)
		(layer "In3.Cu")
	)
	(gr_arc
		(start 276.815042 -441.4901)
		(mid 276.961452 -441.843558)
		(end 277.314914 -441.989972)
		(stroke
			(width 1.016)
			(type default)
		)
		(layer "In3.Cu")
	)
	(gr_arc
		(start 276.815042 -441.17006)
		(mid 276.668558 -440.816418)
		(end 276.314916 -440.669934)
		(stroke
			(width 1.016)
			(type default)
		)
		(layer "In3.Cu")
	)
	(gr_circle
		(center 276.9362 -389.29564)
		(end 277.8252 -389.29564)
		(stroke
			(width 0.2)
			(type default)
		)
		(fill no)
		(layer "In3.Cu")
	)
	(gr_circle
		(center 277.347426 -348.704662)
		(end 278.227536 -348.704662)
		(stroke
			(width 0.2)
			(type default)
		)
		(fill no)
		(layer "In3.Cu")
	)
	(gr_circle
		(center 277.593806 -348.025212)
		(end 278.482806 -348.025212)
		(stroke
			(width 0.2)
			(type default)
		)
		(fill no)
		(layer "In3.Cu")
	)
	(gr_circle
		(center 277.593806 -347.288612)
		(end 278.482806 -347.288612)
		(stroke
			(width 0.2)
			(type default)
		)
		(fill no)
		(layer "In3.Cu")
	)
	(gr_circle
		(center 277.6982 -389.29564)
		(end 278.5872 -389.29564)
		(stroke
			(width 0.2)
			(type default)
		)
		(fill no)
		(layer "In3.Cu")
	)
	(gr_circle
		(center 278.049482 -350.313752)
		(end 278.938482 -350.313752)
		(stroke
			(width 0.2)
			(type default)
		)
		(fill no)
		(layer "In3.Cu")
	)
	(gr_circle
		(center 278.049482 -349.577152)
		(end 278.938482 -349.577152)
		(stroke
			(width 0.2)
			(type default)
		)
		(fill no)
		(layer "In3.Cu")
	)
	(gr_circle
		(center 278.4602 -389.29564)
		(end 279.3492 -389.29564)
		(stroke
			(width 0.2)
			(type default)
		)
		(fill no)
		(layer "In3.Cu")
	)
	(gr_circle
		(center 278.574246 -349.137732)
		(end 279.463246 -349.137732)
		(stroke
			(width 0.2)
			(type default)
		)
		(fill no)
		(layer "In3.Cu")
	)
	(gr_circle
		(center 278.599646 -349.899732)
		(end 279.488646 -349.899732)
		(stroke
			(width 0.2)
			(type default)
		)
		(fill no)
		(layer "In3.Cu")
	)
	(gr_circle
		(center 279.133046 -350.255332)
		(end 280.022046 -350.255332)
		(stroke
			(width 0.2)
			(type default)
		)
		(fill no)
		(layer "In3.Cu")
	)
	(gr_circle
		(center 279.133046 -349.518732)
		(end 280.022046 -349.518732)
		(stroke
			(width 0.2)
			(type default)
		)
		(fill no)
		(layer "In3.Cu")
	)
	(gr_circle
		(center 279.133046 -348.782132)
		(end 280.022046 -348.782132)
		(stroke
			(width 0.2)
			(type default)
		)
		(fill no)
		(layer "In3.Cu")
	)
	(gr_line
		(start 279.415748 -397.461232)
		(end 280.36774 -398.413224)
		(stroke
			(width 0.635)
			(type default)
		)
		(layer "In3.Cu")
	)
	(gr_line
		(start 280.36774 -409.10256)
		(end 272.19021 -417.28009)
		(stroke
			(width 0.635)
			(type default)
		)
		(layer "In3.Cu")
	)
	(gr_line
		(start 280.36774 -398.413224)
		(end 280.36774 -409.10256)
		(stroke
			(width 0.635)
			(type default)
		)
		(layer "In3.Cu")
	)
	(gr_circle
		(center 284.393386 -348.704662)
		(end 285.273496 -348.704662)
		(stroke
			(width 0.2)
			(type default)
		)
		(fill no)
		(layer "In3.Cu")
	)
	(gr_circle
		(center 285.010606 -348.704662)
		(end 285.890716 -348.704662)
		(stroke
			(width 0.2)
			(type default)
		)
		(fill no)
		(layer "In3.Cu")
	)
	(gr_circle
		(center 285.627826 -348.704662)
		(end 286.507936 -348.704662)
		(stroke
			(width 0.2)
			(type default)
		)
		(fill no)
		(layer "In3.Cu")
	)
	(gr_circle
		(center 285.869126 -347.982032)
		(end 286.758126 -347.982032)
		(stroke
			(width 0.2)
			(type default)
		)
		(fill no)
		(layer "In3.Cu")
	)
	(gr_circle
		(center 285.869126 -347.245432)
		(end 286.758126 -347.245432)
		(stroke
			(width 0.2)
			(type default)
		)
		(fill no)
		(layer "In3.Cu")
	)
	(gr_circle
		(center 286.329882 -350.313752)
		(end 287.218882 -350.313752)
		(stroke
			(width 0.2)
			(type default)
		)
		(fill no)
		(layer "In3.Cu")
	)
	(gr_circle
		(center 286.329882 -349.577152)
		(end 287.218882 -349.577152)
		(stroke
			(width 0.2)
			(type default)
		)
		(fill no)
		(layer "In3.Cu")
	)
	(gr_circle
		(center 286.36595 -355.279198)
		(end 287.25495 -355.279198)
		(stroke
			(width 0.2)
			(type default)
		)
		(fill no)
		(layer "In3.Cu")
	)
	(gr_circle
		(center 286.37611 -356.584758)
		(end 287.26511 -356.584758)
		(stroke
			(width 0.2)
			(type default)
		)
		(fill no)
		(layer "In3.Cu")
	)
	(gr_circle
		(center 286.37611 -355.949758)
		(end 287.26511 -355.949758)
		(stroke
			(width 0.2)
			(type default)
		)
		(fill no)
		(layer "In3.Cu")
	)
	(gr_circle
		(center 286.854646 -349.137732)
		(end 287.743646 -349.137732)
		(stroke
			(width 0.2)
			(type default)
		)
		(fill no)
		(layer "In3.Cu")
	)
	(gr_circle
		(center 286.880046 -349.899732)
		(end 287.769046 -349.899732)
		(stroke
			(width 0.2)
			(type default)
		)
		(fill no)
		(layer "In3.Cu")
	)
	(gr_circle
		(center 287.00095 -355.279198)
		(end 287.88995 -355.279198)
		(stroke
			(width 0.2)
			(type default)
		)
		(fill no)
		(layer "In3.Cu")
	)
	(gr_circle
		(center 287.01111 -356.584758)
		(end 287.90011 -356.584758)
		(stroke
			(width 0.2)
			(type default)
		)
		(fill no)
		(layer "In3.Cu")
	)
	(gr_circle
		(center 287.01111 -355.949758)
		(end 287.90011 -355.949758)
		(stroke
			(width 0.2)
			(type default)
		)
		(fill no)
		(layer "In3.Cu")
	)
	(gr_circle
		(center 287.413446 -350.255332)
		(end 288.302446 -350.255332)
		(stroke
			(width 0.2)
			(type default)
		)
		(fill no)
		(layer "In3.Cu")
	)
	(gr_circle
		(center 287.413446 -349.518732)
		(end 288.302446 -349.518732)
		(stroke
			(width 0.2)
			(type default)
		)
		(fill no)
		(layer "In3.Cu")
	)
	(gr_circle
		(center 287.413446 -348.782132)
		(end 288.302446 -348.782132)
		(stroke
			(width 0.2)
			(type default)
		)
		(fill no)
		(layer "In3.Cu")
	)
	(gr_circle
		(center 287.63595 -355.279198)
		(end 288.52495 -355.279198)
		(stroke
			(width 0.2)
			(type default)
		)
		(fill no)
		(layer "In3.Cu")
	)
	(gr_circle
		(center 287.64611 -356.584758)
		(end 288.53511 -356.584758)
		(stroke
			(width 0.2)
			(type default)
		)
		(fill no)
		(layer "In3.Cu")
	)
	(gr_circle
		(center 287.64611 -355.949758)
		(end 288.53511 -355.949758)
		(stroke
			(width 0.2)
			(type default)
		)
		(fill no)
		(layer "In3.Cu")
	)
	(gr_circle
		(center 288.27095 -355.279198)
		(end 289.15995 -355.279198)
		(stroke
			(width 0.2)
			(type default)
		)
		(fill no)
		(layer "In3.Cu")
	)
	(gr_circle
		(center 288.28111 -356.584758)
		(end 289.17011 -356.584758)
		(stroke
			(width 0.2)
			(type default)
		)
		(fill no)
		(layer "In3.Cu")
	)
	(gr_circle
		(center 288.28111 -355.949758)
		(end 289.17011 -355.949758)
		(stroke
			(width 0.2)
			(type default)
		)
		(fill no)
		(layer "In3.Cu")
	)
	(gr_circle
		(center 288.90595 -355.279198)
		(end 289.79495 -355.279198)
		(stroke
			(width 0.2)
			(type default)
		)
		(fill no)
		(layer "In3.Cu")
	)
	(gr_circle
		(center 288.91611 -356.584758)
		(end 289.80511 -356.584758)
		(stroke
			(width 0.2)
			(type default)
		)
		(fill no)
		(layer "In3.Cu")
	)
	(gr_circle
		(center 288.91611 -355.949758)
		(end 289.80511 -355.949758)
		(stroke
			(width 0.2)
			(type default)
		)
		(fill no)
		(layer "In3.Cu")
	)
	(gr_circle
		(center 292.699186 -348.704662)
		(end 293.579296 -348.704662)
		(stroke
			(width 0.2)
			(type default)
		)
		(fill no)
		(layer "In3.Cu")
	)
	(gr_circle
		(center 293.316406 -348.704662)
		(end 294.196516 -348.704662)
		(stroke
			(width 0.2)
			(type default)
		)
		(fill no)
		(layer "In3.Cu")
	)
	(gr_circle
		(center 293.933626 -348.704662)
		(end 294.813736 -348.704662)
		(stroke
			(width 0.2)
			(type default)
		)
		(fill no)
		(layer "In3.Cu")
	)
	(gr_circle
		(center 294.146986 -347.959172)
		(end 295.035986 -347.959172)
		(stroke
			(width 0.2)
			(type default)
		)
		(fill no)
		(layer "In3.Cu")
	)
	(gr_circle
		(center 294.146986 -347.222572)
		(end 295.035986 -347.222572)
		(stroke
			(width 0.2)
			(type default)
		)
		(fill no)
		(layer "In3.Cu")
	)
	(gr_circle
		(center 294.635682 -350.313752)
		(end 295.524682 -350.313752)
		(stroke
			(width 0.2)
			(type default)
		)
		(fill no)
		(layer "In3.Cu")
	)
	(gr_circle
		(center 294.635682 -349.577152)
		(end 295.524682 -349.577152)
		(stroke
			(width 0.2)
			(type default)
		)
		(fill no)
		(layer "In3.Cu")
	)
	(gr_circle
		(center 295.160446 -349.137732)
		(end 296.049446 -349.137732)
		(stroke
			(width 0.2)
			(type default)
		)
		(fill no)
		(layer "In3.Cu")
	)
	(gr_circle
		(center 295.185846 -349.899732)
		(end 296.074846 -349.899732)
		(stroke
			(width 0.2)
			(type default)
		)
		(fill no)
		(layer "In3.Cu")
	)
	(gr_circle
		(center 295.719246 -350.255332)
		(end 296.608246 -350.255332)
		(stroke
			(width 0.2)
			(type default)
		)
		(fill no)
		(layer "In3.Cu")
	)
	(gr_circle
		(center 295.719246 -349.518732)
		(end 296.608246 -349.518732)
		(stroke
			(width 0.2)
			(type default)
		)
		(fill no)
		(layer "In3.Cu")
	)
	(gr_circle
		(center 295.719246 -348.782132)
		(end 296.608246 -348.782132)
		(stroke
			(width 0.2)
			(type default)
		)
		(fill no)
		(layer "In3.Cu")
	)
	(gr_circle
		(center 296.29989 -358.769666)
		(end 297.69689 -358.769666)
		(stroke
			(width 0.2)
			(type default)
		)
		(fill no)
		(layer "In3.Cu")
	)
	(gr_circle
		(center 301.055786 -348.704662)
		(end 301.935896 -348.704662)
		(stroke
			(width 0.2)
			(type default)
		)
		(fill no)
		(layer "In3.Cu")
	)
	(gr_circle
		(center 301.673006 -348.704662)
		(end 302.553116 -348.704662)
		(stroke
			(width 0.2)
			(type default)
		)
		(fill no)
		(layer "In3.Cu")
	)
	(gr_circle
		(center 302.290226 -348.704662)
		(end 303.170336 -348.704662)
		(stroke
			(width 0.2)
			(type default)
		)
		(fill no)
		(layer "In3.Cu")
	)
	(gr_circle
		(center 302.526446 -348.002352)
		(end 303.415446 -348.002352)
		(stroke
			(width 0.2)
			(type default)
		)
		(fill no)
		(layer "In3.Cu")
	)
	(gr_circle
		(center 302.526446 -347.265752)
		(end 303.415446 -347.265752)
		(stroke
			(width 0.2)
			(type default)
		)
		(fill no)
		(layer "In3.Cu")
	)
	(gr_circle
		(center 302.992282 -350.313752)
		(end 303.881282 -350.313752)
		(stroke
			(width 0.2)
			(type default)
		)
		(fill no)
		(layer "In3.Cu")
	)
	(gr_circle
		(center 302.992282 -349.577152)
		(end 303.881282 -349.577152)
		(stroke
			(width 0.2)
			(type default)
		)
		(fill no)
		(layer "In3.Cu")
	)
	(gr_circle
		(center 303.517046 -349.137732)
		(end 304.406046 -349.137732)
		(stroke
			(width 0.2)
			(type default)
		)
		(fill no)
		(layer "In3.Cu")
	)
	(gr_circle
		(center 303.542446 -349.899732)
		(end 304.431446 -349.899732)
		(stroke
			(width 0.2)
			(type default)
		)
		(fill no)
		(layer "In3.Cu")
	)
	(gr_circle
		(center 304.075846 -350.255332)
		(end 304.964846 -350.255332)
		(stroke
			(width 0.2)
			(type default)
		)
		(fill no)
		(layer "In3.Cu")
	)
	(gr_circle
		(center 304.075846 -349.518732)
		(end 304.964846 -349.518732)
		(stroke
			(width 0.2)
			(type default)
		)
		(fill no)
		(layer "In3.Cu")
	)
	(gr_circle
		(center 304.075846 -348.782132)
		(end 304.964846 -348.782132)
		(stroke
			(width 0.2)
			(type default)
		)
		(fill no)
		(layer "In3.Cu")
	)
	(gr_circle
		(center 309.386986 -348.704662)
		(end 310.267096 -348.704662)
		(stroke
			(width 0.2)
			(type default)
		)
		(fill no)
		(layer "In3.Cu")
	)
	(gr_circle
		(center 310.004206 -348.704662)
		(end 310.884316 -348.704662)
		(stroke
			(width 0.2)
			(type default)
		)
		(fill no)
		(layer "In3.Cu")
	)
	(gr_circle
		(center 310.621426 -348.704662)
		(end 311.501536 -348.704662)
		(stroke
			(width 0.2)
			(type default)
		)
		(fill no)
		(layer "In3.Cu")
	)
	(gr_circle
		(center 310.867806 -348.002352)
		(end 311.756806 -348.002352)
		(stroke
			(width 0.2)
			(type default)
		)
		(fill no)
		(layer "In3.Cu")
	)
	(gr_circle
		(center 310.867806 -347.265752)
		(end 311.756806 -347.265752)
		(stroke
			(width 0.2)
			(type default)
		)
		(fill no)
		(layer "In3.Cu")
	)
	(gr_circle
		(center 311.323482 -350.313752)
		(end 312.212482 -350.313752)
		(stroke
			(width 0.2)
			(type default)
		)
		(fill no)
		(layer "In3.Cu")
	)
	(gr_circle
		(center 311.323482 -349.577152)
		(end 312.212482 -349.577152)
		(stroke
			(width 0.2)
			(type default)
		)
		(fill no)
		(layer "In3.Cu")
	)
	(gr_circle
		(center 311.848246 -349.137732)
		(end 312.737246 -349.137732)
		(stroke
			(width 0.2)
			(type default)
		)
		(fill no)
		(layer "In3.Cu")
	)
	(gr_circle
		(center 311.873646 -349.899732)
		(end 312.762646 -349.899732)
		(stroke
			(width 0.2)
			(type default)
		)
		(fill no)
		(layer "In3.Cu")
	)
	(gr_circle
		(center 312.407046 -350.255332)
		(end 313.296046 -350.255332)
		(stroke
			(width 0.2)
			(type default)
		)
		(fill no)
		(layer "In3.Cu")
	)
	(gr_circle
		(center 312.407046 -349.518732)
		(end 313.296046 -349.518732)
		(stroke
			(width 0.2)
			(type default)
		)
		(fill no)
		(layer "In3.Cu")
	)
	(gr_circle
		(center 312.407046 -348.782132)
		(end 313.296046 -348.782132)
		(stroke
			(width 0.2)
			(type default)
		)
		(fill no)
		(layer "In3.Cu")
	)
	(gr_circle
		(center 319.0367 -336.983578)
		(end 319.91681 -336.983578)
		(stroke
			(width 0.2)
			(type default)
		)
		(fill no)
		(layer "In3.Cu")
	)
	(gr_circle
		(center 319.65392 -336.983578)
		(end 320.53403 -336.983578)
		(stroke
			(width 0.2)
			(type default)
		)
		(fill no)
		(layer "In3.Cu")
	)
	(gr_circle
		(center 320.27114 -336.983578)
		(end 321.15125 -336.983578)
		(stroke
			(width 0.2)
			(type default)
		)
		(fill no)
		(layer "In3.Cu")
	)
	(gr_circle
		(center 320.5607 -336.239612)
		(end 321.4497 -336.239612)
		(stroke
			(width 0.2)
			(type default)
		)
		(fill no)
		(layer "In3.Cu")
	)
	(gr_circle
		(center 320.5607 -335.503012)
		(end 321.4497 -335.503012)
		(stroke
			(width 0.2)
			(type default)
		)
		(fill no)
		(layer "In3.Cu")
	)
	(gr_circle
		(center 320.973196 -338.592668)
		(end 321.862196 -338.592668)
		(stroke
			(width 0.2)
			(type default)
		)
		(fill no)
		(layer "In3.Cu")
	)
	(gr_circle
		(center 320.973196 -337.856068)
		(end 321.862196 -337.856068)
		(stroke
			(width 0.2)
			(type default)
		)
		(fill no)
		(layer "In3.Cu")
	)
	(gr_circle
		(center 321.49796 -337.416648)
		(end 322.38696 -337.416648)
		(stroke
			(width 0.2)
			(type default)
		)
		(fill no)
		(layer "In3.Cu")
	)
	(gr_circle
		(center 321.52336 -338.178648)
		(end 322.41236 -338.178648)
		(stroke
			(width 0.2)
			(type default)
		)
		(fill no)
		(layer "In3.Cu")
	)
	(gr_circle
		(center 322.05676 -338.534248)
		(end 322.94576 -338.534248)
		(stroke
			(width 0.2)
			(type default)
		)
		(fill no)
		(layer "In3.Cu")
	)
	(gr_circle
		(center 322.05676 -337.797648)
		(end 322.94576 -337.797648)
		(stroke
			(width 0.2)
			(type default)
		)
		(fill no)
		(layer "In3.Cu")
	)
	(gr_circle
		(center 322.05676 -337.061048)
		(end 322.94576 -337.061048)
		(stroke
			(width 0.2)
			(type default)
		)
		(fill no)
		(layer "In3.Cu")
	)
	(gr_circle
		(center 327.392284 -336.976466)
		(end 328.272394 -336.976466)
		(stroke
			(width 0.2)
			(type default)
		)
		(fill no)
		(layer "In3.Cu")
	)
	(gr_circle
		(center 327.692258 -104.30129)
		(end 328.581258 -104.30129)
		(stroke
			(width 0.2)
			(type default)
		)
		(fill no)
		(layer "In3.Cu")
	)
	(gr_circle
		(center 327.951084 -349.43161)
		(end 329.348084 -349.43161)
		(stroke
			(width 0.2)
			(type default)
		)
		(fill no)
		(layer "In3.Cu")
	)
	(gr_circle
		(center 328.009504 -336.976466)
		(end 328.889614 -336.976466)
		(stroke
			(width 0.2)
			(type default)
		)
		(fill no)
		(layer "In3.Cu")
	)
	(gr_circle
		(center 328.626724 -336.976466)
		(end 329.506834 -336.976466)
		(stroke
			(width 0.2)
			(type default)
		)
		(fill no)
		(layer "In3.Cu")
	)
	(gr_circle
		(center 328.918824 -336.253836)
		(end 329.807824 -336.253836)
		(stroke
			(width 0.2)
			(type default)
		)
		(fill no)
		(layer "In3.Cu")
	)
	(gr_circle
		(center 328.918824 -335.517236)
		(end 329.807824 -335.517236)
		(stroke
			(width 0.2)
			(type default)
		)
		(fill no)
		(layer "In3.Cu")
	)
	(gr_circle
		(center 329.32878 -338.585556)
		(end 330.21778 -338.585556)
		(stroke
			(width 0.2)
			(type default)
		)
		(fill no)
		(layer "In3.Cu")
	)
	(gr_circle
		(center 329.32878 -337.848956)
		(end 330.21778 -337.848956)
		(stroke
			(width 0.2)
			(type default)
		)
		(fill no)
		(layer "In3.Cu")
	)
	(gr_circle
		(center 329.853544 -337.409536)
		(end 330.742544 -337.409536)
		(stroke
			(width 0.2)
			(type default)
		)
		(fill no)
		(layer "In3.Cu")
	)
	(gr_circle
		(center 329.878944 -338.171536)
		(end 330.767944 -338.171536)
		(stroke
			(width 0.2)
			(type default)
		)
		(fill no)
		(layer "In3.Cu")
	)
	(gr_circle
		(center 330.412344 -338.527136)
		(end 331.301344 -338.527136)
		(stroke
			(width 0.2)
			(type default)
		)
		(fill no)
		(layer "In3.Cu")
	)
	(gr_circle
		(center 330.412344 -337.790536)
		(end 331.301344 -337.790536)
		(stroke
			(width 0.2)
			(type default)
		)
		(fill no)
		(layer "In3.Cu")
	)
	(gr_circle
		(center 330.412344 -337.053936)
		(end 331.301344 -337.053936)
		(stroke
			(width 0.2)
			(type default)
		)
		(fill no)
		(layer "In3.Cu")
	)
	(gr_circle
		(center 335.411064 -349.43161)
		(end 336.808064 -349.43161)
		(stroke
			(width 0.2)
			(type default)
		)
		(fill no)
		(layer "In3.Cu")
	)
	(gr_circle
		(center 335.7499 -336.961988)
		(end 336.63001 -336.961988)
		(stroke
			(width 0.2)
			(type default)
		)
		(fill no)
		(layer "In3.Cu")
	)
	(gr_circle
		(center 336.36712 -336.961988)
		(end 337.24723 -336.961988)
		(stroke
			(width 0.2)
			(type default)
		)
		(fill no)
		(layer "In3.Cu")
	)
	(gr_circle
		(center 336.98434 -336.961988)
		(end 337.86445 -336.961988)
		(stroke
			(width 0.2)
			(type default)
		)
		(fill no)
		(layer "In3.Cu")
	)
	(gr_circle
		(center 337.280504 -336.253836)
		(end 338.169504 -336.253836)
		(stroke
			(width 0.2)
			(type default)
		)
		(fill no)
		(layer "In3.Cu")
	)
	(gr_circle
		(center 337.280504 -335.517236)
		(end 338.169504 -335.517236)
		(stroke
			(width 0.2)
			(type default)
		)
		(fill no)
		(layer "In3.Cu")
	)
	(gr_circle
		(center 337.686396 -338.571078)
		(end 338.575396 -338.571078)
		(stroke
			(width 0.2)
			(type default)
		)
		(fill no)
		(layer "In3.Cu")
	)
	(gr_circle
		(center 337.686396 -337.834478)
		(end 338.575396 -337.834478)
		(stroke
			(width 0.2)
			(type default)
		)
		(fill no)
		(layer "In3.Cu")
	)
	(gr_circle
		(center 338.21116 -337.395058)
		(end 339.10016 -337.395058)
		(stroke
			(width 0.2)
			(type default)
		)
		(fill no)
		(layer "In3.Cu")
	)
	(gr_circle
		(center 338.23656 -338.157058)
		(end 339.12556 -338.157058)
		(stroke
			(width 0.2)
			(type default)
		)
		(fill no)
		(layer "In3.Cu")
	)
	(gr_circle
		(center 338.76996 -338.512658)
		(end 339.65896 -338.512658)
		(stroke
			(width 0.2)
			(type default)
		)
		(fill no)
		(layer "In3.Cu")
	)
	(gr_circle
		(center 338.76996 -337.776058)
		(end 339.65896 -337.776058)
		(stroke
			(width 0.2)
			(type default)
		)
		(fill no)
		(layer "In3.Cu")
	)
	(gr_circle
		(center 338.76996 -337.039458)
		(end 339.65896 -337.039458)
		(stroke
			(width 0.2)
			(type default)
		)
		(fill no)
		(layer "In3.Cu")
	)
	(gr_circle
		(center 339.73897 -352.973132)
		(end 340.62797 -352.973132)
		(stroke
			(width 0.2)
			(type default)
		)
		(fill no)
		(layer "In3.Cu")
	)
	(gr_circle
		(center 339.739224 -352.215196)
		(end 340.628224 -352.215196)
		(stroke
			(width 0.2)
			(type default)
		)
		(fill no)
		(layer "In3.Cu")
	)
	(gr_circle
		(center 339.739224 -351.453196)
		(end 340.628224 -351.453196)
		(stroke
			(width 0.2)
			(type default)
		)
		(fill no)
		(layer "In3.Cu")
	)
	(gr_circle
		(center 340.501224 -352.215196)
		(end 341.390224 -352.215196)
		(stroke
			(width 0.2)
			(type default)
		)
		(fill no)
		(layer "In3.Cu")
	)
	(gr_circle
		(center 340.501224 -351.453196)
		(end 341.390224 -351.453196)
		(stroke
			(width 0.2)
			(type default)
		)
		(fill no)
		(layer "In3.Cu")
	)
	(gr_circle
		(center 340.667848 -353.010216)
		(end 341.556848 -353.010216)
		(stroke
			(width 0.2)
			(type default)
		)
		(fill no)
		(layer "In3.Cu")
	)
	(gr_circle
		(center 341.263224 -352.215196)
		(end 342.152224 -352.215196)
		(stroke
			(width 0.2)
			(type default)
		)
		(fill no)
		(layer "In3.Cu")
	)
	(gr_circle
		(center 341.263224 -351.453196)
		(end 342.152224 -351.453196)
		(stroke
			(width 0.2)
			(type default)
		)
		(fill no)
		(layer "In3.Cu")
	)
	(gr_circle
		(center 341.302848 -353.010216)
		(end 342.191848 -353.010216)
		(stroke
			(width 0.2)
			(type default)
		)
		(fill no)
		(layer "In3.Cu")
	)
	(gr_circle
		(center 341.937848 -353.010216)
		(end 342.826848 -353.010216)
		(stroke
			(width 0.2)
			(type default)
		)
		(fill no)
		(layer "In3.Cu")
	)
	(gr_circle
		(center 342.025224 -352.215196)
		(end 342.914224 -352.215196)
		(stroke
			(width 0.2)
			(type default)
		)
		(fill no)
		(layer "In3.Cu")
	)
	(gr_circle
		(center 342.025224 -351.453196)
		(end 342.914224 -351.453196)
		(stroke
			(width 0.2)
			(type default)
		)
		(fill no)
		(layer "In3.Cu")
	)
	(gr_circle
		(center 342.572848 -353.010216)
		(end 343.461848 -353.010216)
		(stroke
			(width 0.2)
			(type default)
		)
		(fill no)
		(layer "In3.Cu")
	)
	(gr_circle
		(center 342.787224 -352.215196)
		(end 343.676224 -352.215196)
		(stroke
			(width 0.2)
			(type default)
		)
		(fill no)
		(layer "In3.Cu")
	)
	(gr_circle
		(center 342.787224 -351.453196)
		(end 343.676224 -351.453196)
		(stroke
			(width 0.2)
			(type default)
		)
		(fill no)
		(layer "In3.Cu")
	)
	(gr_circle
		(center 343.46515 -353.006152)
		(end 344.35415 -353.006152)
		(stroke
			(width 0.2)
			(type default)
		)
		(fill no)
		(layer "In3.Cu")
	)
	(gr_circle
		(center 343.465404 -352.248216)
		(end 344.354404 -352.248216)
		(stroke
			(width 0.2)
			(type default)
		)
		(fill no)
		(layer "In3.Cu")
	)
	(gr_circle
		(center 343.465404 -351.486216)
		(end 344.354404 -351.486216)
		(stroke
			(width 0.2)
			(type default)
		)
		(fill no)
		(layer "In3.Cu")
	)
	(gr_circle
		(center 344.016838 -159.073596)
		(end 344.905838 -159.073596)
		(stroke
			(width 0.2)
			(type default)
		)
		(fill no)
		(layer "In3.Cu")
	)
	(gr_circle
		(center 344.016838 -158.336996)
		(end 344.905838 -158.336996)
		(stroke
			(width 0.2)
			(type default)
		)
		(fill no)
		(layer "In3.Cu")
	)
	(gr_circle
		(center 344.016838 -157.600396)
		(end 344.905838 -157.600396)
		(stroke
			(width 0.2)
			(type default)
		)
		(fill no)
		(layer "In3.Cu")
	)
	(gr_circle
		(center 344.0811 -337.012788)
		(end 344.96121 -337.012788)
		(stroke
			(width 0.2)
			(type default)
		)
		(fill no)
		(layer "In3.Cu")
	)
	(gr_circle
		(center 344.550238 -157.955996)
		(end 345.439238 -157.955996)
		(stroke
			(width 0.2)
			(type default)
		)
		(fill no)
		(layer "In3.Cu")
	)
	(gr_circle
		(center 344.575638 -158.717996)
		(end 345.464638 -158.717996)
		(stroke
			(width 0.2)
			(type default)
		)
		(fill no)
		(layer "In3.Cu")
	)
	(gr_circle
		(center 344.69832 -337.012788)
		(end 345.57843 -337.012788)
		(stroke
			(width 0.2)
			(type default)
		)
		(fill no)
		(layer "In3.Cu")
	)
	(gr_circle
		(center 345.100402 -158.278576)
		(end 345.989402 -158.278576)
		(stroke
			(width 0.2)
			(type default)
		)
		(fill no)
		(layer "In3.Cu")
	)
	(gr_circle
		(center 345.100402 -157.541976)
		(end 345.989402 -157.541976)
		(stroke
			(width 0.2)
			(type default)
		)
		(fill no)
		(layer "In3.Cu")
	)
	(gr_circle
		(center 345.31554 -337.012788)
		(end 346.19565 -337.012788)
		(stroke
			(width 0.2)
			(type default)
		)
		(fill no)
		(layer "In3.Cu")
	)
	(gr_circle
		(center 345.623896 -336.317336)
		(end 346.512896 -336.317336)
		(stroke
			(width 0.2)
			(type default)
		)
		(fill no)
		(layer "In3.Cu")
	)
	(gr_circle
		(center 345.623896 -335.580736)
		(end 346.512896 -335.580736)
		(stroke
			(width 0.2)
			(type default)
		)
		(fill no)
		(layer "In3.Cu")
	)
	(gr_circle
		(center 345.684856 -160.633156)
		(end 346.573856 -160.633156)
		(stroke
			(width 0.2)
			(type default)
		)
		(fill no)
		(layer "In3.Cu")
	)
	(gr_circle
		(center 345.684856 -159.896556)
		(end 346.573856 -159.896556)
		(stroke
			(width 0.2)
			(type default)
		)
		(fill no)
		(layer "In3.Cu")
	)
	(gr_circle
		(center 345.802458 -159.151066)
		(end 346.682568 -159.151066)
		(stroke
			(width 0.2)
			(type default)
		)
		(fill no)
		(layer "In3.Cu")
	)
	(gr_circle
		(center 346.017596 -339.358478)
		(end 346.906596 -339.358478)
		(stroke
			(width 0.2)
			(type default)
		)
		(fill no)
		(layer "In3.Cu")
	)
	(gr_circle
		(center 346.017596 -338.621878)
		(end 346.906596 -338.621878)
		(stroke
			(width 0.2)
			(type default)
		)
		(fill no)
		(layer "In3.Cu")
	)
	(gr_circle
		(center 346.017596 -337.885278)
		(end 346.906596 -337.885278)
		(stroke
			(width 0.2)
			(type default)
		)
		(fill no)
		(layer "In3.Cu")
	)
	(gr_circle
		(center 346.419678 -159.151066)
		(end 347.299788 -159.151066)
		(stroke
			(width 0.2)
			(type default)
		)
		(fill no)
		(layer "In3.Cu")
	)
	(gr_circle
		(center 346.54236 -337.445858)
		(end 347.43136 -337.445858)
		(stroke
			(width 0.2)
			(type default)
		)
		(fill no)
		(layer "In3.Cu")
	)
	(gr_circle
		(center 346.56776 -339.731858)
		(end 347.45676 -339.731858)
		(stroke
			(width 0.2)
			(type default)
		)
		(fill no)
		(layer "In3.Cu")
	)
	(gr_circle
		(center 346.56776 -338.969858)
		(end 347.45676 -338.969858)
		(stroke
			(width 0.2)
			(type default)
		)
		(fill no)
		(layer "In3.Cu")
	)
	(gr_circle
		(center 346.56776 -338.207858)
		(end 347.45676 -338.207858)
		(stroke
			(width 0.2)
			(type default)
		)
		(fill no)
		(layer "In3.Cu")
	)
	(gr_circle
		(center 347.036898 -159.151066)
		(end 347.917008 -159.151066)
		(stroke
			(width 0.2)
			(type default)
		)
		(fill no)
		(layer "In3.Cu")
	)
	(gr_circle
		(center 352.322638 -167.430196)
		(end 353.211638 -167.430196)
		(stroke
			(width 0.2)
			(type default)
		)
		(fill no)
		(layer "In3.Cu")
	)
	(gr_circle
		(center 352.322638 -166.693596)
		(end 353.211638 -166.693596)
		(stroke
			(width 0.2)
			(type default)
		)
		(fill no)
		(layer "In3.Cu")
	)
	(gr_circle
		(center 352.322638 -165.956996)
		(end 353.211638 -165.956996)
		(stroke
			(width 0.2)
			(type default)
		)
		(fill no)
		(layer "In3.Cu")
	)
	(gr_circle
		(center 352.356928 -341.922862)
		(end 353.237038 -341.922862)
		(stroke
			(width 0.2)
			(type default)
		)
		(fill no)
		(layer "In3.Cu")
	)
	(gr_circle
		(center 352.856038 -166.312596)
		(end 353.745038 -166.312596)
		(stroke
			(width 0.2)
			(type default)
		)
		(fill no)
		(layer "In3.Cu")
	)
	(gr_circle
		(center 352.881438 -167.074596)
		(end 353.770438 -167.074596)
		(stroke
			(width 0.2)
			(type default)
		)
		(fill no)
		(layer "In3.Cu")
	)
	(gr_circle
		(center 352.974148 -341.922862)
		(end 353.854258 -341.922862)
		(stroke
			(width 0.2)
			(type default)
		)
		(fill no)
		(layer "In3.Cu")
	)
	(gr_circle
		(center 353.406202 -166.635176)
		(end 354.295202 -166.635176)
		(stroke
			(width 0.2)
			(type default)
		)
		(fill no)
		(layer "In3.Cu")
	)
	(gr_circle
		(center 353.406202 -165.898576)
		(end 354.295202 -165.898576)
		(stroke
			(width 0.2)
			(type default)
		)
		(fill no)
		(layer "In3.Cu")
	)
	(gr_circle
		(center 353.591368 -341.922862)
		(end 354.471478 -341.922862)
		(stroke
			(width 0.2)
			(type default)
		)
		(fill no)
		(layer "In3.Cu")
	)
	(gr_circle
		(center 353.899724 -341.22741)
		(end 354.788724 -341.22741)
		(stroke
			(width 0.2)
			(type default)
		)
		(fill no)
		(layer "In3.Cu")
	)
	(gr_circle
		(center 353.899724 -340.49081)
		(end 354.788724 -340.49081)
		(stroke
			(width 0.2)
			(type default)
		)
		(fill no)
		(layer "In3.Cu")
	)
	(gr_circle
		(center 353.990656 -168.982136)
		(end 354.879656 -168.982136)
		(stroke
			(width 0.2)
			(type default)
		)
		(fill no)
		(layer "In3.Cu")
	)
	(gr_circle
		(center 353.990656 -168.245536)
		(end 354.879656 -168.245536)
		(stroke
			(width 0.2)
			(type default)
		)
		(fill no)
		(layer "In3.Cu")
	)
	(gr_circle
		(center 354.108258 -167.507666)
		(end 354.988368 -167.507666)
		(stroke
			(width 0.2)
			(type default)
		)
		(fill no)
		(layer "In3.Cu")
	)
	(gr_circle
		(center 354.293424 -343.531952)
		(end 355.182424 -343.531952)
		(stroke
			(width 0.2)
			(type default)
		)
		(fill no)
		(layer "In3.Cu")
	)
	(gr_circle
		(center 354.293424 -342.795352)
		(end 355.182424 -342.795352)
		(stroke
			(width 0.2)
			(type default)
		)
		(fill no)
		(layer "In3.Cu")
	)
	(gr_circle
		(center 354.725478 -167.507666)
		(end 355.605588 -167.507666)
		(stroke
			(width 0.2)
			(type default)
		)
		(fill no)
		(layer "In3.Cu")
	)
	(gr_circle
		(center 354.818188 -342.355932)
		(end 355.707188 -342.355932)
		(stroke
			(width 0.2)
			(type default)
		)
		(fill no)
		(layer "In3.Cu")
	)
	(gr_circle
		(center 354.843588 -343.117932)
		(end 355.732588 -343.117932)
		(stroke
			(width 0.2)
			(type default)
		)
		(fill no)
		(layer "In3.Cu")
	)
	(gr_circle
		(center 355.342698 -167.507666)
		(end 356.222808 -167.507666)
		(stroke
			(width 0.2)
			(type default)
		)
		(fill no)
		(layer "In3.Cu")
	)
	(gr_circle
		(center 355.376988 -343.473532)
		(end 356.265988 -343.473532)
		(stroke
			(width 0.2)
			(type default)
		)
		(fill no)
		(layer "In3.Cu")
	)
	(gr_circle
		(center 355.376988 -342.736932)
		(end 356.265988 -342.736932)
		(stroke
			(width 0.2)
			(type default)
		)
		(fill no)
		(layer "In3.Cu")
	)
	(gr_circle
		(center 355.376988 -342.000332)
		(end 356.265988 -342.000332)
		(stroke
			(width 0.2)
			(type default)
		)
		(fill no)
		(layer "In3.Cu")
	)
	(gr_circle
		(center 359.58526 -152.71242)
		(end 360.98226 -152.71242)
		(stroke
			(width 0.2)
			(type default)
		)
		(fill no)
		(layer "In3.Cu")
	)
	(gr_circle
		(center 360.603038 -175.705516)
		(end 361.492038 -175.705516)
		(stroke
			(width 0.2)
			(type default)
		)
		(fill no)
		(layer "In3.Cu")
	)
	(gr_circle
		(center 360.603038 -174.968916)
		(end 361.492038 -174.968916)
		(stroke
			(width 0.2)
			(type default)
		)
		(fill no)
		(layer "In3.Cu")
	)
	(gr_circle
		(center 360.603038 -174.232316)
		(end 361.492038 -174.232316)
		(stroke
			(width 0.2)
			(type default)
		)
		(fill no)
		(layer "In3.Cu")
	)
	(gr_circle
		(center 361.136438 -174.587916)
		(end 362.025438 -174.587916)
		(stroke
			(width 0.2)
			(type default)
		)
		(fill no)
		(layer "In3.Cu")
	)
	(gr_circle
		(center 361.161838 -175.349916)
		(end 362.050838 -175.349916)
		(stroke
			(width 0.2)
			(type default)
		)
		(fill no)
		(layer "In3.Cu")
	)
	(gr_circle
		(center 361.686602 -174.910496)
		(end 362.575602 -174.910496)
		(stroke
			(width 0.2)
			(type default)
		)
		(fill no)
		(layer "In3.Cu")
	)
	(gr_circle
		(center 361.686602 -174.173896)
		(end 362.575602 -174.173896)
		(stroke
			(width 0.2)
			(type default)
		)
		(fill no)
		(layer "In3.Cu")
	)
	(gr_circle
		(center 362.271056 -177.254916)
		(end 363.160056 -177.254916)
		(stroke
			(width 0.2)
			(type default)
		)
		(fill no)
		(layer "In3.Cu")
	)
	(gr_circle
		(center 362.271056 -176.518316)
		(end 363.160056 -176.518316)
		(stroke
			(width 0.2)
			(type default)
		)
		(fill no)
		(layer "In3.Cu")
	)
	(gr_circle
		(center 362.396278 -175.859186)
		(end 363.276388 -175.859186)
		(stroke
			(width 0.2)
			(type default)
		)
		(fill no)
		(layer "In3.Cu")
	)
	(gr_circle
		(center 363.013498 -175.859186)
		(end 363.893608 -175.859186)
		(stroke
			(width 0.2)
			(type default)
		)
		(fill no)
		(layer "In3.Cu")
	)
	(gr_circle
		(center 363.630718 -175.859186)
		(end 364.510828 -175.859186)
		(stroke
			(width 0.2)
			(type default)
		)
		(fill no)
		(layer "In3.Cu")
	)
	(gr_circle
		(center 366.744504 -164.53358)
		(end 367.633504 -164.53358)
		(stroke
			(width 0.2)
			(type default)
		)
		(fill no)
		(layer "In3.Cu")
	)
	(gr_circle
		(center 366.744504 -163.89858)
		(end 367.633504 -163.89858)
		(stroke
			(width 0.2)
			(type default)
		)
		(fill no)
		(layer "In3.Cu")
	)
	(gr_circle
		(center 366.757204 -165.19398)
		(end 367.646204 -165.19398)
		(stroke
			(width 0.2)
			(type default)
		)
		(fill no)
		(layer "In3.Cu")
	)
	(gr_circle
		(center 367.379504 -164.53358)
		(end 368.268504 -164.53358)
		(stroke
			(width 0.2)
			(type default)
		)
		(fill no)
		(layer "In3.Cu")
	)
	(gr_circle
		(center 367.379504 -163.89858)
		(end 368.268504 -163.89858)
		(stroke
			(width 0.2)
			(type default)
		)
		(fill no)
		(layer "In3.Cu")
	)
	(gr_circle
		(center 367.392204 -165.19398)
		(end 368.281204 -165.19398)
		(stroke
			(width 0.2)
			(type default)
		)
		(fill no)
		(layer "In3.Cu")
	)
	(gr_circle
		(center 368.044984 -164.53358)
		(end 368.933984 -164.53358)
		(stroke
			(width 0.2)
			(type default)
		)
		(fill no)
		(layer "In3.Cu")
	)
	(gr_circle
		(center 368.044984 -163.89858)
		(end 368.933984 -163.89858)
		(stroke
			(width 0.2)
			(type default)
		)
		(fill no)
		(layer "In3.Cu")
	)
	(gr_circle
		(center 368.057684 -165.19398)
		(end 368.946684 -165.19398)
		(stroke
			(width 0.2)
			(type default)
		)
		(fill no)
		(layer "In3.Cu")
	)
	(gr_circle
		(center 368.679984 -164.53358)
		(end 369.568984 -164.53358)
		(stroke
			(width 0.2)
			(type default)
		)
		(fill no)
		(layer "In3.Cu")
	)
	(gr_circle
		(center 368.679984 -163.89858)
		(end 369.568984 -163.89858)
		(stroke
			(width 0.2)
			(type default)
		)
		(fill no)
		(layer "In3.Cu")
	)
	(gr_circle
		(center 368.692684 -165.19398)
		(end 369.581684 -165.19398)
		(stroke
			(width 0.2)
			(type default)
		)
		(fill no)
		(layer "In3.Cu")
	)
	(gr_circle
		(center 368.96421 -179.204874)
		(end 369.85321 -179.204874)
		(stroke
			(width 0.2)
			(type default)
		)
		(fill no)
		(layer "In3.Cu")
	)
	(gr_circle
		(center 369.314984 -164.53358)
		(end 370.203984 -164.53358)
		(stroke
			(width 0.2)
			(type default)
		)
		(fill no)
		(layer "In3.Cu")
	)
	(gr_circle
		(center 369.314984 -163.89858)
		(end 370.203984 -163.89858)
		(stroke
			(width 0.2)
			(type default)
		)
		(fill no)
		(layer "In3.Cu")
	)
	(gr_circle
		(center 369.327684 -165.19398)
		(end 370.216684 -165.19398)
		(stroke
			(width 0.2)
			(type default)
		)
		(fill no)
		(layer "In3.Cu")
	)
	(gr_circle
		(center 369.49761 -179.560474)
		(end 370.38661 -179.560474)
		(stroke
			(width 0.2)
			(type default)
		)
		(fill no)
		(layer "In3.Cu")
	)
	(gr_circle
		(center 369.49761 -178.798474)
		(end 370.38661 -178.798474)
		(stroke
			(width 0.2)
			(type default)
		)
		(fill no)
		(layer "In3.Cu")
	)
	(gr_circle
		(center 369.49761 -178.036474)
		(end 370.38661 -178.036474)
		(stroke
			(width 0.2)
			(type default)
		)
		(fill no)
		(layer "In3.Cu")
	)
	(gr_circle
		(center 369.52301 -180.322474)
		(end 370.41201 -180.322474)
		(stroke
			(width 0.2)
			(type default)
		)
		(fill no)
		(layer "In3.Cu")
	)
	(gr_circle
		(center 369.949984 -164.53358)
		(end 370.838984 -164.53358)
		(stroke
			(width 0.2)
			(type default)
		)
		(fill no)
		(layer "In3.Cu")
	)
	(gr_circle
		(center 369.949984 -163.89858)
		(end 370.838984 -163.89858)
		(stroke
			(width 0.2)
			(type default)
		)
		(fill no)
		(layer "In3.Cu")
	)
	(gr_circle
		(center 369.962684 -165.19398)
		(end 370.851684 -165.19398)
		(stroke
			(width 0.2)
			(type default)
		)
		(fill no)
		(layer "In3.Cu")
	)
	(gr_circle
		(center 370.047774 -179.883054)
		(end 370.936774 -179.883054)
		(stroke
			(width 0.2)
			(type default)
		)
		(fill no)
		(layer "In3.Cu")
	)
	(gr_circle
		(center 370.047774 -179.146454)
		(end 370.936774 -179.146454)
		(stroke
			(width 0.2)
			(type default)
		)
		(fill no)
		(layer "In3.Cu")
	)
	(gr_circle
		(center 370.529358 -182.141876)
		(end 371.418358 -182.141876)
		(stroke
			(width 0.2)
			(type default)
		)
		(fill no)
		(layer "In3.Cu")
	)
	(gr_circle
		(center 370.529358 -181.405276)
		(end 371.418358 -181.405276)
		(stroke
			(width 0.2)
			(type default)
		)
		(fill no)
		(layer "In3.Cu")
	)
	(gr_circle
		(center 370.686584 -164.53358)
		(end 371.575584 -164.53358)
		(stroke
			(width 0.2)
			(type default)
		)
		(fill no)
		(layer "In3.Cu")
	)
	(gr_circle
		(center 370.686584 -163.89858)
		(end 371.575584 -163.89858)
		(stroke
			(width 0.2)
			(type default)
		)
		(fill no)
		(layer "In3.Cu")
	)
	(gr_circle
		(center 370.699284 -165.19398)
		(end 371.588284 -165.19398)
		(stroke
			(width 0.2)
			(type default)
		)
		(fill no)
		(layer "In3.Cu")
	)
	(gr_circle
		(center 370.74221 -180.803804)
		(end 371.62232 -180.803804)
		(stroke
			(width 0.2)
			(type default)
		)
		(fill no)
		(layer "In3.Cu")
	)
	(gr_circle
		(center 371.35943 -180.803804)
		(end 372.23954 -180.803804)
		(stroke
			(width 0.2)
			(type default)
		)
		(fill no)
		(layer "In3.Cu")
	)
	(gr_circle
		(center 371.97665 -180.803804)
		(end 372.85676 -180.803804)
		(stroke
			(width 0.2)
			(type default)
		)
		(fill no)
		(layer "In3.Cu")
	)
	(gr_circle
		(center 377.367038 -180.678074)
		(end 378.256038 -180.678074)
		(stroke
			(width 0.2)
			(type default)
		)
		(fill no)
		(layer "In3.Cu")
	)
	(gr_circle
		(center 377.367038 -179.941474)
		(end 378.256038 -179.941474)
		(stroke
			(width 0.2)
			(type default)
		)
		(fill no)
		(layer "In3.Cu")
	)
	(gr_circle
		(center 377.367038 -179.204874)
		(end 378.256038 -179.204874)
		(stroke
			(width 0.2)
			(type default)
		)
		(fill no)
		(layer "In3.Cu")
	)
	(gr_circle
		(center 377.869958 -162.59683)
		(end 379.266958 -162.59683)
		(stroke
			(width 0.2)
			(type default)
		)
		(fill no)
		(layer "In3.Cu")
	)
	(gr_circle
		(center 377.900438 -179.560474)
		(end 378.789438 -179.560474)
		(stroke
			(width 0.2)
			(type default)
		)
		(fill no)
		(layer "In3.Cu")
	)
	(gr_circle
		(center 377.925838 -180.322474)
		(end 378.814838 -180.322474)
		(stroke
			(width 0.2)
			(type default)
		)
		(fill no)
		(layer "In3.Cu")
	)
	(gr_circle
		(center 378.450602 -179.883054)
		(end 379.339602 -179.883054)
		(stroke
			(width 0.2)
			(type default)
		)
		(fill no)
		(layer "In3.Cu")
	)
	(gr_circle
		(center 378.450602 -179.146454)
		(end 379.339602 -179.146454)
		(stroke
			(width 0.2)
			(type default)
		)
		(fill no)
		(layer "In3.Cu")
	)
	(gr_circle
		(center 379.035056 -182.230776)
		(end 379.924056 -182.230776)
		(stroke
			(width 0.2)
			(type default)
		)
		(fill no)
		(layer "In3.Cu")
	)
	(gr_circle
		(center 379.035056 -181.494176)
		(end 379.924056 -181.494176)
		(stroke
			(width 0.2)
			(type default)
		)
		(fill no)
		(layer "In3.Cu")
	)
	(gr_circle
		(center 379.152658 -180.755544)
		(end 380.032768 -180.755544)
		(stroke
			(width 0.2)
			(type default)
		)
		(fill no)
		(layer "In3.Cu")
	)
	(gr_circle
		(center 379.769878 -180.755544)
		(end 380.649988 -180.755544)
		(stroke
			(width 0.2)
			(type default)
		)
		(fill no)
		(layer "In3.Cu")
	)
	(gr_circle
		(center 380.387098 -180.755544)
		(end 381.267208 -180.755544)
		(stroke
			(width 0.2)
			(type default)
		)
		(fill no)
		(layer "In3.Cu")
	)
	(gr_arc
		(start 385.601972 -11.780012)
		(mid 387.016183 -11.194227)
		(end 387.601968 -9.780016)
		(stroke
			(width 1.016)
			(type default)
		)
		(layer "In3.Cu")
	)
	(gr_circle
		(center 385.698238 -180.678074)
		(end 386.587238 -180.678074)
		(stroke
			(width 0.2)
			(type default)
		)
		(fill no)
		(layer "In3.Cu")
	)
	(gr_circle
		(center 385.698238 -179.941474)
		(end 386.587238 -179.941474)
		(stroke
			(width 0.2)
			(type default)
		)
		(fill no)
		(layer "In3.Cu")
	)
	(gr_circle
		(center 385.698238 -179.204874)
		(end 386.587238 -179.204874)
		(stroke
			(width 0.2)
			(type default)
		)
		(fill no)
		(layer "In3.Cu")
	)
	(gr_circle
		(center 386.231638 -179.560474)
		(end 387.120638 -179.560474)
		(stroke
			(width 0.2)
			(type default)
		)
		(fill no)
		(layer "In3.Cu")
	)
	(gr_circle
		(center 386.257038 -180.322474)
		(end 387.146038 -180.322474)
		(stroke
			(width 0.2)
			(type default)
		)
		(fill no)
		(layer "In3.Cu")
	)
	(gr_circle
		(center 386.781802 -179.883054)
		(end 387.670802 -179.883054)
		(stroke
			(width 0.2)
			(type default)
		)
		(fill no)
		(layer "In3.Cu")
	)
	(gr_circle
		(center 386.781802 -179.146454)
		(end 387.670802 -179.146454)
		(stroke
			(width 0.2)
			(type default)
		)
		(fill no)
		(layer "In3.Cu")
	)
	(gr_circle
		(center 387.206998 -162.65271)
		(end 388.603998 -162.65271)
		(stroke
			(width 0.2)
			(type default)
		)
		(fill no)
		(layer "In3.Cu")
	)
	(gr_circle
		(center 387.293358 -157.001972)
		(end 388.182358 -157.001972)
		(stroke
			(width 0.2)
			(type default)
		)
		(fill no)
		(layer "In3.Cu")
	)
	(gr_circle
		(center 387.293358 -156.366972)
		(end 388.182358 -156.366972)
		(stroke
			(width 0.2)
			(type default)
		)
		(fill no)
		(layer "In3.Cu")
	)
	(gr_circle
		(center 387.293358 -155.724352)
		(end 388.182358 -155.724352)
		(stroke
			(width 0.2)
			(type default)
		)
		(fill no)
		(layer "In3.Cu")
	)
	(gr_circle
		(center 387.293358 -155.089352)
		(end 388.182358 -155.089352)
		(stroke
			(width 0.2)
			(type default)
		)
		(fill no)
		(layer "In3.Cu")
	)
	(gr_circle
		(center 387.293358 -154.428952)
		(end 388.182358 -154.428952)
		(stroke
			(width 0.2)
			(type default)
		)
		(fill no)
		(layer "In3.Cu")
	)
	(gr_circle
		(center 387.293358 -153.793952)
		(end 388.182358 -153.793952)
		(stroke
			(width 0.2)
			(type default)
		)
		(fill no)
		(layer "In3.Cu")
	)
	(gr_circle
		(center 387.366256 -182.230776)
		(end 388.255256 -182.230776)
		(stroke
			(width 0.2)
			(type default)
		)
		(fill no)
		(layer "In3.Cu")
	)
	(gr_circle
		(center 387.366256 -181.494176)
		(end 388.255256 -181.494176)
		(stroke
			(width 0.2)
			(type default)
		)
		(fill no)
		(layer "In3.Cu")
	)
	(gr_circle
		(center 387.483858 -180.755544)
		(end 388.363968 -180.755544)
		(stroke
			(width 0.2)
			(type default)
		)
		(fill no)
		(layer "In3.Cu")
	)
	(gr_line
		(start 387.601968 -9.780016)
		(end 387.601968 -0.500126)
		(stroke
			(width 1.016)
			(type default)
		)
		(layer "In3.Cu")
	)
	(gr_circle
		(center 387.928358 -157.001972)
		(end 388.817358 -157.001972)
		(stroke
			(width 0.2)
			(type default)
		)
		(fill no)
		(layer "In3.Cu")
	)
	(gr_circle
		(center 387.928358 -156.366972)
		(end 388.817358 -156.366972)
		(stroke
			(width 0.2)
			(type default)
		)
		(fill no)
		(layer "In3.Cu")
	)
	(gr_circle
		(center 387.928358 -155.724352)
		(end 388.817358 -155.724352)
		(stroke
			(width 0.2)
			(type default)
		)
		(fill no)
		(layer "In3.Cu")
	)
	(gr_circle
		(center 387.928358 -155.089352)
		(end 388.817358 -155.089352)
		(stroke
			(width 0.2)
			(type default)
		)
		(fill no)
		(layer "In3.Cu")
	)
	(gr_circle
		(center 387.928358 -154.428952)
		(end 388.817358 -154.428952)
		(stroke
			(width 0.2)
			(type default)
		)
		(fill no)
		(layer "In3.Cu")
	)
	(gr_circle
		(center 387.928358 -153.793952)
		(end 388.817358 -153.793952)
		(stroke
			(width 0.2)
			(type default)
		)
		(fill no)
		(layer "In3.Cu")
	)
	(gr_line
		(start 388.09676 -23.189438)
		(end 389.352028 -21.433028)
		(stroke
			(width 0.1016)
			(type default)
		)
		(layer "In3.Cu")
	)
	(gr_circle
		(center 388.101078 -180.755544)
		(end 388.981188 -180.755544)
		(stroke
			(width 0.2)
			(type default)
		)
		(fill no)
		(layer "In3.Cu")
	)
	(gr_arc
		(start 388.102094 0)
		(mid 387.748465 -0.146487)
		(end 387.601968 -0.500126)
		(stroke
			(width 1.016)
			(type default)
		)
		(layer "In3.Cu")
	)
	(gr_line
		(start 388.102094 0)
		(end 455.701908 0)
		(stroke
			(width 1.016)
			(type default)
		)
		(layer "In3.Cu")
	)
	(gr_circle
		(center 388.718298 -180.755544)
		(end 389.598408 -180.755544)
		(stroke
			(width 0.2)
			(type default)
		)
		(fill no)
		(layer "In3.Cu")
	)
	(gr_line
		(start 389.352028 -21.433028)
		(end 389.94588 -21.857462)
		(stroke
			(width 0.1016)
			(type default)
		)
		(layer "In3.Cu")
	)
	(gr_line
		(start 389.94588 -21.857462)
		(end 388.690612 -23.613872)
		(stroke
			(width 0.1016)
			(type default)
		)
		(layer "In3.Cu")
	)
	(gr_line
		(start 390.517888 -23.643336)
		(end 391.789412 -21.898356)
		(stroke
			(width 0.1016)
			(type default)
		)
		(layer "In3.Cu")
	)
	(gr_line
		(start 391.789412 -21.898356)
		(end 392.3792 -22.328124)
		(stroke
			(width 0.1016)
			(type default)
		)
		(layer "In3.Cu")
	)
	(gr_line
		(start 392.3792 -22.328124)
		(end 391.107676 -24.073104)
		(stroke
			(width 0.1016)
			(type default)
		)
		(layer "In3.Cu")
	)
	(gr_line
		(start 394.095478 -22.52472)
		(end 395.38275 -20.791424)
		(stroke
			(width 0.1016)
			(type default)
		)
		(layer "In3.Cu")
	)
	(gr_circle
		(center 394.628878 -173.21911)
		(end 395.517878 -173.21911)
		(stroke
			(width 0.2)
			(type default)
		)
		(fill no)
		(layer "In3.Cu")
	)
	(gr_circle
		(center 394.628878 -172.45711)
		(end 395.517878 -172.45711)
		(stroke
			(width 0.2)
			(type default)
		)
		(fill no)
		(layer "In3.Cu")
	)
	(gr_circle
		(center 394.646658 -173.987714)
		(end 395.535658 -173.987714)
		(stroke
			(width 0.2)
			(type default)
		)
		(fill no)
		(layer "In3.Cu")
	)
	(gr_circle
		(center 394.672058 -174.749714)
		(end 395.561058 -174.749714)
		(stroke
			(width 0.2)
			(type default)
		)
		(fill no)
		(layer "In3.Cu")
	)
	(gr_circle
		(center 395.196822 -174.310294)
		(end 396.085822 -174.310294)
		(stroke
			(width 0.2)
			(type default)
		)
		(fill no)
		(layer "In3.Cu")
	)
	(gr_circle
		(center 395.196822 -173.573694)
		(end 396.085822 -173.573694)
		(stroke
			(width 0.2)
			(type default)
		)
		(fill no)
		(layer "In3.Cu")
	)
	(gr_circle
		(center 395.230858 -172.819314)
		(end 396.119858 -172.819314)
		(stroke
			(width 0.2)
			(type default)
		)
		(fill no)
		(layer "In3.Cu")
	)
	(gr_line
		(start 395.320012 -24.452326)
		(end 396.621762 -22.729952)
		(stroke
			(width 0.1016)
			(type default)
		)
		(layer "In3.Cu")
	)
	(gr_line
		(start 395.38275 -20.791424)
		(end 395.968982 -21.22678)
		(stroke
			(width 0.1016)
			(type default)
		)
		(layer "In3.Cu")
	)
	(gr_circle
		(center 395.781276 -176.657254)
		(end 396.670276 -176.657254)
		(stroke
			(width 0.2)
			(type default)
		)
		(fill no)
		(layer "In3.Cu")
	)
	(gr_circle
		(center 395.781276 -175.895254)
		(end 396.670276 -175.895254)
		(stroke
			(width 0.2)
			(type default)
		)
		(fill no)
		(layer "In3.Cu")
	)
	(gr_circle
		(center 395.898878 -175.182784)
		(end 396.778988 -175.182784)
		(stroke
			(width 0.2)
			(type default)
		)
		(fill no)
		(layer "In3.Cu")
	)
	(gr_line
		(start 395.968982 -21.22678)
		(end 394.68171 -22.960076)
		(stroke
			(width 0.1016)
			(type default)
		)
		(layer "In3.Cu")
	)
	(gr_circle
		(center 396.516098 -175.182784)
		(end 397.396208 -175.182784)
		(stroke
			(width 0.2)
			(type default)
		)
		(fill no)
		(layer "In3.Cu")
	)
	(gr_line
		(start 396.621762 -22.729952)
		(end 397.204184 -23.170134)
		(stroke
			(width 0.1016)
			(type default)
		)
		(layer "In3.Cu")
	)
	(gr_circle
		(center 397.133318 -175.182784)
		(end 398.013428 -175.182784)
		(stroke
			(width 0.2)
			(type default)
		)
		(fill no)
		(layer "In3.Cu")
	)
	(gr_line
		(start 397.204184 -23.170134)
		(end 395.902434 -24.892508)
		(stroke
			(width 0.1016)
			(type default)
		)
		(layer "In3.Cu")
	)
	(gr_circle
		(center 399.165064 -81.051146)
		(end 400.054064 -81.051146)
		(stroke
			(width 0.2)
			(type default)
		)
		(fill no)
		(layer "In3.Cu")
	)
	(gr_line
		(start 399.521934 -22.65299)
		(end 400.839432 -20.942554)
		(stroke
			(width 0.1016)
			(type default)
		)
		(layer "In3.Cu")
	)
	(gr_line
		(start 400.831558 -24.504142)
		(end 402.163534 -22.805136)
		(stroke
			(width 0.1016)
			(type default)
		)
		(layer "In3.Cu")
	)
	(gr_line
		(start 400.839432 -20.942554)
		(end 401.41779 -21.38807)
		(stroke
			(width 0.1016)
			(type default)
		)
		(layer "In3.Cu")
	)
	(gr_line
		(start 401.41779 -21.38807)
		(end 400.100292 -23.098506)
		(stroke
			(width 0.1016)
			(type default)
		)
		(layer "In3.Cu")
	)
	(gr_line
		(start 402.163534 -22.805136)
		(end 402.738082 -23.255478)
		(stroke
			(width 0.1016)
			(type default)
		)
		(layer "In3.Cu")
	)
	(gr_circle
		(center 402.436838 -166.527988)
		(end 403.325838 -166.527988)
		(stroke
			(width 0.2)
			(type default)
		)
		(fill no)
		(layer "In3.Cu")
	)
	(gr_circle
		(center 402.436838 -165.791388)
		(end 403.325838 -165.791388)
		(stroke
			(width 0.2)
			(type default)
		)
		(fill no)
		(layer "In3.Cu")
	)
	(gr_circle
		(center 402.436838 -165.054788)
		(end 403.325838 -165.054788)
		(stroke
			(width 0.2)
			(type default)
		)
		(fill no)
		(layer "In3.Cu")
	)
	(gr_line
		(start 402.738082 -23.255478)
		(end 401.406106 -24.954484)
		(stroke
			(width 0.1016)
			(type default)
		)
		(layer "In3.Cu")
	)
	(gr_circle
		(center 402.970238 -165.410388)
		(end 403.859238 -165.410388)
		(stroke
			(width 0.2)
			(type default)
		)
		(fill no)
		(layer "In3.Cu")
	)
	(gr_circle
		(center 402.995638 -166.172388)
		(end 403.884638 -166.172388)
		(stroke
			(width 0.2)
			(type default)
		)
		(fill no)
		(layer "In3.Cu")
	)
	(gr_circle
		(center 403.520402 -165.732968)
		(end 404.409402 -165.732968)
		(stroke
			(width 0.2)
			(type default)
		)
		(fill no)
		(layer "In3.Cu")
	)
	(gr_circle
		(center 403.520402 -164.996368)
		(end 404.409402 -164.996368)
		(stroke
			(width 0.2)
			(type default)
		)
		(fill no)
		(layer "In3.Cu")
	)
	(gr_circle
		(center 404.104856 -168.082214)
		(end 404.993856 -168.082214)
		(stroke
			(width 0.2)
			(type default)
		)
		(fill no)
		(layer "In3.Cu")
	)
	(gr_circle
		(center 404.104856 -167.320214)
		(end 404.993856 -167.320214)
		(stroke
			(width 0.2)
			(type default)
		)
		(fill no)
		(layer "In3.Cu")
	)
	(gr_circle
		(center 404.222458 -166.605458)
		(end 405.102568 -166.605458)
		(stroke
			(width 0.2)
			(type default)
		)
		(fill no)
		(layer "In3.Cu")
	)
	(gr_circle
		(center 404.839678 -166.605458)
		(end 405.719788 -166.605458)
		(stroke
			(width 0.2)
			(type default)
		)
		(fill no)
		(layer "In3.Cu")
	)
	(gr_line
		(start 405.398732 -23.379176)
		(end 406.744678 -21.691092)
		(stroke
			(width 0.1016)
			(type default)
		)
		(layer "In3.Cu")
	)
	(gr_circle
		(center 405.456898 -166.605458)
		(end 406.337008 -166.605458)
		(stroke
			(width 0.2)
			(type default)
		)
		(fill no)
		(layer "In3.Cu")
	)
	(gr_line
		(start 406.17394 -21.235924)
		(end 404.827994 -22.924008)
		(stroke
			(width 0.1016)
			(type default)
		)
		(layer "In3.Cu")
	)
	(gr_line
		(start 406.365964 -25.588214)
		(end 407.725626 -23.911052)
		(stroke
			(width 0.1016)
			(type default)
		)
		(layer "In3.Cu")
	)
	(gr_line
		(start 406.744678 -21.691092)
		(end 406.17394 -21.235924)
		(stroke
			(width 0.1016)
			(type default)
		)
		(layer "In3.Cu")
	)
	(gr_line
		(start 407.158444 -23.451566)
		(end 405.798782 -25.128728)
		(stroke
			(width 0.1016)
			(type default)
		)
		(layer "In3.Cu")
	)
	(gr_line
		(start 407.725626 -23.911052)
		(end 407.158444 -23.451566)
		(stroke
			(width 0.1016)
			(type default)
		)
		(layer "In3.Cu")
	)
	(gr_line
		(start 409.940506 -23.414228)
		(end 411.313122 -21.747734)
		(stroke
			(width 0.1016)
			(type default)
		)
		(layer "In3.Cu")
	)
	(gr_circle
		(center 410.818838 -161.701988)
		(end 411.707838 -161.701988)
		(stroke
			(width 0.2)
			(type default)
		)
		(fill no)
		(layer "In3.Cu")
	)
	(gr_circle
		(center 410.818838 -160.965388)
		(end 411.707838 -160.965388)
		(stroke
			(width 0.2)
			(type default)
		)
		(fill no)
		(layer "In3.Cu")
	)
	(gr_circle
		(center 410.818838 -160.228788)
		(end 411.707838 -160.228788)
		(stroke
			(width 0.2)
			(type default)
		)
		(fill no)
		(layer "In3.Cu")
	)
	(gr_line
		(start 411.313122 -21.747734)
		(end 411.876494 -22.211792)
		(stroke
			(width 0.1016)
			(type default)
		)
		(layer "In3.Cu")
	)
	(gr_circle
		(center 411.352238 -160.584388)
		(end 412.241238 -160.584388)
		(stroke
			(width 0.2)
			(type default)
		)
		(fill no)
		(layer "In3.Cu")
	)
	(gr_circle
		(center 411.377638 -161.346388)
		(end 412.266638 -161.346388)
		(stroke
			(width 0.2)
			(type default)
		)
		(fill no)
		(layer "In3.Cu")
	)
	(gr_line
		(start 411.876494 -22.211792)
		(end 410.503878 -23.878286)
		(stroke
			(width 0.1016)
			(type default)
		)
		(layer "In3.Cu")
	)
	(gr_circle
		(center 411.902402 -160.906968)
		(end 412.791402 -160.906968)
		(stroke
			(width 0.2)
			(type default)
		)
		(fill no)
		(layer "In3.Cu")
	)
	(gr_circle
		(center 411.902402 -160.170368)
		(end 412.791402 -160.170368)
		(stroke
			(width 0.2)
			(type default)
		)
		(fill no)
		(layer "In3.Cu")
	)
	(gr_line
		(start 412.101792 -24.471884)
		(end 413.490156 -22.818344)
		(stroke
			(width 0.1016)
			(type default)
		)
		(layer "In3.Cu")
	)
	(gr_circle
		(center 412.486856 -163.256214)
		(end 413.375856 -163.256214)
		(stroke
			(width 0.2)
			(type default)
		)
		(fill no)
		(layer "In3.Cu")
	)
	(gr_circle
		(center 412.486856 -162.494214)
		(end 413.375856 -162.494214)
		(stroke
			(width 0.2)
			(type default)
		)
		(fill no)
		(layer "In3.Cu")
	)
	(gr_circle
		(center 412.604458 -161.779458)
		(end 413.484568 -161.779458)
		(stroke
			(width 0.2)
			(type default)
		)
		(fill no)
		(layer "In3.Cu")
	)
	(gr_line
		(start 413.122872 -26.486358)
		(end 414.523682 -24.843486)
		(stroke
			(width 0.1016)
			(type default)
		)
		(layer "In3.Cu")
	)
	(gr_circle
		(center 413.221678 -161.779458)
		(end 414.101788 -161.779458)
		(stroke
			(width 0.2)
			(type default)
		)
		(fill no)
		(layer "In3.Cu")
	)
	(gr_line
		(start 413.490156 -22.818344)
		(end 414.048956 -23.287736)
		(stroke
			(width 0.1016)
			(type default)
		)
		(layer "In3.Cu")
	)
	(gr_circle
		(center 413.838898 -161.779458)
		(end 414.719008 -161.779458)
		(stroke
			(width 0.2)
			(type default)
		)
		(fill no)
		(layer "In3.Cu")
	)
	(gr_line
		(start 414.048956 -23.287736)
		(end 412.660592 -24.941276)
		(stroke
			(width 0.1016)
			(type default)
		)
		(layer "In3.Cu")
	)
	(gr_line
		(start 414.523682 -24.843486)
		(end 415.07918 -25.316942)
		(stroke
			(width 0.1016)
			(type default)
		)
		(layer "In3.Cu")
	)
	(gr_line
		(start 415.07918 -25.316942)
		(end 413.67837 -26.959814)
		(stroke
			(width 0.1016)
			(type default)
		)
		(layer "In3.Cu")
	)
	(gr_line
		(start 419.232842 -22.562566)
		(end 420.64559 -20.929854)
		(stroke
			(width 0.1016)
			(type default)
		)
		(layer "In3.Cu")
	)
	(gr_line
		(start 420.341806 -24.4475)
		(end 421.766492 -22.825202)
		(stroke
			(width 0.1016)
			(type default)
		)
		(layer "In3.Cu")
	)
	(gr_line
		(start 420.64559 -20.929854)
		(end 421.197786 -21.407374)
		(stroke
			(width 0.1016)
			(type default)
		)
		(layer "In3.Cu")
	)
	(gr_line
		(start 421.197786 -21.407374)
		(end 419.785038 -23.040086)
		(stroke
			(width 0.1016)
			(type default)
		)
		(layer "In3.Cu")
	)
	(gr_line
		(start 421.766492 -22.825202)
		(end 422.314878 -23.30704)
		(stroke
			(width 0.1016)
			(type default)
		)
		(layer "In3.Cu")
	)
	(gr_line
		(start 422.314878 -23.30704)
		(end 420.890192 -24.929338)
		(stroke
			(width 0.1016)
			(type default)
		)
		(layer "In3.Cu")
	)
	(gr_circle
		(center 424.33494 -353.10318)
		(end 425.21505 -353.10318)
		(stroke
			(width 0.2)
			(type default)
		)
		(fill no)
		(layer "In3.Cu")
	)
	(gr_line
		(start 424.611038 -22.769068)
		(end 426.047154 -21.157184)
		(stroke
			(width 0.1016)
			(type default)
		)
		(layer "In3.Cu")
	)
	(gr_circle
		(center 424.95216 -353.10318)
		(end 425.83227 -353.10318)
		(stroke
			(width 0.2)
			(type default)
		)
		(fill no)
		(layer "In3.Cu")
	)
	(gr_line
		(start 425.533312 -24.804624)
		(end 426.98035 -23.202392)
		(stroke
			(width 0.1016)
			(type default)
		)
		(layer "In3.Cu")
	)
	(gr_circle
		(center 425.56938 -353.10318)
		(end 426.44949 -353.10318)
		(stroke
			(width 0.2)
			(type default)
		)
		(fill no)
		(layer "In3.Cu")
	)
	(gr_circle
		(center 425.686474 -352.35769)
		(end 426.575474 -352.35769)
		(stroke
			(width 0.2)
			(type default)
		)
		(fill no)
		(layer "In3.Cu")
	)
	(gr_circle
		(center 425.686474 -351.62109)
		(end 426.575474 -351.62109)
		(stroke
			(width 0.2)
			(type default)
		)
		(fill no)
		(layer "In3.Cu")
	)
	(gr_line
		(start 426.047154 -21.157184)
		(end 426.592238 -21.642832)
		(stroke
			(width 0.1016)
			(type default)
		)
		(layer "In3.Cu")
	)
	(gr_circle
		(center 426.271436 -354.71227)
		(end 427.160436 -354.71227)
		(stroke
			(width 0.2)
			(type default)
		)
		(fill no)
		(layer "In3.Cu")
	)
	(gr_circle
		(center 426.271436 -353.97567)
		(end 427.160436 -353.97567)
		(stroke
			(width 0.2)
			(type default)
		)
		(fill no)
		(layer "In3.Cu")
	)
	(gr_line
		(start 426.592238 -21.642832)
		(end 425.156122 -23.254716)
		(stroke
			(width 0.1016)
			(type default)
		)
		(layer "In3.Cu")
	)
	(gr_circle
		(center 426.7962 -353.53625)
		(end 427.6852 -353.53625)
		(stroke
			(width 0.2)
			(type default)
		)
		(fill no)
		(layer "In3.Cu")
	)
	(gr_circle
		(center 426.8216 -354.29825)
		(end 427.7106 -354.29825)
		(stroke
			(width 0.2)
			(type default)
		)
		(fill no)
		(layer "In3.Cu")
	)
	(gr_line
		(start 426.98035 -23.202392)
		(end 427.522132 -23.691596)
		(stroke
			(width 0.1016)
			(type default)
		)
		(layer "In3.Cu")
	)
	(gr_circle
		(center 427.355 -354.65385)
		(end 428.244 -354.65385)
		(stroke
			(width 0.2)
			(type default)
		)
		(fill no)
		(layer "In3.Cu")
	)
	(gr_circle
		(center 427.355 -353.91725)
		(end 428.244 -353.91725)
		(stroke
			(width 0.2)
			(type default)
		)
		(fill no)
		(layer "In3.Cu")
	)
	(gr_circle
		(center 427.355 -353.18065)
		(end 428.244 -353.18065)
		(stroke
			(width 0.2)
			(type default)
		)
		(fill no)
		(layer "In3.Cu")
	)
	(gr_line
		(start 427.522132 -23.691596)
		(end 426.075094 -25.293828)
		(stroke
			(width 0.1016)
			(type default)
		)
		(layer "In3.Cu")
	)
	(gr_line
		(start 428.93488 -23.684738)
		(end 430.389792 -22.089618)
		(stroke
			(width 0.1016)
			(type default)
		)
		(layer "In3.Cu")
	)
	(gr_line
		(start 430.389792 -22.089618)
		(end 430.929288 -22.581362)
		(stroke
			(width 0.1016)
			(type default)
		)
		(layer "In3.Cu")
	)
	(gr_line
		(start 430.929288 -22.581362)
		(end 429.474376 -24.176482)
		(stroke
			(width 0.1016)
			(type default)
		)
		(layer "In3.Cu")
	)
	(gr_circle
		(center 432.01336 -361.827826)
		(end 433.41036 -361.827826)
		(stroke
			(width 0.2)
			(type default)
		)
		(fill no)
		(layer "In3.Cu")
	)
	(gr_circle
		(center 432.661568 -353.12858)
		(end 433.541678 -353.12858)
		(stroke
			(width 0.2)
			(type default)
		)
		(fill no)
		(layer "In3.Cu")
	)
	(gr_circle
		(center 433.278788 -353.12858)
		(end 434.158898 -353.12858)
		(stroke
			(width 0.2)
			(type default)
		)
		(fill no)
		(layer "In3.Cu")
	)
	(gr_circle
		(center 433.896008 -353.12858)
		(end 434.776118 -353.12858)
		(stroke
			(width 0.2)
			(type default)
		)
		(fill no)
		(layer "In3.Cu")
	)
	(gr_circle
		(center 434.013102 -352.38309)
		(end 434.902102 -352.38309)
		(stroke
			(width 0.2)
			(type default)
		)
		(fill no)
		(layer "In3.Cu")
	)
	(gr_circle
		(center 434.013102 -351.64649)
		(end 434.902102 -351.64649)
		(stroke
			(width 0.2)
			(type default)
		)
		(fill no)
		(layer "In3.Cu")
	)
	(gr_circle
		(center 434.598064 -354.73767)
		(end 435.487064 -354.73767)
		(stroke
			(width 0.2)
			(type default)
		)
		(fill no)
		(layer "In3.Cu")
	)
	(gr_circle
		(center 434.598064 -354.00107)
		(end 435.487064 -354.00107)
		(stroke
			(width 0.2)
			(type default)
		)
		(fill no)
		(layer "In3.Cu")
	)
	(gr_circle
		(center 435.122828 -353.56165)
		(end 436.011828 -353.56165)
		(stroke
			(width 0.2)
			(type default)
		)
		(fill no)
		(layer "In3.Cu")
	)
	(gr_circle
		(center 435.148228 -354.32365)
		(end 436.037228 -354.32365)
		(stroke
			(width 0.2)
			(type default)
		)
		(fill no)
		(layer "In3.Cu")
	)
	(gr_circle
		(center 435.469538 -361.496102)
		(end 436.358538 -361.496102)
		(stroke
			(width 0.2)
			(type default)
		)
		(fill no)
		(layer "In3.Cu")
	)
	(gr_circle
		(center 435.469538 -360.734102)
		(end 436.358538 -360.734102)
		(stroke
			(width 0.2)
			(type default)
		)
		(fill no)
		(layer "In3.Cu")
	)
	(gr_circle
		(center 435.469538 -359.972102)
		(end 436.358538 -359.972102)
		(stroke
			(width 0.2)
			(type default)
		)
		(fill no)
		(layer "In3.Cu")
	)
	(gr_circle
		(center 435.681628 -354.67925)
		(end 436.570628 -354.67925)
		(stroke
			(width 0.2)
			(type default)
		)
		(fill no)
		(layer "In3.Cu")
	)
	(gr_circle
		(center 435.681628 -353.94265)
		(end 436.570628 -353.94265)
		(stroke
			(width 0.2)
			(type default)
		)
		(fill no)
		(layer "In3.Cu")
	)
	(gr_circle
		(center 435.681628 -353.20605)
		(end 436.570628 -353.20605)
		(stroke
			(width 0.2)
			(type default)
		)
		(fill no)
		(layer "In3.Cu")
	)
	(gr_circle
		(center 436.231538 -361.496102)
		(end 437.120538 -361.496102)
		(stroke
			(width 0.2)
			(type default)
		)
		(fill no)
		(layer "In3.Cu")
	)
	(gr_circle
		(center 436.231538 -360.734102)
		(end 437.120538 -360.734102)
		(stroke
			(width 0.2)
			(type default)
		)
		(fill no)
		(layer "In3.Cu")
	)
	(gr_circle
		(center 436.231538 -359.972102)
		(end 437.120538 -359.972102)
		(stroke
			(width 0.2)
			(type default)
		)
		(fill no)
		(layer "In3.Cu")
	)
	(gr_circle
		(center 437.703214 -12.400788)
		(end 438.592214 -12.400788)
		(stroke
			(width 0.2)
			(type default)
		)
		(fill no)
		(layer "In3.Cu")
	)
	(gr_circle
		(center 438.06999 -13.069316)
		(end 438.95899 -13.069316)
		(stroke
			(width 0.2)
			(type default)
		)
		(fill no)
		(layer "In3.Cu")
	)
	(gr_circle
		(center 438.592214 -12.400788)
		(end 439.481214 -12.400788)
		(stroke
			(width 0.2)
			(type default)
		)
		(fill no)
		(layer "In3.Cu")
	)
	(gr_circle
		(center 438.71515 -13.061696)
		(end 439.60415 -13.061696)
		(stroke
			(width 0.2)
			(type default)
		)
		(fill no)
		(layer "In3.Cu")
	)
	(gr_circle
		(center 439.39333 -13.043916)
		(end 440.28233 -13.043916)
		(stroke
			(width 0.2)
			(type default)
		)
		(fill no)
		(layer "In3.Cu")
	)
	(gr_circle
		(center 439.481214 -12.400788)
		(end 440.370214 -12.400788)
		(stroke
			(width 0.2)
			(type default)
		)
		(fill no)
		(layer "In3.Cu")
	)
	(gr_circle
		(center 440.945524 -11.261852)
		(end 441.834524 -11.261852)
		(stroke
			(width 0.2)
			(type default)
		)
		(fill no)
		(layer "In3.Cu")
	)
	(gr_circle
		(center 440.945524 -10.626852)
		(end 441.834524 -10.626852)
		(stroke
			(width 0.2)
			(type default)
		)
		(fill no)
		(layer "In3.Cu")
	)
	(gr_circle
		(center 441.129674 -25.982422)
		(end 442.018674 -25.982422)
		(stroke
			(width 0.2)
			(type default)
		)
		(fill no)
		(layer "In3.Cu")
	)
	(gr_circle
		(center 441.354718 -20.73656)
		(end 442.243718 -20.73656)
		(stroke
			(width 0.2)
			(type default)
		)
		(fill no)
		(layer "In3.Cu")
	)
	(gr_circle
		(center 441.354718 -20.10156)
		(end 442.243718 -20.10156)
		(stroke
			(width 0.2)
			(type default)
		)
		(fill no)
		(layer "In3.Cu")
	)
	(gr_circle
		(center 441.354718 -19.21256)
		(end 442.243718 -19.21256)
		(stroke
			(width 0.2)
			(type default)
		)
		(fill no)
		(layer "In3.Cu")
	)
	(gr_circle
		(center 441.354718 -18.57756)
		(end 442.243718 -18.57756)
		(stroke
			(width 0.2)
			(type default)
		)
		(fill no)
		(layer "In3.Cu")
	)
	(gr_circle
		(center 441.475622 -14.123162)
		(end 442.364622 -14.123162)
		(stroke
			(width 0.2)
			(type default)
		)
		(fill no)
		(layer "In3.Cu")
	)
	(gr_circle
		(center 441.475622 -13.488162)
		(end 442.364622 -13.488162)
		(stroke
			(width 0.2)
			(type default)
		)
		(fill no)
		(layer "In3.Cu")
	)
	(gr_circle
		(center 441.56249 -25.461976)
		(end 442.45149 -25.461976)
		(stroke
			(width 0.2)
			(type default)
		)
		(fill no)
		(layer "In3.Cu")
	)
	(gr_circle
		(center 442.018674 -25.982422)
		(end 442.907674 -25.982422)
		(stroke
			(width 0.2)
			(type default)
		)
		(fill no)
		(layer "In3.Cu")
	)
	(gr_circle
		(center 442.371734 -20.983702)
		(end 443.260734 -20.983702)
		(stroke
			(width 0.2)
			(type default)
		)
		(fill no)
		(layer "In3.Cu")
	)
	(gr_circle
		(center 442.371734 -20.348702)
		(end 443.260734 -20.348702)
		(stroke
			(width 0.2)
			(type default)
		)
		(fill no)
		(layer "In3.Cu")
	)
	(gr_circle
		(center 442.371734 -19.459702)
		(end 443.260734 -19.459702)
		(stroke
			(width 0.2)
			(type default)
		)
		(fill no)
		(layer "In3.Cu")
	)
	(gr_circle
		(center 442.371734 -18.824702)
		(end 443.260734 -18.824702)
		(stroke
			(width 0.2)
			(type default)
		)
		(fill no)
		(layer "In3.Cu")
	)
	(gr_circle
		(center 442.45149 -25.461976)
		(end 443.34049 -25.461976)
		(stroke
			(width 0.2)
			(type default)
		)
		(fill no)
		(layer "In3.Cu")
	)
	(gr_circle
		(center 442.907674 -25.982422)
		(end 443.796674 -25.982422)
		(stroke
			(width 0.2)
			(type default)
		)
		(fill no)
		(layer "In3.Cu")
	)
	(gr_circle
		(center 443.34049 -25.461976)
		(end 444.22949 -25.461976)
		(stroke
			(width 0.2)
			(type default)
		)
		(fill no)
		(layer "In3.Cu")
	)
	(gr_circle
		(center 444.166244 -24.741632)
		(end 445.055244 -24.741632)
		(stroke
			(width 0.2)
			(type default)
		)
		(fill no)
		(layer "In3.Cu")
	)
	(gr_circle
		(center 450.669914 -14.526514)
		(end 451.558914 -14.526514)
		(stroke
			(width 0.2)
			(type default)
		)
		(fill no)
		(layer "In3.Cu")
	)
	(gr_circle
		(center 450.670676 -16.010382)
		(end 451.559676 -16.010382)
		(stroke
			(width 0.2)
			(type default)
		)
		(fill no)
		(layer "In3.Cu")
	)
	(gr_circle
		(center 450.670676 -15.273782)
		(end 451.559676 -15.273782)
		(stroke
			(width 0.2)
			(type default)
		)
		(fill no)
		(layer "In3.Cu")
	)
	(gr_circle
		(center 452.054976 -18.535142)
		(end 452.943976 -18.535142)
		(stroke
			(width 0.2)
			(type default)
		)
		(fill no)
		(layer "In3.Cu")
	)
	(gr_circle
		(center 452.054976 -17.798542)
		(end 452.943976 -17.798542)
		(stroke
			(width 0.2)
			(type default)
		)
		(fill no)
		(layer "In3.Cu")
	)
	(gr_arc
		(start 456.202034 -9.780016)
		(mid 456.787819 -11.194227)
		(end 458.20203 -11.780012)
		(stroke
			(width 1.016)
			(type default)
		)
		(layer "In3.Cu")
	)
	(gr_arc
		(start 456.202034 -0.500126)
		(mid 456.05556 -0.146464)
		(end 455.701908 0)
		(stroke
			(width 1.016)
			(type default)
		)
		(layer "In3.Cu")
	)
	(gr_line
		(start 456.202034 -0.500126)
		(end 456.202034 -9.780016)
		(stroke
			(width 1.016)
			(type default)
		)
		(layer "In3.Cu")
	)
	(gr_line
		(start 458.20203 -11.780012)
		(end 469.799924 -11.780012)
		(stroke
			(width 1.016)
			(type default)
		)
		(layer "In3.Cu")
	)
	(gr_line
		(start 463.300064 -441.989972)
		(end 277.314914 -441.989972)
		(stroke
			(width 1.016)
			(type default)
		)
		(layer "In3.Cu")
	)
	(gr_arc
		(start 463.300064 -441.989972)
		(mid 464.71429 -441.404198)
		(end 465.30006 -439.989976)
		(stroke
			(width 1.016)
			(type default)
		)
		(layer "In3.Cu")
	)
	(gr_line
		(start 465.30006 -409.528518)
		(end 465.30006 -439.989976)
		(stroke
			(width 1.016)
			(type default)
		)
		(layer "In3.Cu")
	)
	(gr_arc
		(start 465.885784 -408.114246)
		(mid 465.452221 -408.76312)
		(end 465.30006 -409.528518)
		(stroke
			(width 1.016)
			(type default)
		)
		(layer "In3.Cu")
	)
	(gr_line
		(start 467.71433 -406.2857)
		(end 465.885784 -408.114246)
		(stroke
			(width 1.016)
			(type default)
		)
		(layer "In3.Cu")
	)
	(gr_arc
		(start 467.71433 -406.2857)
		(mid 468.147828 -405.636947)
		(end 468.300054 -404.871682)
		(stroke
			(width 1.016)
			(type default)
		)
		(layer "In3.Cu")
	)
	(gr_line
		(start 468.300054 -82.828384)
		(end 468.300054 -404.871682)
		(stroke
			(width 1.016)
			(type default)
		)
		(layer "In3.Cu")
	)
	(gr_arc
		(start 468.885778 -81.414112)
		(mid 468.452215 -82.062986)
		(end 468.300054 -82.828384)
		(stroke
			(width 1.016)
			(type default)
		)
		(layer "In3.Cu")
	)
	(gr_line
		(start 471.214196 -79.085694)
		(end 468.885778 -81.414112)
		(stroke
			(width 1.016)
			(type default)
		)
		(layer "In3.Cu")
	)
	(gr_arc
		(start 471.214196 -79.085694)
		(mid 471.6477 -78.436942)
		(end 471.79992 -77.671676)
		(stroke
			(width 1.016)
			(type default)
		)
		(layer "In3.Cu")
	)
	(gr_arc
		(start 471.79992 -13.780008)
		(mid 471.214139 -12.365784)
		(end 469.799924 -11.780012)
		(stroke
			(width 1.016)
			(type default)
		)
		(layer "In3.Cu")
	)
	(gr_line
		(start 471.79992 -13.780008)
		(end 471.79992 -77.671676)
		(stroke
			(width 1.016)
			(type default)
		)
		(layer "In3.Cu")
	)
	(gr_poly
		(pts
			(xy 78.264004 -294.781732) (xy 78.22565 -294.75938) (xy 78.088998 -294.795956) (xy 78.125574 -294.932608)
			(xy 78.164182 -294.95496)
		)
		(stroke
			(width 0)
			(type solid)
		)
		(fill yes)
		(layer "In4.Cu")
		(net "M_D_CPU1_SB_DQ<28>")
	)
	(gr_poly
		(pts
			(xy 78.385416 -223.728534) (xy 78.31709 -223.540574) (xy 78.27518 -223.555814) (xy 78.21549 -223.684084)
			(xy 78.34376 -223.743774)
		)
		(stroke
			(width 0)
			(type solid)
		)
		(fill yes)
		(layer "In4.Cu")
		(net "M_D_CPU1_SA_DQ<6>")
	)
	(gr_poly
		(pts
			(xy 78.498446 -247.522746) (xy 78.498446 -247.475248) (xy 78.298548 -247.475248) (xy 78.298548 -247.522746)
			(xy 78.398624 -247.622822)
		)
		(stroke
			(width 0)
			(type solid)
		)
		(fill yes)
		(layer "In4.Cu")
		(net "M_D_CPU1_SA_DQS_DP<9>")
	)
	(gr_poly
		(pts
			(xy 78.498446 -242.66271) (xy 78.498446 -242.615212) (xy 78.298548 -242.615212) (xy 78.298548 -242.66271)
			(xy 78.398624 -242.762786)
		)
		(stroke
			(width 0)
			(type solid)
		)
		(fill yes)
		(layer "In4.Cu")
		(net "M_D_CPU1_SA_DQS_DP<8>")
	)
	(gr_poly
		(pts
			(xy 78.501494 -254.002794) (xy 78.501494 -253.958344) (xy 78.301342 -253.958344) (xy 78.301342 -254.002794)
			(xy 78.401418 -254.102616)
		)
		(stroke
			(width 0)
			(type solid)
		)
		(fill yes)
		(layer "In4.Cu")
		(net "M_D_CPU1_SA_CA<3>")
	)
	(gr_poly
		(pts
			(xy 78.501494 -252.382782) (xy 78.501494 -252.338332) (xy 78.301342 -252.338332) (xy 78.301342 -252.382782)
			(xy 78.401418 -252.482604)
		)
		(stroke
			(width 0)
			(type solid)
		)
		(fill yes)
		(layer "In4.Cu")
		(net "M_D_CPU1_SA_CS_N<1>")
	)
	(gr_poly
		(pts
			(xy 78.501494 -249.142758) (xy 78.501494 -249.098308) (xy 78.301342 -249.098308) (xy 78.301342 -249.142758)
			(xy 78.401418 -249.24258)
		)
		(stroke
			(width 0)
			(type solid)
		)
		(fill yes)
		(layer "In4.Cu")
		(net "M_D_CPU1_SA_CB<7>")
	)
	(gr_poly
		(pts
			(xy 78.501494 -245.902734) (xy 78.501494 -245.858284) (xy 78.301342 -245.858284) (xy 78.301342 -245.902734)
			(xy 78.401418 -246.002556)
		)
		(stroke
			(width 0)
			(type solid)
		)
		(fill yes)
		(layer "In4.Cu")
		(net "M_D_CPU1_SA_CB<3>")
	)
	(gr_poly
		(pts
			(xy 78.501494 -244.282722) (xy 78.501494 -244.238272) (xy 78.301342 -244.238272) (xy 78.301342 -244.282722)
			(xy 78.401418 -244.382544)
		)
		(stroke
			(width 0)
			(type solid)
		)
		(fill yes)
		(layer "In4.Cu")
		(net "M_D_CPU1_SA_DQ<31>")
	)
	(gr_poly
		(pts
			(xy 78.528926 -223.223836) (xy 78.565756 -223.087184) (xy 78.429104 -223.050608) (xy 78.390496 -223.07296)
			(xy 78.490572 -223.246188)
		)
		(stroke
			(width 0)
			(type solid)
		)
		(fill yes)
		(layer "In4.Cu")
		(net "M_D_CPU1_SA_DQ<4>")
	)
	(gr_poly
		(pts
			(xy 78.530704 -254.406146) (xy 78.430628 -254.30607) (xy 78.330806 -254.406146) (xy 78.330806 -254.450596)
			(xy 78.530704 -254.450596)
		)
		(stroke
			(width 0)
			(type solid)
		)
		(fill yes)
		(layer "In4.Cu")
		(net "M_D_CPU1_SA_CA<4>")
	)
	(gr_poly
		(pts
			(xy 78.530704 -252.786134) (xy 78.430628 -252.686058) (xy 78.330806 -252.786134) (xy 78.330806 -252.830584)
			(xy 78.530704 -252.830584)
		)
		(stroke
			(width 0)
			(type solid)
		)
		(fill yes)
		(layer "In4.Cu")
		(net "M_D_CPU1_SA_CA<0>")
	)
	(gr_poly
		(pts
			(xy 78.530704 -247.926098) (xy 78.430628 -247.826022) (xy 78.330806 -247.926098) (xy 78.330806 -247.970548)
			(xy 78.530704 -247.970548)
		)
		(stroke
			(width 0)
			(type solid)
		)
		(fill yes)
		(layer "In4.Cu")
		(net "M_D_CPU1_SA_CB<4>")
	)
	(gr_poly
		(pts
			(xy 78.730348 -293.986712) (xy 78.691994 -293.96436) (xy 78.555342 -294.000936) (xy 78.591918 -294.137588)
			(xy 78.630526 -294.15994)
		)
		(stroke
			(width 0)
			(type solid)
		)
		(fill yes)
		(layer "In4.Cu")
		(net "M_D_CPU1_SB_DQ<28>")
	)
	(gr_poly
		(pts
			(xy 78.801468 -289.677856) (xy 78.701392 -289.578034) (xy 78.60157 -289.677856) (xy 78.60157 -289.722306)
			(xy 78.801468 -289.722306)
		)
		(stroke
			(width 0)
			(type solid)
		)
		(fill yes)
		(layer "In4.Cu")
		(net "M_D_CPU1_SB_DQ<25>")
	)
	(gr_poly
		(pts
			(xy 78.801468 -286.437832) (xy 78.701392 -286.33801) (xy 78.60157 -286.437832) (xy 78.60157 -286.485584)
			(xy 78.801468 -286.485584)
		)
		(stroke
			(width 0)
			(type solid)
		)
		(fill yes)
		(layer "In4.Cu")
		(net "M_D_CPU1_SB_DQS_DN<7>")
	)
	(gr_poly
		(pts
			(xy 78.801468 -284.818074) (xy 78.701392 -284.718252) (xy 78.60157 -284.818074) (xy 78.60157 -284.862524)
			(xy 78.801468 -284.862524)
		)
		(stroke
			(width 0)
			(type solid)
		)
		(fill yes)
		(layer "In4.Cu")
		(net "M_D_CPU1_SB_DQ<17>")
	)
	(gr_poly
		(pts
			(xy 78.801468 -273.074638) (xy 78.801468 -273.030188) (xy 78.60157 -273.030188) (xy 78.60157 -273.074638)
			(xy 78.701392 -273.17446)
		)
		(stroke
			(width 0)
			(type solid)
		)
		(fill yes)
		(layer "In4.Cu")
		(net "M_D_CPU1_SB_CB<2>")
	)
	(gr_poly
		(pts
			(xy 78.801468 -269.834614) (xy 78.801468 -269.790164) (xy 78.60157 -269.790164) (xy 78.60157 -269.834614)
			(xy 78.701392 -269.934436)
		)
		(stroke
			(width 0)
			(type solid)
		)
		(fill yes)
		(layer "In4.Cu")
		(net "M_D_CPU1_SB_CB<6>")
	)
	(gr_poly
		(pts
			(xy 78.80223 -288.057844) (xy 78.702408 -287.957768) (xy 78.602332 -288.057844) (xy 78.602332 -288.102294)
			(xy 78.80223 -288.102294)
		)
		(stroke
			(width 0)
			(type solid)
		)
		(fill yes)
		(layer "In4.Cu")
		(net "M_D_CPU1_SB_DQ<21>")
	)
	(gr_poly
		(pts
			(xy 78.819756 -281.174698) (xy 78.819756 -281.1272) (xy 78.619858 -281.1272) (xy 78.619858 -281.174698)
			(xy 78.71968 -281.274774)
		)
		(stroke
			(width 0)
			(type solid)
		)
		(fill yes)
		(layer "In4.Cu")
		(net "M_D_CPU1_SB_DQS_DN<1>")
	)
	(gr_poly
		(pts
			(xy 78.900274 -224.582736) (xy 78.800198 -224.409508) (xy 78.76159 -224.431606) (xy 78.725014 -224.568258)
			(xy 78.861666 -224.604834)
		)
		(stroke
			(width 0)
			(type solid)
		)
		(fill yes)
		(layer "In4.Cu")
		(net "M_D_CPU1_SA_DQ<6>")
	)
	(gr_poly
		(pts
			(xy 78.904846 -222.964502) (xy 78.80477 -222.791274) (xy 78.763622 -222.81515) (xy 78.727046 -222.951802)
			(xy 78.863698 -222.988378)
		)
		(stroke
			(width 0)
			(type solid)
		)
		(fill yes)
		(layer "In4.Cu")
		(net "M_D_CPU1_SA_DQS_DP<5>")
	)
	(gr_poly
		(pts
			(xy 78.96225 -256.433066) (xy 78.96225 -256.385568) (xy 78.762352 -256.385568) (xy 78.762352 -256.433066)
			(xy 78.862428 -256.533142)
		)
		(stroke
			(width 0)
			(type solid)
		)
		(fill yes)
		(layer "In4.Cu")
		(net "M_D_CPU1_CLK_DN<0>")
	)
	(gr_poly
		(pts
			(xy 78.96733 -239.015778) (xy 78.867254 -238.915702) (xy 78.767178 -239.015778) (xy 78.767178 -239.060228)
			(xy 78.96733 -239.060228)
		)
		(stroke
			(width 0)
			(type solid)
		)
		(fill yes)
		(layer "In4.Cu")
		(net "M_D_CPU1_SA_DQ<21>")
	)
	(gr_poly
		(pts
			(xy 78.969362 -254.813054) (xy 78.969362 -254.768604) (xy 78.769464 -254.768604) (xy 78.769464 -254.813054)
			(xy 78.86954 -254.91313)
		)
		(stroke
			(width 0)
			(type solid)
		)
		(fill yes)
		(layer "In4.Cu")
		(net "M_D_CPU1_SA_CA<5>")
	)
	(gr_poly
		(pts
			(xy 78.969362 -253.193042) (xy 78.969362 -253.148592) (xy 78.769464 -253.148592) (xy 78.769464 -253.193042)
			(xy 78.86954 -253.293118)
		)
		(stroke
			(width 0)
			(type solid)
		)
		(fill yes)
		(layer "In4.Cu")
		(net "M_D_CPU1_SA_CA<1>")
	)
	(gr_poly
		(pts
			(xy 78.969362 -248.333006) (xy 78.969362 -248.288556) (xy 78.769464 -248.288556) (xy 78.769464 -248.333006)
			(xy 78.86954 -248.433082)
		)
		(stroke
			(width 0)
			(type solid)
		)
		(fill yes)
		(layer "In4.Cu")
		(net "M_D_CPU1_SA_CB<6>")
	)
	(gr_poly
		(pts
			(xy 78.969362 -246.712994) (xy 78.969362 -246.665496) (xy 78.769464 -246.665496) (xy 78.769464 -246.712994)
			(xy 78.86954 -246.81307)
		)
		(stroke
			(width 0)
			(type solid)
		)
		(fill yes)
		(layer "In4.Cu")
		(net "M_D_CPU1_SA_DQS_DN<4>")
	)
	(gr_poly
		(pts
			(xy 78.969362 -245.092982) (xy 78.969362 -245.048532) (xy 78.769464 -245.048532) (xy 78.769464 -245.092982)
			(xy 78.86954 -245.193058)
		)
		(stroke
			(width 0)
			(type solid)
		)
		(fill yes)
		(layer "In4.Cu")
		(net "M_D_CPU1_SA_CB<2>")
	)
	(gr_poly
		(pts
			(xy 78.969362 -243.47297) (xy 78.969362 -243.42852) (xy 78.769464 -243.42852) (xy 78.769464 -243.47297)
			(xy 78.86954 -243.573046)
		)
		(stroke
			(width 0)
			(type solid)
		)
		(fill yes)
		(layer "In4.Cu")
		(net "M_D_CPU1_SA_DQ<30>")
	)
	(gr_poly
		(pts
			(xy 78.969362 -240.232946) (xy 78.969362 -240.188496) (xy 78.769464 -240.188496) (xy 78.769464 -240.232946)
			(xy 78.86954 -240.333022)
		)
		(stroke
			(width 0)
			(type solid)
		)
		(fill yes)
		(layer "In4.Cu")
		(net "M_D_CPU1_SA_DQ<26>")
	)
	(gr_poly
		(pts
			(xy 78.969362 -238.612934) (xy 78.969362 -238.568484) (xy 78.769464 -238.568484) (xy 78.769464 -238.612934)
			(xy 78.86954 -238.71301)
		)
		(stroke
			(width 0)
			(type solid)
		)
		(fill yes)
		(layer "In4.Cu")
		(net "M_D_CPU1_SA_DQ<22>")
	)
	(gr_poly
		(pts
			(xy 78.969362 -237.395512) (xy 78.869286 -237.295436) (xy 78.769464 -237.395512) (xy 78.769464 -237.443264)
			(xy 78.969362 -237.443264)
		)
		(stroke
			(width 0)
			(type solid)
		)
		(fill yes)
		(layer "In4.Cu")
		(net "M_D_CPU1_SA_DQS_DN<7>")
	)
	(gr_poly
		(pts
			(xy 78.969362 -236.992922) (xy 78.969362 -236.945424) (xy 78.769464 -236.945424) (xy 78.769464 -236.992922)
			(xy 78.86954 -237.092998)
		)
		(stroke
			(width 0)
			(type solid)
		)
		(fill yes)
		(layer "In4.Cu")
		(net "M_D_CPU1_SA_DQS_DN<2>")
	)
	(gr_poly
		(pts
			(xy 78.97495 -251.572522) (xy 78.97495 -251.528072) (xy 78.774798 -251.528072) (xy 78.774798 -251.572522)
			(xy 78.874874 -251.672598)
		)
		(stroke
			(width 0)
			(type solid)
		)
		(fill yes)
		(layer "In4.Cu")
		(net "M_D_CPU1_SA_CS_N<0>")
	)
	(gr_poly
		(pts
			(xy 78.97495 -240.636298) (xy 78.874874 -240.536222) (xy 78.774798 -240.636298) (xy 78.774798 -240.680748)
			(xy 78.97495 -240.680748)
		)
		(stroke
			(width 0)
			(type solid)
		)
		(fill yes)
		(layer "In4.Cu")
		(net "M_D_CPU1_SA_DQ<25>")
	)
	(gr_poly
		(pts
			(xy 78.981046 -250.35637) (xy 78.88097 -250.256294) (xy 78.780894 -250.35637) (xy 78.780894 -250.40082)
			(xy 78.981046 -250.40082)
		)
		(stroke
			(width 0)
			(type solid)
		)
		(fill yes)
		(layer "In4.Cu")
		(net "M_D_CPU1_ALERT_R_N")
	)
	(gr_poly
		(pts
			(xy 78.981046 -241.852704) (xy 78.981046 -241.804952) (xy 78.780894 -241.804952) (xy 78.780894 -241.852704)
			(xy 78.88097 -241.952526)
		)
		(stroke
			(width 0)
			(type solid)
		)
		(fill yes)
		(layer "In4.Cu")
		(net "M_D_CPU1_SA_DQS_DN<3>")
	)
	(gr_poly
		(pts
			(xy 78.98384 -255.216406) (xy 78.883764 -255.11633) (xy 78.783688 -255.216406) (xy 78.783688 -255.260856)
			(xy 78.98384 -255.260856)
		)
		(stroke
			(width 0)
			(type solid)
		)
		(fill yes)
		(layer "In4.Cu")
		(net "M_D_CPU1_SA_CA<6>")
	)
	(gr_poly
		(pts
			(xy 78.98384 -253.596394) (xy 78.883764 -253.496318) (xy 78.783688 -253.596394) (xy 78.783688 -253.640844)
			(xy 78.98384 -253.640844)
		)
		(stroke
			(width 0)
			(type solid)
		)
		(fill yes)
		(layer "In4.Cu")
		(net "M_D_CPU1_SA_CA<2>")
	)
	(gr_poly
		(pts
			(xy 78.98384 -248.736358) (xy 78.883764 -248.636282) (xy 78.783688 -248.736358) (xy 78.783688 -248.780808)
			(xy 78.98384 -248.780808)
		)
		(stroke
			(width 0)
			(type solid)
		)
		(fill yes)
		(layer "In4.Cu")
		(net "M_D_CPU1_SA_CB<5>")
	)
	(gr_poly
		(pts
			(xy 78.98384 -245.496334) (xy 78.883764 -245.396258) (xy 78.783688 -245.496334) (xy 78.783688 -245.540784)
			(xy 78.98384 -245.540784)
		)
		(stroke
			(width 0)
			(type solid)
		)
		(fill yes)
		(layer "In4.Cu")
		(net "M_D_CPU1_SA_CB<1>")
	)
	(gr_poly
		(pts
			(xy 78.98384 -243.876322) (xy 78.883764 -243.776246) (xy 78.783688 -243.876322) (xy 78.783688 -243.920772)
			(xy 78.98384 -243.920772)
		)
		(stroke
			(width 0)
			(type solid)
		)
		(fill yes)
		(layer "In4.Cu")
		(net "M_D_CPU1_SA_DQ<29>")
	)
	(gr_poly
		(pts
			(xy 78.98892 -247.116092) (xy 78.888844 -247.01627) (xy 78.789022 -247.116092) (xy 78.789022 -247.163844)
			(xy 78.98892 -247.163844)
		)
		(stroke
			(width 0)
			(type solid)
		)
		(fill yes)
		(layer "In4.Cu")
		(net "M_D_CPU1_SA_DQS_DN<9>")
	)
	(gr_poly
		(pts
			(xy 78.99273 -242.256056) (xy 78.892654 -242.15598) (xy 78.792578 -242.256056) (xy 78.792578 -242.303554)
			(xy 78.99273 -242.303554)
		)
		(stroke
			(width 0)
			(type solid)
		)
		(fill yes)
		(layer "In4.Cu")
		(net "M_D_CPU1_SA_DQS_DN<8>")
	)
	(gr_poly
		(pts
			(xy 78.995524 -224.045272) (xy 79.043784 -223.91243) (xy 78.910942 -223.86417) (xy 78.870556 -223.882966)
			(xy 78.955138 -224.064068)
		)
		(stroke
			(width 0)
			(type solid)
		)
		(fill yes)
		(layer "In4.Cu")
		(net "M_D_CPU1_SA_DQ<4>")
	)
	(gr_poly
		(pts
			(xy 79.00035 -222.41637) (xy 79.036926 -222.279718) (xy 78.900274 -222.243142) (xy 78.859126 -222.266764)
			(xy 78.959202 -222.439992)
		)
		(stroke
			(width 0)
			(type solid)
		)
		(fill yes)
		(layer "In4.Cu")
		(net "M_D_CPU1_SA_DQS_DN<5>")
	)
	(gr_poly
		(pts
			(xy 79.000604 -225.656902) (xy 79.03718 -225.520504) (xy 78.900528 -225.483928) (xy 78.862174 -225.506026)
			(xy 78.96225 -225.679254)
		)
		(stroke
			(width 0)
			(type solid)
		)
		(fill yes)
		(layer "In4.Cu")
		(net "M_D_CPU1_SA_DQ<5>")
	)
	(gr_poly
		(pts
			(xy 79.200248 -293.177468) (xy 79.16164 -293.155116) (xy 79.025242 -293.191692) (xy 79.061818 -293.328344)
			(xy 79.100172 -293.350696)
		)
		(stroke
			(width 0)
			(type solid)
		)
		(fill yes)
		(layer "In4.Cu")
		(net "M_D_CPU1_SB_DQ<28>")
	)
	(gr_poly
		(pts
			(xy 79.267304 -283.60497) (xy 79.267304 -283.56052) (xy 79.067152 -283.56052) (xy 79.067152 -283.60497)
			(xy 79.167228 -283.705046)
		)
		(stroke
			(width 0)
			(type solid)
		)
		(fill yes)
		(layer "In4.Cu")
		(net "M_D_CPU1_SB_DQ<15>")
	)
	(gr_poly
		(pts
			(xy 79.27213 -287.248092) (xy 79.172308 -287.14827) (xy 79.072232 -287.248092) (xy 79.072232 -287.292542)
			(xy 79.27213 -287.292542)
		)
		(stroke
			(width 0)
			(type solid)
		)
		(fill yes)
		(layer "In4.Cu")
		(net "M_D_CPU1_SB_DQ<20>")
	)
	(gr_poly
		(pts
			(xy 79.275178 -285.62808) (xy 79.175356 -285.528004) (xy 79.07528 -285.62808) (xy 79.07528 -285.675578)
			(xy 79.275178 -285.675578)
		)
		(stroke
			(width 0)
			(type solid)
		)
		(fill yes)
		(layer "In4.Cu")
		(net "M_D_CPU1_SB_DQS_DP<2>")
	)
	(gr_poly
		(pts
			(xy 79.275178 -280.768044) (xy 79.175356 -280.667968) (xy 79.07528 -280.768044) (xy 79.07528 -280.815542)
			(xy 79.275178 -280.815542)
		)
		(stroke
			(width 0)
			(type solid)
		)
		(fill yes)
		(layer "In4.Cu")
		(net "M_D_CPU1_SB_DQS_DP<1>")
	)
	(gr_poly
		(pts
			(xy 79.28102 -288.464498) (xy 79.28102 -288.420048) (xy 79.080868 -288.420048) (xy 79.080868 -288.464498)
			(xy 79.180944 -288.564574)
		)
		(stroke
			(width 0)
			(type solid)
		)
		(fill yes)
		(layer "In4.Cu")
		(net "M_D_CPU1_SB_DQ<23>")
	)
	(gr_poly
		(pts
			(xy 79.283814 -290.084256) (xy 79.283814 -290.039806) (xy 79.083662 -290.039806) (xy 79.083662 -290.084256)
			(xy 79.183738 -290.184332)
		)
		(stroke
			(width 0)
			(type solid)
		)
		(fill yes)
		(layer "In4.Cu")
		(net "M_D_CPU1_SB_DQ<27>")
	)
	(gr_poly
		(pts
			(xy 79.283814 -286.844486) (xy 79.283814 -286.796988) (xy 79.083662 -286.796988) (xy 79.083662 -286.844486)
			(xy 79.183738 -286.944562)
		)
		(stroke
			(width 0)
			(type solid)
		)
		(fill yes)
		(layer "In4.Cu")
		(net "M_D_CPU1_SB_DQS_DP<7>")
	)
	(gr_poly
		(pts
			(xy 79.283814 -285.224474) (xy 79.283814 -285.180024) (xy 79.083662 -285.180024) (xy 79.083662 -285.224474)
			(xy 79.183738 -285.32455)
		)
		(stroke
			(width 0)
			(type solid)
		)
		(fill yes)
		(layer "In4.Cu")
		(net "M_D_CPU1_SB_DQ<19>")
	)
	(gr_poly
		(pts
			(xy 79.283814 -284.008322) (xy 79.183738 -283.908246) (xy 79.083662 -284.008322) (xy 79.083662 -284.052772)
			(xy 79.283814 -284.052772)
		)
		(stroke
			(width 0)
			(type solid)
		)
		(fill yes)
		(layer "In4.Cu")
		(net "M_D_CPU1_SB_DQ<16>")
	)
	(gr_poly
		(pts
			(xy 79.283814 -282.38831) (xy 79.183738 -282.288234) (xy 79.083662 -282.38831) (xy 79.083662 -282.43276)
			(xy 79.283814 -282.43276)
		)
		(stroke
			(width 0)
			(type solid)
		)
		(fill yes)
		(layer "In4.Cu")
		(net "M_D_CPU1_SB_DQ<12>")
	)
	(gr_poly
		(pts
			(xy 79.283814 -279.148286) (xy 79.183738 -279.04821) (xy 79.083662 -279.148286) (xy 79.083662 -279.192736)
			(xy 79.283814 -279.192736)
		)
		(stroke
			(width 0)
			(type solid)
		)
		(fill yes)
		(layer "In4.Cu")
		(net "M_D_CPU1_SB_DQ<8>")
	)
	(gr_poly
		(pts
			(xy 79.283814 -277.528274) (xy 79.183738 -277.428198) (xy 79.083662 -277.528274) (xy 79.083662 -277.572724)
			(xy 79.283814 -277.572724)
		)
		(stroke
			(width 0)
			(type solid)
		)
		(fill yes)
		(layer "In4.Cu")
		(net "M_D_CPU1_SB_DQ<4>")
	)
	(gr_poly
		(pts
			(xy 79.283814 -274.28825) (xy 79.183738 -274.188174) (xy 79.083662 -274.28825) (xy 79.083662 -274.3327)
			(xy 79.283814 -274.3327)
		)
		(stroke
			(width 0)
			(type solid)
		)
		(fill yes)
		(layer "In4.Cu")
		(net "M_D_CPU1_SB_DQ<0>")
	)
	(gr_poly
		(pts
			(xy 79.283814 -273.88439) (xy 79.283814 -273.83994) (xy 79.083662 -273.83994) (xy 79.083662 -273.88439)
			(xy 79.183738 -273.984466)
		)
		(stroke
			(width 0)
			(type solid)
		)
		(fill yes)
		(layer "In4.Cu")
		(net "M_D_CPU1_SB_CB<3>")
	)
	(gr_poly
		(pts
			(xy 79.283814 -272.668238) (xy 79.183738 -272.568162) (xy 79.083662 -272.668238) (xy 79.083662 -272.712688)
			(xy 79.283814 -272.712688)
		)
		(stroke
			(width 0)
			(type solid)
		)
		(fill yes)
		(layer "In4.Cu")
		(net "M_D_CPU1_SB_CB<0>")
	)
	(gr_poly
		(pts
			(xy 79.283814 -264.568178) (xy 79.183738 -264.468102) (xy 79.083662 -264.568178) (xy 79.083662 -264.612628)
			(xy 79.283814 -264.612628)
		)
		(stroke
			(width 0)
			(type solid)
		)
		(fill yes)
		(layer "In4.Cu")
		(net "M_D_CPU1_SB_CA<6>")
	)
	(gr_poly
		(pts
			(xy 79.28991 -288.86785) (xy 79.189834 -288.768028) (xy 79.089758 -288.86785) (xy 79.089758 -288.9123)
			(xy 79.28991 -288.9123)
		)
		(stroke
			(width 0)
			(type solid)
		)
		(fill yes)
		(layer "In4.Cu")
		(net "M_D_CPU1_SB_DQ<24>")
	)
	(gr_poly
		(pts
			(xy 79.28991 -269.42796) (xy 79.189834 -269.328138) (xy 79.089758 -269.42796) (xy 79.089758 -269.47241)
			(xy 79.28991 -269.47241)
		)
		(stroke
			(width 0)
			(type solid)
		)
		(fill yes)
		(layer "In4.Cu")
		(net "M_D_CPU1_SB_CB<4>")
	)
	(gr_poly
		(pts
			(xy 79.29499 -267.801344) (xy 79.194914 -267.701268) (xy 79.095092 -267.801344) (xy 79.095092 -267.845794)
			(xy 79.29499 -267.845794)
		)
		(stroke
			(width 0)
			(type solid)
		)
		(fill yes)
		(layer "In4.Cu")
		(net "M_D_CPU1_SB_RSP<0>")
	)
	(gr_poly
		(pts
			(xy 79.3369 -295.481502) (xy 79.300324 -295.34485) (xy 79.261716 -295.322498) (xy 79.161894 -295.495726)
			(xy 79.200248 -295.518078)
		)
		(stroke
			(width 0)
			(type solid)
		)
		(fill yes)
		(layer "In4.Cu")
		(net "M_D_CPU1_SB_DQ<30>")
	)
	(gr_poly
		(pts
			(xy 79.36992 -225.392742) (xy 79.269844 -225.219514) (xy 79.23149 -225.241866) (xy 79.194914 -225.378264)
			(xy 79.331312 -225.41484)
		)
		(stroke
			(width 0)
			(type solid)
		)
		(fill yes)
		(layer "In4.Cu")
		(net "M_D_CPU1_SA_DQ<6>")
	)
	(gr_poly
		(pts
			(xy 79.372968 -223.771968) (xy 79.273146 -223.59874) (xy 79.231744 -223.622362) (xy 79.195168 -223.759014)
			(xy 79.33182 -223.79559)
		)
		(stroke
			(width 0)
			(type solid)
		)
		(fill yes)
		(layer "In4.Cu")
		(net "M_D_CPU1_SA_DQS_DP<5>")
	)
	(gr_poly
		(pts
			(xy 79.437992 -246.30634) (xy 79.33817 -246.206264) (xy 79.238094 -246.30634) (xy 79.238094 -246.353838)
			(xy 79.437992 -246.353838)
		)
		(stroke
			(width 0)
			(type solid)
		)
		(fill yes)
		(layer "In4.Cu")
		(net "M_D_CPU1_SA_DQS_DP<4>")
	)
	(gr_poly
		(pts
			(xy 79.437992 -236.586268) (xy 79.33817 -236.486192) (xy 79.238094 -236.586268) (xy 79.238094 -236.633766)
			(xy 79.437992 -236.633766)
		)
		(stroke
			(width 0)
			(type solid)
		)
		(fill yes)
		(layer "In4.Cu")
		(net "M_D_CPU1_SA_DQS_DP<2>")
	)
	(gr_poly
		(pts
			(xy 79.439262 -239.422432) (xy 79.439262 -239.377728) (xy 79.239364 -239.377728) (xy 79.239364 -239.422432)
			(xy 79.339186 -239.522254)
		)
		(stroke
			(width 0)
			(type solid)
		)
		(fill yes)
		(layer "In4.Cu")
		(net "M_D_CPU1_SA_DQ<23>")
	)
	(gr_poly
		(pts
			(xy 79.440278 -254.406654) (xy 79.340202 -254.306578) (xy 79.240126 -254.406654) (xy 79.240126 -254.451104)
			(xy 79.440278 -254.451104)
		)
		(stroke
			(width 0)
			(type solid)
		)
		(fill yes)
		(layer "In4.Cu")
		(net "M_D_CPU1_SA_CA<4>")
	)
	(gr_poly
		(pts
			(xy 79.440278 -252.786642) (xy 79.340202 -252.686566) (xy 79.240126 -252.786642) (xy 79.240126 -252.831092)
			(xy 79.440278 -252.831092)
		)
		(stroke
			(width 0)
			(type solid)
		)
		(fill yes)
		(layer "In4.Cu")
		(net "M_D_CPU1_SA_CA<0>")
	)
	(gr_poly
		(pts
			(xy 79.440278 -247.926606) (xy 79.340202 -247.82653) (xy 79.240126 -247.926606) (xy 79.240126 -247.971056)
			(xy 79.440278 -247.971056)
		)
		(stroke
			(width 0)
			(type solid)
		)
		(fill yes)
		(layer "In4.Cu")
		(net "M_D_CPU1_SA_CB<4>")
	)
	(gr_poly
		(pts
			(xy 79.440278 -244.686582) (xy 79.340202 -244.586506) (xy 79.240126 -244.686582) (xy 79.240126 -244.731032)
			(xy 79.440278 -244.731032)
		)
		(stroke
			(width 0)
			(type solid)
		)
		(fill yes)
		(layer "In4.Cu")
		(net "M_D_CPU1_SA_CB<0>")
	)
	(gr_poly
		(pts
			(xy 79.440278 -243.06657) (xy 79.340202 -242.966494) (xy 79.240126 -243.06657) (xy 79.240126 -243.11102)
			(xy 79.440278 -243.11102)
		)
		(stroke
			(width 0)
			(type solid)
		)
		(fill yes)
		(layer "In4.Cu")
		(net "M_D_CPU1_SA_DQ<28>")
	)
	(gr_poly
		(pts
			(xy 79.440278 -239.826546) (xy 79.340202 -239.72647) (xy 79.240126 -239.826546) (xy 79.240126 -239.870996)
			(xy 79.440278 -239.870996)
		)
		(stroke
			(width 0)
			(type solid)
		)
		(fill yes)
		(layer "In4.Cu")
		(net "M_D_CPU1_SA_DQ<24>")
	)
	(gr_poly
		(pts
			(xy 79.440278 -238.206534) (xy 79.340202 -238.106458) (xy 79.240126 -238.206534) (xy 79.240126 -238.250984)
			(xy 79.440278 -238.250984)
		)
		(stroke
			(width 0)
			(type solid)
		)
		(fill yes)
		(layer "In4.Cu")
		(net "M_D_CPU1_SA_DQ<20>")
	)
	(gr_poly
		(pts
			(xy 79.44231 -242.662964) (xy 79.44231 -242.615212) (xy 79.242412 -242.615212) (xy 79.242412 -242.662964)
			(xy 79.342488 -242.762786)
		)
		(stroke
			(width 0)
			(type solid)
		)
		(fill yes)
		(layer "In4.Cu")
		(net "M_D_CPU1_SA_DQS_DP<8>")
	)
	(gr_poly
		(pts
			(xy 79.4512 -250.762516) (xy 79.4512 -250.718066) (xy 79.251048 -250.718066) (xy 79.251048 -250.762516)
			(xy 79.351124 -250.862592)
		)
		(stroke
			(width 0)
			(type solid)
		)
		(fill yes)
		(layer "In4.Cu")
		(net "M_D_CPU1_RESET_N")
	)
	(gr_poly
		(pts
			(xy 79.4512 -241.44605) (xy 79.351124 -241.346228) (xy 79.251048 -241.44605) (xy 79.251048 -241.493802)
			(xy 79.4512 -241.493802)
		)
		(stroke
			(width 0)
			(type solid)
		)
		(fill yes)
		(layer "In4.Cu")
		(net "M_D_CPU1_SA_DQS_DP<3>")
	)
	(gr_poly
		(pts
			(xy 79.456534 -255.622552) (xy 79.456534 -255.578102) (xy 79.256382 -255.578102) (xy 79.256382 -255.622552)
			(xy 79.356458 -255.722628)
		)
		(stroke
			(width 0)
			(type solid)
		)
		(fill yes)
		(layer "In4.Cu")
		(net "M_D_CPU1_SA_PAR")
	)
	(gr_poly
		(pts
			(xy 79.456534 -254.00254) (xy 79.456534 -253.95809) (xy 79.256382 -253.95809) (xy 79.256382 -254.00254)
			(xy 79.356458 -254.102616)
		)
		(stroke
			(width 0)
			(type solid)
		)
		(fill yes)
		(layer "In4.Cu")
		(net "M_D_CPU1_SA_CA<3>")
	)
	(gr_poly
		(pts
			(xy 79.456534 -252.382528) (xy 79.456534 -252.338078) (xy 79.256382 -252.338078) (xy 79.256382 -252.382528)
			(xy 79.356458 -252.482604)
		)
		(stroke
			(width 0)
			(type solid)
		)
		(fill yes)
		(layer "In4.Cu")
		(net "M_D_CPU1_SA_CS_N<1>")
	)
	(gr_poly
		(pts
			(xy 79.456534 -249.142504) (xy 79.456534 -249.098054) (xy 79.256382 -249.098054) (xy 79.256382 -249.142504)
			(xy 79.356458 -249.24258)
		)
		(stroke
			(width 0)
			(type solid)
		)
		(fill yes)
		(layer "In4.Cu")
		(net "M_D_CPU1_SA_CB<7>")
	)
	(gr_poly
		(pts
			(xy 79.456534 -247.522746) (xy 79.456534 -247.475248) (xy 79.256382 -247.475248) (xy 79.256382 -247.522746)
			(xy 79.356458 -247.622822)
		)
		(stroke
			(width 0)
			(type solid)
		)
		(fill yes)
		(layer "In4.Cu")
		(net "M_D_CPU1_SA_DQS_DP<9>")
	)
	(gr_poly
		(pts
			(xy 79.456534 -245.90248) (xy 79.456534 -245.85803) (xy 79.256382 -245.85803) (xy 79.256382 -245.90248)
			(xy 79.356458 -246.002556)
		)
		(stroke
			(width 0)
			(type solid)
		)
		(fill yes)
		(layer "In4.Cu")
		(net "M_D_CPU1_SA_CB<3>")
	)
	(gr_poly
		(pts
			(xy 79.456534 -244.282468) (xy 79.456534 -244.238018) (xy 79.256382 -244.238018) (xy 79.256382 -244.282468)
			(xy 79.356458 -244.382544)
		)
		(stroke
			(width 0)
			(type solid)
		)
		(fill yes)
		(layer "In4.Cu")
		(net "M_D_CPU1_SA_DQ<31>")
	)
	(gr_poly
		(pts
			(xy 79.459074 -241.042444) (xy 79.459074 -240.997994) (xy 79.259176 -240.997994) (xy 79.259176 -241.042444)
			(xy 79.358998 -241.14252)
		)
		(stroke
			(width 0)
			(type solid)
		)
		(fill yes)
		(layer "In4.Cu")
		(net "M_D_CPU1_SA_DQ<27>")
	)
	(gr_poly
		(pts
			(xy 79.464916 -223.235266) (xy 79.51343 -223.102424) (xy 79.380334 -223.05391) (xy 79.337408 -223.07423)
			(xy 79.421736 -223.255332)
		)
		(stroke
			(width 0)
			(type solid)
		)
		(fill yes)
		(layer "In4.Cu")
		(net "M_D_CPU1_SA_DQS_DN<5>")
	)
	(gr_poly
		(pts
			(xy 79.46644 -256.026412) (xy 79.366364 -255.926336) (xy 79.266542 -256.026412) (xy 79.266542 -256.07391)
			(xy 79.46644 -256.07391)
		)
		(stroke
			(width 0)
			(type solid)
		)
		(fill yes)
		(layer "In4.Cu")
		(net "M_D_CPU1_CLK_DP<0>")
	)
	(gr_poly
		(pts
			(xy 79.469742 -226.465892) (xy 79.506318 -226.32924) (xy 79.369666 -226.292664) (xy 79.331312 -226.314762)
			(xy 79.431388 -226.48799)
		)
		(stroke
			(width 0)
			(type solid)
		)
		(fill yes)
		(layer "In4.Cu")
		(net "M_D_CPU1_SA_DQ<5>")
	)
	(gr_poly
		(pts
			(xy 79.469996 -224.84588) (xy 79.506572 -224.709228) (xy 79.36992 -224.672652) (xy 79.331566 -224.695004)
			(xy 79.431642 -224.868232)
		)
		(stroke
			(width 0)
			(type solid)
		)
		(fill yes)
		(layer "In4.Cu")
		(net "M_D_CPU1_SA_DQ<4>")
	)
	(gr_poly
		(pts
			(xy 79.670148 -292.367462) (xy 79.63154 -292.34511) (xy 79.495142 -292.381686) (xy 79.531718 -292.518338)
			(xy 79.570072 -292.54069)
		)
		(stroke
			(width 0)
			(type solid)
		)
		(fill yes)
		(layer "In4.Cu")
		(net "M_D_CPU1_SB_DQ<28>")
	)
	(gr_poly
		(pts
			(xy 79.670402 -295.607486) (xy 79.631794 -295.585134) (xy 79.495142 -295.62171) (xy 79.531972 -295.758362)
			(xy 79.570326 -295.780714)
		)
		(stroke
			(width 0)
			(type solid)
		)
		(fill yes)
		(layer "In4.Cu")
		(net "M_D_CPU1_SB_DQ<29>")
	)
	(gr_poly
		(pts
			(xy 79.739236 -283.198316) (xy 79.63916 -283.098494) (xy 79.539338 -283.198316) (xy 79.539338 -283.24302)
			(xy 79.739236 -283.24302)
		)
		(stroke
			(width 0)
			(type solid)
		)
		(fill yes)
		(layer "In4.Cu")
		(net "M_D_CPU1_SB_DQ<13>")
	)
	(gr_poly
		(pts
			(xy 79.742284 -289.274504) (xy 79.742284 -289.230054) (xy 79.542386 -289.230054) (xy 79.542386 -289.274504)
			(xy 79.642462 -289.37458)
		)
		(stroke
			(width 0)
			(type solid)
		)
		(fill yes)
		(layer "In4.Cu")
		(net "M_D_CPU1_SB_DQ<26>")
	)
	(gr_poly
		(pts
			(xy 79.742284 -269.834614) (xy 79.742284 -269.790164) (xy 79.542386 -269.790164) (xy 79.542386 -269.834614)
			(xy 79.642462 -269.934436)
		)
		(stroke
			(width 0)
			(type solid)
		)
		(fill yes)
		(layer "In4.Cu")
		(net "M_D_CPU1_SB_CB<6>")
	)
	(gr_poly
		(pts
			(xy 79.745078 -286.034734) (xy 79.745078 -285.986982) (xy 79.54518 -285.986982) (xy 79.54518 -286.034734)
			(xy 79.645256 -286.134556)
		)
		(stroke
			(width 0)
			(type solid)
		)
		(fill yes)
		(layer "In4.Cu")
		(net "M_D_CPU1_SB_DQS_DN<2>")
	)
	(gr_poly
		(pts
			(xy 79.745078 -281.174698) (xy 79.745078 -281.126946) (xy 79.54518 -281.126946) (xy 79.54518 -281.174698)
			(xy 79.645256 -281.27452)
		)
		(stroke
			(width 0)
			(type solid)
		)
		(fill yes)
		(layer "In4.Cu")
		(net "M_D_CPU1_SB_DQS_DN<1>")
	)
	(gr_poly
		(pts
			(xy 79.751174 -288.058098) (xy 79.651098 -287.958022) (xy 79.551022 -288.058098) (xy 79.551022 -288.102548)
			(xy 79.751174 -288.102548)
		)
		(stroke
			(width 0)
			(type solid)
		)
		(fill yes)
		(layer "In4.Cu")
		(net "M_D_CPU1_SB_DQ<21>")
	)
	(gr_poly
		(pts
			(xy 79.756508 -284.414468) (xy 79.756508 -284.370018) (xy 79.55661 -284.370018) (xy 79.55661 -284.414468)
			(xy 79.656432 -284.514544)
		)
		(stroke
			(width 0)
			(type solid)
		)
		(fill yes)
		(layer "In4.Cu")
		(net "M_D_CPU1_SB_DQ<18>")
	)
	(gr_poly
		(pts
			(xy 79.756508 -282.794456) (xy 79.756508 -282.750006) (xy 79.55661 -282.750006) (xy 79.55661 -282.794456)
			(xy 79.656432 -282.894532)
		)
		(stroke
			(width 0)
			(type solid)
		)
		(fill yes)
		(layer "In4.Cu")
		(net "M_D_CPU1_SB_DQ<14>")
	)
	(gr_poly
		(pts
			(xy 79.756508 -279.554432) (xy 79.756508 -279.509982) (xy 79.55661 -279.509982) (xy 79.55661 -279.554432)
			(xy 79.656432 -279.654508)
		)
		(stroke
			(width 0)
			(type solid)
		)
		(fill yes)
		(layer "In4.Cu")
		(net "M_D_CPU1_SB_DQ<10>")
	)
	(gr_poly
		(pts
			(xy 79.756508 -277.93442) (xy 79.756508 -277.88997) (xy 79.55661 -277.88997) (xy 79.55661 -277.93442)
			(xy 79.656432 -278.034496)
		)
		(stroke
			(width 0)
			(type solid)
		)
		(fill yes)
		(layer "In4.Cu")
		(net "M_D_CPU1_SB_DQ<6>")
	)
	(gr_poly
		(pts
			(xy 79.756508 -274.694396) (xy 79.756508 -274.649946) (xy 79.55661 -274.649946) (xy 79.55661 -274.694396)
			(xy 79.656432 -274.794472)
		)
		(stroke
			(width 0)
			(type solid)
		)
		(fill yes)
		(layer "In4.Cu")
		(net "M_D_CPU1_SB_DQ<2>")
	)
	(gr_poly
		(pts
			(xy 79.756508 -273.074384) (xy 79.756508 -273.029934) (xy 79.55661 -273.029934) (xy 79.55661 -273.074384)
			(xy 79.656432 -273.17446)
		)
		(stroke
			(width 0)
			(type solid)
		)
		(fill yes)
		(layer "In4.Cu")
		(net "M_D_CPU1_SB_CB<2>")
	)
	(gr_poly
		(pts
			(xy 79.756508 -264.974324) (xy 79.756508 -264.929874) (xy 79.55661 -264.929874) (xy 79.55661 -264.974324)
			(xy 79.656432 -265.0744)
		)
		(stroke
			(width 0)
			(type solid)
		)
		(fill yes)
		(layer "In4.Cu")
		(net "M_D_CPU1_SB_PAR")
	)
	(gr_poly
		(pts
			(xy 79.758794 -289.677856) (xy 79.658718 -289.57778) (xy 79.558896 -289.677856) (xy 79.558896 -289.722306)
			(xy 79.758794 -289.722306)
		)
		(stroke
			(width 0)
			(type solid)
		)
		(fill yes)
		(layer "In4.Cu")
		(net "M_D_CPU1_SB_DQ<25>")
	)
	(gr_poly
		(pts
			(xy 79.758794 -286.437832) (xy 79.658718 -286.337756) (xy 79.558896 -286.437832) (xy 79.558896 -286.485584)
			(xy 79.758794 -286.485584)
		)
		(stroke
			(width 0)
			(type solid)
		)
		(fill yes)
		(layer "In4.Cu")
		(net "M_D_CPU1_SB_DQS_DN<7>")
	)
	(gr_poly
		(pts
			(xy 79.758794 -284.818074) (xy 79.658718 -284.718252) (xy 79.558896 -284.818074) (xy 79.558896 -284.862524)
			(xy 79.758794 -284.862524)
		)
		(stroke
			(width 0)
			(type solid)
		)
		(fill yes)
		(layer "In4.Cu")
		(net "M_D_CPU1_SB_DQ<17>")
	)
	(gr_poly
		(pts
			(xy 79.758794 -273.47799) (xy 79.658718 -273.378168) (xy 79.558896 -273.47799) (xy 79.558896 -273.52244)
			(xy 79.758794 -273.52244)
		)
		(stroke
			(width 0)
			(type solid)
		)
		(fill yes)
		(layer "In4.Cu")
		(net "M_D_CPU1_SB_CB<1>")
	)
	(gr_poly
		(pts
			(xy 79.76108 -287.654492) (xy 79.76108 -287.610042) (xy 79.561182 -287.610042) (xy 79.561182 -287.654492)
			(xy 79.661004 -287.754568)
		)
		(stroke
			(width 0)
			(type solid)
		)
		(fill yes)
		(layer "In4.Cu")
		(net "M_D_CPU1_SB_DQ<22>")
	)
	(gr_poly
		(pts
			(xy 79.806546 -294.672004) (xy 79.76997 -294.535352) (xy 79.731362 -294.513254) (xy 79.631286 -294.686482)
			(xy 79.669894 -294.70858)
		)
		(stroke
			(width 0)
			(type solid)
		)
		(fill yes)
		(layer "In4.Cu")
		(net "M_D_CPU1_SB_DQ<30>")
	)
	(gr_poly
		(pts
			(xy 79.840328 -231.063292) (xy 79.740252 -230.890064) (xy 79.701898 -230.912416) (xy 79.665322 -231.049068)
			(xy 79.80172 -231.085644)
		)
		(stroke
			(width 0)
			(type solid)
		)
		(fill yes)
		(layer "In4.Cu")
		(net "M_D_CPU1_SA_DQ<11>")
	)
	(gr_poly
		(pts
			(xy 79.841344 -226.20478) (xy 79.741268 -226.031552) (xy 79.70266 -226.05365) (xy 79.666084 -226.190302)
			(xy 79.802736 -226.226878)
		)
		(stroke
			(width 0)
			(type solid)
		)
		(fill yes)
		(layer "In4.Cu")
		(net "M_D_CPU1_SA_DQ<6>")
	)
	(gr_poly
		(pts
			(xy 79.843376 -222.96247) (xy 79.743554 -222.789242) (xy 79.702152 -222.813118) (xy 79.665576 -222.949516)
			(xy 79.802228 -222.986092)
		)
		(stroke
			(width 0)
			(type solid)
		)
		(fill yes)
		(layer "In4.Cu")
		(net "M_D_CPU1_SA_DQS_DN<0>")
	)
	(gr_poly
		(pts
			(xy 79.844138 -224.583752) (xy 79.744316 -224.410524) (xy 79.702914 -224.4344) (xy 79.666338 -224.571052)
			(xy 79.80299 -224.607628)
		)
		(stroke
			(width 0)
			(type solid)
		)
		(fill yes)
		(layer "In4.Cu")
		(net "M_D_CPU1_SA_DQS_DP<5>")
	)
	(gr_poly
		(pts
			(xy 79.91475 -255.216406) (xy 79.814928 -255.11633) (xy 79.714852 -255.216406) (xy 79.714852 -255.260856)
			(xy 79.91475 -255.260856)
		)
		(stroke
			(width 0)
			(type solid)
		)
		(fill yes)
		(layer "In4.Cu")
		(net "M_D_CPU1_SA_CA<6>")
	)
	(gr_poly
		(pts
			(xy 79.91475 -253.596394) (xy 79.814928 -253.496318) (xy 79.714852 -253.596394) (xy 79.714852 -253.640844)
			(xy 79.91475 -253.640844)
		)
		(stroke
			(width 0)
			(type solid)
		)
		(fill yes)
		(layer "In4.Cu")
		(net "M_D_CPU1_SA_CA<2>")
	)
	(gr_poly
		(pts
			(xy 79.91475 -251.572522) (xy 79.91475 -251.528072) (xy 79.714852 -251.528072) (xy 79.714852 -251.572522)
			(xy 79.814928 -251.672598)
		)
		(stroke
			(width 0)
			(type solid)
		)
		(fill yes)
		(layer "In4.Cu")
		(net "M_D_CPU1_SA_CS_N<0>")
	)
	(gr_poly
		(pts
			(xy 79.91475 -248.736358) (xy 79.814928 -248.636282) (xy 79.714852 -248.736358) (xy 79.714852 -248.780808)
			(xy 79.91475 -248.780808)
		)
		(stroke
			(width 0)
			(type solid)
		)
		(fill yes)
		(layer "In4.Cu")
		(net "M_D_CPU1_SA_CB<5>")
	)
	(gr_poly
		(pts
			(xy 79.91475 -247.116092) (xy 79.814928 -247.016016) (xy 79.714852 -247.116092) (xy 79.714852 -247.16359)
			(xy 79.91475 -247.16359)
		)
		(stroke
			(width 0)
			(type solid)
		)
		(fill yes)
		(layer "In4.Cu")
		(net "M_D_CPU1_SA_DQS_DN<9>")
	)
	(gr_poly
		(pts
			(xy 79.91475 -245.496334) (xy 79.814928 -245.396258) (xy 79.714852 -245.496334) (xy 79.714852 -245.540784)
			(xy 79.91475 -245.540784)
		)
		(stroke
			(width 0)
			(type solid)
		)
		(fill yes)
		(layer "In4.Cu")
		(net "M_D_CPU1_SA_CB<1>")
	)
	(gr_poly
		(pts
			(xy 79.91475 -243.876322) (xy 79.814928 -243.776246) (xy 79.714852 -243.876322) (xy 79.714852 -243.920772)
			(xy 79.91475 -243.920772)
		)
		(stroke
			(width 0)
			(type solid)
		)
		(fill yes)
		(layer "In4.Cu")
		(net "M_D_CPU1_SA_DQ<29>")
	)
	(gr_poly
		(pts
			(xy 79.91475 -240.636298) (xy 79.814928 -240.536222) (xy 79.714852 -240.636298) (xy 79.714852 -240.680748)
			(xy 79.91475 -240.680748)
		)
		(stroke
			(width 0)
			(type solid)
		)
		(fill yes)
		(layer "In4.Cu")
		(net "M_D_CPU1_SA_DQ<25>")
	)
	(gr_poly
		(pts
			(xy 79.91475 -235.776262) (xy 79.814928 -235.676186) (xy 79.714852 -235.776262) (xy 79.714852 -235.820712)
			(xy 79.91475 -235.820712)
		)
		(stroke
			(width 0)
			(type solid)
		)
		(fill yes)
		(layer "In4.Cu")
		(net "M_D_CPU1_SA_DQ<17>")
	)
	(gr_poly
		(pts
			(xy 79.9211 -256.432812) (xy 79.9211 -256.38506) (xy 79.720948 -256.38506) (xy 79.720948 -256.432812)
			(xy 79.821024 -256.532634)
		)
		(stroke
			(width 0)
			(type solid)
		)
		(fill yes)
		(layer "In4.Cu")
		(net "M_D_CPU1_CLK_DN<0>")
	)
	(gr_poly
		(pts
			(xy 79.9211 -250.35637) (xy 79.821024 -250.256294) (xy 79.720948 -250.35637) (xy 79.720948 -250.40082)
			(xy 79.9211 -250.40082)
		)
		(stroke
			(width 0)
			(type solid)
		)
		(fill yes)
		(layer "In4.Cu")
		(net "M_D_CPU1_ALERT_R_N")
	)
	(gr_poly
		(pts
			(xy 79.9211 -242.256056) (xy 79.821024 -242.156234) (xy 79.720948 -242.256056) (xy 79.720948 -242.303808)
			(xy 79.9211 -242.303808)
		)
		(stroke
			(width 0)
			(type solid)
		)
		(fill yes)
		(layer "In4.Cu")
		(net "M_D_CPU1_SA_DQS_DN<8>")
	)
	(gr_poly
		(pts
			(xy 79.9211 -241.852704) (xy 79.9211 -241.804952) (xy 79.720948 -241.804952) (xy 79.720948 -241.852704)
			(xy 79.821024 -241.952526)
		)
		(stroke
			(width 0)
			(type solid)
		)
		(fill yes)
		(layer "In4.Cu")
		(net "M_D_CPU1_SA_DQS_DN<3>")
	)
	(gr_poly
		(pts
			(xy 79.9211 -232.132632) (xy 79.9211 -232.08488) (xy 79.720948 -232.08488) (xy 79.720948 -232.132632)
			(xy 79.821024 -232.232454)
		)
		(stroke
			(width 0)
			(type solid)
		)
		(fill yes)
		(layer "In4.Cu")
		(net "M_D_CPU1_SA_DQS_DN<1>")
	)
	(gr_poly
		(pts
			(xy 79.934308 -254.812292) (xy 79.934308 -254.767842) (xy 79.734156 -254.767842) (xy 79.734156 -254.812292)
			(xy 79.834232 -254.912368)
		)
		(stroke
			(width 0)
			(type solid)
		)
		(fill yes)
		(layer "In4.Cu")
		(net "M_D_CPU1_SA_CA<5>")
	)
	(gr_poly
		(pts
			(xy 79.934308 -253.19228) (xy 79.934308 -253.14783) (xy 79.734156 -253.14783) (xy 79.734156 -253.19228)
			(xy 79.834232 -253.292356)
		)
		(stroke
			(width 0)
			(type solid)
		)
		(fill yes)
		(layer "In4.Cu")
		(net "M_D_CPU1_SA_CA<1>")
	)
	(gr_poly
		(pts
			(xy 79.934308 -248.332244) (xy 79.934308 -248.287794) (xy 79.734156 -248.287794) (xy 79.734156 -248.332244)
			(xy 79.834232 -248.43232)
		)
		(stroke
			(width 0)
			(type solid)
		)
		(fill yes)
		(layer "In4.Cu")
		(net "M_D_CPU1_SA_CB<6>")
	)
	(gr_poly
		(pts
			(xy 79.934308 -245.09222) (xy 79.934308 -245.04777) (xy 79.734156 -245.04777) (xy 79.734156 -245.09222)
			(xy 79.834232 -245.192296)
		)
		(stroke
			(width 0)
			(type solid)
		)
		(fill yes)
		(layer "In4.Cu")
		(net "M_D_CPU1_SA_CB<2>")
	)
	(gr_poly
		(pts
			(xy 79.934308 -243.472208) (xy 79.934308 -243.427758) (xy 79.734156 -243.427758) (xy 79.734156 -243.472208)
			(xy 79.834232 -243.572284)
		)
		(stroke
			(width 0)
			(type solid)
		)
		(fill yes)
		(layer "In4.Cu")
		(net "M_D_CPU1_SA_DQ<30>")
	)
	(gr_poly
		(pts
			(xy 79.934308 -240.232184) (xy 79.934308 -240.187734) (xy 79.734156 -240.187734) (xy 79.734156 -240.232184)
			(xy 79.834232 -240.33226)
		)
		(stroke
			(width 0)
			(type solid)
		)
		(fill yes)
		(layer "In4.Cu")
		(net "M_D_CPU1_SA_DQ<26>")
	)
	(gr_poly
		(pts
			(xy 79.934308 -238.612172) (xy 79.934308 -238.567722) (xy 79.734156 -238.567722) (xy 79.734156 -238.612172)
			(xy 79.834232 -238.712248)
		)
		(stroke
			(width 0)
			(type solid)
		)
		(fill yes)
		(layer "In4.Cu")
		(net "M_D_CPU1_SA_DQ<22>")
	)
	(gr_poly
		(pts
			(xy 79.934308 -235.372148) (xy 79.934308 -235.327698) (xy 79.734156 -235.327698) (xy 79.734156 -235.372148)
			(xy 79.834232 -235.472224)
		)
		(stroke
			(width 0)
			(type solid)
		)
		(fill yes)
		(layer "In4.Cu")
		(net "M_D_CPU1_SA_DQ<18>")
	)
	(gr_poly
		(pts
			(xy 79.934308 -233.752136) (xy 79.934308 -233.707686) (xy 79.734156 -233.707686) (xy 79.734156 -233.752136)
			(xy 79.834232 -233.852212)
		)
		(stroke
			(width 0)
			(type solid)
		)
		(fill yes)
		(layer "In4.Cu")
		(net "M_D_CPU1_SA_DQ<14>")
	)
	(gr_poly
		(pts
			(xy 79.935578 -239.01654) (xy 79.835756 -238.916464) (xy 79.73568 -239.01654) (xy 79.73568 -239.060736)
			(xy 79.935578 -239.060736)
		)
		(stroke
			(width 0)
			(type solid)
		)
		(fill yes)
		(layer "In4.Cu")
		(net "M_D_CPU1_SA_DQ<21>")
	)
	(gr_poly
		(pts
			(xy 79.93634 -246.712486) (xy 79.93634 -246.664988) (xy 79.736442 -246.664988) (xy 79.736442 -246.712486)
			(xy 79.836264 -246.812562)
		)
		(stroke
			(width 0)
			(type solid)
		)
		(fill yes)
		(layer "In4.Cu")
		(net "M_D_CPU1_SA_DQS_DN<4>")
	)
	(gr_poly
		(pts
			(xy 79.93634 -236.992414) (xy 79.93634 -236.944916) (xy 79.736442 -236.944916) (xy 79.736442 -236.992414)
			(xy 79.836264 -237.09249)
		)
		(stroke
			(width 0)
			(type solid)
		)
		(fill yes)
		(layer "In4.Cu")
		(net "M_D_CPU1_SA_DQS_DN<2>")
	)
	(gr_poly
		(pts
			(xy 79.939388 -227.274882) (xy 79.975964 -227.138484) (xy 79.839312 -227.101654) (xy 79.800704 -227.124006)
			(xy 79.90078 -227.297234)
		)
		(stroke
			(width 0)
			(type solid)
		)
		(fill yes)
		(layer "In4.Cu")
		(net "M_D_CPU1_SA_DQ<5>")
	)
	(gr_poly
		(pts
			(xy 79.939642 -224.03562) (xy 79.976472 -223.898968) (xy 79.83982 -223.862392) (xy 79.798418 -223.886268)
			(xy 79.898494 -224.059496)
		)
		(stroke
			(width 0)
			(type solid)
		)
		(fill yes)
		(layer "In4.Cu")
		(net "M_D_CPU1_SA_DQS_DN<5>")
	)
	(gr_poly
		(pts
			(xy 79.939896 -230.515414) (xy 79.976472 -230.378762) (xy 79.83982 -230.342186) (xy 79.801212 -230.364284)
			(xy 79.901288 -230.537512)
		)
		(stroke
			(width 0)
			(type solid)
		)
		(fill yes)
		(layer "In4.Cu")
		(net "M_D_CPU1_SA_DQ<9>")
	)
	(gr_poly
		(pts
			(xy 79.94015 -225.655886) (xy 79.976726 -225.519234) (xy 79.840074 -225.482658) (xy 79.80172 -225.50501)
			(xy 79.901542 -225.678238)
		)
		(stroke
			(width 0)
			(type solid)
		)
		(fill yes)
		(layer "In4.Cu")
		(net "M_D_CPU1_SA_DQ<4>")
	)
	(gr_poly
		(pts
			(xy 79.940404 -228.896672) (xy 79.977234 -228.76002) (xy 79.840582 -228.723444) (xy 79.801974 -228.745796)
			(xy 79.90205 -228.919024)
		)
		(stroke
			(width 0)
			(type solid)
		)
		(fill yes)
		(layer "In4.Cu")
		(net "M_D_CPU1_SA_DQ<8>")
	)
	(gr_poly
		(pts
			(xy 79.940912 -222.416624) (xy 79.977488 -222.279972) (xy 79.840836 -222.243396) (xy 79.799688 -222.267272)
			(xy 79.89951 -222.4405)
		)
		(stroke
			(width 0)
			(type solid)
		)
		(fill yes)
		(layer "In4.Cu")
		(net "M_D_CPU1_SA_DQS_DP<0>")
	)
	(gr_poly
		(pts
			(xy 80.141318 -294.795956) (xy 80.10271 -294.773858) (xy 79.966058 -294.810434) (xy 80.002634 -294.947086)
			(xy 80.041242 -294.969184)
		)
		(stroke
			(width 0)
			(type solid)
		)
		(fill yes)
		(layer "In4.Cu")
		(net "M_D_CPU1_SB_DQ<29>")
	)
	(gr_poly
		(pts
			(xy 80.212184 -290.08451) (xy 80.212184 -290.04006) (xy 80.012286 -290.04006) (xy 80.012286 -290.08451)
			(xy 80.112362 -290.184332)
		)
		(stroke
			(width 0)
			(type solid)
		)
		(fill yes)
		(layer "In4.Cu")
		(net "M_D_CPU1_SB_DQ<27>")
	)
	(gr_poly
		(pts
			(xy 80.212184 -286.84474) (xy 80.212184 -286.796988) (xy 80.012286 -286.796988) (xy 80.012286 -286.84474)
			(xy 80.112362 -286.944816)
		)
		(stroke
			(width 0)
			(type solid)
		)
		(fill yes)
		(layer "In4.Cu")
		(net "M_D_CPU1_SB_DQS_DP<7>")
	)
	(gr_poly
		(pts
			(xy 80.212184 -285.224728) (xy 80.212184 -285.180278) (xy 80.012286 -285.180278) (xy 80.012286 -285.224728)
			(xy 80.112362 -285.324804)
		)
		(stroke
			(width 0)
			(type solid)
		)
		(fill yes)
		(layer "In4.Cu")
		(net "M_D_CPU1_SB_DQ<19>")
	)
	(gr_poly
		(pts
			(xy 80.212184 -280.364692) (xy 80.212184 -280.320242) (xy 80.012286 -280.320242) (xy 80.012286 -280.364692)
			(xy 80.112362 -280.464768)
		)
		(stroke
			(width 0)
			(type solid)
		)
		(fill yes)
		(layer "In4.Cu")
		(net "M_D_CPU1_SB_DQ<11>")
	)
	(gr_poly
		(pts
			(xy 80.212184 -277.124922) (xy 80.212184 -277.07717) (xy 80.012286 -277.07717) (xy 80.012286 -277.124922)
			(xy 80.112362 -277.224744)
		)
		(stroke
			(width 0)
			(type solid)
		)
		(fill yes)
		(layer "In4.Cu")
		(net "M_D_CPU1_SB_DQS_DP<5>")
	)
	(gr_poly
		(pts
			(xy 80.212184 -275.504656) (xy 80.212184 -275.460206) (xy 80.012286 -275.460206) (xy 80.012286 -275.504656)
			(xy 80.112362 -275.604732)
		)
		(stroke
			(width 0)
			(type solid)
		)
		(fill yes)
		(layer "In4.Cu")
		(net "M_D_CPU1_SB_DQ<3>")
	)
	(gr_poly
		(pts
			(xy 80.212184 -273.884644) (xy 80.212184 -273.840194) (xy 80.012286 -273.840194) (xy 80.012286 -273.884644)
			(xy 80.112362 -273.98472)
		)
		(stroke
			(width 0)
			(type solid)
		)
		(fill yes)
		(layer "In4.Cu")
		(net "M_D_CPU1_SB_CB<3>")
	)
	(gr_poly
		(pts
			(xy 80.212184 -272.264886) (xy 80.212184 -272.217134) (xy 80.012286 -272.217134) (xy 80.012286 -272.264886)
			(xy 80.112362 -272.364708)
		)
		(stroke
			(width 0)
			(type solid)
		)
		(fill yes)
		(layer "In4.Cu")
		(net "M_D_CPU1_SB_DQS_DP<4>")
	)
	(gr_poly
		(pts
			(xy 80.212184 -270.64462) (xy 80.212184 -270.60017) (xy 80.012286 -270.60017) (xy 80.012286 -270.64462)
			(xy 80.112362 -270.744696)
		)
		(stroke
			(width 0)
			(type solid)
		)
		(fill yes)
		(layer "In4.Cu")
		(net "M_D_CPU1_SB_CB<7>")
	)
	(gr_poly
		(pts
			(xy 80.212184 -265.784584) (xy 80.212184 -265.740134) (xy 80.012286 -265.740134) (xy 80.012286 -265.784584)
			(xy 80.112362 -265.88466)
		)
		(stroke
			(width 0)
			(type solid)
		)
		(fill yes)
		(layer "In4.Cu")
		(net "M_D_CPU1_SB_CS_N<0>")
	)
	(gr_poly
		(pts
			(xy 80.212184 -264.164572) (xy 80.212184 -264.120122) (xy 80.012286 -264.120122) (xy 80.012286 -264.164572)
			(xy 80.112362 -264.264648)
		)
		(stroke
			(width 0)
			(type solid)
		)
		(fill yes)
		(layer "In4.Cu")
		(net "M_D_CPU1_SB_CA<5>")
	)
	(gr_poly
		(pts
			(xy 80.212184 -262.54456) (xy 80.212184 -262.50011) (xy 80.012286 -262.50011) (xy 80.012286 -262.54456)
			(xy 80.112362 -262.644636)
		)
		(stroke
			(width 0)
			(type solid)
		)
		(fill yes)
		(layer "In4.Cu")
		(net "M_D_CPU1_SB_CA<1>")
	)
	(gr_poly
		(pts
			(xy 80.214216 -281.98445) (xy 80.214216 -281.936698) (xy 80.014318 -281.936698) (xy 80.014318 -281.98445)
			(xy 80.11414 -282.084272)
		)
		(stroke
			(width 0)
			(type solid)
		)
		(fill yes)
		(layer "In4.Cu")
		(net "M_D_CPU1_SB_DQS_DP<6>")
	)
	(gr_poly
		(pts
			(xy 80.214978 -287.248092) (xy 80.114902 -287.148016) (xy 80.014826 -287.248092) (xy 80.014826 -287.292542)
			(xy 80.214978 -287.292542)
		)
		(stroke
			(width 0)
			(type solid)
		)
		(fill yes)
		(layer "In4.Cu")
		(net "M_D_CPU1_SB_DQ<20>")
	)
	(gr_poly
		(pts
			(xy 80.214978 -284.008322) (xy 80.114902 -283.908246) (xy 80.014826 -284.008322) (xy 80.014826 -284.052772)
			(xy 80.214978 -284.052772)
		)
		(stroke
			(width 0)
			(type solid)
		)
		(fill yes)
		(layer "In4.Cu")
		(net "M_D_CPU1_SB_DQ<16>")
	)
	(gr_poly
		(pts
			(xy 80.214978 -282.38831) (xy 80.114902 -282.288234) (xy 80.014826 -282.38831) (xy 80.014826 -282.43276)
			(xy 80.214978 -282.43276)
		)
		(stroke
			(width 0)
			(type solid)
		)
		(fill yes)
		(layer "In4.Cu")
		(net "M_D_CPU1_SB_DQ<12>")
	)
	(gr_poly
		(pts
			(xy 80.214978 -279.148286) (xy 80.114902 -279.04821) (xy 80.014826 -279.148286) (xy 80.014826 -279.192736)
			(xy 80.214978 -279.192736)
		)
		(stroke
			(width 0)
			(type solid)
		)
		(fill yes)
		(layer "In4.Cu")
		(net "M_D_CPU1_SB_DQ<8>")
	)
	(gr_poly
		(pts
			(xy 80.214978 -278.744426) (xy 80.214978 -278.699976) (xy 80.014826 -278.699976) (xy 80.014826 -278.744426)
			(xy 80.114902 -278.844502)
		)
		(stroke
			(width 0)
			(type solid)
		)
		(fill yes)
		(layer "In4.Cu")
		(net "M_D_CPU1_SB_DQ<7>")
	)
	(gr_poly
		(pts
			(xy 80.214978 -277.528274) (xy 80.114902 -277.428198) (xy 80.014826 -277.528274) (xy 80.014826 -277.572724)
			(xy 80.214978 -277.572724)
		)
		(stroke
			(width 0)
			(type solid)
		)
		(fill yes)
		(layer "In4.Cu")
		(net "M_D_CPU1_SB_DQ<4>")
	)
	(gr_poly
		(pts
			(xy 80.214978 -275.908008) (xy 80.114902 -275.807932) (xy 80.014826 -275.908008) (xy 80.014826 -275.955506)
			(xy 80.214978 -275.955506)
		)
		(stroke
			(width 0)
			(type solid)
		)
		(fill yes)
		(layer "In4.Cu")
		(net "M_D_CPU1_SB_DQS_DP<0>")
	)
	(gr_poly
		(pts
			(xy 80.214978 -274.28825) (xy 80.114902 -274.188174) (xy 80.014826 -274.28825) (xy 80.014826 -274.3327)
			(xy 80.214978 -274.3327)
		)
		(stroke
			(width 0)
			(type solid)
		)
		(fill yes)
		(layer "In4.Cu")
		(net "M_D_CPU1_SB_DQ<0>")
	)
	(gr_poly
		(pts
			(xy 80.214978 -272.668238) (xy 80.114902 -272.568162) (xy 80.014826 -272.668238) (xy 80.014826 -272.712688)
			(xy 80.214978 -272.712688)
		)
		(stroke
			(width 0)
			(type solid)
		)
		(fill yes)
		(layer "In4.Cu")
		(net "M_D_CPU1_SB_CB<0>")
	)
	(gr_poly
		(pts
			(xy 80.214978 -271.047972) (xy 80.114902 -270.947896) (xy 80.014826 -271.047972) (xy 80.014826 -271.09547)
			(xy 80.214978 -271.09547)
		)
		(stroke
			(width 0)
			(type solid)
		)
		(fill yes)
		(layer "In4.Cu")
		(net "M_D_CPU1_SB_DQS_DP<9>")
	)
	(gr_poly
		(pts
			(xy 80.214978 -264.568178) (xy 80.114902 -264.468102) (xy 80.014826 -264.568178) (xy 80.014826 -264.612628)
			(xy 80.214978 -264.612628)
		)
		(stroke
			(width 0)
			(type solid)
		)
		(fill yes)
		(layer "In4.Cu")
		(net "M_D_CPU1_SB_CA<6>")
	)
	(gr_poly
		(pts
			(xy 80.214978 -262.948166) (xy 80.114902 -262.84809) (xy 80.014826 -262.948166) (xy 80.014826 -262.992616)
			(xy 80.214978 -262.992616)
		)
		(stroke
			(width 0)
			(type solid)
		)
		(fill yes)
		(layer "In4.Cu")
		(net "M_D_CPU1_SB_CA<2>")
	)
	(gr_poly
		(pts
			(xy 80.221074 -292.108128) (xy 80.120998 -292.008052) (xy 80.020922 -292.108128) (xy 80.020922 -292.152578)
			(xy 80.221074 -292.152578)
		)
		(stroke
			(width 0)
			(type solid)
		)
		(fill yes)
		(layer "In4.Cu")
		(net "M_D_CPU1_SB_DQ<28>")
	)
	(gr_poly
		(pts
			(xy 80.221074 -288.868104) (xy 80.120998 -288.768028) (xy 80.020922 -288.868104) (xy 80.020922 -288.912554)
			(xy 80.221074 -288.912554)
		)
		(stroke
			(width 0)
			(type solid)
		)
		(fill yes)
		(layer "In4.Cu")
		(net "M_D_CPU1_SB_DQ<24>")
	)
	(gr_poly
		(pts
			(xy 80.221074 -288.464498) (xy 80.221074 -288.420048) (xy 80.020922 -288.420048) (xy 80.020922 -288.464498)
			(xy 80.120998 -288.564574)
		)
		(stroke
			(width 0)
			(type solid)
		)
		(fill yes)
		(layer "In4.Cu")
		(net "M_D_CPU1_SB_DQ<23>")
	)
	(gr_poly
		(pts
			(xy 80.221074 -269.428214) (xy 80.120998 -269.328138) (xy 80.020922 -269.428214) (xy 80.020922 -269.472664)
			(xy 80.221074 -269.472664)
		)
		(stroke
			(width 0)
			(type solid)
		)
		(fill yes)
		(layer "In4.Cu")
		(net "M_D_CPU1_SB_CB<4>")
	)
	(gr_poly
		(pts
			(xy 80.22717 -285.62808) (xy 80.127094 -285.528258) (xy 80.027018 -285.62808) (xy 80.027018 -285.675832)
			(xy 80.22717 -285.675832)
		)
		(stroke
			(width 0)
			(type solid)
		)
		(fill yes)
		(layer "In4.Cu")
		(net "M_D_CPU1_SB_DQS_DP<2>")
	)
	(gr_poly
		(pts
			(xy 80.22717 -280.768044) (xy 80.127094 -280.668222) (xy 80.027018 -280.768044) (xy 80.027018 -280.815796)
			(xy 80.22717 -280.815796)
		)
		(stroke
			(width 0)
			(type solid)
		)
		(fill yes)
		(layer "In4.Cu")
		(net "M_D_CPU1_SB_DQS_DP<1>")
	)
	(gr_poly
		(pts
			(xy 80.235044 -267.801852) (xy 80.134968 -267.701776) (xy 80.035146 -267.801852) (xy 80.035146 -267.846302)
			(xy 80.235044 -267.846302)
		)
		(stroke
			(width 0)
			(type solid)
		)
		(fill yes)
		(layer "In4.Cu")
		(net "M_D_CPU1_SB_RSP<0>")
	)
	(gr_poly
		(pts
			(xy 80.235552 -283.604208) (xy 80.235552 -283.560012) (xy 80.035654 -283.560012) (xy 80.035654 -283.604208)
			(xy 80.13573 -283.704284)
		)
		(stroke
			(width 0)
			(type solid)
		)
		(fill yes)
		(layer "In4.Cu")
		(net "M_D_CPU1_SB_DQ<15>")
	)
	(gr_poly
		(pts
			(xy 80.276954 -293.860728) (xy 80.240378 -293.724076) (xy 80.202024 -293.701724) (xy 80.101948 -293.874952)
			(xy 80.140556 -293.897304)
		)
		(stroke
			(width 0)
			(type solid)
		)
		(fill yes)
		(layer "In4.Cu")
		(net "M_D_CPU1_SB_DQ<30>")
	)
	(gr_poly
		(pts
			(xy 80.310228 -228.633274) (xy 80.210152 -228.460046) (xy 80.171798 -228.482398) (xy 80.135222 -228.61905)
			(xy 80.27162 -228.655626)
		)
		(stroke
			(width 0)
			(type solid)
		)
		(fill yes)
		(layer "In4.Cu")
		(net "M_D_CPU1_SA_DQ<7>")
	)
	(gr_poly
		(pts
			(xy 80.310228 -227.013262) (xy 80.210152 -226.840034) (xy 80.171798 -226.862386) (xy 80.135222 -226.999038)
			(xy 80.27162 -227.035614)
		)
		(stroke
			(width 0)
			(type solid)
		)
		(fill yes)
		(layer "In4.Cu")
		(net "M_D_CPU1_SA_DQ<6>")
	)
	(gr_poly
		(pts
			(xy 80.31099 -230.254556) (xy 80.210914 -230.081328) (xy 80.172306 -230.103426) (xy 80.13573 -230.240078)
			(xy 80.272382 -230.276654)
		)
		(stroke
			(width 0)
			(type solid)
		)
		(fill yes)
		(layer "In4.Cu")
		(net "M_D_CPU1_SA_DQ<10>")
	)
	(gr_poly
		(pts
			(xy 80.313022 -225.392488) (xy 80.2132 -225.21926) (xy 80.171798 -225.243136) (xy 80.135222 -225.379534)
			(xy 80.271874 -225.416364)
		)
		(stroke
			(width 0)
			(type solid)
		)
		(fill yes)
		(layer "In4.Cu")
		(net "M_D_CPU1_SA_DQS_DP<5>")
	)
	(gr_poly
		(pts
			(xy 80.314038 -223.773746) (xy 80.214216 -223.600518) (xy 80.172814 -223.624394) (xy 80.136238 -223.761046)
			(xy 80.27289 -223.797622)
		)
		(stroke
			(width 0)
			(type solid)
		)
		(fill yes)
		(layer "In4.Cu")
		(net "M_D_CPU1_SA_DQS_DN<0>")
	)
	(gr_poly
		(pts
			(xy 80.391254 -256.026158) (xy 80.291178 -255.926336) (xy 80.191102 -256.026158) (xy 80.191102 -256.07391)
			(xy 80.391254 -256.07391)
		)
		(stroke
			(width 0)
			(type solid)
		)
		(fill yes)
		(layer "In4.Cu")
		(net "M_D_CPU1_CLK_DP<0>")
	)
	(gr_poly
		(pts
			(xy 80.391254 -255.622552) (xy 80.391254 -255.578102) (xy 80.191102 -255.578102) (xy 80.191102 -255.622552)
			(xy 80.291178 -255.722628)
		)
		(stroke
			(width 0)
			(type solid)
		)
		(fill yes)
		(layer "In4.Cu")
		(net "M_D_CPU1_SA_PAR")
	)
	(gr_poly
		(pts
			(xy 80.391254 -254.4064) (xy 80.291178 -254.306324) (xy 80.191102 -254.4064) (xy 80.191102 -254.45085)
			(xy 80.391254 -254.45085)
		)
		(stroke
			(width 0)
			(type solid)
		)
		(fill yes)
		(layer "In4.Cu")
		(net "M_D_CPU1_SA_CA<4>")
	)
	(gr_poly
		(pts
			(xy 80.391254 -254.00254) (xy 80.391254 -253.95809) (xy 80.191102 -253.95809) (xy 80.191102 -254.00254)
			(xy 80.291178 -254.102616)
		)
		(stroke
			(width 0)
			(type solid)
		)
		(fill yes)
		(layer "In4.Cu")
		(net "M_D_CPU1_SA_CA<3>")
	)
	(gr_poly
		(pts
			(xy 80.391254 -252.786388) (xy 80.291178 -252.686312) (xy 80.191102 -252.786388) (xy 80.191102 -252.830838)
			(xy 80.391254 -252.830838)
		)
		(stroke
			(width 0)
			(type solid)
		)
		(fill yes)
		(layer "In4.Cu")
		(net "M_D_CPU1_SA_CA<0>")
	)
	(gr_poly
		(pts
			(xy 80.391254 -252.382528) (xy 80.391254 -252.338078) (xy 80.191102 -252.338078) (xy 80.191102 -252.382528)
			(xy 80.291178 -252.482604)
		)
		(stroke
			(width 0)
			(type solid)
		)
		(fill yes)
		(layer "In4.Cu")
		(net "M_D_CPU1_SA_CS_N<1>")
	)
	(gr_poly
		(pts
			(xy 80.391254 -250.762516) (xy 80.391254 -250.718066) (xy 80.191102 -250.718066) (xy 80.191102 -250.762516)
			(xy 80.291178 -250.862592)
		)
		(stroke
			(width 0)
			(type solid)
		)
		(fill yes)
		(layer "In4.Cu")
		(net "M_D_CPU1_RESET_N")
	)
	(gr_poly
		(pts
			(xy 80.391254 -249.142504) (xy 80.391254 -249.098054) (xy 80.191102 -249.098054) (xy 80.191102 -249.142504)
			(xy 80.291178 -249.24258)
		)
		(stroke
			(width 0)
			(type solid)
		)
		(fill yes)
		(layer "In4.Cu")
		(net "M_D_CPU1_SA_CB<7>")
	)
	(gr_poly
		(pts
			(xy 80.391254 -247.926352) (xy 80.291178 -247.826276) (xy 80.191102 -247.926352) (xy 80.191102 -247.970802)
			(xy 80.391254 -247.970802)
		)
		(stroke
			(width 0)
			(type solid)
		)
		(fill yes)
		(layer "In4.Cu")
		(net "M_D_CPU1_SA_CB<4>")
	)
	(gr_poly
		(pts
			(xy 80.391254 -247.522746) (xy 80.391254 -247.474994) (xy 80.191102 -247.474994) (xy 80.191102 -247.522746)
			(xy 80.291178 -247.622568)
		)
		(stroke
			(width 0)
			(type solid)
		)
		(fill yes)
		(layer "In4.Cu")
		(net "M_D_CPU1_SA_DQS_DP<9>")
	)
	(gr_poly
		(pts
			(xy 80.391254 -246.306086) (xy 80.291178 -246.206264) (xy 80.191102 -246.306086) (xy 80.191102 -246.353838)
			(xy 80.391254 -246.353838)
		)
		(stroke
			(width 0)
			(type solid)
		)
		(fill yes)
		(layer "In4.Cu")
		(net "M_D_CPU1_SA_DQS_DP<4>")
	)
	(gr_poly
		(pts
			(xy 80.391254 -245.90248) (xy 80.391254 -245.85803) (xy 80.191102 -245.85803) (xy 80.191102 -245.90248)
			(xy 80.291178 -246.002556)
		)
		(stroke
			(width 0)
			(type solid)
		)
		(fill yes)
		(layer "In4.Cu")
		(net "M_D_CPU1_SA_CB<3>")
	)
	(gr_poly
		(pts
			(xy 80.391254 -244.686328) (xy 80.291178 -244.586252) (xy 80.191102 -244.686328) (xy 80.191102 -244.730778)
			(xy 80.391254 -244.730778)
		)
		(stroke
			(width 0)
			(type solid)
		)
		(fill yes)
		(layer "In4.Cu")
		(net "M_D_CPU1_SA_CB<0>")
	)
	(gr_poly
		(pts
			(xy 80.391254 -244.282468) (xy 80.391254 -244.238018) (xy 80.191102 -244.238018) (xy 80.191102 -244.282468)
			(xy 80.291178 -244.382544)
		)
		(stroke
			(width 0)
			(type solid)
		)
		(fill yes)
		(layer "In4.Cu")
		(net "M_D_CPU1_SA_DQ<31>")
	)
	(gr_poly
		(pts
			(xy 80.391254 -243.066316) (xy 80.291178 -242.96624) (xy 80.191102 -243.066316) (xy 80.191102 -243.110766)
			(xy 80.391254 -243.110766)
		)
		(stroke
			(width 0)
			(type solid)
		)
		(fill yes)
		(layer "In4.Cu")
		(net "M_D_CPU1_SA_DQ<28>")
	)
	(gr_poly
		(pts
			(xy 80.391254 -242.66271) (xy 80.391254 -242.614958) (xy 80.191102 -242.614958) (xy 80.191102 -242.66271)
			(xy 80.291178 -242.762532)
		)
		(stroke
			(width 0)
			(type solid)
		)
		(fill yes)
		(layer "In4.Cu")
		(net "M_D_CPU1_SA_DQS_DP<8>")
	)
	(gr_poly
		(pts
			(xy 80.391254 -241.44605) (xy 80.291178 -241.346228) (xy 80.191102 -241.44605) (xy 80.191102 -241.493802)
			(xy 80.391254 -241.493802)
		)
		(stroke
			(width 0)
			(type solid)
		)
		(fill yes)
		(layer "In4.Cu")
		(net "M_D_CPU1_SA_DQS_DP<3>")
	)
	(gr_poly
		(pts
			(xy 80.391254 -241.042444) (xy 80.391254 -240.997994) (xy 80.191102 -240.997994) (xy 80.191102 -241.042444)
			(xy 80.291178 -241.14252)
		)
		(stroke
			(width 0)
			(type solid)
		)
		(fill yes)
		(layer "In4.Cu")
		(net "M_D_CPU1_SA_DQ<27>")
	)
	(gr_poly
		(pts
			(xy 80.391254 -239.826292) (xy 80.291178 -239.726216) (xy 80.191102 -239.826292) (xy 80.191102 -239.870742)
			(xy 80.391254 -239.870742)
		)
		(stroke
			(width 0)
			(type solid)
		)
		(fill yes)
		(layer "In4.Cu")
		(net "M_D_CPU1_SA_DQ<24>")
	)
	(gr_poly
		(pts
			(xy 80.391254 -239.422432) (xy 80.391254 -239.377982) (xy 80.191102 -239.377982) (xy 80.191102 -239.422432)
			(xy 80.291178 -239.522508)
		)
		(stroke
			(width 0)
			(type solid)
		)
		(fill yes)
		(layer "In4.Cu")
		(net "M_D_CPU1_SA_DQ<23>")
	)
	(gr_poly
		(pts
			(xy 80.391254 -238.20628) (xy 80.291178 -238.106204) (xy 80.191102 -238.20628) (xy 80.191102 -238.25073)
			(xy 80.391254 -238.25073)
		)
		(stroke
			(width 0)
			(type solid)
		)
		(fill yes)
		(layer "In4.Cu")
		(net "M_D_CPU1_SA_DQ<20>")
	)
	(gr_poly
		(pts
			(xy 80.391254 -237.802674) (xy 80.391254 -237.754922) (xy 80.191102 -237.754922) (xy 80.191102 -237.802674)
			(xy 80.291178 -237.902496)
		)
		(stroke
			(width 0)
			(type solid)
		)
		(fill yes)
		(layer "In4.Cu")
		(net "M_D_CPU1_SA_DQS_DP<7>")
	)
	(gr_poly
		(pts
			(xy 80.391254 -236.586014) (xy 80.291178 -236.486192) (xy 80.191102 -236.586014) (xy 80.191102 -236.633766)
			(xy 80.391254 -236.633766)
		)
		(stroke
			(width 0)
			(type solid)
		)
		(fill yes)
		(layer "In4.Cu")
		(net "M_D_CPU1_SA_DQS_DP<2>")
	)
	(gr_poly
		(pts
			(xy 80.391254 -236.182408) (xy 80.391254 -236.137958) (xy 80.191102 -236.137958) (xy 80.191102 -236.182408)
			(xy 80.291178 -236.282484)
		)
		(stroke
			(width 0)
			(type solid)
		)
		(fill yes)
		(layer "In4.Cu")
		(net "M_D_CPU1_SA_DQ<19>")
	)
	(gr_poly
		(pts
			(xy 80.391254 -234.966256) (xy 80.291178 -234.86618) (xy 80.191102 -234.966256) (xy 80.191102 -235.010706)
			(xy 80.391254 -235.010706)
		)
		(stroke
			(width 0)
			(type solid)
		)
		(fill yes)
		(layer "In4.Cu")
		(net "M_D_CPU1_SA_DQ<16>")
	)
	(gr_poly
		(pts
			(xy 80.391254 -234.562396) (xy 80.391254 -234.517946) (xy 80.191102 -234.517946) (xy 80.191102 -234.562396)
			(xy 80.291178 -234.662472)
		)
		(stroke
			(width 0)
			(type solid)
		)
		(fill yes)
		(layer "In4.Cu")
		(net "M_D_CPU1_SA_DQ<15>")
	)
	(gr_poly
		(pts
			(xy 80.391254 -233.346244) (xy 80.291178 -233.246168) (xy 80.191102 -233.346244) (xy 80.191102 -233.390694)
			(xy 80.391254 -233.390694)
		)
		(stroke
			(width 0)
			(type solid)
		)
		(fill yes)
		(layer "In4.Cu")
		(net "M_D_CPU1_SA_DQ<12>")
	)
	(gr_poly
		(pts
			(xy 80.391254 -232.942638) (xy 80.391254 -232.894886) (xy 80.191102 -232.894886) (xy 80.191102 -232.942638)
			(xy 80.291178 -233.04246)
		)
		(stroke
			(width 0)
			(type solid)
		)
		(fill yes)
		(layer "In4.Cu")
		(net "M_D_CPU1_SA_DQS_DP<6>")
	)
	(gr_poly
		(pts
			(xy 80.391254 -231.725978) (xy 80.291178 -231.626156) (xy 80.191102 -231.725978) (xy 80.191102 -231.77373)
			(xy 80.391254 -231.77373)
		)
		(stroke
			(width 0)
			(type solid)
		)
		(fill yes)
		(layer "In4.Cu")
		(net "M_D_CPU1_SA_DQS_DP<1>")
	)
	(gr_poly
		(pts
			(xy 80.391254 -231.322626) (xy 80.391254 -231.278176) (xy 80.191102 -231.278176) (xy 80.191102 -231.322626)
			(xy 80.291178 -231.422702)
		)
		(stroke
			(width 0)
			(type solid)
		)
		(fill yes)
		(layer "In4.Cu")
		(net "M_D_CPU1_SA_DQ<11>")
	)
	(gr_poly
		(pts
			(xy 80.409542 -223.224598) (xy 80.446118 -223.087946) (xy 80.309466 -223.05137) (xy 80.268318 -223.075246)
			(xy 80.36814 -223.248474)
		)
		(stroke
			(width 0)
			(type solid)
		)
		(fill yes)
		(layer "In4.Cu")
		(net "M_D_CPU1_SA_DQS_DP<0>")
	)
	(gr_poly
		(pts
			(xy 80.41005 -224.846388) (xy 80.446626 -224.709736) (xy 80.309974 -224.67316) (xy 80.268572 -224.697036)
			(xy 80.368648 -224.870264)
		)
		(stroke
			(width 0)
			(type solid)
		)
		(fill yes)
		(layer "In4.Cu")
		(net "M_D_CPU1_SA_DQS_DN<5>")
	)
	(gr_poly
		(pts
			(xy 80.410304 -229.706424) (xy 80.447134 -229.569772) (xy 80.310482 -229.533196) (xy 80.271874 -229.555548)
			(xy 80.37195 -229.728776)
		)
		(stroke
			(width 0)
			(type solid)
		)
		(fill yes)
		(layer "In4.Cu")
		(net "M_D_CPU1_SA_DQ<8>")
	)
	(gr_poly
		(pts
			(xy 80.410304 -228.086666) (xy 80.447134 -227.950014) (xy 80.310482 -227.913438) (xy 80.271874 -227.93579)
			(xy 80.37195 -228.109018)
		)
		(stroke
			(width 0)
			(type solid)
		)
		(fill yes)
		(layer "In4.Cu")
		(net "M_D_CPU1_SA_DQ<5>")
	)
	(gr_poly
		(pts
			(xy 80.410304 -226.466654) (xy 80.447134 -226.330002) (xy 80.310482 -226.293426) (xy 80.271874 -226.315778)
			(xy 80.37195 -226.489006)
		)
		(stroke
			(width 0)
			(type solid)
		)
		(fill yes)
		(layer "In4.Cu")
		(net "M_D_CPU1_SA_DQ<4>")
	)
	(gr_poly
		(pts
			(xy 80.610202 -293.987474) (xy 80.571594 -293.965122) (xy 80.434942 -294.001698) (xy 80.471772 -294.13835)
			(xy 80.510126 -294.160702)
		)
		(stroke
			(width 0)
			(type solid)
		)
		(fill yes)
		(layer "In4.Cu")
		(net "M_D_CPU1_SB_DQ<29>")
	)
	(gr_poly
		(pts
			(xy 80.684878 -266.991846) (xy 80.584802 -266.89177) (xy 80.48498 -266.991846) (xy 80.48498 -267.036296)
			(xy 80.684878 -267.036296)
		)
		(stroke
			(width 0)
			(type solid)
		)
		(fill yes)
		(layer "In4.Cu")
		(net "M_D_CPU1_SA_RSP<0>")
	)
	(gr_poly
		(pts
			(xy 80.691228 -291.297868) (xy 80.591152 -291.198046) (xy 80.491076 -291.297868) (xy 80.491076 -291.34562)
			(xy 80.691228 -291.34562)
		)
		(stroke
			(width 0)
			(type solid)
		)
		(fill yes)
		(layer "In4.Cu")
		(net "M_D_CPU1_SB_DQS_DN<8>")
	)
	(gr_poly
		(pts
			(xy 80.691228 -290.894516) (xy 80.691228 -290.846764) (xy 80.491076 -290.846764) (xy 80.491076 -290.894516)
			(xy 80.591152 -290.994338)
		)
		(stroke
			(width 0)
			(type solid)
		)
		(fill yes)
		(layer "In4.Cu")
		(net "M_D_CPU1_SB_DQS_DN<3>")
	)
	(gr_poly
		(pts
			(xy 80.691228 -289.67811) (xy 80.591152 -289.578034) (xy 80.491076 -289.67811) (xy 80.491076 -289.72256)
			(xy 80.691228 -289.72256)
		)
		(stroke
			(width 0)
			(type solid)
		)
		(fill yes)
		(layer "In4.Cu")
		(net "M_D_CPU1_SB_DQ<25>")
	)
	(gr_poly
		(pts
			(xy 80.691228 -289.27425) (xy 80.691228 -289.2298) (xy 80.491076 -289.2298) (xy 80.491076 -289.27425)
			(xy 80.591152 -289.374326)
		)
		(stroke
			(width 0)
			(type solid)
		)
		(fill yes)
		(layer "In4.Cu")
		(net "M_D_CPU1_SB_DQ<26>")
	)
	(gr_poly
		(pts
			(xy 80.691228 -288.058098) (xy 80.591152 -287.958022) (xy 80.491076 -288.058098) (xy 80.491076 -288.102548)
			(xy 80.691228 -288.102548)
		)
		(stroke
			(width 0)
			(type solid)
		)
		(fill yes)
		(layer "In4.Cu")
		(net "M_D_CPU1_SB_DQ<21>")
	)
	(gr_poly
		(pts
			(xy 80.691228 -287.654492) (xy 80.691228 -287.610042) (xy 80.491076 -287.610042) (xy 80.491076 -287.654492)
			(xy 80.591152 -287.754568)
		)
		(stroke
			(width 0)
			(type solid)
		)
		(fill yes)
		(layer "In4.Cu")
		(net "M_D_CPU1_SB_DQ<22>")
	)
	(gr_poly
		(pts
			(xy 80.691228 -286.438086) (xy 80.591152 -286.33801) (xy 80.491076 -286.438086) (xy 80.491076 -286.485838)
			(xy 80.691228 -286.485838)
		)
		(stroke
			(width 0)
			(type solid)
		)
		(fill yes)
		(layer "In4.Cu")
		(net "M_D_CPU1_SB_DQS_DN<7>")
	)
	(gr_poly
		(pts
			(xy 80.691228 -286.034734) (xy 80.691228 -285.986982) (xy 80.491076 -285.986982) (xy 80.491076 -286.034734)
			(xy 80.591152 -286.134556)
		)
		(stroke
			(width 0)
			(type solid)
		)
		(fill yes)
		(layer "In4.Cu")
		(net "M_D_CPU1_SB_DQS_DN<2>")
	)
	(gr_poly
		(pts
			(xy 80.691228 -284.818328) (xy 80.591152 -284.718252) (xy 80.491076 -284.818328) (xy 80.491076 -284.862778)
			(xy 80.691228 -284.862778)
		)
		(stroke
			(width 0)
			(type solid)
		)
		(fill yes)
		(layer "In4.Cu")
		(net "M_D_CPU1_SB_DQ<17>")
	)
	(gr_poly
		(pts
			(xy 80.691228 -284.414468) (xy 80.691228 -284.370018) (xy 80.491076 -284.370018) (xy 80.491076 -284.414468)
			(xy 80.591152 -284.514544)
		)
		(stroke
			(width 0)
			(type solid)
		)
		(fill yes)
		(layer "In4.Cu")
		(net "M_D_CPU1_SB_DQ<18>")
	)
	(gr_poly
		(pts
			(xy 80.691228 -283.198316) (xy 80.591152 -283.09824) (xy 80.491076 -283.198316) (xy 80.491076 -283.242766)
			(xy 80.691228 -283.242766)
		)
		(stroke
			(width 0)
			(type solid)
		)
		(fill yes)
		(layer "In4.Cu")
		(net "M_D_CPU1_SB_DQ<13>")
	)
	(gr_poly
		(pts
			(xy 80.691228 -282.794456) (xy 80.691228 -282.750006) (xy 80.491076 -282.750006) (xy 80.491076 -282.794456)
			(xy 80.591152 -282.894532)
		)
		(stroke
			(width 0)
			(type solid)
		)
		(fill yes)
		(layer "In4.Cu")
		(net "M_D_CPU1_SB_DQ<14>")
	)
	(gr_poly
		(pts
			(xy 80.691228 -281.57805) (xy 80.591152 -281.478228) (xy 80.491076 -281.57805) (xy 80.491076 -281.625802)
			(xy 80.691228 -281.625802)
		)
		(stroke
			(width 0)
			(type solid)
		)
		(fill yes)
		(layer "In4.Cu")
		(net "M_D_CPU1_SB_DQS_DN<6>")
	)
	(gr_poly
		(pts
			(xy 80.691228 -281.174698) (xy 80.691228 -281.126946) (xy 80.491076 -281.126946) (xy 80.491076 -281.174698)
			(xy 80.591152 -281.27452)
		)
		(stroke
			(width 0)
			(type solid)
		)
		(fill yes)
		(layer "In4.Cu")
		(net "M_D_CPU1_SB_DQS_DN<1>")
	)
	(gr_poly
		(pts
			(xy 80.691228 -279.958292) (xy 80.591152 -279.858216) (xy 80.491076 -279.958292) (xy 80.491076 -280.002742)
			(xy 80.691228 -280.002742)
		)
		(stroke
			(width 0)
			(type solid)
		)
		(fill yes)
		(layer "In4.Cu")
		(net "M_D_CPU1_SB_DQ<9>")
	)
	(gr_poly
		(pts
			(xy 80.691228 -279.554432) (xy 80.691228 -279.509982) (xy 80.491076 -279.509982) (xy 80.491076 -279.554432)
			(xy 80.591152 -279.654508)
		)
		(stroke
			(width 0)
			(type solid)
		)
		(fill yes)
		(layer "In4.Cu")
		(net "M_D_CPU1_SB_DQ<10>")
	)
	(gr_poly
		(pts
			(xy 80.691228 -278.33828) (xy 80.591152 -278.238204) (xy 80.491076 -278.33828) (xy 80.491076 -278.38273)
			(xy 80.691228 -278.38273)
		)
		(stroke
			(width 0)
			(type solid)
		)
		(fill yes)
		(layer "In4.Cu")
		(net "M_D_CPU1_SB_DQ<5>")
	)
	(gr_poly
		(pts
			(xy 80.691228 -277.93442) (xy 80.691228 -277.88997) (xy 80.491076 -277.88997) (xy 80.491076 -277.93442)
			(xy 80.591152 -278.034496)
		)
		(stroke
			(width 0)
			(type solid)
		)
		(fill yes)
		(layer "In4.Cu")
		(net "M_D_CPU1_SB_DQ<6>")
	)
	(gr_poly
		(pts
			(xy 80.691228 -276.718014) (xy 80.591152 -276.618192) (xy 80.491076 -276.718014) (xy 80.491076 -276.765766)
			(xy 80.691228 -276.765766)
		)
		(stroke
			(width 0)
			(type solid)
		)
		(fill yes)
		(layer "In4.Cu")
		(net "M_D_CPU1_SB_DQS_DN<5>")
	)
	(gr_poly
		(pts
			(xy 80.691228 -276.314662) (xy 80.691228 -276.26691) (xy 80.491076 -276.26691) (xy 80.491076 -276.314662)
			(xy 80.591152 -276.414484)
		)
		(stroke
			(width 0)
			(type solid)
		)
		(fill yes)
		(layer "In4.Cu")
		(net "M_D_CPU1_SB_DQS_DN<0>")
	)
	(gr_poly
		(pts
			(xy 80.691228 -275.098256) (xy 80.591152 -274.99818) (xy 80.491076 -275.098256) (xy 80.491076 -275.142706)
			(xy 80.691228 -275.142706)
		)
		(stroke
			(width 0)
			(type solid)
		)
		(fill yes)
		(layer "In4.Cu")
		(net "M_D_CPU1_SB_DQ<1>")
	)
	(gr_poly
		(pts
			(xy 80.691228 -274.694396) (xy 80.691228 -274.649946) (xy 80.491076 -274.649946) (xy 80.491076 -274.694396)
			(xy 80.591152 -274.794472)
		)
		(stroke
			(width 0)
			(type solid)
		)
		(fill yes)
		(layer "In4.Cu")
		(net "M_D_CPU1_SB_DQ<2>")
	)
	(gr_poly
		(pts
			(xy 80.691228 -273.478244) (xy 80.591152 -273.378168) (xy 80.491076 -273.478244) (xy 80.491076 -273.522694)
			(xy 80.691228 -273.522694)
		)
		(stroke
			(width 0)
			(type solid)
		)
		(fill yes)
		(layer "In4.Cu")
		(net "M_D_CPU1_SB_CB<1>")
	)
	(gr_poly
		(pts
			(xy 80.691228 -273.074384) (xy 80.691228 -273.029934) (xy 80.491076 -273.029934) (xy 80.491076 -273.074384)
			(xy 80.591152 -273.17446)
		)
		(stroke
			(width 0)
			(type solid)
		)
		(fill yes)
		(layer "In4.Cu")
		(net "M_D_CPU1_SB_CB<2>")
	)
	(gr_poly
		(pts
			(xy 80.691228 -271.857978) (xy 80.591152 -271.758156) (xy 80.491076 -271.857978) (xy 80.491076 -271.90573)
			(xy 80.691228 -271.90573)
		)
		(stroke
			(width 0)
			(type solid)
		)
		(fill yes)
		(layer "In4.Cu")
		(net "M_D_CPU1_SB_DQS_DN<4>")
	)
	(gr_poly
		(pts
			(xy 80.691228 -271.454626) (xy 80.691228 -271.406874) (xy 80.491076 -271.406874) (xy 80.491076 -271.454626)
			(xy 80.591152 -271.554448)
		)
		(stroke
			(width 0)
			(type solid)
		)
		(fill yes)
		(layer "In4.Cu")
		(net "M_D_CPU1_SB_DQS_DN<9>")
	)
	(gr_poly
		(pts
			(xy 80.691228 -270.23822) (xy 80.591152 -270.138144) (xy 80.491076 -270.23822) (xy 80.491076 -270.28267)
			(xy 80.691228 -270.28267)
		)
		(stroke
			(width 0)
			(type solid)
		)
		(fill yes)
		(layer "In4.Cu")
		(net "M_D_CPU1_SB_CB<5>")
	)
	(gr_poly
		(pts
			(xy 80.691228 -269.83436) (xy 80.691228 -269.78991) (xy 80.491076 -269.78991) (xy 80.491076 -269.83436)
			(xy 80.591152 -269.934436)
		)
		(stroke
			(width 0)
			(type solid)
		)
		(fill yes)
		(layer "In4.Cu")
		(net "M_D_CPU1_SB_CB<6>")
	)
	(gr_poly
		(pts
			(xy 80.691228 -266.594336) (xy 80.691228 -266.549886) (xy 80.491076 -266.549886) (xy 80.491076 -266.594336)
			(xy 80.591152 -266.694412)
		)
		(stroke
			(width 0)
			(type solid)
		)
		(fill yes)
		(layer "In4.Cu")
		(net "M_D_CPU1_SB_CS_N<1>")
	)
	(gr_poly
		(pts
			(xy 80.691228 -264.974324) (xy 80.691228 -264.929874) (xy 80.491076 -264.929874) (xy 80.491076 -264.974324)
			(xy 80.591152 -265.0744)
		)
		(stroke
			(width 0)
			(type solid)
		)
		(fill yes)
		(layer "In4.Cu")
		(net "M_D_CPU1_SB_PAR")
	)
	(gr_poly
		(pts
			(xy 80.691228 -263.758172) (xy 80.591152 -263.658096) (xy 80.491076 -263.758172) (xy 80.491076 -263.802622)
			(xy 80.691228 -263.802622)
		)
		(stroke
			(width 0)
			(type solid)
		)
		(fill yes)
		(layer "In4.Cu")
		(net "M_D_CPU1_SB_CA<4>")
	)
	(gr_poly
		(pts
			(xy 80.691228 -263.354312) (xy 80.691228 -263.309862) (xy 80.491076 -263.309862) (xy 80.491076 -263.354312)
			(xy 80.591152 -263.454388)
		)
		(stroke
			(width 0)
			(type solid)
		)
		(fill yes)
		(layer "In4.Cu")
		(net "M_D_CPU1_SB_CA<3>")
	)
	(gr_poly
		(pts
			(xy 80.691228 -262.13816) (xy 80.591152 -262.038084) (xy 80.491076 -262.13816) (xy 80.491076 -262.18261)
			(xy 80.691228 -262.18261)
		)
		(stroke
			(width 0)
			(type solid)
		)
		(fill yes)
		(layer "In4.Cu")
		(net "M_D_CPU1_SB_CA<0>")
	)
	(gr_poly
		(pts
			(xy 80.746854 -293.050722) (xy 80.710278 -292.91407) (xy 80.671924 -292.891718) (xy 80.571848 -293.064946)
			(xy 80.610456 -293.087298)
		)
		(stroke
			(width 0)
			(type solid)
		)
		(fill yes)
		(layer "In4.Cu")
		(net "M_D_CPU1_SB_DQ<30>")
	)
	(gr_poly
		(pts
			(xy 80.747362 -296.289984) (xy 80.710532 -296.153332) (xy 80.672178 -296.131234) (xy 80.572102 -296.304462)
			(xy 80.61071 -296.32656)
		)
		(stroke
			(width 0)
			(type solid)
		)
		(fill yes)
		(layer "In4.Cu")
		(net "M_D_CPU1_SB_DQ<31>")
	)
	(gr_poly
		(pts
			(xy 80.781144 -229.444804) (xy 80.681068 -229.271576) (xy 80.64246 -229.293674) (xy 80.605884 -229.430326)
			(xy 80.742536 -229.466902)
		)
		(stroke
			(width 0)
			(type solid)
		)
		(fill yes)
		(layer "In4.Cu")
		(net "M_D_CPU1_SA_DQ<7>")
	)
	(gr_poly
		(pts
			(xy 80.781144 -227.824792) (xy 80.681068 -227.651564) (xy 80.64246 -227.673662) (xy 80.605884 -227.810314)
			(xy 80.742536 -227.84689)
		)
		(stroke
			(width 0)
			(type solid)
		)
		(fill yes)
		(layer "In4.Cu")
		(net "M_D_CPU1_SA_DQ<6>")
	)
	(gr_poly
		(pts
			(xy 80.781144 -222.964756) (xy 80.681068 -222.791528) (xy 80.64246 -222.813626) (xy 80.605884 -222.950278)
			(xy 80.742536 -222.986854)
		)
		(stroke
			(width 0)
			(type solid)
		)
		(fill yes)
		(layer "In4.Cu")
		(net "M_D_CPU1_SA_DQ<3>")
	)
	(gr_poly
		(pts
			(xy 80.783938 -226.203764) (xy 80.684116 -226.030536) (xy 80.642714 -226.054412) (xy 80.606138 -226.191064)
			(xy 80.74279 -226.22764)
		)
		(stroke
			(width 0)
			(type solid)
		)
		(fill yes)
		(layer "In4.Cu")
		(net "M_D_CPU1_SA_DQS_DP<5>")
	)
	(gr_poly
		(pts
			(xy 80.783938 -224.583752) (xy 80.684116 -224.410524) (xy 80.642714 -224.4344) (xy 80.606138 -224.571052)
			(xy 80.74279 -224.607628)
		)
		(stroke
			(width 0)
			(type solid)
		)
		(fill yes)
		(layer "In4.Cu")
		(net "M_D_CPU1_SA_DQS_DN<0>")
	)
	(gr_poly
		(pts
			(xy 80.861154 -256.432812) (xy 80.861154 -256.38506) (xy 80.661002 -256.38506) (xy 80.661002 -256.432812)
			(xy 80.761078 -256.532634)
		)
		(stroke
			(width 0)
			(type solid)
		)
		(fill yes)
		(layer "In4.Cu")
		(net "M_D_CPU1_CLK_DN<0>")
	)
	(gr_poly
		(pts
			(xy 80.861154 -255.216406) (xy 80.761078 -255.11633) (xy 80.661002 -255.216406) (xy 80.661002 -255.260856)
			(xy 80.861154 -255.260856)
		)
		(stroke
			(width 0)
			(type solid)
		)
		(fill yes)
		(layer "In4.Cu")
		(net "M_D_CPU1_SA_CA<6>")
	)
	(gr_poly
		(pts
			(xy 80.861154 -254.812546) (xy 80.861154 -254.768096) (xy 80.661002 -254.768096) (xy 80.661002 -254.812546)
			(xy 80.761078 -254.912622)
		)
		(stroke
			(width 0)
			(type solid)
		)
		(fill yes)
		(layer "In4.Cu")
		(net "M_D_CPU1_SA_CA<5>")
	)
	(gr_poly
		(pts
			(xy 80.861154 -253.596394) (xy 80.761078 -253.496318) (xy 80.661002 -253.596394) (xy 80.661002 -253.640844)
			(xy 80.861154 -253.640844)
		)
		(stroke
			(width 0)
			(type solid)
		)
		(fill yes)
		(layer "In4.Cu")
		(net "M_D_CPU1_SA_CA<2>")
	)
	(gr_poly
		(pts
			(xy 80.861154 -253.192534) (xy 80.861154 -253.148084) (xy 80.661002 -253.148084) (xy 80.661002 -253.192534)
			(xy 80.761078 -253.29261)
		)
		(stroke
			(width 0)
			(type solid)
		)
		(fill yes)
		(layer "In4.Cu")
		(net "M_D_CPU1_SA_CA<1>")
	)
	(gr_poly
		(pts
			(xy 80.861154 -251.572522) (xy 80.861154 -251.528072) (xy 80.661002 -251.528072) (xy 80.661002 -251.572522)
			(xy 80.761078 -251.672598)
		)
		(stroke
			(width 0)
			(type solid)
		)
		(fill yes)
		(layer "In4.Cu")
		(net "M_D_CPU1_SA_CS_N<0>")
	)
	(gr_poly
		(pts
			(xy 80.861154 -250.35637) (xy 80.761078 -250.256294) (xy 80.661002 -250.35637) (xy 80.661002 -250.40082)
			(xy 80.861154 -250.40082)
		)
		(stroke
			(width 0)
			(type solid)
		)
		(fill yes)
		(layer "In4.Cu")
		(net "M_D_CPU1_ALERT_R_N")
	)
	(gr_poly
		(pts
			(xy 80.861154 -248.736358) (xy 80.761078 -248.636282) (xy 80.661002 -248.736358) (xy 80.661002 -248.780808)
			(xy 80.861154 -248.780808)
		)
		(stroke
			(width 0)
			(type solid)
		)
		(fill yes)
		(layer "In4.Cu")
		(net "M_D_CPU1_SA_CB<5>")
	)
	(gr_poly
		(pts
			(xy 80.861154 -248.332498) (xy 80.861154 -248.288048) (xy 80.661002 -248.288048) (xy 80.661002 -248.332498)
			(xy 80.761078 -248.432574)
		)
		(stroke
			(width 0)
			(type solid)
		)
		(fill yes)
		(layer "In4.Cu")
		(net "M_D_CPU1_SA_CB<6>")
	)
	(gr_poly
		(pts
			(xy 80.861154 -247.116092) (xy 80.761078 -247.01627) (xy 80.661002 -247.116092) (xy 80.661002 -247.163844)
			(xy 80.861154 -247.163844)
		)
		(stroke
			(width 0)
			(type solid)
		)
		(fill yes)
		(layer "In4.Cu")
		(net "M_D_CPU1_SA_DQS_DN<9>")
	)
	(gr_poly
		(pts
			(xy 80.861154 -246.71274) (xy 80.861154 -246.664988) (xy 80.661002 -246.664988) (xy 80.661002 -246.71274)
			(xy 80.761078 -246.812562)
		)
		(stroke
			(width 0)
			(type solid)
		)
		(fill yes)
		(layer "In4.Cu")
		(net "M_D_CPU1_SA_DQS_DN<4>")
	)
	(gr_poly
		(pts
			(xy 80.861154 -245.496334) (xy 80.761078 -245.396258) (xy 80.661002 -245.496334) (xy 80.661002 -245.540784)
			(xy 80.861154 -245.540784)
		)
		(stroke
			(width 0)
			(type solid)
		)
		(fill yes)
		(layer "In4.Cu")
		(net "M_D_CPU1_SA_CB<1>")
	)
	(gr_poly
		(pts
			(xy 80.861154 -245.092474) (xy 80.861154 -245.048024) (xy 80.661002 -245.048024) (xy 80.661002 -245.092474)
			(xy 80.761078 -245.19255)
		)
		(stroke
			(width 0)
			(type solid)
		)
		(fill yes)
		(layer "In4.Cu")
		(net "M_D_CPU1_SA_CB<2>")
	)
	(gr_poly
		(pts
			(xy 80.861154 -243.876322) (xy 80.761078 -243.776246) (xy 80.661002 -243.876322) (xy 80.661002 -243.920772)
			(xy 80.861154 -243.920772)
		)
		(stroke
			(width 0)
			(type solid)
		)
		(fill yes)
		(layer "In4.Cu")
		(net "M_D_CPU1_SA_DQ<29>")
	)
	(gr_poly
		(pts
			(xy 80.861154 -243.472462) (xy 80.861154 -243.428012) (xy 80.661002 -243.428012) (xy 80.661002 -243.472462)
			(xy 80.761078 -243.572538)
		)
		(stroke
			(width 0)
			(type solid)
		)
		(fill yes)
		(layer "In4.Cu")
		(net "M_D_CPU1_SA_DQ<30>")
	)
	(gr_poly
		(pts
			(xy 80.861154 -242.256056) (xy 80.761078 -242.156234) (xy 80.661002 -242.256056) (xy 80.661002 -242.303808)
			(xy 80.861154 -242.303808)
		)
		(stroke
			(width 0)
			(type solid)
		)
		(fill yes)
		(layer "In4.Cu")
		(net "M_D_CPU1_SA_DQS_DN<8>")
	)
	(gr_poly
		(pts
			(xy 80.861154 -241.852704) (xy 80.861154 -241.804952) (xy 80.661002 -241.804952) (xy 80.661002 -241.852704)
			(xy 80.761078 -241.952526)
		)
		(stroke
			(width 0)
			(type solid)
		)
		(fill yes)
		(layer "In4.Cu")
		(net "M_D_CPU1_SA_DQS_DN<3>")
	)
	(gr_poly
		(pts
			(xy 80.861154 -240.636298) (xy 80.761078 -240.536222) (xy 80.661002 -240.636298) (xy 80.661002 -240.680748)
			(xy 80.861154 -240.680748)
		)
		(stroke
			(width 0)
			(type solid)
		)
		(fill yes)
		(layer "In4.Cu")
		(net "M_D_CPU1_SA_DQ<25>")
	)
	(gr_poly
		(pts
			(xy 80.861154 -240.232438) (xy 80.861154 -240.187988) (xy 80.661002 -240.187988) (xy 80.661002 -240.232438)
			(xy 80.761078 -240.332514)
		)
		(stroke
			(width 0)
			(type solid)
		)
		(fill yes)
		(layer "In4.Cu")
		(net "M_D_CPU1_SA_DQ<26>")
	)
	(gr_poly
		(pts
			(xy 80.861154 -239.016286) (xy 80.761078 -238.91621) (xy 80.661002 -239.016286) (xy 80.661002 -239.060736)
			(xy 80.861154 -239.060736)
		)
		(stroke
			(width 0)
			(type solid)
		)
		(fill yes)
		(layer "In4.Cu")
		(net "M_D_CPU1_SA_DQ<21>")
	)
	(gr_poly
		(pts
			(xy 80.861154 -238.612426) (xy 80.861154 -238.567976) (xy 80.661002 -238.567976) (xy 80.661002 -238.612426)
			(xy 80.761078 -238.712502)
		)
		(stroke
			(width 0)
			(type solid)
		)
		(fill yes)
		(layer "In4.Cu")
		(net "M_D_CPU1_SA_DQ<22>")
	)
	(gr_poly
		(pts
			(xy 80.861154 -237.39602) (xy 80.761078 -237.296198) (xy 80.661002 -237.39602) (xy 80.661002 -237.443772)
			(xy 80.861154 -237.443772)
		)
		(stroke
			(width 0)
			(type solid)
		)
		(fill yes)
		(layer "In4.Cu")
		(net "M_D_CPU1_SA_DQS_DN<7>")
	)
	(gr_poly
		(pts
			(xy 80.861154 -236.992668) (xy 80.861154 -236.944916) (xy 80.661002 -236.944916) (xy 80.661002 -236.992668)
			(xy 80.761078 -237.09249)
		)
		(stroke
			(width 0)
			(type solid)
		)
		(fill yes)
		(layer "In4.Cu")
		(net "M_D_CPU1_SA_DQS_DN<2>")
	)
	(gr_poly
		(pts
			(xy 80.861154 -235.776262) (xy 80.761078 -235.676186) (xy 80.661002 -235.776262) (xy 80.661002 -235.820712)
			(xy 80.861154 -235.820712)
		)
		(stroke
			(width 0)
			(type solid)
		)
		(fill yes)
		(layer "In4.Cu")
		(net "M_D_CPU1_SA_DQ<17>")
	)
	(gr_poly
		(pts
			(xy 80.861154 -235.372402) (xy 80.861154 -235.327952) (xy 80.661002 -235.327952) (xy 80.661002 -235.372402)
			(xy 80.761078 -235.472478)
		)
		(stroke
			(width 0)
			(type solid)
		)
		(fill yes)
		(layer "In4.Cu")
		(net "M_D_CPU1_SA_DQ<18>")
	)
	(gr_poly
		(pts
			(xy 80.861154 -234.15625) (xy 80.761078 -234.056174) (xy 80.661002 -234.15625) (xy 80.661002 -234.2007)
			(xy 80.861154 -234.2007)
		)
		(stroke
			(width 0)
			(type solid)
		)
		(fill yes)
		(layer "In4.Cu")
		(net "M_D_CPU1_SA_DQ<13>")
	)
	(gr_poly
		(pts
			(xy 80.861154 -233.75239) (xy 80.861154 -233.70794) (xy 80.661002 -233.70794) (xy 80.661002 -233.75239)
			(xy 80.761078 -233.852466)
		)
		(stroke
			(width 0)
			(type solid)
		)
		(fill yes)
		(layer "In4.Cu")
		(net "M_D_CPU1_SA_DQ<14>")
	)
	(gr_poly
		(pts
			(xy 80.861154 -232.535984) (xy 80.761078 -232.436162) (xy 80.661002 -232.535984) (xy 80.661002 -232.583736)
			(xy 80.861154 -232.583736)
		)
		(stroke
			(width 0)
			(type solid)
		)
		(fill yes)
		(layer "In4.Cu")
		(net "M_D_CPU1_SA_DQS_DN<6>")
	)
	(gr_poly
		(pts
			(xy 80.861154 -232.132632) (xy 80.861154 -232.08488) (xy 80.661002 -232.08488) (xy 80.661002 -232.132632)
			(xy 80.761078 -232.232454)
		)
		(stroke
			(width 0)
			(type solid)
		)
		(fill yes)
		(layer "In4.Cu")
		(net "M_D_CPU1_SA_DQS_DN<1>")
	)
	(gr_poly
		(pts
			(xy 80.861154 -230.916226) (xy 80.761078 -230.81615) (xy 80.661002 -230.916226) (xy 80.661002 -230.960676)
			(xy 80.861154 -230.960676)
		)
		(stroke
			(width 0)
			(type solid)
		)
		(fill yes)
		(layer "In4.Cu")
		(net "M_D_CPU1_SA_DQ<9>")
	)
	(gr_poly
		(pts
			(xy 80.861154 -230.51262) (xy 80.861154 -230.46817) (xy 80.661002 -230.46817) (xy 80.661002 -230.51262)
			(xy 80.761078 -230.612696)
		)
		(stroke
			(width 0)
			(type solid)
		)
		(fill yes)
		(layer "In4.Cu")
		(net "M_D_CPU1_SA_DQ<10>")
	)
	(gr_poly
		(pts
			(xy 80.879442 -224.034604) (xy 80.916018 -223.897952) (xy 80.779366 -223.861376) (xy 80.738218 -223.885252)
			(xy 80.83804 -224.05848)
		)
		(stroke
			(width 0)
			(type solid)
		)
		(fill yes)
		(layer "In4.Cu")
		(net "M_D_CPU1_SA_DQS_DP<0>")
	)
	(gr_poly
		(pts
			(xy 80.879696 -228.895402) (xy 80.916272 -228.75875) (xy 80.77962 -228.722174) (xy 80.741012 -228.744272)
			(xy 80.841088 -228.9175)
		)
		(stroke
			(width 0)
			(type solid)
		)
		(fill yes)
		(layer "In4.Cu")
		(net "M_D_CPU1_SA_DQ<5>")
	)
	(gr_poly
		(pts
			(xy 80.879696 -227.27539) (xy 80.916272 -227.138738) (xy 80.77962 -227.102162) (xy 80.741012 -227.12426)
			(xy 80.841088 -227.297488)
		)
		(stroke
			(width 0)
			(type solid)
		)
		(fill yes)
		(layer "In4.Cu")
		(net "M_D_CPU1_SA_DQ<4>")
	)
	(gr_poly
		(pts
			(xy 80.87995 -222.415354) (xy 80.916526 -222.278702) (xy 80.779874 -222.242126) (xy 80.741266 -222.264224)
			(xy 80.841342 -222.437452)
		)
		(stroke
			(width 0)
			(type solid)
		)
		(fill yes)
		(layer "In4.Cu")
		(net "M_D_CPU1_SA_DQ<1>")
	)
	(gr_poly
		(pts
			(xy 80.880458 -225.656902) (xy 80.917034 -225.52025) (xy 80.780382 -225.483674) (xy 80.739234 -225.507296)
			(xy 80.839056 -225.680524)
		)
		(stroke
			(width 0)
			(type solid)
		)
		(fill yes)
		(layer "In4.Cu")
		(net "M_D_CPU1_SA_DQS_DN<5>")
	)
	(gr_poly
		(pts
			(xy 81.081118 -293.175944) (xy 81.04251 -293.153846) (xy 80.905858 -293.190422) (xy 80.942434 -293.327074)
			(xy 80.981042 -293.349172)
		)
		(stroke
			(width 0)
			(type solid)
		)
		(fill yes)
		(layer "In4.Cu")
		(net "M_D_CPU1_SB_DQ<29>")
	)
	(gr_poly
		(pts
			(xy 81.161128 -292.108128) (xy 81.061052 -292.008052) (xy 80.960976 -292.108128) (xy 80.960976 -292.152578)
			(xy 81.161128 -292.152578)
		)
		(stroke
			(width 0)
			(type solid)
		)
		(fill yes)
		(layer "In4.Cu")
		(net "M_D_CPU1_SB_DQ<28>")
	)
	(gr_poly
		(pts
			(xy 81.161128 -291.704522) (xy 81.161128 -291.65677) (xy 80.960976 -291.65677) (xy 80.960976 -291.704522)
			(xy 81.061052 -291.804344)
		)
		(stroke
			(width 0)
			(type solid)
		)
		(fill yes)
		(layer "In4.Cu")
		(net "M_D_CPU1_SB_DQS_DP<8>")
	)
	(gr_poly
		(pts
			(xy 81.161128 -290.487862) (xy 81.061052 -290.38804) (xy 80.960976 -290.487862) (xy 80.960976 -290.535614)
			(xy 81.161128 -290.535614)
		)
		(stroke
			(width 0)
			(type solid)
		)
		(fill yes)
		(layer "In4.Cu")
		(net "M_D_CPU1_SB_DQS_DP<3>")
	)
	(gr_poly
		(pts
			(xy 81.161128 -290.084256) (xy 81.161128 -290.039806) (xy 80.960976 -290.039806) (xy 80.960976 -290.084256)
			(xy 81.061052 -290.184332)
		)
		(stroke
			(width 0)
			(type solid)
		)
		(fill yes)
		(layer "In4.Cu")
		(net "M_D_CPU1_SB_DQ<27>")
	)
	(gr_poly
		(pts
			(xy 81.161128 -288.868104) (xy 81.061052 -288.768028) (xy 80.960976 -288.868104) (xy 80.960976 -288.912554)
			(xy 81.161128 -288.912554)
		)
		(stroke
			(width 0)
			(type solid)
		)
		(fill yes)
		(layer "In4.Cu")
		(net "M_D_CPU1_SB_DQ<24>")
	)
	(gr_poly
		(pts
			(xy 81.161128 -288.464498) (xy 81.161128 -288.420048) (xy 80.960976 -288.420048) (xy 80.960976 -288.464498)
			(xy 81.061052 -288.564574)
		)
		(stroke
			(width 0)
			(type solid)
		)
		(fill yes)
		(layer "In4.Cu")
		(net "M_D_CPU1_SB_DQ<23>")
	)
	(gr_poly
		(pts
			(xy 81.161128 -287.248092) (xy 81.061052 -287.148016) (xy 80.960976 -287.248092) (xy 80.960976 -287.292542)
			(xy 81.161128 -287.292542)
		)
		(stroke
			(width 0)
			(type solid)
		)
		(fill yes)
		(layer "In4.Cu")
		(net "M_D_CPU1_SB_DQ<20>")
	)
	(gr_poly
		(pts
			(xy 81.161128 -286.844486) (xy 81.161128 -286.796734) (xy 80.960976 -286.796734) (xy 80.960976 -286.844486)
			(xy 81.061052 -286.944562)
		)
		(stroke
			(width 0)
			(type solid)
		)
		(fill yes)
		(layer "In4.Cu")
		(net "M_D_CPU1_SB_DQS_DP<7>")
	)
	(gr_poly
		(pts
			(xy 81.161128 -285.62808) (xy 81.061052 -285.528258) (xy 80.960976 -285.62808) (xy 80.960976 -285.675832)
			(xy 81.161128 -285.675832)
		)
		(stroke
			(width 0)
			(type solid)
		)
		(fill yes)
		(layer "In4.Cu")
		(net "M_D_CPU1_SB_DQS_DP<2>")
	)
	(gr_poly
		(pts
			(xy 81.161128 -285.224474) (xy 81.161128 -285.180024) (xy 80.960976 -285.180024) (xy 80.960976 -285.224474)
			(xy 81.061052 -285.32455)
		)
		(stroke
			(width 0)
			(type solid)
		)
		(fill yes)
		(layer "In4.Cu")
		(net "M_D_CPU1_SB_DQ<19>")
	)
	(gr_poly
		(pts
			(xy 81.161128 -284.008322) (xy 81.061052 -283.908246) (xy 80.960976 -284.008322) (xy 80.960976 -284.052772)
			(xy 81.161128 -284.052772)
		)
		(stroke
			(width 0)
			(type solid)
		)
		(fill yes)
		(layer "In4.Cu")
		(net "M_D_CPU1_SB_DQ<16>")
	)
	(gr_poly
		(pts
			(xy 81.161128 -283.604462) (xy 81.161128 -283.560012) (xy 80.960976 -283.560012) (xy 80.960976 -283.604462)
			(xy 81.061052 -283.704538)
		)
		(stroke
			(width 0)
			(type solid)
		)
		(fill yes)
		(layer "In4.Cu")
		(net "M_D_CPU1_SB_DQ<15>")
	)
	(gr_poly
		(pts
			(xy 81.161128 -282.38831) (xy 81.061052 -282.288234) (xy 80.960976 -282.38831) (xy 80.960976 -282.43276)
			(xy 81.161128 -282.43276)
		)
		(stroke
			(width 0)
			(type solid)
		)
		(fill yes)
		(layer "In4.Cu")
		(net "M_D_CPU1_SB_DQ<12>")
	)
	(gr_poly
		(pts
			(xy 81.161128 -281.984704) (xy 81.161128 -281.936952) (xy 80.960976 -281.936952) (xy 80.960976 -281.984704)
			(xy 81.061052 -282.084526)
		)
		(stroke
			(width 0)
			(type solid)
		)
		(fill yes)
		(layer "In4.Cu")
		(net "M_D_CPU1_SB_DQS_DP<6>")
	)
	(gr_poly
		(pts
			(xy 81.161128 -280.768044) (xy 81.061052 -280.668222) (xy 80.960976 -280.768044) (xy 80.960976 -280.815796)
			(xy 81.161128 -280.815796)
		)
		(stroke
			(width 0)
			(type solid)
		)
		(fill yes)
		(layer "In4.Cu")
		(net "M_D_CPU1_SB_DQS_DP<1>")
	)
	(gr_poly
		(pts
			(xy 81.161128 -280.364438) (xy 81.161128 -280.319988) (xy 80.960976 -280.319988) (xy 80.960976 -280.364438)
			(xy 81.061052 -280.464514)
		)
		(stroke
			(width 0)
			(type solid)
		)
		(fill yes)
		(layer "In4.Cu")
		(net "M_D_CPU1_SB_DQ<11>")
	)
	(gr_poly
		(pts
			(xy 81.161128 -279.148286) (xy 81.061052 -279.04821) (xy 80.960976 -279.148286) (xy 80.960976 -279.192736)
			(xy 81.161128 -279.192736)
		)
		(stroke
			(width 0)
			(type solid)
		)
		(fill yes)
		(layer "In4.Cu")
		(net "M_D_CPU1_SB_DQ<8>")
	)
	(gr_poly
		(pts
			(xy 81.161128 -278.744426) (xy 81.161128 -278.699976) (xy 80.960976 -278.699976) (xy 80.960976 -278.744426)
			(xy 81.061052 -278.844502)
		)
		(stroke
			(width 0)
			(type solid)
		)
		(fill yes)
		(layer "In4.Cu")
		(net "M_D_CPU1_SB_DQ<7>")
	)
	(gr_poly
		(pts
			(xy 81.161128 -277.528274) (xy 81.061052 -277.428198) (xy 80.960976 -277.528274) (xy 80.960976 -277.572724)
			(xy 81.161128 -277.572724)
		)
		(stroke
			(width 0)
			(type solid)
		)
		(fill yes)
		(layer "In4.Cu")
		(net "M_D_CPU1_SB_DQ<4>")
	)
	(gr_poly
		(pts
			(xy 81.161128 -277.124668) (xy 81.161128 -277.076916) (xy 80.960976 -277.076916) (xy 80.960976 -277.124668)
			(xy 81.061052 -277.22449)
		)
		(stroke
			(width 0)
			(type solid)
		)
		(fill yes)
		(layer "In4.Cu")
		(net "M_D_CPU1_SB_DQS_DP<5>")
	)
	(gr_poly
		(pts
			(xy 81.161128 -275.908008) (xy 81.061052 -275.808186) (xy 80.960976 -275.908008) (xy 80.960976 -275.95576)
			(xy 81.161128 -275.95576)
		)
		(stroke
			(width 0)
			(type solid)
		)
		(fill yes)
		(layer "In4.Cu")
		(net "M_D_CPU1_SB_DQS_DP<0>")
	)
	(gr_poly
		(pts
			(xy 81.161128 -275.504402) (xy 81.161128 -275.459952) (xy 80.960976 -275.459952) (xy 80.960976 -275.504402)
			(xy 81.061052 -275.604478)
		)
		(stroke
			(width 0)
			(type solid)
		)
		(fill yes)
		(layer "In4.Cu")
		(net "M_D_CPU1_SB_DQ<3>")
	)
	(gr_poly
		(pts
			(xy 81.161128 -274.28825) (xy 81.061052 -274.188174) (xy 80.960976 -274.28825) (xy 80.960976 -274.3327)
			(xy 81.161128 -274.3327)
		)
		(stroke
			(width 0)
			(type solid)
		)
		(fill yes)
		(layer "In4.Cu")
		(net "M_D_CPU1_SB_DQ<0>")
	)
	(gr_poly
		(pts
			(xy 81.161128 -273.88439) (xy 81.161128 -273.83994) (xy 80.960976 -273.83994) (xy 80.960976 -273.88439)
			(xy 81.061052 -273.984466)
		)
		(stroke
			(width 0)
			(type solid)
		)
		(fill yes)
		(layer "In4.Cu")
		(net "M_D_CPU1_SB_CB<3>")
	)
	(gr_poly
		(pts
			(xy 81.161128 -272.668238) (xy 81.061052 -272.568162) (xy 80.960976 -272.668238) (xy 80.960976 -272.712688)
			(xy 81.161128 -272.712688)
		)
		(stroke
			(width 0)
			(type solid)
		)
		(fill yes)
		(layer "In4.Cu")
		(net "M_D_CPU1_SB_CB<0>")
	)
	(gr_poly
		(pts
			(xy 81.161128 -272.264632) (xy 81.161128 -272.21688) (xy 80.960976 -272.21688) (xy 80.960976 -272.264632)
			(xy 81.061052 -272.364454)
		)
		(stroke
			(width 0)
			(type solid)
		)
		(fill yes)
		(layer "In4.Cu")
		(net "M_D_CPU1_SB_DQS_DP<4>")
	)
	(gr_poly
		(pts
			(xy 81.161128 -271.047972) (xy 81.061052 -270.94815) (xy 80.960976 -271.047972) (xy 80.960976 -271.095724)
			(xy 81.161128 -271.095724)
		)
		(stroke
			(width 0)
			(type solid)
		)
		(fill yes)
		(layer "In4.Cu")
		(net "M_D_CPU1_SB_DQS_DP<9>")
	)
	(gr_poly
		(pts
			(xy 81.161128 -270.644366) (xy 81.161128 -270.599916) (xy 80.960976 -270.599916) (xy 80.960976 -270.644366)
			(xy 81.061052 -270.744442)
		)
		(stroke
			(width 0)
			(type solid)
		)
		(fill yes)
		(layer "In4.Cu")
		(net "M_D_CPU1_SB_CB<7>")
	)
	(gr_poly
		(pts
			(xy 81.161128 -269.428214) (xy 81.061052 -269.328138) (xy 80.960976 -269.428214) (xy 80.960976 -269.472664)
			(xy 81.161128 -269.472664)
		)
		(stroke
			(width 0)
			(type solid)
		)
		(fill yes)
		(layer "In4.Cu")
		(net "M_D_CPU1_SB_CB<4>")
	)
	(gr_poly
		(pts
			(xy 81.161128 -267.801852) (xy 81.061052 -267.701776) (xy 80.960976 -267.801852) (xy 80.960976 -267.846302)
			(xy 81.161128 -267.846302)
		)
		(stroke
			(width 0)
			(type solid)
		)
		(fill yes)
		(layer "In4.Cu")
		(net "M_D_CPU1_SB_RSP<0>")
	)
	(gr_poly
		(pts
			(xy 81.161128 -265.78433) (xy 81.161128 -265.73988) (xy 80.960976 -265.73988) (xy 80.960976 -265.78433)
			(xy 81.061052 -265.884406)
		)
		(stroke
			(width 0)
			(type solid)
		)
		(fill yes)
		(layer "In4.Cu")
		(net "M_D_CPU1_SB_CS_N<0>")
	)
	(gr_poly
		(pts
			(xy 81.161128 -264.568178) (xy 81.061052 -264.468102) (xy 80.960976 -264.568178) (xy 80.960976 -264.612628)
			(xy 81.161128 -264.612628)
		)
		(stroke
			(width 0)
			(type solid)
		)
		(fill yes)
		(layer "In4.Cu")
		(net "M_D_CPU1_SB_CA<6>")
	)
	(gr_poly
		(pts
			(xy 81.161128 -264.164318) (xy 81.161128 -264.119868) (xy 80.960976 -264.119868) (xy 80.960976 -264.164318)
			(xy 81.061052 -264.264394)
		)
		(stroke
			(width 0)
			(type solid)
		)
		(fill yes)
		(layer "In4.Cu")
		(net "M_D_CPU1_SB_CA<5>")
	)
	(gr_poly
		(pts
			(xy 81.161128 -262.948166) (xy 81.061052 -262.84809) (xy 80.960976 -262.948166) (xy 80.960976 -262.992616)
			(xy 81.161128 -262.992616)
		)
		(stroke
			(width 0)
			(type solid)
		)
		(fill yes)
		(layer "In4.Cu")
		(net "M_D_CPU1_SB_CA<2>")
	)
	(gr_poly
		(pts
			(xy 81.161128 -262.544306) (xy 81.161128 -262.499856) (xy 80.960976 -262.499856) (xy 80.960976 -262.544306)
			(xy 81.061052 -262.644382)
		)
		(stroke
			(width 0)
			(type solid)
		)
		(fill yes)
		(layer "In4.Cu")
		(net "M_D_CPU1_SB_CA<1>")
	)
	(gr_poly
		(pts
			(xy 81.216754 -295.48074) (xy 81.180178 -295.344088) (xy 81.141824 -295.321736) (xy 81.041748 -295.494964)
			(xy 81.080356 -295.517316)
		)
		(stroke
			(width 0)
			(type solid)
		)
		(fill yes)
		(layer "In4.Cu")
		(net "M_D_CPU1_SB_DQ<31>")
	)
	(gr_poly
		(pts
			(xy 81.250282 -228.633274) (xy 81.150206 -228.460046) (xy 81.111852 -228.482398) (xy 81.075022 -228.61905)
			(xy 81.211674 -228.655626)
		)
		(stroke
			(width 0)
			(type solid)
		)
		(fill yes)
		(layer "In4.Cu")
		(net "M_D_CPU1_SA_DQ<6>")
	)
	(gr_poly
		(pts
			(xy 81.250282 -223.773238) (xy 81.150206 -223.60001) (xy 81.111852 -223.622362) (xy 81.075022 -223.759014)
			(xy 81.211674 -223.79559)
		)
		(stroke
			(width 0)
			(type solid)
		)
		(fill yes)
		(layer "In4.Cu")
		(net "M_D_CPU1_SA_DQ<3>")
	)
	(gr_poly
		(pts
			(xy 81.253076 -227.0125) (xy 81.153254 -226.839272) (xy 81.111852 -226.863148) (xy 81.075276 -226.999546)
			(xy 81.211928 -227.036376)
		)
		(stroke
			(width 0)
			(type solid)
		)
		(fill yes)
		(layer "In4.Cu")
		(net "M_D_CPU1_SA_DQS_DP<5>")
	)
	(gr_poly
		(pts
			(xy 81.253076 -225.392488) (xy 81.153254 -225.21926) (xy 81.111852 -225.243136) (xy 81.075276 -225.379534)
			(xy 81.211928 -225.416364)
		)
		(stroke
			(width 0)
			(type solid)
		)
		(fill yes)
		(layer "In4.Cu")
		(net "M_D_CPU1_SA_DQS_DN<0>")
	)
	(gr_poly
		(pts
			(xy 81.331054 -256.026158) (xy 81.230978 -255.926336) (xy 81.130902 -256.026158) (xy 81.130902 -256.07391)
			(xy 81.331054 -256.07391)
		)
		(stroke
			(width 0)
			(type solid)
		)
		(fill yes)
		(layer "In4.Cu")
		(net "M_D_CPU1_CLK_DP<0>")
	)
	(gr_poly
		(pts
			(xy 81.331054 -255.622552) (xy 81.331054 -255.578102) (xy 81.130902 -255.578102) (xy 81.130902 -255.622552)
			(xy 81.230978 -255.722628)
		)
		(stroke
			(width 0)
			(type solid)
		)
		(fill yes)
		(layer "In4.Cu")
		(net "M_D_CPU1_SA_PAR")
	)
	(gr_poly
		(pts
			(xy 81.331054 -254.4064) (xy 81.230978 -254.306324) (xy 81.130902 -254.4064) (xy 81.130902 -254.45085)
			(xy 81.331054 -254.45085)
		)
		(stroke
			(width 0)
			(type solid)
		)
		(fill yes)
		(layer "In4.Cu")
		(net "M_D_CPU1_SA_CA<4>")
	)
	(gr_poly
		(pts
			(xy 81.331054 -254.00254) (xy 81.331054 -253.95809) (xy 81.130902 -253.95809) (xy 81.130902 -254.00254)
			(xy 81.230978 -254.102616)
		)
		(stroke
			(width 0)
			(type solid)
		)
		(fill yes)
		(layer "In4.Cu")
		(net "M_D_CPU1_SA_CA<3>")
	)
	(gr_poly
		(pts
			(xy 81.331054 -252.786388) (xy 81.230978 -252.686312) (xy 81.130902 -252.786388) (xy 81.130902 -252.830838)
			(xy 81.331054 -252.830838)
		)
		(stroke
			(width 0)
			(type solid)
		)
		(fill yes)
		(layer "In4.Cu")
		(net "M_D_CPU1_SA_CA<0>")
	)
	(gr_poly
		(pts
			(xy 81.331054 -252.382528) (xy 81.331054 -252.338078) (xy 81.130902 -252.338078) (xy 81.130902 -252.382528)
			(xy 81.230978 -252.482604)
		)
		(stroke
			(width 0)
			(type solid)
		)
		(fill yes)
		(layer "In4.Cu")
		(net "M_D_CPU1_SA_CS_N<1>")
	)
	(gr_poly
		(pts
			(xy 81.331054 -250.762516) (xy 81.331054 -250.718066) (xy 81.130902 -250.718066) (xy 81.130902 -250.762516)
			(xy 81.230978 -250.862592)
		)
		(stroke
			(width 0)
			(type solid)
		)
		(fill yes)
		(layer "In4.Cu")
		(net "M_D_CPU1_RESET_N")
	)
	(gr_poly
		(pts
			(xy 81.331054 -249.142504) (xy 81.331054 -249.098054) (xy 81.130902 -249.098054) (xy 81.130902 -249.142504)
			(xy 81.230978 -249.24258)
		)
		(stroke
			(width 0)
			(type solid)
		)
		(fill yes)
		(layer "In4.Cu")
		(net "M_D_CPU1_SA_CB<7>")
	)
	(gr_poly
		(pts
			(xy 81.331054 -247.926352) (xy 81.230978 -247.826276) (xy 81.130902 -247.926352) (xy 81.130902 -247.970802)
			(xy 81.331054 -247.970802)
		)
		(stroke
			(width 0)
			(type solid)
		)
		(fill yes)
		(layer "In4.Cu")
		(net "M_D_CPU1_SA_CB<4>")
	)
	(gr_poly
		(pts
			(xy 81.331054 -247.522746) (xy 81.331054 -247.474994) (xy 81.130902 -247.474994) (xy 81.130902 -247.522746)
			(xy 81.230978 -247.622568)
		)
		(stroke
			(width 0)
			(type solid)
		)
		(fill yes)
		(layer "In4.Cu")
		(net "M_D_CPU1_SA_DQS_DP<9>")
	)
	(gr_poly
		(pts
			(xy 81.331054 -246.306086) (xy 81.230978 -246.206264) (xy 81.130902 -246.306086) (xy 81.130902 -246.353838)
			(xy 81.331054 -246.353838)
		)
		(stroke
			(width 0)
			(type solid)
		)
		(fill yes)
		(layer "In4.Cu")
		(net "M_D_CPU1_SA_DQS_DP<4>")
	)
	(gr_poly
		(pts
			(xy 81.331054 -245.90248) (xy 81.331054 -245.85803) (xy 81.130902 -245.85803) (xy 81.130902 -245.90248)
			(xy 81.230978 -246.002556)
		)
		(stroke
			(width 0)
			(type solid)
		)
		(fill yes)
		(layer "In4.Cu")
		(net "M_D_CPU1_SA_CB<3>")
	)
	(gr_poly
		(pts
			(xy 81.331054 -244.686328) (xy 81.230978 -244.586252) (xy 81.130902 -244.686328) (xy 81.130902 -244.730778)
			(xy 81.331054 -244.730778)
		)
		(stroke
			(width 0)
			(type solid)
		)
		(fill yes)
		(layer "In4.Cu")
		(net "M_D_CPU1_SA_CB<0>")
	)
	(gr_poly
		(pts
			(xy 81.331054 -244.282468) (xy 81.331054 -244.238018) (xy 81.130902 -244.238018) (xy 81.130902 -244.282468)
			(xy 81.230978 -244.382544)
		)
		(stroke
			(width 0)
			(type solid)
		)
		(fill yes)
		(layer "In4.Cu")
		(net "M_D_CPU1_SA_DQ<31>")
	)
	(gr_poly
		(pts
			(xy 81.331054 -243.066316) (xy 81.230978 -242.96624) (xy 81.130902 -243.066316) (xy 81.130902 -243.110766)
			(xy 81.331054 -243.110766)
		)
		(stroke
			(width 0)
			(type solid)
		)
		(fill yes)
		(layer "In4.Cu")
		(net "M_D_CPU1_SA_DQ<28>")
	)
	(gr_poly
		(pts
			(xy 81.331054 -242.66271) (xy 81.331054 -242.614958) (xy 81.130902 -242.614958) (xy 81.130902 -242.66271)
			(xy 81.230978 -242.762532)
		)
		(stroke
			(width 0)
			(type solid)
		)
		(fill yes)
		(layer "In4.Cu")
		(net "M_D_CPU1_SA_DQS_DP<8>")
	)
	(gr_poly
		(pts
			(xy 81.331054 -241.44605) (xy 81.230978 -241.346228) (xy 81.130902 -241.44605) (xy 81.130902 -241.493802)
			(xy 81.331054 -241.493802)
		)
		(stroke
			(width 0)
			(type solid)
		)
		(fill yes)
		(layer "In4.Cu")
		(net "M_D_CPU1_SA_DQS_DP<3>")
	)
	(gr_poly
		(pts
			(xy 81.331054 -241.042444) (xy 81.331054 -240.997994) (xy 81.130902 -240.997994) (xy 81.130902 -241.042444)
			(xy 81.230978 -241.14252)
		)
		(stroke
			(width 0)
			(type solid)
		)
		(fill yes)
		(layer "In4.Cu")
		(net "M_D_CPU1_SA_DQ<27>")
	)
	(gr_poly
		(pts
			(xy 81.331054 -239.826292) (xy 81.230978 -239.726216) (xy 81.130902 -239.826292) (xy 81.130902 -239.870742)
			(xy 81.331054 -239.870742)
		)
		(stroke
			(width 0)
			(type solid)
		)
		(fill yes)
		(layer "In4.Cu")
		(net "M_D_CPU1_SA_DQ<24>")
	)
	(gr_poly
		(pts
			(xy 81.331054 -239.422432) (xy 81.331054 -239.377982) (xy 81.130902 -239.377982) (xy 81.130902 -239.422432)
			(xy 81.230978 -239.522508)
		)
		(stroke
			(width 0)
			(type solid)
		)
		(fill yes)
		(layer "In4.Cu")
		(net "M_D_CPU1_SA_DQ<23>")
	)
	(gr_poly
		(pts
			(xy 81.331054 -238.20628) (xy 81.230978 -238.106204) (xy 81.130902 -238.20628) (xy 81.130902 -238.25073)
			(xy 81.331054 -238.25073)
		)
		(stroke
			(width 0)
			(type solid)
		)
		(fill yes)
		(layer "In4.Cu")
		(net "M_D_CPU1_SA_DQ<20>")
	)
	(gr_poly
		(pts
			(xy 81.331054 -237.802674) (xy 81.331054 -237.754922) (xy 81.130902 -237.754922) (xy 81.130902 -237.802674)
			(xy 81.230978 -237.902496)
		)
		(stroke
			(width 0)
			(type solid)
		)
		(fill yes)
		(layer "In4.Cu")
		(net "M_D_CPU1_SA_DQS_DP<7>")
	)
	(gr_poly
		(pts
			(xy 81.331054 -236.586014) (xy 81.230978 -236.486192) (xy 81.130902 -236.586014) (xy 81.130902 -236.633766)
			(xy 81.331054 -236.633766)
		)
		(stroke
			(width 0)
			(type solid)
		)
		(fill yes)
		(layer "In4.Cu")
		(net "M_D_CPU1_SA_DQS_DP<2>")
	)
	(gr_poly
		(pts
			(xy 81.331054 -236.182408) (xy 81.331054 -236.137958) (xy 81.130902 -236.137958) (xy 81.130902 -236.182408)
			(xy 81.230978 -236.282484)
		)
		(stroke
			(width 0)
			(type solid)
		)
		(fill yes)
		(layer "In4.Cu")
		(net "M_D_CPU1_SA_DQ<19>")
	)
	(gr_poly
		(pts
			(xy 81.331054 -234.966256) (xy 81.230978 -234.86618) (xy 81.130902 -234.966256) (xy 81.130902 -235.010706)
			(xy 81.331054 -235.010706)
		)
		(stroke
			(width 0)
			(type solid)
		)
		(fill yes)
		(layer "In4.Cu")
		(net "M_D_CPU1_SA_DQ<16>")
	)
	(gr_poly
		(pts
			(xy 81.331054 -234.562396) (xy 81.331054 -234.517946) (xy 81.130902 -234.517946) (xy 81.130902 -234.562396)
			(xy 81.230978 -234.662472)
		)
		(stroke
			(width 0)
			(type solid)
		)
		(fill yes)
		(layer "In4.Cu")
		(net "M_D_CPU1_SA_DQ<15>")
	)
	(gr_poly
		(pts
			(xy 81.331054 -233.346244) (xy 81.230978 -233.246168) (xy 81.130902 -233.346244) (xy 81.130902 -233.390694)
			(xy 81.331054 -233.390694)
		)
		(stroke
			(width 0)
			(type solid)
		)
		(fill yes)
		(layer "In4.Cu")
		(net "M_D_CPU1_SA_DQ<12>")
	)
	(gr_poly
		(pts
			(xy 81.331054 -232.942638) (xy 81.331054 -232.894886) (xy 81.130902 -232.894886) (xy 81.130902 -232.942638)
			(xy 81.230978 -233.04246)
		)
		(stroke
			(width 0)
			(type solid)
		)
		(fill yes)
		(layer "In4.Cu")
		(net "M_D_CPU1_SA_DQS_DP<6>")
	)
	(gr_poly
		(pts
			(xy 81.331054 -231.725978) (xy 81.230978 -231.626156) (xy 81.130902 -231.725978) (xy 81.130902 -231.77373)
			(xy 81.331054 -231.77373)
		)
		(stroke
			(width 0)
			(type solid)
		)
		(fill yes)
		(layer "In4.Cu")
		(net "M_D_CPU1_SA_DQS_DP<1>")
	)
	(gr_poly
		(pts
			(xy 81.331054 -231.322626) (xy 81.331054 -231.278176) (xy 81.130902 -231.278176) (xy 81.130902 -231.322626)
			(xy 81.230978 -231.422702)
		)
		(stroke
			(width 0)
			(type solid)
		)
		(fill yes)
		(layer "In4.Cu")
		(net "M_D_CPU1_SA_DQ<11>")
	)
	(gr_poly
		(pts
			(xy 81.331054 -230.10622) (xy 81.230978 -230.006144) (xy 81.130902 -230.10622) (xy 81.130902 -230.15067)
			(xy 81.331054 -230.15067)
		)
		(stroke
			(width 0)
			(type solid)
		)
		(fill yes)
		(layer "In4.Cu")
		(net "M_D_CPU1_SA_DQ<8>")
	)
	(gr_poly
		(pts
			(xy 81.331054 -229.702614) (xy 81.331054 -229.658164) (xy 81.130902 -229.658164) (xy 81.130902 -229.702614)
			(xy 81.230978 -229.80269)
		)
		(stroke
			(width 0)
			(type solid)
		)
		(fill yes)
		(layer "In4.Cu")
		(net "M_D_CPU1_SA_DQ<7>")
	)
	(gr_poly
		(pts
			(xy 81.350358 -228.086666) (xy 81.386934 -227.950014) (xy 81.250536 -227.913438) (xy 81.211928 -227.93579)
			(xy 81.312004 -228.109018)
		)
		(stroke
			(width 0)
			(type solid)
		)
		(fill yes)
		(layer "In4.Cu")
		(net "M_D_CPU1_SA_DQ<4>")
	)
	(gr_poly
		(pts
			(xy 81.350358 -226.466908) (xy 81.386934 -226.330256) (xy 81.250282 -226.29368) (xy 81.209134 -226.317302)
			(xy 81.308956 -226.49053)
		)
		(stroke
			(width 0)
			(type solid)
		)
		(fill yes)
		(layer "In4.Cu")
		(net "M_D_CPU1_SA_DQS_DN<5>")
	)
	(gr_poly
		(pts
			(xy 81.350358 -224.84588) (xy 81.386934 -224.709482) (xy 81.250282 -224.672652) (xy 81.209134 -224.696528)
			(xy 81.308956 -224.869756)
		)
		(stroke
			(width 0)
			(type solid)
		)
		(fill yes)
		(layer "In4.Cu")
		(net "M_D_CPU1_SA_DQS_DP<0>")
	)
	(gr_poly
		(pts
			(xy 81.350358 -223.22663) (xy 81.386934 -223.089978) (xy 81.250536 -223.053402) (xy 81.211928 -223.075754)
			(xy 81.312004 -223.248982)
		)
		(stroke
			(width 0)
			(type solid)
		)
		(fill yes)
		(layer "In4.Cu")
		(net "M_D_CPU1_SA_DQ<1>")
	)
	(gr_poly
		(pts
			(xy 81.631028 -292.514274) (xy 81.631028 -292.469824) (xy 81.430876 -292.469824) (xy 81.430876 -292.514274)
			(xy 81.530952 -292.61435)
		)
		(stroke
			(width 0)
			(type solid)
		)
		(fill yes)
		(layer "In4.Cu")
		(net "M_D_CPU1_SB_DQ<30>")
	)
	(gr_poly
		(pts
			(xy 81.631028 -291.297868) (xy 81.530952 -291.198046) (xy 81.430876 -291.297868) (xy 81.430876 -291.34562)
			(xy 81.631028 -291.34562)
		)
		(stroke
			(width 0)
			(type solid)
		)
		(fill yes)
		(layer "In4.Cu")
		(net "M_D_CPU1_SB_DQS_DN<8>")
	)
	(gr_poly
		(pts
			(xy 81.631028 -290.894516) (xy 81.631028 -290.846764) (xy 81.430876 -290.846764) (xy 81.430876 -290.894516)
			(xy 81.530952 -290.994338)
		)
		(stroke
			(width 0)
			(type solid)
		)
		(fill yes)
		(layer "In4.Cu")
		(net "M_D_CPU1_SB_DQS_DN<3>")
	)
	(gr_poly
		(pts
			(xy 81.631028 -289.67811) (xy 81.530952 -289.578034) (xy 81.430876 -289.67811) (xy 81.430876 -289.72256)
			(xy 81.631028 -289.72256)
		)
		(stroke
			(width 0)
			(type solid)
		)
		(fill yes)
		(layer "In4.Cu")
		(net "M_D_CPU1_SB_DQ<25>")
	)
	(gr_poly
		(pts
			(xy 81.631028 -289.27425) (xy 81.631028 -289.2298) (xy 81.430876 -289.2298) (xy 81.430876 -289.27425)
			(xy 81.530952 -289.374326)
		)
		(stroke
			(width 0)
			(type solid)
		)
		(fill yes)
		(layer "In4.Cu")
		(net "M_D_CPU1_SB_DQ<26>")
	)
	(gr_poly
		(pts
			(xy 81.631028 -288.058098) (xy 81.530952 -287.958022) (xy 81.430876 -288.058098) (xy 81.430876 -288.102548)
			(xy 81.631028 -288.102548)
		)
		(stroke
			(width 0)
			(type solid)
		)
		(fill yes)
		(layer "In4.Cu")
		(net "M_D_CPU1_SB_DQ<21>")
	)
	(gr_poly
		(pts
			(xy 81.631028 -287.654492) (xy 81.631028 -287.610042) (xy 81.430876 -287.610042) (xy 81.430876 -287.654492)
			(xy 81.530952 -287.754568)
		)
		(stroke
			(width 0)
			(type solid)
		)
		(fill yes)
		(layer "In4.Cu")
		(net "M_D_CPU1_SB_DQ<22>")
	)
	(gr_poly
		(pts
			(xy 81.631028 -286.438086) (xy 81.530952 -286.33801) (xy 81.430876 -286.438086) (xy 81.430876 -286.485838)
			(xy 81.631028 -286.485838)
		)
		(stroke
			(width 0)
			(type solid)
		)
		(fill yes)
		(layer "In4.Cu")
		(net "M_D_CPU1_SB_DQS_DN<7>")
	)
	(gr_poly
		(pts
			(xy 81.631028 -286.034734) (xy 81.631028 -285.986982) (xy 81.430876 -285.986982) (xy 81.430876 -286.034734)
			(xy 81.530952 -286.134556)
		)
		(stroke
			(width 0)
			(type solid)
		)
		(fill yes)
		(layer "In4.Cu")
		(net "M_D_CPU1_SB_DQS_DN<2>")
	)
	(gr_poly
		(pts
			(xy 81.631028 -284.818328) (xy 81.530952 -284.718252) (xy 81.430876 -284.818328) (xy 81.430876 -284.862778)
			(xy 81.631028 -284.862778)
		)
		(stroke
			(width 0)
			(type solid)
		)
		(fill yes)
		(layer "In4.Cu")
		(net "M_D_CPU1_SB_DQ<17>")
	)
	(gr_poly
		(pts
			(xy 81.631028 -284.414468) (xy 81.631028 -284.370018) (xy 81.430876 -284.370018) (xy 81.430876 -284.414468)
			(xy 81.530952 -284.514544)
		)
		(stroke
			(width 0)
			(type solid)
		)
		(fill yes)
		(layer "In4.Cu")
		(net "M_D_CPU1_SB_DQ<18>")
	)
	(gr_poly
		(pts
			(xy 81.631028 -283.198316) (xy 81.530952 -283.09824) (xy 81.430876 -283.198316) (xy 81.430876 -283.242766)
			(xy 81.631028 -283.242766)
		)
		(stroke
			(width 0)
			(type solid)
		)
		(fill yes)
		(layer "In4.Cu")
		(net "M_D_CPU1_SB_DQ<13>")
	)
	(gr_poly
		(pts
			(xy 81.631028 -282.794456) (xy 81.631028 -282.750006) (xy 81.430876 -282.750006) (xy 81.430876 -282.794456)
			(xy 81.530952 -282.894532)
		)
		(stroke
			(width 0)
			(type solid)
		)
		(fill yes)
		(layer "In4.Cu")
		(net "M_D_CPU1_SB_DQ<14>")
	)
	(gr_poly
		(pts
			(xy 81.631028 -281.57805) (xy 81.530952 -281.478228) (xy 81.430876 -281.57805) (xy 81.430876 -281.625802)
			(xy 81.631028 -281.625802)
		)
		(stroke
			(width 0)
			(type solid)
		)
		(fill yes)
		(layer "In4.Cu")
		(net "M_D_CPU1_SB_DQS_DN<6>")
	)
	(gr_poly
		(pts
			(xy 81.631028 -281.174698) (xy 81.631028 -281.126946) (xy 81.430876 -281.126946) (xy 81.430876 -281.174698)
			(xy 81.530952 -281.27452)
		)
		(stroke
			(width 0)
			(type solid)
		)
		(fill yes)
		(layer "In4.Cu")
		(net "M_D_CPU1_SB_DQS_DN<1>")
	)
	(gr_poly
		(pts
			(xy 81.631028 -279.958292) (xy 81.530952 -279.858216) (xy 81.430876 -279.958292) (xy 81.430876 -280.002742)
			(xy 81.631028 -280.002742)
		)
		(stroke
			(width 0)
			(type solid)
		)
		(fill yes)
		(layer "In4.Cu")
		(net "M_D_CPU1_SB_DQ<9>")
	)
	(gr_poly
		(pts
			(xy 81.631028 -279.554432) (xy 81.631028 -279.509982) (xy 81.430876 -279.509982) (xy 81.430876 -279.554432)
			(xy 81.530952 -279.654508)
		)
		(stroke
			(width 0)
			(type solid)
		)
		(fill yes)
		(layer "In4.Cu")
		(net "M_D_CPU1_SB_DQ<10>")
	)
	(gr_poly
		(pts
			(xy 81.631028 -278.33828) (xy 81.530952 -278.238204) (xy 81.430876 -278.33828) (xy 81.430876 -278.38273)
			(xy 81.631028 -278.38273)
		)
		(stroke
			(width 0)
			(type solid)
		)
		(fill yes)
		(layer "In4.Cu")
		(net "M_D_CPU1_SB_DQ<5>")
	)
	(gr_poly
		(pts
			(xy 81.631028 -277.93442) (xy 81.631028 -277.88997) (xy 81.430876 -277.88997) (xy 81.430876 -277.93442)
			(xy 81.530952 -278.034496)
		)
		(stroke
			(width 0)
			(type solid)
		)
		(fill yes)
		(layer "In4.Cu")
		(net "M_D_CPU1_SB_DQ<6>")
	)
	(gr_poly
		(pts
			(xy 81.631028 -275.098256) (xy 81.530952 -274.99818) (xy 81.430876 -275.098256) (xy 81.430876 -275.142706)
			(xy 81.631028 -275.142706)
		)
		(stroke
			(width 0)
			(type solid)
		)
		(fill yes)
		(layer "In4.Cu")
		(net "M_D_CPU1_SB_DQ<1>")
	)
	(gr_poly
		(pts
			(xy 81.631028 -274.694396) (xy 81.631028 -274.649946) (xy 81.430876 -274.649946) (xy 81.430876 -274.694396)
			(xy 81.530952 -274.794472)
		)
		(stroke
			(width 0)
			(type solid)
		)
		(fill yes)
		(layer "In4.Cu")
		(net "M_D_CPU1_SB_DQ<2>")
	)
	(gr_poly
		(pts
			(xy 81.631028 -273.478244) (xy 81.530952 -273.378168) (xy 81.430876 -273.478244) (xy 81.430876 -273.522694)
			(xy 81.631028 -273.522694)
		)
		(stroke
			(width 0)
			(type solid)
		)
		(fill yes)
		(layer "In4.Cu")
		(net "M_D_CPU1_SB_CB<1>")
	)
	(gr_poly
		(pts
			(xy 81.631028 -273.074384) (xy 81.631028 -273.029934) (xy 81.430876 -273.029934) (xy 81.430876 -273.074384)
			(xy 81.530952 -273.17446)
		)
		(stroke
			(width 0)
			(type solid)
		)
		(fill yes)
		(layer "In4.Cu")
		(net "M_D_CPU1_SB_CB<2>")
	)
	(gr_poly
		(pts
			(xy 81.631028 -271.857978) (xy 81.530952 -271.758156) (xy 81.430876 -271.857978) (xy 81.430876 -271.90573)
			(xy 81.631028 -271.90573)
		)
		(stroke
			(width 0)
			(type solid)
		)
		(fill yes)
		(layer "In4.Cu")
		(net "M_D_CPU1_SB_DQS_DN<4>")
	)
	(gr_poly
		(pts
			(xy 81.631028 -271.454626) (xy 81.631028 -271.406874) (xy 81.430876 -271.406874) (xy 81.430876 -271.454626)
			(xy 81.530952 -271.554448)
		)
		(stroke
			(width 0)
			(type solid)
		)
		(fill yes)
		(layer "In4.Cu")
		(net "M_D_CPU1_SB_DQS_DN<9>")
	)
	(gr_poly
		(pts
			(xy 81.631028 -270.23822) (xy 81.530952 -270.138144) (xy 81.430876 -270.23822) (xy 81.430876 -270.28267)
			(xy 81.631028 -270.28267)
		)
		(stroke
			(width 0)
			(type solid)
		)
		(fill yes)
		(layer "In4.Cu")
		(net "M_D_CPU1_SB_CB<5>")
	)
	(gr_poly
		(pts
			(xy 81.631028 -269.83436) (xy 81.631028 -269.78991) (xy 81.430876 -269.78991) (xy 81.430876 -269.83436)
			(xy 81.530952 -269.934436)
		)
		(stroke
			(width 0)
			(type solid)
		)
		(fill yes)
		(layer "In4.Cu")
		(net "M_D_CPU1_SB_CB<6>")
	)
	(gr_poly
		(pts
			(xy 81.631028 -266.594336) (xy 81.631028 -266.549886) (xy 81.430876 -266.549886) (xy 81.430876 -266.594336)
			(xy 81.530952 -266.694412)
		)
		(stroke
			(width 0)
			(type solid)
		)
		(fill yes)
		(layer "In4.Cu")
		(net "M_D_CPU1_SB_CS_N<1>")
	)
	(gr_poly
		(pts
			(xy 81.631028 -264.974324) (xy 81.631028 -264.929874) (xy 81.430876 -264.929874) (xy 81.430876 -264.974324)
			(xy 81.530952 -265.0744)
		)
		(stroke
			(width 0)
			(type solid)
		)
		(fill yes)
		(layer "In4.Cu")
		(net "M_D_CPU1_SB_PAR")
	)
	(gr_poly
		(pts
			(xy 81.631028 -263.758172) (xy 81.530952 -263.658096) (xy 81.430876 -263.758172) (xy 81.430876 -263.802622)
			(xy 81.631028 -263.802622)
		)
		(stroke
			(width 0)
			(type solid)
		)
		(fill yes)
		(layer "In4.Cu")
		(net "M_D_CPU1_SB_CA<4>")
	)
	(gr_poly
		(pts
			(xy 81.631028 -263.354312) (xy 81.631028 -263.309862) (xy 81.430876 -263.309862) (xy 81.430876 -263.354312)
			(xy 81.530952 -263.454388)
		)
		(stroke
			(width 0)
			(type solid)
		)
		(fill yes)
		(layer "In4.Cu")
		(net "M_D_CPU1_SB_CA<3>")
	)
	(gr_poly
		(pts
			(xy 81.631028 -262.13816) (xy 81.530952 -262.038084) (xy 81.430876 -262.13816) (xy 81.430876 -262.18261)
			(xy 81.631028 -262.18261)
		)
		(stroke
			(width 0)
			(type solid)
		)
		(fill yes)
		(layer "In4.Cu")
		(net "M_D_CPU1_SB_CA<0>")
	)
	(gr_poly
		(pts
			(xy 81.637124 -266.991846) (xy 81.537302 -266.89177) (xy 81.437226 -266.991846) (xy 81.437226 -267.036296)
			(xy 81.637124 -267.036296)
		)
		(stroke
			(width 0)
			(type solid)
		)
		(fill yes)
		(layer "In4.Cu")
		(net "M_D_CPU1_SA_RSP<0>")
	)
	(gr_poly
		(pts
			(xy 81.638394 -276.718268) (xy 81.538318 -276.618192) (xy 81.438242 -276.718268) (xy 81.438242 -276.765766)
			(xy 81.638394 -276.765766)
		)
		(stroke
			(width 0)
			(type solid)
		)
		(fill yes)
		(layer "In4.Cu")
		(net "M_D_CPU1_SB_DQS_DN<5>")
	)
	(gr_poly
		(pts
			(xy 81.638394 -276.314408) (xy 81.638394 -276.26691) (xy 81.438242 -276.26691) (xy 81.438242 -276.314408)
			(xy 81.538318 -276.414484)
		)
		(stroke
			(width 0)
			(type solid)
		)
		(fill yes)
		(layer "In4.Cu")
		(net "M_D_CPU1_SB_DQS_DN<0>")
	)
	(gr_poly
		(pts
			(xy 81.687162 -294.670734) (xy 81.650332 -294.534082) (xy 81.611978 -294.51173) (xy 81.511902 -294.684958)
			(xy 81.55051 -294.70731)
		)
		(stroke
			(width 0)
			(type solid)
		)
		(fill yes)
		(layer "In4.Cu")
		(net "M_D_CPU1_SB_DQ<31>")
	)
	(gr_poly
		(pts
			(xy 81.720182 -224.583244) (xy 81.620106 -224.410016) (xy 81.581752 -224.432368) (xy 81.544922 -224.56902)
			(xy 81.681574 -224.605596)
		)
		(stroke
			(width 0)
			(type solid)
		)
		(fill yes)
		(layer "In4.Cu")
		(net "M_D_CPU1_SA_DQ<3>")
	)
	(gr_poly
		(pts
			(xy 81.720182 -222.963232) (xy 81.620106 -222.790004) (xy 81.581752 -222.812356) (xy 81.544922 -222.949008)
			(xy 81.681574 -222.985584)
		)
		(stroke
			(width 0)
			(type solid)
		)
		(fill yes)
		(layer "In4.Cu")
		(net "M_D_CPU1_SA_DQ<2>")
	)
	(gr_poly
		(pts
			(xy 81.722976 -227.822506) (xy 81.623154 -227.649278) (xy 81.581752 -227.673154) (xy 81.545176 -227.809552)
			(xy 81.681828 -227.846128)
		)
		(stroke
			(width 0)
			(type solid)
		)
		(fill yes)
		(layer "In4.Cu")
		(net "M_D_CPU1_SA_DQS_DP<5>")
	)
	(gr_poly
		(pts
			(xy 81.722976 -226.202494) (xy 81.623154 -226.029266) (xy 81.581752 -226.053142) (xy 81.545176 -226.18954)
			(xy 81.681828 -226.22637)
		)
		(stroke
			(width 0)
			(type solid)
		)
		(fill yes)
		(layer "In4.Cu")
		(net "M_D_CPU1_SA_DQS_DN<0>")
	)
	(gr_poly
		(pts
			(xy 81.801208 -256.432812) (xy 81.801208 -256.38506) (xy 81.601056 -256.38506) (xy 81.601056 -256.432812)
			(xy 81.701132 -256.532634)
		)
		(stroke
			(width 0)
			(type solid)
		)
		(fill yes)
		(layer "In4.Cu")
		(net "M_D_CPU1_CLK_DN<0>")
	)
	(gr_poly
		(pts
			(xy 81.801208 -255.216406) (xy 81.701132 -255.11633) (xy 81.601056 -255.216406) (xy 81.601056 -255.260856)
			(xy 81.801208 -255.260856)
		)
		(stroke
			(width 0)
			(type solid)
		)
		(fill yes)
		(layer "In4.Cu")
		(net "M_D_CPU1_SA_CA<6>")
	)
	(gr_poly
		(pts
			(xy 81.801208 -254.812546) (xy 81.801208 -254.768096) (xy 81.601056 -254.768096) (xy 81.601056 -254.812546)
			(xy 81.701132 -254.912622)
		)
		(stroke
			(width 0)
			(type solid)
		)
		(fill yes)
		(layer "In4.Cu")
		(net "M_D_CPU1_SA_CA<5>")
	)
	(gr_poly
		(pts
			(xy 81.801208 -253.596394) (xy 81.701132 -253.496318) (xy 81.601056 -253.596394) (xy 81.601056 -253.640844)
			(xy 81.801208 -253.640844)
		)
		(stroke
			(width 0)
			(type solid)
		)
		(fill yes)
		(layer "In4.Cu")
		(net "M_D_CPU1_SA_CA<2>")
	)
	(gr_poly
		(pts
			(xy 81.801208 -253.192534) (xy 81.801208 -253.148084) (xy 81.601056 -253.148084) (xy 81.601056 -253.192534)
			(xy 81.701132 -253.29261)
		)
		(stroke
			(width 0)
			(type solid)
		)
		(fill yes)
		(layer "In4.Cu")
		(net "M_D_CPU1_SA_CA<1>")
	)
	(gr_poly
		(pts
			(xy 81.801208 -251.572522) (xy 81.801208 -251.528072) (xy 81.601056 -251.528072) (xy 81.601056 -251.572522)
			(xy 81.701132 -251.672598)
		)
		(stroke
			(width 0)
			(type solid)
		)
		(fill yes)
		(layer "In4.Cu")
		(net "M_D_CPU1_SA_CS_N<0>")
	)
	(gr_poly
		(pts
			(xy 81.801208 -250.35637) (xy 81.701132 -250.256294) (xy 81.601056 -250.35637) (xy 81.601056 -250.40082)
			(xy 81.801208 -250.40082)
		)
		(stroke
			(width 0)
			(type solid)
		)
		(fill yes)
		(layer "In4.Cu")
		(net "M_D_CPU1_ALERT_R_N")
	)
	(gr_poly
		(pts
			(xy 81.801208 -248.736358) (xy 81.701132 -248.636282) (xy 81.601056 -248.736358) (xy 81.601056 -248.780808)
			(xy 81.801208 -248.780808)
		)
		(stroke
			(width 0)
			(type solid)
		)
		(fill yes)
		(layer "In4.Cu")
		(net "M_D_CPU1_SA_CB<5>")
	)
	(gr_poly
		(pts
			(xy 81.801208 -248.332498) (xy 81.801208 -248.288048) (xy 81.601056 -248.288048) (xy 81.601056 -248.332498)
			(xy 81.701132 -248.432574)
		)
		(stroke
			(width 0)
			(type solid)
		)
		(fill yes)
		(layer "In4.Cu")
		(net "M_D_CPU1_SA_CB<6>")
	)
	(gr_poly
		(pts
			(xy 81.801208 -247.116092) (xy 81.701132 -247.01627) (xy 81.601056 -247.116092) (xy 81.601056 -247.163844)
			(xy 81.801208 -247.163844)
		)
		(stroke
			(width 0)
			(type solid)
		)
		(fill yes)
		(layer "In4.Cu")
		(net "M_D_CPU1_SA_DQS_DN<9>")
	)
	(gr_poly
		(pts
			(xy 81.801208 -246.71274) (xy 81.801208 -246.664988) (xy 81.601056 -246.664988) (xy 81.601056 -246.71274)
			(xy 81.701132 -246.812562)
		)
		(stroke
			(width 0)
			(type solid)
		)
		(fill yes)
		(layer "In4.Cu")
		(net "M_D_CPU1_SA_DQS_DN<4>")
	)
	(gr_poly
		(pts
			(xy 81.801208 -245.496334) (xy 81.701132 -245.396258) (xy 81.601056 -245.496334) (xy 81.601056 -245.540784)
			(xy 81.801208 -245.540784)
		)
		(stroke
			(width 0)
			(type solid)
		)
		(fill yes)
		(layer "In4.Cu")
		(net "M_D_CPU1_SA_CB<1>")
	)
	(gr_poly
		(pts
			(xy 81.801208 -245.092474) (xy 81.801208 -245.048024) (xy 81.601056 -245.048024) (xy 81.601056 -245.092474)
			(xy 81.701132 -245.19255)
		)
		(stroke
			(width 0)
			(type solid)
		)
		(fill yes)
		(layer "In4.Cu")
		(net "M_D_CPU1_SA_CB<2>")
	)
	(gr_poly
		(pts
			(xy 81.801208 -243.876322) (xy 81.701132 -243.776246) (xy 81.601056 -243.876322) (xy 81.601056 -243.920772)
			(xy 81.801208 -243.920772)
		)
		(stroke
			(width 0)
			(type solid)
		)
		(fill yes)
		(layer "In4.Cu")
		(net "M_D_CPU1_SA_DQ<29>")
	)
	(gr_poly
		(pts
			(xy 81.801208 -243.472462) (xy 81.801208 -243.428012) (xy 81.601056 -243.428012) (xy 81.601056 -243.472462)
			(xy 81.701132 -243.572538)
		)
		(stroke
			(width 0)
			(type solid)
		)
		(fill yes)
		(layer "In4.Cu")
		(net "M_D_CPU1_SA_DQ<30>")
	)
	(gr_poly
		(pts
			(xy 81.801208 -242.256056) (xy 81.701132 -242.156234) (xy 81.601056 -242.256056) (xy 81.601056 -242.303808)
			(xy 81.801208 -242.303808)
		)
		(stroke
			(width 0)
			(type solid)
		)
		(fill yes)
		(layer "In4.Cu")
		(net "M_D_CPU1_SA_DQS_DN<8>")
	)
	(gr_poly
		(pts
			(xy 81.801208 -241.852704) (xy 81.801208 -241.804952) (xy 81.601056 -241.804952) (xy 81.601056 -241.852704)
			(xy 81.701132 -241.952526)
		)
		(stroke
			(width 0)
			(type solid)
		)
		(fill yes)
		(layer "In4.Cu")
		(net "M_D_CPU1_SA_DQS_DN<3>")
	)
	(gr_poly
		(pts
			(xy 81.801208 -240.636298) (xy 81.701132 -240.536222) (xy 81.601056 -240.636298) (xy 81.601056 -240.680748)
			(xy 81.801208 -240.680748)
		)
		(stroke
			(width 0)
			(type solid)
		)
		(fill yes)
		(layer "In4.Cu")
		(net "M_D_CPU1_SA_DQ<25>")
	)
	(gr_poly
		(pts
			(xy 81.801208 -240.232438) (xy 81.801208 -240.187988) (xy 81.601056 -240.187988) (xy 81.601056 -240.232438)
			(xy 81.701132 -240.332514)
		)
		(stroke
			(width 0)
			(type solid)
		)
		(fill yes)
		(layer "In4.Cu")
		(net "M_D_CPU1_SA_DQ<26>")
	)
	(gr_poly
		(pts
			(xy 81.801208 -239.016286) (xy 81.701132 -238.91621) (xy 81.601056 -239.016286) (xy 81.601056 -239.060736)
			(xy 81.801208 -239.060736)
		)
		(stroke
			(width 0)
			(type solid)
		)
		(fill yes)
		(layer "In4.Cu")
		(net "M_D_CPU1_SA_DQ<21>")
	)
	(gr_poly
		(pts
			(xy 81.801208 -238.612426) (xy 81.801208 -238.567976) (xy 81.601056 -238.567976) (xy 81.601056 -238.612426)
			(xy 81.701132 -238.712502)
		)
		(stroke
			(width 0)
			(type solid)
		)
		(fill yes)
		(layer "In4.Cu")
		(net "M_D_CPU1_SA_DQ<22>")
	)
	(gr_poly
		(pts
			(xy 81.801208 -237.39602) (xy 81.701132 -237.296198) (xy 81.601056 -237.39602) (xy 81.601056 -237.443772)
			(xy 81.801208 -237.443772)
		)
		(stroke
			(width 0)
			(type solid)
		)
		(fill yes)
		(layer "In4.Cu")
		(net "M_D_CPU1_SA_DQS_DN<7>")
	)
	(gr_poly
		(pts
			(xy 81.801208 -236.992668) (xy 81.801208 -236.944916) (xy 81.601056 -236.944916) (xy 81.601056 -236.992668)
			(xy 81.701132 -237.09249)
		)
		(stroke
			(width 0)
			(type solid)
		)
		(fill yes)
		(layer "In4.Cu")
		(net "M_D_CPU1_SA_DQS_DN<2>")
	)
	(gr_poly
		(pts
			(xy 81.801208 -235.776262) (xy 81.701132 -235.676186) (xy 81.601056 -235.776262) (xy 81.601056 -235.820712)
			(xy 81.801208 -235.820712)
		)
		(stroke
			(width 0)
			(type solid)
		)
		(fill yes)
		(layer "In4.Cu")
		(net "M_D_CPU1_SA_DQ<17>")
	)
	(gr_poly
		(pts
			(xy 81.801208 -235.372402) (xy 81.801208 -235.327952) (xy 81.601056 -235.327952) (xy 81.601056 -235.372402)
			(xy 81.701132 -235.472478)
		)
		(stroke
			(width 0)
			(type solid)
		)
		(fill yes)
		(layer "In4.Cu")
		(net "M_D_CPU1_SA_DQ<18>")
	)
	(gr_poly
		(pts
			(xy 81.801208 -234.15625) (xy 81.701132 -234.056174) (xy 81.601056 -234.15625) (xy 81.601056 -234.2007)
			(xy 81.801208 -234.2007)
		)
		(stroke
			(width 0)
			(type solid)
		)
		(fill yes)
		(layer "In4.Cu")
		(net "M_D_CPU1_SA_DQ<13>")
	)
	(gr_poly
		(pts
			(xy 81.801208 -233.75239) (xy 81.801208 -233.70794) (xy 81.601056 -233.70794) (xy 81.601056 -233.75239)
			(xy 81.701132 -233.852466)
		)
		(stroke
			(width 0)
			(type solid)
		)
		(fill yes)
		(layer "In4.Cu")
		(net "M_D_CPU1_SA_DQ<14>")
	)
	(gr_poly
		(pts
			(xy 81.801208 -232.535984) (xy 81.701132 -232.436162) (xy 81.601056 -232.535984) (xy 81.601056 -232.583736)
			(xy 81.801208 -232.583736)
		)
		(stroke
			(width 0)
			(type solid)
		)
		(fill yes)
		(layer "In4.Cu")
		(net "M_D_CPU1_SA_DQS_DN<6>")
	)
	(gr_poly
		(pts
			(xy 81.801208 -232.132632) (xy 81.801208 -232.08488) (xy 81.601056 -232.08488) (xy 81.601056 -232.132632)
			(xy 81.701132 -232.232454)
		)
		(stroke
			(width 0)
			(type solid)
		)
		(fill yes)
		(layer "In4.Cu")
		(net "M_D_CPU1_SA_DQS_DN<1>")
	)
	(gr_poly
		(pts
			(xy 81.801208 -230.916226) (xy 81.701132 -230.81615) (xy 81.601056 -230.916226) (xy 81.601056 -230.960676)
			(xy 81.801208 -230.960676)
		)
		(stroke
			(width 0)
			(type solid)
		)
		(fill yes)
		(layer "In4.Cu")
		(net "M_D_CPU1_SA_DQ<9>")
	)
	(gr_poly
		(pts
			(xy 81.801208 -230.51262) (xy 81.801208 -230.46817) (xy 81.601056 -230.46817) (xy 81.601056 -230.51262)
			(xy 81.701132 -230.612696)
		)
		(stroke
			(width 0)
			(type solid)
		)
		(fill yes)
		(layer "In4.Cu")
		(net "M_D_CPU1_SA_DQ<10>")
	)
	(gr_poly
		(pts
			(xy 81.801208 -229.296214) (xy 81.701132 -229.196138) (xy 81.601056 -229.296214) (xy 81.601056 -229.340664)
			(xy 81.801208 -229.340664)
		)
		(stroke
			(width 0)
			(type solid)
		)
		(fill yes)
		(layer "In4.Cu")
		(net "M_D_CPU1_SA_DQ<5>")
	)
	(gr_poly
		(pts
			(xy 81.801208 -228.892608) (xy 81.801208 -228.848158) (xy 81.601056 -228.848158) (xy 81.601056 -228.892608)
			(xy 81.701132 -228.992684)
		)
		(stroke
			(width 0)
			(type solid)
		)
		(fill yes)
		(layer "In4.Cu")
		(net "M_D_CPU1_SA_DQ<6>")
	)
	(gr_poly
		(pts
			(xy 81.81975 -227.276406) (xy 81.85658 -227.139754) (xy 81.719928 -227.103178) (xy 81.678526 -227.127054)
			(xy 81.778602 -227.300282)
		)
		(stroke
			(width 0)
			(type solid)
		)
		(fill yes)
		(layer "In4.Cu")
		(net "M_D_CPU1_SA_DQS_DN<5>")
	)
	(gr_poly
		(pts
			(xy 81.820258 -225.655886) (xy 81.856834 -225.519488) (xy 81.720182 -225.482912) (xy 81.679034 -225.506534)
			(xy 81.778856 -225.679762)
		)
		(stroke
			(width 0)
			(type solid)
		)
		(fill yes)
		(layer "In4.Cu")
		(net "M_D_CPU1_SA_DQS_DP<0>")
	)
	(gr_poly
		(pts
			(xy 81.820258 -224.036636) (xy 81.856834 -223.899984) (xy 81.720436 -223.863408) (xy 81.681828 -223.88576)
			(xy 81.781904 -224.058988)
		)
		(stroke
			(width 0)
			(type solid)
		)
		(fill yes)
		(layer "In4.Cu")
		(net "M_D_CPU1_SA_DQ<1>")
	)
	(gr_poly
		(pts
			(xy 82.094832 -267.801852) (xy 81.994756 -267.701776) (xy 81.894934 -267.801852) (xy 81.894934 -267.846302)
			(xy 82.094832 -267.846302)
		)
		(stroke
			(width 0)
			(type solid)
		)
		(fill yes)
		(layer "In4.Cu")
		(net "M_D_CPU1_SB_RSP<0>")
	)
	(gr_poly
		(pts
			(xy 82.101182 -292.108128) (xy 82.001106 -292.008052) (xy 81.90103 -292.108128) (xy 81.90103 -292.152578)
			(xy 82.101182 -292.152578)
		)
		(stroke
			(width 0)
			(type solid)
		)
		(fill yes)
		(layer "In4.Cu")
		(net "M_D_CPU1_SB_DQ<28>")
	)
	(gr_poly
		(pts
			(xy 82.101182 -291.704522) (xy 82.101182 -291.65677) (xy 81.90103 -291.65677) (xy 81.90103 -291.704522)
			(xy 82.001106 -291.804344)
		)
		(stroke
			(width 0)
			(type solid)
		)
		(fill yes)
		(layer "In4.Cu")
		(net "M_D_CPU1_SB_DQS_DP<8>")
	)
	(gr_poly
		(pts
			(xy 82.101182 -290.487862) (xy 82.001106 -290.38804) (xy 81.90103 -290.487862) (xy 81.90103 -290.535614)
			(xy 82.101182 -290.535614)
		)
		(stroke
			(width 0)
			(type solid)
		)
		(fill yes)
		(layer "In4.Cu")
		(net "M_D_CPU1_SB_DQS_DP<3>")
	)
	(gr_poly
		(pts
			(xy 82.101182 -290.084256) (xy 82.101182 -290.039806) (xy 81.90103 -290.039806) (xy 81.90103 -290.084256)
			(xy 82.001106 -290.184332)
		)
		(stroke
			(width 0)
			(type solid)
		)
		(fill yes)
		(layer "In4.Cu")
		(net "M_D_CPU1_SB_DQ<27>")
	)
	(gr_poly
		(pts
			(xy 82.101182 -288.868104) (xy 82.001106 -288.768028) (xy 81.90103 -288.868104) (xy 81.90103 -288.912554)
			(xy 82.101182 -288.912554)
		)
		(stroke
			(width 0)
			(type solid)
		)
		(fill yes)
		(layer "In4.Cu")
		(net "M_D_CPU1_SB_DQ<24>")
	)
	(gr_poly
		(pts
			(xy 82.101182 -288.464498) (xy 82.101182 -288.420048) (xy 81.90103 -288.420048) (xy 81.90103 -288.464498)
			(xy 82.001106 -288.564574)
		)
		(stroke
			(width 0)
			(type solid)
		)
		(fill yes)
		(layer "In4.Cu")
		(net "M_D_CPU1_SB_DQ<23>")
	)
	(gr_poly
		(pts
			(xy 82.101182 -287.248092) (xy 82.001106 -287.148016) (xy 81.90103 -287.248092) (xy 81.90103 -287.292542)
			(xy 82.101182 -287.292542)
		)
		(stroke
			(width 0)
			(type solid)
		)
		(fill yes)
		(layer "In4.Cu")
		(net "M_D_CPU1_SB_DQ<20>")
	)
	(gr_poly
		(pts
			(xy 82.101182 -286.844486) (xy 82.101182 -286.796734) (xy 81.90103 -286.796734) (xy 81.90103 -286.844486)
			(xy 82.001106 -286.944562)
		)
		(stroke
			(width 0)
			(type solid)
		)
		(fill yes)
		(layer "In4.Cu")
		(net "M_D_CPU1_SB_DQS_DP<7>")
	)
	(gr_poly
		(pts
			(xy 82.101182 -285.62808) (xy 82.001106 -285.528258) (xy 81.90103 -285.62808) (xy 81.90103 -285.675832)
			(xy 82.101182 -285.675832)
		)
		(stroke
			(width 0)
			(type solid)
		)
		(fill yes)
		(layer "In4.Cu")
		(net "M_D_CPU1_SB_DQS_DP<2>")
	)
	(gr_poly
		(pts
			(xy 82.101182 -285.224474) (xy 82.101182 -285.180024) (xy 81.90103 -285.180024) (xy 81.90103 -285.224474)
			(xy 82.001106 -285.32455)
		)
		(stroke
			(width 0)
			(type solid)
		)
		(fill yes)
		(layer "In4.Cu")
		(net "M_D_CPU1_SB_DQ<19>")
	)
	(gr_poly
		(pts
			(xy 82.101182 -284.008322) (xy 82.001106 -283.908246) (xy 81.90103 -284.008322) (xy 81.90103 -284.052772)
			(xy 82.101182 -284.052772)
		)
		(stroke
			(width 0)
			(type solid)
		)
		(fill yes)
		(layer "In4.Cu")
		(net "M_D_CPU1_SB_DQ<16>")
	)
	(gr_poly
		(pts
			(xy 82.101182 -283.604462) (xy 82.101182 -283.560012) (xy 81.90103 -283.560012) (xy 81.90103 -283.604462)
			(xy 82.001106 -283.704538)
		)
		(stroke
			(width 0)
			(type solid)
		)
		(fill yes)
		(layer "In4.Cu")
		(net "M_D_CPU1_SB_DQ<15>")
	)
	(gr_poly
		(pts
			(xy 82.101182 -282.38831) (xy 82.001106 -282.288234) (xy 81.90103 -282.38831) (xy 81.90103 -282.43276)
			(xy 82.101182 -282.43276)
		)
		(stroke
			(width 0)
			(type solid)
		)
		(fill yes)
		(layer "In4.Cu")
		(net "M_D_CPU1_SB_DQ<12>")
	)
	(gr_poly
		(pts
			(xy 82.101182 -281.984704) (xy 82.101182 -281.936952) (xy 81.90103 -281.936952) (xy 81.90103 -281.984704)
			(xy 82.001106 -282.084526)
		)
		(stroke
			(width 0)
			(type solid)
		)
		(fill yes)
		(layer "In4.Cu")
		(net "M_D_CPU1_SB_DQS_DP<6>")
	)
	(gr_poly
		(pts
			(xy 82.101182 -280.768044) (xy 82.001106 -280.668222) (xy 81.90103 -280.768044) (xy 81.90103 -280.815796)
			(xy 82.101182 -280.815796)
		)
		(stroke
			(width 0)
			(type solid)
		)
		(fill yes)
		(layer "In4.Cu")
		(net "M_D_CPU1_SB_DQS_DP<1>")
	)
	(gr_poly
		(pts
			(xy 82.101182 -280.364438) (xy 82.101182 -280.319988) (xy 81.90103 -280.319988) (xy 81.90103 -280.364438)
			(xy 82.001106 -280.464514)
		)
		(stroke
			(width 0)
			(type solid)
		)
		(fill yes)
		(layer "In4.Cu")
		(net "M_D_CPU1_SB_DQ<11>")
	)
	(gr_poly
		(pts
			(xy 82.101182 -279.148286) (xy 82.001106 -279.04821) (xy 81.90103 -279.148286) (xy 81.90103 -279.192736)
			(xy 82.101182 -279.192736)
		)
		(stroke
			(width 0)
			(type solid)
		)
		(fill yes)
		(layer "In4.Cu")
		(net "M_D_CPU1_SB_DQ<8>")
	)
	(gr_poly
		(pts
			(xy 82.101182 -278.744426) (xy 82.101182 -278.699976) (xy 81.90103 -278.699976) (xy 81.90103 -278.744426)
			(xy 82.001106 -278.844502)
		)
		(stroke
			(width 0)
			(type solid)
		)
		(fill yes)
		(layer "In4.Cu")
		(net "M_D_CPU1_SB_DQ<7>")
	)
	(gr_poly
		(pts
			(xy 82.101182 -277.528274) (xy 82.001106 -277.428198) (xy 81.90103 -277.528274) (xy 81.90103 -277.572724)
			(xy 82.101182 -277.572724)
		)
		(stroke
			(width 0)
			(type solid)
		)
		(fill yes)
		(layer "In4.Cu")
		(net "M_D_CPU1_SB_DQ<4>")
	)
	(gr_poly
		(pts
			(xy 82.101182 -277.124668) (xy 82.101182 -277.076916) (xy 81.90103 -277.076916) (xy 81.90103 -277.124668)
			(xy 82.001106 -277.22449)
		)
		(stroke
			(width 0)
			(type solid)
		)
		(fill yes)
		(layer "In4.Cu")
		(net "M_D_CPU1_SB_DQS_DP<5>")
	)
	(gr_poly
		(pts
			(xy 82.101182 -275.908008) (xy 82.001106 -275.808186) (xy 81.90103 -275.908008) (xy 81.90103 -275.95576)
			(xy 82.101182 -275.95576)
		)
		(stroke
			(width 0)
			(type solid)
		)
		(fill yes)
		(layer "In4.Cu")
		(net "M_D_CPU1_SB_DQS_DP<0>")
	)
	(gr_poly
		(pts
			(xy 82.101182 -275.504402) (xy 82.101182 -275.459952) (xy 81.90103 -275.459952) (xy 81.90103 -275.504402)
			(xy 82.001106 -275.604478)
		)
		(stroke
			(width 0)
			(type solid)
		)
		(fill yes)
		(layer "In4.Cu")
		(net "M_D_CPU1_SB_DQ<3>")
	)
	(gr_poly
		(pts
			(xy 82.101182 -274.28825) (xy 82.001106 -274.188174) (xy 81.90103 -274.28825) (xy 81.90103 -274.3327)
			(xy 82.101182 -274.3327)
		)
		(stroke
			(width 0)
			(type solid)
		)
		(fill yes)
		(layer "In4.Cu")
		(net "M_D_CPU1_SB_DQ<0>")
	)
	(gr_poly
		(pts
			(xy 82.101182 -273.88439) (xy 82.101182 -273.83994) (xy 81.90103 -273.83994) (xy 81.90103 -273.88439)
			(xy 82.001106 -273.984466)
		)
		(stroke
			(width 0)
			(type solid)
		)
		(fill yes)
		(layer "In4.Cu")
		(net "M_D_CPU1_SB_CB<3>")
	)
	(gr_poly
		(pts
			(xy 82.101182 -272.668238) (xy 82.001106 -272.568162) (xy 81.90103 -272.668238) (xy 81.90103 -272.712688)
			(xy 82.101182 -272.712688)
		)
		(stroke
			(width 0)
			(type solid)
		)
		(fill yes)
		(layer "In4.Cu")
		(net "M_D_CPU1_SB_CB<0>")
	)
	(gr_poly
		(pts
			(xy 82.101182 -272.264632) (xy 82.101182 -272.21688) (xy 81.90103 -272.21688) (xy 81.90103 -272.264632)
			(xy 82.001106 -272.364454)
		)
		(stroke
			(width 0)
			(type solid)
		)
		(fill yes)
		(layer "In4.Cu")
		(net "M_D_CPU1_SB_DQS_DP<4>")
	)
	(gr_poly
		(pts
			(xy 82.101182 -271.047972) (xy 82.001106 -270.94815) (xy 81.90103 -271.047972) (xy 81.90103 -271.095724)
			(xy 82.101182 -271.095724)
		)
		(stroke
			(width 0)
			(type solid)
		)
		(fill yes)
		(layer "In4.Cu")
		(net "M_D_CPU1_SB_DQS_DP<9>")
	)
	(gr_poly
		(pts
			(xy 82.101182 -270.644366) (xy 82.101182 -270.599916) (xy 81.90103 -270.599916) (xy 81.90103 -270.644366)
			(xy 82.001106 -270.744442)
		)
		(stroke
			(width 0)
			(type solid)
		)
		(fill yes)
		(layer "In4.Cu")
		(net "M_D_CPU1_SB_CB<7>")
	)
	(gr_poly
		(pts
			(xy 82.101182 -269.428214) (xy 82.001106 -269.328138) (xy 81.90103 -269.428214) (xy 81.90103 -269.472664)
			(xy 82.101182 -269.472664)
		)
		(stroke
			(width 0)
			(type solid)
		)
		(fill yes)
		(layer "In4.Cu")
		(net "M_D_CPU1_SB_CB<4>")
	)
	(gr_poly
		(pts
			(xy 82.101182 -265.78433) (xy 82.101182 -265.73988) (xy 81.90103 -265.73988) (xy 81.90103 -265.78433)
			(xy 82.001106 -265.884406)
		)
		(stroke
			(width 0)
			(type solid)
		)
		(fill yes)
		(layer "In4.Cu")
		(net "M_D_CPU1_SB_CS_N<0>")
	)
	(gr_poly
		(pts
			(xy 82.101182 -264.568178) (xy 82.001106 -264.468102) (xy 81.90103 -264.568178) (xy 81.90103 -264.612628)
			(xy 82.101182 -264.612628)
		)
		(stroke
			(width 0)
			(type solid)
		)
		(fill yes)
		(layer "In4.Cu")
		(net "M_D_CPU1_SB_CA<6>")
	)
	(gr_poly
		(pts
			(xy 82.101182 -264.164318) (xy 82.101182 -264.119868) (xy 81.90103 -264.119868) (xy 81.90103 -264.164318)
			(xy 82.001106 -264.264394)
		)
		(stroke
			(width 0)
			(type solid)
		)
		(fill yes)
		(layer "In4.Cu")
		(net "M_D_CPU1_SB_CA<5>")
	)
	(gr_poly
		(pts
			(xy 82.101182 -262.948166) (xy 82.001106 -262.84809) (xy 81.90103 -262.948166) (xy 81.90103 -262.992616)
			(xy 82.101182 -262.992616)
		)
		(stroke
			(width 0)
			(type solid)
		)
		(fill yes)
		(layer "In4.Cu")
		(net "M_D_CPU1_SB_CA<2>")
	)
	(gr_poly
		(pts
			(xy 82.101182 -262.544306) (xy 82.101182 -262.499856) (xy 81.90103 -262.499856) (xy 81.90103 -262.544306)
			(xy 82.001106 -262.644382)
		)
		(stroke
			(width 0)
			(type solid)
		)
		(fill yes)
		(layer "In4.Cu")
		(net "M_D_CPU1_SB_CA<1>")
	)
	(gr_poly
		(pts
			(xy 82.146394 -293.878762) (xy 82.109818 -293.74211) (xy 82.07121 -293.719758) (xy 81.971388 -293.892986)
			(xy 82.009742 -293.915338)
		)
		(stroke
			(width 0)
			(type solid)
		)
		(fill yes)
		(layer "In4.Cu")
		(net "M_D_CPU1_SB_DQ<31>")
	)
	(gr_poly
		(pts
			(xy 82.191098 -225.394774) (xy 82.091022 -225.221546) (xy 82.052414 -225.243644) (xy 82.015838 -225.380296)
			(xy 82.15249 -225.416872)
		)
		(stroke
			(width 0)
			(type solid)
		)
		(fill yes)
		(layer "In4.Cu")
		(net "M_D_CPU1_SA_DQ<3>")
	)
	(gr_poly
		(pts
			(xy 82.191098 -223.774762) (xy 82.091022 -223.601534) (xy 82.052414 -223.623632) (xy 82.015838 -223.760284)
			(xy 82.15249 -223.79686)
		)
		(stroke
			(width 0)
			(type solid)
		)
		(fill yes)
		(layer "In4.Cu")
		(net "M_D_CPU1_SA_DQ<2>")
	)
	(gr_poly
		(pts
			(xy 82.194146 -227.01377) (xy 82.09407 -226.840542) (xy 82.052668 -226.864418) (xy 82.016092 -227.00107)
			(xy 82.152744 -227.037646)
		)
		(stroke
			(width 0)
			(type solid)
		)
		(fill yes)
		(layer "In4.Cu")
		(net "M_D_CPU1_SA_DQS_DN<0>")
	)
	(gr_poly
		(pts
			(xy 82.271108 -256.026158) (xy 82.171032 -255.926336) (xy 82.070956 -256.026158) (xy 82.070956 -256.07391)
			(xy 82.271108 -256.07391)
		)
		(stroke
			(width 0)
			(type solid)
		)
		(fill yes)
		(layer "In4.Cu")
		(net "M_D_CPU1_CLK_DP<0>")
	)
	(gr_poly
		(pts
			(xy 82.271108 -255.622552) (xy 82.271108 -255.578102) (xy 82.070956 -255.578102) (xy 82.070956 -255.622552)
			(xy 82.171032 -255.722628)
		)
		(stroke
			(width 0)
			(type solid)
		)
		(fill yes)
		(layer "In4.Cu")
		(net "M_D_CPU1_SA_PAR")
	)
	(gr_poly
		(pts
			(xy 82.271108 -254.4064) (xy 82.171032 -254.306324) (xy 82.070956 -254.4064) (xy 82.070956 -254.45085)
			(xy 82.271108 -254.45085)
		)
		(stroke
			(width 0)
			(type solid)
		)
		(fill yes)
		(layer "In4.Cu")
		(net "M_D_CPU1_SA_CA<4>")
	)
	(gr_poly
		(pts
			(xy 82.271108 -254.00254) (xy 82.271108 -253.95809) (xy 82.070956 -253.95809) (xy 82.070956 -254.00254)
			(xy 82.171032 -254.102616)
		)
		(stroke
			(width 0)
			(type solid)
		)
		(fill yes)
		(layer "In4.Cu")
		(net "M_D_CPU1_SA_CA<3>")
	)
	(gr_poly
		(pts
			(xy 82.271108 -252.786388) (xy 82.171032 -252.686312) (xy 82.070956 -252.786388) (xy 82.070956 -252.830838)
			(xy 82.271108 -252.830838)
		)
		(stroke
			(width 0)
			(type solid)
		)
		(fill yes)
		(layer "In4.Cu")
		(net "M_D_CPU1_SA_CA<0>")
	)
	(gr_poly
		(pts
			(xy 82.271108 -252.382528) (xy 82.271108 -252.338078) (xy 82.070956 -252.338078) (xy 82.070956 -252.382528)
			(xy 82.171032 -252.482604)
		)
		(stroke
			(width 0)
			(type solid)
		)
		(fill yes)
		(layer "In4.Cu")
		(net "M_D_CPU1_SA_CS_N<1>")
	)
	(gr_poly
		(pts
			(xy 82.271108 -250.762516) (xy 82.271108 -250.718066) (xy 82.070956 -250.718066) (xy 82.070956 -250.762516)
			(xy 82.171032 -250.862592)
		)
		(stroke
			(width 0)
			(type solid)
		)
		(fill yes)
		(layer "In4.Cu")
		(net "M_D_CPU1_RESET_N")
	)
	(gr_poly
		(pts
			(xy 82.271108 -249.142504) (xy 82.271108 -249.098054) (xy 82.070956 -249.098054) (xy 82.070956 -249.142504)
			(xy 82.171032 -249.24258)
		)
		(stroke
			(width 0)
			(type solid)
		)
		(fill yes)
		(layer "In4.Cu")
		(net "M_D_CPU1_SA_CB<7>")
	)
	(gr_poly
		(pts
			(xy 82.271108 -247.926352) (xy 82.171032 -247.826276) (xy 82.070956 -247.926352) (xy 82.070956 -247.970802)
			(xy 82.271108 -247.970802)
		)
		(stroke
			(width 0)
			(type solid)
		)
		(fill yes)
		(layer "In4.Cu")
		(net "M_D_CPU1_SA_CB<4>")
	)
	(gr_poly
		(pts
			(xy 82.271108 -247.522746) (xy 82.271108 -247.474994) (xy 82.070956 -247.474994) (xy 82.070956 -247.522746)
			(xy 82.171032 -247.622568)
		)
		(stroke
			(width 0)
			(type solid)
		)
		(fill yes)
		(layer "In4.Cu")
		(net "M_D_CPU1_SA_DQS_DP<9>")
	)
	(gr_poly
		(pts
			(xy 82.271108 -246.306086) (xy 82.171032 -246.206264) (xy 82.070956 -246.306086) (xy 82.070956 -246.353838)
			(xy 82.271108 -246.353838)
		)
		(stroke
			(width 0)
			(type solid)
		)
		(fill yes)
		(layer "In4.Cu")
		(net "M_D_CPU1_SA_DQS_DP<4>")
	)
	(gr_poly
		(pts
			(xy 82.271108 -245.90248) (xy 82.271108 -245.85803) (xy 82.070956 -245.85803) (xy 82.070956 -245.90248)
			(xy 82.171032 -246.002556)
		)
		(stroke
			(width 0)
			(type solid)
		)
		(fill yes)
		(layer "In4.Cu")
		(net "M_D_CPU1_SA_CB<3>")
	)
	(gr_poly
		(pts
			(xy 82.271108 -244.686328) (xy 82.171032 -244.586252) (xy 82.070956 -244.686328) (xy 82.070956 -244.730778)
			(xy 82.271108 -244.730778)
		)
		(stroke
			(width 0)
			(type solid)
		)
		(fill yes)
		(layer "In4.Cu")
		(net "M_D_CPU1_SA_CB<0>")
	)
	(gr_poly
		(pts
			(xy 82.271108 -244.282468) (xy 82.271108 -244.238018) (xy 82.070956 -244.238018) (xy 82.070956 -244.282468)
			(xy 82.171032 -244.382544)
		)
		(stroke
			(width 0)
			(type solid)
		)
		(fill yes)
		(layer "In4.Cu")
		(net "M_D_CPU1_SA_DQ<31>")
	)
	(gr_poly
		(pts
			(xy 82.271108 -243.066316) (xy 82.171032 -242.96624) (xy 82.070956 -243.066316) (xy 82.070956 -243.110766)
			(xy 82.271108 -243.110766)
		)
		(stroke
			(width 0)
			(type solid)
		)
		(fill yes)
		(layer "In4.Cu")
		(net "M_D_CPU1_SA_DQ<28>")
	)
	(gr_poly
		(pts
			(xy 82.271108 -242.66271) (xy 82.271108 -242.614958) (xy 82.070956 -242.614958) (xy 82.070956 -242.66271)
			(xy 82.171032 -242.762532)
		)
		(stroke
			(width 0)
			(type solid)
		)
		(fill yes)
		(layer "In4.Cu")
		(net "M_D_CPU1_SA_DQS_DP<8>")
	)
	(gr_poly
		(pts
			(xy 82.271108 -241.44605) (xy 82.171032 -241.346228) (xy 82.070956 -241.44605) (xy 82.070956 -241.493802)
			(xy 82.271108 -241.493802)
		)
		(stroke
			(width 0)
			(type solid)
		)
		(fill yes)
		(layer "In4.Cu")
		(net "M_D_CPU1_SA_DQS_DP<3>")
	)
	(gr_poly
		(pts
			(xy 82.271108 -241.042444) (xy 82.271108 -240.997994) (xy 82.070956 -240.997994) (xy 82.070956 -241.042444)
			(xy 82.171032 -241.14252)
		)
		(stroke
			(width 0)
			(type solid)
		)
		(fill yes)
		(layer "In4.Cu")
		(net "M_D_CPU1_SA_DQ<27>")
	)
	(gr_poly
		(pts
			(xy 82.271108 -239.826292) (xy 82.171032 -239.726216) (xy 82.070956 -239.826292) (xy 82.070956 -239.870742)
			(xy 82.271108 -239.870742)
		)
		(stroke
			(width 0)
			(type solid)
		)
		(fill yes)
		(layer "In4.Cu")
		(net "M_D_CPU1_SA_DQ<24>")
	)
	(gr_poly
		(pts
			(xy 82.271108 -239.422432) (xy 82.271108 -239.377982) (xy 82.070956 -239.377982) (xy 82.070956 -239.422432)
			(xy 82.171032 -239.522508)
		)
		(stroke
			(width 0)
			(type solid)
		)
		(fill yes)
		(layer "In4.Cu")
		(net "M_D_CPU1_SA_DQ<23>")
	)
	(gr_poly
		(pts
			(xy 82.271108 -238.20628) (xy 82.171032 -238.106204) (xy 82.070956 -238.20628) (xy 82.070956 -238.25073)
			(xy 82.271108 -238.25073)
		)
		(stroke
			(width 0)
			(type solid)
		)
		(fill yes)
		(layer "In4.Cu")
		(net "M_D_CPU1_SA_DQ<20>")
	)
	(gr_poly
		(pts
			(xy 82.271108 -237.802674) (xy 82.271108 -237.754922) (xy 82.070956 -237.754922) (xy 82.070956 -237.802674)
			(xy 82.171032 -237.902496)
		)
		(stroke
			(width 0)
			(type solid)
		)
		(fill yes)
		(layer "In4.Cu")
		(net "M_D_CPU1_SA_DQS_DP<7>")
	)
	(gr_poly
		(pts
			(xy 82.271108 -236.586014) (xy 82.171032 -236.486192) (xy 82.070956 -236.586014) (xy 82.070956 -236.633766)
			(xy 82.271108 -236.633766)
		)
		(stroke
			(width 0)
			(type solid)
		)
		(fill yes)
		(layer "In4.Cu")
		(net "M_D_CPU1_SA_DQS_DP<2>")
	)
	(gr_poly
		(pts
			(xy 82.271108 -236.182408) (xy 82.271108 -236.137958) (xy 82.070956 -236.137958) (xy 82.070956 -236.182408)
			(xy 82.171032 -236.282484)
		)
		(stroke
			(width 0)
			(type solid)
		)
		(fill yes)
		(layer "In4.Cu")
		(net "M_D_CPU1_SA_DQ<19>")
	)
	(gr_poly
		(pts
			(xy 82.271108 -234.966256) (xy 82.171032 -234.86618) (xy 82.070956 -234.966256) (xy 82.070956 -235.010706)
			(xy 82.271108 -235.010706)
		)
		(stroke
			(width 0)
			(type solid)
		)
		(fill yes)
		(layer "In4.Cu")
		(net "M_D_CPU1_SA_DQ<16>")
	)
	(gr_poly
		(pts
			(xy 82.271108 -234.562396) (xy 82.271108 -234.517946) (xy 82.070956 -234.517946) (xy 82.070956 -234.562396)
			(xy 82.171032 -234.662472)
		)
		(stroke
			(width 0)
			(type solid)
		)
		(fill yes)
		(layer "In4.Cu")
		(net "M_D_CPU1_SA_DQ<15>")
	)
	(gr_poly
		(pts
			(xy 82.271108 -233.346244) (xy 82.171032 -233.246168) (xy 82.070956 -233.346244) (xy 82.070956 -233.390694)
			(xy 82.271108 -233.390694)
		)
		(stroke
			(width 0)
			(type solid)
		)
		(fill yes)
		(layer "In4.Cu")
		(net "M_D_CPU1_SA_DQ<12>")
	)
	(gr_poly
		(pts
			(xy 82.271108 -232.942638) (xy 82.271108 -232.894886) (xy 82.070956 -232.894886) (xy 82.070956 -232.942638)
			(xy 82.171032 -233.04246)
		)
		(stroke
			(width 0)
			(type solid)
		)
		(fill yes)
		(layer "In4.Cu")
		(net "M_D_CPU1_SA_DQS_DP<6>")
	)
	(gr_poly
		(pts
			(xy 82.271108 -231.725978) (xy 82.171032 -231.626156) (xy 82.070956 -231.725978) (xy 82.070956 -231.77373)
			(xy 82.271108 -231.77373)
		)
		(stroke
			(width 0)
			(type solid)
		)
		(fill yes)
		(layer "In4.Cu")
		(net "M_D_CPU1_SA_DQS_DP<1>")
	)
	(gr_poly
		(pts
			(xy 82.271108 -231.322626) (xy 82.271108 -231.278176) (xy 82.070956 -231.278176) (xy 82.070956 -231.322626)
			(xy 82.171032 -231.422702)
		)
		(stroke
			(width 0)
			(type solid)
		)
		(fill yes)
		(layer "In4.Cu")
		(net "M_D_CPU1_SA_DQ<11>")
	)
	(gr_poly
		(pts
			(xy 82.271108 -230.10622) (xy 82.171032 -230.006144) (xy 82.070956 -230.10622) (xy 82.070956 -230.15067)
			(xy 82.271108 -230.15067)
		)
		(stroke
			(width 0)
			(type solid)
		)
		(fill yes)
		(layer "In4.Cu")
		(net "M_D_CPU1_SA_DQ<8>")
	)
	(gr_poly
		(pts
			(xy 82.271108 -229.702614) (xy 82.271108 -229.658164) (xy 82.070956 -229.658164) (xy 82.070956 -229.702614)
			(xy 82.171032 -229.80269)
		)
		(stroke
			(width 0)
			(type solid)
		)
		(fill yes)
		(layer "In4.Cu")
		(net "M_D_CPU1_SA_DQ<7>")
	)
	(gr_poly
		(pts
			(xy 82.271108 -228.486462) (xy 82.171032 -228.386386) (xy 82.070956 -228.486462) (xy 82.070956 -228.530912)
			(xy 82.271108 -228.530912)
		)
		(stroke
			(width 0)
			(type solid)
		)
		(fill yes)
		(layer "In4.Cu")
		(net "M_D_CPU1_SA_DQ<4>")
	)
	(gr_poly
		(pts
			(xy 82.271108 -228.082856) (xy 82.271108 -228.035104) (xy 82.070956 -228.035104) (xy 82.070956 -228.082856)
			(xy 82.171032 -228.182678)
		)
		(stroke
			(width 0)
			(type solid)
		)
		(fill yes)
		(layer "In4.Cu")
		(net "M_D_CPU1_SA_DQS_DP<5>")
	)
	(gr_poly
		(pts
			(xy 82.289396 -226.464622) (xy 82.325972 -226.32797) (xy 82.18932 -226.291394) (xy 82.147918 -226.31527)
			(xy 82.247994 -226.488498)
		)
		(stroke
			(width 0)
			(type solid)
		)
		(fill yes)
		(layer "In4.Cu")
		(net "M_D_CPU1_SA_DQS_DP<0>")
	)
	(gr_poly
		(pts
			(xy 82.28965 -224.845372) (xy 82.326226 -224.70872) (xy 82.189574 -224.672144) (xy 82.150966 -224.694242)
			(xy 82.251042 -224.86747)
		)
		(stroke
			(width 0)
			(type solid)
		)
		(fill yes)
		(layer "In4.Cu")
		(net "M_D_CPU1_SA_DQ<1>")
	)
	(gr_poly
		(pts
			(xy 82.28965 -223.22536) (xy 82.326226 -223.088708) (xy 82.189574 -223.052132) (xy 82.150966 -223.07423)
			(xy 82.251042 -223.247458)
		)
		(stroke
			(width 0)
			(type solid)
		)
		(fill yes)
		(layer "In4.Cu")
		(net "M_D_CPU1_SA_DQ<0>")
	)
	(gr_poly
		(pts
			(xy 82.571082 -292.918134) (xy 82.471006 -292.818058) (xy 82.37093 -292.918134) (xy 82.37093 -292.962584)
			(xy 82.571082 -292.962584)
		)
		(stroke
			(width 0)
			(type solid)
		)
		(fill yes)
		(layer "In4.Cu")
		(net "M_D_CPU1_SB_DQ<29>")
	)
	(gr_poly
		(pts
			(xy 82.571082 -292.514274) (xy 82.571082 -292.469824) (xy 82.37093 -292.469824) (xy 82.37093 -292.514274)
			(xy 82.471006 -292.61435)
		)
		(stroke
			(width 0)
			(type solid)
		)
		(fill yes)
		(layer "In4.Cu")
		(net "M_D_CPU1_SB_DQ<30>")
	)
	(gr_poly
		(pts
			(xy 82.571082 -291.297868) (xy 82.471006 -291.198046) (xy 82.37093 -291.297868) (xy 82.37093 -291.34562)
			(xy 82.571082 -291.34562)
		)
		(stroke
			(width 0)
			(type solid)
		)
		(fill yes)
		(layer "In4.Cu")
		(net "M_D_CPU1_SB_DQS_DN<8>")
	)
	(gr_poly
		(pts
			(xy 82.571082 -290.894516) (xy 82.571082 -290.846764) (xy 82.37093 -290.846764) (xy 82.37093 -290.894516)
			(xy 82.471006 -290.994338)
		)
		(stroke
			(width 0)
			(type solid)
		)
		(fill yes)
		(layer "In4.Cu")
		(net "M_D_CPU1_SB_DQS_DN<3>")
	)
	(gr_poly
		(pts
			(xy 82.571082 -289.67811) (xy 82.471006 -289.578034) (xy 82.37093 -289.67811) (xy 82.37093 -289.72256)
			(xy 82.571082 -289.72256)
		)
		(stroke
			(width 0)
			(type solid)
		)
		(fill yes)
		(layer "In4.Cu")
		(net "M_D_CPU1_SB_DQ<25>")
	)
	(gr_poly
		(pts
			(xy 82.571082 -289.27425) (xy 82.571082 -289.2298) (xy 82.37093 -289.2298) (xy 82.37093 -289.27425)
			(xy 82.471006 -289.374326)
		)
		(stroke
			(width 0)
			(type solid)
		)
		(fill yes)
		(layer "In4.Cu")
		(net "M_D_CPU1_SB_DQ<26>")
	)
	(gr_poly
		(pts
			(xy 82.571082 -288.058098) (xy 82.471006 -287.958022) (xy 82.37093 -288.058098) (xy 82.37093 -288.102548)
			(xy 82.571082 -288.102548)
		)
		(stroke
			(width 0)
			(type solid)
		)
		(fill yes)
		(layer "In4.Cu")
		(net "M_D_CPU1_SB_DQ<21>")
	)
	(gr_poly
		(pts
			(xy 82.571082 -287.654492) (xy 82.571082 -287.610042) (xy 82.37093 -287.610042) (xy 82.37093 -287.654492)
			(xy 82.471006 -287.754568)
		)
		(stroke
			(width 0)
			(type solid)
		)
		(fill yes)
		(layer "In4.Cu")
		(net "M_D_CPU1_SB_DQ<22>")
	)
	(gr_poly
		(pts
			(xy 82.571082 -286.438086) (xy 82.471006 -286.33801) (xy 82.37093 -286.438086) (xy 82.37093 -286.485838)
			(xy 82.571082 -286.485838)
		)
		(stroke
			(width 0)
			(type solid)
		)
		(fill yes)
		(layer "In4.Cu")
		(net "M_D_CPU1_SB_DQS_DN<7>")
	)
	(gr_poly
		(pts
			(xy 82.571082 -286.034734) (xy 82.571082 -285.986982) (xy 82.37093 -285.986982) (xy 82.37093 -286.034734)
			(xy 82.471006 -286.134556)
		)
		(stroke
			(width 0)
			(type solid)
		)
		(fill yes)
		(layer "In4.Cu")
		(net "M_D_CPU1_SB_DQS_DN<2>")
	)
	(gr_poly
		(pts
			(xy 82.571082 -284.818328) (xy 82.471006 -284.718252) (xy 82.37093 -284.818328) (xy 82.37093 -284.862778)
			(xy 82.571082 -284.862778)
		)
		(stroke
			(width 0)
			(type solid)
		)
		(fill yes)
		(layer "In4.Cu")
		(net "M_D_CPU1_SB_DQ<17>")
	)
	(gr_poly
		(pts
			(xy 82.571082 -284.414468) (xy 82.571082 -284.370018) (xy 82.37093 -284.370018) (xy 82.37093 -284.414468)
			(xy 82.471006 -284.514544)
		)
		(stroke
			(width 0)
			(type solid)
		)
		(fill yes)
		(layer "In4.Cu")
		(net "M_D_CPU1_SB_DQ<18>")
	)
	(gr_poly
		(pts
			(xy 82.571082 -283.198316) (xy 82.471006 -283.09824) (xy 82.37093 -283.198316) (xy 82.37093 -283.242766)
			(xy 82.571082 -283.242766)
		)
		(stroke
			(width 0)
			(type solid)
		)
		(fill yes)
		(layer "In4.Cu")
		(net "M_D_CPU1_SB_DQ<13>")
	)
	(gr_poly
		(pts
			(xy 82.571082 -282.794456) (xy 82.571082 -282.750006) (xy 82.37093 -282.750006) (xy 82.37093 -282.794456)
			(xy 82.471006 -282.894532)
		)
		(stroke
			(width 0)
			(type solid)
		)
		(fill yes)
		(layer "In4.Cu")
		(net "M_D_CPU1_SB_DQ<14>")
	)
	(gr_poly
		(pts
			(xy 82.571082 -281.57805) (xy 82.471006 -281.478228) (xy 82.37093 -281.57805) (xy 82.37093 -281.625802)
			(xy 82.571082 -281.625802)
		)
		(stroke
			(width 0)
			(type solid)
		)
		(fill yes)
		(layer "In4.Cu")
		(net "M_D_CPU1_SB_DQS_DN<6>")
	)
	(gr_poly
		(pts
			(xy 82.571082 -281.174698) (xy 82.571082 -281.126946) (xy 82.37093 -281.126946) (xy 82.37093 -281.174698)
			(xy 82.471006 -281.27452)
		)
		(stroke
			(width 0)
			(type solid)
		)
		(fill yes)
		(layer "In4.Cu")
		(net "M_D_CPU1_SB_DQS_DN<1>")
	)
	(gr_poly
		(pts
			(xy 82.571082 -279.958292) (xy 82.471006 -279.858216) (xy 82.37093 -279.958292) (xy 82.37093 -280.002742)
			(xy 82.571082 -280.002742)
		)
		(stroke
			(width 0)
			(type solid)
		)
		(fill yes)
		(layer "In4.Cu")
		(net "M_D_CPU1_SB_DQ<9>")
	)
	(gr_poly
		(pts
			(xy 82.571082 -279.554432) (xy 82.571082 -279.509982) (xy 82.37093 -279.509982) (xy 82.37093 -279.554432)
			(xy 82.471006 -279.654508)
		)
		(stroke
			(width 0)
			(type solid)
		)
		(fill yes)
		(layer "In4.Cu")
		(net "M_D_CPU1_SB_DQ<10>")
	)
	(gr_poly
		(pts
			(xy 82.571082 -278.33828) (xy 82.471006 -278.238204) (xy 82.37093 -278.33828) (xy 82.37093 -278.38273)
			(xy 82.571082 -278.38273)
		)
		(stroke
			(width 0)
			(type solid)
		)
		(fill yes)
		(layer "In4.Cu")
		(net "M_D_CPU1_SB_DQ<5>")
	)
	(gr_poly
		(pts
			(xy 82.571082 -277.93442) (xy 82.571082 -277.88997) (xy 82.37093 -277.88997) (xy 82.37093 -277.93442)
			(xy 82.471006 -278.034496)
		)
		(stroke
			(width 0)
			(type solid)
		)
		(fill yes)
		(layer "In4.Cu")
		(net "M_D_CPU1_SB_DQ<6>")
	)
	(gr_poly
		(pts
			(xy 82.571082 -276.718014) (xy 82.471006 -276.618192) (xy 82.37093 -276.718014) (xy 82.37093 -276.765766)
			(xy 82.571082 -276.765766)
		)
		(stroke
			(width 0)
			(type solid)
		)
		(fill yes)
		(layer "In4.Cu")
		(net "M_D_CPU1_SB_DQS_DN<5>")
	)
	(gr_poly
		(pts
			(xy 82.571082 -276.314662) (xy 82.571082 -276.26691) (xy 82.37093 -276.26691) (xy 82.37093 -276.314662)
			(xy 82.471006 -276.414484)
		)
		(stroke
			(width 0)
			(type solid)
		)
		(fill yes)
		(layer "In4.Cu")
		(net "M_D_CPU1_SB_DQS_DN<0>")
	)
	(gr_poly
		(pts
			(xy 82.571082 -275.098256) (xy 82.471006 -274.99818) (xy 82.37093 -275.098256) (xy 82.37093 -275.142706)
			(xy 82.571082 -275.142706)
		)
		(stroke
			(width 0)
			(type solid)
		)
		(fill yes)
		(layer "In4.Cu")
		(net "M_D_CPU1_SB_DQ<1>")
	)
	(gr_poly
		(pts
			(xy 82.571082 -274.694396) (xy 82.571082 -274.649946) (xy 82.37093 -274.649946) (xy 82.37093 -274.694396)
			(xy 82.471006 -274.794472)
		)
		(stroke
			(width 0)
			(type solid)
		)
		(fill yes)
		(layer "In4.Cu")
		(net "M_D_CPU1_SB_DQ<2>")
	)
	(gr_poly
		(pts
			(xy 82.571082 -273.478244) (xy 82.471006 -273.378168) (xy 82.37093 -273.478244) (xy 82.37093 -273.522694)
			(xy 82.571082 -273.522694)
		)
		(stroke
			(width 0)
			(type solid)
		)
		(fill yes)
		(layer "In4.Cu")
		(net "M_D_CPU1_SB_CB<1>")
	)
	(gr_poly
		(pts
			(xy 82.571082 -273.074384) (xy 82.571082 -273.029934) (xy 82.37093 -273.029934) (xy 82.37093 -273.074384)
			(xy 82.471006 -273.17446)
		)
		(stroke
			(width 0)
			(type solid)
		)
		(fill yes)
		(layer "In4.Cu")
		(net "M_D_CPU1_SB_CB<2>")
	)
	(gr_poly
		(pts
			(xy 82.571082 -271.857978) (xy 82.471006 -271.758156) (xy 82.37093 -271.857978) (xy 82.37093 -271.90573)
			(xy 82.571082 -271.90573)
		)
		(stroke
			(width 0)
			(type solid)
		)
		(fill yes)
		(layer "In4.Cu")
		(net "M_D_CPU1_SB_DQS_DN<4>")
	)
	(gr_poly
		(pts
			(xy 82.571082 -271.454626) (xy 82.571082 -271.406874) (xy 82.37093 -271.406874) (xy 82.37093 -271.454626)
			(xy 82.471006 -271.554448)
		)
		(stroke
			(width 0)
			(type solid)
		)
		(fill yes)
		(layer "In4.Cu")
		(net "M_D_CPU1_SB_DQS_DN<9>")
	)
	(gr_poly
		(pts
			(xy 82.571082 -270.23822) (xy 82.471006 -270.138144) (xy 82.37093 -270.23822) (xy 82.37093 -270.28267)
			(xy 82.571082 -270.28267)
		)
		(stroke
			(width 0)
			(type solid)
		)
		(fill yes)
		(layer "In4.Cu")
		(net "M_D_CPU1_SB_CB<5>")
	)
	(gr_poly
		(pts
			(xy 82.571082 -269.83436) (xy 82.571082 -269.78991) (xy 82.37093 -269.78991) (xy 82.37093 -269.83436)
			(xy 82.471006 -269.934436)
		)
		(stroke
			(width 0)
			(type solid)
		)
		(fill yes)
		(layer "In4.Cu")
		(net "M_D_CPU1_SB_CB<6>")
	)
	(gr_poly
		(pts
			(xy 82.571082 -266.991846) (xy 82.471006 -266.89177) (xy 82.37093 -266.991846) (xy 82.37093 -267.036296)
			(xy 82.571082 -267.036296)
		)
		(stroke
			(width 0)
			(type solid)
		)
		(fill yes)
		(layer "In4.Cu")
		(net "M_D_CPU1_SA_RSP<0>")
	)
	(gr_poly
		(pts
			(xy 82.571082 -266.594336) (xy 82.571082 -266.549886) (xy 82.37093 -266.549886) (xy 82.37093 -266.594336)
			(xy 82.471006 -266.694412)
		)
		(stroke
			(width 0)
			(type solid)
		)
		(fill yes)
		(layer "In4.Cu")
		(net "M_D_CPU1_SB_CS_N<1>")
	)
	(gr_poly
		(pts
			(xy 82.571082 -264.974324) (xy 82.571082 -264.929874) (xy 82.37093 -264.929874) (xy 82.37093 -264.974324)
			(xy 82.471006 -265.0744)
		)
		(stroke
			(width 0)
			(type solid)
		)
		(fill yes)
		(layer "In4.Cu")
		(net "M_D_CPU1_SB_PAR")
	)
	(gr_poly
		(pts
			(xy 82.571082 -263.758172) (xy 82.471006 -263.658096) (xy 82.37093 -263.758172) (xy 82.37093 -263.802622)
			(xy 82.571082 -263.802622)
		)
		(stroke
			(width 0)
			(type solid)
		)
		(fill yes)
		(layer "In4.Cu")
		(net "M_D_CPU1_SB_CA<4>")
	)
	(gr_poly
		(pts
			(xy 82.571082 -263.354312) (xy 82.571082 -263.309862) (xy 82.37093 -263.309862) (xy 82.37093 -263.354312)
			(xy 82.471006 -263.454388)
		)
		(stroke
			(width 0)
			(type solid)
		)
		(fill yes)
		(layer "In4.Cu")
		(net "M_D_CPU1_SB_CA<3>")
	)
	(gr_poly
		(pts
			(xy 82.571082 -262.13816) (xy 82.471006 -262.038084) (xy 82.37093 -262.13816) (xy 82.37093 -262.18261)
			(xy 82.571082 -262.18261)
		)
		(stroke
			(width 0)
			(type solid)
		)
		(fill yes)
		(layer "In4.Cu")
		(net "M_D_CPU1_SB_CA<0>")
	)
	(gr_poly
		(pts
			(xy 82.660236 -226.203256) (xy 82.56016 -226.030028) (xy 82.521806 -226.05238) (xy 82.48523 -226.189032)
			(xy 82.621628 -226.225608)
		)
		(stroke
			(width 0)
			(type solid)
		)
		(fill yes)
		(layer "In4.Cu")
		(net "M_D_CPU1_SA_DQ<3>")
	)
	(gr_poly
		(pts
			(xy 82.660236 -224.583244) (xy 82.56016 -224.410016) (xy 82.521806 -224.432368) (xy 82.48523 -224.56902)
			(xy 82.621628 -224.605596)
		)
		(stroke
			(width 0)
			(type solid)
		)
		(fill yes)
		(layer "In4.Cu")
		(net "M_D_CPU1_SA_DQ<2>")
	)
	(gr_poly
		(pts
			(xy 82.741008 -256.432812) (xy 82.741008 -256.38506) (xy 82.540856 -256.38506) (xy 82.540856 -256.432812)
			(xy 82.640932 -256.532634)
		)
		(stroke
			(width 0)
			(type solid)
		)
		(fill yes)
		(layer "In4.Cu")
		(net "M_D_CPU1_CLK_DN<0>")
	)
	(gr_poly
		(pts
			(xy 82.741008 -255.216406) (xy 82.640932 -255.11633) (xy 82.540856 -255.216406) (xy 82.540856 -255.260856)
			(xy 82.741008 -255.260856)
		)
		(stroke
			(width 0)
			(type solid)
		)
		(fill yes)
		(layer "In4.Cu")
		(net "M_D_CPU1_SA_CA<6>")
	)
	(gr_poly
		(pts
			(xy 82.741008 -254.812546) (xy 82.741008 -254.768096) (xy 82.540856 -254.768096) (xy 82.540856 -254.812546)
			(xy 82.640932 -254.912622)
		)
		(stroke
			(width 0)
			(type solid)
		)
		(fill yes)
		(layer "In4.Cu")
		(net "M_D_CPU1_SA_CA<5>")
	)
	(gr_poly
		(pts
			(xy 82.741008 -253.596394) (xy 82.640932 -253.496318) (xy 82.540856 -253.596394) (xy 82.540856 -253.640844)
			(xy 82.741008 -253.640844)
		)
		(stroke
			(width 0)
			(type solid)
		)
		(fill yes)
		(layer "In4.Cu")
		(net "M_D_CPU1_SA_CA<2>")
	)
	(gr_poly
		(pts
			(xy 82.741008 -253.192534) (xy 82.741008 -253.148084) (xy 82.540856 -253.148084) (xy 82.540856 -253.192534)
			(xy 82.640932 -253.29261)
		)
		(stroke
			(width 0)
			(type solid)
		)
		(fill yes)
		(layer "In4.Cu")
		(net "M_D_CPU1_SA_CA<1>")
	)
	(gr_poly
		(pts
			(xy 82.741008 -251.572522) (xy 82.741008 -251.528072) (xy 82.540856 -251.528072) (xy 82.540856 -251.572522)
			(xy 82.640932 -251.672598)
		)
		(stroke
			(width 0)
			(type solid)
		)
		(fill yes)
		(layer "In4.Cu")
		(net "M_D_CPU1_SA_CS_N<0>")
	)
	(gr_poly
		(pts
			(xy 82.741008 -250.35637) (xy 82.640932 -250.256294) (xy 82.540856 -250.35637) (xy 82.540856 -250.40082)
			(xy 82.741008 -250.40082)
		)
		(stroke
			(width 0)
			(type solid)
		)
		(fill yes)
		(layer "In4.Cu")
		(net "M_D_CPU1_ALERT_R_N")
	)
	(gr_poly
		(pts
			(xy 82.741008 -248.736358) (xy 82.640932 -248.636282) (xy 82.540856 -248.736358) (xy 82.540856 -248.780808)
			(xy 82.741008 -248.780808)
		)
		(stroke
			(width 0)
			(type solid)
		)
		(fill yes)
		(layer "In4.Cu")
		(net "M_D_CPU1_SA_CB<5>")
	)
	(gr_poly
		(pts
			(xy 82.741008 -248.332498) (xy 82.741008 -248.288048) (xy 82.540856 -248.288048) (xy 82.540856 -248.332498)
			(xy 82.640932 -248.432574)
		)
		(stroke
			(width 0)
			(type solid)
		)
		(fill yes)
		(layer "In4.Cu")
		(net "M_D_CPU1_SA_CB<6>")
	)
	(gr_poly
		(pts
			(xy 82.741008 -247.116092) (xy 82.640932 -247.01627) (xy 82.540856 -247.116092) (xy 82.540856 -247.163844)
			(xy 82.741008 -247.163844)
		)
		(stroke
			(width 0)
			(type solid)
		)
		(fill yes)
		(layer "In4.Cu")
		(net "M_D_CPU1_SA_DQS_DN<9>")
	)
	(gr_poly
		(pts
			(xy 82.741008 -246.71274) (xy 82.741008 -246.664988) (xy 82.540856 -246.664988) (xy 82.540856 -246.71274)
			(xy 82.640932 -246.812562)
		)
		(stroke
			(width 0)
			(type solid)
		)
		(fill yes)
		(layer "In4.Cu")
		(net "M_D_CPU1_SA_DQS_DN<4>")
	)
	(gr_poly
		(pts
			(xy 82.741008 -245.496334) (xy 82.640932 -245.396258) (xy 82.540856 -245.496334) (xy 82.540856 -245.540784)
			(xy 82.741008 -245.540784)
		)
		(stroke
			(width 0)
			(type solid)
		)
		(fill yes)
		(layer "In4.Cu")
		(net "M_D_CPU1_SA_CB<1>")
	)
	(gr_poly
		(pts
			(xy 82.741008 -245.092474) (xy 82.741008 -245.048024) (xy 82.540856 -245.048024) (xy 82.540856 -245.092474)
			(xy 82.640932 -245.19255)
		)
		(stroke
			(width 0)
			(type solid)
		)
		(fill yes)
		(layer "In4.Cu")
		(net "M_D_CPU1_SA_CB<2>")
	)
	(gr_poly
		(pts
			(xy 82.741008 -243.876322) (xy 82.640932 -243.776246) (xy 82.540856 -243.876322) (xy 82.540856 -243.920772)
			(xy 82.741008 -243.920772)
		)
		(stroke
			(width 0)
			(type solid)
		)
		(fill yes)
		(layer "In4.Cu")
		(net "M_D_CPU1_SA_DQ<29>")
	)
	(gr_poly
		(pts
			(xy 82.741008 -243.472462) (xy 82.741008 -243.428012) (xy 82.540856 -243.428012) (xy 82.540856 -243.472462)
			(xy 82.640932 -243.572538)
		)
		(stroke
			(width 0)
			(type solid)
		)
		(fill yes)
		(layer "In4.Cu")
		(net "M_D_CPU1_SA_DQ<30>")
	)
	(gr_poly
		(pts
			(xy 82.741008 -242.256056) (xy 82.640932 -242.156234) (xy 82.540856 -242.256056) (xy 82.540856 -242.303808)
			(xy 82.741008 -242.303808)
		)
		(stroke
			(width 0)
			(type solid)
		)
		(fill yes)
		(layer "In4.Cu")
		(net "M_D_CPU1_SA_DQS_DN<8>")
	)
	(gr_poly
		(pts
			(xy 82.741008 -241.852704) (xy 82.741008 -241.804952) (xy 82.540856 -241.804952) (xy 82.540856 -241.852704)
			(xy 82.640932 -241.952526)
		)
		(stroke
			(width 0)
			(type solid)
		)
		(fill yes)
		(layer "In4.Cu")
		(net "M_D_CPU1_SA_DQS_DN<3>")
	)
	(gr_poly
		(pts
			(xy 82.741008 -240.636298) (xy 82.640932 -240.536222) (xy 82.540856 -240.636298) (xy 82.540856 -240.680748)
			(xy 82.741008 -240.680748)
		)
		(stroke
			(width 0)
			(type solid)
		)
		(fill yes)
		(layer "In4.Cu")
		(net "M_D_CPU1_SA_DQ<25>")
	)
	(gr_poly
		(pts
			(xy 82.741008 -240.232438) (xy 82.741008 -240.187988) (xy 82.540856 -240.187988) (xy 82.540856 -240.232438)
			(xy 82.640932 -240.332514)
		)
		(stroke
			(width 0)
			(type solid)
		)
		(fill yes)
		(layer "In4.Cu")
		(net "M_D_CPU1_SA_DQ<26>")
	)
	(gr_poly
		(pts
			(xy 82.741008 -239.016286) (xy 82.640932 -238.91621) (xy 82.540856 -239.016286) (xy 82.540856 -239.060736)
			(xy 82.741008 -239.060736)
		)
		(stroke
			(width 0)
			(type solid)
		)
		(fill yes)
		(layer "In4.Cu")
		(net "M_D_CPU1_SA_DQ<21>")
	)
	(gr_poly
		(pts
			(xy 82.741008 -238.612426) (xy 82.741008 -238.567976) (xy 82.540856 -238.567976) (xy 82.540856 -238.612426)
			(xy 82.640932 -238.712502)
		)
		(stroke
			(width 0)
			(type solid)
		)
		(fill yes)
		(layer "In4.Cu")
		(net "M_D_CPU1_SA_DQ<22>")
	)
	(gr_poly
		(pts
			(xy 82.741008 -237.39602) (xy 82.640932 -237.296198) (xy 82.540856 -237.39602) (xy 82.540856 -237.443772)
			(xy 82.741008 -237.443772)
		)
		(stroke
			(width 0)
			(type solid)
		)
		(fill yes)
		(layer "In4.Cu")
		(net "M_D_CPU1_SA_DQS_DN<7>")
	)
	(gr_poly
		(pts
			(xy 82.741008 -236.992668) (xy 82.741008 -236.944916) (xy 82.540856 -236.944916) (xy 82.540856 -236.992668)
			(xy 82.640932 -237.09249)
		)
		(stroke
			(width 0)
			(type solid)
		)
		(fill yes)
		(layer "In4.Cu")
		(net "M_D_CPU1_SA_DQS_DN<2>")
	)
	(gr_poly
		(pts
			(xy 82.741008 -235.776262) (xy 82.640932 -235.676186) (xy 82.540856 -235.776262) (xy 82.540856 -235.820712)
			(xy 82.741008 -235.820712)
		)
		(stroke
			(width 0)
			(type solid)
		)
		(fill yes)
		(layer "In4.Cu")
		(net "M_D_CPU1_SA_DQ<17>")
	)
	(gr_poly
		(pts
			(xy 82.741008 -235.372402) (xy 82.741008 -235.327952) (xy 82.540856 -235.327952) (xy 82.540856 -235.372402)
			(xy 82.640932 -235.472478)
		)
		(stroke
			(width 0)
			(type solid)
		)
		(fill yes)
		(layer "In4.Cu")
		(net "M_D_CPU1_SA_DQ<18>")
	)
	(gr_poly
		(pts
			(xy 82.741008 -234.15625) (xy 82.640932 -234.056174) (xy 82.540856 -234.15625) (xy 82.540856 -234.2007)
			(xy 82.741008 -234.2007)
		)
		(stroke
			(width 0)
			(type solid)
		)
		(fill yes)
		(layer "In4.Cu")
		(net "M_D_CPU1_SA_DQ<13>")
	)
	(gr_poly
		(pts
			(xy 82.741008 -233.75239) (xy 82.741008 -233.70794) (xy 82.540856 -233.70794) (xy 82.540856 -233.75239)
			(xy 82.640932 -233.852466)
		)
		(stroke
			(width 0)
			(type solid)
		)
		(fill yes)
		(layer "In4.Cu")
		(net "M_D_CPU1_SA_DQ<14>")
	)
	(gr_poly
		(pts
			(xy 82.741008 -232.535984) (xy 82.640932 -232.436162) (xy 82.540856 -232.535984) (xy 82.540856 -232.583736)
			(xy 82.741008 -232.583736)
		)
		(stroke
			(width 0)
			(type solid)
		)
		(fill yes)
		(layer "In4.Cu")
		(net "M_D_CPU1_SA_DQS_DN<6>")
	)
	(gr_poly
		(pts
			(xy 82.741008 -232.132632) (xy 82.741008 -232.08488) (xy 82.540856 -232.08488) (xy 82.540856 -232.132632)
			(xy 82.640932 -232.232454)
		)
		(stroke
			(width 0)
			(type solid)
		)
		(fill yes)
		(layer "In4.Cu")
		(net "M_D_CPU1_SA_DQS_DN<1>")
	)
	(gr_poly
		(pts
			(xy 82.741008 -230.916226) (xy 82.640932 -230.81615) (xy 82.540856 -230.916226) (xy 82.540856 -230.960676)
			(xy 82.741008 -230.960676)
		)
		(stroke
			(width 0)
			(type solid)
		)
		(fill yes)
		(layer "In4.Cu")
		(net "M_D_CPU1_SA_DQ<9>")
	)
	(gr_poly
		(pts
			(xy 82.741008 -230.51262) (xy 82.741008 -230.46817) (xy 82.540856 -230.46817) (xy 82.540856 -230.51262)
			(xy 82.640932 -230.612696)
		)
		(stroke
			(width 0)
			(type solid)
		)
		(fill yes)
		(layer "In4.Cu")
		(net "M_D_CPU1_SA_DQ<10>")
	)
	(gr_poly
		(pts
			(xy 82.741008 -229.296214) (xy 82.640932 -229.196138) (xy 82.540856 -229.296214) (xy 82.540856 -229.340664)
			(xy 82.741008 -229.340664)
		)
		(stroke
			(width 0)
			(type solid)
		)
		(fill yes)
		(layer "In4.Cu")
		(net "M_D_CPU1_SA_DQ<5>")
	)
	(gr_poly
		(pts
			(xy 82.741008 -228.892608) (xy 82.741008 -228.848158) (xy 82.540856 -228.848158) (xy 82.540856 -228.892608)
			(xy 82.640932 -228.992684)
		)
		(stroke
			(width 0)
			(type solid)
		)
		(fill yes)
		(layer "In4.Cu")
		(net "M_D_CPU1_SA_DQ<6>")
	)
	(gr_poly
		(pts
			(xy 82.741008 -227.27285) (xy 82.741008 -227.225098) (xy 82.540856 -227.225098) (xy 82.540856 -227.27285)
			(xy 82.640932 -227.372672)
		)
		(stroke
			(width 0)
			(type solid)
		)
		(fill yes)
		(layer "In4.Cu")
		(net "M_D_CPU1_SA_DQS_DN<0>")
	)
	(gr_poly
		(pts
			(xy 82.747104 -227.67671) (xy 82.647028 -227.576634) (xy 82.547206 -227.67671) (xy 82.547206 -227.724208)
			(xy 82.747104 -227.724208)
		)
		(stroke
			(width 0)
			(type solid)
		)
		(fill yes)
		(layer "In4.Cu")
		(net "M_D_CPU1_SA_DQS_DN<5>")
	)
	(gr_poly
		(pts
			(xy 82.760312 -225.656648) (xy 82.797142 -225.519996) (xy 82.66049 -225.48342) (xy 82.621882 -225.505772)
			(xy 82.721958 -225.679)
		)
		(stroke
			(width 0)
			(type solid)
		)
		(fill yes)
		(layer "In4.Cu")
		(net "M_D_CPU1_SA_DQ<1>")
	)
	(gr_poly
		(pts
			(xy 82.760312 -224.036636) (xy 82.797142 -223.899984) (xy 82.66049 -223.863408) (xy 82.621882 -223.88576)
			(xy 82.721958 -224.058988)
		)
		(stroke
			(width 0)
			(type solid)
		)
		(fill yes)
		(layer "In4.Cu")
		(net "M_D_CPU1_SA_DQ<0>")
	)
	(gr_poly
		(pts
			(xy 83.040982 -293.32428) (xy 83.040982 -293.27983) (xy 82.84083 -293.27983) (xy 82.84083 -293.32428)
			(xy 82.940906 -293.424356)
		)
		(stroke
			(width 0)
			(type solid)
		)
		(fill yes)
		(layer "In4.Cu")
		(net "M_D_CPU1_SB_DQ<31>")
	)
	(gr_poly
		(pts
			(xy 83.040982 -292.108128) (xy 82.940906 -292.008052) (xy 82.84083 -292.108128) (xy 82.84083 -292.152578)
			(xy 83.040982 -292.152578)
		)
		(stroke
			(width 0)
			(type solid)
		)
		(fill yes)
		(layer "In4.Cu")
		(net "M_D_CPU1_SB_DQ<28>")
	)
	(gr_poly
		(pts
			(xy 83.040982 -291.704522) (xy 83.040982 -291.65677) (xy 82.84083 -291.65677) (xy 82.84083 -291.704522)
			(xy 82.940906 -291.804344)
		)
		(stroke
			(width 0)
			(type solid)
		)
		(fill yes)
		(layer "In4.Cu")
		(net "M_D_CPU1_SB_DQS_DP<8>")
	)
	(gr_poly
		(pts
			(xy 83.040982 -290.487862) (xy 82.940906 -290.38804) (xy 82.84083 -290.487862) (xy 82.84083 -290.535614)
			(xy 83.040982 -290.535614)
		)
		(stroke
			(width 0)
			(type solid)
		)
		(fill yes)
		(layer "In4.Cu")
		(net "M_D_CPU1_SB_DQS_DP<3>")
	)
	(gr_poly
		(pts
			(xy 83.040982 -290.084256) (xy 83.040982 -290.039806) (xy 82.84083 -290.039806) (xy 82.84083 -290.084256)
			(xy 82.940906 -290.184332)
		)
		(stroke
			(width 0)
			(type solid)
		)
		(fill yes)
		(layer "In4.Cu")
		(net "M_D_CPU1_SB_DQ<27>")
	)
	(gr_poly
		(pts
			(xy 83.040982 -288.868104) (xy 82.940906 -288.768028) (xy 82.84083 -288.868104) (xy 82.84083 -288.912554)
			(xy 83.040982 -288.912554)
		)
		(stroke
			(width 0)
			(type solid)
		)
		(fill yes)
		(layer "In4.Cu")
		(net "M_D_CPU1_SB_DQ<24>")
	)
	(gr_poly
		(pts
			(xy 83.040982 -288.464498) (xy 83.040982 -288.420048) (xy 82.84083 -288.420048) (xy 82.84083 -288.464498)
			(xy 82.940906 -288.564574)
		)
		(stroke
			(width 0)
			(type solid)
		)
		(fill yes)
		(layer "In4.Cu")
		(net "M_D_CPU1_SB_DQ<23>")
	)
	(gr_poly
		(pts
			(xy 83.040982 -287.248092) (xy 82.940906 -287.148016) (xy 82.84083 -287.248092) (xy 82.84083 -287.292542)
			(xy 83.040982 -287.292542)
		)
		(stroke
			(width 0)
			(type solid)
		)
		(fill yes)
		(layer "In4.Cu")
		(net "M_D_CPU1_SB_DQ<20>")
	)
	(gr_poly
		(pts
			(xy 83.040982 -286.844486) (xy 83.040982 -286.796734) (xy 82.84083 -286.796734) (xy 82.84083 -286.844486)
			(xy 82.940906 -286.944562)
		)
		(stroke
			(width 0)
			(type solid)
		)
		(fill yes)
		(layer "In4.Cu")
		(net "M_D_CPU1_SB_DQS_DP<7>")
	)
	(gr_poly
		(pts
			(xy 83.040982 -285.62808) (xy 82.940906 -285.528258) (xy 82.84083 -285.62808) (xy 82.84083 -285.675832)
			(xy 83.040982 -285.675832)
		)
		(stroke
			(width 0)
			(type solid)
		)
		(fill yes)
		(layer "In4.Cu")
		(net "M_D_CPU1_SB_DQS_DP<2>")
	)
	(gr_poly
		(pts
			(xy 83.040982 -285.224474) (xy 83.040982 -285.180024) (xy 82.84083 -285.180024) (xy 82.84083 -285.224474)
			(xy 82.940906 -285.32455)
		)
		(stroke
			(width 0)
			(type solid)
		)
		(fill yes)
		(layer "In4.Cu")
		(net "M_D_CPU1_SB_DQ<19>")
	)
	(gr_poly
		(pts
			(xy 83.040982 -284.008322) (xy 82.940906 -283.908246) (xy 82.84083 -284.008322) (xy 82.84083 -284.052772)
			(xy 83.040982 -284.052772)
		)
		(stroke
			(width 0)
			(type solid)
		)
		(fill yes)
		(layer "In4.Cu")
		(net "M_D_CPU1_SB_DQ<16>")
	)
	(gr_poly
		(pts
			(xy 83.040982 -283.604462) (xy 83.040982 -283.560012) (xy 82.84083 -283.560012) (xy 82.84083 -283.604462)
			(xy 82.940906 -283.704538)
		)
		(stroke
			(width 0)
			(type solid)
		)
		(fill yes)
		(layer "In4.Cu")
		(net "M_D_CPU1_SB_DQ<15>")
	)
	(gr_poly
		(pts
			(xy 83.040982 -282.38831) (xy 82.940906 -282.288234) (xy 82.84083 -282.38831) (xy 82.84083 -282.43276)
			(xy 83.040982 -282.43276)
		)
		(stroke
			(width 0)
			(type solid)
		)
		(fill yes)
		(layer "In4.Cu")
		(net "M_D_CPU1_SB_DQ<12>")
	)
	(gr_poly
		(pts
			(xy 83.040982 -281.984704) (xy 83.040982 -281.936952) (xy 82.84083 -281.936952) (xy 82.84083 -281.984704)
			(xy 82.940906 -282.084526)
		)
		(stroke
			(width 0)
			(type solid)
		)
		(fill yes)
		(layer "In4.Cu")
		(net "M_D_CPU1_SB_DQS_DP<6>")
	)
	(gr_poly
		(pts
			(xy 83.040982 -280.768044) (xy 82.940906 -280.668222) (xy 82.84083 -280.768044) (xy 82.84083 -280.815796)
			(xy 83.040982 -280.815796)
		)
		(stroke
			(width 0)
			(type solid)
		)
		(fill yes)
		(layer "In4.Cu")
		(net "M_D_CPU1_SB_DQS_DP<1>")
	)
	(gr_poly
		(pts
			(xy 83.040982 -280.364438) (xy 83.040982 -280.319988) (xy 82.84083 -280.319988) (xy 82.84083 -280.364438)
			(xy 82.940906 -280.464514)
		)
		(stroke
			(width 0)
			(type solid)
		)
		(fill yes)
		(layer "In4.Cu")
		(net "M_D_CPU1_SB_DQ<11>")
	)
	(gr_poly
		(pts
			(xy 83.040982 -279.148286) (xy 82.940906 -279.04821) (xy 82.84083 -279.148286) (xy 82.84083 -279.192736)
			(xy 83.040982 -279.192736)
		)
		(stroke
			(width 0)
			(type solid)
		)
		(fill yes)
		(layer "In4.Cu")
		(net "M_D_CPU1_SB_DQ<8>")
	)
	(gr_poly
		(pts
			(xy 83.040982 -278.744426) (xy 83.040982 -278.699976) (xy 82.84083 -278.699976) (xy 82.84083 -278.744426)
			(xy 82.940906 -278.844502)
		)
		(stroke
			(width 0)
			(type solid)
		)
		(fill yes)
		(layer "In4.Cu")
		(net "M_D_CPU1_SB_DQ<7>")
	)
	(gr_poly
		(pts
			(xy 83.040982 -277.528274) (xy 82.940906 -277.428198) (xy 82.84083 -277.528274) (xy 82.84083 -277.572724)
			(xy 83.040982 -277.572724)
		)
		(stroke
			(width 0)
			(type solid)
		)
		(fill yes)
		(layer "In4.Cu")
		(net "M_D_CPU1_SB_DQ<4>")
	)
	(gr_poly
		(pts
			(xy 83.040982 -275.504402) (xy 83.040982 -275.459952) (xy 82.84083 -275.459952) (xy 82.84083 -275.504402)
			(xy 82.940906 -275.604478)
		)
		(stroke
			(width 0)
			(type solid)
		)
		(fill yes)
		(layer "In4.Cu")
		(net "M_D_CPU1_SB_DQ<3>")
	)
	(gr_poly
		(pts
			(xy 83.040982 -274.28825) (xy 82.940906 -274.188174) (xy 82.84083 -274.28825) (xy 82.84083 -274.3327)
			(xy 83.040982 -274.3327)
		)
		(stroke
			(width 0)
			(type solid)
		)
		(fill yes)
		(layer "In4.Cu")
		(net "M_D_CPU1_SB_DQ<0>")
	)
	(gr_poly
		(pts
			(xy 83.040982 -273.88439) (xy 83.040982 -273.83994) (xy 82.84083 -273.83994) (xy 82.84083 -273.88439)
			(xy 82.940906 -273.984466)
		)
		(stroke
			(width 0)
			(type solid)
		)
		(fill yes)
		(layer "In4.Cu")
		(net "M_D_CPU1_SB_CB<3>")
	)
	(gr_poly
		(pts
			(xy 83.040982 -272.668238) (xy 82.940906 -272.568162) (xy 82.84083 -272.668238) (xy 82.84083 -272.712688)
			(xy 83.040982 -272.712688)
		)
		(stroke
			(width 0)
			(type solid)
		)
		(fill yes)
		(layer "In4.Cu")
		(net "M_D_CPU1_SB_CB<0>")
	)
	(gr_poly
		(pts
			(xy 83.040982 -272.264632) (xy 83.040982 -272.21688) (xy 82.84083 -272.21688) (xy 82.84083 -272.264632)
			(xy 82.940906 -272.364454)
		)
		(stroke
			(width 0)
			(type solid)
		)
		(fill yes)
		(layer "In4.Cu")
		(net "M_D_CPU1_SB_DQS_DP<4>")
	)
	(gr_poly
		(pts
			(xy 83.040982 -271.047972) (xy 82.940906 -270.94815) (xy 82.84083 -271.047972) (xy 82.84083 -271.095724)
			(xy 83.040982 -271.095724)
		)
		(stroke
			(width 0)
			(type solid)
		)
		(fill yes)
		(layer "In4.Cu")
		(net "M_D_CPU1_SB_DQS_DP<9>")
	)
	(gr_poly
		(pts
			(xy 83.040982 -270.644366) (xy 83.040982 -270.599916) (xy 82.84083 -270.599916) (xy 82.84083 -270.644366)
			(xy 82.940906 -270.744442)
		)
		(stroke
			(width 0)
			(type solid)
		)
		(fill yes)
		(layer "In4.Cu")
		(net "M_D_CPU1_SB_CB<7>")
	)
	(gr_poly
		(pts
			(xy 83.040982 -269.428214) (xy 82.940906 -269.328138) (xy 82.84083 -269.428214) (xy 82.84083 -269.472664)
			(xy 83.040982 -269.472664)
		)
		(stroke
			(width 0)
			(type solid)
		)
		(fill yes)
		(layer "In4.Cu")
		(net "M_D_CPU1_SB_CB<4>")
	)
	(gr_poly
		(pts
			(xy 83.040982 -264.164318) (xy 83.040982 -264.119868) (xy 82.84083 -264.119868) (xy 82.84083 -264.164318)
			(xy 82.940906 -264.264394)
		)
		(stroke
			(width 0)
			(type solid)
		)
		(fill yes)
		(layer "In4.Cu")
		(net "M_D_CPU1_SB_CA<5>")
	)
	(gr_poly
		(pts
			(xy 83.040982 -262.948166) (xy 82.940906 -262.84809) (xy 82.84083 -262.948166) (xy 82.84083 -262.992616)
			(xy 83.040982 -262.992616)
		)
		(stroke
			(width 0)
			(type solid)
		)
		(fill yes)
		(layer "In4.Cu")
		(net "M_D_CPU1_SB_CA<2>")
	)
	(gr_poly
		(pts
			(xy 83.040982 -262.544306) (xy 83.040982 -262.499856) (xy 82.84083 -262.499856) (xy 82.84083 -262.544306)
			(xy 82.940906 -262.644382)
		)
		(stroke
			(width 0)
			(type solid)
		)
		(fill yes)
		(layer "In4.Cu")
		(net "M_D_CPU1_SB_CA<1>")
	)
	(gr_poly
		(pts
			(xy 83.041236 -265.78433) (xy 83.041236 -265.73988) (xy 82.841084 -265.73988) (xy 82.841084 -265.78433)
			(xy 82.94116 -265.884406)
		)
		(stroke
			(width 0)
			(type solid)
		)
		(fill yes)
		(layer "In4.Cu")
		(net "M_D_CPU1_SB_CS_N<0>")
	)
	(gr_poly
		(pts
			(xy 83.041236 -264.568178) (xy 82.94116 -264.468102) (xy 82.841084 -264.568178) (xy 82.841084 -264.612628)
			(xy 83.041236 -264.612628)
		)
		(stroke
			(width 0)
			(type solid)
		)
		(fill yes)
		(layer "In4.Cu")
		(net "M_D_CPU1_SB_CA<6>")
	)
	(gr_poly
		(pts
			(xy 83.047078 -267.801852) (xy 82.947256 -267.701776) (xy 82.84718 -267.801852) (xy 82.84718 -267.846302)
			(xy 83.047078 -267.846302)
		)
		(stroke
			(width 0)
			(type solid)
		)
		(fill yes)
		(layer "In4.Cu")
		(net "M_D_CPU1_SB_RSP<0>")
	)
	(gr_poly
		(pts
			(xy 83.048094 -277.124668) (xy 83.048094 -277.076916) (xy 82.848196 -277.076916) (xy 82.848196 -277.124668)
			(xy 82.948272 -277.22449)
		)
		(stroke
			(width 0)
			(type solid)
		)
		(fill yes)
		(layer "In4.Cu")
		(net "M_D_CPU1_SB_DQS_DP<5>")
	)
	(gr_poly
		(pts
			(xy 83.048094 -275.908008) (xy 82.948272 -275.808186) (xy 82.848196 -275.908008) (xy 82.848196 -275.95576)
			(xy 83.048094 -275.95576)
		)
		(stroke
			(width 0)
			(type solid)
		)
		(fill yes)
		(layer "In4.Cu")
		(net "M_D_CPU1_SB_DQS_DP<0>")
	)
	(gr_poly
		(pts
			(xy 83.130136 -225.39325) (xy 83.03006 -225.220022) (xy 82.991706 -225.242374) (xy 82.95513 -225.379026)
			(xy 83.091528 -225.415602)
		)
		(stroke
			(width 0)
			(type solid)
		)
		(fill yes)
		(layer "In4.Cu")
		(net "M_D_CPU1_SA_DQ<2>")
	)
	(gr_poly
		(pts
			(xy 83.211162 -256.026158) (xy 83.111086 -255.926336) (xy 83.01101 -256.026158) (xy 83.01101 -256.07391)
			(xy 83.211162 -256.07391)
		)
		(stroke
			(width 0)
			(type solid)
		)
		(fill yes)
		(layer "In4.Cu")
		(net "M_D_CPU1_CLK_DP<0>")
	)
	(gr_poly
		(pts
			(xy 83.211162 -255.622552) (xy 83.211162 -255.578102) (xy 83.01101 -255.578102) (xy 83.01101 -255.622552)
			(xy 83.111086 -255.722628)
		)
		(stroke
			(width 0)
			(type solid)
		)
		(fill yes)
		(layer "In4.Cu")
		(net "M_D_CPU1_SA_PAR")
	)
	(gr_poly
		(pts
			(xy 83.211162 -254.4064) (xy 83.111086 -254.306324) (xy 83.01101 -254.4064) (xy 83.01101 -254.45085)
			(xy 83.211162 -254.45085)
		)
		(stroke
			(width 0)
			(type solid)
		)
		(fill yes)
		(layer "In4.Cu")
		(net "M_D_CPU1_SA_CA<4>")
	)
	(gr_poly
		(pts
			(xy 83.211162 -254.00254) (xy 83.211162 -253.95809) (xy 83.01101 -253.95809) (xy 83.01101 -254.00254)
			(xy 83.111086 -254.102616)
		)
		(stroke
			(width 0)
			(type solid)
		)
		(fill yes)
		(layer "In4.Cu")
		(net "M_D_CPU1_SA_CA<3>")
	)
	(gr_poly
		(pts
			(xy 83.211162 -252.786388) (xy 83.111086 -252.686312) (xy 83.01101 -252.786388) (xy 83.01101 -252.830838)
			(xy 83.211162 -252.830838)
		)
		(stroke
			(width 0)
			(type solid)
		)
		(fill yes)
		(layer "In4.Cu")
		(net "M_D_CPU1_SA_CA<0>")
	)
	(gr_poly
		(pts
			(xy 83.211162 -252.382528) (xy 83.211162 -252.338078) (xy 83.01101 -252.338078) (xy 83.01101 -252.382528)
			(xy 83.111086 -252.482604)
		)
		(stroke
			(width 0)
			(type solid)
		)
		(fill yes)
		(layer "In4.Cu")
		(net "M_D_CPU1_SA_CS_N<1>")
	)
	(gr_poly
		(pts
			(xy 83.211162 -250.762516) (xy 83.211162 -250.718066) (xy 83.01101 -250.718066) (xy 83.01101 -250.762516)
			(xy 83.111086 -250.862592)
		)
		(stroke
			(width 0)
			(type solid)
		)
		(fill yes)
		(layer "In4.Cu")
		(net "M_D_CPU1_RESET_N")
	)
	(gr_poly
		(pts
			(xy 83.211162 -249.142504) (xy 83.211162 -249.098054) (xy 83.01101 -249.098054) (xy 83.01101 -249.142504)
			(xy 83.111086 -249.24258)
		)
		(stroke
			(width 0)
			(type solid)
		)
		(fill yes)
		(layer "In4.Cu")
		(net "M_D_CPU1_SA_CB<7>")
	)
	(gr_poly
		(pts
			(xy 83.211162 -247.926352) (xy 83.111086 -247.826276) (xy 83.01101 -247.926352) (xy 83.01101 -247.970802)
			(xy 83.211162 -247.970802)
		)
		(stroke
			(width 0)
			(type solid)
		)
		(fill yes)
		(layer "In4.Cu")
		(net "M_D_CPU1_SA_CB<4>")
	)
	(gr_poly
		(pts
			(xy 83.211162 -247.522746) (xy 83.211162 -247.474994) (xy 83.01101 -247.474994) (xy 83.01101 -247.522746)
			(xy 83.111086 -247.622568)
		)
		(stroke
			(width 0)
			(type solid)
		)
		(fill yes)
		(layer "In4.Cu")
		(net "M_D_CPU1_SA_DQS_DP<9>")
	)
	(gr_poly
		(pts
			(xy 83.211162 -246.306086) (xy 83.111086 -246.206264) (xy 83.01101 -246.306086) (xy 83.01101 -246.353838)
			(xy 83.211162 -246.353838)
		)
		(stroke
			(width 0)
			(type solid)
		)
		(fill yes)
		(layer "In4.Cu")
		(net "M_D_CPU1_SA_DQS_DP<4>")
	)
	(gr_poly
		(pts
			(xy 83.211162 -245.90248) (xy 83.211162 -245.85803) (xy 83.01101 -245.85803) (xy 83.01101 -245.90248)
			(xy 83.111086 -246.002556)
		)
		(stroke
			(width 0)
			(type solid)
		)
		(fill yes)
		(layer "In4.Cu")
		(net "M_D_CPU1_SA_CB<3>")
	)
	(gr_poly
		(pts
			(xy 83.211162 -244.686328) (xy 83.111086 -244.586252) (xy 83.01101 -244.686328) (xy 83.01101 -244.730778)
			(xy 83.211162 -244.730778)
		)
		(stroke
			(width 0)
			(type solid)
		)
		(fill yes)
		(layer "In4.Cu")
		(net "M_D_CPU1_SA_CB<0>")
	)
	(gr_poly
		(pts
			(xy 83.211162 -244.282468) (xy 83.211162 -244.238018) (xy 83.01101 -244.238018) (xy 83.01101 -244.282468)
			(xy 83.111086 -244.382544)
		)
		(stroke
			(width 0)
			(type solid)
		)
		(fill yes)
		(layer "In4.Cu")
		(net "M_D_CPU1_SA_DQ<31>")
	)
	(gr_poly
		(pts
			(xy 83.211162 -243.066316) (xy 83.111086 -242.96624) (xy 83.01101 -243.066316) (xy 83.01101 -243.110766)
			(xy 83.211162 -243.110766)
		)
		(stroke
			(width 0)
			(type solid)
		)
		(fill yes)
		(layer "In4.Cu")
		(net "M_D_CPU1_SA_DQ<28>")
	)
	(gr_poly
		(pts
			(xy 83.211162 -242.66271) (xy 83.211162 -242.614958) (xy 83.01101 -242.614958) (xy 83.01101 -242.66271)
			(xy 83.111086 -242.762532)
		)
		(stroke
			(width 0)
			(type solid)
		)
		(fill yes)
		(layer "In4.Cu")
		(net "M_D_CPU1_SA_DQS_DP<8>")
	)
	(gr_poly
		(pts
			(xy 83.211162 -241.44605) (xy 83.111086 -241.346228) (xy 83.01101 -241.44605) (xy 83.01101 -241.493802)
			(xy 83.211162 -241.493802)
		)
		(stroke
			(width 0)
			(type solid)
		)
		(fill yes)
		(layer "In4.Cu")
		(net "M_D_CPU1_SA_DQS_DP<3>")
	)
	(gr_poly
		(pts
			(xy 83.211162 -241.042444) (xy 83.211162 -240.997994) (xy 83.01101 -240.997994) (xy 83.01101 -241.042444)
			(xy 83.111086 -241.14252)
		)
		(stroke
			(width 0)
			(type solid)
		)
		(fill yes)
		(layer "In4.Cu")
		(net "M_D_CPU1_SA_DQ<27>")
	)
	(gr_poly
		(pts
			(xy 83.211162 -239.826292) (xy 83.111086 -239.726216) (xy 83.01101 -239.826292) (xy 83.01101 -239.870742)
			(xy 83.211162 -239.870742)
		)
		(stroke
			(width 0)
			(type solid)
		)
		(fill yes)
		(layer "In4.Cu")
		(net "M_D_CPU1_SA_DQ<24>")
	)
	(gr_poly
		(pts
			(xy 83.211162 -239.422432) (xy 83.211162 -239.377982) (xy 83.01101 -239.377982) (xy 83.01101 -239.422432)
			(xy 83.111086 -239.522508)
		)
		(stroke
			(width 0)
			(type solid)
		)
		(fill yes)
		(layer "In4.Cu")
		(net "M_D_CPU1_SA_DQ<23>")
	)
	(gr_poly
		(pts
			(xy 83.211162 -238.20628) (xy 83.111086 -238.106204) (xy 83.01101 -238.20628) (xy 83.01101 -238.25073)
			(xy 83.211162 -238.25073)
		)
		(stroke
			(width 0)
			(type solid)
		)
		(fill yes)
		(layer "In4.Cu")
		(net "M_D_CPU1_SA_DQ<20>")
	)
	(gr_poly
		(pts
			(xy 83.211162 -237.802674) (xy 83.211162 -237.754922) (xy 83.01101 -237.754922) (xy 83.01101 -237.802674)
			(xy 83.111086 -237.902496)
		)
		(stroke
			(width 0)
			(type solid)
		)
		(fill yes)
		(layer "In4.Cu")
		(net "M_D_CPU1_SA_DQS_DP<7>")
	)
	(gr_poly
		(pts
			(xy 83.211162 -236.586014) (xy 83.111086 -236.486192) (xy 83.01101 -236.586014) (xy 83.01101 -236.633766)
			(xy 83.211162 -236.633766)
		)
		(stroke
			(width 0)
			(type solid)
		)
		(fill yes)
		(layer "In4.Cu")
		(net "M_D_CPU1_SA_DQS_DP<2>")
	)
	(gr_poly
		(pts
			(xy 83.211162 -236.182408) (xy 83.211162 -236.137958) (xy 83.01101 -236.137958) (xy 83.01101 -236.182408)
			(xy 83.111086 -236.282484)
		)
		(stroke
			(width 0)
			(type solid)
		)
		(fill yes)
		(layer "In4.Cu")
		(net "M_D_CPU1_SA_DQ<19>")
	)
	(gr_poly
		(pts
			(xy 83.211162 -234.966256) (xy 83.111086 -234.86618) (xy 83.01101 -234.966256) (xy 83.01101 -235.010706)
			(xy 83.211162 -235.010706)
		)
		(stroke
			(width 0)
			(type solid)
		)
		(fill yes)
		(layer "In4.Cu")
		(net "M_D_CPU1_SA_DQ<16>")
	)
	(gr_poly
		(pts
			(xy 83.211162 -234.562396) (xy 83.211162 -234.517946) (xy 83.01101 -234.517946) (xy 83.01101 -234.562396)
			(xy 83.111086 -234.662472)
		)
		(stroke
			(width 0)
			(type solid)
		)
		(fill yes)
		(layer "In4.Cu")
		(net "M_D_CPU1_SA_DQ<15>")
	)
	(gr_poly
		(pts
			(xy 83.211162 -233.346244) (xy 83.111086 -233.246168) (xy 83.01101 -233.346244) (xy 83.01101 -233.390694)
			(xy 83.211162 -233.390694)
		)
		(stroke
			(width 0)
			(type solid)
		)
		(fill yes)
		(layer "In4.Cu")
		(net "M_D_CPU1_SA_DQ<12>")
	)
	(gr_poly
		(pts
			(xy 83.211162 -232.942638) (xy 83.211162 -232.894886) (xy 83.01101 -232.894886) (xy 83.01101 -232.942638)
			(xy 83.111086 -233.04246)
		)
		(stroke
			(width 0)
			(type solid)
		)
		(fill yes)
		(layer "In4.Cu")
		(net "M_D_CPU1_SA_DQS_DP<6>")
	)
	(gr_poly
		(pts
			(xy 83.211162 -231.725978) (xy 83.111086 -231.626156) (xy 83.01101 -231.725978) (xy 83.01101 -231.77373)
			(xy 83.211162 -231.77373)
		)
		(stroke
			(width 0)
			(type solid)
		)
		(fill yes)
		(layer "In4.Cu")
		(net "M_D_CPU1_SA_DQS_DP<1>")
	)
	(gr_poly
		(pts
			(xy 83.211162 -231.322626) (xy 83.211162 -231.278176) (xy 83.01101 -231.278176) (xy 83.01101 -231.322626)
			(xy 83.111086 -231.422702)
		)
		(stroke
			(width 0)
			(type solid)
		)
		(fill yes)
		(layer "In4.Cu")
		(net "M_D_CPU1_SA_DQ<11>")
	)
	(gr_poly
		(pts
			(xy 83.211162 -230.10622) (xy 83.111086 -230.006144) (xy 83.01101 -230.10622) (xy 83.01101 -230.15067)
			(xy 83.211162 -230.15067)
		)
		(stroke
			(width 0)
			(type solid)
		)
		(fill yes)
		(layer "In4.Cu")
		(net "M_D_CPU1_SA_DQ<8>")
	)
	(gr_poly
		(pts
			(xy 83.211162 -229.702614) (xy 83.211162 -229.658164) (xy 83.01101 -229.658164) (xy 83.01101 -229.702614)
			(xy 83.111086 -229.80269)
		)
		(stroke
			(width 0)
			(type solid)
		)
		(fill yes)
		(layer "In4.Cu")
		(net "M_D_CPU1_SA_DQ<7>")
	)
	(gr_poly
		(pts
			(xy 83.211162 -228.486462) (xy 83.111086 -228.386386) (xy 83.01101 -228.486462) (xy 83.01101 -228.530912)
			(xy 83.211162 -228.530912)
		)
		(stroke
			(width 0)
			(type solid)
		)
		(fill yes)
		(layer "In4.Cu")
		(net "M_D_CPU1_SA_DQ<4>")
	)
	(gr_poly
		(pts
			(xy 83.211162 -228.082856) (xy 83.211162 -228.035104) (xy 83.01101 -228.035104) (xy 83.01101 -228.082856)
			(xy 83.111086 -228.182678)
		)
		(stroke
			(width 0)
			(type solid)
		)
		(fill yes)
		(layer "In4.Cu")
		(net "M_D_CPU1_SA_DQS_DP<5>")
	)
	(gr_poly
		(pts
			(xy 83.211162 -226.866196) (xy 83.111086 -226.766374) (xy 83.01101 -226.866196) (xy 83.01101 -226.913948)
			(xy 83.211162 -226.913948)
		)
		(stroke
			(width 0)
			(type solid)
		)
		(fill yes)
		(layer "In4.Cu")
		(net "M_D_CPU1_SA_DQS_DP<0>")
	)
	(gr_poly
		(pts
			(xy 83.211162 -226.46259) (xy 83.211162 -226.41814) (xy 83.01101 -226.41814) (xy 83.01101 -226.46259)
			(xy 83.111086 -226.562666)
		)
		(stroke
			(width 0)
			(type solid)
		)
		(fill yes)
		(layer "In4.Cu")
		(net "M_D_CPU1_SA_DQ<3>")
	)
	(gr_poly
		(pts
			(xy 83.230212 -224.846642) (xy 83.267042 -224.70999) (xy 83.13039 -224.673414) (xy 83.091782 -224.695766)
			(xy 83.191858 -224.868994)
		)
		(stroke
			(width 0)
			(type solid)
		)
		(fill yes)
		(layer "In4.Cu")
		(net "M_D_CPU1_SA_DQ<0>")
	)
	(gr_poly
		(pts
			(xy 83.504786 -266.991846) (xy 83.40471 -266.89177) (xy 83.304888 -266.991846) (xy 83.304888 -267.036296)
			(xy 83.504786 -267.036296)
		)
		(stroke
			(width 0)
			(type solid)
		)
		(fill yes)
		(layer "In4.Cu")
		(net "M_D_CPU1_SA_RSP<0>")
	)
	(gr_poly
		(pts
			(xy 83.511136 -292.918134) (xy 83.41106 -292.818058) (xy 83.310984 -292.918134) (xy 83.310984 -292.962584)
			(xy 83.511136 -292.962584)
		)
		(stroke
			(width 0)
			(type solid)
		)
		(fill yes)
		(layer "In4.Cu")
		(net "M_D_CPU1_SB_DQ<29>")
	)
	(gr_poly
		(pts
			(xy 83.511136 -292.514274) (xy 83.511136 -292.469824) (xy 83.310984 -292.469824) (xy 83.310984 -292.514274)
			(xy 83.41106 -292.61435)
		)
		(stroke
			(width 0)
			(type solid)
		)
		(fill yes)
		(layer "In4.Cu")
		(net "M_D_CPU1_SB_DQ<30>")
	)
	(gr_poly
		(pts
			(xy 83.511136 -291.297868) (xy 83.41106 -291.198046) (xy 83.310984 -291.297868) (xy 83.310984 -291.34562)
			(xy 83.511136 -291.34562)
		)
		(stroke
			(width 0)
			(type solid)
		)
		(fill yes)
		(layer "In4.Cu")
		(net "M_D_CPU1_SB_DQS_DN<8>")
	)
	(gr_poly
		(pts
			(xy 83.511136 -290.894516) (xy 83.511136 -290.846764) (xy 83.310984 -290.846764) (xy 83.310984 -290.894516)
			(xy 83.41106 -290.994338)
		)
		(stroke
			(width 0)
			(type solid)
		)
		(fill yes)
		(layer "In4.Cu")
		(net "M_D_CPU1_SB_DQS_DN<3>")
	)
	(gr_poly
		(pts
			(xy 83.511136 -289.67811) (xy 83.41106 -289.578034) (xy 83.310984 -289.67811) (xy 83.310984 -289.72256)
			(xy 83.511136 -289.72256)
		)
		(stroke
			(width 0)
			(type solid)
		)
		(fill yes)
		(layer "In4.Cu")
		(net "M_D_CPU1_SB_DQ<25>")
	)
	(gr_poly
		(pts
			(xy 83.511136 -289.27425) (xy 83.511136 -289.2298) (xy 83.310984 -289.2298) (xy 83.310984 -289.27425)
			(xy 83.41106 -289.374326)
		)
		(stroke
			(width 0)
			(type solid)
		)
		(fill yes)
		(layer "In4.Cu")
		(net "M_D_CPU1_SB_DQ<26>")
	)
	(gr_poly
		(pts
			(xy 83.511136 -288.058098) (xy 83.41106 -287.958022) (xy 83.310984 -288.058098) (xy 83.310984 -288.102548)
			(xy 83.511136 -288.102548)
		)
		(stroke
			(width 0)
			(type solid)
		)
		(fill yes)
		(layer "In4.Cu")
		(net "M_D_CPU1_SB_DQ<21>")
	)
	(gr_poly
		(pts
			(xy 83.511136 -287.654492) (xy 83.511136 -287.610042) (xy 83.310984 -287.610042) (xy 83.310984 -287.654492)
			(xy 83.41106 -287.754568)
		)
		(stroke
			(width 0)
			(type solid)
		)
		(fill yes)
		(layer "In4.Cu")
		(net "M_D_CPU1_SB_DQ<22>")
	)
	(gr_poly
		(pts
			(xy 83.511136 -286.438086) (xy 83.41106 -286.33801) (xy 83.310984 -286.438086) (xy 83.310984 -286.485838)
			(xy 83.511136 -286.485838)
		)
		(stroke
			(width 0)
			(type solid)
		)
		(fill yes)
		(layer "In4.Cu")
		(net "M_D_CPU1_SB_DQS_DN<7>")
	)
	(gr_poly
		(pts
			(xy 83.511136 -286.034734) (xy 83.511136 -285.986982) (xy 83.310984 -285.986982) (xy 83.310984 -286.034734)
			(xy 83.41106 -286.134556)
		)
		(stroke
			(width 0)
			(type solid)
		)
		(fill yes)
		(layer "In4.Cu")
		(net "M_D_CPU1_SB_DQS_DN<2>")
	)
	(gr_poly
		(pts
			(xy 83.511136 -284.818328) (xy 83.41106 -284.718252) (xy 83.310984 -284.818328) (xy 83.310984 -284.862778)
			(xy 83.511136 -284.862778)
		)
		(stroke
			(width 0)
			(type solid)
		)
		(fill yes)
		(layer "In4.Cu")
		(net "M_D_CPU1_SB_DQ<17>")
	)
	(gr_poly
		(pts
			(xy 83.511136 -284.414468) (xy 83.511136 -284.370018) (xy 83.310984 -284.370018) (xy 83.310984 -284.414468)
			(xy 83.41106 -284.514544)
		)
		(stroke
			(width 0)
			(type solid)
		)
		(fill yes)
		(layer "In4.Cu")
		(net "M_D_CPU1_SB_DQ<18>")
	)
	(gr_poly
		(pts
			(xy 83.511136 -283.198316) (xy 83.41106 -283.09824) (xy 83.310984 -283.198316) (xy 83.310984 -283.242766)
			(xy 83.511136 -283.242766)
		)
		(stroke
			(width 0)
			(type solid)
		)
		(fill yes)
		(layer "In4.Cu")
		(net "M_D_CPU1_SB_DQ<13>")
	)
	(gr_poly
		(pts
			(xy 83.511136 -282.794456) (xy 83.511136 -282.750006) (xy 83.310984 -282.750006) (xy 83.310984 -282.794456)
			(xy 83.41106 -282.894532)
		)
		(stroke
			(width 0)
			(type solid)
		)
		(fill yes)
		(layer "In4.Cu")
		(net "M_D_CPU1_SB_DQ<14>")
	)
	(gr_poly
		(pts
			(xy 83.511136 -281.57805) (xy 83.41106 -281.478228) (xy 83.310984 -281.57805) (xy 83.310984 -281.625802)
			(xy 83.511136 -281.625802)
		)
		(stroke
			(width 0)
			(type solid)
		)
		(fill yes)
		(layer "In4.Cu")
		(net "M_D_CPU1_SB_DQS_DN<6>")
	)
	(gr_poly
		(pts
			(xy 83.511136 -281.174698) (xy 83.511136 -281.126946) (xy 83.310984 -281.126946) (xy 83.310984 -281.174698)
			(xy 83.41106 -281.27452)
		)
		(stroke
			(width 0)
			(type solid)
		)
		(fill yes)
		(layer "In4.Cu")
		(net "M_D_CPU1_SB_DQS_DN<1>")
	)
	(gr_poly
		(pts
			(xy 83.511136 -279.958292) (xy 83.41106 -279.858216) (xy 83.310984 -279.958292) (xy 83.310984 -280.002742)
			(xy 83.511136 -280.002742)
		)
		(stroke
			(width 0)
			(type solid)
		)
		(fill yes)
		(layer "In4.Cu")
		(net "M_D_CPU1_SB_DQ<9>")
	)
	(gr_poly
		(pts
			(xy 83.511136 -279.554432) (xy 83.511136 -279.509982) (xy 83.310984 -279.509982) (xy 83.310984 -279.554432)
			(xy 83.41106 -279.654508)
		)
		(stroke
			(width 0)
			(type solid)
		)
		(fill yes)
		(layer "In4.Cu")
		(net "M_D_CPU1_SB_DQ<10>")
	)
	(gr_poly
		(pts
			(xy 83.511136 -278.33828) (xy 83.41106 -278.238204) (xy 83.310984 -278.33828) (xy 83.310984 -278.38273)
			(xy 83.511136 -278.38273)
		)
		(stroke
			(width 0)
			(type solid)
		)
		(fill yes)
		(layer "In4.Cu")
		(net "M_D_CPU1_SB_DQ<5>")
	)
	(gr_poly
		(pts
			(xy 83.511136 -277.93442) (xy 83.511136 -277.88997) (xy 83.310984 -277.88997) (xy 83.310984 -277.93442)
			(xy 83.41106 -278.034496)
		)
		(stroke
			(width 0)
			(type solid)
		)
		(fill yes)
		(layer "In4.Cu")
		(net "M_D_CPU1_SB_DQ<6>")
	)
	(gr_poly
		(pts
			(xy 83.511136 -276.718014) (xy 83.41106 -276.618192) (xy 83.310984 -276.718014) (xy 83.310984 -276.765766)
			(xy 83.511136 -276.765766)
		)
		(stroke
			(width 0)
			(type solid)
		)
		(fill yes)
		(layer "In4.Cu")
		(net "M_D_CPU1_SB_DQS_DN<5>")
	)
	(gr_poly
		(pts
			(xy 83.511136 -276.314662) (xy 83.511136 -276.26691) (xy 83.310984 -276.26691) (xy 83.310984 -276.314662)
			(xy 83.41106 -276.414484)
		)
		(stroke
			(width 0)
			(type solid)
		)
		(fill yes)
		(layer "In4.Cu")
		(net "M_D_CPU1_SB_DQS_DN<0>")
	)
	(gr_poly
		(pts
			(xy 83.511136 -275.098256) (xy 83.41106 -274.99818) (xy 83.310984 -275.098256) (xy 83.310984 -275.142706)
			(xy 83.511136 -275.142706)
		)
		(stroke
			(width 0)
			(type solid)
		)
		(fill yes)
		(layer "In4.Cu")
		(net "M_D_CPU1_SB_DQ<1>")
	)
	(gr_poly
		(pts
			(xy 83.511136 -274.694396) (xy 83.511136 -274.649946) (xy 83.310984 -274.649946) (xy 83.310984 -274.694396)
			(xy 83.41106 -274.794472)
		)
		(stroke
			(width 0)
			(type solid)
		)
		(fill yes)
		(layer "In4.Cu")
		(net "M_D_CPU1_SB_DQ<2>")
	)
	(gr_poly
		(pts
			(xy 83.511136 -273.478244) (xy 83.41106 -273.378168) (xy 83.310984 -273.478244) (xy 83.310984 -273.522694)
			(xy 83.511136 -273.522694)
		)
		(stroke
			(width 0)
			(type solid)
		)
		(fill yes)
		(layer "In4.Cu")
		(net "M_D_CPU1_SB_CB<1>")
	)
	(gr_poly
		(pts
			(xy 83.511136 -273.074384) (xy 83.511136 -273.029934) (xy 83.310984 -273.029934) (xy 83.310984 -273.074384)
			(xy 83.41106 -273.17446)
		)
		(stroke
			(width 0)
			(type solid)
		)
		(fill yes)
		(layer "In4.Cu")
		(net "M_D_CPU1_SB_CB<2>")
	)
	(gr_poly
		(pts
			(xy 83.511136 -271.857978) (xy 83.41106 -271.758156) (xy 83.310984 -271.857978) (xy 83.310984 -271.90573)
			(xy 83.511136 -271.90573)
		)
		(stroke
			(width 0)
			(type solid)
		)
		(fill yes)
		(layer "In4.Cu")
		(net "M_D_CPU1_SB_DQS_DN<4>")
	)
	(gr_poly
		(pts
			(xy 83.511136 -271.454626) (xy 83.511136 -271.406874) (xy 83.310984 -271.406874) (xy 83.310984 -271.454626)
			(xy 83.41106 -271.554448)
		)
		(stroke
			(width 0)
			(type solid)
		)
		(fill yes)
		(layer "In4.Cu")
		(net "M_D_CPU1_SB_DQS_DN<9>")
	)
	(gr_poly
		(pts
			(xy 83.511136 -270.23822) (xy 83.41106 -270.138144) (xy 83.310984 -270.23822) (xy 83.310984 -270.28267)
			(xy 83.511136 -270.28267)
		)
		(stroke
			(width 0)
			(type solid)
		)
		(fill yes)
		(layer "In4.Cu")
		(net "M_D_CPU1_SB_CB<5>")
	)
	(gr_poly
		(pts
			(xy 83.511136 -269.83436) (xy 83.511136 -269.78991) (xy 83.310984 -269.78991) (xy 83.310984 -269.83436)
			(xy 83.41106 -269.934436)
		)
		(stroke
			(width 0)
			(type solid)
		)
		(fill yes)
		(layer "In4.Cu")
		(net "M_D_CPU1_SB_CB<6>")
	)
	(gr_poly
		(pts
			(xy 83.511136 -266.594336) (xy 83.511136 -266.549886) (xy 83.310984 -266.549886) (xy 83.310984 -266.594336)
			(xy 83.41106 -266.694412)
		)
		(stroke
			(width 0)
			(type solid)
		)
		(fill yes)
		(layer "In4.Cu")
		(net "M_D_CPU1_SB_CS_N<1>")
	)
	(gr_poly
		(pts
			(xy 83.511136 -264.974324) (xy 83.511136 -264.929874) (xy 83.310984 -264.929874) (xy 83.310984 -264.974324)
			(xy 83.41106 -265.0744)
		)
		(stroke
			(width 0)
			(type solid)
		)
		(fill yes)
		(layer "In4.Cu")
		(net "M_D_CPU1_SB_PAR")
	)
	(gr_poly
		(pts
			(xy 83.511136 -263.758172) (xy 83.41106 -263.658096) (xy 83.310984 -263.758172) (xy 83.310984 -263.802622)
			(xy 83.511136 -263.802622)
		)
		(stroke
			(width 0)
			(type solid)
		)
		(fill yes)
		(layer "In4.Cu")
		(net "M_D_CPU1_SB_CA<4>")
	)
	(gr_poly
		(pts
			(xy 83.511136 -263.354312) (xy 83.511136 -263.309862) (xy 83.310984 -263.309862) (xy 83.310984 -263.354312)
			(xy 83.41106 -263.454388)
		)
		(stroke
			(width 0)
			(type solid)
		)
		(fill yes)
		(layer "In4.Cu")
		(net "M_D_CPU1_SB_CA<3>")
	)
	(gr_poly
		(pts
			(xy 83.511136 -262.13816) (xy 83.41106 -262.038084) (xy 83.310984 -262.13816) (xy 83.310984 -262.18261)
			(xy 83.511136 -262.18261)
		)
		(stroke
			(width 0)
			(type solid)
		)
		(fill yes)
		(layer "In4.Cu")
		(net "M_D_CPU1_SB_CA<0>")
	)
	(gr_poly
		(pts
			(xy 83.681062 -256.432812) (xy 83.681062 -256.38506) (xy 83.48091 -256.38506) (xy 83.48091 -256.432812)
			(xy 83.580986 -256.532634)
		)
		(stroke
			(width 0)
			(type solid)
		)
		(fill yes)
		(layer "In4.Cu")
		(net "M_D_CPU1_CLK_DN<0>")
	)
	(gr_poly
		(pts
			(xy 83.681062 -255.216406) (xy 83.580986 -255.11633) (xy 83.48091 -255.216406) (xy 83.48091 -255.260856)
			(xy 83.681062 -255.260856)
		)
		(stroke
			(width 0)
			(type solid)
		)
		(fill yes)
		(layer "In4.Cu")
		(net "M_D_CPU1_SA_CA<6>")
	)
	(gr_poly
		(pts
			(xy 83.681062 -254.812546) (xy 83.681062 -254.768096) (xy 83.48091 -254.768096) (xy 83.48091 -254.812546)
			(xy 83.580986 -254.912622)
		)
		(stroke
			(width 0)
			(type solid)
		)
		(fill yes)
		(layer "In4.Cu")
		(net "M_D_CPU1_SA_CA<5>")
	)
	(gr_poly
		(pts
			(xy 83.681062 -253.596394) (xy 83.580986 -253.496318) (xy 83.48091 -253.596394) (xy 83.48091 -253.640844)
			(xy 83.681062 -253.640844)
		)
		(stroke
			(width 0)
			(type solid)
		)
		(fill yes)
		(layer "In4.Cu")
		(net "M_D_CPU1_SA_CA<2>")
	)
	(gr_poly
		(pts
			(xy 83.681062 -253.192534) (xy 83.681062 -253.148084) (xy 83.48091 -253.148084) (xy 83.48091 -253.192534)
			(xy 83.580986 -253.29261)
		)
		(stroke
			(width 0)
			(type solid)
		)
		(fill yes)
		(layer "In4.Cu")
		(net "M_D_CPU1_SA_CA<1>")
	)
	(gr_poly
		(pts
			(xy 83.681062 -251.572522) (xy 83.681062 -251.528072) (xy 83.48091 -251.528072) (xy 83.48091 -251.572522)
			(xy 83.580986 -251.672598)
		)
		(stroke
			(width 0)
			(type solid)
		)
		(fill yes)
		(layer "In4.Cu")
		(net "M_D_CPU1_SA_CS_N<0>")
	)
	(gr_poly
		(pts
			(xy 83.681062 -250.35637) (xy 83.580986 -250.256294) (xy 83.48091 -250.35637) (xy 83.48091 -250.40082)
			(xy 83.681062 -250.40082)
		)
		(stroke
			(width 0)
			(type solid)
		)
		(fill yes)
		(layer "In4.Cu")
		(net "M_D_CPU1_ALERT_R_N")
	)
	(gr_poly
		(pts
			(xy 83.681062 -248.736358) (xy 83.580986 -248.636282) (xy 83.48091 -248.736358) (xy 83.48091 -248.780808)
			(xy 83.681062 -248.780808)
		)
		(stroke
			(width 0)
			(type solid)
		)
		(fill yes)
		(layer "In4.Cu")
		(net "M_D_CPU1_SA_CB<5>")
	)
	(gr_poly
		(pts
			(xy 83.681062 -248.332498) (xy 83.681062 -248.288048) (xy 83.48091 -248.288048) (xy 83.48091 -248.332498)
			(xy 83.580986 -248.432574)
		)
		(stroke
			(width 0)
			(type solid)
		)
		(fill yes)
		(layer "In4.Cu")
		(net "M_D_CPU1_SA_CB<6>")
	)
	(gr_poly
		(pts
			(xy 83.681062 -247.116092) (xy 83.580986 -247.01627) (xy 83.48091 -247.116092) (xy 83.48091 -247.163844)
			(xy 83.681062 -247.163844)
		)
		(stroke
			(width 0)
			(type solid)
		)
		(fill yes)
		(layer "In4.Cu")
		(net "M_D_CPU1_SA_DQS_DN<9>")
	)
	(gr_poly
		(pts
			(xy 83.681062 -246.71274) (xy 83.681062 -246.664988) (xy 83.48091 -246.664988) (xy 83.48091 -246.71274)
			(xy 83.580986 -246.812562)
		)
		(stroke
			(width 0)
			(type solid)
		)
		(fill yes)
		(layer "In4.Cu")
		(net "M_D_CPU1_SA_DQS_DN<4>")
	)
	(gr_poly
		(pts
			(xy 83.681062 -245.496334) (xy 83.580986 -245.396258) (xy 83.48091 -245.496334) (xy 83.48091 -245.540784)
			(xy 83.681062 -245.540784)
		)
		(stroke
			(width 0)
			(type solid)
		)
		(fill yes)
		(layer "In4.Cu")
		(net "M_D_CPU1_SA_CB<1>")
	)
	(gr_poly
		(pts
			(xy 83.681062 -245.092474) (xy 83.681062 -245.048024) (xy 83.48091 -245.048024) (xy 83.48091 -245.092474)
			(xy 83.580986 -245.19255)
		)
		(stroke
			(width 0)
			(type solid)
		)
		(fill yes)
		(layer "In4.Cu")
		(net "M_D_CPU1_SA_CB<2>")
	)
	(gr_poly
		(pts
			(xy 83.681062 -243.876322) (xy 83.580986 -243.776246) (xy 83.48091 -243.876322) (xy 83.48091 -243.920772)
			(xy 83.681062 -243.920772)
		)
		(stroke
			(width 0)
			(type solid)
		)
		(fill yes)
		(layer "In4.Cu")
		(net "M_D_CPU1_SA_DQ<29>")
	)
	(gr_poly
		(pts
			(xy 83.681062 -243.472462) (xy 83.681062 -243.428012) (xy 83.48091 -243.428012) (xy 83.48091 -243.472462)
			(xy 83.580986 -243.572538)
		)
		(stroke
			(width 0)
			(type solid)
		)
		(fill yes)
		(layer "In4.Cu")
		(net "M_D_CPU1_SA_DQ<30>")
	)
	(gr_poly
		(pts
			(xy 83.681062 -242.256056) (xy 83.580986 -242.156234) (xy 83.48091 -242.256056) (xy 83.48091 -242.303808)
			(xy 83.681062 -242.303808)
		)
		(stroke
			(width 0)
			(type solid)
		)
		(fill yes)
		(layer "In4.Cu")
		(net "M_D_CPU1_SA_DQS_DN<8>")
	)
	(gr_poly
		(pts
			(xy 83.681062 -241.852704) (xy 83.681062 -241.804952) (xy 83.48091 -241.804952) (xy 83.48091 -241.852704)
			(xy 83.580986 -241.952526)
		)
		(stroke
			(width 0)
			(type solid)
		)
		(fill yes)
		(layer "In4.Cu")
		(net "M_D_CPU1_SA_DQS_DN<3>")
	)
	(gr_poly
		(pts
			(xy 83.681062 -240.636298) (xy 83.580986 -240.536222) (xy 83.48091 -240.636298) (xy 83.48091 -240.680748)
			(xy 83.681062 -240.680748)
		)
		(stroke
			(width 0)
			(type solid)
		)
		(fill yes)
		(layer "In4.Cu")
		(net "M_D_CPU1_SA_DQ<25>")
	)
	(gr_poly
		(pts
			(xy 83.681062 -240.232438) (xy 83.681062 -240.187988) (xy 83.48091 -240.187988) (xy 83.48091 -240.232438)
			(xy 83.580986 -240.332514)
		)
		(stroke
			(width 0)
			(type solid)
		)
		(fill yes)
		(layer "In4.Cu")
		(net "M_D_CPU1_SA_DQ<26>")
	)
	(gr_poly
		(pts
			(xy 83.681062 -239.016286) (xy 83.580986 -238.91621) (xy 83.48091 -239.016286) (xy 83.48091 -239.060736)
			(xy 83.681062 -239.060736)
		)
		(stroke
			(width 0)
			(type solid)
		)
		(fill yes)
		(layer "In4.Cu")
		(net "M_D_CPU1_SA_DQ<21>")
	)
	(gr_poly
		(pts
			(xy 83.681062 -238.612426) (xy 83.681062 -238.567976) (xy 83.48091 -238.567976) (xy 83.48091 -238.612426)
			(xy 83.580986 -238.712502)
		)
		(stroke
			(width 0)
			(type solid)
		)
		(fill yes)
		(layer "In4.Cu")
		(net "M_D_CPU1_SA_DQ<22>")
	)
	(gr_poly
		(pts
			(xy 83.681062 -237.39602) (xy 83.580986 -237.296198) (xy 83.48091 -237.39602) (xy 83.48091 -237.443772)
			(xy 83.681062 -237.443772)
		)
		(stroke
			(width 0)
			(type solid)
		)
		(fill yes)
		(layer "In4.Cu")
		(net "M_D_CPU1_SA_DQS_DN<7>")
	)
	(gr_poly
		(pts
			(xy 83.681062 -236.992668) (xy 83.681062 -236.944916) (xy 83.48091 -236.944916) (xy 83.48091 -236.992668)
			(xy 83.580986 -237.09249)
		)
		(stroke
			(width 0)
			(type solid)
		)
		(fill yes)
		(layer "In4.Cu")
		(net "M_D_CPU1_SA_DQS_DN<2>")
	)
	(gr_poly
		(pts
			(xy 83.681062 -235.776262) (xy 83.580986 -235.676186) (xy 83.48091 -235.776262) (xy 83.48091 -235.820712)
			(xy 83.681062 -235.820712)
		)
		(stroke
			(width 0)
			(type solid)
		)
		(fill yes)
		(layer "In4.Cu")
		(net "M_D_CPU1_SA_DQ<17>")
	)
	(gr_poly
		(pts
			(xy 83.681062 -235.372402) (xy 83.681062 -235.327952) (xy 83.48091 -235.327952) (xy 83.48091 -235.372402)
			(xy 83.580986 -235.472478)
		)
		(stroke
			(width 0)
			(type solid)
		)
		(fill yes)
		(layer "In4.Cu")
		(net "M_D_CPU1_SA_DQ<18>")
	)
	(gr_poly
		(pts
			(xy 83.681062 -234.15625) (xy 83.580986 -234.056174) (xy 83.48091 -234.15625) (xy 83.48091 -234.2007)
			(xy 83.681062 -234.2007)
		)
		(stroke
			(width 0)
			(type solid)
		)
		(fill yes)
		(layer "In4.Cu")
		(net "M_D_CPU1_SA_DQ<13>")
	)
	(gr_poly
		(pts
			(xy 83.681062 -233.75239) (xy 83.681062 -233.70794) (xy 83.48091 -233.70794) (xy 83.48091 -233.75239)
			(xy 83.580986 -233.852466)
		)
		(stroke
			(width 0)
			(type solid)
		)
		(fill yes)
		(layer "In4.Cu")
		(net "M_D_CPU1_SA_DQ<14>")
	)
	(gr_poly
		(pts
			(xy 83.681062 -232.535984) (xy 83.580986 -232.436162) (xy 83.48091 -232.535984) (xy 83.48091 -232.583736)
			(xy 83.681062 -232.583736)
		)
		(stroke
			(width 0)
			(type solid)
		)
		(fill yes)
		(layer "In4.Cu")
		(net "M_D_CPU1_SA_DQS_DN<6>")
	)
	(gr_poly
		(pts
			(xy 83.681062 -232.132632) (xy 83.681062 -232.08488) (xy 83.48091 -232.08488) (xy 83.48091 -232.132632)
			(xy 83.580986 -232.232454)
		)
		(stroke
			(width 0)
			(type solid)
		)
		(fill yes)
		(layer "In4.Cu")
		(net "M_D_CPU1_SA_DQS_DN<1>")
	)
	(gr_poly
		(pts
			(xy 83.681062 -230.916226) (xy 83.580986 -230.81615) (xy 83.48091 -230.916226) (xy 83.48091 -230.960676)
			(xy 83.681062 -230.960676)
		)
		(stroke
			(width 0)
			(type solid)
		)
		(fill yes)
		(layer "In4.Cu")
		(net "M_D_CPU1_SA_DQ<9>")
	)
	(gr_poly
		(pts
			(xy 83.681062 -230.51262) (xy 83.681062 -230.46817) (xy 83.48091 -230.46817) (xy 83.48091 -230.51262)
			(xy 83.580986 -230.612696)
		)
		(stroke
			(width 0)
			(type solid)
		)
		(fill yes)
		(layer "In4.Cu")
		(net "M_D_CPU1_SA_DQ<10>")
	)
	(gr_poly
		(pts
			(xy 83.681062 -229.296214) (xy 83.580986 -229.196138) (xy 83.48091 -229.296214) (xy 83.48091 -229.340664)
			(xy 83.681062 -229.340664)
		)
		(stroke
			(width 0)
			(type solid)
		)
		(fill yes)
		(layer "In4.Cu")
		(net "M_D_CPU1_SA_DQ<5>")
	)
	(gr_poly
		(pts
			(xy 83.681062 -228.892608) (xy 83.681062 -228.848158) (xy 83.48091 -228.848158) (xy 83.48091 -228.892608)
			(xy 83.580986 -228.992684)
		)
		(stroke
			(width 0)
			(type solid)
		)
		(fill yes)
		(layer "In4.Cu")
		(net "M_D_CPU1_SA_DQ<6>")
	)
	(gr_poly
		(pts
			(xy 83.681062 -227.27285) (xy 83.681062 -227.225098) (xy 83.48091 -227.225098) (xy 83.48091 -227.27285)
			(xy 83.580986 -227.372672)
		)
		(stroke
			(width 0)
			(type solid)
		)
		(fill yes)
		(layer "In4.Cu")
		(net "M_D_CPU1_SA_DQS_DN<0>")
	)
	(gr_poly
		(pts
			(xy 83.681062 -226.056444) (xy 83.580986 -225.956368) (xy 83.48091 -226.056444) (xy 83.48091 -226.100894)
			(xy 83.681062 -226.100894)
		)
		(stroke
			(width 0)
			(type solid)
		)
		(fill yes)
		(layer "In4.Cu")
		(net "M_D_CPU1_SA_DQ<1>")
	)
	(gr_poly
		(pts
			(xy 83.681062 -225.652584) (xy 83.681062 -225.608134) (xy 83.48091 -225.608134) (xy 83.48091 -225.652584)
			(xy 83.580986 -225.75266)
		)
		(stroke
			(width 0)
			(type solid)
		)
		(fill yes)
		(layer "In4.Cu")
		(net "M_D_CPU1_SA_DQ<2>")
	)
	(gr_poly
		(pts
			(xy 83.687158 -227.67671) (xy 83.587082 -227.576634) (xy 83.487006 -227.67671) (xy 83.487006 -227.724208)
			(xy 83.687158 -227.724208)
		)
		(stroke
			(width 0)
			(type solid)
		)
		(fill yes)
		(layer "In4.Cu")
		(net "M_D_CPU1_SA_DQS_DN<5>")
	)
	(gr_poly
		(pts
			(xy 83.981036 -293.32428) (xy 83.981036 -293.27983) (xy 83.780884 -293.27983) (xy 83.780884 -293.32428)
			(xy 83.88096 -293.424356)
		)
		(stroke
			(width 0)
			(type solid)
		)
		(fill yes)
		(layer "In4.Cu")
		(net "M_D_CPU1_SB_DQ<31>")
	)
	(gr_poly
		(pts
			(xy 83.981036 -292.108128) (xy 83.88096 -292.008052) (xy 83.780884 -292.108128) (xy 83.780884 -292.152578)
			(xy 83.981036 -292.152578)
		)
		(stroke
			(width 0)
			(type solid)
		)
		(fill yes)
		(layer "In4.Cu")
		(net "M_D_CPU1_SB_DQ<28>")
	)
	(gr_poly
		(pts
			(xy 83.981036 -291.704522) (xy 83.981036 -291.65677) (xy 83.780884 -291.65677) (xy 83.780884 -291.704522)
			(xy 83.88096 -291.804344)
		)
		(stroke
			(width 0)
			(type solid)
		)
		(fill yes)
		(layer "In4.Cu")
		(net "M_D_CPU1_SB_DQS_DP<8>")
	)
	(gr_poly
		(pts
			(xy 83.981036 -290.487862) (xy 83.88096 -290.38804) (xy 83.780884 -290.487862) (xy 83.780884 -290.535614)
			(xy 83.981036 -290.535614)
		)
		(stroke
			(width 0)
			(type solid)
		)
		(fill yes)
		(layer "In4.Cu")
		(net "M_D_CPU1_SB_DQS_DP<3>")
	)
	(gr_poly
		(pts
			(xy 83.981036 -290.084256) (xy 83.981036 -290.039806) (xy 83.780884 -290.039806) (xy 83.780884 -290.084256)
			(xy 83.88096 -290.184332)
		)
		(stroke
			(width 0)
			(type solid)
		)
		(fill yes)
		(layer "In4.Cu")
		(net "M_D_CPU1_SB_DQ<27>")
	)
	(gr_poly
		(pts
			(xy 83.981036 -288.868104) (xy 83.88096 -288.768028) (xy 83.780884 -288.868104) (xy 83.780884 -288.912554)
			(xy 83.981036 -288.912554)
		)
		(stroke
			(width 0)
			(type solid)
		)
		(fill yes)
		(layer "In4.Cu")
		(net "M_D_CPU1_SB_DQ<24>")
	)
	(gr_poly
		(pts
			(xy 83.981036 -288.464498) (xy 83.981036 -288.420048) (xy 83.780884 -288.420048) (xy 83.780884 -288.464498)
			(xy 83.88096 -288.564574)
		)
		(stroke
			(width 0)
			(type solid)
		)
		(fill yes)
		(layer "In4.Cu")
		(net "M_D_CPU1_SB_DQ<23>")
	)
	(gr_poly
		(pts
			(xy 83.981036 -287.248092) (xy 83.88096 -287.148016) (xy 83.780884 -287.248092) (xy 83.780884 -287.292542)
			(xy 83.981036 -287.292542)
		)
		(stroke
			(width 0)
			(type solid)
		)
		(fill yes)
		(layer "In4.Cu")
		(net "M_D_CPU1_SB_DQ<20>")
	)
	(gr_poly
		(pts
			(xy 83.981036 -286.844486) (xy 83.981036 -286.796734) (xy 83.780884 -286.796734) (xy 83.780884 -286.844486)
			(xy 83.88096 -286.944562)
		)
		(stroke
			(width 0)
			(type solid)
		)
		(fill yes)
		(layer "In4.Cu")
		(net "M_D_CPU1_SB_DQS_DP<7>")
	)
	(gr_poly
		(pts
			(xy 83.981036 -285.62808) (xy 83.88096 -285.528258) (xy 83.780884 -285.62808) (xy 83.780884 -285.675832)
			(xy 83.981036 -285.675832)
		)
		(stroke
			(width 0)
			(type solid)
		)
		(fill yes)
		(layer "In4.Cu")
		(net "M_D_CPU1_SB_DQS_DP<2>")
	)
	(gr_poly
		(pts
			(xy 83.981036 -285.224474) (xy 83.981036 -285.180024) (xy 83.780884 -285.180024) (xy 83.780884 -285.224474)
			(xy 83.88096 -285.32455)
		)
		(stroke
			(width 0)
			(type solid)
		)
		(fill yes)
		(layer "In4.Cu")
		(net "M_D_CPU1_SB_DQ<19>")
	)
	(gr_poly
		(pts
			(xy 83.981036 -284.008322) (xy 83.88096 -283.908246) (xy 83.780884 -284.008322) (xy 83.780884 -284.052772)
			(xy 83.981036 -284.052772)
		)
		(stroke
			(width 0)
			(type solid)
		)
		(fill yes)
		(layer "In4.Cu")
		(net "M_D_CPU1_SB_DQ<16>")
	)
	(gr_poly
		(pts
			(xy 83.981036 -283.604462) (xy 83.981036 -283.560012) (xy 83.780884 -283.560012) (xy 83.780884 -283.604462)
			(xy 83.88096 -283.704538)
		)
		(stroke
			(width 0)
			(type solid)
		)
		(fill yes)
		(layer "In4.Cu")
		(net "M_D_CPU1_SB_DQ<15>")
	)
	(gr_poly
		(pts
			(xy 83.981036 -282.38831) (xy 83.88096 -282.288234) (xy 83.780884 -282.38831) (xy 83.780884 -282.43276)
			(xy 83.981036 -282.43276)
		)
		(stroke
			(width 0)
			(type solid)
		)
		(fill yes)
		(layer "In4.Cu")
		(net "M_D_CPU1_SB_DQ<12>")
	)
	(gr_poly
		(pts
			(xy 83.981036 -281.984704) (xy 83.981036 -281.936952) (xy 83.780884 -281.936952) (xy 83.780884 -281.984704)
			(xy 83.88096 -282.084526)
		)
		(stroke
			(width 0)
			(type solid)
		)
		(fill yes)
		(layer "In4.Cu")
		(net "M_D_CPU1_SB_DQS_DP<6>")
	)
	(gr_poly
		(pts
			(xy 83.981036 -280.768044) (xy 83.88096 -280.668222) (xy 83.780884 -280.768044) (xy 83.780884 -280.815796)
			(xy 83.981036 -280.815796)
		)
		(stroke
			(width 0)
			(type solid)
		)
		(fill yes)
		(layer "In4.Cu")
		(net "M_D_CPU1_SB_DQS_DP<1>")
	)
	(gr_poly
		(pts
			(xy 83.981036 -280.364438) (xy 83.981036 -280.319988) (xy 83.780884 -280.319988) (xy 83.780884 -280.364438)
			(xy 83.88096 -280.464514)
		)
		(stroke
			(width 0)
			(type solid)
		)
		(fill yes)
		(layer "In4.Cu")
		(net "M_D_CPU1_SB_DQ<11>")
	)
	(gr_poly
		(pts
			(xy 83.981036 -279.148286) (xy 83.88096 -279.04821) (xy 83.780884 -279.148286) (xy 83.780884 -279.192736)
			(xy 83.981036 -279.192736)
		)
		(stroke
			(width 0)
			(type solid)
		)
		(fill yes)
		(layer "In4.Cu")
		(net "M_D_CPU1_SB_DQ<8>")
	)
	(gr_poly
		(pts
			(xy 83.981036 -278.744426) (xy 83.981036 -278.699976) (xy 83.780884 -278.699976) (xy 83.780884 -278.744426)
			(xy 83.88096 -278.844502)
		)
		(stroke
			(width 0)
			(type solid)
		)
		(fill yes)
		(layer "In4.Cu")
		(net "M_D_CPU1_SB_DQ<7>")
	)
	(gr_poly
		(pts
			(xy 83.981036 -277.528274) (xy 83.88096 -277.428198) (xy 83.780884 -277.528274) (xy 83.780884 -277.572724)
			(xy 83.981036 -277.572724)
		)
		(stroke
			(width 0)
			(type solid)
		)
		(fill yes)
		(layer "In4.Cu")
		(net "M_D_CPU1_SB_DQ<4>")
	)
	(gr_poly
		(pts
			(xy 83.981036 -275.504402) (xy 83.981036 -275.459952) (xy 83.780884 -275.459952) (xy 83.780884 -275.504402)
			(xy 83.88096 -275.604478)
		)
		(stroke
			(width 0)
			(type solid)
		)
		(fill yes)
		(layer "In4.Cu")
		(net "M_D_CPU1_SB_DQ<3>")
	)
	(gr_poly
		(pts
			(xy 83.981036 -274.28825) (xy 83.88096 -274.188174) (xy 83.780884 -274.28825) (xy 83.780884 -274.3327)
			(xy 83.981036 -274.3327)
		)
		(stroke
			(width 0)
			(type solid)
		)
		(fill yes)
		(layer "In4.Cu")
		(net "M_D_CPU1_SB_DQ<0>")
	)
	(gr_poly
		(pts
			(xy 83.981036 -273.88439) (xy 83.981036 -273.83994) (xy 83.780884 -273.83994) (xy 83.780884 -273.88439)
			(xy 83.88096 -273.984466)
		)
		(stroke
			(width 0)
			(type solid)
		)
		(fill yes)
		(layer "In4.Cu")
		(net "M_D_CPU1_SB_CB<3>")
	)
	(gr_poly
		(pts
			(xy 83.981036 -272.668238) (xy 83.88096 -272.568162) (xy 83.780884 -272.668238) (xy 83.780884 -272.712688)
			(xy 83.981036 -272.712688)
		)
		(stroke
			(width 0)
			(type solid)
		)
		(fill yes)
		(layer "In4.Cu")
		(net "M_D_CPU1_SB_CB<0>")
	)
	(gr_poly
		(pts
			(xy 83.981036 -272.264632) (xy 83.981036 -272.21688) (xy 83.780884 -272.21688) (xy 83.780884 -272.264632)
			(xy 83.88096 -272.364454)
		)
		(stroke
			(width 0)
			(type solid)
		)
		(fill yes)
		(layer "In4.Cu")
		(net "M_D_CPU1_SB_DQS_DP<4>")
	)
	(gr_poly
		(pts
			(xy 83.981036 -271.047972) (xy 83.88096 -270.94815) (xy 83.780884 -271.047972) (xy 83.780884 -271.095724)
			(xy 83.981036 -271.095724)
		)
		(stroke
			(width 0)
			(type solid)
		)
		(fill yes)
		(layer "In4.Cu")
		(net "M_D_CPU1_SB_DQS_DP<9>")
	)
	(gr_poly
		(pts
			(xy 83.981036 -270.644366) (xy 83.981036 -270.599916) (xy 83.780884 -270.599916) (xy 83.780884 -270.644366)
			(xy 83.88096 -270.744442)
		)
		(stroke
			(width 0)
			(type solid)
		)
		(fill yes)
		(layer "In4.Cu")
		(net "M_D_CPU1_SB_CB<7>")
	)
	(gr_poly
		(pts
			(xy 83.981036 -269.428214) (xy 83.88096 -269.328138) (xy 83.780884 -269.428214) (xy 83.780884 -269.472664)
			(xy 83.981036 -269.472664)
		)
		(stroke
			(width 0)
			(type solid)
		)
		(fill yes)
		(layer "In4.Cu")
		(net "M_D_CPU1_SB_CB<4>")
	)
	(gr_poly
		(pts
			(xy 83.981036 -265.78433) (xy 83.981036 -265.73988) (xy 83.780884 -265.73988) (xy 83.780884 -265.78433)
			(xy 83.88096 -265.884406)
		)
		(stroke
			(width 0)
			(type solid)
		)
		(fill yes)
		(layer "In4.Cu")
		(net "M_D_CPU1_SB_CS_N<0>")
	)
	(gr_poly
		(pts
			(xy 83.981036 -264.568178) (xy 83.88096 -264.468102) (xy 83.780884 -264.568178) (xy 83.780884 -264.612628)
			(xy 83.981036 -264.612628)
		)
		(stroke
			(width 0)
			(type solid)
		)
		(fill yes)
		(layer "In4.Cu")
		(net "M_D_CPU1_SB_CA<6>")
	)
	(gr_poly
		(pts
			(xy 83.981036 -264.164318) (xy 83.981036 -264.119868) (xy 83.780884 -264.119868) (xy 83.780884 -264.164318)
			(xy 83.88096 -264.264394)
		)
		(stroke
			(width 0)
			(type solid)
		)
		(fill yes)
		(layer "In4.Cu")
		(net "M_D_CPU1_SB_CA<5>")
	)
	(gr_poly
		(pts
			(xy 83.981036 -262.948166) (xy 83.88096 -262.84809) (xy 83.780884 -262.948166) (xy 83.780884 -262.992616)
			(xy 83.981036 -262.992616)
		)
		(stroke
			(width 0)
			(type solid)
		)
		(fill yes)
		(layer "In4.Cu")
		(net "M_D_CPU1_SB_CA<2>")
	)
	(gr_poly
		(pts
			(xy 83.981036 -262.544306) (xy 83.981036 -262.499856) (xy 83.780884 -262.499856) (xy 83.780884 -262.544306)
			(xy 83.88096 -262.644382)
		)
		(stroke
			(width 0)
			(type solid)
		)
		(fill yes)
		(layer "In4.Cu")
		(net "M_D_CPU1_SB_CA<1>")
	)
	(gr_poly
		(pts
			(xy 83.987132 -267.801852) (xy 83.88731 -267.701776) (xy 83.787234 -267.801852) (xy 83.787234 -267.846302)
			(xy 83.987132 -267.846302)
		)
		(stroke
			(width 0)
			(type solid)
		)
		(fill yes)
		(layer "In4.Cu")
		(net "M_D_CPU1_SB_RSP<0>")
	)
	(gr_poly
		(pts
			(xy 83.988402 -277.124414) (xy 83.988402 -277.076916) (xy 83.78825 -277.076916) (xy 83.78825 -277.124414)
			(xy 83.888326 -277.22449)
		)
		(stroke
			(width 0)
			(type solid)
		)
		(fill yes)
		(layer "In4.Cu")
		(net "M_D_CPU1_SB_DQS_DP<5>")
	)
	(gr_poly
		(pts
			(xy 83.988402 -275.908262) (xy 83.888326 -275.808186) (xy 83.78825 -275.908262) (xy 83.78825 -275.95576)
			(xy 83.988402 -275.95576)
		)
		(stroke
			(width 0)
			(type solid)
		)
		(fill yes)
		(layer "In4.Cu")
		(net "M_D_CPU1_SB_DQS_DP<0>")
	)
	(gr_poly
		(pts
			(xy 84.151216 -256.026158) (xy 84.05114 -255.926336) (xy 83.951064 -256.026158) (xy 83.951064 -256.07391)
			(xy 84.151216 -256.07391)
		)
		(stroke
			(width 0)
			(type solid)
		)
		(fill yes)
		(layer "In4.Cu")
		(net "M_D_CPU1_CLK_DP<0>")
	)
	(gr_poly
		(pts
			(xy 84.151216 -255.622552) (xy 84.151216 -255.578102) (xy 83.951064 -255.578102) (xy 83.951064 -255.622552)
			(xy 84.05114 -255.722628)
		)
		(stroke
			(width 0)
			(type solid)
		)
		(fill yes)
		(layer "In4.Cu")
		(net "M_D_CPU1_SA_PAR")
	)
	(gr_poly
		(pts
			(xy 84.151216 -254.4064) (xy 84.05114 -254.306324) (xy 83.951064 -254.4064) (xy 83.951064 -254.45085)
			(xy 84.151216 -254.45085)
		)
		(stroke
			(width 0)
			(type solid)
		)
		(fill yes)
		(layer "In4.Cu")
		(net "M_D_CPU1_SA_CA<4>")
	)
	(gr_poly
		(pts
			(xy 84.151216 -254.00254) (xy 84.151216 -253.95809) (xy 83.951064 -253.95809) (xy 83.951064 -254.00254)
			(xy 84.05114 -254.102616)
		)
		(stroke
			(width 0)
			(type solid)
		)
		(fill yes)
		(layer "In4.Cu")
		(net "M_D_CPU1_SA_CA<3>")
	)
	(gr_poly
		(pts
			(xy 84.151216 -252.786388) (xy 84.05114 -252.686312) (xy 83.951064 -252.786388) (xy 83.951064 -252.830838)
			(xy 84.151216 -252.830838)
		)
		(stroke
			(width 0)
			(type solid)
		)
		(fill yes)
		(layer "In4.Cu")
		(net "M_D_CPU1_SA_CA<0>")
	)
	(gr_poly
		(pts
			(xy 84.151216 -252.382528) (xy 84.151216 -252.338078) (xy 83.951064 -252.338078) (xy 83.951064 -252.382528)
			(xy 84.05114 -252.482604)
		)
		(stroke
			(width 0)
			(type solid)
		)
		(fill yes)
		(layer "In4.Cu")
		(net "M_D_CPU1_SA_CS_N<1>")
	)
	(gr_poly
		(pts
			(xy 84.151216 -250.762516) (xy 84.151216 -250.718066) (xy 83.951064 -250.718066) (xy 83.951064 -250.762516)
			(xy 84.05114 -250.862592)
		)
		(stroke
			(width 0)
			(type solid)
		)
		(fill yes)
		(layer "In4.Cu")
		(net "M_D_CPU1_RESET_N")
	)
	(gr_poly
		(pts
			(xy 84.151216 -249.142504) (xy 84.151216 -249.098054) (xy 83.951064 -249.098054) (xy 83.951064 -249.142504)
			(xy 84.05114 -249.24258)
		)
		(stroke
			(width 0)
			(type solid)
		)
		(fill yes)
		(layer "In4.Cu")
		(net "M_D_CPU1_SA_CB<7>")
	)
	(gr_poly
		(pts
			(xy 84.151216 -247.926352) (xy 84.05114 -247.826276) (xy 83.951064 -247.926352) (xy 83.951064 -247.970802)
			(xy 84.151216 -247.970802)
		)
		(stroke
			(width 0)
			(type solid)
		)
		(fill yes)
		(layer "In4.Cu")
		(net "M_D_CPU1_SA_CB<4>")
	)
	(gr_poly
		(pts
			(xy 84.151216 -247.522746) (xy 84.151216 -247.474994) (xy 83.951064 -247.474994) (xy 83.951064 -247.522746)
			(xy 84.05114 -247.622568)
		)
		(stroke
			(width 0)
			(type solid)
		)
		(fill yes)
		(layer "In4.Cu")
		(net "M_D_CPU1_SA_DQS_DP<9>")
	)
	(gr_poly
		(pts
			(xy 84.151216 -246.306086) (xy 84.05114 -246.206264) (xy 83.951064 -246.306086) (xy 83.951064 -246.353838)
			(xy 84.151216 -246.353838)
		)
		(stroke
			(width 0)
			(type solid)
		)
		(fill yes)
		(layer "In4.Cu")
		(net "M_D_CPU1_SA_DQS_DP<4>")
	)
	(gr_poly
		(pts
			(xy 84.151216 -245.90248) (xy 84.151216 -245.85803) (xy 83.951064 -245.85803) (xy 83.951064 -245.90248)
			(xy 84.05114 -246.002556)
		)
		(stroke
			(width 0)
			(type solid)
		)
		(fill yes)
		(layer "In4.Cu")
		(net "M_D_CPU1_SA_CB<3>")
	)
	(gr_poly
		(pts
			(xy 84.151216 -244.686328) (xy 84.05114 -244.586252) (xy 83.951064 -244.686328) (xy 83.951064 -244.730778)
			(xy 84.151216 -244.730778)
		)
		(stroke
			(width 0)
			(type solid)
		)
		(fill yes)
		(layer "In4.Cu")
		(net "M_D_CPU1_SA_CB<0>")
	)
	(gr_poly
		(pts
			(xy 84.151216 -244.282468) (xy 84.151216 -244.238018) (xy 83.951064 -244.238018) (xy 83.951064 -244.282468)
			(xy 84.05114 -244.382544)
		)
		(stroke
			(width 0)
			(type solid)
		)
		(fill yes)
		(layer "In4.Cu")
		(net "M_D_CPU1_SA_DQ<31>")
	)
	(gr_poly
		(pts
			(xy 84.151216 -243.066316) (xy 84.05114 -242.96624) (xy 83.951064 -243.066316) (xy 83.951064 -243.110766)
			(xy 84.151216 -243.110766)
		)
		(stroke
			(width 0)
			(type solid)
		)
		(fill yes)
		(layer "In4.Cu")
		(net "M_D_CPU1_SA_DQ<28>")
	)
	(gr_poly
		(pts
			(xy 84.151216 -242.66271) (xy 84.151216 -242.614958) (xy 83.951064 -242.614958) (xy 83.951064 -242.66271)
			(xy 84.05114 -242.762532)
		)
		(stroke
			(width 0)
			(type solid)
		)
		(fill yes)
		(layer "In4.Cu")
		(net "M_D_CPU1_SA_DQS_DP<8>")
	)
	(gr_poly
		(pts
			(xy 84.151216 -241.44605) (xy 84.05114 -241.346228) (xy 83.951064 -241.44605) (xy 83.951064 -241.493802)
			(xy 84.151216 -241.493802)
		)
		(stroke
			(width 0)
			(type solid)
		)
		(fill yes)
		(layer "In4.Cu")
		(net "M_D_CPU1_SA_DQS_DP<3>")
	)
	(gr_poly
		(pts
			(xy 84.151216 -241.042444) (xy 84.151216 -240.997994) (xy 83.951064 -240.997994) (xy 83.951064 -241.042444)
			(xy 84.05114 -241.14252)
		)
		(stroke
			(width 0)
			(type solid)
		)
		(fill yes)
		(layer "In4.Cu")
		(net "M_D_CPU1_SA_DQ<27>")
	)
	(gr_poly
		(pts
			(xy 84.151216 -239.826292) (xy 84.05114 -239.726216) (xy 83.951064 -239.826292) (xy 83.951064 -239.870742)
			(xy 84.151216 -239.870742)
		)
		(stroke
			(width 0)
			(type solid)
		)
		(fill yes)
		(layer "In4.Cu")
		(net "M_D_CPU1_SA_DQ<24>")
	)
	(gr_poly
		(pts
			(xy 84.151216 -239.422432) (xy 84.151216 -239.377982) (xy 83.951064 -239.377982) (xy 83.951064 -239.422432)
			(xy 84.05114 -239.522508)
		)
		(stroke
			(width 0)
			(type solid)
		)
		(fill yes)
		(layer "In4.Cu")
		(net "M_D_CPU1_SA_DQ<23>")
	)
	(gr_poly
		(pts
			(xy 84.151216 -238.20628) (xy 84.05114 -238.106204) (xy 83.951064 -238.20628) (xy 83.951064 -238.25073)
			(xy 84.151216 -238.25073)
		)
		(stroke
			(width 0)
			(type solid)
		)
		(fill yes)
		(layer "In4.Cu")
		(net "M_D_CPU1_SA_DQ<20>")
	)
	(gr_poly
		(pts
			(xy 84.151216 -237.802674) (xy 84.151216 -237.754922) (xy 83.951064 -237.754922) (xy 83.951064 -237.802674)
			(xy 84.05114 -237.902496)
		)
		(stroke
			(width 0)
			(type solid)
		)
		(fill yes)
		(layer "In4.Cu")
		(net "M_D_CPU1_SA_DQS_DP<7>")
	)
	(gr_poly
		(pts
			(xy 84.151216 -236.586014) (xy 84.05114 -236.486192) (xy 83.951064 -236.586014) (xy 83.951064 -236.633766)
			(xy 84.151216 -236.633766)
		)
		(stroke
			(width 0)
			(type solid)
		)
		(fill yes)
		(layer "In4.Cu")
		(net "M_D_CPU1_SA_DQS_DP<2>")
	)
	(gr_poly
		(pts
			(xy 84.151216 -236.182408) (xy 84.151216 -236.137958) (xy 83.951064 -236.137958) (xy 83.951064 -236.182408)
			(xy 84.05114 -236.282484)
		)
		(stroke
			(width 0)
			(type solid)
		)
		(fill yes)
		(layer "In4.Cu")
		(net "M_D_CPU1_SA_DQ<19>")
	)
	(gr_poly
		(pts
			(xy 84.151216 -234.966256) (xy 84.05114 -234.86618) (xy 83.951064 -234.966256) (xy 83.951064 -235.010706)
			(xy 84.151216 -235.010706)
		)
		(stroke
			(width 0)
			(type solid)
		)
		(fill yes)
		(layer "In4.Cu")
		(net "M_D_CPU1_SA_DQ<16>")
	)
	(gr_poly
		(pts
			(xy 84.151216 -234.562396) (xy 84.151216 -234.517946) (xy 83.951064 -234.517946) (xy 83.951064 -234.562396)
			(xy 84.05114 -234.662472)
		)
		(stroke
			(width 0)
			(type solid)
		)
		(fill yes)
		(layer "In4.Cu")
		(net "M_D_CPU1_SA_DQ<15>")
	)
	(gr_poly
		(pts
			(xy 84.151216 -233.346244) (xy 84.05114 -233.246168) (xy 83.951064 -233.346244) (xy 83.951064 -233.390694)
			(xy 84.151216 -233.390694)
		)
		(stroke
			(width 0)
			(type solid)
		)
		(fill yes)
		(layer "In4.Cu")
		(net "M_D_CPU1_SA_DQ<12>")
	)
	(gr_poly
		(pts
			(xy 84.151216 -232.942638) (xy 84.151216 -232.894886) (xy 83.951064 -232.894886) (xy 83.951064 -232.942638)
			(xy 84.05114 -233.04246)
		)
		(stroke
			(width 0)
			(type solid)
		)
		(fill yes)
		(layer "In4.Cu")
		(net "M_D_CPU1_SA_DQS_DP<6>")
	)
	(gr_poly
		(pts
			(xy 84.151216 -231.725978) (xy 84.05114 -231.626156) (xy 83.951064 -231.725978) (xy 83.951064 -231.77373)
			(xy 84.151216 -231.77373)
		)
		(stroke
			(width 0)
			(type solid)
		)
		(fill yes)
		(layer "In4.Cu")
		(net "M_D_CPU1_SA_DQS_DP<1>")
	)
	(gr_poly
		(pts
			(xy 84.151216 -231.322626) (xy 84.151216 -231.278176) (xy 83.951064 -231.278176) (xy 83.951064 -231.322626)
			(xy 84.05114 -231.422702)
		)
		(stroke
			(width 0)
			(type solid)
		)
		(fill yes)
		(layer "In4.Cu")
		(net "M_D_CPU1_SA_DQ<11>")
	)
	(gr_poly
		(pts
			(xy 84.151216 -230.10622) (xy 84.05114 -230.006144) (xy 83.951064 -230.10622) (xy 83.951064 -230.15067)
			(xy 84.151216 -230.15067)
		)
		(stroke
			(width 0)
			(type solid)
		)
		(fill yes)
		(layer "In4.Cu")
		(net "M_D_CPU1_SA_DQ<8>")
	)
	(gr_poly
		(pts
			(xy 84.151216 -229.702614) (xy 84.151216 -229.658164) (xy 83.951064 -229.658164) (xy 83.951064 -229.702614)
			(xy 84.05114 -229.80269)
		)
		(stroke
			(width 0)
			(type solid)
		)
		(fill yes)
		(layer "In4.Cu")
		(net "M_D_CPU1_SA_DQ<7>")
	)
	(gr_poly
		(pts
			(xy 84.151216 -228.486462) (xy 84.05114 -228.386386) (xy 83.951064 -228.486462) (xy 83.951064 -228.530912)
			(xy 84.151216 -228.530912)
		)
		(stroke
			(width 0)
			(type solid)
		)
		(fill yes)
		(layer "In4.Cu")
		(net "M_D_CPU1_SA_DQ<4>")
	)
	(gr_poly
		(pts
			(xy 84.151216 -228.082856) (xy 84.151216 -228.035104) (xy 83.951064 -228.035104) (xy 83.951064 -228.082856)
			(xy 84.05114 -228.182678)
		)
		(stroke
			(width 0)
			(type solid)
		)
		(fill yes)
		(layer "In4.Cu")
		(net "M_D_CPU1_SA_DQS_DP<5>")
	)
	(gr_poly
		(pts
			(xy 84.151216 -226.866196) (xy 84.05114 -226.766374) (xy 83.951064 -226.866196) (xy 83.951064 -226.913948)
			(xy 84.151216 -226.913948)
		)
		(stroke
			(width 0)
			(type solid)
		)
		(fill yes)
		(layer "In4.Cu")
		(net "M_D_CPU1_SA_DQS_DP<0>")
	)
	(gr_poly
		(pts
			(xy 84.151216 -226.46259) (xy 84.151216 -226.41814) (xy 83.951064 -226.41814) (xy 83.951064 -226.46259)
			(xy 84.05114 -226.562666)
		)
		(stroke
			(width 0)
			(type solid)
		)
		(fill yes)
		(layer "In4.Cu")
		(net "M_D_CPU1_SA_DQ<3>")
	)
	(gr_poly
		(pts
			(xy 84.151216 -225.246438) (xy 84.05114 -225.146362) (xy 83.951064 -225.246438) (xy 83.951064 -225.290888)
			(xy 84.151216 -225.290888)
		)
		(stroke
			(width 0)
			(type solid)
		)
		(fill yes)
		(layer "In4.Cu")
		(net "M_D_CPU1_SA_DQ<0>")
	)
	(gr_poly
		(pts
			(xy 84.44484 -266.991846) (xy 84.344764 -266.89177) (xy 84.244942 -266.991846) (xy 84.244942 -267.036296)
			(xy 84.44484 -267.036296)
		)
		(stroke
			(width 0)
			(type solid)
		)
		(fill yes)
		(layer "In4.Cu")
		(net "M_D_CPU1_SA_RSP<0>")
	)
	(gr_poly
		(pts
			(xy 84.45119 -292.918134) (xy 84.351114 -292.818058) (xy 84.251038 -292.918134) (xy 84.251038 -292.962584)
			(xy 84.45119 -292.962584)
		)
		(stroke
			(width 0)
			(type solid)
		)
		(fill yes)
		(layer "In4.Cu")
		(net "M_D_CPU1_SB_DQ<29>")
	)
	(gr_poly
		(pts
			(xy 84.45119 -292.514274) (xy 84.45119 -292.469824) (xy 84.251038 -292.469824) (xy 84.251038 -292.514274)
			(xy 84.351114 -292.61435)
		)
		(stroke
			(width 0)
			(type solid)
		)
		(fill yes)
		(layer "In4.Cu")
		(net "M_D_CPU1_SB_DQ<30>")
	)
	(gr_poly
		(pts
			(xy 84.45119 -291.297868) (xy 84.351114 -291.198046) (xy 84.251038 -291.297868) (xy 84.251038 -291.34562)
			(xy 84.45119 -291.34562)
		)
		(stroke
			(width 0)
			(type solid)
		)
		(fill yes)
		(layer "In4.Cu")
		(net "M_D_CPU1_SB_DQS_DN<8>")
	)
	(gr_poly
		(pts
			(xy 84.45119 -290.894516) (xy 84.45119 -290.846764) (xy 84.251038 -290.846764) (xy 84.251038 -290.894516)
			(xy 84.351114 -290.994338)
		)
		(stroke
			(width 0)
			(type solid)
		)
		(fill yes)
		(layer "In4.Cu")
		(net "M_D_CPU1_SB_DQS_DN<3>")
	)
	(gr_poly
		(pts
			(xy 84.45119 -289.67811) (xy 84.351114 -289.578034) (xy 84.251038 -289.67811) (xy 84.251038 -289.72256)
			(xy 84.45119 -289.72256)
		)
		(stroke
			(width 0)
			(type solid)
		)
		(fill yes)
		(layer "In4.Cu")
		(net "M_D_CPU1_SB_DQ<25>")
	)
	(gr_poly
		(pts
			(xy 84.45119 -289.27425) (xy 84.45119 -289.2298) (xy 84.251038 -289.2298) (xy 84.251038 -289.27425)
			(xy 84.351114 -289.374326)
		)
		(stroke
			(width 0)
			(type solid)
		)
		(fill yes)
		(layer "In4.Cu")
		(net "M_D_CPU1_SB_DQ<26>")
	)
	(gr_poly
		(pts
			(xy 84.45119 -288.058098) (xy 84.351114 -287.958022) (xy 84.251038 -288.058098) (xy 84.251038 -288.102548)
			(xy 84.45119 -288.102548)
		)
		(stroke
			(width 0)
			(type solid)
		)
		(fill yes)
		(layer "In4.Cu")
		(net "M_D_CPU1_SB_DQ<21>")
	)
	(gr_poly
		(pts
			(xy 84.45119 -287.654492) (xy 84.45119 -287.610042) (xy 84.251038 -287.610042) (xy 84.251038 -287.654492)
			(xy 84.351114 -287.754568)
		)
		(stroke
			(width 0)
			(type solid)
		)
		(fill yes)
		(layer "In4.Cu")
		(net "M_D_CPU1_SB_DQ<22>")
	)
	(gr_poly
		(pts
			(xy 84.45119 -286.438086) (xy 84.351114 -286.33801) (xy 84.251038 -286.438086) (xy 84.251038 -286.485838)
			(xy 84.45119 -286.485838)
		)
		(stroke
			(width 0)
			(type solid)
		)
		(fill yes)
		(layer "In4.Cu")
		(net "M_D_CPU1_SB_DQS_DN<7>")
	)
	(gr_poly
		(pts
			(xy 84.45119 -286.034734) (xy 84.45119 -285.986982) (xy 84.251038 -285.986982) (xy 84.251038 -286.034734)
			(xy 84.351114 -286.134556)
		)
		(stroke
			(width 0)
			(type solid)
		)
		(fill yes)
		(layer "In4.Cu")
		(net "M_D_CPU1_SB_DQS_DN<2>")
	)
	(gr_poly
		(pts
			(xy 84.45119 -284.818328) (xy 84.351114 -284.718252) (xy 84.251038 -284.818328) (xy 84.251038 -284.862778)
			(xy 84.45119 -284.862778)
		)
		(stroke
			(width 0)
			(type solid)
		)
		(fill yes)
		(layer "In4.Cu")
		(net "M_D_CPU1_SB_DQ<17>")
	)
	(gr_poly
		(pts
			(xy 84.45119 -284.414468) (xy 84.45119 -284.370018) (xy 84.251038 -284.370018) (xy 84.251038 -284.414468)
			(xy 84.351114 -284.514544)
		)
		(stroke
			(width 0)
			(type solid)
		)
		(fill yes)
		(layer "In4.Cu")
		(net "M_D_CPU1_SB_DQ<18>")
	)
	(gr_poly
		(pts
			(xy 84.45119 -283.198316) (xy 84.351114 -283.09824) (xy 84.251038 -283.198316) (xy 84.251038 -283.242766)
			(xy 84.45119 -283.242766)
		)
		(stroke
			(width 0)
			(type solid)
		)
		(fill yes)
		(layer "In4.Cu")
		(net "M_D_CPU1_SB_DQ<13>")
	)
	(gr_poly
		(pts
			(xy 84.45119 -282.794456) (xy 84.45119 -282.750006) (xy 84.251038 -282.750006) (xy 84.251038 -282.794456)
			(xy 84.351114 -282.894532)
		)
		(stroke
			(width 0)
			(type solid)
		)
		(fill yes)
		(layer "In4.Cu")
		(net "M_D_CPU1_SB_DQ<14>")
	)
	(gr_poly
		(pts
			(xy 84.45119 -281.57805) (xy 84.351114 -281.478228) (xy 84.251038 -281.57805) (xy 84.251038 -281.625802)
			(xy 84.45119 -281.625802)
		)
		(stroke
			(width 0)
			(type solid)
		)
		(fill yes)
		(layer "In4.Cu")
		(net "M_D_CPU1_SB_DQS_DN<6>")
	)
	(gr_poly
		(pts
			(xy 84.45119 -281.174698) (xy 84.45119 -281.126946) (xy 84.251038 -281.126946) (xy 84.251038 -281.174698)
			(xy 84.351114 -281.27452)
		)
		(stroke
			(width 0)
			(type solid)
		)
		(fill yes)
		(layer "In4.Cu")
		(net "M_D_CPU1_SB_DQS_DN<1>")
	)
	(gr_poly
		(pts
			(xy 84.45119 -279.958292) (xy 84.351114 -279.858216) (xy 84.251038 -279.958292) (xy 84.251038 -280.002742)
			(xy 84.45119 -280.002742)
		)
		(stroke
			(width 0)
			(type solid)
		)
		(fill yes)
		(layer "In4.Cu")
		(net "M_D_CPU1_SB_DQ<9>")
	)
	(gr_poly
		(pts
			(xy 84.45119 -279.554432) (xy 84.45119 -279.509982) (xy 84.251038 -279.509982) (xy 84.251038 -279.554432)
			(xy 84.351114 -279.654508)
		)
		(stroke
			(width 0)
			(type solid)
		)
		(fill yes)
		(layer "In4.Cu")
		(net "M_D_CPU1_SB_DQ<10>")
	)
	(gr_poly
		(pts
			(xy 84.45119 -278.33828) (xy 84.351114 -278.238204) (xy 84.251038 -278.33828) (xy 84.251038 -278.38273)
			(xy 84.45119 -278.38273)
		)
		(stroke
			(width 0)
			(type solid)
		)
		(fill yes)
		(layer "In4.Cu")
		(net "M_D_CPU1_SB_DQ<5>")
	)
	(gr_poly
		(pts
			(xy 84.45119 -277.93442) (xy 84.45119 -277.88997) (xy 84.251038 -277.88997) (xy 84.251038 -277.93442)
			(xy 84.351114 -278.034496)
		)
		(stroke
			(width 0)
			(type solid)
		)
		(fill yes)
		(layer "In4.Cu")
		(net "M_D_CPU1_SB_DQ<6>")
	)
	(gr_poly
		(pts
			(xy 84.45119 -276.718014) (xy 84.351114 -276.618192) (xy 84.251038 -276.718014) (xy 84.251038 -276.765766)
			(xy 84.45119 -276.765766)
		)
		(stroke
			(width 0)
			(type solid)
		)
		(fill yes)
		(layer "In4.Cu")
		(net "M_D_CPU1_SB_DQS_DN<5>")
	)
	(gr_poly
		(pts
			(xy 84.45119 -276.314662) (xy 84.45119 -276.26691) (xy 84.251038 -276.26691) (xy 84.251038 -276.314662)
			(xy 84.351114 -276.414484)
		)
		(stroke
			(width 0)
			(type solid)
		)
		(fill yes)
		(layer "In4.Cu")
		(net "M_D_CPU1_SB_DQS_DN<0>")
	)
	(gr_poly
		(pts
			(xy 84.45119 -275.098256) (xy 84.351114 -274.99818) (xy 84.251038 -275.098256) (xy 84.251038 -275.142706)
			(xy 84.45119 -275.142706)
		)
		(stroke
			(width 0)
			(type solid)
		)
		(fill yes)
		(layer "In4.Cu")
		(net "M_D_CPU1_SB_DQ<1>")
	)
	(gr_poly
		(pts
			(xy 84.45119 -274.694396) (xy 84.45119 -274.649946) (xy 84.251038 -274.649946) (xy 84.251038 -274.694396)
			(xy 84.351114 -274.794472)
		)
		(stroke
			(width 0)
			(type solid)
		)
		(fill yes)
		(layer "In4.Cu")
		(net "M_D_CPU1_SB_DQ<2>")
	)
	(gr_poly
		(pts
			(xy 84.45119 -273.478244) (xy 84.351114 -273.378168) (xy 84.251038 -273.478244) (xy 84.251038 -273.522694)
			(xy 84.45119 -273.522694)
		)
		(stroke
			(width 0)
			(type solid)
		)
		(fill yes)
		(layer "In4.Cu")
		(net "M_D_CPU1_SB_CB<1>")
	)
	(gr_poly
		(pts
			(xy 84.45119 -273.074384) (xy 84.45119 -273.029934) (xy 84.251038 -273.029934) (xy 84.251038 -273.074384)
			(xy 84.351114 -273.17446)
		)
		(stroke
			(width 0)
			(type solid)
		)
		(fill yes)
		(layer "In4.Cu")
		(net "M_D_CPU1_SB_CB<2>")
	)
	(gr_poly
		(pts
			(xy 84.45119 -271.857978) (xy 84.351114 -271.758156) (xy 84.251038 -271.857978) (xy 84.251038 -271.90573)
			(xy 84.45119 -271.90573)
		)
		(stroke
			(width 0)
			(type solid)
		)
		(fill yes)
		(layer "In4.Cu")
		(net "M_D_CPU1_SB_DQS_DN<4>")
	)
	(gr_poly
		(pts
			(xy 84.45119 -271.454626) (xy 84.45119 -271.406874) (xy 84.251038 -271.406874) (xy 84.251038 -271.454626)
			(xy 84.351114 -271.554448)
		)
		(stroke
			(width 0)
			(type solid)
		)
		(fill yes)
		(layer "In4.Cu")
		(net "M_D_CPU1_SB_DQS_DN<9>")
	)
	(gr_poly
		(pts
			(xy 84.45119 -270.23822) (xy 84.351114 -270.138144) (xy 84.251038 -270.23822) (xy 84.251038 -270.28267)
			(xy 84.45119 -270.28267)
		)
		(stroke
			(width 0)
			(type solid)
		)
		(fill yes)
		(layer "In4.Cu")
		(net "M_D_CPU1_SB_CB<5>")
	)
	(gr_poly
		(pts
			(xy 84.45119 -269.83436) (xy 84.45119 -269.78991) (xy 84.251038 -269.78991) (xy 84.251038 -269.83436)
			(xy 84.351114 -269.934436)
		)
		(stroke
			(width 0)
			(type solid)
		)
		(fill yes)
		(layer "In4.Cu")
		(net "M_D_CPU1_SB_CB<6>")
	)
	(gr_poly
		(pts
			(xy 84.45119 -266.594336) (xy 84.45119 -266.549886) (xy 84.251038 -266.549886) (xy 84.251038 -266.594336)
			(xy 84.351114 -266.694412)
		)
		(stroke
			(width 0)
			(type solid)
		)
		(fill yes)
		(layer "In4.Cu")
		(net "M_D_CPU1_SB_CS_N<1>")
	)
	(gr_poly
		(pts
			(xy 84.45119 -264.974324) (xy 84.45119 -264.929874) (xy 84.251038 -264.929874) (xy 84.251038 -264.974324)
			(xy 84.351114 -265.0744)
		)
		(stroke
			(width 0)
			(type solid)
		)
		(fill yes)
		(layer "In4.Cu")
		(net "M_D_CPU1_SB_PAR")
	)
	(gr_poly
		(pts
			(xy 84.45119 -263.758172) (xy 84.351114 -263.658096) (xy 84.251038 -263.758172) (xy 84.251038 -263.802622)
			(xy 84.45119 -263.802622)
		)
		(stroke
			(width 0)
			(type solid)
		)
		(fill yes)
		(layer "In4.Cu")
		(net "M_D_CPU1_SB_CA<4>")
	)
	(gr_poly
		(pts
			(xy 84.45119 -263.354312) (xy 84.45119 -263.309862) (xy 84.251038 -263.309862) (xy 84.251038 -263.354312)
			(xy 84.351114 -263.454388)
		)
		(stroke
			(width 0)
			(type solid)
		)
		(fill yes)
		(layer "In4.Cu")
		(net "M_D_CPU1_SB_CA<3>")
	)
	(gr_poly
		(pts
			(xy 84.45119 -262.13816) (xy 84.351114 -262.038084) (xy 84.251038 -262.13816) (xy 84.251038 -262.18261)
			(xy 84.45119 -262.18261)
		)
		(stroke
			(width 0)
			(type solid)
		)
		(fill yes)
		(layer "In4.Cu")
		(net "M_D_CPU1_SB_CA<0>")
	)
	(gr_poly
		(pts
			(xy 84.621116 -256.432812) (xy 84.621116 -256.38506) (xy 84.420964 -256.38506) (xy 84.420964 -256.432812)
			(xy 84.52104 -256.532634)
		)
		(stroke
			(width 0)
			(type solid)
		)
		(fill yes)
		(layer "In4.Cu")
		(net "M_D_CPU1_CLK_DN<0>")
	)
	(gr_poly
		(pts
			(xy 84.621116 -255.216406) (xy 84.52104 -255.11633) (xy 84.420964 -255.216406) (xy 84.420964 -255.260856)
			(xy 84.621116 -255.260856)
		)
		(stroke
			(width 0)
			(type solid)
		)
		(fill yes)
		(layer "In4.Cu")
		(net "M_D_CPU1_SA_CA<6>")
	)
	(gr_poly
		(pts
			(xy 84.621116 -254.812546) (xy 84.621116 -254.768096) (xy 84.420964 -254.768096) (xy 84.420964 -254.812546)
			(xy 84.52104 -254.912622)
		)
		(stroke
			(width 0)
			(type solid)
		)
		(fill yes)
		(layer "In4.Cu")
		(net "M_D_CPU1_SA_CA<5>")
	)
	(gr_poly
		(pts
			(xy 84.621116 -253.596394) (xy 84.52104 -253.496318) (xy 84.420964 -253.596394) (xy 84.420964 -253.640844)
			(xy 84.621116 -253.640844)
		)
		(stroke
			(width 0)
			(type solid)
		)
		(fill yes)
		(layer "In4.Cu")
		(net "M_D_CPU1_SA_CA<2>")
	)
	(gr_poly
		(pts
			(xy 84.621116 -253.192534) (xy 84.621116 -253.148084) (xy 84.420964 -253.148084) (xy 84.420964 -253.192534)
			(xy 84.52104 -253.29261)
		)
		(stroke
			(width 0)
			(type solid)
		)
		(fill yes)
		(layer "In4.Cu")
		(net "M_D_CPU1_SA_CA<1>")
	)
	(gr_poly
		(pts
			(xy 84.621116 -251.572522) (xy 84.621116 -251.528072) (xy 84.420964 -251.528072) (xy 84.420964 -251.572522)
			(xy 84.52104 -251.672598)
		)
		(stroke
			(width 0)
			(type solid)
		)
		(fill yes)
		(layer "In4.Cu")
		(net "M_D_CPU1_SA_CS_N<0>")
	)
	(gr_poly
		(pts
			(xy 84.621116 -250.35637) (xy 84.52104 -250.256294) (xy 84.420964 -250.35637) (xy 84.420964 -250.40082)
			(xy 84.621116 -250.40082)
		)
		(stroke
			(width 0)
			(type solid)
		)
		(fill yes)
		(layer "In4.Cu")
		(net "M_D_CPU1_ALERT_R_N")
	)
	(gr_poly
		(pts
			(xy 84.621116 -248.736358) (xy 84.52104 -248.636282) (xy 84.420964 -248.736358) (xy 84.420964 -248.780808)
			(xy 84.621116 -248.780808)
		)
		(stroke
			(width 0)
			(type solid)
		)
		(fill yes)
		(layer "In4.Cu")
		(net "M_D_CPU1_SA_CB<5>")
	)
	(gr_poly
		(pts
			(xy 84.621116 -248.332498) (xy 84.621116 -248.288048) (xy 84.420964 -248.288048) (xy 84.420964 -248.332498)
			(xy 84.52104 -248.432574)
		)
		(stroke
			(width 0)
			(type solid)
		)
		(fill yes)
		(layer "In4.Cu")
		(net "M_D_CPU1_SA_CB<6>")
	)
	(gr_poly
		(pts
			(xy 84.621116 -247.116092) (xy 84.52104 -247.01627) (xy 84.420964 -247.116092) (xy 84.420964 -247.163844)
			(xy 84.621116 -247.163844)
		)
		(stroke
			(width 0)
			(type solid)
		)
		(fill yes)
		(layer "In4.Cu")
		(net "M_D_CPU1_SA_DQS_DN<9>")
	)
	(gr_poly
		(pts
			(xy 84.621116 -246.71274) (xy 84.621116 -246.664988) (xy 84.420964 -246.664988) (xy 84.420964 -246.71274)
			(xy 84.52104 -246.812562)
		)
		(stroke
			(width 0)
			(type solid)
		)
		(fill yes)
		(layer "In4.Cu")
		(net "M_D_CPU1_SA_DQS_DN<4>")
	)
	(gr_poly
		(pts
			(xy 84.621116 -245.496334) (xy 84.52104 -245.396258) (xy 84.420964 -245.496334) (xy 84.420964 -245.540784)
			(xy 84.621116 -245.540784)
		)
		(stroke
			(width 0)
			(type solid)
		)
		(fill yes)
		(layer "In4.Cu")
		(net "M_D_CPU1_SA_CB<1>")
	)
	(gr_poly
		(pts
			(xy 84.621116 -245.092474) (xy 84.621116 -245.048024) (xy 84.420964 -245.048024) (xy 84.420964 -245.092474)
			(xy 84.52104 -245.19255)
		)
		(stroke
			(width 0)
			(type solid)
		)
		(fill yes)
		(layer "In4.Cu")
		(net "M_D_CPU1_SA_CB<2>")
	)
	(gr_poly
		(pts
			(xy 84.621116 -243.876322) (xy 84.52104 -243.776246) (xy 84.420964 -243.876322) (xy 84.420964 -243.920772)
			(xy 84.621116 -243.920772)
		)
		(stroke
			(width 0)
			(type solid)
		)
		(fill yes)
		(layer "In4.Cu")
		(net "M_D_CPU1_SA_DQ<29>")
	)
	(gr_poly
		(pts
			(xy 84.621116 -243.472462) (xy 84.621116 -243.428012) (xy 84.420964 -243.428012) (xy 84.420964 -243.472462)
			(xy 84.52104 -243.572538)
		)
		(stroke
			(width 0)
			(type solid)
		)
		(fill yes)
		(layer "In4.Cu")
		(net "M_D_CPU1_SA_DQ<30>")
	)
	(gr_poly
		(pts
			(xy 84.621116 -242.256056) (xy 84.52104 -242.156234) (xy 84.420964 -242.256056) (xy 84.420964 -242.303808)
			(xy 84.621116 -242.303808)
		)
		(stroke
			(width 0)
			(type solid)
		)
		(fill yes)
		(layer "In4.Cu")
		(net "M_D_CPU1_SA_DQS_DN<8>")
	)
	(gr_poly
		(pts
			(xy 84.621116 -241.852704) (xy 84.621116 -241.804952) (xy 84.420964 -241.804952) (xy 84.420964 -241.852704)
			(xy 84.52104 -241.952526)
		)
		(stroke
			(width 0)
			(type solid)
		)
		(fill yes)
		(layer "In4.Cu")
		(net "M_D_CPU1_SA_DQS_DN<3>")
	)
	(gr_poly
		(pts
			(xy 84.621116 -240.636298) (xy 84.52104 -240.536222) (xy 84.420964 -240.636298) (xy 84.420964 -240.680748)
			(xy 84.621116 -240.680748)
		)
		(stroke
			(width 0)
			(type solid)
		)
		(fill yes)
		(layer "In4.Cu")
		(net "M_D_CPU1_SA_DQ<25>")
	)
	(gr_poly
		(pts
			(xy 84.621116 -240.232438) (xy 84.621116 -240.187988) (xy 84.420964 -240.187988) (xy 84.420964 -240.232438)
			(xy 84.52104 -240.332514)
		)
		(stroke
			(width 0)
			(type solid)
		)
		(fill yes)
		(layer "In4.Cu")
		(net "M_D_CPU1_SA_DQ<26>")
	)
	(gr_poly
		(pts
			(xy 84.621116 -239.016286) (xy 84.52104 -238.91621) (xy 84.420964 -239.016286) (xy 84.420964 -239.060736)
			(xy 84.621116 -239.060736)
		)
		(stroke
			(width 0)
			(type solid)
		)
		(fill yes)
		(layer "In4.Cu")
		(net "M_D_CPU1_SA_DQ<21>")
	)
	(gr_poly
		(pts
			(xy 84.621116 -238.612426) (xy 84.621116 -238.567976) (xy 84.420964 -238.567976) (xy 84.420964 -238.612426)
			(xy 84.52104 -238.712502)
		)
		(stroke
			(width 0)
			(type solid)
		)
		(fill yes)
		(layer "In4.Cu")
		(net "M_D_CPU1_SA_DQ<22>")
	)
	(gr_poly
		(pts
			(xy 84.621116 -237.39602) (xy 84.52104 -237.296198) (xy 84.420964 -237.39602) (xy 84.420964 -237.443772)
			(xy 84.621116 -237.443772)
		)
		(stroke
			(width 0)
			(type solid)
		)
		(fill yes)
		(layer "In4.Cu")
		(net "M_D_CPU1_SA_DQS_DN<7>")
	)
	(gr_poly
		(pts
			(xy 84.621116 -236.992668) (xy 84.621116 -236.944916) (xy 84.420964 -236.944916) (xy 84.420964 -236.992668)
			(xy 84.52104 -237.09249)
		)
		(stroke
			(width 0)
			(type solid)
		)
		(fill yes)
		(layer "In4.Cu")
		(net "M_D_CPU1_SA_DQS_DN<2>")
	)
	(gr_poly
		(pts
			(xy 84.621116 -235.776262) (xy 84.52104 -235.676186) (xy 84.420964 -235.776262) (xy 84.420964 -235.820712)
			(xy 84.621116 -235.820712)
		)
		(stroke
			(width 0)
			(type solid)
		)
		(fill yes)
		(layer "In4.Cu")
		(net "M_D_CPU1_SA_DQ<17>")
	)
	(gr_poly
		(pts
			(xy 84.621116 -235.372402) (xy 84.621116 -235.327952) (xy 84.420964 -235.327952) (xy 84.420964 -235.372402)
			(xy 84.52104 -235.472478)
		)
		(stroke
			(width 0)
			(type solid)
		)
		(fill yes)
		(layer "In4.Cu")
		(net "M_D_CPU1_SA_DQ<18>")
	)
	(gr_poly
		(pts
			(xy 84.621116 -234.15625) (xy 84.52104 -234.056174) (xy 84.420964 -234.15625) (xy 84.420964 -234.2007)
			(xy 84.621116 -234.2007)
		)
		(stroke
			(width 0)
			(type solid)
		)
		(fill yes)
		(layer "In4.Cu")
		(net "M_D_CPU1_SA_DQ<13>")
	)
	(gr_poly
		(pts
			(xy 84.621116 -233.75239) (xy 84.621116 -233.70794) (xy 84.420964 -233.70794) (xy 84.420964 -233.75239)
			(xy 84.52104 -233.852466)
		)
		(stroke
			(width 0)
			(type solid)
		)
		(fill yes)
		(layer "In4.Cu")
		(net "M_D_CPU1_SA_DQ<14>")
	)
	(gr_poly
		(pts
			(xy 84.621116 -232.535984) (xy 84.52104 -232.436162) (xy 84.420964 -232.535984) (xy 84.420964 -232.583736)
			(xy 84.621116 -232.583736)
		)
		(stroke
			(width 0)
			(type solid)
		)
		(fill yes)
		(layer "In4.Cu")
		(net "M_D_CPU1_SA_DQS_DN<6>")
	)
	(gr_poly
		(pts
			(xy 84.621116 -232.132632) (xy 84.621116 -232.08488) (xy 84.420964 -232.08488) (xy 84.420964 -232.132632)
			(xy 84.52104 -232.232454)
		)
		(stroke
			(width 0)
			(type solid)
		)
		(fill yes)
		(layer "In4.Cu")
		(net "M_D_CPU1_SA_DQS_DN<1>")
	)
	(gr_poly
		(pts
			(xy 84.621116 -230.916226) (xy 84.52104 -230.81615) (xy 84.420964 -230.916226) (xy 84.420964 -230.960676)
			(xy 84.621116 -230.960676)
		)
		(stroke
			(width 0)
			(type solid)
		)
		(fill yes)
		(layer "In4.Cu")
		(net "M_D_CPU1_SA_DQ<9>")
	)
	(gr_poly
		(pts
			(xy 84.621116 -230.51262) (xy 84.621116 -230.46817) (xy 84.420964 -230.46817) (xy 84.420964 -230.51262)
			(xy 84.52104 -230.612696)
		)
		(stroke
			(width 0)
			(type solid)
		)
		(fill yes)
		(layer "In4.Cu")
		(net "M_D_CPU1_SA_DQ<10>")
	)
	(gr_poly
		(pts
			(xy 84.621116 -229.296214) (xy 84.52104 -229.196138) (xy 84.420964 -229.296214) (xy 84.420964 -229.340664)
			(xy 84.621116 -229.340664)
		)
		(stroke
			(width 0)
			(type solid)
		)
		(fill yes)
		(layer "In4.Cu")
		(net "M_D_CPU1_SA_DQ<5>")
	)
	(gr_poly
		(pts
			(xy 84.621116 -228.892608) (xy 84.621116 -228.848158) (xy 84.420964 -228.848158) (xy 84.420964 -228.892608)
			(xy 84.52104 -228.992684)
		)
		(stroke
			(width 0)
			(type solid)
		)
		(fill yes)
		(layer "In4.Cu")
		(net "M_D_CPU1_SA_DQ<6>")
	)
	(gr_poly
		(pts
			(xy 84.621116 -227.67671) (xy 84.52104 -227.576634) (xy 84.420964 -227.67671) (xy 84.420964 -227.724462)
			(xy 84.621116 -227.724462)
		)
		(stroke
			(width 0)
			(type solid)
		)
		(fill yes)
		(layer "In4.Cu")
		(net "M_D_CPU1_SA_DQS_DN<5>")
	)
	(gr_poly
		(pts
			(xy 84.621116 -227.27285) (xy 84.621116 -227.225098) (xy 84.420964 -227.225098) (xy 84.420964 -227.27285)
			(xy 84.52104 -227.372672)
		)
		(stroke
			(width 0)
			(type solid)
		)
		(fill yes)
		(layer "In4.Cu")
		(net "M_D_CPU1_SA_DQS_DN<0>")
	)
	(gr_poly
		(pts
			(xy 84.621116 -226.056444) (xy 84.52104 -225.956368) (xy 84.420964 -226.056444) (xy 84.420964 -226.100894)
			(xy 84.621116 -226.100894)
		)
		(stroke
			(width 0)
			(type solid)
		)
		(fill yes)
		(layer "In4.Cu")
		(net "M_D_CPU1_SA_DQ<1>")
	)
	(gr_poly
		(pts
			(xy 84.621116 -225.652584) (xy 84.621116 -225.608134) (xy 84.420964 -225.608134) (xy 84.420964 -225.652584)
			(xy 84.52104 -225.75266)
		)
		(stroke
			(width 0)
			(type solid)
		)
		(fill yes)
		(layer "In4.Cu")
		(net "M_D_CPU1_SA_DQ<2>")
	)
	(gr_poly
		(pts
			(xy 84.92109 -293.32428) (xy 84.92109 -293.27983) (xy 84.720938 -293.27983) (xy 84.720938 -293.32428)
			(xy 84.821014 -293.424356)
		)
		(stroke
			(width 0)
			(type solid)
		)
		(fill yes)
		(layer "In4.Cu")
		(net "M_D_CPU1_SB_DQ<31>")
	)
	(gr_poly
		(pts
			(xy 84.92109 -292.108128) (xy 84.821014 -292.008052) (xy 84.720938 -292.108128) (xy 84.720938 -292.152578)
			(xy 84.92109 -292.152578)
		)
		(stroke
			(width 0)
			(type solid)
		)
		(fill yes)
		(layer "In4.Cu")
		(net "M_D_CPU1_SB_DQ<28>")
	)
	(gr_poly
		(pts
			(xy 84.92109 -291.704522) (xy 84.92109 -291.65677) (xy 84.720938 -291.65677) (xy 84.720938 -291.704522)
			(xy 84.821014 -291.804344)
		)
		(stroke
			(width 0)
			(type solid)
		)
		(fill yes)
		(layer "In4.Cu")
		(net "M_D_CPU1_SB_DQS_DP<8>")
	)
	(gr_poly
		(pts
			(xy 84.92109 -290.487862) (xy 84.821014 -290.38804) (xy 84.720938 -290.487862) (xy 84.720938 -290.535614)
			(xy 84.92109 -290.535614)
		)
		(stroke
			(width 0)
			(type solid)
		)
		(fill yes)
		(layer "In4.Cu")
		(net "M_D_CPU1_SB_DQS_DP<3>")
	)
	(gr_poly
		(pts
			(xy 84.92109 -290.084256) (xy 84.92109 -290.039806) (xy 84.720938 -290.039806) (xy 84.720938 -290.084256)
			(xy 84.821014 -290.184332)
		)
		(stroke
			(width 0)
			(type solid)
		)
		(fill yes)
		(layer "In4.Cu")
		(net "M_D_CPU1_SB_DQ<27>")
	)
	(gr_poly
		(pts
			(xy 84.92109 -288.868104) (xy 84.821014 -288.768028) (xy 84.720938 -288.868104) (xy 84.720938 -288.912554)
			(xy 84.92109 -288.912554)
		)
		(stroke
			(width 0)
			(type solid)
		)
		(fill yes)
		(layer "In4.Cu")
		(net "M_D_CPU1_SB_DQ<24>")
	)
	(gr_poly
		(pts
			(xy 84.92109 -288.464498) (xy 84.92109 -288.420048) (xy 84.720938 -288.420048) (xy 84.720938 -288.464498)
			(xy 84.821014 -288.564574)
		)
		(stroke
			(width 0)
			(type solid)
		)
		(fill yes)
		(layer "In4.Cu")
		(net "M_D_CPU1_SB_DQ<23>")
	)
	(gr_poly
		(pts
			(xy 84.92109 -287.248092) (xy 84.821014 -287.148016) (xy 84.720938 -287.248092) (xy 84.720938 -287.292542)
			(xy 84.92109 -287.292542)
		)
		(stroke
			(width 0)
			(type solid)
		)
		(fill yes)
		(layer "In4.Cu")
		(net "M_D_CPU1_SB_DQ<20>")
	)
	(gr_poly
		(pts
			(xy 84.92109 -286.844486) (xy 84.92109 -286.796734) (xy 84.720938 -286.796734) (xy 84.720938 -286.844486)
			(xy 84.821014 -286.944562)
		)
		(stroke
			(width 0)
			(type solid)
		)
		(fill yes)
		(layer "In4.Cu")
		(net "M_D_CPU1_SB_DQS_DP<7>")
	)
	(gr_poly
		(pts
			(xy 84.92109 -285.62808) (xy 84.821014 -285.528258) (xy 84.720938 -285.62808) (xy 84.720938 -285.675832)
			(xy 84.92109 -285.675832)
		)
		(stroke
			(width 0)
			(type solid)
		)
		(fill yes)
		(layer "In4.Cu")
		(net "M_D_CPU1_SB_DQS_DP<2>")
	)
	(gr_poly
		(pts
			(xy 84.92109 -285.224474) (xy 84.92109 -285.180024) (xy 84.720938 -285.180024) (xy 84.720938 -285.224474)
			(xy 84.821014 -285.32455)
		)
		(stroke
			(width 0)
			(type solid)
		)
		(fill yes)
		(layer "In4.Cu")
		(net "M_D_CPU1_SB_DQ<19>")
	)
	(gr_poly
		(pts
			(xy 84.92109 -284.008322) (xy 84.821014 -283.908246) (xy 84.720938 -284.008322) (xy 84.720938 -284.052772)
			(xy 84.92109 -284.052772)
		)
		(stroke
			(width 0)
			(type solid)
		)
		(fill yes)
		(layer "In4.Cu")
		(net "M_D_CPU1_SB_DQ<16>")
	)
	(gr_poly
		(pts
			(xy 84.92109 -283.604462) (xy 84.92109 -283.560012) (xy 84.720938 -283.560012) (xy 84.720938 -283.604462)
			(xy 84.821014 -283.704538)
		)
		(stroke
			(width 0)
			(type solid)
		)
		(fill yes)
		(layer "In4.Cu")
		(net "M_D_CPU1_SB_DQ<15>")
	)
	(gr_poly
		(pts
			(xy 84.92109 -282.38831) (xy 84.821014 -282.288234) (xy 84.720938 -282.38831) (xy 84.720938 -282.43276)
			(xy 84.92109 -282.43276)
		)
		(stroke
			(width 0)
			(type solid)
		)
		(fill yes)
		(layer "In4.Cu")
		(net "M_D_CPU1_SB_DQ<12>")
	)
	(gr_poly
		(pts
			(xy 84.92109 -281.984704) (xy 84.92109 -281.936952) (xy 84.720938 -281.936952) (xy 84.720938 -281.984704)
			(xy 84.821014 -282.084526)
		)
		(stroke
			(width 0)
			(type solid)
		)
		(fill yes)
		(layer "In4.Cu")
		(net "M_D_CPU1_SB_DQS_DP<6>")
	)
	(gr_poly
		(pts
			(xy 84.92109 -280.768044) (xy 84.821014 -280.668222) (xy 84.720938 -280.768044) (xy 84.720938 -280.815796)
			(xy 84.92109 -280.815796)
		)
		(stroke
			(width 0)
			(type solid)
		)
		(fill yes)
		(layer "In4.Cu")
		(net "M_D_CPU1_SB_DQS_DP<1>")
	)
	(gr_poly
		(pts
			(xy 84.92109 -280.364438) (xy 84.92109 -280.319988) (xy 84.720938 -280.319988) (xy 84.720938 -280.364438)
			(xy 84.821014 -280.464514)
		)
		(stroke
			(width 0)
			(type solid)
		)
		(fill yes)
		(layer "In4.Cu")
		(net "M_D_CPU1_SB_DQ<11>")
	)
	(gr_poly
		(pts
			(xy 84.92109 -279.148286) (xy 84.821014 -279.04821) (xy 84.720938 -279.148286) (xy 84.720938 -279.192736)
			(xy 84.92109 -279.192736)
		)
		(stroke
			(width 0)
			(type solid)
		)
		(fill yes)
		(layer "In4.Cu")
		(net "M_D_CPU1_SB_DQ<8>")
	)
	(gr_poly
		(pts
			(xy 84.92109 -278.744426) (xy 84.92109 -278.699976) (xy 84.720938 -278.699976) (xy 84.720938 -278.744426)
			(xy 84.821014 -278.844502)
		)
		(stroke
			(width 0)
			(type solid)
		)
		(fill yes)
		(layer "In4.Cu")
		(net "M_D_CPU1_SB_DQ<7>")
	)
	(gr_poly
		(pts
			(xy 84.92109 -277.528274) (xy 84.821014 -277.428198) (xy 84.720938 -277.528274) (xy 84.720938 -277.572724)
			(xy 84.92109 -277.572724)
		)
		(stroke
			(width 0)
			(type solid)
		)
		(fill yes)
		(layer "In4.Cu")
		(net "M_D_CPU1_SB_DQ<4>")
	)
	(gr_poly
		(pts
			(xy 84.92109 -277.124668) (xy 84.92109 -277.076916) (xy 84.720938 -277.076916) (xy 84.720938 -277.124668)
			(xy 84.821014 -277.22449)
		)
		(stroke
			(width 0)
			(type solid)
		)
		(fill yes)
		(layer "In4.Cu")
		(net "M_D_CPU1_SB_DQS_DP<5>")
	)
	(gr_poly
		(pts
			(xy 84.92109 -275.908008) (xy 84.821014 -275.808186) (xy 84.720938 -275.908008) (xy 84.720938 -275.95576)
			(xy 84.92109 -275.95576)
		)
		(stroke
			(width 0)
			(type solid)
		)
		(fill yes)
		(layer "In4.Cu")
		(net "M_D_CPU1_SB_DQS_DP<0>")
	)
	(gr_poly
		(pts
			(xy 84.92109 -275.504402) (xy 84.92109 -275.459952) (xy 84.720938 -275.459952) (xy 84.720938 -275.504402)
			(xy 84.821014 -275.604478)
		)
		(stroke
			(width 0)
			(type solid)
		)
		(fill yes)
		(layer "In4.Cu")
		(net "M_D_CPU1_SB_DQ<3>")
	)
	(gr_poly
		(pts
			(xy 84.92109 -274.28825) (xy 84.821014 -274.188174) (xy 84.720938 -274.28825) (xy 84.720938 -274.3327)
			(xy 84.92109 -274.3327)
		)
		(stroke
			(width 0)
			(type solid)
		)
		(fill yes)
		(layer "In4.Cu")
		(net "M_D_CPU1_SB_DQ<0>")
	)
	(gr_poly
		(pts
			(xy 84.92109 -273.88439) (xy 84.92109 -273.83994) (xy 84.720938 -273.83994) (xy 84.720938 -273.88439)
			(xy 84.821014 -273.984466)
		)
		(stroke
			(width 0)
			(type solid)
		)
		(fill yes)
		(layer "In4.Cu")
		(net "M_D_CPU1_SB_CB<3>")
	)
	(gr_poly
		(pts
			(xy 84.92109 -272.668238) (xy 84.821014 -272.568162) (xy 84.720938 -272.668238) (xy 84.720938 -272.712688)
			(xy 84.92109 -272.712688)
		)
		(stroke
			(width 0)
			(type solid)
		)
		(fill yes)
		(layer "In4.Cu")
		(net "M_D_CPU1_SB_CB<0>")
	)
	(gr_poly
		(pts
			(xy 84.92109 -272.264632) (xy 84.92109 -272.21688) (xy 84.720938 -272.21688) (xy 84.720938 -272.264632)
			(xy 84.821014 -272.364454)
		)
		(stroke
			(width 0)
			(type solid)
		)
		(fill yes)
		(layer "In4.Cu")
		(net "M_D_CPU1_SB_DQS_DP<4>")
	)
	(gr_poly
		(pts
			(xy 84.92109 -271.047972) (xy 84.821014 -270.94815) (xy 84.720938 -271.047972) (xy 84.720938 -271.095724)
			(xy 84.92109 -271.095724)
		)
		(stroke
			(width 0)
			(type solid)
		)
		(fill yes)
		(layer "In4.Cu")
		(net "M_D_CPU1_SB_DQS_DP<9>")
	)
	(gr_poly
		(pts
			(xy 84.92109 -270.644366) (xy 84.92109 -270.599916) (xy 84.720938 -270.599916) (xy 84.720938 -270.644366)
			(xy 84.821014 -270.744442)
		)
		(stroke
			(width 0)
			(type solid)
		)
		(fill yes)
		(layer "In4.Cu")
		(net "M_D_CPU1_SB_CB<7>")
	)
	(gr_poly
		(pts
			(xy 84.92109 -269.428214) (xy 84.821014 -269.328138) (xy 84.720938 -269.428214) (xy 84.720938 -269.472664)
			(xy 84.92109 -269.472664)
		)
		(stroke
			(width 0)
			(type solid)
		)
		(fill yes)
		(layer "In4.Cu")
		(net "M_D_CPU1_SB_CB<4>")
	)
	(gr_poly
		(pts
			(xy 84.92109 -267.801852) (xy 84.821014 -267.701776) (xy 84.720938 -267.801852) (xy 84.720938 -267.846302)
			(xy 84.92109 -267.846302)
		)
		(stroke
			(width 0)
			(type solid)
		)
		(fill yes)
		(layer "In4.Cu")
		(net "M_D_CPU1_SB_RSP<0>")
	)
	(gr_poly
		(pts
			(xy 84.92109 -265.78433) (xy 84.92109 -265.73988) (xy 84.720938 -265.73988) (xy 84.720938 -265.78433)
			(xy 84.821014 -265.884406)
		)
		(stroke
			(width 0)
			(type solid)
		)
		(fill yes)
		(layer "In4.Cu")
		(net "M_D_CPU1_SB_CS_N<0>")
	)
	(gr_poly
		(pts
			(xy 84.92109 -264.568178) (xy 84.821014 -264.468102) (xy 84.720938 -264.568178) (xy 84.720938 -264.612628)
			(xy 84.92109 -264.612628)
		)
		(stroke
			(width 0)
			(type solid)
		)
		(fill yes)
		(layer "In4.Cu")
		(net "M_D_CPU1_SB_CA<6>")
	)
	(gr_poly
		(pts
			(xy 84.92109 -264.164318) (xy 84.92109 -264.119868) (xy 84.720938 -264.119868) (xy 84.720938 -264.164318)
			(xy 84.821014 -264.264394)
		)
		(stroke
			(width 0)
			(type solid)
		)
		(fill yes)
		(layer "In4.Cu")
		(net "M_D_CPU1_SB_CA<5>")
	)
	(gr_poly
		(pts
			(xy 84.92109 -262.948166) (xy 84.821014 -262.84809) (xy 84.720938 -262.948166) (xy 84.720938 -262.992616)
			(xy 84.92109 -262.992616)
		)
		(stroke
			(width 0)
			(type solid)
		)
		(fill yes)
		(layer "In4.Cu")
		(net "M_D_CPU1_SB_CA<2>")
	)
	(gr_poly
		(pts
			(xy 84.92109 -262.544306) (xy 84.92109 -262.499856) (xy 84.720938 -262.499856) (xy 84.720938 -262.544306)
			(xy 84.821014 -262.644382)
		)
		(stroke
			(width 0)
			(type solid)
		)
		(fill yes)
		(layer "In4.Cu")
		(net "M_D_CPU1_SB_CA<1>")
	)
	(gr_poly
		(pts
			(xy 85.091016 -256.026158) (xy 84.99094 -255.926336) (xy 84.890864 -256.026158) (xy 84.890864 -256.07391)
			(xy 85.091016 -256.07391)
		)
		(stroke
			(width 0)
			(type solid)
		)
		(fill yes)
		(layer "In4.Cu")
		(net "M_D_CPU1_CLK_DP<0>")
	)
	(gr_poly
		(pts
			(xy 85.091016 -255.622552) (xy 85.091016 -255.578102) (xy 84.890864 -255.578102) (xy 84.890864 -255.622552)
			(xy 84.99094 -255.722628)
		)
		(stroke
			(width 0)
			(type solid)
		)
		(fill yes)
		(layer "In4.Cu")
		(net "M_D_CPU1_SA_PAR")
	)
	(gr_poly
		(pts
			(xy 85.091016 -254.4064) (xy 84.99094 -254.306324) (xy 84.890864 -254.4064) (xy 84.890864 -254.45085)
			(xy 85.091016 -254.45085)
		)
		(stroke
			(width 0)
			(type solid)
		)
		(fill yes)
		(layer "In4.Cu")
		(net "M_D_CPU1_SA_CA<4>")
	)
	(gr_poly
		(pts
			(xy 85.091016 -254.00254) (xy 85.091016 -253.95809) (xy 84.890864 -253.95809) (xy 84.890864 -254.00254)
			(xy 84.99094 -254.102616)
		)
		(stroke
			(width 0)
			(type solid)
		)
		(fill yes)
		(layer "In4.Cu")
		(net "M_D_CPU1_SA_CA<3>")
	)
	(gr_poly
		(pts
			(xy 85.091016 -252.786388) (xy 84.99094 -252.686312) (xy 84.890864 -252.786388) (xy 84.890864 -252.830838)
			(xy 85.091016 -252.830838)
		)
		(stroke
			(width 0)
			(type solid)
		)
		(fill yes)
		(layer "In4.Cu")
		(net "M_D_CPU1_SA_CA<0>")
	)
	(gr_poly
		(pts
			(xy 85.091016 -252.382528) (xy 85.091016 -252.338078) (xy 84.890864 -252.338078) (xy 84.890864 -252.382528)
			(xy 84.99094 -252.482604)
		)
		(stroke
			(width 0)
			(type solid)
		)
		(fill yes)
		(layer "In4.Cu")
		(net "M_D_CPU1_SA_CS_N<1>")
	)
	(gr_poly
		(pts
			(xy 85.091016 -250.762516) (xy 85.091016 -250.718066) (xy 84.890864 -250.718066) (xy 84.890864 -250.762516)
			(xy 84.99094 -250.862592)
		)
		(stroke
			(width 0)
			(type solid)
		)
		(fill yes)
		(layer "In4.Cu")
		(net "M_D_CPU1_RESET_N")
	)
	(gr_poly
		(pts
			(xy 85.091016 -249.142504) (xy 85.091016 -249.098054) (xy 84.890864 -249.098054) (xy 84.890864 -249.142504)
			(xy 84.99094 -249.24258)
		)
		(stroke
			(width 0)
			(type solid)
		)
		(fill yes)
		(layer "In4.Cu")
		(net "M_D_CPU1_SA_CB<7>")
	)
	(gr_poly
		(pts
			(xy 85.091016 -247.926352) (xy 84.99094 -247.826276) (xy 84.890864 -247.926352) (xy 84.890864 -247.970802)
			(xy 85.091016 -247.970802)
		)
		(stroke
			(width 0)
			(type solid)
		)
		(fill yes)
		(layer "In4.Cu")
		(net "M_D_CPU1_SA_CB<4>")
	)
	(gr_poly
		(pts
			(xy 85.091016 -247.522746) (xy 85.091016 -247.474994) (xy 84.890864 -247.474994) (xy 84.890864 -247.522746)
			(xy 84.99094 -247.622568)
		)
		(stroke
			(width 0)
			(type solid)
		)
		(fill yes)
		(layer "In4.Cu")
		(net "M_D_CPU1_SA_DQS_DP<9>")
	)
	(gr_poly
		(pts
			(xy 85.091016 -246.306086) (xy 84.99094 -246.206264) (xy 84.890864 -246.306086) (xy 84.890864 -246.353838)
			(xy 85.091016 -246.353838)
		)
		(stroke
			(width 0)
			(type solid)
		)
		(fill yes)
		(layer "In4.Cu")
		(net "M_D_CPU1_SA_DQS_DP<4>")
	)
	(gr_poly
		(pts
			(xy 85.091016 -245.90248) (xy 85.091016 -245.85803) (xy 84.890864 -245.85803) (xy 84.890864 -245.90248)
			(xy 84.99094 -246.002556)
		)
		(stroke
			(width 0)
			(type solid)
		)
		(fill yes)
		(layer "In4.Cu")
		(net "M_D_CPU1_SA_CB<3>")
	)
	(gr_poly
		(pts
			(xy 85.091016 -244.686328) (xy 84.99094 -244.586252) (xy 84.890864 -244.686328) (xy 84.890864 -244.730778)
			(xy 85.091016 -244.730778)
		)
		(stroke
			(width 0)
			(type solid)
		)
		(fill yes)
		(layer "In4.Cu")
		(net "M_D_CPU1_SA_CB<0>")
	)
	(gr_poly
		(pts
			(xy 85.091016 -244.282468) (xy 85.091016 -244.238018) (xy 84.890864 -244.238018) (xy 84.890864 -244.282468)
			(xy 84.99094 -244.382544)
		)
		(stroke
			(width 0)
			(type solid)
		)
		(fill yes)
		(layer "In4.Cu")
		(net "M_D_CPU1_SA_DQ<31>")
	)
	(gr_poly
		(pts
			(xy 85.091016 -243.066316) (xy 84.99094 -242.96624) (xy 84.890864 -243.066316) (xy 84.890864 -243.110766)
			(xy 85.091016 -243.110766)
		)
		(stroke
			(width 0)
			(type solid)
		)
		(fill yes)
		(layer "In4.Cu")
		(net "M_D_CPU1_SA_DQ<28>")
	)
	(gr_poly
		(pts
			(xy 85.091016 -242.66271) (xy 85.091016 -242.614958) (xy 84.890864 -242.614958) (xy 84.890864 -242.66271)
			(xy 84.99094 -242.762532)
		)
		(stroke
			(width 0)
			(type solid)
		)
		(fill yes)
		(layer "In4.Cu")
		(net "M_D_CPU1_SA_DQS_DP<8>")
	)
	(gr_poly
		(pts
			(xy 85.091016 -241.44605) (xy 84.99094 -241.346228) (xy 84.890864 -241.44605) (xy 84.890864 -241.493802)
			(xy 85.091016 -241.493802)
		)
		(stroke
			(width 0)
			(type solid)
		)
		(fill yes)
		(layer "In4.Cu")
		(net "M_D_CPU1_SA_DQS_DP<3>")
	)
	(gr_poly
		(pts
			(xy 85.091016 -241.042444) (xy 85.091016 -240.997994) (xy 84.890864 -240.997994) (xy 84.890864 -241.042444)
			(xy 84.99094 -241.14252)
		)
		(stroke
			(width 0)
			(type solid)
		)
		(fill yes)
		(layer "In4.Cu")
		(net "M_D_CPU1_SA_DQ<27>")
	)
	(gr_poly
		(pts
			(xy 85.091016 -239.826292) (xy 84.99094 -239.726216) (xy 84.890864 -239.826292) (xy 84.890864 -239.870742)
			(xy 85.091016 -239.870742)
		)
		(stroke
			(width 0)
			(type solid)
		)
		(fill yes)
		(layer "In4.Cu")
		(net "M_D_CPU1_SA_DQ<24>")
	)
	(gr_poly
		(pts
			(xy 85.091016 -239.422432) (xy 85.091016 -239.377982) (xy 84.890864 -239.377982) (xy 84.890864 -239.422432)
			(xy 84.99094 -239.522508)
		)
		(stroke
			(width 0)
			(type solid)
		)
		(fill yes)
		(layer "In4.Cu")
		(net "M_D_CPU1_SA_DQ<23>")
	)
	(gr_poly
		(pts
			(xy 85.091016 -238.20628) (xy 84.99094 -238.106204) (xy 84.890864 -238.20628) (xy 84.890864 -238.25073)
			(xy 85.091016 -238.25073)
		)
		(stroke
			(width 0)
			(type solid)
		)
		(fill yes)
		(layer "In4.Cu")
		(net "M_D_CPU1_SA_DQ<20>")
	)
	(gr_poly
		(pts
			(xy 85.091016 -237.802674) (xy 85.091016 -237.754922) (xy 84.890864 -237.754922) (xy 84.890864 -237.802674)
			(xy 84.99094 -237.902496)
		)
		(stroke
			(width 0)
			(type solid)
		)
		(fill yes)
		(layer "In4.Cu")
		(net "M_D_CPU1_SA_DQS_DP<7>")
	)
	(gr_poly
		(pts
			(xy 85.091016 -236.586014) (xy 84.99094 -236.486192) (xy 84.890864 -236.586014) (xy 84.890864 -236.633766)
			(xy 85.091016 -236.633766)
		)
		(stroke
			(width 0)
			(type solid)
		)
		(fill yes)
		(layer "In4.Cu")
		(net "M_D_CPU1_SA_DQS_DP<2>")
	)
	(gr_poly
		(pts
			(xy 85.091016 -236.182408) (xy 85.091016 -236.137958) (xy 84.890864 -236.137958) (xy 84.890864 -236.182408)
			(xy 84.99094 -236.282484)
		)
		(stroke
			(width 0)
			(type solid)
		)
		(fill yes)
		(layer "In4.Cu")
		(net "M_D_CPU1_SA_DQ<19>")
	)
	(gr_poly
		(pts
			(xy 85.091016 -234.966256) (xy 84.99094 -234.86618) (xy 84.890864 -234.966256) (xy 84.890864 -235.010706)
			(xy 85.091016 -235.010706)
		)
		(stroke
			(width 0)
			(type solid)
		)
		(fill yes)
		(layer "In4.Cu")
		(net "M_D_CPU1_SA_DQ<16>")
	)
	(gr_poly
		(pts
			(xy 85.091016 -234.562396) (xy 85.091016 -234.517946) (xy 84.890864 -234.517946) (xy 84.890864 -234.562396)
			(xy 84.99094 -234.662472)
		)
		(stroke
			(width 0)
			(type solid)
		)
		(fill yes)
		(layer "In4.Cu")
		(net "M_D_CPU1_SA_DQ<15>")
	)
	(gr_poly
		(pts
			(xy 85.091016 -233.346244) (xy 84.99094 -233.246168) (xy 84.890864 -233.346244) (xy 84.890864 -233.390694)
			(xy 85.091016 -233.390694)
		)
		(stroke
			(width 0)
			(type solid)
		)
		(fill yes)
		(layer "In4.Cu")
		(net "M_D_CPU1_SA_DQ<12>")
	)
	(gr_poly
		(pts
			(xy 85.091016 -232.942638) (xy 85.091016 -232.894886) (xy 84.890864 -232.894886) (xy 84.890864 -232.942638)
			(xy 84.99094 -233.04246)
		)
		(stroke
			(width 0)
			(type solid)
		)
		(fill yes)
		(layer "In4.Cu")
		(net "M_D_CPU1_SA_DQS_DP<6>")
	)
	(gr_poly
		(pts
			(xy 85.091016 -231.725978) (xy 84.99094 -231.626156) (xy 84.890864 -231.725978) (xy 84.890864 -231.77373)
			(xy 85.091016 -231.77373)
		)
		(stroke
			(width 0)
			(type solid)
		)
		(fill yes)
		(layer "In4.Cu")
		(net "M_D_CPU1_SA_DQS_DP<1>")
	)
	(gr_poly
		(pts
			(xy 85.091016 -231.322626) (xy 85.091016 -231.278176) (xy 84.890864 -231.278176) (xy 84.890864 -231.322626)
			(xy 84.99094 -231.422702)
		)
		(stroke
			(width 0)
			(type solid)
		)
		(fill yes)
		(layer "In4.Cu")
		(net "M_D_CPU1_SA_DQ<11>")
	)
	(gr_poly
		(pts
			(xy 85.091016 -230.10622) (xy 84.99094 -230.006144) (xy 84.890864 -230.10622) (xy 84.890864 -230.15067)
			(xy 85.091016 -230.15067)
		)
		(stroke
			(width 0)
			(type solid)
		)
		(fill yes)
		(layer "In4.Cu")
		(net "M_D_CPU1_SA_DQ<8>")
	)
	(gr_poly
		(pts
			(xy 85.091016 -229.702614) (xy 85.091016 -229.658164) (xy 84.890864 -229.658164) (xy 84.890864 -229.702614)
			(xy 84.99094 -229.80269)
		)
		(stroke
			(width 0)
			(type solid)
		)
		(fill yes)
		(layer "In4.Cu")
		(net "M_D_CPU1_SA_DQ<7>")
	)
	(gr_poly
		(pts
			(xy 85.091016 -228.486462) (xy 84.99094 -228.386386) (xy 84.890864 -228.486462) (xy 84.890864 -228.530912)
			(xy 85.091016 -228.530912)
		)
		(stroke
			(width 0)
			(type solid)
		)
		(fill yes)
		(layer "In4.Cu")
		(net "M_D_CPU1_SA_DQ<4>")
	)
	(gr_poly
		(pts
			(xy 85.091016 -228.082856) (xy 85.091016 -228.035104) (xy 84.890864 -228.035104) (xy 84.890864 -228.082856)
			(xy 84.99094 -228.182678)
		)
		(stroke
			(width 0)
			(type solid)
		)
		(fill yes)
		(layer "In4.Cu")
		(net "M_D_CPU1_SA_DQS_DP<5>")
	)
	(gr_poly
		(pts
			(xy 85.091016 -226.866196) (xy 84.99094 -226.766374) (xy 84.890864 -226.866196) (xy 84.890864 -226.913948)
			(xy 85.091016 -226.913948)
		)
		(stroke
			(width 0)
			(type solid)
		)
		(fill yes)
		(layer "In4.Cu")
		(net "M_D_CPU1_SA_DQS_DP<0>")
	)
	(gr_poly
		(pts
			(xy 85.091016 -226.46259) (xy 85.091016 -226.41814) (xy 84.890864 -226.41814) (xy 84.890864 -226.46259)
			(xy 84.99094 -226.562666)
		)
		(stroke
			(width 0)
			(type solid)
		)
		(fill yes)
		(layer "In4.Cu")
		(net "M_D_CPU1_SA_DQ<3>")
	)
	(gr_poly
		(pts
			(xy 85.091016 -225.246438) (xy 84.99094 -225.146362) (xy 84.890864 -225.246438) (xy 84.890864 -225.290888)
			(xy 85.091016 -225.290888)
		)
		(stroke
			(width 0)
			(type solid)
		)
		(fill yes)
		(layer "In4.Cu")
		(net "M_D_CPU1_SA_DQ<0>")
	)
	(gr_poly
		(pts
			(xy 85.39099 -292.918134) (xy 85.290914 -292.818058) (xy 85.190838 -292.918134) (xy 85.190838 -292.962584)
			(xy 85.39099 -292.962584)
		)
		(stroke
			(width 0)
			(type solid)
		)
		(fill yes)
		(layer "In4.Cu")
		(net "M_D_CPU1_SB_DQ<29>")
	)
	(gr_poly
		(pts
			(xy 85.39099 -292.514274) (xy 85.39099 -292.469824) (xy 85.190838 -292.469824) (xy 85.190838 -292.514274)
			(xy 85.290914 -292.61435)
		)
		(stroke
			(width 0)
			(type solid)
		)
		(fill yes)
		(layer "In4.Cu")
		(net "M_D_CPU1_SB_DQ<30>")
	)
	(gr_poly
		(pts
			(xy 85.39099 -291.297868) (xy 85.290914 -291.198046) (xy 85.190838 -291.297868) (xy 85.190838 -291.34562)
			(xy 85.39099 -291.34562)
		)
		(stroke
			(width 0)
			(type solid)
		)
		(fill yes)
		(layer "In4.Cu")
		(net "M_D_CPU1_SB_DQS_DN<8>")
	)
	(gr_poly
		(pts
			(xy 85.39099 -290.894516) (xy 85.39099 -290.846764) (xy 85.190838 -290.846764) (xy 85.190838 -290.894516)
			(xy 85.290914 -290.994338)
		)
		(stroke
			(width 0)
			(type solid)
		)
		(fill yes)
		(layer "In4.Cu")
		(net "M_D_CPU1_SB_DQS_DN<3>")
	)
	(gr_poly
		(pts
			(xy 85.39099 -289.67811) (xy 85.290914 -289.578034) (xy 85.190838 -289.67811) (xy 85.190838 -289.72256)
			(xy 85.39099 -289.72256)
		)
		(stroke
			(width 0)
			(type solid)
		)
		(fill yes)
		(layer "In4.Cu")
		(net "M_D_CPU1_SB_DQ<25>")
	)
	(gr_poly
		(pts
			(xy 85.39099 -289.27425) (xy 85.39099 -289.2298) (xy 85.190838 -289.2298) (xy 85.190838 -289.27425)
			(xy 85.290914 -289.374326)
		)
		(stroke
			(width 0)
			(type solid)
		)
		(fill yes)
		(layer "In4.Cu")
		(net "M_D_CPU1_SB_DQ<26>")
	)
	(gr_poly
		(pts
			(xy 85.39099 -288.058098) (xy 85.290914 -287.958022) (xy 85.190838 -288.058098) (xy 85.190838 -288.102548)
			(xy 85.39099 -288.102548)
		)
		(stroke
			(width 0)
			(type solid)
		)
		(fill yes)
		(layer "In4.Cu")
		(net "M_D_CPU1_SB_DQ<21>")
	)
	(gr_poly
		(pts
			(xy 85.39099 -287.654492) (xy 85.39099 -287.610042) (xy 85.190838 -287.610042) (xy 85.190838 -287.654492)
			(xy 85.290914 -287.754568)
		)
		(stroke
			(width 0)
			(type solid)
		)
		(fill yes)
		(layer "In4.Cu")
		(net "M_D_CPU1_SB_DQ<22>")
	)
	(gr_poly
		(pts
			(xy 85.39099 -286.438086) (xy 85.290914 -286.33801) (xy 85.190838 -286.438086) (xy 85.190838 -286.485838)
			(xy 85.39099 -286.485838)
		)
		(stroke
			(width 0)
			(type solid)
		)
		(fill yes)
		(layer "In4.Cu")
		(net "M_D_CPU1_SB_DQS_DN<7>")
	)
	(gr_poly
		(pts
			(xy 85.39099 -286.034734) (xy 85.39099 -285.986982) (xy 85.190838 -285.986982) (xy 85.190838 -286.034734)
			(xy 85.290914 -286.134556)
		)
		(stroke
			(width 0)
			(type solid)
		)
		(fill yes)
		(layer "In4.Cu")
		(net "M_D_CPU1_SB_DQS_DN<2>")
	)
	(gr_poly
		(pts
			(xy 85.39099 -284.818328) (xy 85.290914 -284.718252) (xy 85.190838 -284.818328) (xy 85.190838 -284.862778)
			(xy 85.39099 -284.862778)
		)
		(stroke
			(width 0)
			(type solid)
		)
		(fill yes)
		(layer "In4.Cu")
		(net "M_D_CPU1_SB_DQ<17>")
	)
	(gr_poly
		(pts
			(xy 85.39099 -284.414468) (xy 85.39099 -284.370018) (xy 85.190838 -284.370018) (xy 85.190838 -284.414468)
			(xy 85.290914 -284.514544)
		)
		(stroke
			(width 0)
			(type solid)
		)
		(fill yes)
		(layer "In4.Cu")
		(net "M_D_CPU1_SB_DQ<18>")
	)
	(gr_poly
		(pts
			(xy 85.39099 -283.198316) (xy 85.290914 -283.09824) (xy 85.190838 -283.198316) (xy 85.190838 -283.242766)
			(xy 85.39099 -283.242766)
		)
		(stroke
			(width 0)
			(type solid)
		)
		(fill yes)
		(layer "In4.Cu")
		(net "M_D_CPU1_SB_DQ<13>")
	)
	(gr_poly
		(pts
			(xy 85.39099 -282.794456) (xy 85.39099 -282.750006) (xy 85.190838 -282.750006) (xy 85.190838 -282.794456)
			(xy 85.290914 -282.894532)
		)
		(stroke
			(width 0)
			(type solid)
		)
		(fill yes)
		(layer "In4.Cu")
		(net "M_D_CPU1_SB_DQ<14>")
	)
	(gr_poly
		(pts
			(xy 85.39099 -281.57805) (xy 85.290914 -281.478228) (xy 85.190838 -281.57805) (xy 85.190838 -281.625802)
			(xy 85.39099 -281.625802)
		)
		(stroke
			(width 0)
			(type solid)
		)
		(fill yes)
		(layer "In4.Cu")
		(net "M_D_CPU1_SB_DQS_DN<6>")
	)
	(gr_poly
		(pts
			(xy 85.39099 -281.174698) (xy 85.39099 -281.126946) (xy 85.190838 -281.126946) (xy 85.190838 -281.174698)
			(xy 85.290914 -281.27452)
		)
		(stroke
			(width 0)
			(type solid)
		)
		(fill yes)
		(layer "In4.Cu")
		(net "M_D_CPU1_SB_DQS_DN<1>")
	)
	(gr_poly
		(pts
			(xy 85.39099 -279.958292) (xy 85.290914 -279.858216) (xy 85.190838 -279.958292) (xy 85.190838 -280.002742)
			(xy 85.39099 -280.002742)
		)
		(stroke
			(width 0)
			(type solid)
		)
		(fill yes)
		(layer "In4.Cu")
		(net "M_D_CPU1_SB_DQ<9>")
	)
	(gr_poly
		(pts
			(xy 85.39099 -279.554432) (xy 85.39099 -279.509982) (xy 85.190838 -279.509982) (xy 85.190838 -279.554432)
			(xy 85.290914 -279.654508)
		)
		(stroke
			(width 0)
			(type solid)
		)
		(fill yes)
		(layer "In4.Cu")
		(net "M_D_CPU1_SB_DQ<10>")
	)
	(gr_poly
		(pts
			(xy 85.39099 -278.33828) (xy 85.290914 -278.238204) (xy 85.190838 -278.33828) (xy 85.190838 -278.38273)
			(xy 85.39099 -278.38273)
		)
		(stroke
			(width 0)
			(type solid)
		)
		(fill yes)
		(layer "In4.Cu")
		(net "M_D_CPU1_SB_DQ<5>")
	)
	(gr_poly
		(pts
			(xy 85.39099 -277.93442) (xy 85.39099 -277.88997) (xy 85.190838 -277.88997) (xy 85.190838 -277.93442)
			(xy 85.290914 -278.034496)
		)
		(stroke
			(width 0)
			(type solid)
		)
		(fill yes)
		(layer "In4.Cu")
		(net "M_D_CPU1_SB_DQ<6>")
	)
	(gr_poly
		(pts
			(xy 85.39099 -275.098256) (xy 85.290914 -274.99818) (xy 85.190838 -275.098256) (xy 85.190838 -275.142706)
			(xy 85.39099 -275.142706)
		)
		(stroke
			(width 0)
			(type solid)
		)
		(fill yes)
		(layer "In4.Cu")
		(net "M_D_CPU1_SB_DQ<1>")
	)
	(gr_poly
		(pts
			(xy 85.39099 -274.694396) (xy 85.39099 -274.649946) (xy 85.190838 -274.649946) (xy 85.190838 -274.694396)
			(xy 85.290914 -274.794472)
		)
		(stroke
			(width 0)
			(type solid)
		)
		(fill yes)
		(layer "In4.Cu")
		(net "M_D_CPU1_SB_DQ<2>")
	)
	(gr_poly
		(pts
			(xy 85.39099 -273.478244) (xy 85.290914 -273.378168) (xy 85.190838 -273.478244) (xy 85.190838 -273.522694)
			(xy 85.39099 -273.522694)
		)
		(stroke
			(width 0)
			(type solid)
		)
		(fill yes)
		(layer "In4.Cu")
		(net "M_D_CPU1_SB_CB<1>")
	)
	(gr_poly
		(pts
			(xy 85.39099 -273.074384) (xy 85.39099 -273.029934) (xy 85.190838 -273.029934) (xy 85.190838 -273.074384)
			(xy 85.290914 -273.17446)
		)
		(stroke
			(width 0)
			(type solid)
		)
		(fill yes)
		(layer "In4.Cu")
		(net "M_D_CPU1_SB_CB<2>")
	)
	(gr_poly
		(pts
			(xy 85.39099 -271.857978) (xy 85.290914 -271.758156) (xy 85.190838 -271.857978) (xy 85.190838 -271.90573)
			(xy 85.39099 -271.90573)
		)
		(stroke
			(width 0)
			(type solid)
		)
		(fill yes)
		(layer "In4.Cu")
		(net "M_D_CPU1_SB_DQS_DN<4>")
	)
	(gr_poly
		(pts
			(xy 85.39099 -271.454626) (xy 85.39099 -271.406874) (xy 85.190838 -271.406874) (xy 85.190838 -271.454626)
			(xy 85.290914 -271.554448)
		)
		(stroke
			(width 0)
			(type solid)
		)
		(fill yes)
		(layer "In4.Cu")
		(net "M_D_CPU1_SB_DQS_DN<9>")
	)
	(gr_poly
		(pts
			(xy 85.39099 -270.23822) (xy 85.290914 -270.138144) (xy 85.190838 -270.23822) (xy 85.190838 -270.28267)
			(xy 85.39099 -270.28267)
		)
		(stroke
			(width 0)
			(type solid)
		)
		(fill yes)
		(layer "In4.Cu")
		(net "M_D_CPU1_SB_CB<5>")
	)
	(gr_poly
		(pts
			(xy 85.39099 -269.83436) (xy 85.39099 -269.78991) (xy 85.190838 -269.78991) (xy 85.190838 -269.83436)
			(xy 85.290914 -269.934436)
		)
		(stroke
			(width 0)
			(type solid)
		)
		(fill yes)
		(layer "In4.Cu")
		(net "M_D_CPU1_SB_CB<6>")
	)
	(gr_poly
		(pts
			(xy 85.39099 -266.594336) (xy 85.39099 -266.549886) (xy 85.190838 -266.549886) (xy 85.190838 -266.594336)
			(xy 85.290914 -266.694412)
		)
		(stroke
			(width 0)
			(type solid)
		)
		(fill yes)
		(layer "In4.Cu")
		(net "M_D_CPU1_SB_CS_N<1>")
	)
	(gr_poly
		(pts
			(xy 85.39099 -264.974324) (xy 85.39099 -264.929874) (xy 85.190838 -264.929874) (xy 85.190838 -264.974324)
			(xy 85.290914 -265.0744)
		)
		(stroke
			(width 0)
			(type solid)
		)
		(fill yes)
		(layer "In4.Cu")
		(net "M_D_CPU1_SB_PAR")
	)
	(gr_poly
		(pts
			(xy 85.39099 -263.758172) (xy 85.290914 -263.658096) (xy 85.190838 -263.758172) (xy 85.190838 -263.802622)
			(xy 85.39099 -263.802622)
		)
		(stroke
			(width 0)
			(type solid)
		)
		(fill yes)
		(layer "In4.Cu")
		(net "M_D_CPU1_SB_CA<4>")
	)
	(gr_poly
		(pts
			(xy 85.39099 -263.354312) (xy 85.39099 -263.309862) (xy 85.190838 -263.309862) (xy 85.190838 -263.354312)
			(xy 85.290914 -263.454388)
		)
		(stroke
			(width 0)
			(type solid)
		)
		(fill yes)
		(layer "In4.Cu")
		(net "M_D_CPU1_SB_CA<3>")
	)
	(gr_poly
		(pts
			(xy 85.39099 -262.13816) (xy 85.290914 -262.038084) (xy 85.190838 -262.13816) (xy 85.190838 -262.18261)
			(xy 85.39099 -262.18261)
		)
		(stroke
			(width 0)
			(type solid)
		)
		(fill yes)
		(layer "In4.Cu")
		(net "M_D_CPU1_SB_CA<0>")
	)
	(gr_poly
		(pts
			(xy 85.397086 -266.991846) (xy 85.297264 -266.89177) (xy 85.197188 -266.991846) (xy 85.197188 -267.036296)
			(xy 85.397086 -267.036296)
		)
		(stroke
			(width 0)
			(type solid)
		)
		(fill yes)
		(layer "In4.Cu")
		(net "M_D_CPU1_SA_RSP<0>")
	)
	(gr_poly
		(pts
			(xy 85.398102 -276.718268) (xy 85.29828 -276.618192) (xy 85.198204 -276.718268) (xy 85.198204 -276.765766)
			(xy 85.398102 -276.765766)
		)
		(stroke
			(width 0)
			(type solid)
		)
		(fill yes)
		(layer "In4.Cu")
		(net "M_D_CPU1_SB_DQS_DN<5>")
	)
	(gr_poly
		(pts
			(xy 85.398102 -276.314408) (xy 85.398102 -276.26691) (xy 85.198204 -276.26691) (xy 85.198204 -276.314408)
			(xy 85.29828 -276.414484)
		)
		(stroke
			(width 0)
			(type solid)
		)
		(fill yes)
		(layer "In4.Cu")
		(net "M_D_CPU1_SB_DQS_DN<0>")
	)
	(gr_poly
		(pts
			(xy 85.555074 -227.67671) (xy 85.454998 -227.576634) (xy 85.354922 -227.67671) (xy 85.354922 -227.724208)
			(xy 85.555074 -227.724208)
		)
		(stroke
			(width 0)
			(type solid)
		)
		(fill yes)
		(layer "In4.Cu")
		(net "M_D_CPU1_SA_DQS_DN<5>")
	)
	(gr_poly
		(pts
			(xy 85.56117 -256.432812) (xy 85.56117 -256.38506) (xy 85.361018 -256.38506) (xy 85.361018 -256.432812)
			(xy 85.461094 -256.532634)
		)
		(stroke
			(width 0)
			(type solid)
		)
		(fill yes)
		(layer "In4.Cu")
		(net "M_D_CPU1_CLK_DN<0>")
	)
	(gr_poly
		(pts
			(xy 85.56117 -255.216406) (xy 85.461094 -255.11633) (xy 85.361018 -255.216406) (xy 85.361018 -255.260856)
			(xy 85.56117 -255.260856)
		)
		(stroke
			(width 0)
			(type solid)
		)
		(fill yes)
		(layer "In4.Cu")
		(net "M_D_CPU1_SA_CA<6>")
	)
	(gr_poly
		(pts
			(xy 85.56117 -254.812546) (xy 85.56117 -254.768096) (xy 85.361018 -254.768096) (xy 85.361018 -254.812546)
			(xy 85.461094 -254.912622)
		)
		(stroke
			(width 0)
			(type solid)
		)
		(fill yes)
		(layer "In4.Cu")
		(net "M_D_CPU1_SA_CA<5>")
	)
	(gr_poly
		(pts
			(xy 85.56117 -253.596394) (xy 85.461094 -253.496318) (xy 85.361018 -253.596394) (xy 85.361018 -253.640844)
			(xy 85.56117 -253.640844)
		)
		(stroke
			(width 0)
			(type solid)
		)
		(fill yes)
		(layer "In4.Cu")
		(net "M_D_CPU1_SA_CA<2>")
	)
	(gr_poly
		(pts
			(xy 85.56117 -253.192534) (xy 85.56117 -253.148084) (xy 85.361018 -253.148084) (xy 85.361018 -253.192534)
			(xy 85.461094 -253.29261)
		)
		(stroke
			(width 0)
			(type solid)
		)
		(fill yes)
		(layer "In4.Cu")
		(net "M_D_CPU1_SA_CA<1>")
	)
	(gr_poly
		(pts
			(xy 85.56117 -251.572522) (xy 85.56117 -251.528072) (xy 85.361018 -251.528072) (xy 85.361018 -251.572522)
			(xy 85.461094 -251.672598)
		)
		(stroke
			(width 0)
			(type solid)
		)
		(fill yes)
		(layer "In4.Cu")
		(net "M_D_CPU1_SA_CS_N<0>")
	)
	(gr_poly
		(pts
			(xy 85.56117 -250.35637) (xy 85.461094 -250.256294) (xy 85.361018 -250.35637) (xy 85.361018 -250.40082)
			(xy 85.56117 -250.40082)
		)
		(stroke
			(width 0)
			(type solid)
		)
		(fill yes)
		(layer "In4.Cu")
		(net "M_D_CPU1_ALERT_R_N")
	)
	(gr_poly
		(pts
			(xy 85.56117 -248.736358) (xy 85.461094 -248.636282) (xy 85.361018 -248.736358) (xy 85.361018 -248.780808)
			(xy 85.56117 -248.780808)
		)
		(stroke
			(width 0)
			(type solid)
		)
		(fill yes)
		(layer "In4.Cu")
		(net "M_D_CPU1_SA_CB<5>")
	)
	(gr_poly
		(pts
			(xy 85.56117 -248.332498) (xy 85.56117 -248.288048) (xy 85.361018 -248.288048) (xy 85.361018 -248.332498)
			(xy 85.461094 -248.432574)
		)
		(stroke
			(width 0)
			(type solid)
		)
		(fill yes)
		(layer "In4.Cu")
		(net "M_D_CPU1_SA_CB<6>")
	)
	(gr_poly
		(pts
			(xy 85.56117 -247.116092) (xy 85.461094 -247.01627) (xy 85.361018 -247.116092) (xy 85.361018 -247.163844)
			(xy 85.56117 -247.163844)
		)
		(stroke
			(width 0)
			(type solid)
		)
		(fill yes)
		(layer "In4.Cu")
		(net "M_D_CPU1_SA_DQS_DN<9>")
	)
	(gr_poly
		(pts
			(xy 85.56117 -246.71274) (xy 85.56117 -246.664988) (xy 85.361018 -246.664988) (xy 85.361018 -246.71274)
			(xy 85.461094 -246.812562)
		)
		(stroke
			(width 0)
			(type solid)
		)
		(fill yes)
		(layer "In4.Cu")
		(net "M_D_CPU1_SA_DQS_DN<4>")
	)
	(gr_poly
		(pts
			(xy 85.56117 -245.496334) (xy 85.461094 -245.396258) (xy 85.361018 -245.496334) (xy 85.361018 -245.540784)
			(xy 85.56117 -245.540784)
		)
		(stroke
			(width 0)
			(type solid)
		)
		(fill yes)
		(layer "In4.Cu")
		(net "M_D_CPU1_SA_CB<1>")
	)
	(gr_poly
		(pts
			(xy 85.56117 -245.092474) (xy 85.56117 -245.048024) (xy 85.361018 -245.048024) (xy 85.361018 -245.092474)
			(xy 85.461094 -245.19255)
		)
		(stroke
			(width 0)
			(type solid)
		)
		(fill yes)
		(layer "In4.Cu")
		(net "M_D_CPU1_SA_CB<2>")
	)
	(gr_poly
		(pts
			(xy 85.56117 -243.876322) (xy 85.461094 -243.776246) (xy 85.361018 -243.876322) (xy 85.361018 -243.920772)
			(xy 85.56117 -243.920772)
		)
		(stroke
			(width 0)
			(type solid)
		)
		(fill yes)
		(layer "In4.Cu")
		(net "M_D_CPU1_SA_DQ<29>")
	)
	(gr_poly
		(pts
			(xy 85.56117 -243.472462) (xy 85.56117 -243.428012) (xy 85.361018 -243.428012) (xy 85.361018 -243.472462)
			(xy 85.461094 -243.572538)
		)
		(stroke
			(width 0)
			(type solid)
		)
		(fill yes)
		(layer "In4.Cu")
		(net "M_D_CPU1_SA_DQ<30>")
	)
	(gr_poly
		(pts
			(xy 85.56117 -242.256056) (xy 85.461094 -242.156234) (xy 85.361018 -242.256056) (xy 85.361018 -242.303808)
			(xy 85.56117 -242.303808)
		)
		(stroke
			(width 0)
			(type solid)
		)
		(fill yes)
		(layer "In4.Cu")
		(net "M_D_CPU1_SA_DQS_DN<8>")
	)
	(gr_poly
		(pts
			(xy 85.56117 -241.852704) (xy 85.56117 -241.804952) (xy 85.361018 -241.804952) (xy 85.361018 -241.852704)
			(xy 85.461094 -241.952526)
		)
		(stroke
			(width 0)
			(type solid)
		)
		(fill yes)
		(layer "In4.Cu")
		(net "M_D_CPU1_SA_DQS_DN<3>")
	)
	(gr_poly
		(pts
			(xy 85.56117 -240.636298) (xy 85.461094 -240.536222) (xy 85.361018 -240.636298) (xy 85.361018 -240.680748)
			(xy 85.56117 -240.680748)
		)
		(stroke
			(width 0)
			(type solid)
		)
		(fill yes)
		(layer "In4.Cu")
		(net "M_D_CPU1_SA_DQ<25>")
	)
	(gr_poly
		(pts
			(xy 85.56117 -240.232438) (xy 85.56117 -240.187988) (xy 85.361018 -240.187988) (xy 85.361018 -240.232438)
			(xy 85.461094 -240.332514)
		)
		(stroke
			(width 0)
			(type solid)
		)
		(fill yes)
		(layer "In4.Cu")
		(net "M_D_CPU1_SA_DQ<26>")
	)
	(gr_poly
		(pts
			(xy 85.56117 -239.016286) (xy 85.461094 -238.91621) (xy 85.361018 -239.016286) (xy 85.361018 -239.060736)
			(xy 85.56117 -239.060736)
		)
		(stroke
			(width 0)
			(type solid)
		)
		(fill yes)
		(layer "In4.Cu")
		(net "M_D_CPU1_SA_DQ<21>")
	)
	(gr_poly
		(pts
			(xy 85.56117 -238.612426) (xy 85.56117 -238.567976) (xy 85.361018 -238.567976) (xy 85.361018 -238.612426)
			(xy 85.461094 -238.712502)
		)
		(stroke
			(width 0)
			(type solid)
		)
		(fill yes)
		(layer "In4.Cu")
		(net "M_D_CPU1_SA_DQ<22>")
	)
	(gr_poly
		(pts
			(xy 85.56117 -237.39602) (xy 85.461094 -237.296198) (xy 85.361018 -237.39602) (xy 85.361018 -237.443772)
			(xy 85.56117 -237.443772)
		)
		(stroke
			(width 0)
			(type solid)
		)
		(fill yes)
		(layer "In4.Cu")
		(net "M_D_CPU1_SA_DQS_DN<7>")
	)
	(gr_poly
		(pts
			(xy 85.56117 -236.992668) (xy 85.56117 -236.944916) (xy 85.361018 -236.944916) (xy 85.361018 -236.992668)
			(xy 85.461094 -237.09249)
		)
		(stroke
			(width 0)
			(type solid)
		)
		(fill yes)
		(layer "In4.Cu")
		(net "M_D_CPU1_SA_DQS_DN<2>")
	)
	(gr_poly
		(pts
			(xy 85.56117 -235.776262) (xy 85.461094 -235.676186) (xy 85.361018 -235.776262) (xy 85.361018 -235.820712)
			(xy 85.56117 -235.820712)
		)
		(stroke
			(width 0)
			(type solid)
		)
		(fill yes)
		(layer "In4.Cu")
		(net "M_D_CPU1_SA_DQ<17>")
	)
	(gr_poly
		(pts
			(xy 85.56117 -235.372402) (xy 85.56117 -235.327952) (xy 85.361018 -235.327952) (xy 85.361018 -235.372402)
			(xy 85.461094 -235.472478)
		)
		(stroke
			(width 0)
			(type solid)
		)
		(fill yes)
		(layer "In4.Cu")
		(net "M_D_CPU1_SA_DQ<18>")
	)
	(gr_poly
		(pts
			(xy 85.56117 -234.15625) (xy 85.461094 -234.056174) (xy 85.361018 -234.15625) (xy 85.361018 -234.2007)
			(xy 85.56117 -234.2007)
		)
		(stroke
			(width 0)
			(type solid)
		)
		(fill yes)
		(layer "In4.Cu")
		(net "M_D_CPU1_SA_DQ<13>")
	)
	(gr_poly
		(pts
			(xy 85.56117 -233.75239) (xy 85.56117 -233.70794) (xy 85.361018 -233.70794) (xy 85.361018 -233.75239)
			(xy 85.461094 -233.852466)
		)
		(stroke
			(width 0)
			(type solid)
		)
		(fill yes)
		(layer "In4.Cu")
		(net "M_D_CPU1_SA_DQ<14>")
	)
	(gr_poly
		(pts
			(xy 85.56117 -232.535984) (xy 85.461094 -232.436162) (xy 85.361018 -232.535984) (xy 85.361018 -232.583736)
			(xy 85.56117 -232.583736)
		)
		(stroke
			(width 0)
			(type solid)
		)
		(fill yes)
		(layer "In4.Cu")
		(net "M_D_CPU1_SA_DQS_DN<6>")
	)
	(gr_poly
		(pts
			(xy 85.56117 -232.132632) (xy 85.56117 -232.08488) (xy 85.361018 -232.08488) (xy 85.361018 -232.132632)
			(xy 85.461094 -232.232454)
		)
		(stroke
			(width 0)
			(type solid)
		)
		(fill yes)
		(layer "In4.Cu")
		(net "M_D_CPU1_SA_DQS_DN<1>")
	)
	(gr_poly
		(pts
			(xy 85.56117 -230.916226) (xy 85.461094 -230.81615) (xy 85.361018 -230.916226) (xy 85.361018 -230.960676)
			(xy 85.56117 -230.960676)
		)
		(stroke
			(width 0)
			(type solid)
		)
		(fill yes)
		(layer "In4.Cu")
		(net "M_D_CPU1_SA_DQ<9>")
	)
	(gr_poly
		(pts
			(xy 85.56117 -230.51262) (xy 85.56117 -230.46817) (xy 85.361018 -230.46817) (xy 85.361018 -230.51262)
			(xy 85.461094 -230.612696)
		)
		(stroke
			(width 0)
			(type solid)
		)
		(fill yes)
		(layer "In4.Cu")
		(net "M_D_CPU1_SA_DQ<10>")
	)
	(gr_poly
		(pts
			(xy 85.56117 -229.296214) (xy 85.461094 -229.196138) (xy 85.361018 -229.296214) (xy 85.361018 -229.340664)
			(xy 85.56117 -229.340664)
		)
		(stroke
			(width 0)
			(type solid)
		)
		(fill yes)
		(layer "In4.Cu")
		(net "M_D_CPU1_SA_DQ<5>")
	)
	(gr_poly
		(pts
			(xy 85.56117 -228.892608) (xy 85.56117 -228.848158) (xy 85.361018 -228.848158) (xy 85.361018 -228.892608)
			(xy 85.461094 -228.992684)
		)
		(stroke
			(width 0)
			(type solid)
		)
		(fill yes)
		(layer "In4.Cu")
		(net "M_D_CPU1_SA_DQ<6>")
	)
	(gr_poly
		(pts
			(xy 85.56117 -227.27285) (xy 85.56117 -227.225098) (xy 85.361018 -227.225098) (xy 85.361018 -227.27285)
			(xy 85.461094 -227.372672)
		)
		(stroke
			(width 0)
			(type solid)
		)
		(fill yes)
		(layer "In4.Cu")
		(net "M_D_CPU1_SA_DQS_DN<0>")
	)
	(gr_poly
		(pts
			(xy 85.56117 -226.056444) (xy 85.461094 -225.956368) (xy 85.361018 -226.056444) (xy 85.361018 -226.100894)
			(xy 85.56117 -226.100894)
		)
		(stroke
			(width 0)
			(type solid)
		)
		(fill yes)
		(layer "In4.Cu")
		(net "M_D_CPU1_SA_DQ<1>")
	)
	(gr_poly
		(pts
			(xy 85.56117 -225.652584) (xy 85.56117 -225.608134) (xy 85.361018 -225.608134) (xy 85.361018 -225.652584)
			(xy 85.461094 -225.75266)
		)
		(stroke
			(width 0)
			(type solid)
		)
		(fill yes)
		(layer "In4.Cu")
		(net "M_D_CPU1_SA_DQ<2>")
	)
	(gr_poly
		(pts
			(xy 85.854794 -267.801852) (xy 85.754718 -267.701776) (xy 85.654896 -267.801852) (xy 85.654896 -267.846302)
			(xy 85.854794 -267.846302)
		)
		(stroke
			(width 0)
			(type solid)
		)
		(fill yes)
		(layer "In4.Cu")
		(net "M_D_CPU1_SB_RSP<0>")
	)
	(gr_poly
		(pts
			(xy 85.861144 -293.32428) (xy 85.861144 -293.27983) (xy 85.660992 -293.27983) (xy 85.660992 -293.32428)
			(xy 85.761068 -293.424356)
		)
		(stroke
			(width 0)
			(type solid)
		)
		(fill yes)
		(layer "In4.Cu")
		(net "M_D_CPU1_SB_DQ<31>")
	)
	(gr_poly
		(pts
			(xy 85.861144 -292.108128) (xy 85.761068 -292.008052) (xy 85.660992 -292.108128) (xy 85.660992 -292.152578)
			(xy 85.861144 -292.152578)
		)
		(stroke
			(width 0)
			(type solid)
		)
		(fill yes)
		(layer "In4.Cu")
		(net "M_D_CPU1_SB_DQ<28>")
	)
	(gr_poly
		(pts
			(xy 85.861144 -291.704522) (xy 85.861144 -291.65677) (xy 85.660992 -291.65677) (xy 85.660992 -291.704522)
			(xy 85.761068 -291.804344)
		)
		(stroke
			(width 0)
			(type solid)
		)
		(fill yes)
		(layer "In4.Cu")
		(net "M_D_CPU1_SB_DQS_DP<8>")
	)
	(gr_poly
		(pts
			(xy 85.861144 -290.487862) (xy 85.761068 -290.38804) (xy 85.660992 -290.487862) (xy 85.660992 -290.535614)
			(xy 85.861144 -290.535614)
		)
		(stroke
			(width 0)
			(type solid)
		)
		(fill yes)
		(layer "In4.Cu")
		(net "M_D_CPU1_SB_DQS_DP<3>")
	)
	(gr_poly
		(pts
			(xy 85.861144 -290.084256) (xy 85.861144 -290.039806) (xy 85.660992 -290.039806) (xy 85.660992 -290.084256)
			(xy 85.761068 -290.184332)
		)
		(stroke
			(width 0)
			(type solid)
		)
		(fill yes)
		(layer "In4.Cu")
		(net "M_D_CPU1_SB_DQ<27>")
	)
	(gr_poly
		(pts
			(xy 85.861144 -288.868104) (xy 85.761068 -288.768028) (xy 85.660992 -288.868104) (xy 85.660992 -288.912554)
			(xy 85.861144 -288.912554)
		)
		(stroke
			(width 0)
			(type solid)
		)
		(fill yes)
		(layer "In4.Cu")
		(net "M_D_CPU1_SB_DQ<24>")
	)
	(gr_poly
		(pts
			(xy 85.861144 -288.464498) (xy 85.861144 -288.420048) (xy 85.660992 -288.420048) (xy 85.660992 -288.464498)
			(xy 85.761068 -288.564574)
		)
		(stroke
			(width 0)
			(type solid)
		)
		(fill yes)
		(layer "In4.Cu")
		(net "M_D_CPU1_SB_DQ<23>")
	)
	(gr_poly
		(pts
			(xy 85.861144 -287.248092) (xy 85.761068 -287.148016) (xy 85.660992 -287.248092) (xy 85.660992 -287.292542)
			(xy 85.861144 -287.292542)
		)
		(stroke
			(width 0)
			(type solid)
		)
		(fill yes)
		(layer "In4.Cu")
		(net "M_D_CPU1_SB_DQ<20>")
	)
	(gr_poly
		(pts
			(xy 85.861144 -286.844486) (xy 85.861144 -286.796734) (xy 85.660992 -286.796734) (xy 85.660992 -286.844486)
			(xy 85.761068 -286.944562)
		)
		(stroke
			(width 0)
			(type solid)
		)
		(fill yes)
		(layer "In4.Cu")
		(net "M_D_CPU1_SB_DQS_DP<7>")
	)
	(gr_poly
		(pts
			(xy 85.861144 -285.62808) (xy 85.761068 -285.528258) (xy 85.660992 -285.62808) (xy 85.660992 -285.675832)
			(xy 85.861144 -285.675832)
		)
		(stroke
			(width 0)
			(type solid)
		)
		(fill yes)
		(layer "In4.Cu")
		(net "M_D_CPU1_SB_DQS_DP<2>")
	)
	(gr_poly
		(pts
			(xy 85.861144 -285.224474) (xy 85.861144 -285.180024) (xy 85.660992 -285.180024) (xy 85.660992 -285.224474)
			(xy 85.761068 -285.32455)
		)
		(stroke
			(width 0)
			(type solid)
		)
		(fill yes)
		(layer "In4.Cu")
		(net "M_D_CPU1_SB_DQ<19>")
	)
	(gr_poly
		(pts
			(xy 85.861144 -284.008322) (xy 85.761068 -283.908246) (xy 85.660992 -284.008322) (xy 85.660992 -284.052772)
			(xy 85.861144 -284.052772)
		)
		(stroke
			(width 0)
			(type solid)
		)
		(fill yes)
		(layer "In4.Cu")
		(net "M_D_CPU1_SB_DQ<16>")
	)
	(gr_poly
		(pts
			(xy 85.861144 -283.604462) (xy 85.861144 -283.560012) (xy 85.660992 -283.560012) (xy 85.660992 -283.604462)
			(xy 85.761068 -283.704538)
		)
		(stroke
			(width 0)
			(type solid)
		)
		(fill yes)
		(layer "In4.Cu")
		(net "M_D_CPU1_SB_DQ<15>")
	)
	(gr_poly
		(pts
			(xy 85.861144 -282.38831) (xy 85.761068 -282.288234) (xy 85.660992 -282.38831) (xy 85.660992 -282.43276)
			(xy 85.861144 -282.43276)
		)
		(stroke
			(width 0)
			(type solid)
		)
		(fill yes)
		(layer "In4.Cu")
		(net "M_D_CPU1_SB_DQ<12>")
	)
	(gr_poly
		(pts
			(xy 85.861144 -281.984704) (xy 85.861144 -281.936952) (xy 85.660992 -281.936952) (xy 85.660992 -281.984704)
			(xy 85.761068 -282.084526)
		)
		(stroke
			(width 0)
			(type solid)
		)
		(fill yes)
		(layer "In4.Cu")
		(net "M_D_CPU1_SB_DQS_DP<6>")
	)
	(gr_poly
		(pts
			(xy 85.861144 -280.768044) (xy 85.761068 -280.668222) (xy 85.660992 -280.768044) (xy 85.660992 -280.815796)
			(xy 85.861144 -280.815796)
		)
		(stroke
			(width 0)
			(type solid)
		)
		(fill yes)
		(layer "In4.Cu")
		(net "M_D_CPU1_SB_DQS_DP<1>")
	)
	(gr_poly
		(pts
			(xy 85.861144 -280.364438) (xy 85.861144 -280.319988) (xy 85.660992 -280.319988) (xy 85.660992 -280.364438)
			(xy 85.761068 -280.464514)
		)
		(stroke
			(width 0)
			(type solid)
		)
		(fill yes)
		(layer "In4.Cu")
		(net "M_D_CPU1_SB_DQ<11>")
	)
	(gr_poly
		(pts
			(xy 85.861144 -279.148286) (xy 85.761068 -279.04821) (xy 85.660992 -279.148286) (xy 85.660992 -279.192736)
			(xy 85.861144 -279.192736)
		)
		(stroke
			(width 0)
			(type solid)
		)
		(fill yes)
		(layer "In4.Cu")
		(net "M_D_CPU1_SB_DQ<8>")
	)
	(gr_poly
		(pts
			(xy 85.861144 -278.744426) (xy 85.861144 -278.699976) (xy 85.660992 -278.699976) (xy 85.660992 -278.744426)
			(xy 85.761068 -278.844502)
		)
		(stroke
			(width 0)
			(type solid)
		)
		(fill yes)
		(layer "In4.Cu")
		(net "M_D_CPU1_SB_DQ<7>")
	)
	(gr_poly
		(pts
			(xy 85.861144 -277.528274) (xy 85.761068 -277.428198) (xy 85.660992 -277.528274) (xy 85.660992 -277.572724)
			(xy 85.861144 -277.572724)
		)
		(stroke
			(width 0)
			(type solid)
		)
		(fill yes)
		(layer "In4.Cu")
		(net "M_D_CPU1_SB_DQ<4>")
	)
	(gr_poly
		(pts
			(xy 85.861144 -277.124668) (xy 85.861144 -277.076916) (xy 85.660992 -277.076916) (xy 85.660992 -277.124668)
			(xy 85.761068 -277.22449)
		)
		(stroke
			(width 0)
			(type solid)
		)
		(fill yes)
		(layer "In4.Cu")
		(net "M_D_CPU1_SB_DQS_DP<5>")
	)
	(gr_poly
		(pts
			(xy 85.861144 -275.908008) (xy 85.761068 -275.808186) (xy 85.660992 -275.908008) (xy 85.660992 -275.95576)
			(xy 85.861144 -275.95576)
		)
		(stroke
			(width 0)
			(type solid)
		)
		(fill yes)
		(layer "In4.Cu")
		(net "M_D_CPU1_SB_DQS_DP<0>")
	)
	(gr_poly
		(pts
			(xy 85.861144 -275.504402) (xy 85.861144 -275.459952) (xy 85.660992 -275.459952) (xy 85.660992 -275.504402)
			(xy 85.761068 -275.604478)
		)
		(stroke
			(width 0)
			(type solid)
		)
		(fill yes)
		(layer "In4.Cu")
		(net "M_D_CPU1_SB_DQ<3>")
	)
	(gr_poly
		(pts
			(xy 85.861144 -274.28825) (xy 85.761068 -274.188174) (xy 85.660992 -274.28825) (xy 85.660992 -274.3327)
			(xy 85.861144 -274.3327)
		)
		(stroke
			(width 0)
			(type solid)
		)
		(fill yes)
		(layer "In4.Cu")
		(net "M_D_CPU1_SB_DQ<0>")
	)
	(gr_poly
		(pts
			(xy 85.861144 -273.88439) (xy 85.861144 -273.83994) (xy 85.660992 -273.83994) (xy 85.660992 -273.88439)
			(xy 85.761068 -273.984466)
		)
		(stroke
			(width 0)
			(type solid)
		)
		(fill yes)
		(layer "In4.Cu")
		(net "M_D_CPU1_SB_CB<3>")
	)
	(gr_poly
		(pts
			(xy 85.861144 -272.668238) (xy 85.761068 -272.568162) (xy 85.660992 -272.668238) (xy 85.660992 -272.712688)
			(xy 85.861144 -272.712688)
		)
		(stroke
			(width 0)
			(type solid)
		)
		(fill yes)
		(layer "In4.Cu")
		(net "M_D_CPU1_SB_CB<0>")
	)
	(gr_poly
		(pts
			(xy 85.861144 -272.264632) (xy 85.861144 -272.21688) (xy 85.660992 -272.21688) (xy 85.660992 -272.264632)
			(xy 85.761068 -272.364454)
		)
		(stroke
			(width 0)
			(type solid)
		)
		(fill yes)
		(layer "In4.Cu")
		(net "M_D_CPU1_SB_DQS_DP<4>")
	)
	(gr_poly
		(pts
			(xy 85.861144 -271.047972) (xy 85.761068 -270.94815) (xy 85.660992 -271.047972) (xy 85.660992 -271.095724)
			(xy 85.861144 -271.095724)
		)
		(stroke
			(width 0)
			(type solid)
		)
		(fill yes)
		(layer "In4.Cu")
		(net "M_D_CPU1_SB_DQS_DP<9>")
	)
	(gr_poly
		(pts
			(xy 85.861144 -270.644366) (xy 85.861144 -270.599916) (xy 85.660992 -270.599916) (xy 85.660992 -270.644366)
			(xy 85.761068 -270.744442)
		)
		(stroke
			(width 0)
			(type solid)
		)
		(fill yes)
		(layer "In4.Cu")
		(net "M_D_CPU1_SB_CB<7>")
	)
	(gr_poly
		(pts
			(xy 85.861144 -269.428214) (xy 85.761068 -269.328138) (xy 85.660992 -269.428214) (xy 85.660992 -269.472664)
			(xy 85.861144 -269.472664)
		)
		(stroke
			(width 0)
			(type solid)
		)
		(fill yes)
		(layer "In4.Cu")
		(net "M_D_CPU1_SB_CB<4>")
	)
	(gr_poly
		(pts
			(xy 85.861144 -265.78433) (xy 85.861144 -265.73988) (xy 85.660992 -265.73988) (xy 85.660992 -265.78433)
			(xy 85.761068 -265.884406)
		)
		(stroke
			(width 0)
			(type solid)
		)
		(fill yes)
		(layer "In4.Cu")
		(net "M_D_CPU1_SB_CS_N<0>")
	)
	(gr_poly
		(pts
			(xy 85.861144 -264.568178) (xy 85.761068 -264.468102) (xy 85.660992 -264.568178) (xy 85.660992 -264.612628)
			(xy 85.861144 -264.612628)
		)
		(stroke
			(width 0)
			(type solid)
		)
		(fill yes)
		(layer "In4.Cu")
		(net "M_D_CPU1_SB_CA<6>")
	)
	(gr_poly
		(pts
			(xy 85.861144 -264.164318) (xy 85.861144 -264.119868) (xy 85.660992 -264.119868) (xy 85.660992 -264.164318)
			(xy 85.761068 -264.264394)
		)
		(stroke
			(width 0)
			(type solid)
		)
		(fill yes)
		(layer "In4.Cu")
		(net "M_D_CPU1_SB_CA<5>")
	)
	(gr_poly
		(pts
			(xy 85.861144 -262.948166) (xy 85.761068 -262.84809) (xy 85.660992 -262.948166) (xy 85.660992 -262.992616)
			(xy 85.861144 -262.992616)
		)
		(stroke
			(width 0)
			(type solid)
		)
		(fill yes)
		(layer "In4.Cu")
		(net "M_D_CPU1_SB_CA<2>")
	)
	(gr_poly
		(pts
			(xy 85.861144 -262.544306) (xy 85.861144 -262.499856) (xy 85.660992 -262.499856) (xy 85.660992 -262.544306)
			(xy 85.761068 -262.644382)
		)
		(stroke
			(width 0)
			(type solid)
		)
		(fill yes)
		(layer "In4.Cu")
		(net "M_D_CPU1_SB_CA<1>")
	)
	(gr_poly
		(pts
			(xy 86.03107 -256.026158) (xy 85.930994 -255.926336) (xy 85.830918 -256.026158) (xy 85.830918 -256.07391)
			(xy 86.03107 -256.07391)
		)
		(stroke
			(width 0)
			(type solid)
		)
		(fill yes)
		(layer "In4.Cu")
		(net "M_D_CPU1_CLK_DP<0>")
	)
	(gr_poly
		(pts
			(xy 86.03107 -255.622552) (xy 86.03107 -255.578102) (xy 85.830918 -255.578102) (xy 85.830918 -255.622552)
			(xy 85.930994 -255.722628)
		)
		(stroke
			(width 0)
			(type solid)
		)
		(fill yes)
		(layer "In4.Cu")
		(net "M_D_CPU1_SA_PAR")
	)
	(gr_poly
		(pts
			(xy 86.03107 -254.4064) (xy 85.930994 -254.306324) (xy 85.830918 -254.4064) (xy 85.830918 -254.45085)
			(xy 86.03107 -254.45085)
		)
		(stroke
			(width 0)
			(type solid)
		)
		(fill yes)
		(layer "In4.Cu")
		(net "M_D_CPU1_SA_CA<4>")
	)
	(gr_poly
		(pts
			(xy 86.03107 -254.00254) (xy 86.03107 -253.95809) (xy 85.830918 -253.95809) (xy 85.830918 -254.00254)
			(xy 85.930994 -254.102616)
		)
		(stroke
			(width 0)
			(type solid)
		)
		(fill yes)
		(layer "In4.Cu")
		(net "M_D_CPU1_SA_CA<3>")
	)
	(gr_poly
		(pts
			(xy 86.03107 -252.786388) (xy 85.930994 -252.686312) (xy 85.830918 -252.786388) (xy 85.830918 -252.830838)
			(xy 86.03107 -252.830838)
		)
		(stroke
			(width 0)
			(type solid)
		)
		(fill yes)
		(layer "In4.Cu")
		(net "M_D_CPU1_SA_CA<0>")
	)
	(gr_poly
		(pts
			(xy 86.03107 -252.382528) (xy 86.03107 -252.338078) (xy 85.830918 -252.338078) (xy 85.830918 -252.382528)
			(xy 85.930994 -252.482604)
		)
		(stroke
			(width 0)
			(type solid)
		)
		(fill yes)
		(layer "In4.Cu")
		(net "M_D_CPU1_SA_CS_N<1>")
	)
	(gr_poly
		(pts
			(xy 86.03107 -250.762516) (xy 86.03107 -250.718066) (xy 85.830918 -250.718066) (xy 85.830918 -250.762516)
			(xy 85.930994 -250.862592)
		)
		(stroke
			(width 0)
			(type solid)
		)
		(fill yes)
		(layer "In4.Cu")
		(net "M_D_CPU1_RESET_N")
	)
	(gr_poly
		(pts
			(xy 86.03107 -249.142504) (xy 86.03107 -249.098054) (xy 85.830918 -249.098054) (xy 85.830918 -249.142504)
			(xy 85.930994 -249.24258)
		)
		(stroke
			(width 0)
			(type solid)
		)
		(fill yes)
		(layer "In4.Cu")
		(net "M_D_CPU1_SA_CB<7>")
	)
	(gr_poly
		(pts
			(xy 86.03107 -247.926352) (xy 85.930994 -247.826276) (xy 85.830918 -247.926352) (xy 85.830918 -247.970802)
			(xy 86.03107 -247.970802)
		)
		(stroke
			(width 0)
			(type solid)
		)
		(fill yes)
		(layer "In4.Cu")
		(net "M_D_CPU1_SA_CB<4>")
	)
	(gr_poly
		(pts
			(xy 86.03107 -247.522746) (xy 86.03107 -247.474994) (xy 85.830918 -247.474994) (xy 85.830918 -247.522746)
			(xy 85.930994 -247.622568)
		)
		(stroke
			(width 0)
			(type solid)
		)
		(fill yes)
		(layer "In4.Cu")
		(net "M_D_CPU1_SA_DQS_DP<9>")
	)
	(gr_poly
		(pts
			(xy 86.03107 -246.306086) (xy 85.930994 -246.206264) (xy 85.830918 -246.306086) (xy 85.830918 -246.353838)
			(xy 86.03107 -246.353838)
		)
		(stroke
			(width 0)
			(type solid)
		)
		(fill yes)
		(layer "In4.Cu")
		(net "M_D_CPU1_SA_DQS_DP<4>")
	)
	(gr_poly
		(pts
			(xy 86.03107 -245.90248) (xy 86.03107 -245.85803) (xy 85.830918 -245.85803) (xy 85.830918 -245.90248)
			(xy 85.930994 -246.002556)
		)
		(stroke
			(width 0)
			(type solid)
		)
		(fill yes)
		(layer "In4.Cu")
		(net "M_D_CPU1_SA_CB<3>")
	)
	(gr_poly
		(pts
			(xy 86.03107 -244.686328) (xy 85.930994 -244.586252) (xy 85.830918 -244.686328) (xy 85.830918 -244.730778)
			(xy 86.03107 -244.730778)
		)
		(stroke
			(width 0)
			(type solid)
		)
		(fill yes)
		(layer "In4.Cu")
		(net "M_D_CPU1_SA_CB<0>")
	)
	(gr_poly
		(pts
			(xy 86.03107 -244.282468) (xy 86.03107 -244.238018) (xy 85.830918 -244.238018) (xy 85.830918 -244.282468)
			(xy 85.930994 -244.382544)
		)
		(stroke
			(width 0)
			(type solid)
		)
		(fill yes)
		(layer "In4.Cu")
		(net "M_D_CPU1_SA_DQ<31>")
	)
	(gr_poly
		(pts
			(xy 86.03107 -243.066316) (xy 85.930994 -242.96624) (xy 85.830918 -243.066316) (xy 85.830918 -243.110766)
			(xy 86.03107 -243.110766)
		)
		(stroke
			(width 0)
			(type solid)
		)
		(fill yes)
		(layer "In4.Cu")
		(net "M_D_CPU1_SA_DQ<28>")
	)
	(gr_poly
		(pts
			(xy 86.03107 -242.66271) (xy 86.03107 -242.614958) (xy 85.830918 -242.614958) (xy 85.830918 -242.66271)
			(xy 85.930994 -242.762532)
		)
		(stroke
			(width 0)
			(type solid)
		)
		(fill yes)
		(layer "In4.Cu")
		(net "M_D_CPU1_SA_DQS_DP<8>")
	)
	(gr_poly
		(pts
			(xy 86.03107 -241.44605) (xy 85.930994 -241.346228) (xy 85.830918 -241.44605) (xy 85.830918 -241.493802)
			(xy 86.03107 -241.493802)
		)
		(stroke
			(width 0)
			(type solid)
		)
		(fill yes)
		(layer "In4.Cu")
		(net "M_D_CPU1_SA_DQS_DP<3>")
	)
	(gr_poly
		(pts
			(xy 86.03107 -241.042444) (xy 86.03107 -240.997994) (xy 85.830918 -240.997994) (xy 85.830918 -241.042444)
			(xy 85.930994 -241.14252)
		)
		(stroke
			(width 0)
			(type solid)
		)
		(fill yes)
		(layer "In4.Cu")
		(net "M_D_CPU1_SA_DQ<27>")
	)
	(gr_poly
		(pts
			(xy 86.03107 -239.826292) (xy 85.930994 -239.726216) (xy 85.830918 -239.826292) (xy 85.830918 -239.870742)
			(xy 86.03107 -239.870742)
		)
		(stroke
			(width 0)
			(type solid)
		)
		(fill yes)
		(layer "In4.Cu")
		(net "M_D_CPU1_SA_DQ<24>")
	)
	(gr_poly
		(pts
			(xy 86.03107 -239.422432) (xy 86.03107 -239.377982) (xy 85.830918 -239.377982) (xy 85.830918 -239.422432)
			(xy 85.930994 -239.522508)
		)
		(stroke
			(width 0)
			(type solid)
		)
		(fill yes)
		(layer "In4.Cu")
		(net "M_D_CPU1_SA_DQ<23>")
	)
	(gr_poly
		(pts
			(xy 86.03107 -238.20628) (xy 85.930994 -238.106204) (xy 85.830918 -238.20628) (xy 85.830918 -238.25073)
			(xy 86.03107 -238.25073)
		)
		(stroke
			(width 0)
			(type solid)
		)
		(fill yes)
		(layer "In4.Cu")
		(net "M_D_CPU1_SA_DQ<20>")
	)
	(gr_poly
		(pts
			(xy 86.03107 -237.802674) (xy 86.03107 -237.754922) (xy 85.830918 -237.754922) (xy 85.830918 -237.802674)
			(xy 85.930994 -237.902496)
		)
		(stroke
			(width 0)
			(type solid)
		)
		(fill yes)
		(layer "In4.Cu")
		(net "M_D_CPU1_SA_DQS_DP<7>")
	)
	(gr_poly
		(pts
			(xy 86.03107 -236.586014) (xy 85.930994 -236.486192) (xy 85.830918 -236.586014) (xy 85.830918 -236.633766)
			(xy 86.03107 -236.633766)
		)
		(stroke
			(width 0)
			(type solid)
		)
		(fill yes)
		(layer "In4.Cu")
		(net "M_D_CPU1_SA_DQS_DP<2>")
	)
	(gr_poly
		(pts
			(xy 86.03107 -236.182408) (xy 86.03107 -236.137958) (xy 85.830918 -236.137958) (xy 85.830918 -236.182408)
			(xy 85.930994 -236.282484)
		)
		(stroke
			(width 0)
			(type solid)
		)
		(fill yes)
		(layer "In4.Cu")
		(net "M_D_CPU1_SA_DQ<19>")
	)
	(gr_poly
		(pts
			(xy 86.03107 -234.966256) (xy 85.930994 -234.86618) (xy 85.830918 -234.966256) (xy 85.830918 -235.010706)
			(xy 86.03107 -235.010706)
		)
		(stroke
			(width 0)
			(type solid)
		)
		(fill yes)
		(layer "In4.Cu")
		(net "M_D_CPU1_SA_DQ<16>")
	)
	(gr_poly
		(pts
			(xy 86.03107 -234.562396) (xy 86.03107 -234.517946) (xy 85.830918 -234.517946) (xy 85.830918 -234.562396)
			(xy 85.930994 -234.662472)
		)
		(stroke
			(width 0)
			(type solid)
		)
		(fill yes)
		(layer "In4.Cu")
		(net "M_D_CPU1_SA_DQ<15>")
	)
	(gr_poly
		(pts
			(xy 86.03107 -233.346244) (xy 85.930994 -233.246168) (xy 85.830918 -233.346244) (xy 85.830918 -233.390694)
			(xy 86.03107 -233.390694)
		)
		(stroke
			(width 0)
			(type solid)
		)
		(fill yes)
		(layer "In4.Cu")
		(net "M_D_CPU1_SA_DQ<12>")
	)
	(gr_poly
		(pts
			(xy 86.03107 -232.942638) (xy 86.03107 -232.894886) (xy 85.830918 -232.894886) (xy 85.830918 -232.942638)
			(xy 85.930994 -233.04246)
		)
		(stroke
			(width 0)
			(type solid)
		)
		(fill yes)
		(layer "In4.Cu")
		(net "M_D_CPU1_SA_DQS_DP<6>")
	)
	(gr_poly
		(pts
			(xy 86.03107 -231.725978) (xy 85.930994 -231.626156) (xy 85.830918 -231.725978) (xy 85.830918 -231.77373)
			(xy 86.03107 -231.77373)
		)
		(stroke
			(width 0)
			(type solid)
		)
		(fill yes)
		(layer "In4.Cu")
		(net "M_D_CPU1_SA_DQS_DP<1>")
	)
	(gr_poly
		(pts
			(xy 86.03107 -231.322626) (xy 86.03107 -231.278176) (xy 85.830918 -231.278176) (xy 85.830918 -231.322626)
			(xy 85.930994 -231.422702)
		)
		(stroke
			(width 0)
			(type solid)
		)
		(fill yes)
		(layer "In4.Cu")
		(net "M_D_CPU1_SA_DQ<11>")
	)
	(gr_poly
		(pts
			(xy 86.03107 -230.10622) (xy 85.930994 -230.006144) (xy 85.830918 -230.10622) (xy 85.830918 -230.15067)
			(xy 86.03107 -230.15067)
		)
		(stroke
			(width 0)
			(type solid)
		)
		(fill yes)
		(layer "In4.Cu")
		(net "M_D_CPU1_SA_DQ<8>")
	)
	(gr_poly
		(pts
			(xy 86.03107 -229.702614) (xy 86.03107 -229.658164) (xy 85.830918 -229.658164) (xy 85.830918 -229.702614)
			(xy 85.930994 -229.80269)
		)
		(stroke
			(width 0)
			(type solid)
		)
		(fill yes)
		(layer "In4.Cu")
		(net "M_D_CPU1_SA_DQ<7>")
	)
	(gr_poly
		(pts
			(xy 86.03107 -228.486462) (xy 85.930994 -228.386386) (xy 85.830918 -228.486462) (xy 85.830918 -228.530912)
			(xy 86.03107 -228.530912)
		)
		(stroke
			(width 0)
			(type solid)
		)
		(fill yes)
		(layer "In4.Cu")
		(net "M_D_CPU1_SA_DQ<4>")
	)
	(gr_poly
		(pts
			(xy 86.03107 -228.082856) (xy 86.03107 -228.035104) (xy 85.830918 -228.035104) (xy 85.830918 -228.082856)
			(xy 85.930994 -228.182678)
		)
		(stroke
			(width 0)
			(type solid)
		)
		(fill yes)
		(layer "In4.Cu")
		(net "M_D_CPU1_SA_DQS_DP<5>")
	)
	(gr_poly
		(pts
			(xy 86.03107 -226.866196) (xy 85.930994 -226.766374) (xy 85.830918 -226.866196) (xy 85.830918 -226.913948)
			(xy 86.03107 -226.913948)
		)
		(stroke
			(width 0)
			(type solid)
		)
		(fill yes)
		(layer "In4.Cu")
		(net "M_D_CPU1_SA_DQS_DP<0>")
	)
	(gr_poly
		(pts
			(xy 86.03107 -226.46259) (xy 86.03107 -226.41814) (xy 85.830918 -226.41814) (xy 85.830918 -226.46259)
			(xy 85.930994 -226.562666)
		)
		(stroke
			(width 0)
			(type solid)
		)
		(fill yes)
		(layer "In4.Cu")
		(net "M_D_CPU1_SA_DQ<3>")
	)
	(gr_poly
		(pts
			(xy 86.03107 -225.246438) (xy 85.930994 -225.146362) (xy 85.830918 -225.246438) (xy 85.830918 -225.290888)
			(xy 86.03107 -225.290888)
		)
		(stroke
			(width 0)
			(type solid)
		)
		(fill yes)
		(layer "In4.Cu")
		(net "M_D_CPU1_SA_DQ<0>")
	)
	(gr_poly
		(pts
			(xy 86.331044 -292.918134) (xy 86.230968 -292.818058) (xy 86.130892 -292.918134) (xy 86.130892 -292.962584)
			(xy 86.331044 -292.962584)
		)
		(stroke
			(width 0)
			(type solid)
		)
		(fill yes)
		(layer "In4.Cu")
		(net "M_D_CPU1_SB_DQ<29>")
	)
	(gr_poly
		(pts
			(xy 86.331044 -292.514274) (xy 86.331044 -292.469824) (xy 86.130892 -292.469824) (xy 86.130892 -292.514274)
			(xy 86.230968 -292.61435)
		)
		(stroke
			(width 0)
			(type solid)
		)
		(fill yes)
		(layer "In4.Cu")
		(net "M_D_CPU1_SB_DQ<30>")
	)
	(gr_poly
		(pts
			(xy 86.331044 -291.297868) (xy 86.230968 -291.198046) (xy 86.130892 -291.297868) (xy 86.130892 -291.34562)
			(xy 86.331044 -291.34562)
		)
		(stroke
			(width 0)
			(type solid)
		)
		(fill yes)
		(layer "In4.Cu")
		(net "M_D_CPU1_SB_DQS_DN<8>")
	)
	(gr_poly
		(pts
			(xy 86.331044 -290.894516) (xy 86.331044 -290.846764) (xy 86.130892 -290.846764) (xy 86.130892 -290.894516)
			(xy 86.230968 -290.994338)
		)
		(stroke
			(width 0)
			(type solid)
		)
		(fill yes)
		(layer "In4.Cu")
		(net "M_D_CPU1_SB_DQS_DN<3>")
	)
	(gr_poly
		(pts
			(xy 86.331044 -289.67811) (xy 86.230968 -289.578034) (xy 86.130892 -289.67811) (xy 86.130892 -289.72256)
			(xy 86.331044 -289.72256)
		)
		(stroke
			(width 0)
			(type solid)
		)
		(fill yes)
		(layer "In4.Cu")
		(net "M_D_CPU1_SB_DQ<25>")
	)
	(gr_poly
		(pts
			(xy 86.331044 -289.27425) (xy 86.331044 -289.2298) (xy 86.130892 -289.2298) (xy 86.130892 -289.27425)
			(xy 86.230968 -289.374326)
		)
		(stroke
			(width 0)
			(type solid)
		)
		(fill yes)
		(layer "In4.Cu")
		(net "M_D_CPU1_SB_DQ<26>")
	)
	(gr_poly
		(pts
			(xy 86.331044 -288.058098) (xy 86.230968 -287.958022) (xy 86.130892 -288.058098) (xy 86.130892 -288.102548)
			(xy 86.331044 -288.102548)
		)
		(stroke
			(width 0)
			(type solid)
		)
		(fill yes)
		(layer "In4.Cu")
		(net "M_D_CPU1_SB_DQ<21>")
	)
	(gr_poly
		(pts
			(xy 86.331044 -287.654492) (xy 86.331044 -287.610042) (xy 86.130892 -287.610042) (xy 86.130892 -287.654492)
			(xy 86.230968 -287.754568)
		)
		(stroke
			(width 0)
			(type solid)
		)
		(fill yes)
		(layer "In4.Cu")
		(net "M_D_CPU1_SB_DQ<22>")
	)
	(gr_poly
		(pts
			(xy 86.331044 -286.438086) (xy 86.230968 -286.33801) (xy 86.130892 -286.438086) (xy 86.130892 -286.485838)
			(xy 86.331044 -286.485838)
		)
		(stroke
			(width 0)
			(type solid)
		)
		(fill yes)
		(layer "In4.Cu")
		(net "M_D_CPU1_SB_DQS_DN<7>")
	)
	(gr_poly
		(pts
			(xy 86.331044 -286.034734) (xy 86.331044 -285.986982) (xy 86.130892 -285.986982) (xy 86.130892 -286.034734)
			(xy 86.230968 -286.134556)
		)
		(stroke
			(width 0)
			(type solid)
		)
		(fill yes)
		(layer "In4.Cu")
		(net "M_D_CPU1_SB_DQS_DN<2>")
	)
	(gr_poly
		(pts
			(xy 86.331044 -284.818328) (xy 86.230968 -284.718252) (xy 86.130892 -284.818328) (xy 86.130892 -284.862778)
			(xy 86.331044 -284.862778)
		)
		(stroke
			(width 0)
			(type solid)
		)
		(fill yes)
		(layer "In4.Cu")
		(net "M_D_CPU1_SB_DQ<17>")
	)
	(gr_poly
		(pts
			(xy 86.331044 -284.414468) (xy 86.331044 -284.370018) (xy 86.130892 -284.370018) (xy 86.130892 -284.414468)
			(xy 86.230968 -284.514544)
		)
		(stroke
			(width 0)
			(type solid)
		)
		(fill yes)
		(layer "In4.Cu")
		(net "M_D_CPU1_SB_DQ<18>")
	)
	(gr_poly
		(pts
			(xy 86.331044 -283.198316) (xy 86.230968 -283.09824) (xy 86.130892 -283.198316) (xy 86.130892 -283.242766)
			(xy 86.331044 -283.242766)
		)
		(stroke
			(width 0)
			(type solid)
		)
		(fill yes)
		(layer "In4.Cu")
		(net "M_D_CPU1_SB_DQ<13>")
	)
	(gr_poly
		(pts
			(xy 86.331044 -282.794456) (xy 86.331044 -282.750006) (xy 86.130892 -282.750006) (xy 86.130892 -282.794456)
			(xy 86.230968 -282.894532)
		)
		(stroke
			(width 0)
			(type solid)
		)
		(fill yes)
		(layer "In4.Cu")
		(net "M_D_CPU1_SB_DQ<14>")
	)
	(gr_poly
		(pts
			(xy 86.331044 -281.57805) (xy 86.230968 -281.478228) (xy 86.130892 -281.57805) (xy 86.130892 -281.625802)
			(xy 86.331044 -281.625802)
		)
		(stroke
			(width 0)
			(type solid)
		)
		(fill yes)
		(layer "In4.Cu")
		(net "M_D_CPU1_SB_DQS_DN<6>")
	)
	(gr_poly
		(pts
			(xy 86.331044 -281.174698) (xy 86.331044 -281.126946) (xy 86.130892 -281.126946) (xy 86.130892 -281.174698)
			(xy 86.230968 -281.27452)
		)
		(stroke
			(width 0)
			(type solid)
		)
		(fill yes)
		(layer "In4.Cu")
		(net "M_D_CPU1_SB_DQS_DN<1>")
	)
	(gr_poly
		(pts
			(xy 86.331044 -279.958292) (xy 86.230968 -279.858216) (xy 86.130892 -279.958292) (xy 86.130892 -280.002742)
			(xy 86.331044 -280.002742)
		)
		(stroke
			(width 0)
			(type solid)
		)
		(fill yes)
		(layer "In4.Cu")
		(net "M_D_CPU1_SB_DQ<9>")
	)
	(gr_poly
		(pts
			(xy 86.331044 -279.554432) (xy 86.331044 -279.509982) (xy 86.130892 -279.509982) (xy 86.130892 -279.554432)
			(xy 86.230968 -279.654508)
		)
		(stroke
			(width 0)
			(type solid)
		)
		(fill yes)
		(layer "In4.Cu")
		(net "M_D_CPU1_SB_DQ<10>")
	)
	(gr_poly
		(pts
			(xy 86.331044 -278.33828) (xy 86.230968 -278.238204) (xy 86.130892 -278.33828) (xy 86.130892 -278.38273)
			(xy 86.331044 -278.38273)
		)
		(stroke
			(width 0)
			(type solid)
		)
		(fill yes)
		(layer "In4.Cu")
		(net "M_D_CPU1_SB_DQ<5>")
	)
	(gr_poly
		(pts
			(xy 86.331044 -277.93442) (xy 86.331044 -277.88997) (xy 86.130892 -277.88997) (xy 86.130892 -277.93442)
			(xy 86.230968 -278.034496)
		)
		(stroke
			(width 0)
			(type solid)
		)
		(fill yes)
		(layer "In4.Cu")
		(net "M_D_CPU1_SB_DQ<6>")
	)
	(gr_poly
		(pts
			(xy 86.331044 -275.098256) (xy 86.230968 -274.99818) (xy 86.130892 -275.098256) (xy 86.130892 -275.142706)
			(xy 86.331044 -275.142706)
		)
		(stroke
			(width 0)
			(type solid)
		)
		(fill yes)
		(layer "In4.Cu")
		(net "M_D_CPU1_SB_DQ<1>")
	)
	(gr_poly
		(pts
			(xy 86.331044 -274.694396) (xy 86.331044 -274.649946) (xy 86.130892 -274.649946) (xy 86.130892 -274.694396)
			(xy 86.230968 -274.794472)
		)
		(stroke
			(width 0)
			(type solid)
		)
		(fill yes)
		(layer "In4.Cu")
		(net "M_D_CPU1_SB_DQ<2>")
	)
	(gr_poly
		(pts
			(xy 86.331044 -273.478244) (xy 86.230968 -273.378168) (xy 86.130892 -273.478244) (xy 86.130892 -273.522694)
			(xy 86.331044 -273.522694)
		)
		(stroke
			(width 0)
			(type solid)
		)
		(fill yes)
		(layer "In4.Cu")
		(net "M_D_CPU1_SB_CB<1>")
	)
	(gr_poly
		(pts
			(xy 86.331044 -273.074384) (xy 86.331044 -273.029934) (xy 86.130892 -273.029934) (xy 86.130892 -273.074384)
			(xy 86.230968 -273.17446)
		)
		(stroke
			(width 0)
			(type solid)
		)
		(fill yes)
		(layer "In4.Cu")
		(net "M_D_CPU1_SB_CB<2>")
	)
	(gr_poly
		(pts
			(xy 86.331044 -271.857978) (xy 86.230968 -271.758156) (xy 86.130892 -271.857978) (xy 86.130892 -271.90573)
			(xy 86.331044 -271.90573)
		)
		(stroke
			(width 0)
			(type solid)
		)
		(fill yes)
		(layer "In4.Cu")
		(net "M_D_CPU1_SB_DQS_DN<4>")
	)
	(gr_poly
		(pts
			(xy 86.331044 -271.454626) (xy 86.331044 -271.406874) (xy 86.130892 -271.406874) (xy 86.130892 -271.454626)
			(xy 86.230968 -271.554448)
		)
		(stroke
			(width 0)
			(type solid)
		)
		(fill yes)
		(layer "In4.Cu")
		(net "M_D_CPU1_SB_DQS_DN<9>")
	)
	(gr_poly
		(pts
			(xy 86.331044 -270.23822) (xy 86.230968 -270.138144) (xy 86.130892 -270.23822) (xy 86.130892 -270.28267)
			(xy 86.331044 -270.28267)
		)
		(stroke
			(width 0)
			(type solid)
		)
		(fill yes)
		(layer "In4.Cu")
		(net "M_D_CPU1_SB_CB<5>")
	)
	(gr_poly
		(pts
			(xy 86.331044 -269.83436) (xy 86.331044 -269.78991) (xy 86.130892 -269.78991) (xy 86.130892 -269.83436)
			(xy 86.230968 -269.934436)
		)
		(stroke
			(width 0)
			(type solid)
		)
		(fill yes)
		(layer "In4.Cu")
		(net "M_D_CPU1_SB_CB<6>")
	)
	(gr_poly
		(pts
			(xy 86.331044 -266.594336) (xy 86.331044 -266.549886) (xy 86.130892 -266.549886) (xy 86.130892 -266.594336)
			(xy 86.230968 -266.694412)
		)
		(stroke
			(width 0)
			(type solid)
		)
		(fill yes)
		(layer "In4.Cu")
		(net "M_D_CPU1_SB_CS_N<1>")
	)
	(gr_poly
		(pts
			(xy 86.331044 -264.974324) (xy 86.331044 -264.929874) (xy 86.130892 -264.929874) (xy 86.130892 -264.974324)
			(xy 86.230968 -265.0744)
		)
		(stroke
			(width 0)
			(type solid)
		)
		(fill yes)
		(layer "In4.Cu")
		(net "M_D_CPU1_SB_PAR")
	)
	(gr_poly
		(pts
			(xy 86.331044 -263.758172) (xy 86.230968 -263.658096) (xy 86.130892 -263.758172) (xy 86.130892 -263.802622)
			(xy 86.331044 -263.802622)
		)
		(stroke
			(width 0)
			(type solid)
		)
		(fill yes)
		(layer "In4.Cu")
		(net "M_D_CPU1_SB_CA<4>")
	)
	(gr_poly
		(pts
			(xy 86.331044 -263.354312) (xy 86.331044 -263.309862) (xy 86.130892 -263.309862) (xy 86.130892 -263.354312)
			(xy 86.230968 -263.454388)
		)
		(stroke
			(width 0)
			(type solid)
		)
		(fill yes)
		(layer "In4.Cu")
		(net "M_D_CPU1_SB_CA<3>")
	)
	(gr_poly
		(pts
			(xy 86.331044 -262.13816) (xy 86.230968 -262.038084) (xy 86.130892 -262.13816) (xy 86.130892 -262.18261)
			(xy 86.331044 -262.18261)
		)
		(stroke
			(width 0)
			(type solid)
		)
		(fill yes)
		(layer "In4.Cu")
		(net "M_D_CPU1_SB_CA<0>")
	)
	(gr_poly
		(pts
			(xy 86.33714 -266.991846) (xy 86.237318 -266.89177) (xy 86.137242 -266.991846) (xy 86.137242 -267.036296)
			(xy 86.33714 -267.036296)
		)
		(stroke
			(width 0)
			(type solid)
		)
		(fill yes)
		(layer "In4.Cu")
		(net "M_D_CPU1_SA_RSP<0>")
	)
	(gr_poly
		(pts
			(xy 86.33841 -276.718268) (xy 86.238334 -276.618192) (xy 86.138258 -276.718268) (xy 86.138258 -276.765766)
			(xy 86.33841 -276.765766)
		)
		(stroke
			(width 0)
			(type solid)
		)
		(fill yes)
		(layer "In4.Cu")
		(net "M_D_CPU1_SB_DQS_DN<5>")
	)
	(gr_poly
		(pts
			(xy 86.33841 -276.314408) (xy 86.33841 -276.26691) (xy 86.138258 -276.26691) (xy 86.138258 -276.314408)
			(xy 86.238334 -276.414484)
		)
		(stroke
			(width 0)
			(type solid)
		)
		(fill yes)
		(layer "In4.Cu")
		(net "M_D_CPU1_SB_DQS_DN<0>")
	)
	(gr_poly
		(pts
			(xy 86.494874 -227.67671) (xy 86.395052 -227.576634) (xy 86.294976 -227.67671) (xy 86.294976 -227.724208)
			(xy 86.494874 -227.724208)
		)
		(stroke
			(width 0)
			(type solid)
		)
		(fill yes)
		(layer "In4.Cu")
		(net "M_D_CPU1_SA_DQS_DN<5>")
	)
	(gr_poly
		(pts
			(xy 86.501224 -256.432812) (xy 86.501224 -256.38506) (xy 86.301072 -256.38506) (xy 86.301072 -256.432812)
			(xy 86.401148 -256.532634)
		)
		(stroke
			(width 0)
			(type solid)
		)
		(fill yes)
		(layer "In4.Cu")
		(net "M_D_CPU1_CLK_DN<0>")
	)
	(gr_poly
		(pts
			(xy 86.501224 -255.216406) (xy 86.401148 -255.11633) (xy 86.301072 -255.216406) (xy 86.301072 -255.260856)
			(xy 86.501224 -255.260856)
		)
		(stroke
			(width 0)
			(type solid)
		)
		(fill yes)
		(layer "In4.Cu")
		(net "M_D_CPU1_SA_CA<6>")
	)
	(gr_poly
		(pts
			(xy 86.501224 -254.812546) (xy 86.501224 -254.768096) (xy 86.301072 -254.768096) (xy 86.301072 -254.812546)
			(xy 86.401148 -254.912622)
		)
		(stroke
			(width 0)
			(type solid)
		)
		(fill yes)
		(layer "In4.Cu")
		(net "M_D_CPU1_SA_CA<5>")
	)
	(gr_poly
		(pts
			(xy 86.501224 -253.596394) (xy 86.401148 -253.496318) (xy 86.301072 -253.596394) (xy 86.301072 -253.640844)
			(xy 86.501224 -253.640844)
		)
		(stroke
			(width 0)
			(type solid)
		)
		(fill yes)
		(layer "In4.Cu")
		(net "M_D_CPU1_SA_CA<2>")
	)
	(gr_poly
		(pts
			(xy 86.501224 -253.192534) (xy 86.501224 -253.148084) (xy 86.301072 -253.148084) (xy 86.301072 -253.192534)
			(xy 86.401148 -253.29261)
		)
		(stroke
			(width 0)
			(type solid)
		)
		(fill yes)
		(layer "In4.Cu")
		(net "M_D_CPU1_SA_CA<1>")
	)
	(gr_poly
		(pts
			(xy 86.501224 -251.572522) (xy 86.501224 -251.528072) (xy 86.301072 -251.528072) (xy 86.301072 -251.572522)
			(xy 86.401148 -251.672598)
		)
		(stroke
			(width 0)
			(type solid)
		)
		(fill yes)
		(layer "In4.Cu")
		(net "M_D_CPU1_SA_CS_N<0>")
	)
	(gr_poly
		(pts
			(xy 86.501224 -250.35637) (xy 86.401148 -250.256294) (xy 86.301072 -250.35637) (xy 86.301072 -250.40082)
			(xy 86.501224 -250.40082)
		)
		(stroke
			(width 0)
			(type solid)
		)
		(fill yes)
		(layer "In4.Cu")
		(net "M_D_CPU1_ALERT_R_N")
	)
	(gr_poly
		(pts
			(xy 86.501224 -248.736358) (xy 86.401148 -248.636282) (xy 86.301072 -248.736358) (xy 86.301072 -248.780808)
			(xy 86.501224 -248.780808)
		)
		(stroke
			(width 0)
			(type solid)
		)
		(fill yes)
		(layer "In4.Cu")
		(net "M_D_CPU1_SA_CB<5>")
	)
	(gr_poly
		(pts
			(xy 86.501224 -248.332498) (xy 86.501224 -248.288048) (xy 86.301072 -248.288048) (xy 86.301072 -248.332498)
			(xy 86.401148 -248.432574)
		)
		(stroke
			(width 0)
			(type solid)
		)
		(fill yes)
		(layer "In4.Cu")
		(net "M_D_CPU1_SA_CB<6>")
	)
	(gr_poly
		(pts
			(xy 86.501224 -247.116092) (xy 86.401148 -247.01627) (xy 86.301072 -247.116092) (xy 86.301072 -247.163844)
			(xy 86.501224 -247.163844)
		)
		(stroke
			(width 0)
			(type solid)
		)
		(fill yes)
		(layer "In4.Cu")
		(net "M_D_CPU1_SA_DQS_DN<9>")
	)
	(gr_poly
		(pts
			(xy 86.501224 -246.71274) (xy 86.501224 -246.664988) (xy 86.301072 -246.664988) (xy 86.301072 -246.71274)
			(xy 86.401148 -246.812562)
		)
		(stroke
			(width 0)
			(type solid)
		)
		(fill yes)
		(layer "In4.Cu")
		(net "M_D_CPU1_SA_DQS_DN<4>")
	)
	(gr_poly
		(pts
			(xy 86.501224 -245.496334) (xy 86.401148 -245.396258) (xy 86.301072 -245.496334) (xy 86.301072 -245.540784)
			(xy 86.501224 -245.540784)
		)
		(stroke
			(width 0)
			(type solid)
		)
		(fill yes)
		(layer "In4.Cu")
		(net "M_D_CPU1_SA_CB<1>")
	)
	(gr_poly
		(pts
			(xy 86.501224 -245.092474) (xy 86.501224 -245.048024) (xy 86.301072 -245.048024) (xy 86.301072 -245.092474)
			(xy 86.401148 -245.19255)
		)
		(stroke
			(width 0)
			(type solid)
		)
		(fill yes)
		(layer "In4.Cu")
		(net "M_D_CPU1_SA_CB<2>")
	)
	(gr_poly
		(pts
			(xy 86.501224 -243.876322) (xy 86.401148 -243.776246) (xy 86.301072 -243.876322) (xy 86.301072 -243.920772)
			(xy 86.501224 -243.920772)
		)
		(stroke
			(width 0)
			(type solid)
		)
		(fill yes)
		(layer "In4.Cu")
		(net "M_D_CPU1_SA_DQ<29>")
	)
	(gr_poly
		(pts
			(xy 86.501224 -243.472462) (xy 86.501224 -243.428012) (xy 86.301072 -243.428012) (xy 86.301072 -243.472462)
			(xy 86.401148 -243.572538)
		)
		(stroke
			(width 0)
			(type solid)
		)
		(fill yes)
		(layer "In4.Cu")
		(net "M_D_CPU1_SA_DQ<30>")
	)
	(gr_poly
		(pts
			(xy 86.501224 -242.256056) (xy 86.401148 -242.156234) (xy 86.301072 -242.256056) (xy 86.301072 -242.303808)
			(xy 86.501224 -242.303808)
		)
		(stroke
			(width 0)
			(type solid)
		)
		(fill yes)
		(layer "In4.Cu")
		(net "M_D_CPU1_SA_DQS_DN<8>")
	)
	(gr_poly
		(pts
			(xy 86.501224 -241.852704) (xy 86.501224 -241.804952) (xy 86.301072 -241.804952) (xy 86.301072 -241.852704)
			(xy 86.401148 -241.952526)
		)
		(stroke
			(width 0)
			(type solid)
		)
		(fill yes)
		(layer "In4.Cu")
		(net "M_D_CPU1_SA_DQS_DN<3>")
	)
	(gr_poly
		(pts
			(xy 86.501224 -240.636298) (xy 86.401148 -240.536222) (xy 86.301072 -240.636298) (xy 86.301072 -240.680748)
			(xy 86.501224 -240.680748)
		)
		(stroke
			(width 0)
			(type solid)
		)
		(fill yes)
		(layer "In4.Cu")
		(net "M_D_CPU1_SA_DQ<25>")
	)
	(gr_poly
		(pts
			(xy 86.501224 -240.232438) (xy 86.501224 -240.187988) (xy 86.301072 -240.187988) (xy 86.301072 -240.232438)
			(xy 86.401148 -240.332514)
		)
		(stroke
			(width 0)
			(type solid)
		)
		(fill yes)
		(layer "In4.Cu")
		(net "M_D_CPU1_SA_DQ<26>")
	)
	(gr_poly
		(pts
			(xy 86.501224 -239.016286) (xy 86.401148 -238.91621) (xy 86.301072 -239.016286) (xy 86.301072 -239.060736)
			(xy 86.501224 -239.060736)
		)
		(stroke
			(width 0)
			(type solid)
		)
		(fill yes)
		(layer "In4.Cu")
		(net "M_D_CPU1_SA_DQ<21>")
	)
	(gr_poly
		(pts
			(xy 86.501224 -238.612426) (xy 86.501224 -238.567976) (xy 86.301072 -238.567976) (xy 86.301072 -238.612426)
			(xy 86.401148 -238.712502)
		)
		(stroke
			(width 0)
			(type solid)
		)
		(fill yes)
		(layer "In4.Cu")
		(net "M_D_CPU1_SA_DQ<22>")
	)
	(gr_poly
		(pts
			(xy 86.501224 -237.39602) (xy 86.401148 -237.296198) (xy 86.301072 -237.39602) (xy 86.301072 -237.443772)
			(xy 86.501224 -237.443772)
		)
		(stroke
			(width 0)
			(type solid)
		)
		(fill yes)
		(layer "In4.Cu")
		(net "M_D_CPU1_SA_DQS_DN<7>")
	)
	(gr_poly
		(pts
			(xy 86.501224 -236.992668) (xy 86.501224 -236.944916) (xy 86.301072 -236.944916) (xy 86.301072 -236.992668)
			(xy 86.401148 -237.09249)
		)
		(stroke
			(width 0)
			(type solid)
		)
		(fill yes)
		(layer "In4.Cu")
		(net "M_D_CPU1_SA_DQS_DN<2>")
	)
	(gr_poly
		(pts
			(xy 86.501224 -235.776262) (xy 86.401148 -235.676186) (xy 86.301072 -235.776262) (xy 86.301072 -235.820712)
			(xy 86.501224 -235.820712)
		)
		(stroke
			(width 0)
			(type solid)
		)
		(fill yes)
		(layer "In4.Cu")
		(net "M_D_CPU1_SA_DQ<17>")
	)
	(gr_poly
		(pts
			(xy 86.501224 -235.372402) (xy 86.501224 -235.327952) (xy 86.301072 -235.327952) (xy 86.301072 -235.372402)
			(xy 86.401148 -235.472478)
		)
		(stroke
			(width 0)
			(type solid)
		)
		(fill yes)
		(layer "In4.Cu")
		(net "M_D_CPU1_SA_DQ<18>")
	)
	(gr_poly
		(pts
			(xy 86.501224 -234.15625) (xy 86.401148 -234.056174) (xy 86.301072 -234.15625) (xy 86.301072 -234.2007)
			(xy 86.501224 -234.2007)
		)
		(stroke
			(width 0)
			(type solid)
		)
		(fill yes)
		(layer "In4.Cu")
		(net "M_D_CPU1_SA_DQ<13>")
	)
	(gr_poly
		(pts
			(xy 86.501224 -233.75239) (xy 86.501224 -233.70794) (xy 86.301072 -233.70794) (xy 86.301072 -233.75239)
			(xy 86.401148 -233.852466)
		)
		(stroke
			(width 0)
			(type solid)
		)
		(fill yes)
		(layer "In4.Cu")
		(net "M_D_CPU1_SA_DQ<14>")
	)
	(gr_poly
		(pts
			(xy 86.501224 -232.535984) (xy 86.401148 -232.436162) (xy 86.301072 -232.535984) (xy 86.301072 -232.583736)
			(xy 86.501224 -232.583736)
		)
		(stroke
			(width 0)
			(type solid)
		)
		(fill yes)
		(layer "In4.Cu")
		(net "M_D_CPU1_SA_DQS_DN<6>")
	)
	(gr_poly
		(pts
			(xy 86.501224 -232.132632) (xy 86.501224 -232.08488) (xy 86.301072 -232.08488) (xy 86.301072 -232.132632)
			(xy 86.401148 -232.232454)
		)
		(stroke
			(width 0)
			(type solid)
		)
		(fill yes)
		(layer "In4.Cu")
		(net "M_D_CPU1_SA_DQS_DN<1>")
	)
	(gr_poly
		(pts
			(xy 86.501224 -230.916226) (xy 86.401148 -230.81615) (xy 86.301072 -230.916226) (xy 86.301072 -230.960676)
			(xy 86.501224 -230.960676)
		)
		(stroke
			(width 0)
			(type solid)
		)
		(fill yes)
		(layer "In4.Cu")
		(net "M_D_CPU1_SA_DQ<9>")
	)
	(gr_poly
		(pts
			(xy 86.501224 -230.51262) (xy 86.501224 -230.46817) (xy 86.301072 -230.46817) (xy 86.301072 -230.51262)
			(xy 86.401148 -230.612696)
		)
		(stroke
			(width 0)
			(type solid)
		)
		(fill yes)
		(layer "In4.Cu")
		(net "M_D_CPU1_SA_DQ<10>")
	)
	(gr_poly
		(pts
			(xy 86.501224 -229.296214) (xy 86.401148 -229.196138) (xy 86.301072 -229.296214) (xy 86.301072 -229.340664)
			(xy 86.501224 -229.340664)
		)
		(stroke
			(width 0)
			(type solid)
		)
		(fill yes)
		(layer "In4.Cu")
		(net "M_D_CPU1_SA_DQ<5>")
	)
	(gr_poly
		(pts
			(xy 86.501224 -228.892608) (xy 86.501224 -228.848158) (xy 86.301072 -228.848158) (xy 86.301072 -228.892608)
			(xy 86.401148 -228.992684)
		)
		(stroke
			(width 0)
			(type solid)
		)
		(fill yes)
		(layer "In4.Cu")
		(net "M_D_CPU1_SA_DQ<6>")
	)
	(gr_poly
		(pts
			(xy 86.501224 -227.27285) (xy 86.501224 -227.225098) (xy 86.301072 -227.225098) (xy 86.301072 -227.27285)
			(xy 86.401148 -227.372672)
		)
		(stroke
			(width 0)
			(type solid)
		)
		(fill yes)
		(layer "In4.Cu")
		(net "M_D_CPU1_SA_DQS_DN<0>")
	)
	(gr_poly
		(pts
			(xy 86.501224 -226.056444) (xy 86.401148 -225.956368) (xy 86.301072 -226.056444) (xy 86.301072 -226.100894)
			(xy 86.501224 -226.100894)
		)
		(stroke
			(width 0)
			(type solid)
		)
		(fill yes)
		(layer "In4.Cu")
		(net "M_D_CPU1_SA_DQ<1>")
	)
	(gr_poly
		(pts
			(xy 86.501224 -225.652584) (xy 86.501224 -225.608134) (xy 86.301072 -225.608134) (xy 86.301072 -225.652584)
			(xy 86.401148 -225.75266)
		)
		(stroke
			(width 0)
			(type solid)
		)
		(fill yes)
		(layer "In4.Cu")
		(net "M_D_CPU1_SA_DQ<2>")
	)
	(gr_poly
		(pts
			(xy 86.794848 -267.801852) (xy 86.694772 -267.701776) (xy 86.59495 -267.801852) (xy 86.59495 -267.846302)
			(xy 86.794848 -267.846302)
		)
		(stroke
			(width 0)
			(type solid)
		)
		(fill yes)
		(layer "In4.Cu")
		(net "M_D_CPU1_SB_RSP<0>")
	)
	(gr_poly
		(pts
			(xy 86.801198 -293.32428) (xy 86.801198 -293.27983) (xy 86.601046 -293.27983) (xy 86.601046 -293.32428)
			(xy 86.701122 -293.424356)
		)
		(stroke
			(width 0)
			(type solid)
		)
		(fill yes)
		(layer "In4.Cu")
		(net "M_D_CPU1_SB_DQ<31>")
	)
	(gr_poly
		(pts
			(xy 86.801198 -292.108128) (xy 86.701122 -292.008052) (xy 86.601046 -292.108128) (xy 86.601046 -292.152578)
			(xy 86.801198 -292.152578)
		)
		(stroke
			(width 0)
			(type solid)
		)
		(fill yes)
		(layer "In4.Cu")
		(net "M_D_CPU1_SB_DQ<28>")
	)
	(gr_poly
		(pts
			(xy 86.801198 -291.704522) (xy 86.801198 -291.65677) (xy 86.601046 -291.65677) (xy 86.601046 -291.704522)
			(xy 86.701122 -291.804344)
		)
		(stroke
			(width 0)
			(type solid)
		)
		(fill yes)
		(layer "In4.Cu")
		(net "M_D_CPU1_SB_DQS_DP<8>")
	)
	(gr_poly
		(pts
			(xy 86.801198 -290.487862) (xy 86.701122 -290.38804) (xy 86.601046 -290.487862) (xy 86.601046 -290.535614)
			(xy 86.801198 -290.535614)
		)
		(stroke
			(width 0)
			(type solid)
		)
		(fill yes)
		(layer "In4.Cu")
		(net "M_D_CPU1_SB_DQS_DP<3>")
	)
	(gr_poly
		(pts
			(xy 86.801198 -290.084256) (xy 86.801198 -290.039806) (xy 86.601046 -290.039806) (xy 86.601046 -290.084256)
			(xy 86.701122 -290.184332)
		)
		(stroke
			(width 0)
			(type solid)
		)
		(fill yes)
		(layer "In4.Cu")
		(net "M_D_CPU1_SB_DQ<27>")
	)
	(gr_poly
		(pts
			(xy 86.801198 -288.868104) (xy 86.701122 -288.768028) (xy 86.601046 -288.868104) (xy 86.601046 -288.912554)
			(xy 86.801198 -288.912554)
		)
		(stroke
			(width 0)
			(type solid)
		)
		(fill yes)
		(layer "In4.Cu")
		(net "M_D_CPU1_SB_DQ<24>")
	)
	(gr_poly
		(pts
			(xy 86.801198 -288.464498) (xy 86.801198 -288.420048) (xy 86.601046 -288.420048) (xy 86.601046 -288.464498)
			(xy 86.701122 -288.564574)
		)
		(stroke
			(width 0)
			(type solid)
		)
		(fill yes)
		(layer "In4.Cu")
		(net "M_D_CPU1_SB_DQ<23>")
	)
	(gr_poly
		(pts
			(xy 86.801198 -287.248092) (xy 86.701122 -287.148016) (xy 86.601046 -287.248092) (xy 86.601046 -287.292542)
			(xy 86.801198 -287.292542)
		)
		(stroke
			(width 0)
			(type solid)
		)
		(fill yes)
		(layer "In4.Cu")
		(net "M_D_CPU1_SB_DQ<20>")
	)
	(gr_poly
		(pts
			(xy 86.801198 -286.844486) (xy 86.801198 -286.796734) (xy 86.601046 -286.796734) (xy 86.601046 -286.844486)
			(xy 86.701122 -286.944562)
		)
		(stroke
			(width 0)
			(type solid)
		)
		(fill yes)
		(layer "In4.Cu")
		(net "M_D_CPU1_SB_DQS_DP<7>")
	)
	(gr_poly
		(pts
			(xy 86.801198 -285.62808) (xy 86.701122 -285.528258) (xy 86.601046 -285.62808) (xy 86.601046 -285.675832)
			(xy 86.801198 -285.675832)
		)
		(stroke
			(width 0)
			(type solid)
		)
		(fill yes)
		(layer "In4.Cu")
		(net "M_D_CPU1_SB_DQS_DP<2>")
	)
	(gr_poly
		(pts
			(xy 86.801198 -285.224474) (xy 86.801198 -285.180024) (xy 86.601046 -285.180024) (xy 86.601046 -285.224474)
			(xy 86.701122 -285.32455)
		)
		(stroke
			(width 0)
			(type solid)
		)
		(fill yes)
		(layer "In4.Cu")
		(net "M_D_CPU1_SB_DQ<19>")
	)
	(gr_poly
		(pts
			(xy 86.801198 -284.008322) (xy 86.701122 -283.908246) (xy 86.601046 -284.008322) (xy 86.601046 -284.052772)
			(xy 86.801198 -284.052772)
		)
		(stroke
			(width 0)
			(type solid)
		)
		(fill yes)
		(layer "In4.Cu")
		(net "M_D_CPU1_SB_DQ<16>")
	)
	(gr_poly
		(pts
			(xy 86.801198 -283.604462) (xy 86.801198 -283.560012) (xy 86.601046 -283.560012) (xy 86.601046 -283.604462)
			(xy 86.701122 -283.704538)
		)
		(stroke
			(width 0)
			(type solid)
		)
		(fill yes)
		(layer "In4.Cu")
		(net "M_D_CPU1_SB_DQ<15>")
	)
	(gr_poly
		(pts
			(xy 86.801198 -282.38831) (xy 86.701122 -282.288234) (xy 86.601046 -282.38831) (xy 86.601046 -282.43276)
			(xy 86.801198 -282.43276)
		)
		(stroke
			(width 0)
			(type solid)
		)
		(fill yes)
		(layer "In4.Cu")
		(net "M_D_CPU1_SB_DQ<12>")
	)
	(gr_poly
		(pts
			(xy 86.801198 -281.984704) (xy 86.801198 -281.936952) (xy 86.601046 -281.936952) (xy 86.601046 -281.984704)
			(xy 86.701122 -282.084526)
		)
		(stroke
			(width 0)
			(type solid)
		)
		(fill yes)
		(layer "In4.Cu")
		(net "M_D_CPU1_SB_DQS_DP<6>")
	)
	(gr_poly
		(pts
			(xy 86.801198 -280.768044) (xy 86.701122 -280.668222) (xy 86.601046 -280.768044) (xy 86.601046 -280.815796)
			(xy 86.801198 -280.815796)
		)
		(stroke
			(width 0)
			(type solid)
		)
		(fill yes)
		(layer "In4.Cu")
		(net "M_D_CPU1_SB_DQS_DP<1>")
	)
	(gr_poly
		(pts
			(xy 86.801198 -280.364438) (xy 86.801198 -280.319988) (xy 86.601046 -280.319988) (xy 86.601046 -280.364438)
			(xy 86.701122 -280.464514)
		)
		(stroke
			(width 0)
			(type solid)
		)
		(fill yes)
		(layer "In4.Cu")
		(net "M_D_CPU1_SB_DQ<11>")
	)
	(gr_poly
		(pts
			(xy 86.801198 -279.148286) (xy 86.701122 -279.04821) (xy 86.601046 -279.148286) (xy 86.601046 -279.192736)
			(xy 86.801198 -279.192736)
		)
		(stroke
			(width 0)
			(type solid)
		)
		(fill yes)
		(layer "In4.Cu")
		(net "M_D_CPU1_SB_DQ<8>")
	)
	(gr_poly
		(pts
			(xy 86.801198 -278.744426) (xy 86.801198 -278.699976) (xy 86.601046 -278.699976) (xy 86.601046 -278.744426)
			(xy 86.701122 -278.844502)
		)
		(stroke
			(width 0)
			(type solid)
		)
		(fill yes)
		(layer "In4.Cu")
		(net "M_D_CPU1_SB_DQ<7>")
	)
	(gr_poly
		(pts
			(xy 86.801198 -277.528274) (xy 86.701122 -277.428198) (xy 86.601046 -277.528274) (xy 86.601046 -277.572724)
			(xy 86.801198 -277.572724)
		)
		(stroke
			(width 0)
			(type solid)
		)
		(fill yes)
		(layer "In4.Cu")
		(net "M_D_CPU1_SB_DQ<4>")
	)
	(gr_poly
		(pts
			(xy 86.801198 -277.124668) (xy 86.801198 -277.076916) (xy 86.601046 -277.076916) (xy 86.601046 -277.124668)
			(xy 86.701122 -277.22449)
		)
		(stroke
			(width 0)
			(type solid)
		)
		(fill yes)
		(layer "In4.Cu")
		(net "M_D_CPU1_SB_DQS_DP<5>")
	)
	(gr_poly
		(pts
			(xy 86.801198 -275.908008) (xy 86.701122 -275.808186) (xy 86.601046 -275.908008) (xy 86.601046 -275.95576)
			(xy 86.801198 -275.95576)
		)
		(stroke
			(width 0)
			(type solid)
		)
		(fill yes)
		(layer "In4.Cu")
		(net "M_D_CPU1_SB_DQS_DP<0>")
	)
	(gr_poly
		(pts
			(xy 86.801198 -275.504402) (xy 86.801198 -275.459952) (xy 86.601046 -275.459952) (xy 86.601046 -275.504402)
			(xy 86.701122 -275.604478)
		)
		(stroke
			(width 0)
			(type solid)
		)
		(fill yes)
		(layer "In4.Cu")
		(net "M_D_CPU1_SB_DQ<3>")
	)
	(gr_poly
		(pts
			(xy 86.801198 -274.28825) (xy 86.701122 -274.188174) (xy 86.601046 -274.28825) (xy 86.601046 -274.3327)
			(xy 86.801198 -274.3327)
		)
		(stroke
			(width 0)
			(type solid)
		)
		(fill yes)
		(layer "In4.Cu")
		(net "M_D_CPU1_SB_DQ<0>")
	)
	(gr_poly
		(pts
			(xy 86.801198 -273.88439) (xy 86.801198 -273.83994) (xy 86.601046 -273.83994) (xy 86.601046 -273.88439)
			(xy 86.701122 -273.984466)
		)
		(stroke
			(width 0)
			(type solid)
		)
		(fill yes)
		(layer "In4.Cu")
		(net "M_D_CPU1_SB_CB<3>")
	)
	(gr_poly
		(pts
			(xy 86.801198 -272.668238) (xy 86.701122 -272.568162) (xy 86.601046 -272.668238) (xy 86.601046 -272.712688)
			(xy 86.801198 -272.712688)
		)
		(stroke
			(width 0)
			(type solid)
		)
		(fill yes)
		(layer "In4.Cu")
		(net "M_D_CPU1_SB_CB<0>")
	)
	(gr_poly
		(pts
			(xy 86.801198 -272.264632) (xy 86.801198 -272.21688) (xy 86.601046 -272.21688) (xy 86.601046 -272.264632)
			(xy 86.701122 -272.364454)
		)
		(stroke
			(width 0)
			(type solid)
		)
		(fill yes)
		(layer "In4.Cu")
		(net "M_D_CPU1_SB_DQS_DP<4>")
	)
	(gr_poly
		(pts
			(xy 86.801198 -271.047972) (xy 86.701122 -270.94815) (xy 86.601046 -271.047972) (xy 86.601046 -271.095724)
			(xy 86.801198 -271.095724)
		)
		(stroke
			(width 0)
			(type solid)
		)
		(fill yes)
		(layer "In4.Cu")
		(net "M_D_CPU1_SB_DQS_DP<9>")
	)
	(gr_poly
		(pts
			(xy 86.801198 -270.644366) (xy 86.801198 -270.599916) (xy 86.601046 -270.599916) (xy 86.601046 -270.644366)
			(xy 86.701122 -270.744442)
		)
		(stroke
			(width 0)
			(type solid)
		)
		(fill yes)
		(layer "In4.Cu")
		(net "M_D_CPU1_SB_CB<7>")
	)
	(gr_poly
		(pts
			(xy 86.801198 -269.428214) (xy 86.701122 -269.328138) (xy 86.601046 -269.428214) (xy 86.601046 -269.472664)
			(xy 86.801198 -269.472664)
		)
		(stroke
			(width 0)
			(type solid)
		)
		(fill yes)
		(layer "In4.Cu")
		(net "M_D_CPU1_SB_CB<4>")
	)
	(gr_poly
		(pts
			(xy 86.801198 -265.78433) (xy 86.801198 -265.73988) (xy 86.601046 -265.73988) (xy 86.601046 -265.78433)
			(xy 86.701122 -265.884406)
		)
		(stroke
			(width 0)
			(type solid)
		)
		(fill yes)
		(layer "In4.Cu")
		(net "M_D_CPU1_SB_CS_N<0>")
	)
	(gr_poly
		(pts
			(xy 86.801198 -264.568178) (xy 86.701122 -264.468102) (xy 86.601046 -264.568178) (xy 86.601046 -264.612628)
			(xy 86.801198 -264.612628)
		)
		(stroke
			(width 0)
			(type solid)
		)
		(fill yes)
		(layer "In4.Cu")
		(net "M_D_CPU1_SB_CA<6>")
	)
	(gr_poly
		(pts
			(xy 86.801198 -264.164318) (xy 86.801198 -264.119868) (xy 86.601046 -264.119868) (xy 86.601046 -264.164318)
			(xy 86.701122 -264.264394)
		)
		(stroke
			(width 0)
			(type solid)
		)
		(fill yes)
		(layer "In4.Cu")
		(net "M_D_CPU1_SB_CA<5>")
	)
	(gr_poly
		(pts
			(xy 86.801198 -262.948166) (xy 86.701122 -262.84809) (xy 86.601046 -262.948166) (xy 86.601046 -262.992616)
			(xy 86.801198 -262.992616)
		)
		(stroke
			(width 0)
			(type solid)
		)
		(fill yes)
		(layer "In4.Cu")
		(net "M_D_CPU1_SB_CA<2>")
	)
	(gr_poly
		(pts
			(xy 86.801198 -262.544306) (xy 86.801198 -262.499856) (xy 86.601046 -262.499856) (xy 86.601046 -262.544306)
			(xy 86.701122 -262.644382)
		)
		(stroke
			(width 0)
			(type solid)
		)
		(fill yes)
		(layer "In4.Cu")
		(net "M_D_CPU1_SB_CA<1>")
	)
	(gr_poly
		(pts
			(xy 86.971124 -256.026158) (xy 86.871048 -255.926336) (xy 86.770972 -256.026158) (xy 86.770972 -256.07391)
			(xy 86.971124 -256.07391)
		)
		(stroke
			(width 0)
			(type solid)
		)
		(fill yes)
		(layer "In4.Cu")
		(net "M_D_CPU1_CLK_DP<0>")
	)
	(gr_poly
		(pts
			(xy 86.971124 -255.622552) (xy 86.971124 -255.578102) (xy 86.770972 -255.578102) (xy 86.770972 -255.622552)
			(xy 86.871048 -255.722628)
		)
		(stroke
			(width 0)
			(type solid)
		)
		(fill yes)
		(layer "In4.Cu")
		(net "M_D_CPU1_SA_PAR")
	)
	(gr_poly
		(pts
			(xy 86.971124 -254.4064) (xy 86.871048 -254.306324) (xy 86.770972 -254.4064) (xy 86.770972 -254.45085)
			(xy 86.971124 -254.45085)
		)
		(stroke
			(width 0)
			(type solid)
		)
		(fill yes)
		(layer "In4.Cu")
		(net "M_D_CPU1_SA_CA<4>")
	)
	(gr_poly
		(pts
			(xy 86.971124 -254.00254) (xy 86.971124 -253.95809) (xy 86.770972 -253.95809) (xy 86.770972 -254.00254)
			(xy 86.871048 -254.102616)
		)
		(stroke
			(width 0)
			(type solid)
		)
		(fill yes)
		(layer "In4.Cu")
		(net "M_D_CPU1_SA_CA<3>")
	)
	(gr_poly
		(pts
			(xy 86.971124 -252.786388) (xy 86.871048 -252.686312) (xy 86.770972 -252.786388) (xy 86.770972 -252.830838)
			(xy 86.971124 -252.830838)
		)
		(stroke
			(width 0)
			(type solid)
		)
		(fill yes)
		(layer "In4.Cu")
		(net "M_D_CPU1_SA_CA<0>")
	)
	(gr_poly
		(pts
			(xy 86.971124 -252.382528) (xy 86.971124 -252.338078) (xy 86.770972 -252.338078) (xy 86.770972 -252.382528)
			(xy 86.871048 -252.482604)
		)
		(stroke
			(width 0)
			(type solid)
		)
		(fill yes)
		(layer "In4.Cu")
		(net "M_D_CPU1_SA_CS_N<1>")
	)
	(gr_poly
		(pts
			(xy 86.971124 -250.762516) (xy 86.971124 -250.718066) (xy 86.770972 -250.718066) (xy 86.770972 -250.762516)
			(xy 86.871048 -250.862592)
		)
		(stroke
			(width 0)
			(type solid)
		)
		(fill yes)
		(layer "In4.Cu")
		(net "M_D_CPU1_RESET_N")
	)
	(gr_poly
		(pts
			(xy 86.971124 -249.142504) (xy 86.971124 -249.098054) (xy 86.770972 -249.098054) (xy 86.770972 -249.142504)
			(xy 86.871048 -249.24258)
		)
		(stroke
			(width 0)
			(type solid)
		)
		(fill yes)
		(layer "In4.Cu")
		(net "M_D_CPU1_SA_CB<7>")
	)
	(gr_poly
		(pts
			(xy 86.971124 -247.926352) (xy 86.871048 -247.826276) (xy 86.770972 -247.926352) (xy 86.770972 -247.970802)
			(xy 86.971124 -247.970802)
		)
		(stroke
			(width 0)
			(type solid)
		)
		(fill yes)
		(layer "In4.Cu")
		(net "M_D_CPU1_SA_CB<4>")
	)
	(gr_poly
		(pts
			(xy 86.971124 -247.522746) (xy 86.971124 -247.474994) (xy 86.770972 -247.474994) (xy 86.770972 -247.522746)
			(xy 86.871048 -247.622568)
		)
		(stroke
			(width 0)
			(type solid)
		)
		(fill yes)
		(layer "In4.Cu")
		(net "M_D_CPU1_SA_DQS_DP<9>")
	)
	(gr_poly
		(pts
			(xy 86.971124 -246.306086) (xy 86.871048 -246.206264) (xy 86.770972 -246.306086) (xy 86.770972 -246.353838)
			(xy 86.971124 -246.353838)
		)
		(stroke
			(width 0)
			(type solid)
		)
		(fill yes)
		(layer "In4.Cu")
		(net "M_D_CPU1_SA_DQS_DP<4>")
	)
	(gr_poly
		(pts
			(xy 86.971124 -245.90248) (xy 86.971124 -245.85803) (xy 86.770972 -245.85803) (xy 86.770972 -245.90248)
			(xy 86.871048 -246.002556)
		)
		(stroke
			(width 0)
			(type solid)
		)
		(fill yes)
		(layer "In4.Cu")
		(net "M_D_CPU1_SA_CB<3>")
	)
	(gr_poly
		(pts
			(xy 86.971124 -244.686328) (xy 86.871048 -244.586252) (xy 86.770972 -244.686328) (xy 86.770972 -244.730778)
			(xy 86.971124 -244.730778)
		)
		(stroke
			(width 0)
			(type solid)
		)
		(fill yes)
		(layer "In4.Cu")
		(net "M_D_CPU1_SA_CB<0>")
	)
	(gr_poly
		(pts
			(xy 86.971124 -244.282468) (xy 86.971124 -244.238018) (xy 86.770972 -244.238018) (xy 86.770972 -244.282468)
			(xy 86.871048 -244.382544)
		)
		(stroke
			(width 0)
			(type solid)
		)
		(fill yes)
		(layer "In4.Cu")
		(net "M_D_CPU1_SA_DQ<31>")
	)
	(gr_poly
		(pts
			(xy 86.971124 -243.066316) (xy 86.871048 -242.96624) (xy 86.770972 -243.066316) (xy 86.770972 -243.110766)
			(xy 86.971124 -243.110766)
		)
		(stroke
			(width 0)
			(type solid)
		)
		(fill yes)
		(layer "In4.Cu")
		(net "M_D_CPU1_SA_DQ<28>")
	)
	(gr_poly
		(pts
			(xy 86.971124 -242.66271) (xy 86.971124 -242.614958) (xy 86.770972 -242.614958) (xy 86.770972 -242.66271)
			(xy 86.871048 -242.762532)
		)
		(stroke
			(width 0)
			(type solid)
		)
		(fill yes)
		(layer "In4.Cu")
		(net "M_D_CPU1_SA_DQS_DP<8>")
	)
	(gr_poly
		(pts
			(xy 86.971124 -241.44605) (xy 86.871048 -241.346228) (xy 86.770972 -241.44605) (xy 86.770972 -241.493802)
			(xy 86.971124 -241.493802)
		)
		(stroke
			(width 0)
			(type solid)
		)
		(fill yes)
		(layer "In4.Cu")
		(net "M_D_CPU1_SA_DQS_DP<3>")
	)
	(gr_poly
		(pts
			(xy 86.971124 -241.042444) (xy 86.971124 -240.997994) (xy 86.770972 -240.997994) (xy 86.770972 -241.042444)
			(xy 86.871048 -241.14252)
		)
		(stroke
			(width 0)
			(type solid)
		)
		(fill yes)
		(layer "In4.Cu")
		(net "M_D_CPU1_SA_DQ<27>")
	)
	(gr_poly
		(pts
			(xy 86.971124 -239.826292) (xy 86.871048 -239.726216) (xy 86.770972 -239.826292) (xy 86.770972 -239.870742)
			(xy 86.971124 -239.870742)
		)
		(stroke
			(width 0)
			(type solid)
		)
		(fill yes)
		(layer "In4.Cu")
		(net "M_D_CPU1_SA_DQ<24>")
	)
	(gr_poly
		(pts
			(xy 86.971124 -239.422432) (xy 86.971124 -239.377982) (xy 86.770972 -239.377982) (xy 86.770972 -239.422432)
			(xy 86.871048 -239.522508)
		)
		(stroke
			(width 0)
			(type solid)
		)
		(fill yes)
		(layer "In4.Cu")
		(net "M_D_CPU1_SA_DQ<23>")
	)
	(gr_poly
		(pts
			(xy 86.971124 -238.20628) (xy 86.871048 -238.106204) (xy 86.770972 -238.20628) (xy 86.770972 -238.25073)
			(xy 86.971124 -238.25073)
		)
		(stroke
			(width 0)
			(type solid)
		)
		(fill yes)
		(layer "In4.Cu")
		(net "M_D_CPU1_SA_DQ<20>")
	)
	(gr_poly
		(pts
			(xy 86.971124 -237.802674) (xy 86.971124 -237.754922) (xy 86.770972 -237.754922) (xy 86.770972 -237.802674)
			(xy 86.871048 -237.902496)
		)
		(stroke
			(width 0)
			(type solid)
		)
		(fill yes)
		(layer "In4.Cu")
		(net "M_D_CPU1_SA_DQS_DP<7>")
	)
	(gr_poly
		(pts
			(xy 86.971124 -236.586014) (xy 86.871048 -236.486192) (xy 86.770972 -236.586014) (xy 86.770972 -236.633766)
			(xy 86.971124 -236.633766)
		)
		(stroke
			(width 0)
			(type solid)
		)
		(fill yes)
		(layer "In4.Cu")
		(net "M_D_CPU1_SA_DQS_DP<2>")
	)
	(gr_poly
		(pts
			(xy 86.971124 -236.182408) (xy 86.971124 -236.137958) (xy 86.770972 -236.137958) (xy 86.770972 -236.182408)
			(xy 86.871048 -236.282484)
		)
		(stroke
			(width 0)
			(type solid)
		)
		(fill yes)
		(layer "In4.Cu")
		(net "M_D_CPU1_SA_DQ<19>")
	)
	(gr_poly
		(pts
			(xy 86.971124 -234.966256) (xy 86.871048 -234.86618) (xy 86.770972 -234.966256) (xy 86.770972 -235.010706)
			(xy 86.971124 -235.010706)
		)
		(stroke
			(width 0)
			(type solid)
		)
		(fill yes)
		(layer "In4.Cu")
		(net "M_D_CPU1_SA_DQ<16>")
	)
	(gr_poly
		(pts
			(xy 86.971124 -234.562396) (xy 86.971124 -234.517946) (xy 86.770972 -234.517946) (xy 86.770972 -234.562396)
			(xy 86.871048 -234.662472)
		)
		(stroke
			(width 0)
			(type solid)
		)
		(fill yes)
		(layer "In4.Cu")
		(net "M_D_CPU1_SA_DQ<15>")
	)
	(gr_poly
		(pts
			(xy 86.971124 -233.346244) (xy 86.871048 -233.246168) (xy 86.770972 -233.346244) (xy 86.770972 -233.390694)
			(xy 86.971124 -233.390694)
		)
		(stroke
			(width 0)
			(type solid)
		)
		(fill yes)
		(layer "In4.Cu")
		(net "M_D_CPU1_SA_DQ<12>")
	)
	(gr_poly
		(pts
			(xy 86.971124 -232.942638) (xy 86.971124 -232.894886) (xy 86.770972 -232.894886) (xy 86.770972 -232.942638)
			(xy 86.871048 -233.04246)
		)
		(stroke
			(width 0)
			(type solid)
		)
		(fill yes)
		(layer "In4.Cu")
		(net "M_D_CPU1_SA_DQS_DP<6>")
	)
	(gr_poly
		(pts
			(xy 86.971124 -231.725978) (xy 86.871048 -231.626156) (xy 86.770972 -231.725978) (xy 86.770972 -231.77373)
			(xy 86.971124 -231.77373)
		)
		(stroke
			(width 0)
			(type solid)
		)
		(fill yes)
		(layer "In4.Cu")
		(net "M_D_CPU1_SA_DQS_DP<1>")
	)
	(gr_poly
		(pts
			(xy 86.971124 -231.322626) (xy 86.971124 -231.278176) (xy 86.770972 -231.278176) (xy 86.770972 -231.322626)
			(xy 86.871048 -231.422702)
		)
		(stroke
			(width 0)
			(type solid)
		)
		(fill yes)
		(layer "In4.Cu")
		(net "M_D_CPU1_SA_DQ<11>")
	)
	(gr_poly
		(pts
			(xy 86.971124 -230.10622) (xy 86.871048 -230.006144) (xy 86.770972 -230.10622) (xy 86.770972 -230.15067)
			(xy 86.971124 -230.15067)
		)
		(stroke
			(width 0)
			(type solid)
		)
		(fill yes)
		(layer "In4.Cu")
		(net "M_D_CPU1_SA_DQ<8>")
	)
	(gr_poly
		(pts
			(xy 86.971124 -229.702614) (xy 86.971124 -229.658164) (xy 86.770972 -229.658164) (xy 86.770972 -229.702614)
			(xy 86.871048 -229.80269)
		)
		(stroke
			(width 0)
			(type solid)
		)
		(fill yes)
		(layer "In4.Cu")
		(net "M_D_CPU1_SA_DQ<7>")
	)
	(gr_poly
		(pts
			(xy 86.971124 -228.486462) (xy 86.871048 -228.386386) (xy 86.770972 -228.486462) (xy 86.770972 -228.530912)
			(xy 86.971124 -228.530912)
		)
		(stroke
			(width 0)
			(type solid)
		)
		(fill yes)
		(layer "In4.Cu")
		(net "M_D_CPU1_SA_DQ<4>")
	)
	(gr_poly
		(pts
			(xy 86.971124 -228.082856) (xy 86.971124 -228.035104) (xy 86.770972 -228.035104) (xy 86.770972 -228.082856)
			(xy 86.871048 -228.182678)
		)
		(stroke
			(width 0)
			(type solid)
		)
		(fill yes)
		(layer "In4.Cu")
		(net "M_D_CPU1_SA_DQS_DP<5>")
	)
	(gr_poly
		(pts
			(xy 86.971124 -226.866196) (xy 86.871048 -226.766374) (xy 86.770972 -226.866196) (xy 86.770972 -226.913948)
			(xy 86.971124 -226.913948)
		)
		(stroke
			(width 0)
			(type solid)
		)
		(fill yes)
		(layer "In4.Cu")
		(net "M_D_CPU1_SA_DQS_DP<0>")
	)
	(gr_poly
		(pts
			(xy 86.971124 -226.46259) (xy 86.971124 -226.41814) (xy 86.770972 -226.41814) (xy 86.770972 -226.46259)
			(xy 86.871048 -226.562666)
		)
		(stroke
			(width 0)
			(type solid)
		)
		(fill yes)
		(layer "In4.Cu")
		(net "M_D_CPU1_SA_DQ<3>")
	)
	(gr_poly
		(pts
			(xy 86.971124 -225.246438) (xy 86.871048 -225.146362) (xy 86.770972 -225.246438) (xy 86.770972 -225.290888)
			(xy 86.971124 -225.290888)
		)
		(stroke
			(width 0)
			(type solid)
		)
		(fill yes)
		(layer "In4.Cu")
		(net "M_D_CPU1_SA_DQ<0>")
	)
	(gr_poly
		(pts
			(xy 87.271098 -292.918134) (xy 87.171022 -292.818058) (xy 87.070946 -292.918134) (xy 87.070946 -292.962584)
			(xy 87.271098 -292.962584)
		)
		(stroke
			(width 0)
			(type solid)
		)
		(fill yes)
		(layer "In4.Cu")
		(net "M_D_CPU1_SB_DQ<29>")
	)
	(gr_poly
		(pts
			(xy 87.271098 -292.514274) (xy 87.271098 -292.469824) (xy 87.070946 -292.469824) (xy 87.070946 -292.514274)
			(xy 87.171022 -292.61435)
		)
		(stroke
			(width 0)
			(type solid)
		)
		(fill yes)
		(layer "In4.Cu")
		(net "M_D_CPU1_SB_DQ<30>")
	)
	(gr_poly
		(pts
			(xy 87.271098 -291.297868) (xy 87.171022 -291.198046) (xy 87.070946 -291.297868) (xy 87.070946 -291.34562)
			(xy 87.271098 -291.34562)
		)
		(stroke
			(width 0)
			(type solid)
		)
		(fill yes)
		(layer "In4.Cu")
		(net "M_D_CPU1_SB_DQS_DN<8>")
	)
	(gr_poly
		(pts
			(xy 87.271098 -290.894516) (xy 87.271098 -290.846764) (xy 87.070946 -290.846764) (xy 87.070946 -290.894516)
			(xy 87.171022 -290.994338)
		)
		(stroke
			(width 0)
			(type solid)
		)
		(fill yes)
		(layer "In4.Cu")
		(net "M_D_CPU1_SB_DQS_DN<3>")
	)
	(gr_poly
		(pts
			(xy 87.271098 -289.67811) (xy 87.171022 -289.578034) (xy 87.070946 -289.67811) (xy 87.070946 -289.72256)
			(xy 87.271098 -289.72256)
		)
		(stroke
			(width 0)
			(type solid)
		)
		(fill yes)
		(layer "In4.Cu")
		(net "M_D_CPU1_SB_DQ<25>")
	)
	(gr_poly
		(pts
			(xy 87.271098 -289.27425) (xy 87.271098 -289.2298) (xy 87.070946 -289.2298) (xy 87.070946 -289.27425)
			(xy 87.171022 -289.374326)
		)
		(stroke
			(width 0)
			(type solid)
		)
		(fill yes)
		(layer "In4.Cu")
		(net "M_D_CPU1_SB_DQ<26>")
	)
	(gr_poly
		(pts
			(xy 87.271098 -288.058098) (xy 87.171022 -287.958022) (xy 87.070946 -288.058098) (xy 87.070946 -288.102548)
			(xy 87.271098 -288.102548)
		)
		(stroke
			(width 0)
			(type solid)
		)
		(fill yes)
		(layer "In4.Cu")
		(net "M_D_CPU1_SB_DQ<21>")
	)
	(gr_poly
		(pts
			(xy 87.271098 -287.654492) (xy 87.271098 -287.610042) (xy 87.070946 -287.610042) (xy 87.070946 -287.654492)
			(xy 87.171022 -287.754568)
		)
		(stroke
			(width 0)
			(type solid)
		)
		(fill yes)
		(layer "In4.Cu")
		(net "M_D_CPU1_SB_DQ<22>")
	)
	(gr_poly
		(pts
			(xy 87.271098 -286.438086) (xy 87.171022 -286.33801) (xy 87.070946 -286.438086) (xy 87.070946 -286.485838)
			(xy 87.271098 -286.485838)
		)
		(stroke
			(width 0)
			(type solid)
		)
		(fill yes)
		(layer "In4.Cu")
		(net "M_D_CPU1_SB_DQS_DN<7>")
	)
	(gr_poly
		(pts
			(xy 87.271098 -286.034734) (xy 87.271098 -285.986982) (xy 87.070946 -285.986982) (xy 87.070946 -286.034734)
			(xy 87.171022 -286.134556)
		)
		(stroke
			(width 0)
			(type solid)
		)
		(fill yes)
		(layer "In4.Cu")
		(net "M_D_CPU1_SB_DQS_DN<2>")
	)
	(gr_poly
		(pts
			(xy 87.271098 -284.818328) (xy 87.171022 -284.718252) (xy 87.070946 -284.818328) (xy 87.070946 -284.862778)
			(xy 87.271098 -284.862778)
		)
		(stroke
			(width 0)
			(type solid)
		)
		(fill yes)
		(layer "In4.Cu")
		(net "M_D_CPU1_SB_DQ<17>")
	)
	(gr_poly
		(pts
			(xy 87.271098 -284.414468) (xy 87.271098 -284.370018) (xy 87.070946 -284.370018) (xy 87.070946 -284.414468)
			(xy 87.171022 -284.514544)
		)
		(stroke
			(width 0)
			(type solid)
		)
		(fill yes)
		(layer "In4.Cu")
		(net "M_D_CPU1_SB_DQ<18>")
	)
	(gr_poly
		(pts
			(xy 87.271098 -283.198316) (xy 87.171022 -283.09824) (xy 87.070946 -283.198316) (xy 87.070946 -283.242766)
			(xy 87.271098 -283.242766)
		)
		(stroke
			(width 0)
			(type solid)
		)
		(fill yes)
		(layer "In4.Cu")
		(net "M_D_CPU1_SB_DQ<13>")
	)
	(gr_poly
		(pts
			(xy 87.271098 -282.794456) (xy 87.271098 -282.750006) (xy 87.070946 -282.750006) (xy 87.070946 -282.794456)
			(xy 87.171022 -282.894532)
		)
		(stroke
			(width 0)
			(type solid)
		)
		(fill yes)
		(layer "In4.Cu")
		(net "M_D_CPU1_SB_DQ<14>")
	)
	(gr_poly
		(pts
			(xy 87.271098 -281.57805) (xy 87.171022 -281.478228) (xy 87.070946 -281.57805) (xy 87.070946 -281.625802)
			(xy 87.271098 -281.625802)
		)
		(stroke
			(width 0)
			(type solid)
		)
		(fill yes)
		(layer "In4.Cu")
		(net "M_D_CPU1_SB_DQS_DN<6>")
	)
	(gr_poly
		(pts
			(xy 87.271098 -281.174698) (xy 87.271098 -281.126946) (xy 87.070946 -281.126946) (xy 87.070946 -281.174698)
			(xy 87.171022 -281.27452)
		)
		(stroke
			(width 0)
			(type solid)
		)
		(fill yes)
		(layer "In4.Cu")
		(net "M_D_CPU1_SB_DQS_DN<1>")
	)
	(gr_poly
		(pts
			(xy 87.271098 -279.958292) (xy 87.171022 -279.858216) (xy 87.070946 -279.958292) (xy 87.070946 -280.002742)
			(xy 87.271098 -280.002742)
		)
		(stroke
			(width 0)
			(type solid)
		)
		(fill yes)
		(layer "In4.Cu")
		(net "M_D_CPU1_SB_DQ<9>")
	)
	(gr_poly
		(pts
			(xy 87.271098 -279.554432) (xy 87.271098 -279.509982) (xy 87.070946 -279.509982) (xy 87.070946 -279.554432)
			(xy 87.171022 -279.654508)
		)
		(stroke
			(width 0)
			(type solid)
		)
		(fill yes)
		(layer "In4.Cu")
		(net "M_D_CPU1_SB_DQ<10>")
	)
	(gr_poly
		(pts
			(xy 87.271098 -278.33828) (xy 87.171022 -278.238204) (xy 87.070946 -278.33828) (xy 87.070946 -278.38273)
			(xy 87.271098 -278.38273)
		)
		(stroke
			(width 0)
			(type solid)
		)
		(fill yes)
		(layer "In4.Cu")
		(net "M_D_CPU1_SB_DQ<5>")
	)
	(gr_poly
		(pts
			(xy 87.271098 -277.93442) (xy 87.271098 -277.88997) (xy 87.070946 -277.88997) (xy 87.070946 -277.93442)
			(xy 87.171022 -278.034496)
		)
		(stroke
			(width 0)
			(type solid)
		)
		(fill yes)
		(layer "In4.Cu")
		(net "M_D_CPU1_SB_DQ<6>")
	)
	(gr_poly
		(pts
			(xy 87.271098 -276.718014) (xy 87.171022 -276.618192) (xy 87.070946 -276.718014) (xy 87.070946 -276.765766)
			(xy 87.271098 -276.765766)
		)
		(stroke
			(width 0)
			(type solid)
		)
		(fill yes)
		(layer "In4.Cu")
		(net "M_D_CPU1_SB_DQS_DN<5>")
	)
	(gr_poly
		(pts
			(xy 87.271098 -276.314662) (xy 87.271098 -276.26691) (xy 87.070946 -276.26691) (xy 87.070946 -276.314662)
			(xy 87.171022 -276.414484)
		)
		(stroke
			(width 0)
			(type solid)
		)
		(fill yes)
		(layer "In4.Cu")
		(net "M_D_CPU1_SB_DQS_DN<0>")
	)
	(gr_poly
		(pts
			(xy 87.271098 -275.098256) (xy 87.171022 -274.99818) (xy 87.070946 -275.098256) (xy 87.070946 -275.142706)
			(xy 87.271098 -275.142706)
		)
		(stroke
			(width 0)
			(type solid)
		)
		(fill yes)
		(layer "In4.Cu")
		(net "M_D_CPU1_SB_DQ<1>")
	)
	(gr_poly
		(pts
			(xy 87.271098 -274.694396) (xy 87.271098 -274.649946) (xy 87.070946 -274.649946) (xy 87.070946 -274.694396)
			(xy 87.171022 -274.794472)
		)
		(stroke
			(width 0)
			(type solid)
		)
		(fill yes)
		(layer "In4.Cu")
		(net "M_D_CPU1_SB_DQ<2>")
	)
	(gr_poly
		(pts
			(xy 87.271098 -273.478244) (xy 87.171022 -273.378168) (xy 87.070946 -273.478244) (xy 87.070946 -273.522694)
			(xy 87.271098 -273.522694)
		)
		(stroke
			(width 0)
			(type solid)
		)
		(fill yes)
		(layer "In4.Cu")
		(net "M_D_CPU1_SB_CB<1>")
	)
	(gr_poly
		(pts
			(xy 87.271098 -273.074384) (xy 87.271098 -273.029934) (xy 87.070946 -273.029934) (xy 87.070946 -273.074384)
			(xy 87.171022 -273.17446)
		)
		(stroke
			(width 0)
			(type solid)
		)
		(fill yes)
		(layer "In4.Cu")
		(net "M_D_CPU1_SB_CB<2>")
	)
	(gr_poly
		(pts
			(xy 87.271098 -271.857978) (xy 87.171022 -271.758156) (xy 87.070946 -271.857978) (xy 87.070946 -271.90573)
			(xy 87.271098 -271.90573)
		)
		(stroke
			(width 0)
			(type solid)
		)
		(fill yes)
		(layer "In4.Cu")
		(net "M_D_CPU1_SB_DQS_DN<4>")
	)
	(gr_poly
		(pts
			(xy 87.271098 -271.454626) (xy 87.271098 -271.406874) (xy 87.070946 -271.406874) (xy 87.070946 -271.454626)
			(xy 87.171022 -271.554448)
		)
		(stroke
			(width 0)
			(type solid)
		)
		(fill yes)
		(layer "In4.Cu")
		(net "M_D_CPU1_SB_DQS_DN<9>")
	)
	(gr_poly
		(pts
			(xy 87.271098 -270.23822) (xy 87.171022 -270.138144) (xy 87.070946 -270.23822) (xy 87.070946 -270.28267)
			(xy 87.271098 -270.28267)
		)
		(stroke
			(width 0)
			(type solid)
		)
		(fill yes)
		(layer "In4.Cu")
		(net "M_D_CPU1_SB_CB<5>")
	)
	(gr_poly
		(pts
			(xy 87.271098 -269.83436) (xy 87.271098 -269.78991) (xy 87.070946 -269.78991) (xy 87.070946 -269.83436)
			(xy 87.171022 -269.934436)
		)
		(stroke
			(width 0)
			(type solid)
		)
		(fill yes)
		(layer "In4.Cu")
		(net "M_D_CPU1_SB_CB<6>")
	)
	(gr_poly
		(pts
			(xy 87.271098 -266.991846) (xy 87.171022 -266.89177) (xy 87.070946 -266.991846) (xy 87.070946 -267.036296)
			(xy 87.271098 -267.036296)
		)
		(stroke
			(width 0)
			(type solid)
		)
		(fill yes)
		(layer "In4.Cu")
		(net "M_D_CPU1_SA_RSP<0>")
	)
	(gr_poly
		(pts
			(xy 87.271098 -266.594336) (xy 87.271098 -266.549886) (xy 87.070946 -266.549886) (xy 87.070946 -266.594336)
			(xy 87.171022 -266.694412)
		)
		(stroke
			(width 0)
			(type solid)
		)
		(fill yes)
		(layer "In4.Cu")
		(net "M_D_CPU1_SB_CS_N<1>")
	)
	(gr_poly
		(pts
			(xy 87.271098 -264.974324) (xy 87.271098 -264.929874) (xy 87.070946 -264.929874) (xy 87.070946 -264.974324)
			(xy 87.171022 -265.0744)
		)
		(stroke
			(width 0)
			(type solid)
		)
		(fill yes)
		(layer "In4.Cu")
		(net "M_D_CPU1_SB_PAR")
	)
	(gr_poly
		(pts
			(xy 87.271098 -263.758172) (xy 87.171022 -263.658096) (xy 87.070946 -263.758172) (xy 87.070946 -263.802622)
			(xy 87.271098 -263.802622)
		)
		(stroke
			(width 0)
			(type solid)
		)
		(fill yes)
		(layer "In4.Cu")
		(net "M_D_CPU1_SB_CA<4>")
	)
	(gr_poly
		(pts
			(xy 87.271098 -263.354312) (xy 87.271098 -263.309862) (xy 87.070946 -263.309862) (xy 87.070946 -263.354312)
			(xy 87.171022 -263.454388)
		)
		(stroke
			(width 0)
			(type solid)
		)
		(fill yes)
		(layer "In4.Cu")
		(net "M_D_CPU1_SB_CA<3>")
	)
	(gr_poly
		(pts
			(xy 87.271098 -262.13816) (xy 87.171022 -262.038084) (xy 87.070946 -262.13816) (xy 87.070946 -262.18261)
			(xy 87.271098 -262.18261)
		)
		(stroke
			(width 0)
			(type solid)
		)
		(fill yes)
		(layer "In4.Cu")
		(net "M_D_CPU1_SB_CA<0>")
	)
	(gr_poly
		(pts
			(xy 87.441024 -256.432812) (xy 87.441024 -256.38506) (xy 87.240872 -256.38506) (xy 87.240872 -256.432812)
			(xy 87.340948 -256.532634)
		)
		(stroke
			(width 0)
			(type solid)
		)
		(fill yes)
		(layer "In4.Cu")
		(net "M_D_CPU1_CLK_DN<0>")
	)
	(gr_poly
		(pts
			(xy 87.441024 -255.216406) (xy 87.340948 -255.11633) (xy 87.240872 -255.216406) (xy 87.240872 -255.260856)
			(xy 87.441024 -255.260856)
		)
		(stroke
			(width 0)
			(type solid)
		)
		(fill yes)
		(layer "In4.Cu")
		(net "M_D_CPU1_SA_CA<6>")
	)
	(gr_poly
		(pts
			(xy 87.441024 -254.812546) (xy 87.441024 -254.768096) (xy 87.240872 -254.768096) (xy 87.240872 -254.812546)
			(xy 87.340948 -254.912622)
		)
		(stroke
			(width 0)
			(type solid)
		)
		(fill yes)
		(layer "In4.Cu")
		(net "M_D_CPU1_SA_CA<5>")
	)
	(gr_poly
		(pts
			(xy 87.441024 -253.596394) (xy 87.340948 -253.496318) (xy 87.240872 -253.596394) (xy 87.240872 -253.640844)
			(xy 87.441024 -253.640844)
		)
		(stroke
			(width 0)
			(type solid)
		)
		(fill yes)
		(layer "In4.Cu")
		(net "M_D_CPU1_SA_CA<2>")
	)
	(gr_poly
		(pts
			(xy 87.441024 -253.192534) (xy 87.441024 -253.148084) (xy 87.240872 -253.148084) (xy 87.240872 -253.192534)
			(xy 87.340948 -253.29261)
		)
		(stroke
			(width 0)
			(type solid)
		)
		(fill yes)
		(layer "In4.Cu")
		(net "M_D_CPU1_SA_CA<1>")
	)
	(gr_poly
		(pts
			(xy 87.441024 -251.572522) (xy 87.441024 -251.528072) (xy 87.240872 -251.528072) (xy 87.240872 -251.572522)
			(xy 87.340948 -251.672598)
		)
		(stroke
			(width 0)
			(type solid)
		)
		(fill yes)
		(layer "In4.Cu")
		(net "M_D_CPU1_SA_CS_N<0>")
	)
	(gr_poly
		(pts
			(xy 87.441024 -250.35637) (xy 87.340948 -250.256294) (xy 87.240872 -250.35637) (xy 87.240872 -250.40082)
			(xy 87.441024 -250.40082)
		)
		(stroke
			(width 0)
			(type solid)
		)
		(fill yes)
		(layer "In4.Cu")
		(net "M_D_CPU1_ALERT_R_N")
	)
	(gr_poly
		(pts
			(xy 87.441024 -248.736358) (xy 87.340948 -248.636282) (xy 87.240872 -248.736358) (xy 87.240872 -248.780808)
			(xy 87.441024 -248.780808)
		)
		(stroke
			(width 0)
			(type solid)
		)
		(fill yes)
		(layer "In4.Cu")
		(net "M_D_CPU1_SA_CB<5>")
	)
	(gr_poly
		(pts
			(xy 87.441024 -248.332498) (xy 87.441024 -248.288048) (xy 87.240872 -248.288048) (xy 87.240872 -248.332498)
			(xy 87.340948 -248.432574)
		)
		(stroke
			(width 0)
			(type solid)
		)
		(fill yes)
		(layer "In4.Cu")
		(net "M_D_CPU1_SA_CB<6>")
	)
	(gr_poly
		(pts
			(xy 87.441024 -247.116092) (xy 87.340948 -247.01627) (xy 87.240872 -247.116092) (xy 87.240872 -247.163844)
			(xy 87.441024 -247.163844)
		)
		(stroke
			(width 0)
			(type solid)
		)
		(fill yes)
		(layer "In4.Cu")
		(net "M_D_CPU1_SA_DQS_DN<9>")
	)
	(gr_poly
		(pts
			(xy 87.441024 -246.71274) (xy 87.441024 -246.664988) (xy 87.240872 -246.664988) (xy 87.240872 -246.71274)
			(xy 87.340948 -246.812562)
		)
		(stroke
			(width 0)
			(type solid)
		)
		(fill yes)
		(layer "In4.Cu")
		(net "M_D_CPU1_SA_DQS_DN<4>")
	)
	(gr_poly
		(pts
			(xy 87.441024 -245.496334) (xy 87.340948 -245.396258) (xy 87.240872 -245.496334) (xy 87.240872 -245.540784)
			(xy 87.441024 -245.540784)
		)
		(stroke
			(width 0)
			(type solid)
		)
		(fill yes)
		(layer "In4.Cu")
		(net "M_D_CPU1_SA_CB<1>")
	)
	(gr_poly
		(pts
			(xy 87.441024 -245.092474) (xy 87.441024 -245.048024) (xy 87.240872 -245.048024) (xy 87.240872 -245.092474)
			(xy 87.340948 -245.19255)
		)
		(stroke
			(width 0)
			(type solid)
		)
		(fill yes)
		(layer "In4.Cu")
		(net "M_D_CPU1_SA_CB<2>")
	)
	(gr_poly
		(pts
			(xy 87.441024 -243.876322) (xy 87.340948 -243.776246) (xy 87.240872 -243.876322) (xy 87.240872 -243.920772)
			(xy 87.441024 -243.920772)
		)
		(stroke
			(width 0)
			(type solid)
		)
		(fill yes)
		(layer "In4.Cu")
		(net "M_D_CPU1_SA_DQ<29>")
	)
	(gr_poly
		(pts
			(xy 87.441024 -243.472462) (xy 87.441024 -243.428012) (xy 87.240872 -243.428012) (xy 87.240872 -243.472462)
			(xy 87.340948 -243.572538)
		)
		(stroke
			(width 0)
			(type solid)
		)
		(fill yes)
		(layer "In4.Cu")
		(net "M_D_CPU1_SA_DQ<30>")
	)
	(gr_poly
		(pts
			(xy 87.441024 -242.256056) (xy 87.340948 -242.156234) (xy 87.240872 -242.256056) (xy 87.240872 -242.303808)
			(xy 87.441024 -242.303808)
		)
		(stroke
			(width 0)
			(type solid)
		)
		(fill yes)
		(layer "In4.Cu")
		(net "M_D_CPU1_SA_DQS_DN<8>")
	)
	(gr_poly
		(pts
			(xy 87.441024 -241.852704) (xy 87.441024 -241.804952) (xy 87.240872 -241.804952) (xy 87.240872 -241.852704)
			(xy 87.340948 -241.952526)
		)
		(stroke
			(width 0)
			(type solid)
		)
		(fill yes)
		(layer "In4.Cu")
		(net "M_D_CPU1_SA_DQS_DN<3>")
	)
	(gr_poly
		(pts
			(xy 87.441024 -240.636298) (xy 87.340948 -240.536222) (xy 87.240872 -240.636298) (xy 87.240872 -240.680748)
			(xy 87.441024 -240.680748)
		)
		(stroke
			(width 0)
			(type solid)
		)
		(fill yes)
		(layer "In4.Cu")
		(net "M_D_CPU1_SA_DQ<25>")
	)
	(gr_poly
		(pts
			(xy 87.441024 -240.232438) (xy 87.441024 -240.187988) (xy 87.240872 -240.187988) (xy 87.240872 -240.232438)
			(xy 87.340948 -240.332514)
		)
		(stroke
			(width 0)
			(type solid)
		)
		(fill yes)
		(layer "In4.Cu")
		(net "M_D_CPU1_SA_DQ<26>")
	)
	(gr_poly
		(pts
			(xy 87.441024 -239.016286) (xy 87.340948 -238.91621) (xy 87.240872 -239.016286) (xy 87.240872 -239.060736)
			(xy 87.441024 -239.060736)
		)
		(stroke
			(width 0)
			(type solid)
		)
		(fill yes)
		(layer "In4.Cu")
		(net "M_D_CPU1_SA_DQ<21>")
	)
	(gr_poly
		(pts
			(xy 87.441024 -238.612426) (xy 87.441024 -238.567976) (xy 87.240872 -238.567976) (xy 87.240872 -238.612426)
			(xy 87.340948 -238.712502)
		)
		(stroke
			(width 0)
			(type solid)
		)
		(fill yes)
		(layer "In4.Cu")
		(net "M_D_CPU1_SA_DQ<22>")
	)
	(gr_poly
		(pts
			(xy 87.441024 -237.39602) (xy 87.340948 -237.296198) (xy 87.240872 -237.39602) (xy 87.240872 -237.443772)
			(xy 87.441024 -237.443772)
		)
		(stroke
			(width 0)
			(type solid)
		)
		(fill yes)
		(layer "In4.Cu")
		(net "M_D_CPU1_SA_DQS_DN<7>")
	)
	(gr_poly
		(pts
			(xy 87.441024 -236.992668) (xy 87.441024 -236.944916) (xy 87.240872 -236.944916) (xy 87.240872 -236.992668)
			(xy 87.340948 -237.09249)
		)
		(stroke
			(width 0)
			(type solid)
		)
		(fill yes)
		(layer "In4.Cu")
		(net "M_D_CPU1_SA_DQS_DN<2>")
	)
	(gr_poly
		(pts
			(xy 87.441024 -235.776262) (xy 87.340948 -235.676186) (xy 87.240872 -235.776262) (xy 87.240872 -235.820712)
			(xy 87.441024 -235.820712)
		)
		(stroke
			(width 0)
			(type solid)
		)
		(fill yes)
		(layer "In4.Cu")
		(net "M_D_CPU1_SA_DQ<17>")
	)
	(gr_poly
		(pts
			(xy 87.441024 -235.372402) (xy 87.441024 -235.327952) (xy 87.240872 -235.327952) (xy 87.240872 -235.372402)
			(xy 87.340948 -235.472478)
		)
		(stroke
			(width 0)
			(type solid)
		)
		(fill yes)
		(layer "In4.Cu")
		(net "M_D_CPU1_SA_DQ<18>")
	)
	(gr_poly
		(pts
			(xy 87.441024 -234.15625) (xy 87.340948 -234.056174) (xy 87.240872 -234.15625) (xy 87.240872 -234.2007)
			(xy 87.441024 -234.2007)
		)
		(stroke
			(width 0)
			(type solid)
		)
		(fill yes)
		(layer "In4.Cu")
		(net "M_D_CPU1_SA_DQ<13>")
	)
	(gr_poly
		(pts
			(xy 87.441024 -233.75239) (xy 87.441024 -233.70794) (xy 87.240872 -233.70794) (xy 87.240872 -233.75239)
			(xy 87.340948 -233.852466)
		)
		(stroke
			(width 0)
			(type solid)
		)
		(fill yes)
		(layer "In4.Cu")
		(net "M_D_CPU1_SA_DQ<14>")
	)
	(gr_poly
		(pts
			(xy 87.441024 -232.535984) (xy 87.340948 -232.436162) (xy 87.240872 -232.535984) (xy 87.240872 -232.583736)
			(xy 87.441024 -232.583736)
		)
		(stroke
			(width 0)
			(type solid)
		)
		(fill yes)
		(layer "In4.Cu")
		(net "M_D_CPU1_SA_DQS_DN<6>")
	)
	(gr_poly
		(pts
			(xy 87.441024 -232.132632) (xy 87.441024 -232.08488) (xy 87.240872 -232.08488) (xy 87.240872 -232.132632)
			(xy 87.340948 -232.232454)
		)
		(stroke
			(width 0)
			(type solid)
		)
		(fill yes)
		(layer "In4.Cu")
		(net "M_D_CPU1_SA_DQS_DN<1>")
	)
	(gr_poly
		(pts
			(xy 87.441024 -230.916226) (xy 87.340948 -230.81615) (xy 87.240872 -230.916226) (xy 87.240872 -230.960676)
			(xy 87.441024 -230.960676)
		)
		(stroke
			(width 0)
			(type solid)
		)
		(fill yes)
		(layer "In4.Cu")
		(net "M_D_CPU1_SA_DQ<9>")
	)
	(gr_poly
		(pts
			(xy 87.441024 -230.51262) (xy 87.441024 -230.46817) (xy 87.240872 -230.46817) (xy 87.240872 -230.51262)
			(xy 87.340948 -230.612696)
		)
		(stroke
			(width 0)
			(type solid)
		)
		(fill yes)
		(layer "In4.Cu")
		(net "M_D_CPU1_SA_DQ<10>")
	)
	(gr_poly
		(pts
			(xy 87.441024 -229.296214) (xy 87.340948 -229.196138) (xy 87.240872 -229.296214) (xy 87.240872 -229.340664)
			(xy 87.441024 -229.340664)
		)
		(stroke
			(width 0)
			(type solid)
		)
		(fill yes)
		(layer "In4.Cu")
		(net "M_D_CPU1_SA_DQ<5>")
	)
	(gr_poly
		(pts
			(xy 87.441024 -228.892608) (xy 87.441024 -228.848158) (xy 87.240872 -228.848158) (xy 87.240872 -228.892608)
			(xy 87.340948 -228.992684)
		)
		(stroke
			(width 0)
			(type solid)
		)
		(fill yes)
		(layer "In4.Cu")
		(net "M_D_CPU1_SA_DQ<6>")
	)
	(gr_poly
		(pts
			(xy 87.441024 -227.27285) (xy 87.441024 -227.225098) (xy 87.240872 -227.225098) (xy 87.240872 -227.27285)
			(xy 87.340948 -227.372672)
		)
		(stroke
			(width 0)
			(type solid)
		)
		(fill yes)
		(layer "In4.Cu")
		(net "M_D_CPU1_SA_DQS_DN<0>")
	)
	(gr_poly
		(pts
			(xy 87.441024 -226.056444) (xy 87.340948 -225.956368) (xy 87.240872 -226.056444) (xy 87.240872 -226.100894)
			(xy 87.441024 -226.100894)
		)
		(stroke
			(width 0)
			(type solid)
		)
		(fill yes)
		(layer "In4.Cu")
		(net "M_D_CPU1_SA_DQ<1>")
	)
	(gr_poly
		(pts
			(xy 87.441024 -225.652584) (xy 87.441024 -225.608134) (xy 87.240872 -225.608134) (xy 87.240872 -225.652584)
			(xy 87.340948 -225.75266)
		)
		(stroke
			(width 0)
			(type solid)
		)
		(fill yes)
		(layer "In4.Cu")
		(net "M_D_CPU1_SA_DQ<2>")
	)
	(gr_poly
		(pts
			(xy 87.44712 -227.67671) (xy 87.347044 -227.576634) (xy 87.247222 -227.67671) (xy 87.247222 -227.724208)
			(xy 87.44712 -227.724208)
		)
		(stroke
			(width 0)
			(type solid)
		)
		(fill yes)
		(layer "In4.Cu")
		(net "M_D_CPU1_SA_DQS_DN<5>")
	)
	(gr_poly
		(pts
			(xy 87.740998 -293.32428) (xy 87.740998 -293.27983) (xy 87.540846 -293.27983) (xy 87.540846 -293.32428)
			(xy 87.640922 -293.424356)
		)
		(stroke
			(width 0)
			(type solid)
		)
		(fill yes)
		(layer "In4.Cu")
		(net "M_D_CPU1_SB_DQ<31>")
	)
	(gr_poly
		(pts
			(xy 87.740998 -292.108128) (xy 87.640922 -292.008052) (xy 87.540846 -292.108128) (xy 87.540846 -292.152578)
			(xy 87.740998 -292.152578)
		)
		(stroke
			(width 0)
			(type solid)
		)
		(fill yes)
		(layer "In4.Cu")
		(net "M_D_CPU1_SB_DQ<28>")
	)
	(gr_poly
		(pts
			(xy 87.740998 -291.704522) (xy 87.740998 -291.65677) (xy 87.540846 -291.65677) (xy 87.540846 -291.704522)
			(xy 87.640922 -291.804344)
		)
		(stroke
			(width 0)
			(type solid)
		)
		(fill yes)
		(layer "In4.Cu")
		(net "M_D_CPU1_SB_DQS_DP<8>")
	)
	(gr_poly
		(pts
			(xy 87.740998 -290.487862) (xy 87.640922 -290.38804) (xy 87.540846 -290.487862) (xy 87.540846 -290.535614)
			(xy 87.740998 -290.535614)
		)
		(stroke
			(width 0)
			(type solid)
		)
		(fill yes)
		(layer "In4.Cu")
		(net "M_D_CPU1_SB_DQS_DP<3>")
	)
	(gr_poly
		(pts
			(xy 87.740998 -290.084256) (xy 87.740998 -290.039806) (xy 87.540846 -290.039806) (xy 87.540846 -290.084256)
			(xy 87.640922 -290.184332)
		)
		(stroke
			(width 0)
			(type solid)
		)
		(fill yes)
		(layer "In4.Cu")
		(net "M_D_CPU1_SB_DQ<27>")
	)
	(gr_poly
		(pts
			(xy 87.740998 -288.868104) (xy 87.640922 -288.768028) (xy 87.540846 -288.868104) (xy 87.540846 -288.912554)
			(xy 87.740998 -288.912554)
		)
		(stroke
			(width 0)
			(type solid)
		)
		(fill yes)
		(layer "In4.Cu")
		(net "M_D_CPU1_SB_DQ<24>")
	)
	(gr_poly
		(pts
			(xy 87.740998 -288.464498) (xy 87.740998 -288.420048) (xy 87.540846 -288.420048) (xy 87.540846 -288.464498)
			(xy 87.640922 -288.564574)
		)
		(stroke
			(width 0)
			(type solid)
		)
		(fill yes)
		(layer "In4.Cu")
		(net "M_D_CPU1_SB_DQ<23>")
	)
	(gr_poly
		(pts
			(xy 87.740998 -287.248092) (xy 87.640922 -287.148016) (xy 87.540846 -287.248092) (xy 87.540846 -287.292542)
			(xy 87.740998 -287.292542)
		)
		(stroke
			(width 0)
			(type solid)
		)
		(fill yes)
		(layer "In4.Cu")
		(net "M_D_CPU1_SB_DQ<20>")
	)
	(gr_poly
		(pts
			(xy 87.740998 -286.844486) (xy 87.740998 -286.796734) (xy 87.540846 -286.796734) (xy 87.540846 -286.844486)
			(xy 87.640922 -286.944562)
		)
		(stroke
			(width 0)
			(type solid)
		)
		(fill yes)
		(layer "In4.Cu")
		(net "M_D_CPU1_SB_DQS_DP<7>")
	)
	(gr_poly
		(pts
			(xy 87.740998 -285.62808) (xy 87.640922 -285.528258) (xy 87.540846 -285.62808) (xy 87.540846 -285.675832)
			(xy 87.740998 -285.675832)
		)
		(stroke
			(width 0)
			(type solid)
		)
		(fill yes)
		(layer "In4.Cu")
		(net "M_D_CPU1_SB_DQS_DP<2>")
	)
	(gr_poly
		(pts
			(xy 87.740998 -285.224474) (xy 87.740998 -285.180024) (xy 87.540846 -285.180024) (xy 87.540846 -285.224474)
			(xy 87.640922 -285.32455)
		)
		(stroke
			(width 0)
			(type solid)
		)
		(fill yes)
		(layer "In4.Cu")
		(net "M_D_CPU1_SB_DQ<19>")
	)
	(gr_poly
		(pts
			(xy 87.740998 -284.008322) (xy 87.640922 -283.908246) (xy 87.540846 -284.008322) (xy 87.540846 -284.052772)
			(xy 87.740998 -284.052772)
		)
		(stroke
			(width 0)
			(type solid)
		)
		(fill yes)
		(layer "In4.Cu")
		(net "M_D_CPU1_SB_DQ<16>")
	)
	(gr_poly
		(pts
			(xy 87.740998 -283.604462) (xy 87.740998 -283.560012) (xy 87.540846 -283.560012) (xy 87.540846 -283.604462)
			(xy 87.640922 -283.704538)
		)
		(stroke
			(width 0)
			(type solid)
		)
		(fill yes)
		(layer "In4.Cu")
		(net "M_D_CPU1_SB_DQ<15>")
	)
	(gr_poly
		(pts
			(xy 87.740998 -282.38831) (xy 87.640922 -282.288234) (xy 87.540846 -282.38831) (xy 87.540846 -282.43276)
			(xy 87.740998 -282.43276)
		)
		(stroke
			(width 0)
			(type solid)
		)
		(fill yes)
		(layer "In4.Cu")
		(net "M_D_CPU1_SB_DQ<12>")
	)
	(gr_poly
		(pts
			(xy 87.740998 -281.984704) (xy 87.740998 -281.936952) (xy 87.540846 -281.936952) (xy 87.540846 -281.984704)
			(xy 87.640922 -282.084526)
		)
		(stroke
			(width 0)
			(type solid)
		)
		(fill yes)
		(layer "In4.Cu")
		(net "M_D_CPU1_SB_DQS_DP<6>")
	)
	(gr_poly
		(pts
			(xy 87.740998 -280.768044) (xy 87.640922 -280.668222) (xy 87.540846 -280.768044) (xy 87.540846 -280.815796)
			(xy 87.740998 -280.815796)
		)
		(stroke
			(width 0)
			(type solid)
		)
		(fill yes)
		(layer "In4.Cu")
		(net "M_D_CPU1_SB_DQS_DP<1>")
	)
	(gr_poly
		(pts
			(xy 87.740998 -280.364438) (xy 87.740998 -280.319988) (xy 87.540846 -280.319988) (xy 87.540846 -280.364438)
			(xy 87.640922 -280.464514)
		)
		(stroke
			(width 0)
			(type solid)
		)
		(fill yes)
		(layer "In4.Cu")
		(net "M_D_CPU1_SB_DQ<11>")
	)
	(gr_poly
		(pts
			(xy 87.740998 -279.148286) (xy 87.640922 -279.04821) (xy 87.540846 -279.148286) (xy 87.540846 -279.192736)
			(xy 87.740998 -279.192736)
		)
		(stroke
			(width 0)
			(type solid)
		)
		(fill yes)
		(layer "In4.Cu")
		(net "M_D_CPU1_SB_DQ<8>")
	)
	(gr_poly
		(pts
			(xy 87.740998 -278.744426) (xy 87.740998 -278.699976) (xy 87.540846 -278.699976) (xy 87.540846 -278.744426)
			(xy 87.640922 -278.844502)
		)
		(stroke
			(width 0)
			(type solid)
		)
		(fill yes)
		(layer "In4.Cu")
		(net "M_D_CPU1_SB_DQ<7>")
	)
	(gr_poly
		(pts
			(xy 87.740998 -277.528274) (xy 87.640922 -277.428198) (xy 87.540846 -277.528274) (xy 87.540846 -277.572724)
			(xy 87.740998 -277.572724)
		)
		(stroke
			(width 0)
			(type solid)
		)
		(fill yes)
		(layer "In4.Cu")
		(net "M_D_CPU1_SB_DQ<4>")
	)
	(gr_poly
		(pts
			(xy 87.740998 -275.504402) (xy 87.740998 -275.459952) (xy 87.540846 -275.459952) (xy 87.540846 -275.504402)
			(xy 87.640922 -275.604478)
		)
		(stroke
			(width 0)
			(type solid)
		)
		(fill yes)
		(layer "In4.Cu")
		(net "M_D_CPU1_SB_DQ<3>")
	)
	(gr_poly
		(pts
			(xy 87.740998 -274.28825) (xy 87.640922 -274.188174) (xy 87.540846 -274.28825) (xy 87.540846 -274.3327)
			(xy 87.740998 -274.3327)
		)
		(stroke
			(width 0)
			(type solid)
		)
		(fill yes)
		(layer "In4.Cu")
		(net "M_D_CPU1_SB_DQ<0>")
	)
	(gr_poly
		(pts
			(xy 87.740998 -273.88439) (xy 87.740998 -273.83994) (xy 87.540846 -273.83994) (xy 87.540846 -273.88439)
			(xy 87.640922 -273.984466)
		)
		(stroke
			(width 0)
			(type solid)
		)
		(fill yes)
		(layer "In4.Cu")
		(net "M_D_CPU1_SB_CB<3>")
	)
	(gr_poly
		(pts
			(xy 87.740998 -272.668238) (xy 87.640922 -272.568162) (xy 87.540846 -272.668238) (xy 87.540846 -272.712688)
			(xy 87.740998 -272.712688)
		)
		(stroke
			(width 0)
			(type solid)
		)
		(fill yes)
		(layer "In4.Cu")
		(net "M_D_CPU1_SB_CB<0>")
	)
	(gr_poly
		(pts
			(xy 87.740998 -272.264632) (xy 87.740998 -272.21688) (xy 87.540846 -272.21688) (xy 87.540846 -272.264632)
			(xy 87.640922 -272.364454)
		)
		(stroke
			(width 0)
			(type solid)
		)
		(fill yes)
		(layer "In4.Cu")
		(net "M_D_CPU1_SB_DQS_DP<4>")
	)
	(gr_poly
		(pts
			(xy 87.740998 -271.047972) (xy 87.640922 -270.94815) (xy 87.540846 -271.047972) (xy 87.540846 -271.095724)
			(xy 87.740998 -271.095724)
		)
		(stroke
			(width 0)
			(type solid)
		)
		(fill yes)
		(layer "In4.Cu")
		(net "M_D_CPU1_SB_DQS_DP<9>")
	)
	(gr_poly
		(pts
			(xy 87.740998 -270.644366) (xy 87.740998 -270.599916) (xy 87.540846 -270.599916) (xy 87.540846 -270.644366)
			(xy 87.640922 -270.744442)
		)
		(stroke
			(width 0)
			(type solid)
		)
		(fill yes)
		(layer "In4.Cu")
		(net "M_D_CPU1_SB_CB<7>")
	)
	(gr_poly
		(pts
			(xy 87.740998 -269.428214) (xy 87.640922 -269.328138) (xy 87.540846 -269.428214) (xy 87.540846 -269.472664)
			(xy 87.740998 -269.472664)
		)
		(stroke
			(width 0)
			(type solid)
		)
		(fill yes)
		(layer "In4.Cu")
		(net "M_D_CPU1_SB_CB<4>")
	)
	(gr_poly
		(pts
			(xy 87.740998 -265.78433) (xy 87.740998 -265.73988) (xy 87.540846 -265.73988) (xy 87.540846 -265.78433)
			(xy 87.640922 -265.884406)
		)
		(stroke
			(width 0)
			(type solid)
		)
		(fill yes)
		(layer "In4.Cu")
		(net "M_D_CPU1_SB_CS_N<0>")
	)
	(gr_poly
		(pts
			(xy 87.740998 -264.568178) (xy 87.640922 -264.468102) (xy 87.540846 -264.568178) (xy 87.540846 -264.612628)
			(xy 87.740998 -264.612628)
		)
		(stroke
			(width 0)
			(type solid)
		)
		(fill yes)
		(layer "In4.Cu")
		(net "M_D_CPU1_SB_CA<6>")
	)
	(gr_poly
		(pts
			(xy 87.740998 -264.164318) (xy 87.740998 -264.119868) (xy 87.540846 -264.119868) (xy 87.540846 -264.164318)
			(xy 87.640922 -264.264394)
		)
		(stroke
			(width 0)
			(type solid)
		)
		(fill yes)
		(layer "In4.Cu")
		(net "M_D_CPU1_SB_CA<5>")
	)
	(gr_poly
		(pts
			(xy 87.740998 -262.948166) (xy 87.640922 -262.84809) (xy 87.540846 -262.948166) (xy 87.540846 -262.992616)
			(xy 87.740998 -262.992616)
		)
		(stroke
			(width 0)
			(type solid)
		)
		(fill yes)
		(layer "In4.Cu")
		(net "M_D_CPU1_SB_CA<2>")
	)
	(gr_poly
		(pts
			(xy 87.740998 -262.544306) (xy 87.740998 -262.499856) (xy 87.540846 -262.499856) (xy 87.540846 -262.544306)
			(xy 87.640922 -262.644382)
		)
		(stroke
			(width 0)
			(type solid)
		)
		(fill yes)
		(layer "In4.Cu")
		(net "M_D_CPU1_SB_CA<1>")
	)
	(gr_poly
		(pts
			(xy 87.747094 -267.801852) (xy 87.647272 -267.701776) (xy 87.547196 -267.801852) (xy 87.547196 -267.846302)
			(xy 87.747094 -267.846302)
		)
		(stroke
			(width 0)
			(type solid)
		)
		(fill yes)
		(layer "In4.Cu")
		(net "M_D_CPU1_SB_RSP<0>")
	)
	(gr_poly
		(pts
			(xy 87.74811 -277.124668) (xy 87.74811 -277.076916) (xy 87.548212 -277.076916) (xy 87.548212 -277.124668)
			(xy 87.648288 -277.22449)
		)
		(stroke
			(width 0)
			(type solid)
		)
		(fill yes)
		(layer "In4.Cu")
		(net "M_D_CPU1_SB_DQS_DP<5>")
	)
	(gr_poly
		(pts
			(xy 87.74811 -275.908008) (xy 87.648288 -275.808186) (xy 87.548212 -275.908008) (xy 87.548212 -275.95576)
			(xy 87.74811 -275.95576)
		)
		(stroke
			(width 0)
			(type solid)
		)
		(fill yes)
		(layer "In4.Cu")
		(net "M_D_CPU1_SB_DQS_DP<0>")
	)
	(gr_poly
		(pts
			(xy 87.911178 -256.026158) (xy 87.811102 -255.926336) (xy 87.711026 -256.026158) (xy 87.711026 -256.07391)
			(xy 87.911178 -256.07391)
		)
		(stroke
			(width 0)
			(type solid)
		)
		(fill yes)
		(layer "In4.Cu")
		(net "M_D_CPU1_CLK_DP<0>")
	)
	(gr_poly
		(pts
			(xy 87.911178 -255.622552) (xy 87.911178 -255.578102) (xy 87.711026 -255.578102) (xy 87.711026 -255.622552)
			(xy 87.811102 -255.722628)
		)
		(stroke
			(width 0)
			(type solid)
		)
		(fill yes)
		(layer "In4.Cu")
		(net "M_D_CPU1_SA_PAR")
	)
	(gr_poly
		(pts
			(xy 87.911178 -254.4064) (xy 87.811102 -254.306324) (xy 87.711026 -254.4064) (xy 87.711026 -254.45085)
			(xy 87.911178 -254.45085)
		)
		(stroke
			(width 0)
			(type solid)
		)
		(fill yes)
		(layer "In4.Cu")
		(net "M_D_CPU1_SA_CA<4>")
	)
	(gr_poly
		(pts
			(xy 87.911178 -254.00254) (xy 87.911178 -253.95809) (xy 87.711026 -253.95809) (xy 87.711026 -254.00254)
			(xy 87.811102 -254.102616)
		)
		(stroke
			(width 0)
			(type solid)
		)
		(fill yes)
		(layer "In4.Cu")
		(net "M_D_CPU1_SA_CA<3>")
	)
	(gr_poly
		(pts
			(xy 87.911178 -252.786388) (xy 87.811102 -252.686312) (xy 87.711026 -252.786388) (xy 87.711026 -252.830838)
			(xy 87.911178 -252.830838)
		)
		(stroke
			(width 0)
			(type solid)
		)
		(fill yes)
		(layer "In4.Cu")
		(net "M_D_CPU1_SA_CA<0>")
	)
	(gr_poly
		(pts
			(xy 87.911178 -252.382528) (xy 87.911178 -252.338078) (xy 87.711026 -252.338078) (xy 87.711026 -252.382528)
			(xy 87.811102 -252.482604)
		)
		(stroke
			(width 0)
			(type solid)
		)
		(fill yes)
		(layer "In4.Cu")
		(net "M_D_CPU1_SA_CS_N<1>")
	)
	(gr_poly
		(pts
			(xy 87.911178 -250.762516) (xy 87.911178 -250.718066) (xy 87.711026 -250.718066) (xy 87.711026 -250.762516)
			(xy 87.811102 -250.862592)
		)
		(stroke
			(width 0)
			(type solid)
		)
		(fill yes)
		(layer "In4.Cu")
		(net "M_D_CPU1_RESET_N")
	)
	(gr_poly
		(pts
			(xy 87.911178 -249.142504) (xy 87.911178 -249.098054) (xy 87.711026 -249.098054) (xy 87.711026 -249.142504)
			(xy 87.811102 -249.24258)
		)
		(stroke
			(width 0)
			(type solid)
		)
		(fill yes)
		(layer "In4.Cu")
		(net "M_D_CPU1_SA_CB<7>")
	)
	(gr_poly
		(pts
			(xy 87.911178 -247.926352) (xy 87.811102 -247.826276) (xy 87.711026 -247.926352) (xy 87.711026 -247.970802)
			(xy 87.911178 -247.970802)
		)
		(stroke
			(width 0)
			(type solid)
		)
		(fill yes)
		(layer "In4.Cu")
		(net "M_D_CPU1_SA_CB<4>")
	)
	(gr_poly
		(pts
			(xy 87.911178 -247.522746) (xy 87.911178 -247.474994) (xy 87.711026 -247.474994) (xy 87.711026 -247.522746)
			(xy 87.811102 -247.622568)
		)
		(stroke
			(width 0)
			(type solid)
		)
		(fill yes)
		(layer "In4.Cu")
		(net "M_D_CPU1_SA_DQS_DP<9>")
	)
	(gr_poly
		(pts
			(xy 87.911178 -246.306086) (xy 87.811102 -246.206264) (xy 87.711026 -246.306086) (xy 87.711026 -246.353838)
			(xy 87.911178 -246.353838)
		)
		(stroke
			(width 0)
			(type solid)
		)
		(fill yes)
		(layer "In4.Cu")
		(net "M_D_CPU1_SA_DQS_DP<4>")
	)
	(gr_poly
		(pts
			(xy 87.911178 -245.90248) (xy 87.911178 -245.85803) (xy 87.711026 -245.85803) (xy 87.711026 -245.90248)
			(xy 87.811102 -246.002556)
		)
		(stroke
			(width 0)
			(type solid)
		)
		(fill yes)
		(layer "In4.Cu")
		(net "M_D_CPU1_SA_CB<3>")
	)
	(gr_poly
		(pts
			(xy 87.911178 -244.686328) (xy 87.811102 -244.586252) (xy 87.711026 -244.686328) (xy 87.711026 -244.730778)
			(xy 87.911178 -244.730778)
		)
		(stroke
			(width 0)
			(type solid)
		)
		(fill yes)
		(layer "In4.Cu")
		(net "M_D_CPU1_SA_CB<0>")
	)
	(gr_poly
		(pts
			(xy 87.911178 -244.282468) (xy 87.911178 -244.238018) (xy 87.711026 -244.238018) (xy 87.711026 -244.282468)
			(xy 87.811102 -244.382544)
		)
		(stroke
			(width 0)
			(type solid)
		)
		(fill yes)
		(layer "In4.Cu")
		(net "M_D_CPU1_SA_DQ<31>")
	)
	(gr_poly
		(pts
			(xy 87.911178 -243.066316) (xy 87.811102 -242.96624) (xy 87.711026 -243.066316) (xy 87.711026 -243.110766)
			(xy 87.911178 -243.110766)
		)
		(stroke
			(width 0)
			(type solid)
		)
		(fill yes)
		(layer "In4.Cu")
		(net "M_D_CPU1_SA_DQ<28>")
	)
	(gr_poly
		(pts
			(xy 87.911178 -242.66271) (xy 87.911178 -242.614958) (xy 87.711026 -242.614958) (xy 87.711026 -242.66271)
			(xy 87.811102 -242.762532)
		)
		(stroke
			(width 0)
			(type solid)
		)
		(fill yes)
		(layer "In4.Cu")
		(net "M_D_CPU1_SA_DQS_DP<8>")
	)
	(gr_poly
		(pts
			(xy 87.911178 -241.44605) (xy 87.811102 -241.346228) (xy 87.711026 -241.44605) (xy 87.711026 -241.493802)
			(xy 87.911178 -241.493802)
		)
		(stroke
			(width 0)
			(type solid)
		)
		(fill yes)
		(layer "In4.Cu")
		(net "M_D_CPU1_SA_DQS_DP<3>")
	)
	(gr_poly
		(pts
			(xy 87.911178 -241.042444) (xy 87.911178 -240.997994) (xy 87.711026 -240.997994) (xy 87.711026 -241.042444)
			(xy 87.811102 -241.14252)
		)
		(stroke
			(width 0)
			(type solid)
		)
		(fill yes)
		(layer "In4.Cu")
		(net "M_D_CPU1_SA_DQ<27>")
	)
	(gr_poly
		(pts
			(xy 87.911178 -239.826292) (xy 87.811102 -239.726216) (xy 87.711026 -239.826292) (xy 87.711026 -239.870742)
			(xy 87.911178 -239.870742)
		)
		(stroke
			(width 0)
			(type solid)
		)
		(fill yes)
		(layer "In4.Cu")
		(net "M_D_CPU1_SA_DQ<24>")
	)
	(gr_poly
		(pts
			(xy 87.911178 -239.422432) (xy 87.911178 -239.377982) (xy 87.711026 -239.377982) (xy 87.711026 -239.422432)
			(xy 87.811102 -239.522508)
		)
		(stroke
			(width 0)
			(type solid)
		)
		(fill yes)
		(layer "In4.Cu")
		(net "M_D_CPU1_SA_DQ<23>")
	)
	(gr_poly
		(pts
			(xy 87.911178 -238.20628) (xy 87.811102 -238.106204) (xy 87.711026 -238.20628) (xy 87.711026 -238.25073)
			(xy 87.911178 -238.25073)
		)
		(stroke
			(width 0)
			(type solid)
		)
		(fill yes)
		(layer "In4.Cu")
		(net "M_D_CPU1_SA_DQ<20>")
	)
	(gr_poly
		(pts
			(xy 87.911178 -237.802674) (xy 87.911178 -237.754922) (xy 87.711026 -237.754922) (xy 87.711026 -237.802674)
			(xy 87.811102 -237.902496)
		)
		(stroke
			(width 0)
			(type solid)
		)
		(fill yes)
		(layer "In4.Cu")
		(net "M_D_CPU1_SA_DQS_DP<7>")
	)
	(gr_poly
		(pts
			(xy 87.911178 -236.586014) (xy 87.811102 -236.486192) (xy 87.711026 -236.586014) (xy 87.711026 -236.633766)
			(xy 87.911178 -236.633766)
		)
		(stroke
			(width 0)
			(type solid)
		)
		(fill yes)
		(layer "In4.Cu")
		(net "M_D_CPU1_SA_DQS_DP<2>")
	)
	(gr_poly
		(pts
			(xy 87.911178 -236.182408) (xy 87.911178 -236.137958) (xy 87.711026 -236.137958) (xy 87.711026 -236.182408)
			(xy 87.811102 -236.282484)
		)
		(stroke
			(width 0)
			(type solid)
		)
		(fill yes)
		(layer "In4.Cu")
		(net "M_D_CPU1_SA_DQ<19>")
	)
	(gr_poly
		(pts
			(xy 87.911178 -234.966256) (xy 87.811102 -234.86618) (xy 87.711026 -234.966256) (xy 87.711026 -235.010706)
			(xy 87.911178 -235.010706)
		)
		(stroke
			(width 0)
			(type solid)
		)
		(fill yes)
		(layer "In4.Cu")
		(net "M_D_CPU1_SA_DQ<16>")
	)
	(gr_poly
		(pts
			(xy 87.911178 -234.562396) (xy 87.911178 -234.517946) (xy 87.711026 -234.517946) (xy 87.711026 -234.562396)
			(xy 87.811102 -234.662472)
		)
		(stroke
			(width 0)
			(type solid)
		)
		(fill yes)
		(layer "In4.Cu")
		(net "M_D_CPU1_SA_DQ<15>")
	)
	(gr_poly
		(pts
			(xy 87.911178 -233.346244) (xy 87.811102 -233.246168) (xy 87.711026 -233.346244) (xy 87.711026 -233.390694)
			(xy 87.911178 -233.390694)
		)
		(stroke
			(width 0)
			(type solid)
		)
		(fill yes)
		(layer "In4.Cu")
		(net "M_D_CPU1_SA_DQ<12>")
	)
	(gr_poly
		(pts
			(xy 87.911178 -232.942638) (xy 87.911178 -232.894886) (xy 87.711026 -232.894886) (xy 87.711026 -232.942638)
			(xy 87.811102 -233.04246)
		)
		(stroke
			(width 0)
			(type solid)
		)
		(fill yes)
		(layer "In4.Cu")
		(net "M_D_CPU1_SA_DQS_DP<6>")
	)
	(gr_poly
		(pts
			(xy 87.911178 -231.725978) (xy 87.811102 -231.626156) (xy 87.711026 -231.725978) (xy 87.711026 -231.77373)
			(xy 87.911178 -231.77373)
		)
		(stroke
			(width 0)
			(type solid)
		)
		(fill yes)
		(layer "In4.Cu")
		(net "M_D_CPU1_SA_DQS_DP<1>")
	)
	(gr_poly
		(pts
			(xy 87.911178 -231.322626) (xy 87.911178 -231.278176) (xy 87.711026 -231.278176) (xy 87.711026 -231.322626)
			(xy 87.811102 -231.422702)
		)
		(stroke
			(width 0)
			(type solid)
		)
		(fill yes)
		(layer "In4.Cu")
		(net "M_D_CPU1_SA_DQ<11>")
	)
	(gr_poly
		(pts
			(xy 87.911178 -230.10622) (xy 87.811102 -230.006144) (xy 87.711026 -230.10622) (xy 87.711026 -230.15067)
			(xy 87.911178 -230.15067)
		)
		(stroke
			(width 0)
			(type solid)
		)
		(fill yes)
		(layer "In4.Cu")
		(net "M_D_CPU1_SA_DQ<8>")
	)
	(gr_poly
		(pts
			(xy 87.911178 -229.702614) (xy 87.911178 -229.658164) (xy 87.711026 -229.658164) (xy 87.711026 -229.702614)
			(xy 87.811102 -229.80269)
		)
		(stroke
			(width 0)
			(type solid)
		)
		(fill yes)
		(layer "In4.Cu")
		(net "M_D_CPU1_SA_DQ<7>")
	)
	(gr_poly
		(pts
			(xy 87.911178 -228.486462) (xy 87.811102 -228.386386) (xy 87.711026 -228.486462) (xy 87.711026 -228.530912)
			(xy 87.911178 -228.530912)
		)
		(stroke
			(width 0)
			(type solid)
		)
		(fill yes)
		(layer "In4.Cu")
		(net "M_D_CPU1_SA_DQ<4>")
	)
	(gr_poly
		(pts
			(xy 87.911178 -228.082856) (xy 87.911178 -228.035104) (xy 87.711026 -228.035104) (xy 87.711026 -228.082856)
			(xy 87.811102 -228.182678)
		)
		(stroke
			(width 0)
			(type solid)
		)
		(fill yes)
		(layer "In4.Cu")
		(net "M_D_CPU1_SA_DQS_DP<5>")
	)
	(gr_poly
		(pts
			(xy 87.911178 -226.866196) (xy 87.811102 -226.766374) (xy 87.711026 -226.866196) (xy 87.711026 -226.913948)
			(xy 87.911178 -226.913948)
		)
		(stroke
			(width 0)
			(type solid)
		)
		(fill yes)
		(layer "In4.Cu")
		(net "M_D_CPU1_SA_DQS_DP<0>")
	)
	(gr_poly
		(pts
			(xy 87.911178 -226.46259) (xy 87.911178 -226.41814) (xy 87.711026 -226.41814) (xy 87.711026 -226.46259)
			(xy 87.811102 -226.562666)
		)
		(stroke
			(width 0)
			(type solid)
		)
		(fill yes)
		(layer "In4.Cu")
		(net "M_D_CPU1_SA_DQ<3>")
	)
	(gr_poly
		(pts
			(xy 87.911178 -225.246438) (xy 87.811102 -225.146362) (xy 87.711026 -225.246438) (xy 87.711026 -225.290888)
			(xy 87.911178 -225.290888)
		)
		(stroke
			(width 0)
			(type solid)
		)
		(fill yes)
		(layer "In4.Cu")
		(net "M_D_CPU1_SA_DQ<0>")
	)
	(gr_poly
		(pts
			(xy 88.204802 -266.991846) (xy 88.104726 -266.89177) (xy 88.004904 -266.991846) (xy 88.004904 -267.036296)
			(xy 88.204802 -267.036296)
		)
		(stroke
			(width 0)
			(type solid)
		)
		(fill yes)
		(layer "In4.Cu")
		(net "M_D_CPU1_SA_RSP<0>")
	)
	(gr_poly
		(pts
			(xy 88.211152 -292.918134) (xy 88.111076 -292.818058) (xy 88.011 -292.918134) (xy 88.011 -292.962584)
			(xy 88.211152 -292.962584)
		)
		(stroke
			(width 0)
			(type solid)
		)
		(fill yes)
		(layer "In4.Cu")
		(net "M_D_CPU1_SB_DQ<29>")
	)
	(gr_poly
		(pts
			(xy 88.211152 -292.514274) (xy 88.211152 -292.469824) (xy 88.011 -292.469824) (xy 88.011 -292.514274)
			(xy 88.111076 -292.61435)
		)
		(stroke
			(width 0)
			(type solid)
		)
		(fill yes)
		(layer "In4.Cu")
		(net "M_D_CPU1_SB_DQ<30>")
	)
	(gr_poly
		(pts
			(xy 88.211152 -291.297868) (xy 88.111076 -291.198046) (xy 88.011 -291.297868) (xy 88.011 -291.34562)
			(xy 88.211152 -291.34562)
		)
		(stroke
			(width 0)
			(type solid)
		)
		(fill yes)
		(layer "In4.Cu")
		(net "M_D_CPU1_SB_DQS_DN<8>")
	)
	(gr_poly
		(pts
			(xy 88.211152 -290.894516) (xy 88.211152 -290.846764) (xy 88.011 -290.846764) (xy 88.011 -290.894516)
			(xy 88.111076 -290.994338)
		)
		(stroke
			(width 0)
			(type solid)
		)
		(fill yes)
		(layer "In4.Cu")
		(net "M_D_CPU1_SB_DQS_DN<3>")
	)
	(gr_poly
		(pts
			(xy 88.211152 -289.67811) (xy 88.111076 -289.578034) (xy 88.011 -289.67811) (xy 88.011 -289.72256)
			(xy 88.211152 -289.72256)
		)
		(stroke
			(width 0)
			(type solid)
		)
		(fill yes)
		(layer "In4.Cu")
		(net "M_D_CPU1_SB_DQ<25>")
	)
	(gr_poly
		(pts
			(xy 88.211152 -289.27425) (xy 88.211152 -289.2298) (xy 88.011 -289.2298) (xy 88.011 -289.27425) (xy 88.111076 -289.374326)
		)
		(stroke
			(width 0)
			(type solid)
		)
		(fill yes)
		(layer "In4.Cu")
		(net "M_D_CPU1_SB_DQ<26>")
	)
	(gr_poly
		(pts
			(xy 88.211152 -288.058098) (xy 88.111076 -287.958022) (xy 88.011 -288.058098) (xy 88.011 -288.102548)
			(xy 88.211152 -288.102548)
		)
		(stroke
			(width 0)
			(type solid)
		)
		(fill yes)
		(layer "In4.Cu")
		(net "M_D_CPU1_SB_DQ<21>")
	)
	(gr_poly
		(pts
			(xy 88.211152 -287.654492) (xy 88.211152 -287.610042) (xy 88.011 -287.610042) (xy 88.011 -287.654492)
			(xy 88.111076 -287.754568)
		)
		(stroke
			(width 0)
			(type solid)
		)
		(fill yes)
		(layer "In4.Cu")
		(net "M_D_CPU1_SB_DQ<22>")
	)
	(gr_poly
		(pts
			(xy 88.211152 -286.438086) (xy 88.111076 -286.33801) (xy 88.011 -286.438086) (xy 88.011 -286.485838)
			(xy 88.211152 -286.485838)
		)
		(stroke
			(width 0)
			(type solid)
		)
		(fill yes)
		(layer "In4.Cu")
		(net "M_D_CPU1_SB_DQS_DN<7>")
	)
	(gr_poly
		(pts
			(xy 88.211152 -286.034734) (xy 88.211152 -285.986982) (xy 88.011 -285.986982) (xy 88.011 -286.034734)
			(xy 88.111076 -286.134556)
		)
		(stroke
			(width 0)
			(type solid)
		)
		(fill yes)
		(layer "In4.Cu")
		(net "M_D_CPU1_SB_DQS_DN<2>")
	)
	(gr_poly
		(pts
			(xy 88.211152 -284.818328) (xy 88.111076 -284.718252) (xy 88.011 -284.818328) (xy 88.011 -284.862778)
			(xy 88.211152 -284.862778)
		)
		(stroke
			(width 0)
			(type solid)
		)
		(fill yes)
		(layer "In4.Cu")
		(net "M_D_CPU1_SB_DQ<17>")
	)
	(gr_poly
		(pts
			(xy 88.211152 -284.414468) (xy 88.211152 -284.370018) (xy 88.011 -284.370018) (xy 88.011 -284.414468)
			(xy 88.111076 -284.514544)
		)
		(stroke
			(width 0)
			(type solid)
		)
		(fill yes)
		(layer "In4.Cu")
		(net "M_D_CPU1_SB_DQ<18>")
	)
	(gr_poly
		(pts
			(xy 88.211152 -283.198316) (xy 88.111076 -283.09824) (xy 88.011 -283.198316) (xy 88.011 -283.242766)
			(xy 88.211152 -283.242766)
		)
		(stroke
			(width 0)
			(type solid)
		)
		(fill yes)
		(layer "In4.Cu")
		(net "M_D_CPU1_SB_DQ<13>")
	)
	(gr_poly
		(pts
			(xy 88.211152 -282.794456) (xy 88.211152 -282.750006) (xy 88.011 -282.750006) (xy 88.011 -282.794456)
			(xy 88.111076 -282.894532)
		)
		(stroke
			(width 0)
			(type solid)
		)
		(fill yes)
		(layer "In4.Cu")
		(net "M_D_CPU1_SB_DQ<14>")
	)
	(gr_poly
		(pts
			(xy 88.211152 -281.57805) (xy 88.111076 -281.478228) (xy 88.011 -281.57805) (xy 88.011 -281.625802)
			(xy 88.211152 -281.625802)
		)
		(stroke
			(width 0)
			(type solid)
		)
		(fill yes)
		(layer "In4.Cu")
		(net "M_D_CPU1_SB_DQS_DN<6>")
	)
	(gr_poly
		(pts
			(xy 88.211152 -281.174698) (xy 88.211152 -281.126946) (xy 88.011 -281.126946) (xy 88.011 -281.174698)
			(xy 88.111076 -281.27452)
		)
		(stroke
			(width 0)
			(type solid)
		)
		(fill yes)
		(layer "In4.Cu")
		(net "M_D_CPU1_SB_DQS_DN<1>")
	)
	(gr_poly
		(pts
			(xy 88.211152 -279.958292) (xy 88.111076 -279.858216) (xy 88.011 -279.958292) (xy 88.011 -280.002742)
			(xy 88.211152 -280.002742)
		)
		(stroke
			(width 0)
			(type solid)
		)
		(fill yes)
		(layer "In4.Cu")
		(net "M_D_CPU1_SB_DQ<9>")
	)
	(gr_poly
		(pts
			(xy 88.211152 -279.554432) (xy 88.211152 -279.509982) (xy 88.011 -279.509982) (xy 88.011 -279.554432)
			(xy 88.111076 -279.654508)
		)
		(stroke
			(width 0)
			(type solid)
		)
		(fill yes)
		(layer "In4.Cu")
		(net "M_D_CPU1_SB_DQ<10>")
	)
	(gr_poly
		(pts
			(xy 88.211152 -278.33828) (xy 88.111076 -278.238204) (xy 88.011 -278.33828) (xy 88.011 -278.38273)
			(xy 88.211152 -278.38273)
		)
		(stroke
			(width 0)
			(type solid)
		)
		(fill yes)
		(layer "In4.Cu")
		(net "M_D_CPU1_SB_DQ<5>")
	)
	(gr_poly
		(pts
			(xy 88.211152 -277.93442) (xy 88.211152 -277.88997) (xy 88.011 -277.88997) (xy 88.011 -277.93442)
			(xy 88.111076 -278.034496)
		)
		(stroke
			(width 0)
			(type solid)
		)
		(fill yes)
		(layer "In4.Cu")
		(net "M_D_CPU1_SB_DQ<6>")
	)
	(gr_poly
		(pts
			(xy 88.211152 -276.718014) (xy 88.111076 -276.618192) (xy 88.011 -276.718014) (xy 88.011 -276.765766)
			(xy 88.211152 -276.765766)
		)
		(stroke
			(width 0)
			(type solid)
		)
		(fill yes)
		(layer "In4.Cu")
		(net "M_D_CPU1_SB_DQS_DN<5>")
	)
	(gr_poly
		(pts
			(xy 88.211152 -276.314662) (xy 88.211152 -276.26691) (xy 88.011 -276.26691) (xy 88.011 -276.314662)
			(xy 88.111076 -276.414484)
		)
		(stroke
			(width 0)
			(type solid)
		)
		(fill yes)
		(layer "In4.Cu")
		(net "M_D_CPU1_SB_DQS_DN<0>")
	)
	(gr_poly
		(pts
			(xy 88.211152 -275.098256) (xy 88.111076 -274.99818) (xy 88.011 -275.098256) (xy 88.011 -275.142706)
			(xy 88.211152 -275.142706)
		)
		(stroke
			(width 0)
			(type solid)
		)
		(fill yes)
		(layer "In4.Cu")
		(net "M_D_CPU1_SB_DQ<1>")
	)
	(gr_poly
		(pts
			(xy 88.211152 -274.694396) (xy 88.211152 -274.649946) (xy 88.011 -274.649946) (xy 88.011 -274.694396)
			(xy 88.111076 -274.794472)
		)
		(stroke
			(width 0)
			(type solid)
		)
		(fill yes)
		(layer "In4.Cu")
		(net "M_D_CPU1_SB_DQ<2>")
	)
	(gr_poly
		(pts
			(xy 88.211152 -273.478244) (xy 88.111076 -273.378168) (xy 88.011 -273.478244) (xy 88.011 -273.522694)
			(xy 88.211152 -273.522694)
		)
		(stroke
			(width 0)
			(type solid)
		)
		(fill yes)
		(layer "In4.Cu")
		(net "M_D_CPU1_SB_CB<1>")
	)
	(gr_poly
		(pts
			(xy 88.211152 -273.074384) (xy 88.211152 -273.029934) (xy 88.011 -273.029934) (xy 88.011 -273.074384)
			(xy 88.111076 -273.17446)
		)
		(stroke
			(width 0)
			(type solid)
		)
		(fill yes)
		(layer "In4.Cu")
		(net "M_D_CPU1_SB_CB<2>")
	)
	(gr_poly
		(pts
			(xy 88.211152 -271.857978) (xy 88.111076 -271.758156) (xy 88.011 -271.857978) (xy 88.011 -271.90573)
			(xy 88.211152 -271.90573)
		)
		(stroke
			(width 0)
			(type solid)
		)
		(fill yes)
		(layer "In4.Cu")
		(net "M_D_CPU1_SB_DQS_DN<4>")
	)
	(gr_poly
		(pts
			(xy 88.211152 -271.454626) (xy 88.211152 -271.406874) (xy 88.011 -271.406874) (xy 88.011 -271.454626)
			(xy 88.111076 -271.554448)
		)
		(stroke
			(width 0)
			(type solid)
		)
		(fill yes)
		(layer "In4.Cu")
		(net "M_D_CPU1_SB_DQS_DN<9>")
	)
	(gr_poly
		(pts
			(xy 88.211152 -270.23822) (xy 88.111076 -270.138144) (xy 88.011 -270.23822) (xy 88.011 -270.28267)
			(xy 88.211152 -270.28267)
		)
		(stroke
			(width 0)
			(type solid)
		)
		(fill yes)
		(layer "In4.Cu")
		(net "M_D_CPU1_SB_CB<5>")
	)
	(gr_poly
		(pts
			(xy 88.211152 -269.83436) (xy 88.211152 -269.78991) (xy 88.011 -269.78991) (xy 88.011 -269.83436)
			(xy 88.111076 -269.934436)
		)
		(stroke
			(width 0)
			(type solid)
		)
		(fill yes)
		(layer "In4.Cu")
		(net "M_D_CPU1_SB_CB<6>")
	)
	(gr_poly
		(pts
			(xy 88.211152 -266.594336) (xy 88.211152 -266.549886) (xy 88.011 -266.549886) (xy 88.011 -266.594336)
			(xy 88.111076 -266.694412)
		)
		(stroke
			(width 0)
			(type solid)
		)
		(fill yes)
		(layer "In4.Cu")
		(net "M_D_CPU1_SB_CS_N<1>")
	)
	(gr_poly
		(pts
			(xy 88.211152 -264.974324) (xy 88.211152 -264.929874) (xy 88.011 -264.929874) (xy 88.011 -264.974324)
			(xy 88.111076 -265.0744)
		)
		(stroke
			(width 0)
			(type solid)
		)
		(fill yes)
		(layer "In4.Cu")
		(net "M_D_CPU1_SB_PAR")
	)
	(gr_poly
		(pts
			(xy 88.211152 -263.758172) (xy 88.111076 -263.658096) (xy 88.011 -263.758172) (xy 88.011 -263.802622)
			(xy 88.211152 -263.802622)
		)
		(stroke
			(width 0)
			(type solid)
		)
		(fill yes)
		(layer "In4.Cu")
		(net "M_D_CPU1_SB_CA<4>")
	)
	(gr_poly
		(pts
			(xy 88.211152 -263.354312) (xy 88.211152 -263.309862) (xy 88.011 -263.309862) (xy 88.011 -263.354312)
			(xy 88.111076 -263.454388)
		)
		(stroke
			(width 0)
			(type solid)
		)
		(fill yes)
		(layer "In4.Cu")
		(net "M_D_CPU1_SB_CA<3>")
	)
	(gr_poly
		(pts
			(xy 88.211152 -262.13816) (xy 88.111076 -262.038084) (xy 88.011 -262.13816) (xy 88.011 -262.18261)
			(xy 88.211152 -262.18261)
		)
		(stroke
			(width 0)
			(type solid)
		)
		(fill yes)
		(layer "In4.Cu")
		(net "M_D_CPU1_SB_CA<0>")
	)
	(gr_poly
		(pts
			(xy 88.381078 -256.432812) (xy 88.381078 -256.38506) (xy 88.180926 -256.38506) (xy 88.180926 -256.432812)
			(xy 88.281002 -256.532634)
		)
		(stroke
			(width 0)
			(type solid)
		)
		(fill yes)
		(layer "In4.Cu")
		(net "M_D_CPU1_CLK_DN<0>")
	)
	(gr_poly
		(pts
			(xy 88.381078 -255.216406) (xy 88.281002 -255.11633) (xy 88.180926 -255.216406) (xy 88.180926 -255.260856)
			(xy 88.381078 -255.260856)
		)
		(stroke
			(width 0)
			(type solid)
		)
		(fill yes)
		(layer "In4.Cu")
		(net "M_D_CPU1_SA_CA<6>")
	)
	(gr_poly
		(pts
			(xy 88.381078 -254.812546) (xy 88.381078 -254.768096) (xy 88.180926 -254.768096) (xy 88.180926 -254.812546)
			(xy 88.281002 -254.912622)
		)
		(stroke
			(width 0)
			(type solid)
		)
		(fill yes)
		(layer "In4.Cu")
		(net "M_D_CPU1_SA_CA<5>")
	)
	(gr_poly
		(pts
			(xy 88.381078 -253.596394) (xy 88.281002 -253.496318) (xy 88.180926 -253.596394) (xy 88.180926 -253.640844)
			(xy 88.381078 -253.640844)
		)
		(stroke
			(width 0)
			(type solid)
		)
		(fill yes)
		(layer "In4.Cu")
		(net "M_D_CPU1_SA_CA<2>")
	)
	(gr_poly
		(pts
			(xy 88.381078 -253.192534) (xy 88.381078 -253.148084) (xy 88.180926 -253.148084) (xy 88.180926 -253.192534)
			(xy 88.281002 -253.29261)
		)
		(stroke
			(width 0)
			(type solid)
		)
		(fill yes)
		(layer "In4.Cu")
		(net "M_D_CPU1_SA_CA<1>")
	)
	(gr_poly
		(pts
			(xy 88.381078 -251.572522) (xy 88.381078 -251.528072) (xy 88.180926 -251.528072) (xy 88.180926 -251.572522)
			(xy 88.281002 -251.672598)
		)
		(stroke
			(width 0)
			(type solid)
		)
		(fill yes)
		(layer "In4.Cu")
		(net "M_D_CPU1_SA_CS_N<0>")
	)
	(gr_poly
		(pts
			(xy 88.381078 -250.35637) (xy 88.281002 -250.256294) (xy 88.180926 -250.35637) (xy 88.180926 -250.40082)
			(xy 88.381078 -250.40082)
		)
		(stroke
			(width 0)
			(type solid)
		)
		(fill yes)
		(layer "In4.Cu")
		(net "M_D_CPU1_ALERT_R_N")
	)
	(gr_poly
		(pts
			(xy 88.381078 -248.736358) (xy 88.281002 -248.636282) (xy 88.180926 -248.736358) (xy 88.180926 -248.780808)
			(xy 88.381078 -248.780808)
		)
		(stroke
			(width 0)
			(type solid)
		)
		(fill yes)
		(layer "In4.Cu")
		(net "M_D_CPU1_SA_CB<5>")
	)
	(gr_poly
		(pts
			(xy 88.381078 -248.332498) (xy 88.381078 -248.288048) (xy 88.180926 -248.288048) (xy 88.180926 -248.332498)
			(xy 88.281002 -248.432574)
		)
		(stroke
			(width 0)
			(type solid)
		)
		(fill yes)
		(layer "In4.Cu")
		(net "M_D_CPU1_SA_CB<6>")
	)
	(gr_poly
		(pts
			(xy 88.381078 -247.116092) (xy 88.281002 -247.01627) (xy 88.180926 -247.116092) (xy 88.180926 -247.163844)
			(xy 88.381078 -247.163844)
		)
		(stroke
			(width 0)
			(type solid)
		)
		(fill yes)
		(layer "In4.Cu")
		(net "M_D_CPU1_SA_DQS_DN<9>")
	)
	(gr_poly
		(pts
			(xy 88.381078 -246.71274) (xy 88.381078 -246.664988) (xy 88.180926 -246.664988) (xy 88.180926 -246.71274)
			(xy 88.281002 -246.812562)
		)
		(stroke
			(width 0)
			(type solid)
		)
		(fill yes)
		(layer "In4.Cu")
		(net "M_D_CPU1_SA_DQS_DN<4>")
	)
	(gr_poly
		(pts
			(xy 88.381078 -245.496334) (xy 88.281002 -245.396258) (xy 88.180926 -245.496334) (xy 88.180926 -245.540784)
			(xy 88.381078 -245.540784)
		)
		(stroke
			(width 0)
			(type solid)
		)
		(fill yes)
		(layer "In4.Cu")
		(net "M_D_CPU1_SA_CB<1>")
	)
	(gr_poly
		(pts
			(xy 88.381078 -245.092474) (xy 88.381078 -245.048024) (xy 88.180926 -245.048024) (xy 88.180926 -245.092474)
			(xy 88.281002 -245.19255)
		)
		(stroke
			(width 0)
			(type solid)
		)
		(fill yes)
		(layer "In4.Cu")
		(net "M_D_CPU1_SA_CB<2>")
	)
	(gr_poly
		(pts
			(xy 88.381078 -243.876322) (xy 88.281002 -243.776246) (xy 88.180926 -243.876322) (xy 88.180926 -243.920772)
			(xy 88.381078 -243.920772)
		)
		(stroke
			(width 0)
			(type solid)
		)
		(fill yes)
		(layer "In4.Cu")
		(net "M_D_CPU1_SA_DQ<29>")
	)
	(gr_poly
		(pts
			(xy 88.381078 -243.472462) (xy 88.381078 -243.428012) (xy 88.180926 -243.428012) (xy 88.180926 -243.472462)
			(xy 88.281002 -243.572538)
		)
		(stroke
			(width 0)
			(type solid)
		)
		(fill yes)
		(layer "In4.Cu")
		(net "M_D_CPU1_SA_DQ<30>")
	)
	(gr_poly
		(pts
			(xy 88.381078 -242.256056) (xy 88.281002 -242.156234) (xy 88.180926 -242.256056) (xy 88.180926 -242.303808)
			(xy 88.381078 -242.303808)
		)
		(stroke
			(width 0)
			(type solid)
		)
		(fill yes)
		(layer "In4.Cu")
		(net "M_D_CPU1_SA_DQS_DN<8>")
	)
	(gr_poly
		(pts
			(xy 88.381078 -241.852704) (xy 88.381078 -241.804952) (xy 88.180926 -241.804952) (xy 88.180926 -241.852704)
			(xy 88.281002 -241.952526)
		)
		(stroke
			(width 0)
			(type solid)
		)
		(fill yes)
		(layer "In4.Cu")
		(net "M_D_CPU1_SA_DQS_DN<3>")
	)
	(gr_poly
		(pts
			(xy 88.381078 -240.636298) (xy 88.281002 -240.536222) (xy 88.180926 -240.636298) (xy 88.180926 -240.680748)
			(xy 88.381078 -240.680748)
		)
		(stroke
			(width 0)
			(type solid)
		)
		(fill yes)
		(layer "In4.Cu")
		(net "M_D_CPU1_SA_DQ<25>")
	)
	(gr_poly
		(pts
			(xy 88.381078 -240.232438) (xy 88.381078 -240.187988) (xy 88.180926 -240.187988) (xy 88.180926 -240.232438)
			(xy 88.281002 -240.332514)
		)
		(stroke
			(width 0)
			(type solid)
		)
		(fill yes)
		(layer "In4.Cu")
		(net "M_D_CPU1_SA_DQ<26>")
	)
	(gr_poly
		(pts
			(xy 88.381078 -239.016286) (xy 88.281002 -238.91621) (xy 88.180926 -239.016286) (xy 88.180926 -239.060736)
			(xy 88.381078 -239.060736)
		)
		(stroke
			(width 0)
			(type solid)
		)
		(fill yes)
		(layer "In4.Cu")
		(net "M_D_CPU1_SA_DQ<21>")
	)
	(gr_poly
		(pts
			(xy 88.381078 -238.612426) (xy 88.381078 -238.567976) (xy 88.180926 -238.567976) (xy 88.180926 -238.612426)
			(xy 88.281002 -238.712502)
		)
		(stroke
			(width 0)
			(type solid)
		)
		(fill yes)
		(layer "In4.Cu")
		(net "M_D_CPU1_SA_DQ<22>")
	)
	(gr_poly
		(pts
			(xy 88.381078 -237.39602) (xy 88.281002 -237.296198) (xy 88.180926 -237.39602) (xy 88.180926 -237.443772)
			(xy 88.381078 -237.443772)
		)
		(stroke
			(width 0)
			(type solid)
		)
		(fill yes)
		(layer "In4.Cu")
		(net "M_D_CPU1_SA_DQS_DN<7>")
	)
	(gr_poly
		(pts
			(xy 88.381078 -236.992668) (xy 88.381078 -236.944916) (xy 88.180926 -236.944916) (xy 88.180926 -236.992668)
			(xy 88.281002 -237.09249)
		)
		(stroke
			(width 0)
			(type solid)
		)
		(fill yes)
		(layer "In4.Cu")
		(net "M_D_CPU1_SA_DQS_DN<2>")
	)
	(gr_poly
		(pts
			(xy 88.381078 -235.776262) (xy 88.281002 -235.676186) (xy 88.180926 -235.776262) (xy 88.180926 -235.820712)
			(xy 88.381078 -235.820712)
		)
		(stroke
			(width 0)
			(type solid)
		)
		(fill yes)
		(layer "In4.Cu")
		(net "M_D_CPU1_SA_DQ<17>")
	)
	(gr_poly
		(pts
			(xy 88.381078 -235.372402) (xy 88.381078 -235.327952) (xy 88.180926 -235.327952) (xy 88.180926 -235.372402)
			(xy 88.281002 -235.472478)
		)
		(stroke
			(width 0)
			(type solid)
		)
		(fill yes)
		(layer "In4.Cu")
		(net "M_D_CPU1_SA_DQ<18>")
	)
	(gr_poly
		(pts
			(xy 88.381078 -234.15625) (xy 88.281002 -234.056174) (xy 88.180926 -234.15625) (xy 88.180926 -234.2007)
			(xy 88.381078 -234.2007)
		)
		(stroke
			(width 0)
			(type solid)
		)
		(fill yes)
		(layer "In4.Cu")
		(net "M_D_CPU1_SA_DQ<13>")
	)
	(gr_poly
		(pts
			(xy 88.381078 -233.75239) (xy 88.381078 -233.70794) (xy 88.180926 -233.70794) (xy 88.180926 -233.75239)
			(xy 88.281002 -233.852466)
		)
		(stroke
			(width 0)
			(type solid)
		)
		(fill yes)
		(layer "In4.Cu")
		(net "M_D_CPU1_SA_DQ<14>")
	)
	(gr_poly
		(pts
			(xy 88.381078 -232.535984) (xy 88.281002 -232.436162) (xy 88.180926 -232.535984) (xy 88.180926 -232.583736)
			(xy 88.381078 -232.583736)
		)
		(stroke
			(width 0)
			(type solid)
		)
		(fill yes)
		(layer "In4.Cu")
		(net "M_D_CPU1_SA_DQS_DN<6>")
	)
	(gr_poly
		(pts
			(xy 88.381078 -232.132632) (xy 88.381078 -232.08488) (xy 88.180926 -232.08488) (xy 88.180926 -232.132632)
			(xy 88.281002 -232.232454)
		)
		(stroke
			(width 0)
			(type solid)
		)
		(fill yes)
		(layer "In4.Cu")
		(net "M_D_CPU1_SA_DQS_DN<1>")
	)
	(gr_poly
		(pts
			(xy 88.381078 -230.916226) (xy 88.281002 -230.81615) (xy 88.180926 -230.916226) (xy 88.180926 -230.960676)
			(xy 88.381078 -230.960676)
		)
		(stroke
			(width 0)
			(type solid)
		)
		(fill yes)
		(layer "In4.Cu")
		(net "M_D_CPU1_SA_DQ<9>")
	)
	(gr_poly
		(pts
			(xy 88.381078 -230.51262) (xy 88.381078 -230.46817) (xy 88.180926 -230.46817) (xy 88.180926 -230.51262)
			(xy 88.281002 -230.612696)
		)
		(stroke
			(width 0)
			(type solid)
		)
		(fill yes)
		(layer "In4.Cu")
		(net "M_D_CPU1_SA_DQ<10>")
	)
	(gr_poly
		(pts
			(xy 88.381078 -229.296214) (xy 88.281002 -229.196138) (xy 88.180926 -229.296214) (xy 88.180926 -229.340664)
			(xy 88.381078 -229.340664)
		)
		(stroke
			(width 0)
			(type solid)
		)
		(fill yes)
		(layer "In4.Cu")
		(net "M_D_CPU1_SA_DQ<5>")
	)
	(gr_poly
		(pts
			(xy 88.381078 -228.892608) (xy 88.381078 -228.848158) (xy 88.180926 -228.848158) (xy 88.180926 -228.892608)
			(xy 88.281002 -228.992684)
		)
		(stroke
			(width 0)
			(type solid)
		)
		(fill yes)
		(layer "In4.Cu")
		(net "M_D_CPU1_SA_DQ<6>")
	)
	(gr_poly
		(pts
			(xy 88.381078 -227.27285) (xy 88.381078 -227.225098) (xy 88.180926 -227.225098) (xy 88.180926 -227.27285)
			(xy 88.281002 -227.372672)
		)
		(stroke
			(width 0)
			(type solid)
		)
		(fill yes)
		(layer "In4.Cu")
		(net "M_D_CPU1_SA_DQS_DN<0>")
	)
	(gr_poly
		(pts
			(xy 88.381078 -226.056444) (xy 88.281002 -225.956368) (xy 88.180926 -226.056444) (xy 88.180926 -226.100894)
			(xy 88.381078 -226.100894)
		)
		(stroke
			(width 0)
			(type solid)
		)
		(fill yes)
		(layer "In4.Cu")
		(net "M_D_CPU1_SA_DQ<1>")
	)
	(gr_poly
		(pts
			(xy 88.381078 -225.652584) (xy 88.381078 -225.608134) (xy 88.180926 -225.608134) (xy 88.180926 -225.652584)
			(xy 88.281002 -225.75266)
		)
		(stroke
			(width 0)
			(type solid)
		)
		(fill yes)
		(layer "In4.Cu")
		(net "M_D_CPU1_SA_DQ<2>")
	)
	(gr_poly
		(pts
			(xy 88.387174 -227.67671) (xy 88.287098 -227.576634) (xy 88.187022 -227.67671) (xy 88.187022 -227.724208)
			(xy 88.387174 -227.724208)
		)
		(stroke
			(width 0)
			(type solid)
		)
		(fill yes)
		(layer "In4.Cu")
		(net "M_D_CPU1_SA_DQS_DN<5>")
	)
	(gr_poly
		(pts
			(xy 88.681052 -293.32428) (xy 88.681052 -293.27983) (xy 88.4809 -293.27983) (xy 88.4809 -293.32428)
			(xy 88.580976 -293.424356)
		)
		(stroke
			(width 0)
			(type solid)
		)
		(fill yes)
		(layer "In4.Cu")
		(net "M_D_CPU1_SB_DQ<31>")
	)
	(gr_poly
		(pts
			(xy 88.681052 -292.108128) (xy 88.580976 -292.008052) (xy 88.4809 -292.108128) (xy 88.4809 -292.152578)
			(xy 88.681052 -292.152578)
		)
		(stroke
			(width 0)
			(type solid)
		)
		(fill yes)
		(layer "In4.Cu")
		(net "M_D_CPU1_SB_DQ<28>")
	)
	(gr_poly
		(pts
			(xy 88.681052 -291.704522) (xy 88.681052 -291.65677) (xy 88.4809 -291.65677) (xy 88.4809 -291.704522)
			(xy 88.580976 -291.804344)
		)
		(stroke
			(width 0)
			(type solid)
		)
		(fill yes)
		(layer "In4.Cu")
		(net "M_D_CPU1_SB_DQS_DP<8>")
	)
	(gr_poly
		(pts
			(xy 88.681052 -290.487862) (xy 88.580976 -290.38804) (xy 88.4809 -290.487862) (xy 88.4809 -290.535614)
			(xy 88.681052 -290.535614)
		)
		(stroke
			(width 0)
			(type solid)
		)
		(fill yes)
		(layer "In4.Cu")
		(net "M_D_CPU1_SB_DQS_DP<3>")
	)
	(gr_poly
		(pts
			(xy 88.681052 -290.084256) (xy 88.681052 -290.039806) (xy 88.4809 -290.039806) (xy 88.4809 -290.084256)
			(xy 88.580976 -290.184332)
		)
		(stroke
			(width 0)
			(type solid)
		)
		(fill yes)
		(layer "In4.Cu")
		(net "M_D_CPU1_SB_DQ<27>")
	)
	(gr_poly
		(pts
			(xy 88.681052 -288.868104) (xy 88.580976 -288.768028) (xy 88.4809 -288.868104) (xy 88.4809 -288.912554)
			(xy 88.681052 -288.912554)
		)
		(stroke
			(width 0)
			(type solid)
		)
		(fill yes)
		(layer "In4.Cu")
		(net "M_D_CPU1_SB_DQ<24>")
	)
	(gr_poly
		(pts
			(xy 88.681052 -288.464498) (xy 88.681052 -288.420048) (xy 88.4809 -288.420048) (xy 88.4809 -288.464498)
			(xy 88.580976 -288.564574)
		)
		(stroke
			(width 0)
			(type solid)
		)
		(fill yes)
		(layer "In4.Cu")
		(net "M_D_CPU1_SB_DQ<23>")
	)
	(gr_poly
		(pts
			(xy 88.681052 -287.248092) (xy 88.580976 -287.148016) (xy 88.4809 -287.248092) (xy 88.4809 -287.292542)
			(xy 88.681052 -287.292542)
		)
		(stroke
			(width 0)
			(type solid)
		)
		(fill yes)
		(layer "In4.Cu")
		(net "M_D_CPU1_SB_DQ<20>")
	)
	(gr_poly
		(pts
			(xy 88.681052 -286.844486) (xy 88.681052 -286.796734) (xy 88.4809 -286.796734) (xy 88.4809 -286.844486)
			(xy 88.580976 -286.944562)
		)
		(stroke
			(width 0)
			(type solid)
		)
		(fill yes)
		(layer "In4.Cu")
		(net "M_D_CPU1_SB_DQS_DP<7>")
	)
	(gr_poly
		(pts
			(xy 88.681052 -285.62808) (xy 88.580976 -285.528258) (xy 88.4809 -285.62808) (xy 88.4809 -285.675832)
			(xy 88.681052 -285.675832)
		)
		(stroke
			(width 0)
			(type solid)
		)
		(fill yes)
		(layer "In4.Cu")
		(net "M_D_CPU1_SB_DQS_DP<2>")
	)
	(gr_poly
		(pts
			(xy 88.681052 -285.224474) (xy 88.681052 -285.180024) (xy 88.4809 -285.180024) (xy 88.4809 -285.224474)
			(xy 88.580976 -285.32455)
		)
		(stroke
			(width 0)
			(type solid)
		)
		(fill yes)
		(layer "In4.Cu")
		(net "M_D_CPU1_SB_DQ<19>")
	)
	(gr_poly
		(pts
			(xy 88.681052 -284.008322) (xy 88.580976 -283.908246) (xy 88.4809 -284.008322) (xy 88.4809 -284.052772)
			(xy 88.681052 -284.052772)
		)
		(stroke
			(width 0)
			(type solid)
		)
		(fill yes)
		(layer "In4.Cu")
		(net "M_D_CPU1_SB_DQ<16>")
	)
	(gr_poly
		(pts
			(xy 88.681052 -283.604462) (xy 88.681052 -283.560012) (xy 88.4809 -283.560012) (xy 88.4809 -283.604462)
			(xy 88.580976 -283.704538)
		)
		(stroke
			(width 0)
			(type solid)
		)
		(fill yes)
		(layer "In4.Cu")
		(net "M_D_CPU1_SB_DQ<15>")
	)
	(gr_poly
		(pts
			(xy 88.681052 -282.38831) (xy 88.580976 -282.288234) (xy 88.4809 -282.38831) (xy 88.4809 -282.43276)
			(xy 88.681052 -282.43276)
		)
		(stroke
			(width 0)
			(type solid)
		)
		(fill yes)
		(layer "In4.Cu")
		(net "M_D_CPU1_SB_DQ<12>")
	)
	(gr_poly
		(pts
			(xy 88.681052 -281.984704) (xy 88.681052 -281.936952) (xy 88.4809 -281.936952) (xy 88.4809 -281.984704)
			(xy 88.580976 -282.084526)
		)
		(stroke
			(width 0)
			(type solid)
		)
		(fill yes)
		(layer "In4.Cu")
		(net "M_D_CPU1_SB_DQS_DP<6>")
	)
	(gr_poly
		(pts
			(xy 88.681052 -280.768044) (xy 88.580976 -280.668222) (xy 88.4809 -280.768044) (xy 88.4809 -280.815796)
			(xy 88.681052 -280.815796)
		)
		(stroke
			(width 0)
			(type solid)
		)
		(fill yes)
		(layer "In4.Cu")
		(net "M_D_CPU1_SB_DQS_DP<1>")
	)
	(gr_poly
		(pts
			(xy 88.681052 -280.364438) (xy 88.681052 -280.319988) (xy 88.4809 -280.319988) (xy 88.4809 -280.364438)
			(xy 88.580976 -280.464514)
		)
		(stroke
			(width 0)
			(type solid)
		)
		(fill yes)
		(layer "In4.Cu")
		(net "M_D_CPU1_SB_DQ<11>")
	)
	(gr_poly
		(pts
			(xy 88.681052 -279.148286) (xy 88.580976 -279.04821) (xy 88.4809 -279.148286) (xy 88.4809 -279.192736)
			(xy 88.681052 -279.192736)
		)
		(stroke
			(width 0)
			(type solid)
		)
		(fill yes)
		(layer "In4.Cu")
		(net "M_D_CPU1_SB_DQ<8>")
	)
	(gr_poly
		(pts
			(xy 88.681052 -278.744426) (xy 88.681052 -278.699976) (xy 88.4809 -278.699976) (xy 88.4809 -278.744426)
			(xy 88.580976 -278.844502)
		)
		(stroke
			(width 0)
			(type solid)
		)
		(fill yes)
		(layer "In4.Cu")
		(net "M_D_CPU1_SB_DQ<7>")
	)
	(gr_poly
		(pts
			(xy 88.681052 -277.528274) (xy 88.580976 -277.428198) (xy 88.4809 -277.528274) (xy 88.4809 -277.572724)
			(xy 88.681052 -277.572724)
		)
		(stroke
			(width 0)
			(type solid)
		)
		(fill yes)
		(layer "In4.Cu")
		(net "M_D_CPU1_SB_DQ<4>")
	)
	(gr_poly
		(pts
			(xy 88.681052 -275.504402) (xy 88.681052 -275.459952) (xy 88.4809 -275.459952) (xy 88.4809 -275.504402)
			(xy 88.580976 -275.604478)
		)
		(stroke
			(width 0)
			(type solid)
		)
		(fill yes)
		(layer "In4.Cu")
		(net "M_D_CPU1_SB_DQ<3>")
	)
	(gr_poly
		(pts
			(xy 88.681052 -274.28825) (xy 88.580976 -274.188174) (xy 88.4809 -274.28825) (xy 88.4809 -274.3327)
			(xy 88.681052 -274.3327)
		)
		(stroke
			(width 0)
			(type solid)
		)
		(fill yes)
		(layer "In4.Cu")
		(net "M_D_CPU1_SB_DQ<0>")
	)
	(gr_poly
		(pts
			(xy 88.681052 -273.88439) (xy 88.681052 -273.83994) (xy 88.4809 -273.83994) (xy 88.4809 -273.88439)
			(xy 88.580976 -273.984466)
		)
		(stroke
			(width 0)
			(type solid)
		)
		(fill yes)
		(layer "In4.Cu")
		(net "M_D_CPU1_SB_CB<3>")
	)
	(gr_poly
		(pts
			(xy 88.681052 -272.668238) (xy 88.580976 -272.568162) (xy 88.4809 -272.668238) (xy 88.4809 -272.712688)
			(xy 88.681052 -272.712688)
		)
		(stroke
			(width 0)
			(type solid)
		)
		(fill yes)
		(layer "In4.Cu")
		(net "M_D_CPU1_SB_CB<0>")
	)
	(gr_poly
		(pts
			(xy 88.681052 -272.264632) (xy 88.681052 -272.21688) (xy 88.4809 -272.21688) (xy 88.4809 -272.264632)
			(xy 88.580976 -272.364454)
		)
		(stroke
			(width 0)
			(type solid)
		)
		(fill yes)
		(layer "In4.Cu")
		(net "M_D_CPU1_SB_DQS_DP<4>")
	)
	(gr_poly
		(pts
			(xy 88.681052 -271.047972) (xy 88.580976 -270.94815) (xy 88.4809 -271.047972) (xy 88.4809 -271.095724)
			(xy 88.681052 -271.095724)
		)
		(stroke
			(width 0)
			(type solid)
		)
		(fill yes)
		(layer "In4.Cu")
		(net "M_D_CPU1_SB_DQS_DP<9>")
	)
	(gr_poly
		(pts
			(xy 88.681052 -270.644366) (xy 88.681052 -270.599916) (xy 88.4809 -270.599916) (xy 88.4809 -270.644366)
			(xy 88.580976 -270.744442)
		)
		(stroke
			(width 0)
			(type solid)
		)
		(fill yes)
		(layer "In4.Cu")
		(net "M_D_CPU1_SB_CB<7>")
	)
	(gr_poly
		(pts
			(xy 88.681052 -269.428214) (xy 88.580976 -269.328138) (xy 88.4809 -269.428214) (xy 88.4809 -269.472664)
			(xy 88.681052 -269.472664)
		)
		(stroke
			(width 0)
			(type solid)
		)
		(fill yes)
		(layer "In4.Cu")
		(net "M_D_CPU1_SB_CB<4>")
	)
	(gr_poly
		(pts
			(xy 88.681052 -265.78433) (xy 88.681052 -265.73988) (xy 88.4809 -265.73988) (xy 88.4809 -265.78433)
			(xy 88.580976 -265.884406)
		)
		(stroke
			(width 0)
			(type solid)
		)
		(fill yes)
		(layer "In4.Cu")
		(net "M_D_CPU1_SB_CS_N<0>")
	)
	(gr_poly
		(pts
			(xy 88.681052 -264.568178) (xy 88.580976 -264.468102) (xy 88.4809 -264.568178) (xy 88.4809 -264.612628)
			(xy 88.681052 -264.612628)
		)
		(stroke
			(width 0)
			(type solid)
		)
		(fill yes)
		(layer "In4.Cu")
		(net "M_D_CPU1_SB_CA<6>")
	)
	(gr_poly
		(pts
			(xy 88.681052 -264.164318) (xy 88.681052 -264.119868) (xy 88.4809 -264.119868) (xy 88.4809 -264.164318)
			(xy 88.580976 -264.264394)
		)
		(stroke
			(width 0)
			(type solid)
		)
		(fill yes)
		(layer "In4.Cu")
		(net "M_D_CPU1_SB_CA<5>")
	)
	(gr_poly
		(pts
			(xy 88.681052 -262.948166) (xy 88.580976 -262.84809) (xy 88.4809 -262.948166) (xy 88.4809 -262.992616)
			(xy 88.681052 -262.992616)
		)
		(stroke
			(width 0)
			(type solid)
		)
		(fill yes)
		(layer "In4.Cu")
		(net "M_D_CPU1_SB_CA<2>")
	)
	(gr_poly
		(pts
			(xy 88.681052 -262.544306) (xy 88.681052 -262.499856) (xy 88.4809 -262.499856) (xy 88.4809 -262.544306)
			(xy 88.580976 -262.644382)
		)
		(stroke
			(width 0)
			(type solid)
		)
		(fill yes)
		(layer "In4.Cu")
		(net "M_D_CPU1_SB_CA<1>")
	)
	(gr_poly
		(pts
			(xy 88.687148 -267.801852) (xy 88.587326 -267.701776) (xy 88.48725 -267.801852) (xy 88.48725 -267.846302)
			(xy 88.687148 -267.846302)
		)
		(stroke
			(width 0)
			(type solid)
		)
		(fill yes)
		(layer "In4.Cu")
		(net "M_D_CPU1_SB_RSP<0>")
	)
	(gr_poly
		(pts
			(xy 88.688418 -277.124414) (xy 88.688418 -277.076916) (xy 88.488266 -277.076916) (xy 88.488266 -277.124414)
			(xy 88.588342 -277.22449)
		)
		(stroke
			(width 0)
			(type solid)
		)
		(fill yes)
		(layer "In4.Cu")
		(net "M_D_CPU1_SB_DQS_DP<5>")
	)
	(gr_poly
		(pts
			(xy 88.688418 -275.908262) (xy 88.588342 -275.808186) (xy 88.488266 -275.908262) (xy 88.488266 -275.95576)
			(xy 88.688418 -275.95576)
		)
		(stroke
			(width 0)
			(type solid)
		)
		(fill yes)
		(layer "In4.Cu")
		(net "M_D_CPU1_SB_DQS_DP<0>")
	)
	(gr_poly
		(pts
			(xy 88.851232 -256.026158) (xy 88.751156 -255.926336) (xy 88.65108 -256.026158) (xy 88.65108 -256.07391)
			(xy 88.851232 -256.07391)
		)
		(stroke
			(width 0)
			(type solid)
		)
		(fill yes)
		(layer "In4.Cu")
		(net "M_D_CPU1_CLK_DP<0>")
	)
	(gr_poly
		(pts
			(xy 88.851232 -255.622552) (xy 88.851232 -255.578102) (xy 88.65108 -255.578102) (xy 88.65108 -255.622552)
			(xy 88.751156 -255.722628)
		)
		(stroke
			(width 0)
			(type solid)
		)
		(fill yes)
		(layer "In4.Cu")
		(net "M_D_CPU1_SA_PAR")
	)
	(gr_poly
		(pts
			(xy 88.851232 -254.4064) (xy 88.751156 -254.306324) (xy 88.65108 -254.4064) (xy 88.65108 -254.45085)
			(xy 88.851232 -254.45085)
		)
		(stroke
			(width 0)
			(type solid)
		)
		(fill yes)
		(layer "In4.Cu")
		(net "M_D_CPU1_SA_CA<4>")
	)
	(gr_poly
		(pts
			(xy 88.851232 -254.00254) (xy 88.851232 -253.95809) (xy 88.65108 -253.95809) (xy 88.65108 -254.00254)
			(xy 88.751156 -254.102616)
		)
		(stroke
			(width 0)
			(type solid)
		)
		(fill yes)
		(layer "In4.Cu")
		(net "M_D_CPU1_SA_CA<3>")
	)
	(gr_poly
		(pts
			(xy 88.851232 -252.786388) (xy 88.751156 -252.686312) (xy 88.65108 -252.786388) (xy 88.65108 -252.830838)
			(xy 88.851232 -252.830838)
		)
		(stroke
			(width 0)
			(type solid)
		)
		(fill yes)
		(layer "In4.Cu")
		(net "M_D_CPU1_SA_CA<0>")
	)
	(gr_poly
		(pts
			(xy 88.851232 -252.382528) (xy 88.851232 -252.338078) (xy 88.65108 -252.338078) (xy 88.65108 -252.382528)
			(xy 88.751156 -252.482604)
		)
		(stroke
			(width 0)
			(type solid)
		)
		(fill yes)
		(layer "In4.Cu")
		(net "M_D_CPU1_SA_CS_N<1>")
	)
	(gr_poly
		(pts
			(xy 88.851232 -250.762516) (xy 88.851232 -250.718066) (xy 88.65108 -250.718066) (xy 88.65108 -250.762516)
			(xy 88.751156 -250.862592)
		)
		(stroke
			(width 0)
			(type solid)
		)
		(fill yes)
		(layer "In4.Cu")
		(net "M_D_CPU1_RESET_N")
	)
	(gr_poly
		(pts
			(xy 88.851232 -249.142504) (xy 88.851232 -249.098054) (xy 88.65108 -249.098054) (xy 88.65108 -249.142504)
			(xy 88.751156 -249.24258)
		)
		(stroke
			(width 0)
			(type solid)
		)
		(fill yes)
		(layer "In4.Cu")
		(net "M_D_CPU1_SA_CB<7>")
	)
	(gr_poly
		(pts
			(xy 88.851232 -247.926352) (xy 88.751156 -247.826276) (xy 88.65108 -247.926352) (xy 88.65108 -247.970802)
			(xy 88.851232 -247.970802)
		)
		(stroke
			(width 0)
			(type solid)
		)
		(fill yes)
		(layer "In4.Cu")
		(net "M_D_CPU1_SA_CB<4>")
	)
	(gr_poly
		(pts
			(xy 88.851232 -247.522746) (xy 88.851232 -247.474994) (xy 88.65108 -247.474994) (xy 88.65108 -247.522746)
			(xy 88.751156 -247.622568)
		)
		(stroke
			(width 0)
			(type solid)
		)
		(fill yes)
		(layer "In4.Cu")
		(net "M_D_CPU1_SA_DQS_DP<9>")
	)
	(gr_poly
		(pts
			(xy 88.851232 -246.306086) (xy 88.751156 -246.206264) (xy 88.65108 -246.306086) (xy 88.65108 -246.353838)
			(xy 88.851232 -246.353838)
		)
		(stroke
			(width 0)
			(type solid)
		)
		(fill yes)
		(layer "In4.Cu")
		(net "M_D_CPU1_SA_DQS_DP<4>")
	)
	(gr_poly
		(pts
			(xy 88.851232 -245.90248) (xy 88.851232 -245.85803) (xy 88.65108 -245.85803) (xy 88.65108 -245.90248)
			(xy 88.751156 -246.002556)
		)
		(stroke
			(width 0)
			(type solid)
		)
		(fill yes)
		(layer "In4.Cu")
		(net "M_D_CPU1_SA_CB<3>")
	)
	(gr_poly
		(pts
			(xy 88.851232 -244.686328) (xy 88.751156 -244.586252) (xy 88.65108 -244.686328) (xy 88.65108 -244.730778)
			(xy 88.851232 -244.730778)
		)
		(stroke
			(width 0)
			(type solid)
		)
		(fill yes)
		(layer "In4.Cu")
		(net "M_D_CPU1_SA_CB<0>")
	)
	(gr_poly
		(pts
			(xy 88.851232 -244.282468) (xy 88.851232 -244.238018) (xy 88.65108 -244.238018) (xy 88.65108 -244.282468)
			(xy 88.751156 -244.382544)
		)
		(stroke
			(width 0)
			(type solid)
		)
		(fill yes)
		(layer "In4.Cu")
		(net "M_D_CPU1_SA_DQ<31>")
	)
	(gr_poly
		(pts
			(xy 88.851232 -243.066316) (xy 88.751156 -242.96624) (xy 88.65108 -243.066316) (xy 88.65108 -243.110766)
			(xy 88.851232 -243.110766)
		)
		(stroke
			(width 0)
			(type solid)
		)
		(fill yes)
		(layer "In4.Cu")
		(net "M_D_CPU1_SA_DQ<28>")
	)
	(gr_poly
		(pts
			(xy 88.851232 -242.66271) (xy 88.851232 -242.614958) (xy 88.65108 -242.614958) (xy 88.65108 -242.66271)
			(xy 88.751156 -242.762532)
		)
		(stroke
			(width 0)
			(type solid)
		)
		(fill yes)
		(layer "In4.Cu")
		(net "M_D_CPU1_SA_DQS_DP<8>")
	)
	(gr_poly
		(pts
			(xy 88.851232 -241.44605) (xy 88.751156 -241.346228) (xy 88.65108 -241.44605) (xy 88.65108 -241.493802)
			(xy 88.851232 -241.493802)
		)
		(stroke
			(width 0)
			(type solid)
		)
		(fill yes)
		(layer "In4.Cu")
		(net "M_D_CPU1_SA_DQS_DP<3>")
	)
	(gr_poly
		(pts
			(xy 88.851232 -241.042444) (xy 88.851232 -240.997994) (xy 88.65108 -240.997994) (xy 88.65108 -241.042444)
			(xy 88.751156 -241.14252)
		)
		(stroke
			(width 0)
			(type solid)
		)
		(fill yes)
		(layer "In4.Cu")
		(net "M_D_CPU1_SA_DQ<27>")
	)
	(gr_poly
		(pts
			(xy 88.851232 -239.826292) (xy 88.751156 -239.726216) (xy 88.65108 -239.826292) (xy 88.65108 -239.870742)
			(xy 88.851232 -239.870742)
		)
		(stroke
			(width 0)
			(type solid)
		)
		(fill yes)
		(layer "In4.Cu")
		(net "M_D_CPU1_SA_DQ<24>")
	)
	(gr_poly
		(pts
			(xy 88.851232 -239.422432) (xy 88.851232 -239.377982) (xy 88.65108 -239.377982) (xy 88.65108 -239.422432)
			(xy 88.751156 -239.522508)
		)
		(stroke
			(width 0)
			(type solid)
		)
		(fill yes)
		(layer "In4.Cu")
		(net "M_D_CPU1_SA_DQ<23>")
	)
	(gr_poly
		(pts
			(xy 88.851232 -238.20628) (xy 88.751156 -238.106204) (xy 88.65108 -238.20628) (xy 88.65108 -238.25073)
			(xy 88.851232 -238.25073)
		)
		(stroke
			(width 0)
			(type solid)
		)
		(fill yes)
		(layer "In4.Cu")
		(net "M_D_CPU1_SA_DQ<20>")
	)
	(gr_poly
		(pts
			(xy 88.851232 -237.802674) (xy 88.851232 -237.754922) (xy 88.65108 -237.754922) (xy 88.65108 -237.802674)
			(xy 88.751156 -237.902496)
		)
		(stroke
			(width 0)
			(type solid)
		)
		(fill yes)
		(layer "In4.Cu")
		(net "M_D_CPU1_SA_DQS_DP<7>")
	)
	(gr_poly
		(pts
			(xy 88.851232 -236.586014) (xy 88.751156 -236.486192) (xy 88.65108 -236.586014) (xy 88.65108 -236.633766)
			(xy 88.851232 -236.633766)
		)
		(stroke
			(width 0)
			(type solid)
		)
		(fill yes)
		(layer "In4.Cu")
		(net "M_D_CPU1_SA_DQS_DP<2>")
	)
	(gr_poly
		(pts
			(xy 88.851232 -236.182408) (xy 88.851232 -236.137958) (xy 88.65108 -236.137958) (xy 88.65108 -236.182408)
			(xy 88.751156 -236.282484)
		)
		(stroke
			(width 0)
			(type solid)
		)
		(fill yes)
		(layer "In4.Cu")
		(net "M_D_CPU1_SA_DQ<19>")
	)
	(gr_poly
		(pts
			(xy 88.851232 -234.966256) (xy 88.751156 -234.86618) (xy 88.65108 -234.966256) (xy 88.65108 -235.010706)
			(xy 88.851232 -235.010706)
		)
		(stroke
			(width 0)
			(type solid)
		)
		(fill yes)
		(layer "In4.Cu")
		(net "M_D_CPU1_SA_DQ<16>")
	)
	(gr_poly
		(pts
			(xy 88.851232 -234.562396) (xy 88.851232 -234.517946) (xy 88.65108 -234.517946) (xy 88.65108 -234.562396)
			(xy 88.751156 -234.662472)
		)
		(stroke
			(width 0)
			(type solid)
		)
		(fill yes)
		(layer "In4.Cu")
		(net "M_D_CPU1_SA_DQ<15>")
	)
	(gr_poly
		(pts
			(xy 88.851232 -233.346244) (xy 88.751156 -233.246168) (xy 88.65108 -233.346244) (xy 88.65108 -233.390694)
			(xy 88.851232 -233.390694)
		)
		(stroke
			(width 0)
			(type solid)
		)
		(fill yes)
		(layer "In4.Cu")
		(net "M_D_CPU1_SA_DQ<12>")
	)
	(gr_poly
		(pts
			(xy 88.851232 -232.942638) (xy 88.851232 -232.894886) (xy 88.65108 -232.894886) (xy 88.65108 -232.942638)
			(xy 88.751156 -233.04246)
		)
		(stroke
			(width 0)
			(type solid)
		)
		(fill yes)
		(layer "In4.Cu")
		(net "M_D_CPU1_SA_DQS_DP<6>")
	)
	(gr_poly
		(pts
			(xy 88.851232 -231.725978) (xy 88.751156 -231.626156) (xy 88.65108 -231.725978) (xy 88.65108 -231.77373)
			(xy 88.851232 -231.77373)
		)
		(stroke
			(width 0)
			(type solid)
		)
		(fill yes)
		(layer "In4.Cu")
		(net "M_D_CPU1_SA_DQS_DP<1>")
	)
	(gr_poly
		(pts
			(xy 88.851232 -231.322626) (xy 88.851232 -231.278176) (xy 88.65108 -231.278176) (xy 88.65108 -231.322626)
			(xy 88.751156 -231.422702)
		)
		(stroke
			(width 0)
			(type solid)
		)
		(fill yes)
		(layer "In4.Cu")
		(net "M_D_CPU1_SA_DQ<11>")
	)
	(gr_poly
		(pts
			(xy 88.851232 -230.10622) (xy 88.751156 -230.006144) (xy 88.65108 -230.10622) (xy 88.65108 -230.15067)
			(xy 88.851232 -230.15067)
		)
		(stroke
			(width 0)
			(type solid)
		)
		(fill yes)
		(layer "In4.Cu")
		(net "M_D_CPU1_SA_DQ<8>")
	)
	(gr_poly
		(pts
			(xy 88.851232 -229.702614) (xy 88.851232 -229.658164) (xy 88.65108 -229.658164) (xy 88.65108 -229.702614)
			(xy 88.751156 -229.80269)
		)
		(stroke
			(width 0)
			(type solid)
		)
		(fill yes)
		(layer "In4.Cu")
		(net "M_D_CPU1_SA_DQ<7>")
	)
	(gr_poly
		(pts
			(xy 88.851232 -228.486462) (xy 88.751156 -228.386386) (xy 88.65108 -228.486462) (xy 88.65108 -228.530912)
			(xy 88.851232 -228.530912)
		)
		(stroke
			(width 0)
			(type solid)
		)
		(fill yes)
		(layer "In4.Cu")
		(net "M_D_CPU1_SA_DQ<4>")
	)
	(gr_poly
		(pts
			(xy 88.851232 -228.082856) (xy 88.851232 -228.035104) (xy 88.65108 -228.035104) (xy 88.65108 -228.082856)
			(xy 88.751156 -228.182678)
		)
		(stroke
			(width 0)
			(type solid)
		)
		(fill yes)
		(layer "In4.Cu")
		(net "M_D_CPU1_SA_DQS_DP<5>")
	)
	(gr_poly
		(pts
			(xy 88.851232 -226.866196) (xy 88.751156 -226.766374) (xy 88.65108 -226.866196) (xy 88.65108 -226.913948)
			(xy 88.851232 -226.913948)
		)
		(stroke
			(width 0)
			(type solid)
		)
		(fill yes)
		(layer "In4.Cu")
		(net "M_D_CPU1_SA_DQS_DP<0>")
	)
	(gr_poly
		(pts
			(xy 88.851232 -226.46259) (xy 88.851232 -226.41814) (xy 88.65108 -226.41814) (xy 88.65108 -226.46259)
			(xy 88.751156 -226.562666)
		)
		(stroke
			(width 0)
			(type solid)
		)
		(fill yes)
		(layer "In4.Cu")
		(net "M_D_CPU1_SA_DQ<3>")
	)
	(gr_poly
		(pts
			(xy 88.851232 -225.246438) (xy 88.751156 -225.146362) (xy 88.65108 -225.246438) (xy 88.65108 -225.290888)
			(xy 88.851232 -225.290888)
		)
		(stroke
			(width 0)
			(type solid)
		)
		(fill yes)
		(layer "In4.Cu")
		(net "M_D_CPU1_SA_DQ<0>")
	)
	(gr_poly
		(pts
			(xy 89.144856 -266.991846) (xy 89.04478 -266.89177) (xy 88.944958 -266.991846) (xy 88.944958 -267.036296)
			(xy 89.144856 -267.036296)
		)
		(stroke
			(width 0)
			(type solid)
		)
		(fill yes)
		(layer "In4.Cu")
		(net "M_D_CPU1_SA_RSP<0>")
	)
	(gr_poly
		(pts
			(xy 89.151206 -292.918134) (xy 89.05113 -292.818058) (xy 88.951054 -292.918134) (xy 88.951054 -292.962584)
			(xy 89.151206 -292.962584)
		)
		(stroke
			(width 0)
			(type solid)
		)
		(fill yes)
		(layer "In4.Cu")
		(net "M_D_CPU1_SB_DQ<29>")
	)
	(gr_poly
		(pts
			(xy 89.151206 -292.514274) (xy 89.151206 -292.469824) (xy 88.951054 -292.469824) (xy 88.951054 -292.514274)
			(xy 89.05113 -292.61435)
		)
		(stroke
			(width 0)
			(type solid)
		)
		(fill yes)
		(layer "In4.Cu")
		(net "M_D_CPU1_SB_DQ<30>")
	)
	(gr_poly
		(pts
			(xy 89.151206 -291.297868) (xy 89.05113 -291.198046) (xy 88.951054 -291.297868) (xy 88.951054 -291.34562)
			(xy 89.151206 -291.34562)
		)
		(stroke
			(width 0)
			(type solid)
		)
		(fill yes)
		(layer "In4.Cu")
		(net "M_D_CPU1_SB_DQS_DN<8>")
	)
	(gr_poly
		(pts
			(xy 89.151206 -290.894516) (xy 89.151206 -290.846764) (xy 88.951054 -290.846764) (xy 88.951054 -290.894516)
			(xy 89.05113 -290.994338)
		)
		(stroke
			(width 0)
			(type solid)
		)
		(fill yes)
		(layer "In4.Cu")
		(net "M_D_CPU1_SB_DQS_DN<3>")
	)
	(gr_poly
		(pts
			(xy 89.151206 -289.67811) (xy 89.05113 -289.578034) (xy 88.951054 -289.67811) (xy 88.951054 -289.72256)
			(xy 89.151206 -289.72256)
		)
		(stroke
			(width 0)
			(type solid)
		)
		(fill yes)
		(layer "In4.Cu")
		(net "M_D_CPU1_SB_DQ<25>")
	)
	(gr_poly
		(pts
			(xy 89.151206 -289.27425) (xy 89.151206 -289.2298) (xy 88.951054 -289.2298) (xy 88.951054 -289.27425)
			(xy 89.05113 -289.374326)
		)
		(stroke
			(width 0)
			(type solid)
		)
		(fill yes)
		(layer "In4.Cu")
		(net "M_D_CPU1_SB_DQ<26>")
	)
	(gr_poly
		(pts
			(xy 89.151206 -288.058098) (xy 89.05113 -287.958022) (xy 88.951054 -288.058098) (xy 88.951054 -288.102548)
			(xy 89.151206 -288.102548)
		)
		(stroke
			(width 0)
			(type solid)
		)
		(fill yes)
		(layer "In4.Cu")
		(net "M_D_CPU1_SB_DQ<21>")
	)
	(gr_poly
		(pts
			(xy 89.151206 -287.654492) (xy 89.151206 -287.610042) (xy 88.951054 -287.610042) (xy 88.951054 -287.654492)
			(xy 89.05113 -287.754568)
		)
		(stroke
			(width 0)
			(type solid)
		)
		(fill yes)
		(layer "In4.Cu")
		(net "M_D_CPU1_SB_DQ<22>")
	)
	(gr_poly
		(pts
			(xy 89.151206 -286.438086) (xy 89.05113 -286.33801) (xy 88.951054 -286.438086) (xy 88.951054 -286.485838)
			(xy 89.151206 -286.485838)
		)
		(stroke
			(width 0)
			(type solid)
		)
		(fill yes)
		(layer "In4.Cu")
		(net "M_D_CPU1_SB_DQS_DN<7>")
	)
	(gr_poly
		(pts
			(xy 89.151206 -286.034734) (xy 89.151206 -285.986982) (xy 88.951054 -285.986982) (xy 88.951054 -286.034734)
			(xy 89.05113 -286.134556)
		)
		(stroke
			(width 0)
			(type solid)
		)
		(fill yes)
		(layer "In4.Cu")
		(net "M_D_CPU1_SB_DQS_DN<2>")
	)
	(gr_poly
		(pts
			(xy 89.151206 -284.818328) (xy 89.05113 -284.718252) (xy 88.951054 -284.818328) (xy 88.951054 -284.862778)
			(xy 89.151206 -284.862778)
		)
		(stroke
			(width 0)
			(type solid)
		)
		(fill yes)
		(layer "In4.Cu")
		(net "M_D_CPU1_SB_DQ<17>")
	)
	(gr_poly
		(pts
			(xy 89.151206 -284.414468) (xy 89.151206 -284.370018) (xy 88.951054 -284.370018) (xy 88.951054 -284.414468)
			(xy 89.05113 -284.514544)
		)
		(stroke
			(width 0)
			(type solid)
		)
		(fill yes)
		(layer "In4.Cu")
		(net "M_D_CPU1_SB_DQ<18>")
	)
	(gr_poly
		(pts
			(xy 89.151206 -283.198316) (xy 89.05113 -283.09824) (xy 88.951054 -283.198316) (xy 88.951054 -283.242766)
			(xy 89.151206 -283.242766)
		)
		(stroke
			(width 0)
			(type solid)
		)
		(fill yes)
		(layer "In4.Cu")
		(net "M_D_CPU1_SB_DQ<13>")
	)
	(gr_poly
		(pts
			(xy 89.151206 -282.794456) (xy 89.151206 -282.750006) (xy 88.951054 -282.750006) (xy 88.951054 -282.794456)
			(xy 89.05113 -282.894532)
		)
		(stroke
			(width 0)
			(type solid)
		)
		(fill yes)
		(layer "In4.Cu")
		(net "M_D_CPU1_SB_DQ<14>")
	)
	(gr_poly
		(pts
			(xy 89.151206 -281.57805) (xy 89.05113 -281.478228) (xy 88.951054 -281.57805) (xy 88.951054 -281.625802)
			(xy 89.151206 -281.625802)
		)
		(stroke
			(width 0)
			(type solid)
		)
		(fill yes)
		(layer "In4.Cu")
		(net "M_D_CPU1_SB_DQS_DN<6>")
	)
	(gr_poly
		(pts
			(xy 89.151206 -281.174698) (xy 89.151206 -281.126946) (xy 88.951054 -281.126946) (xy 88.951054 -281.174698)
			(xy 89.05113 -281.27452)
		)
		(stroke
			(width 0)
			(type solid)
		)
		(fill yes)
		(layer "In4.Cu")
		(net "M_D_CPU1_SB_DQS_DN<1>")
	)
	(gr_poly
		(pts
			(xy 89.151206 -279.958292) (xy 89.05113 -279.858216) (xy 88.951054 -279.958292) (xy 88.951054 -280.002742)
			(xy 89.151206 -280.002742)
		)
		(stroke
			(width 0)
			(type solid)
		)
		(fill yes)
		(layer "In4.Cu")
		(net "M_D_CPU1_SB_DQ<9>")
	)
	(gr_poly
		(pts
			(xy 89.151206 -279.554432) (xy 89.151206 -279.509982) (xy 88.951054 -279.509982) (xy 88.951054 -279.554432)
			(xy 89.05113 -279.654508)
		)
		(stroke
			(width 0)
			(type solid)
		)
		(fill yes)
		(layer "In4.Cu")
		(net "M_D_CPU1_SB_DQ<10>")
	)
	(gr_poly
		(pts
			(xy 89.151206 -278.33828) (xy 89.05113 -278.238204) (xy 88.951054 -278.33828) (xy 88.951054 -278.38273)
			(xy 89.151206 -278.38273)
		)
		(stroke
			(width 0)
			(type solid)
		)
		(fill yes)
		(layer "In4.Cu")
		(net "M_D_CPU1_SB_DQ<5>")
	)
	(gr_poly
		(pts
			(xy 89.151206 -277.93442) (xy 89.151206 -277.88997) (xy 88.951054 -277.88997) (xy 88.951054 -277.93442)
			(xy 89.05113 -278.034496)
		)
		(stroke
			(width 0)
			(type solid)
		)
		(fill yes)
		(layer "In4.Cu")
		(net "M_D_CPU1_SB_DQ<6>")
	)
	(gr_poly
		(pts
			(xy 89.151206 -276.718014) (xy 89.05113 -276.618192) (xy 88.951054 -276.718014) (xy 88.951054 -276.765766)
			(xy 89.151206 -276.765766)
		)
		(stroke
			(width 0)
			(type solid)
		)
		(fill yes)
		(layer "In4.Cu")
		(net "M_D_CPU1_SB_DQS_DN<5>")
	)
	(gr_poly
		(pts
			(xy 89.151206 -276.314662) (xy 89.151206 -276.26691) (xy 88.951054 -276.26691) (xy 88.951054 -276.314662)
			(xy 89.05113 -276.414484)
		)
		(stroke
			(width 0)
			(type solid)
		)
		(fill yes)
		(layer "In4.Cu")
		(net "M_D_CPU1_SB_DQS_DN<0>")
	)
	(gr_poly
		(pts
			(xy 89.151206 -275.098256) (xy 89.05113 -274.99818) (xy 88.951054 -275.098256) (xy 88.951054 -275.142706)
			(xy 89.151206 -275.142706)
		)
		(stroke
			(width 0)
			(type solid)
		)
		(fill yes)
		(layer "In4.Cu")
		(net "M_D_CPU1_SB_DQ<1>")
	)
	(gr_poly
		(pts
			(xy 89.151206 -274.694396) (xy 89.151206 -274.649946) (xy 88.951054 -274.649946) (xy 88.951054 -274.694396)
			(xy 89.05113 -274.794472)
		)
		(stroke
			(width 0)
			(type solid)
		)
		(fill yes)
		(layer "In4.Cu")
		(net "M_D_CPU1_SB_DQ<2>")
	)
	(gr_poly
		(pts
			(xy 89.151206 -273.478244) (xy 89.05113 -273.378168) (xy 88.951054 -273.478244) (xy 88.951054 -273.522694)
			(xy 89.151206 -273.522694)
		)
		(stroke
			(width 0)
			(type solid)
		)
		(fill yes)
		(layer "In4.Cu")
		(net "M_D_CPU1_SB_CB<1>")
	)
	(gr_poly
		(pts
			(xy 89.151206 -273.074384) (xy 89.151206 -273.029934) (xy 88.951054 -273.029934) (xy 88.951054 -273.074384)
			(xy 89.05113 -273.17446)
		)
		(stroke
			(width 0)
			(type solid)
		)
		(fill yes)
		(layer "In4.Cu")
		(net "M_D_CPU1_SB_CB<2>")
	)
	(gr_poly
		(pts
			(xy 89.151206 -271.857978) (xy 89.05113 -271.758156) (xy 88.951054 -271.857978) (xy 88.951054 -271.90573)
			(xy 89.151206 -271.90573)
		)
		(stroke
			(width 0)
			(type solid)
		)
		(fill yes)
		(layer "In4.Cu")
		(net "M_D_CPU1_SB_DQS_DN<4>")
	)
	(gr_poly
		(pts
			(xy 89.151206 -271.454626) (xy 89.151206 -271.406874) (xy 88.951054 -271.406874) (xy 88.951054 -271.454626)
			(xy 89.05113 -271.554448)
		)
		(stroke
			(width 0)
			(type solid)
		)
		(fill yes)
		(layer "In4.Cu")
		(net "M_D_CPU1_SB_DQS_DN<9>")
	)
	(gr_poly
		(pts
			(xy 89.151206 -270.23822) (xy 89.05113 -270.138144) (xy 88.951054 -270.23822) (xy 88.951054 -270.28267)
			(xy 89.151206 -270.28267)
		)
		(stroke
			(width 0)
			(type solid)
		)
		(fill yes)
		(layer "In4.Cu")
		(net "M_D_CPU1_SB_CB<5>")
	)
	(gr_poly
		(pts
			(xy 89.151206 -269.83436) (xy 89.151206 -269.78991) (xy 88.951054 -269.78991) (xy 88.951054 -269.83436)
			(xy 89.05113 -269.934436)
		)
		(stroke
			(width 0)
			(type solid)
		)
		(fill yes)
		(layer "In4.Cu")
		(net "M_D_CPU1_SB_CB<6>")
	)
	(gr_poly
		(pts
			(xy 89.151206 -266.594336) (xy 89.151206 -266.549886) (xy 88.951054 -266.549886) (xy 88.951054 -266.594336)
			(xy 89.05113 -266.694412)
		)
		(stroke
			(width 0)
			(type solid)
		)
		(fill yes)
		(layer "In4.Cu")
		(net "M_D_CPU1_SB_CS_N<1>")
	)
	(gr_poly
		(pts
			(xy 89.151206 -264.974324) (xy 89.151206 -264.929874) (xy 88.951054 -264.929874) (xy 88.951054 -264.974324)
			(xy 89.05113 -265.0744)
		)
		(stroke
			(width 0)
			(type solid)
		)
		(fill yes)
		(layer "In4.Cu")
		(net "M_D_CPU1_SB_PAR")
	)
	(gr_poly
		(pts
			(xy 89.151206 -263.758172) (xy 89.05113 -263.658096) (xy 88.951054 -263.758172) (xy 88.951054 -263.802622)
			(xy 89.151206 -263.802622)
		)
		(stroke
			(width 0)
			(type solid)
		)
		(fill yes)
		(layer "In4.Cu")
		(net "M_D_CPU1_SB_CA<4>")
	)
	(gr_poly
		(pts
			(xy 89.151206 -263.354312) (xy 89.151206 -263.309862) (xy 88.951054 -263.309862) (xy 88.951054 -263.354312)
			(xy 89.05113 -263.454388)
		)
		(stroke
			(width 0)
			(type solid)
		)
		(fill yes)
		(layer "In4.Cu")
		(net "M_D_CPU1_SB_CA<3>")
	)
	(gr_poly
		(pts
			(xy 89.151206 -262.13816) (xy 89.05113 -262.038084) (xy 88.951054 -262.13816) (xy 88.951054 -262.18261)
			(xy 89.151206 -262.18261)
		)
		(stroke
			(width 0)
			(type solid)
		)
		(fill yes)
		(layer "In4.Cu")
		(net "M_D_CPU1_SB_CA<0>")
	)
	(gr_poly
		(pts
			(xy 89.321132 -256.432812) (xy 89.321132 -256.38506) (xy 89.12098 -256.38506) (xy 89.12098 -256.432812)
			(xy 89.221056 -256.532634)
		)
		(stroke
			(width 0)
			(type solid)
		)
		(fill yes)
		(layer "In4.Cu")
		(net "M_D_CPU1_CLK_DN<0>")
	)
	(gr_poly
		(pts
			(xy 89.321132 -255.216406) (xy 89.221056 -255.11633) (xy 89.12098 -255.216406) (xy 89.12098 -255.260856)
			(xy 89.321132 -255.260856)
		)
		(stroke
			(width 0)
			(type solid)
		)
		(fill yes)
		(layer "In4.Cu")
		(net "M_D_CPU1_SA_CA<6>")
	)
	(gr_poly
		(pts
			(xy 89.321132 -254.812546) (xy 89.321132 -254.768096) (xy 89.12098 -254.768096) (xy 89.12098 -254.812546)
			(xy 89.221056 -254.912622)
		)
		(stroke
			(width 0)
			(type solid)
		)
		(fill yes)
		(layer "In4.Cu")
		(net "M_D_CPU1_SA_CA<5>")
	)
	(gr_poly
		(pts
			(xy 89.321132 -253.596394) (xy 89.221056 -253.496318) (xy 89.12098 -253.596394) (xy 89.12098 -253.640844)
			(xy 89.321132 -253.640844)
		)
		(stroke
			(width 0)
			(type solid)
		)
		(fill yes)
		(layer "In4.Cu")
		(net "M_D_CPU1_SA_CA<2>")
	)
	(gr_poly
		(pts
			(xy 89.321132 -253.192534) (xy 89.321132 -253.148084) (xy 89.12098 -253.148084) (xy 89.12098 -253.192534)
			(xy 89.221056 -253.29261)
		)
		(stroke
			(width 0)
			(type solid)
		)
		(fill yes)
		(layer "In4.Cu")
		(net "M_D_CPU1_SA_CA<1>")
	)
	(gr_poly
		(pts
			(xy 89.321132 -251.572522) (xy 89.321132 -251.528072) (xy 89.12098 -251.528072) (xy 89.12098 -251.572522)
			(xy 89.221056 -251.672598)
		)
		(stroke
			(width 0)
			(type solid)
		)
		(fill yes)
		(layer "In4.Cu")
		(net "M_D_CPU1_SA_CS_N<0>")
	)
	(gr_poly
		(pts
			(xy 89.321132 -250.35637) (xy 89.221056 -250.256294) (xy 89.12098 -250.35637) (xy 89.12098 -250.40082)
			(xy 89.321132 -250.40082)
		)
		(stroke
			(width 0)
			(type solid)
		)
		(fill yes)
		(layer "In4.Cu")
		(net "M_D_CPU1_ALERT_R_N")
	)
	(gr_poly
		(pts
			(xy 89.321132 -248.736358) (xy 89.221056 -248.636282) (xy 89.12098 -248.736358) (xy 89.12098 -248.780808)
			(xy 89.321132 -248.780808)
		)
		(stroke
			(width 0)
			(type solid)
		)
		(fill yes)
		(layer "In4.Cu")
		(net "M_D_CPU1_SA_CB<5>")
	)
	(gr_poly
		(pts
			(xy 89.321132 -248.332498) (xy 89.321132 -248.288048) (xy 89.12098 -248.288048) (xy 89.12098 -248.332498)
			(xy 89.221056 -248.432574)
		)
		(stroke
			(width 0)
			(type solid)
		)
		(fill yes)
		(layer "In4.Cu")
		(net "M_D_CPU1_SA_CB<6>")
	)
	(gr_poly
		(pts
			(xy 89.321132 -247.116092) (xy 89.221056 -247.01627) (xy 89.12098 -247.116092) (xy 89.12098 -247.163844)
			(xy 89.321132 -247.163844)
		)
		(stroke
			(width 0)
			(type solid)
		)
		(fill yes)
		(layer "In4.Cu")
		(net "M_D_CPU1_SA_DQS_DN<9>")
	)
	(gr_poly
		(pts
			(xy 89.321132 -246.71274) (xy 89.321132 -246.664988) (xy 89.12098 -246.664988) (xy 89.12098 -246.71274)
			(xy 89.221056 -246.812562)
		)
		(stroke
			(width 0)
			(type solid)
		)
		(fill yes)
		(layer "In4.Cu")
		(net "M_D_CPU1_SA_DQS_DN<4>")
	)
	(gr_poly
		(pts
			(xy 89.321132 -245.496334) (xy 89.221056 -245.396258) (xy 89.12098 -245.496334) (xy 89.12098 -245.540784)
			(xy 89.321132 -245.540784)
		)
		(stroke
			(width 0)
			(type solid)
		)
		(fill yes)
		(layer "In4.Cu")
		(net "M_D_CPU1_SA_CB<1>")
	)
	(gr_poly
		(pts
			(xy 89.321132 -245.092474) (xy 89.321132 -245.048024) (xy 89.12098 -245.048024) (xy 89.12098 -245.092474)
			(xy 89.221056 -245.19255)
		)
		(stroke
			(width 0)
			(type solid)
		)
		(fill yes)
		(layer "In4.Cu")
		(net "M_D_CPU1_SA_CB<2>")
	)
	(gr_poly
		(pts
			(xy 89.321132 -243.876322) (xy 89.221056 -243.776246) (xy 89.12098 -243.876322) (xy 89.12098 -243.920772)
			(xy 89.321132 -243.920772)
		)
		(stroke
			(width 0)
			(type solid)
		)
		(fill yes)
		(layer "In4.Cu")
		(net "M_D_CPU1_SA_DQ<29>")
	)
	(gr_poly
		(pts
			(xy 89.321132 -243.472462) (xy 89.321132 -243.428012) (xy 89.12098 -243.428012) (xy 89.12098 -243.472462)
			(xy 89.221056 -243.572538)
		)
		(stroke
			(width 0)
			(type solid)
		)
		(fill yes)
		(layer "In4.Cu")
		(net "M_D_CPU1_SA_DQ<30>")
	)
	(gr_poly
		(pts
			(xy 89.321132 -242.256056) (xy 89.221056 -242.156234) (xy 89.12098 -242.256056) (xy 89.12098 -242.303808)
			(xy 89.321132 -242.303808)
		)
		(stroke
			(width 0)
			(type solid)
		)
		(fill yes)
		(layer "In4.Cu")
		(net "M_D_CPU1_SA_DQS_DN<8>")
	)
	(gr_poly
		(pts
			(xy 89.321132 -241.852704) (xy 89.321132 -241.804952) (xy 89.12098 -241.804952) (xy 89.12098 -241.852704)
			(xy 89.221056 -241.952526)
		)
		(stroke
			(width 0)
			(type solid)
		)
		(fill yes)
		(layer "In4.Cu")
		(net "M_D_CPU1_SA_DQS_DN<3>")
	)
	(gr_poly
		(pts
			(xy 89.321132 -240.636298) (xy 89.221056 -240.536222) (xy 89.12098 -240.636298) (xy 89.12098 -240.680748)
			(xy 89.321132 -240.680748)
		)
		(stroke
			(width 0)
			(type solid)
		)
		(fill yes)
		(layer "In4.Cu")
		(net "M_D_CPU1_SA_DQ<25>")
	)
	(gr_poly
		(pts
			(xy 89.321132 -240.232438) (xy 89.321132 -240.187988) (xy 89.12098 -240.187988) (xy 89.12098 -240.232438)
			(xy 89.221056 -240.332514)
		)
		(stroke
			(width 0)
			(type solid)
		)
		(fill yes)
		(layer "In4.Cu")
		(net "M_D_CPU1_SA_DQ<26>")
	)
	(gr_poly
		(pts
			(xy 89.321132 -239.016286) (xy 89.221056 -238.91621) (xy 89.12098 -239.016286) (xy 89.12098 -239.060736)
			(xy 89.321132 -239.060736)
		)
		(stroke
			(width 0)
			(type solid)
		)
		(fill yes)
		(layer "In4.Cu")
		(net "M_D_CPU1_SA_DQ<21>")
	)
	(gr_poly
		(pts
			(xy 89.321132 -238.612426) (xy 89.321132 -238.567976) (xy 89.12098 -238.567976) (xy 89.12098 -238.612426)
			(xy 89.221056 -238.712502)
		)
		(stroke
			(width 0)
			(type solid)
		)
		(fill yes)
		(layer "In4.Cu")
		(net "M_D_CPU1_SA_DQ<22>")
	)
	(gr_poly
		(pts
			(xy 89.321132 -237.39602) (xy 89.221056 -237.296198) (xy 89.12098 -237.39602) (xy 89.12098 -237.443772)
			(xy 89.321132 -237.443772)
		)
		(stroke
			(width 0)
			(type solid)
		)
		(fill yes)
		(layer "In4.Cu")
		(net "M_D_CPU1_SA_DQS_DN<7>")
	)
	(gr_poly
		(pts
			(xy 89.321132 -236.992668) (xy 89.321132 -236.944916) (xy 89.12098 -236.944916) (xy 89.12098 -236.992668)
			(xy 89.221056 -237.09249)
		)
		(stroke
			(width 0)
			(type solid)
		)
		(fill yes)
		(layer "In4.Cu")
		(net "M_D_CPU1_SA_DQS_DN<2>")
	)
	(gr_poly
		(pts
			(xy 89.321132 -235.776262) (xy 89.221056 -235.676186) (xy 89.12098 -235.776262) (xy 89.12098 -235.820712)
			(xy 89.321132 -235.820712)
		)
		(stroke
			(width 0)
			(type solid)
		)
		(fill yes)
		(layer "In4.Cu")
		(net "M_D_CPU1_SA_DQ<17>")
	)
	(gr_poly
		(pts
			(xy 89.321132 -235.372402) (xy 89.321132 -235.327952) (xy 89.12098 -235.327952) (xy 89.12098 -235.372402)
			(xy 89.221056 -235.472478)
		)
		(stroke
			(width 0)
			(type solid)
		)
		(fill yes)
		(layer "In4.Cu")
		(net "M_D_CPU1_SA_DQ<18>")
	)
	(gr_poly
		(pts
			(xy 89.321132 -234.15625) (xy 89.221056 -234.056174) (xy 89.12098 -234.15625) (xy 89.12098 -234.2007)
			(xy 89.321132 -234.2007)
		)
		(stroke
			(width 0)
			(type solid)
		)
		(fill yes)
		(layer "In4.Cu")
		(net "M_D_CPU1_SA_DQ<13>")
	)
	(gr_poly
		(pts
			(xy 89.321132 -233.75239) (xy 89.321132 -233.70794) (xy 89.12098 -233.70794) (xy 89.12098 -233.75239)
			(xy 89.221056 -233.852466)
		)
		(stroke
			(width 0)
			(type solid)
		)
		(fill yes)
		(layer "In4.Cu")
		(net "M_D_CPU1_SA_DQ<14>")
	)
	(gr_poly
		(pts
			(xy 89.321132 -232.535984) (xy 89.221056 -232.436162) (xy 89.12098 -232.535984) (xy 89.12098 -232.583736)
			(xy 89.321132 -232.583736)
		)
		(stroke
			(width 0)
			(type solid)
		)
		(fill yes)
		(layer "In4.Cu")
		(net "M_D_CPU1_SA_DQS_DN<6>")
	)
	(gr_poly
		(pts
			(xy 89.321132 -232.132632) (xy 89.321132 -232.08488) (xy 89.12098 -232.08488) (xy 89.12098 -232.132632)
			(xy 89.221056 -232.232454)
		)
		(stroke
			(width 0)
			(type solid)
		)
		(fill yes)
		(layer "In4.Cu")
		(net "M_D_CPU1_SA_DQS_DN<1>")
	)
	(gr_poly
		(pts
			(xy 89.321132 -230.916226) (xy 89.221056 -230.81615) (xy 89.12098 -230.916226) (xy 89.12098 -230.960676)
			(xy 89.321132 -230.960676)
		)
		(stroke
			(width 0)
			(type solid)
		)
		(fill yes)
		(layer "In4.Cu")
		(net "M_D_CPU1_SA_DQ<9>")
	)
	(gr_poly
		(pts
			(xy 89.321132 -230.51262) (xy 89.321132 -230.46817) (xy 89.12098 -230.46817) (xy 89.12098 -230.51262)
			(xy 89.221056 -230.612696)
		)
		(stroke
			(width 0)
			(type solid)
		)
		(fill yes)
		(layer "In4.Cu")
		(net "M_D_CPU1_SA_DQ<10>")
	)
	(gr_poly
		(pts
			(xy 89.321132 -229.296214) (xy 89.221056 -229.196138) (xy 89.12098 -229.296214) (xy 89.12098 -229.340664)
			(xy 89.321132 -229.340664)
		)
		(stroke
			(width 0)
			(type solid)
		)
		(fill yes)
		(layer "In4.Cu")
		(net "M_D_CPU1_SA_DQ<5>")
	)
	(gr_poly
		(pts
			(xy 89.321132 -228.892608) (xy 89.321132 -228.848158) (xy 89.12098 -228.848158) (xy 89.12098 -228.892608)
			(xy 89.221056 -228.992684)
		)
		(stroke
			(width 0)
			(type solid)
		)
		(fill yes)
		(layer "In4.Cu")
		(net "M_D_CPU1_SA_DQ<6>")
	)
	(gr_poly
		(pts
			(xy 89.321132 -227.67671) (xy 89.221056 -227.576634) (xy 89.12098 -227.67671) (xy 89.12098 -227.724462)
			(xy 89.321132 -227.724462)
		)
		(stroke
			(width 0)
			(type solid)
		)
		(fill yes)
		(layer "In4.Cu")
		(net "M_D_CPU1_SA_DQS_DN<5>")
	)
	(gr_poly
		(pts
			(xy 89.321132 -227.27285) (xy 89.321132 -227.225098) (xy 89.12098 -227.225098) (xy 89.12098 -227.27285)
			(xy 89.221056 -227.372672)
		)
		(stroke
			(width 0)
			(type solid)
		)
		(fill yes)
		(layer "In4.Cu")
		(net "M_D_CPU1_SA_DQS_DN<0>")
	)
	(gr_poly
		(pts
			(xy 89.321132 -226.056444) (xy 89.221056 -225.956368) (xy 89.12098 -226.056444) (xy 89.12098 -226.100894)
			(xy 89.321132 -226.100894)
		)
		(stroke
			(width 0)
			(type solid)
		)
		(fill yes)
		(layer "In4.Cu")
		(net "M_D_CPU1_SA_DQ<1>")
	)
	(gr_poly
		(pts
			(xy 89.321132 -225.652584) (xy 89.321132 -225.608134) (xy 89.12098 -225.608134) (xy 89.12098 -225.652584)
			(xy 89.221056 -225.75266)
		)
		(stroke
			(width 0)
			(type solid)
		)
		(fill yes)
		(layer "In4.Cu")
		(net "M_D_CPU1_SA_DQ<2>")
	)
	(gr_poly
		(pts
			(xy 89.621106 -293.32428) (xy 89.621106 -293.27983) (xy 89.420954 -293.27983) (xy 89.420954 -293.32428)
			(xy 89.52103 -293.424356)
		)
		(stroke
			(width 0)
			(type solid)
		)
		(fill yes)
		(layer "In4.Cu")
		(net "M_D_CPU1_SB_DQ<31>")
	)
	(gr_poly
		(pts
			(xy 89.621106 -292.108128) (xy 89.52103 -292.008052) (xy 89.420954 -292.108128) (xy 89.420954 -292.152578)
			(xy 89.621106 -292.152578)
		)
		(stroke
			(width 0)
			(type solid)
		)
		(fill yes)
		(layer "In4.Cu")
		(net "M_D_CPU1_SB_DQ<28>")
	)
	(gr_poly
		(pts
			(xy 89.621106 -291.704522) (xy 89.621106 -291.65677) (xy 89.420954 -291.65677) (xy 89.420954 -291.704522)
			(xy 89.52103 -291.804344)
		)
		(stroke
			(width 0)
			(type solid)
		)
		(fill yes)
		(layer "In4.Cu")
		(net "M_D_CPU1_SB_DQS_DP<8>")
	)
	(gr_poly
		(pts
			(xy 89.621106 -290.487862) (xy 89.52103 -290.38804) (xy 89.420954 -290.487862) (xy 89.420954 -290.535614)
			(xy 89.621106 -290.535614)
		)
		(stroke
			(width 0)
			(type solid)
		)
		(fill yes)
		(layer "In4.Cu")
		(net "M_D_CPU1_SB_DQS_DP<3>")
	)
	(gr_poly
		(pts
			(xy 89.621106 -290.084256) (xy 89.621106 -290.039806) (xy 89.420954 -290.039806) (xy 89.420954 -290.084256)
			(xy 89.52103 -290.184332)
		)
		(stroke
			(width 0)
			(type solid)
		)
		(fill yes)
		(layer "In4.Cu")
		(net "M_D_CPU1_SB_DQ<27>")
	)
	(gr_poly
		(pts
			(xy 89.621106 -288.868104) (xy 89.52103 -288.768028) (xy 89.420954 -288.868104) (xy 89.420954 -288.912554)
			(xy 89.621106 -288.912554)
		)
		(stroke
			(width 0)
			(type solid)
		)
		(fill yes)
		(layer "In4.Cu")
		(net "M_D_CPU1_SB_DQ<24>")
	)
	(gr_poly
		(pts
			(xy 89.621106 -288.464498) (xy 89.621106 -288.420048) (xy 89.420954 -288.420048) (xy 89.420954 -288.464498)
			(xy 89.52103 -288.564574)
		)
		(stroke
			(width 0)
			(type solid)
		)
		(fill yes)
		(layer "In4.Cu")
		(net "M_D_CPU1_SB_DQ<23>")
	)
	(gr_poly
		(pts
			(xy 89.621106 -287.248092) (xy 89.52103 -287.148016) (xy 89.420954 -287.248092) (xy 89.420954 -287.292542)
			(xy 89.621106 -287.292542)
		)
		(stroke
			(width 0)
			(type solid)
		)
		(fill yes)
		(layer "In4.Cu")
		(net "M_D_CPU1_SB_DQ<20>")
	)
	(gr_poly
		(pts
			(xy 89.621106 -286.844486) (xy 89.621106 -286.796734) (xy 89.420954 -286.796734) (xy 89.420954 -286.844486)
			(xy 89.52103 -286.944562)
		)
		(stroke
			(width 0)
			(type solid)
		)
		(fill yes)
		(layer "In4.Cu")
		(net "M_D_CPU1_SB_DQS_DP<7>")
	)
	(gr_poly
		(pts
			(xy 89.621106 -285.62808) (xy 89.52103 -285.528258) (xy 89.420954 -285.62808) (xy 89.420954 -285.675832)
			(xy 89.621106 -285.675832)
		)
		(stroke
			(width 0)
			(type solid)
		)
		(fill yes)
		(layer "In4.Cu")
		(net "M_D_CPU1_SB_DQS_DP<2>")
	)
	(gr_poly
		(pts
			(xy 89.621106 -285.224474) (xy 89.621106 -285.180024) (xy 89.420954 -285.180024) (xy 89.420954 -285.224474)
			(xy 89.52103 -285.32455)
		)
		(stroke
			(width 0)
			(type solid)
		)
		(fill yes)
		(layer "In4.Cu")
		(net "M_D_CPU1_SB_DQ<19>")
	)
	(gr_poly
		(pts
			(xy 89.621106 -284.008322) (xy 89.52103 -283.908246) (xy 89.420954 -284.008322) (xy 89.420954 -284.052772)
			(xy 89.621106 -284.052772)
		)
		(stroke
			(width 0)
			(type solid)
		)
		(fill yes)
		(layer "In4.Cu")
		(net "M_D_CPU1_SB_DQ<16>")
	)
	(gr_poly
		(pts
			(xy 89.621106 -283.604462) (xy 89.621106 -283.560012) (xy 89.420954 -283.560012) (xy 89.420954 -283.604462)
			(xy 89.52103 -283.704538)
		)
		(stroke
			(width 0)
			(type solid)
		)
		(fill yes)
		(layer "In4.Cu")
		(net "M_D_CPU1_SB_DQ<15>")
	)
	(gr_poly
		(pts
			(xy 89.621106 -282.38831) (xy 89.52103 -282.288234) (xy 89.420954 -282.38831) (xy 89.420954 -282.43276)
			(xy 89.621106 -282.43276)
		)
		(stroke
			(width 0)
			(type solid)
		)
		(fill yes)
		(layer "In4.Cu")
		(net "M_D_CPU1_SB_DQ<12>")
	)
	(gr_poly
		(pts
			(xy 89.621106 -281.984704) (xy 89.621106 -281.936952) (xy 89.420954 -281.936952) (xy 89.420954 -281.984704)
			(xy 89.52103 -282.084526)
		)
		(stroke
			(width 0)
			(type solid)
		)
		(fill yes)
		(layer "In4.Cu")
		(net "M_D_CPU1_SB_DQS_DP<6>")
	)
	(gr_poly
		(pts
			(xy 89.621106 -280.768044) (xy 89.52103 -280.668222) (xy 89.420954 -280.768044) (xy 89.420954 -280.815796)
			(xy 89.621106 -280.815796)
		)
		(stroke
			(width 0)
			(type solid)
		)
		(fill yes)
		(layer "In4.Cu")
		(net "M_D_CPU1_SB_DQS_DP<1>")
	)
	(gr_poly
		(pts
			(xy 89.621106 -280.364438) (xy 89.621106 -280.319988) (xy 89.420954 -280.319988) (xy 89.420954 -280.364438)
			(xy 89.52103 -280.464514)
		)
		(stroke
			(width 0)
			(type solid)
		)
		(fill yes)
		(layer "In4.Cu")
		(net "M_D_CPU1_SB_DQ<11>")
	)
	(gr_poly
		(pts
			(xy 89.621106 -279.148286) (xy 89.52103 -279.04821) (xy 89.420954 -279.148286) (xy 89.420954 -279.192736)
			(xy 89.621106 -279.192736)
		)
		(stroke
			(width 0)
			(type solid)
		)
		(fill yes)
		(layer "In4.Cu")
		(net "M_D_CPU1_SB_DQ<8>")
	)
	(gr_poly
		(pts
			(xy 89.621106 -278.744426) (xy 89.621106 -278.699976) (xy 89.420954 -278.699976) (xy 89.420954 -278.744426)
			(xy 89.52103 -278.844502)
		)
		(stroke
			(width 0)
			(type solid)
		)
		(fill yes)
		(layer "In4.Cu")
		(net "M_D_CPU1_SB_DQ<7>")
	)
	(gr_poly
		(pts
			(xy 89.621106 -277.528274) (xy 89.52103 -277.428198) (xy 89.420954 -277.528274) (xy 89.420954 -277.572724)
			(xy 89.621106 -277.572724)
		)
		(stroke
			(width 0)
			(type solid)
		)
		(fill yes)
		(layer "In4.Cu")
		(net "M_D_CPU1_SB_DQ<4>")
	)
	(gr_poly
		(pts
			(xy 89.621106 -277.124668) (xy 89.621106 -277.076916) (xy 89.420954 -277.076916) (xy 89.420954 -277.124668)
			(xy 89.52103 -277.22449)
		)
		(stroke
			(width 0)
			(type solid)
		)
		(fill yes)
		(layer "In4.Cu")
		(net "M_D_CPU1_SB_DQS_DP<5>")
	)
	(gr_poly
		(pts
			(xy 89.621106 -275.908008) (xy 89.52103 -275.808186) (xy 89.420954 -275.908008) (xy 89.420954 -275.95576)
			(xy 89.621106 -275.95576)
		)
		(stroke
			(width 0)
			(type solid)
		)
		(fill yes)
		(layer "In4.Cu")
		(net "M_D_CPU1_SB_DQS_DP<0>")
	)
	(gr_poly
		(pts
			(xy 89.621106 -275.504402) (xy 89.621106 -275.459952) (xy 89.420954 -275.459952) (xy 89.420954 -275.504402)
			(xy 89.52103 -275.604478)
		)
		(stroke
			(width 0)
			(type solid)
		)
		(fill yes)
		(layer "In4.Cu")
		(net "M_D_CPU1_SB_DQ<3>")
	)
	(gr_poly
		(pts
			(xy 89.621106 -274.28825) (xy 89.52103 -274.188174) (xy 89.420954 -274.28825) (xy 89.420954 -274.3327)
			(xy 89.621106 -274.3327)
		)
		(stroke
			(width 0)
			(type solid)
		)
		(fill yes)
		(layer "In4.Cu")
		(net "M_D_CPU1_SB_DQ<0>")
	)
	(gr_poly
		(pts
			(xy 89.621106 -273.88439) (xy 89.621106 -273.83994) (xy 89.420954 -273.83994) (xy 89.420954 -273.88439)
			(xy 89.52103 -273.984466)
		)
		(stroke
			(width 0)
			(type solid)
		)
		(fill yes)
		(layer "In4.Cu")
		(net "M_D_CPU1_SB_CB<3>")
	)
	(gr_poly
		(pts
			(xy 89.621106 -272.668238) (xy 89.52103 -272.568162) (xy 89.420954 -272.668238) (xy 89.420954 -272.712688)
			(xy 89.621106 -272.712688)
		)
		(stroke
			(width 0)
			(type solid)
		)
		(fill yes)
		(layer "In4.Cu")
		(net "M_D_CPU1_SB_CB<0>")
	)
	(gr_poly
		(pts
			(xy 89.621106 -272.264632) (xy 89.621106 -272.21688) (xy 89.420954 -272.21688) (xy 89.420954 -272.264632)
			(xy 89.52103 -272.364454)
		)
		(stroke
			(width 0)
			(type solid)
		)
		(fill yes)
		(layer "In4.Cu")
		(net "M_D_CPU1_SB_DQS_DP<4>")
	)
	(gr_poly
		(pts
			(xy 89.621106 -271.047972) (xy 89.52103 -270.94815) (xy 89.420954 -271.047972) (xy 89.420954 -271.095724)
			(xy 89.621106 -271.095724)
		)
		(stroke
			(width 0)
			(type solid)
		)
		(fill yes)
		(layer "In4.Cu")
		(net "M_D_CPU1_SB_DQS_DP<9>")
	)
	(gr_poly
		(pts
			(xy 89.621106 -270.644366) (xy 89.621106 -270.599916) (xy 89.420954 -270.599916) (xy 89.420954 -270.644366)
			(xy 89.52103 -270.744442)
		)
		(stroke
			(width 0)
			(type solid)
		)
		(fill yes)
		(layer "In4.Cu")
		(net "M_D_CPU1_SB_CB<7>")
	)
	(gr_poly
		(pts
			(xy 89.621106 -269.428214) (xy 89.52103 -269.328138) (xy 89.420954 -269.428214) (xy 89.420954 -269.472664)
			(xy 89.621106 -269.472664)
		)
		(stroke
			(width 0)
			(type solid)
		)
		(fill yes)
		(layer "In4.Cu")
		(net "M_D_CPU1_SB_CB<4>")
	)
	(gr_poly
		(pts
			(xy 89.621106 -267.801852) (xy 89.52103 -267.701776) (xy 89.420954 -267.801852) (xy 89.420954 -267.846302)
			(xy 89.621106 -267.846302)
		)
		(stroke
			(width 0)
			(type solid)
		)
		(fill yes)
		(layer "In4.Cu")
		(net "M_D_CPU1_SB_RSP<0>")
	)
	(gr_poly
		(pts
			(xy 89.621106 -265.78433) (xy 89.621106 -265.73988) (xy 89.420954 -265.73988) (xy 89.420954 -265.78433)
			(xy 89.52103 -265.884406)
		)
		(stroke
			(width 0)
			(type solid)
		)
		(fill yes)
		(layer "In4.Cu")
		(net "M_D_CPU1_SB_CS_N<0>")
	)
	(gr_poly
		(pts
			(xy 89.621106 -264.568178) (xy 89.52103 -264.468102) (xy 89.420954 -264.568178) (xy 89.420954 -264.612628)
			(xy 89.621106 -264.612628)
		)
		(stroke
			(width 0)
			(type solid)
		)
		(fill yes)
		(layer "In4.Cu")
		(net "M_D_CPU1_SB_CA<6>")
	)
	(gr_poly
		(pts
			(xy 89.621106 -264.164318) (xy 89.621106 -264.119868) (xy 89.420954 -264.119868) (xy 89.420954 -264.164318)
			(xy 89.52103 -264.264394)
		)
		(stroke
			(width 0)
			(type solid)
		)
		(fill yes)
		(layer "In4.Cu")
		(net "M_D_CPU1_SB_CA<5>")
	)
	(gr_poly
		(pts
			(xy 89.621106 -262.948166) (xy 89.52103 -262.84809) (xy 89.420954 -262.948166) (xy 89.420954 -262.992616)
			(xy 89.621106 -262.992616)
		)
		(stroke
			(width 0)
			(type solid)
		)
		(fill yes)
		(layer "In4.Cu")
		(net "M_D_CPU1_SB_CA<2>")
	)
	(gr_poly
		(pts
			(xy 89.621106 -262.544306) (xy 89.621106 -262.499856) (xy 89.420954 -262.499856) (xy 89.420954 -262.544306)
			(xy 89.52103 -262.644382)
		)
		(stroke
			(width 0)
			(type solid)
		)
		(fill yes)
		(layer "In4.Cu")
		(net "M_D_CPU1_SB_CA<1>")
	)
	(gr_poly
		(pts
			(xy 89.791032 -256.026158) (xy 89.690956 -255.926336) (xy 89.59088 -256.026158) (xy 89.59088 -256.07391)
			(xy 89.791032 -256.07391)
		)
		(stroke
			(width 0)
			(type solid)
		)
		(fill yes)
		(layer "In4.Cu")
		(net "M_D_CPU1_CLK_DP<0>")
	)
	(gr_poly
		(pts
			(xy 89.791032 -255.622552) (xy 89.791032 -255.578102) (xy 89.59088 -255.578102) (xy 89.59088 -255.622552)
			(xy 89.690956 -255.722628)
		)
		(stroke
			(width 0)
			(type solid)
		)
		(fill yes)
		(layer "In4.Cu")
		(net "M_D_CPU1_SA_PAR")
	)
	(gr_poly
		(pts
			(xy 89.791032 -254.4064) (xy 89.690956 -254.306324) (xy 89.59088 -254.4064) (xy 89.59088 -254.45085)
			(xy 89.791032 -254.45085)
		)
		(stroke
			(width 0)
			(type solid)
		)
		(fill yes)
		(layer "In4.Cu")
		(net "M_D_CPU1_SA_CA<4>")
	)
	(gr_poly
		(pts
			(xy 89.791032 -254.00254) (xy 89.791032 -253.95809) (xy 89.59088 -253.95809) (xy 89.59088 -254.00254)
			(xy 89.690956 -254.102616)
		)
		(stroke
			(width 0)
			(type solid)
		)
		(fill yes)
		(layer "In4.Cu")
		(net "M_D_CPU1_SA_CA<3>")
	)
	(gr_poly
		(pts
			(xy 89.791032 -252.786388) (xy 89.690956 -252.686312) (xy 89.59088 -252.786388) (xy 89.59088 -252.830838)
			(xy 89.791032 -252.830838)
		)
		(stroke
			(width 0)
			(type solid)
		)
		(fill yes)
		(layer "In4.Cu")
		(net "M_D_CPU1_SA_CA<0>")
	)
	(gr_poly
		(pts
			(xy 89.791032 -252.382528) (xy 89.791032 -252.338078) (xy 89.59088 -252.338078) (xy 89.59088 -252.382528)
			(xy 89.690956 -252.482604)
		)
		(stroke
			(width 0)
			(type solid)
		)
		(fill yes)
		(layer "In4.Cu")
		(net "M_D_CPU1_SA_CS_N<1>")
	)
	(gr_poly
		(pts
			(xy 89.791032 -250.762516) (xy 89.791032 -250.718066) (xy 89.59088 -250.718066) (xy 89.59088 -250.762516)
			(xy 89.690956 -250.862592)
		)
		(stroke
			(width 0)
			(type solid)
		)
		(fill yes)
		(layer "In4.Cu")
		(net "M_D_CPU1_RESET_N")
	)
	(gr_poly
		(pts
			(xy 89.791032 -249.142504) (xy 89.791032 -249.098054) (xy 89.59088 -249.098054) (xy 89.59088 -249.142504)
			(xy 89.690956 -249.24258)
		)
		(stroke
			(width 0)
			(type solid)
		)
		(fill yes)
		(layer "In4.Cu")
		(net "M_D_CPU1_SA_CB<7>")
	)
	(gr_poly
		(pts
			(xy 89.791032 -247.926352) (xy 89.690956 -247.826276) (xy 89.59088 -247.926352) (xy 89.59088 -247.970802)
			(xy 89.791032 -247.970802)
		)
		(stroke
			(width 0)
			(type solid)
		)
		(fill yes)
		(layer "In4.Cu")
		(net "M_D_CPU1_SA_CB<4>")
	)
	(gr_poly
		(pts
			(xy 89.791032 -247.522746) (xy 89.791032 -247.474994) (xy 89.59088 -247.474994) (xy 89.59088 -247.522746)
			(xy 89.690956 -247.622568)
		)
		(stroke
			(width 0)
			(type solid)
		)
		(fill yes)
		(layer "In4.Cu")
		(net "M_D_CPU1_SA_DQS_DP<9>")
	)
	(gr_poly
		(pts
			(xy 89.791032 -246.306086) (xy 89.690956 -246.206264) (xy 89.59088 -246.306086) (xy 89.59088 -246.353838)
			(xy 89.791032 -246.353838)
		)
		(stroke
			(width 0)
			(type solid)
		)
		(fill yes)
		(layer "In4.Cu")
		(net "M_D_CPU1_SA_DQS_DP<4>")
	)
	(gr_poly
		(pts
			(xy 89.791032 -245.90248) (xy 89.791032 -245.85803) (xy 89.59088 -245.85803) (xy 89.59088 -245.90248)
			(xy 89.690956 -246.002556)
		)
		(stroke
			(width 0)
			(type solid)
		)
		(fill yes)
		(layer "In4.Cu")
		(net "M_D_CPU1_SA_CB<3>")
	)
	(gr_poly
		(pts
			(xy 89.791032 -244.686328) (xy 89.690956 -244.586252) (xy 89.59088 -244.686328) (xy 89.59088 -244.730778)
			(xy 89.791032 -244.730778)
		)
		(stroke
			(width 0)
			(type solid)
		)
		(fill yes)
		(layer "In4.Cu")
		(net "M_D_CPU1_SA_CB<0>")
	)
	(gr_poly
		(pts
			(xy 89.791032 -244.282468) (xy 89.791032 -244.238018) (xy 89.59088 -244.238018) (xy 89.59088 -244.282468)
			(xy 89.690956 -244.382544)
		)
		(stroke
			(width 0)
			(type solid)
		)
		(fill yes)
		(layer "In4.Cu")
		(net "M_D_CPU1_SA_DQ<31>")
	)
	(gr_poly
		(pts
			(xy 89.791032 -243.066316) (xy 89.690956 -242.96624) (xy 89.59088 -243.066316) (xy 89.59088 -243.110766)
			(xy 89.791032 -243.110766)
		)
		(stroke
			(width 0)
			(type solid)
		)
		(fill yes)
		(layer "In4.Cu")
		(net "M_D_CPU1_SA_DQ<28>")
	)
	(gr_poly
		(pts
			(xy 89.791032 -242.66271) (xy 89.791032 -242.614958) (xy 89.59088 -242.614958) (xy 89.59088 -242.66271)
			(xy 89.690956 -242.762532)
		)
		(stroke
			(width 0)
			(type solid)
		)
		(fill yes)
		(layer "In4.Cu")
		(net "M_D_CPU1_SA_DQS_DP<8>")
	)
	(gr_poly
		(pts
			(xy 89.791032 -241.44605) (xy 89.690956 -241.346228) (xy 89.59088 -241.44605) (xy 89.59088 -241.493802)
			(xy 89.791032 -241.493802)
		)
		(stroke
			(width 0)
			(type solid)
		)
		(fill yes)
		(layer "In4.Cu")
		(net "M_D_CPU1_SA_DQS_DP<3>")
	)
	(gr_poly
		(pts
			(xy 89.791032 -241.042444) (xy 89.791032 -240.997994) (xy 89.59088 -240.997994) (xy 89.59088 -241.042444)
			(xy 89.690956 -241.14252)
		)
		(stroke
			(width 0)
			(type solid)
		)
		(fill yes)
		(layer "In4.Cu")
		(net "M_D_CPU1_SA_DQ<27>")
	)
	(gr_poly
		(pts
			(xy 89.791032 -239.826292) (xy 89.690956 -239.726216) (xy 89.59088 -239.826292) (xy 89.59088 -239.870742)
			(xy 89.791032 -239.870742)
		)
		(stroke
			(width 0)
			(type solid)
		)
		(fill yes)
		(layer "In4.Cu")
		(net "M_D_CPU1_SA_DQ<24>")
	)
	(gr_poly
		(pts
			(xy 89.791032 -239.422432) (xy 89.791032 -239.377982) (xy 89.59088 -239.377982) (xy 89.59088 -239.422432)
			(xy 89.690956 -239.522508)
		)
		(stroke
			(width 0)
			(type solid)
		)
		(fill yes)
		(layer "In4.Cu")
		(net "M_D_CPU1_SA_DQ<23>")
	)
	(gr_poly
		(pts
			(xy 89.791032 -238.20628) (xy 89.690956 -238.106204) (xy 89.59088 -238.20628) (xy 89.59088 -238.25073)
			(xy 89.791032 -238.25073)
		)
		(stroke
			(width 0)
			(type solid)
		)
		(fill yes)
		(layer "In4.Cu")
		(net "M_D_CPU1_SA_DQ<20>")
	)
	(gr_poly
		(pts
			(xy 89.791032 -237.802674) (xy 89.791032 -237.754922) (xy 89.59088 -237.754922) (xy 89.59088 -237.802674)
			(xy 89.690956 -237.902496)
		)
		(stroke
			(width 0)
			(type solid)
		)
		(fill yes)
		(layer "In4.Cu")
		(net "M_D_CPU1_SA_DQS_DP<7>")
	)
	(gr_poly
		(pts
			(xy 89.791032 -236.586014) (xy 89.690956 -236.486192) (xy 89.59088 -236.586014) (xy 89.59088 -236.633766)
			(xy 89.791032 -236.633766)
		)
		(stroke
			(width 0)
			(type solid)
		)
		(fill yes)
		(layer "In4.Cu")
		(net "M_D_CPU1_SA_DQS_DP<2>")
	)
	(gr_poly
		(pts
			(xy 89.791032 -236.182408) (xy 89.791032 -236.137958) (xy 89.59088 -236.137958) (xy 89.59088 -236.182408)
			(xy 89.690956 -236.282484)
		)
		(stroke
			(width 0)
			(type solid)
		)
		(fill yes)
		(layer "In4.Cu")
		(net "M_D_CPU1_SA_DQ<19>")
	)
	(gr_poly
		(pts
			(xy 89.791032 -234.966256) (xy 89.690956 -234.86618) (xy 89.59088 -234.966256) (xy 89.59088 -235.010706)
			(xy 89.791032 -235.010706)
		)
		(stroke
			(width 0)
			(type solid)
		)
		(fill yes)
		(layer "In4.Cu")
		(net "M_D_CPU1_SA_DQ<16>")
	)
	(gr_poly
		(pts
			(xy 89.791032 -234.562396) (xy 89.791032 -234.517946) (xy 89.59088 -234.517946) (xy 89.59088 -234.562396)
			(xy 89.690956 -234.662472)
		)
		(stroke
			(width 0)
			(type solid)
		)
		(fill yes)
		(layer "In4.Cu")
		(net "M_D_CPU1_SA_DQ<15>")
	)
	(gr_poly
		(pts
			(xy 89.791032 -233.346244) (xy 89.690956 -233.246168) (xy 89.59088 -233.346244) (xy 89.59088 -233.390694)
			(xy 89.791032 -233.390694)
		)
		(stroke
			(width 0)
			(type solid)
		)
		(fill yes)
		(layer "In4.Cu")
		(net "M_D_CPU1_SA_DQ<12>")
	)
	(gr_poly
		(pts
			(xy 89.791032 -232.942638) (xy 89.791032 -232.894886) (xy 89.59088 -232.894886) (xy 89.59088 -232.942638)
			(xy 89.690956 -233.04246)
		)
		(stroke
			(width 0)
			(type solid)
		)
		(fill yes)
		(layer "In4.Cu")
		(net "M_D_CPU1_SA_DQS_DP<6>")
	)
	(gr_poly
		(pts
			(xy 89.791032 -231.725978) (xy 89.690956 -231.626156) (xy 89.59088 -231.725978) (xy 89.59088 -231.77373)
			(xy 89.791032 -231.77373)
		)
		(stroke
			(width 0)
			(type solid)
		)
		(fill yes)
		(layer "In4.Cu")
		(net "M_D_CPU1_SA_DQS_DP<1>")
	)
	(gr_poly
		(pts
			(xy 89.791032 -231.322626) (xy 89.791032 -231.278176) (xy 89.59088 -231.278176) (xy 89.59088 -231.322626)
			(xy 89.690956 -231.422702)
		)
		(stroke
			(width 0)
			(type solid)
		)
		(fill yes)
		(layer "In4.Cu")
		(net "M_D_CPU1_SA_DQ<11>")
	)
	(gr_poly
		(pts
			(xy 89.791032 -230.10622) (xy 89.690956 -230.006144) (xy 89.59088 -230.10622) (xy 89.59088 -230.15067)
			(xy 89.791032 -230.15067)
		)
		(stroke
			(width 0)
			(type solid)
		)
		(fill yes)
		(layer "In4.Cu")
		(net "M_D_CPU1_SA_DQ<8>")
	)
	(gr_poly
		(pts
			(xy 89.791032 -229.702614) (xy 89.791032 -229.658164) (xy 89.59088 -229.658164) (xy 89.59088 -229.702614)
			(xy 89.690956 -229.80269)
		)
		(stroke
			(width 0)
			(type solid)
		)
		(fill yes)
		(layer "In4.Cu")
		(net "M_D_CPU1_SA_DQ<7>")
	)
	(gr_poly
		(pts
			(xy 89.791032 -228.486462) (xy 89.690956 -228.386386) (xy 89.59088 -228.486462) (xy 89.59088 -228.530912)
			(xy 89.791032 -228.530912)
		)
		(stroke
			(width 0)
			(type solid)
		)
		(fill yes)
		(layer "In4.Cu")
		(net "M_D_CPU1_SA_DQ<4>")
	)
	(gr_poly
		(pts
			(xy 89.791032 -228.082856) (xy 89.791032 -228.035104) (xy 89.59088 -228.035104) (xy 89.59088 -228.082856)
			(xy 89.690956 -228.182678)
		)
		(stroke
			(width 0)
			(type solid)
		)
		(fill yes)
		(layer "In4.Cu")
		(net "M_D_CPU1_SA_DQS_DP<5>")
	)
	(gr_poly
		(pts
			(xy 89.791032 -226.866196) (xy 89.690956 -226.766374) (xy 89.59088 -226.866196) (xy 89.59088 -226.913948)
			(xy 89.791032 -226.913948)
		)
		(stroke
			(width 0)
			(type solid)
		)
		(fill yes)
		(layer "In4.Cu")
		(net "M_D_CPU1_SA_DQS_DP<0>")
	)
	(gr_poly
		(pts
			(xy 89.791032 -226.46259) (xy 89.791032 -226.41814) (xy 89.59088 -226.41814) (xy 89.59088 -226.46259)
			(xy 89.690956 -226.562666)
		)
		(stroke
			(width 0)
			(type solid)
		)
		(fill yes)
		(layer "In4.Cu")
		(net "M_D_CPU1_SA_DQ<3>")
	)
	(gr_poly
		(pts
			(xy 89.791032 -225.246438) (xy 89.690956 -225.146362) (xy 89.59088 -225.246438) (xy 89.59088 -225.290888)
			(xy 89.791032 -225.290888)
		)
		(stroke
			(width 0)
			(type solid)
		)
		(fill yes)
		(layer "In4.Cu")
		(net "M_D_CPU1_SA_DQ<0>")
	)
	(gr_poly
		(pts
			(xy 90.091006 -292.918134) (xy 89.99093 -292.818058) (xy 89.890854 -292.918134) (xy 89.890854 -292.962584)
			(xy 90.091006 -292.962584)
		)
		(stroke
			(width 0)
			(type solid)
		)
		(fill yes)
		(layer "In4.Cu")
		(net "M_D_CPU1_SB_DQ<29>")
	)
	(gr_poly
		(pts
			(xy 90.091006 -292.514274) (xy 90.091006 -292.469824) (xy 89.890854 -292.469824) (xy 89.890854 -292.514274)
			(xy 89.99093 -292.61435)
		)
		(stroke
			(width 0)
			(type solid)
		)
		(fill yes)
		(layer "In4.Cu")
		(net "M_D_CPU1_SB_DQ<30>")
	)
	(gr_poly
		(pts
			(xy 90.091006 -291.297868) (xy 89.99093 -291.198046) (xy 89.890854 -291.297868) (xy 89.890854 -291.34562)
			(xy 90.091006 -291.34562)
		)
		(stroke
			(width 0)
			(type solid)
		)
		(fill yes)
		(layer "In4.Cu")
		(net "M_D_CPU1_SB_DQS_DN<8>")
	)
	(gr_poly
		(pts
			(xy 90.091006 -290.894516) (xy 90.091006 -290.846764) (xy 89.890854 -290.846764) (xy 89.890854 -290.894516)
			(xy 89.99093 -290.994338)
		)
		(stroke
			(width 0)
			(type solid)
		)
		(fill yes)
		(layer "In4.Cu")
		(net "M_D_CPU1_SB_DQS_DN<3>")
	)
	(gr_poly
		(pts
			(xy 90.091006 -289.67811) (xy 89.99093 -289.578034) (xy 89.890854 -289.67811) (xy 89.890854 -289.72256)
			(xy 90.091006 -289.72256)
		)
		(stroke
			(width 0)
			(type solid)
		)
		(fill yes)
		(layer "In4.Cu")
		(net "M_D_CPU1_SB_DQ<25>")
	)
	(gr_poly
		(pts
			(xy 90.091006 -289.27425) (xy 90.091006 -289.2298) (xy 89.890854 -289.2298) (xy 89.890854 -289.27425)
			(xy 89.99093 -289.374326)
		)
		(stroke
			(width 0)
			(type solid)
		)
		(fill yes)
		(layer "In4.Cu")
		(net "M_D_CPU1_SB_DQ<26>")
	)
	(gr_poly
		(pts
			(xy 90.091006 -288.058098) (xy 89.99093 -287.958022) (xy 89.890854 -288.058098) (xy 89.890854 -288.102548)
			(xy 90.091006 -288.102548)
		)
		(stroke
			(width 0)
			(type solid)
		)
		(fill yes)
		(layer "In4.Cu")
		(net "M_D_CPU1_SB_DQ<21>")
	)
	(gr_poly
		(pts
			(xy 90.091006 -287.654492) (xy 90.091006 -287.610042) (xy 89.890854 -287.610042) (xy 89.890854 -287.654492)
			(xy 89.99093 -287.754568)
		)
		(stroke
			(width 0)
			(type solid)
		)
		(fill yes)
		(layer "In4.Cu")
		(net "M_D_CPU1_SB_DQ<22>")
	)
	(gr_poly
		(pts
			(xy 90.091006 -286.438086) (xy 89.99093 -286.33801) (xy 89.890854 -286.438086) (xy 89.890854 -286.485838)
			(xy 90.091006 -286.485838)
		)
		(stroke
			(width 0)
			(type solid)
		)
		(fill yes)
		(layer "In4.Cu")
		(net "M_D_CPU1_SB_DQS_DN<7>")
	)
	(gr_poly
		(pts
			(xy 90.091006 -286.034734) (xy 90.091006 -285.986982) (xy 89.890854 -285.986982) (xy 89.890854 -286.034734)
			(xy 89.99093 -286.134556)
		)
		(stroke
			(width 0)
			(type solid)
		)
		(fill yes)
		(layer "In4.Cu")
		(net "M_D_CPU1_SB_DQS_DN<2>")
	)
	(gr_poly
		(pts
			(xy 90.091006 -284.818328) (xy 89.99093 -284.718252) (xy 89.890854 -284.818328) (xy 89.890854 -284.862778)
			(xy 90.091006 -284.862778)
		)
		(stroke
			(width 0)
			(type solid)
		)
		(fill yes)
		(layer "In4.Cu")
		(net "M_D_CPU1_SB_DQ<17>")
	)
	(gr_poly
		(pts
			(xy 90.091006 -284.414468) (xy 90.091006 -284.370018) (xy 89.890854 -284.370018) (xy 89.890854 -284.414468)
			(xy 89.99093 -284.514544)
		)
		(stroke
			(width 0)
			(type solid)
		)
		(fill yes)
		(layer "In4.Cu")
		(net "M_D_CPU1_SB_DQ<18>")
	)
	(gr_poly
		(pts
			(xy 90.091006 -283.198316) (xy 89.99093 -283.09824) (xy 89.890854 -283.198316) (xy 89.890854 -283.242766)
			(xy 90.091006 -283.242766)
		)
		(stroke
			(width 0)
			(type solid)
		)
		(fill yes)
		(layer "In4.Cu")
		(net "M_D_CPU1_SB_DQ<13>")
	)
	(gr_poly
		(pts
			(xy 90.091006 -282.794456) (xy 90.091006 -282.750006) (xy 89.890854 -282.750006) (xy 89.890854 -282.794456)
			(xy 89.99093 -282.894532)
		)
		(stroke
			(width 0)
			(type solid)
		)
		(fill yes)
		(layer "In4.Cu")
		(net "M_D_CPU1_SB_DQ<14>")
	)
	(gr_poly
		(pts
			(xy 90.091006 -281.57805) (xy 89.99093 -281.478228) (xy 89.890854 -281.57805) (xy 89.890854 -281.625802)
			(xy 90.091006 -281.625802)
		)
		(stroke
			(width 0)
			(type solid)
		)
		(fill yes)
		(layer "In4.Cu")
		(net "M_D_CPU1_SB_DQS_DN<6>")
	)
	(gr_poly
		(pts
			(xy 90.091006 -281.174698) (xy 90.091006 -281.126946) (xy 89.890854 -281.126946) (xy 89.890854 -281.174698)
			(xy 89.99093 -281.27452)
		)
		(stroke
			(width 0)
			(type solid)
		)
		(fill yes)
		(layer "In4.Cu")
		(net "M_D_CPU1_SB_DQS_DN<1>")
	)
	(gr_poly
		(pts
			(xy 90.091006 -279.958292) (xy 89.99093 -279.858216) (xy 89.890854 -279.958292) (xy 89.890854 -280.002742)
			(xy 90.091006 -280.002742)
		)
		(stroke
			(width 0)
			(type solid)
		)
		(fill yes)
		(layer "In4.Cu")
		(net "M_D_CPU1_SB_DQ<9>")
	)
	(gr_poly
		(pts
			(xy 90.091006 -279.554432) (xy 90.091006 -279.509982) (xy 89.890854 -279.509982) (xy 89.890854 -279.554432)
			(xy 89.99093 -279.654508)
		)
		(stroke
			(width 0)
			(type solid)
		)
		(fill yes)
		(layer "In4.Cu")
		(net "M_D_CPU1_SB_DQ<10>")
	)
	(gr_poly
		(pts
			(xy 90.091006 -278.33828) (xy 89.99093 -278.238204) (xy 89.890854 -278.33828) (xy 89.890854 -278.38273)
			(xy 90.091006 -278.38273)
		)
		(stroke
			(width 0)
			(type solid)
		)
		(fill yes)
		(layer "In4.Cu")
		(net "M_D_CPU1_SB_DQ<5>")
	)
	(gr_poly
		(pts
			(xy 90.091006 -277.93442) (xy 90.091006 -277.88997) (xy 89.890854 -277.88997) (xy 89.890854 -277.93442)
			(xy 89.99093 -278.034496)
		)
		(stroke
			(width 0)
			(type solid)
		)
		(fill yes)
		(layer "In4.Cu")
		(net "M_D_CPU1_SB_DQ<6>")
	)
	(gr_poly
		(pts
			(xy 90.091006 -275.098256) (xy 89.99093 -274.99818) (xy 89.890854 -275.098256) (xy 89.890854 -275.142706)
			(xy 90.091006 -275.142706)
		)
		(stroke
			(width 0)
			(type solid)
		)
		(fill yes)
		(layer "In4.Cu")
		(net "M_D_CPU1_SB_DQ<1>")
	)
	(gr_poly
		(pts
			(xy 90.091006 -274.694396) (xy 90.091006 -274.649946) (xy 89.890854 -274.649946) (xy 89.890854 -274.694396)
			(xy 89.99093 -274.794472)
		)
		(stroke
			(width 0)
			(type solid)
		)
		(fill yes)
		(layer "In4.Cu")
		(net "M_D_CPU1_SB_DQ<2>")
	)
	(gr_poly
		(pts
			(xy 90.091006 -273.478244) (xy 89.99093 -273.378168) (xy 89.890854 -273.478244) (xy 89.890854 -273.522694)
			(xy 90.091006 -273.522694)
		)
		(stroke
			(width 0)
			(type solid)
		)
		(fill yes)
		(layer "In4.Cu")
		(net "M_D_CPU1_SB_CB<1>")
	)
	(gr_poly
		(pts
			(xy 90.091006 -273.074384) (xy 90.091006 -273.029934) (xy 89.890854 -273.029934) (xy 89.890854 -273.074384)
			(xy 89.99093 -273.17446)
		)
		(stroke
			(width 0)
			(type solid)
		)
		(fill yes)
		(layer "In4.Cu")
		(net "M_D_CPU1_SB_CB<2>")
	)
	(gr_poly
		(pts
			(xy 90.091006 -271.857978) (xy 89.99093 -271.758156) (xy 89.890854 -271.857978) (xy 89.890854 -271.90573)
			(xy 90.091006 -271.90573)
		)
		(stroke
			(width 0)
			(type solid)
		)
		(fill yes)
		(layer "In4.Cu")
		(net "M_D_CPU1_SB_DQS_DN<4>")
	)
	(gr_poly
		(pts
			(xy 90.091006 -271.454626) (xy 90.091006 -271.406874) (xy 89.890854 -271.406874) (xy 89.890854 -271.454626)
			(xy 89.99093 -271.554448)
		)
		(stroke
			(width 0)
			(type solid)
		)
		(fill yes)
		(layer "In4.Cu")
		(net "M_D_CPU1_SB_DQS_DN<9>")
	)
	(gr_poly
		(pts
			(xy 90.091006 -270.23822) (xy 89.99093 -270.138144) (xy 89.890854 -270.23822) (xy 89.890854 -270.28267)
			(xy 90.091006 -270.28267)
		)
		(stroke
			(width 0)
			(type solid)
		)
		(fill yes)
		(layer "In4.Cu")
		(net "M_D_CPU1_SB_CB<5>")
	)
	(gr_poly
		(pts
			(xy 90.091006 -269.83436) (xy 90.091006 -269.78991) (xy 89.890854 -269.78991) (xy 89.890854 -269.83436)
			(xy 89.99093 -269.934436)
		)
		(stroke
			(width 0)
			(type solid)
		)
		(fill yes)
		(layer "In4.Cu")
		(net "M_D_CPU1_SB_CB<6>")
	)
	(gr_poly
		(pts
			(xy 90.091006 -266.594336) (xy 90.091006 -266.549886) (xy 89.890854 -266.549886) (xy 89.890854 -266.594336)
			(xy 89.99093 -266.694412)
		)
		(stroke
			(width 0)
			(type solid)
		)
		(fill yes)
		(layer "In4.Cu")
		(net "M_D_CPU1_SB_CS_N<1>")
	)
	(gr_poly
		(pts
			(xy 90.091006 -264.974324) (xy 90.091006 -264.929874) (xy 89.890854 -264.929874) (xy 89.890854 -264.974324)
			(xy 89.99093 -265.0744)
		)
		(stroke
			(width 0)
			(type solid)
		)
		(fill yes)
		(layer "In4.Cu")
		(net "M_D_CPU1_SB_PAR")
	)
	(gr_poly
		(pts
			(xy 90.091006 -263.758172) (xy 89.99093 -263.658096) (xy 89.890854 -263.758172) (xy 89.890854 -263.802622)
			(xy 90.091006 -263.802622)
		)
		(stroke
			(width 0)
			(type solid)
		)
		(fill yes)
		(layer "In4.Cu")
		(net "M_D_CPU1_SB_CA<4>")
	)
	(gr_poly
		(pts
			(xy 90.091006 -263.354312) (xy 90.091006 -263.309862) (xy 89.890854 -263.309862) (xy 89.890854 -263.354312)
			(xy 89.99093 -263.454388)
		)
		(stroke
			(width 0)
			(type solid)
		)
		(fill yes)
		(layer "In4.Cu")
		(net "M_D_CPU1_SB_CA<3>")
	)
	(gr_poly
		(pts
			(xy 90.091006 -262.13816) (xy 89.99093 -262.038084) (xy 89.890854 -262.13816) (xy 89.890854 -262.18261)
			(xy 90.091006 -262.18261)
		)
		(stroke
			(width 0)
			(type solid)
		)
		(fill yes)
		(layer "In4.Cu")
		(net "M_D_CPU1_SB_CA<0>")
	)
	(gr_poly
		(pts
			(xy 90.097102 -266.991846) (xy 89.99728 -266.89177) (xy 89.897204 -266.991846) (xy 89.897204 -267.036296)
			(xy 90.097102 -267.036296)
		)
		(stroke
			(width 0)
			(type solid)
		)
		(fill yes)
		(layer "In4.Cu")
		(net "M_D_CPU1_SA_RSP<0>")
	)
	(gr_poly
		(pts
			(xy 90.098118 -276.718268) (xy 89.998296 -276.618192) (xy 89.89822 -276.718268) (xy 89.89822 -276.765766)
			(xy 90.098118 -276.765766)
		)
		(stroke
			(width 0)
			(type solid)
		)
		(fill yes)
		(layer "In4.Cu")
		(net "M_D_CPU1_SB_DQS_DN<5>")
	)
	(gr_poly
		(pts
			(xy 90.098118 -276.314408) (xy 90.098118 -276.26691) (xy 89.89822 -276.26691) (xy 89.89822 -276.314408)
			(xy 89.998296 -276.414484)
		)
		(stroke
			(width 0)
			(type solid)
		)
		(fill yes)
		(layer "In4.Cu")
		(net "M_D_CPU1_SB_DQS_DN<0>")
	)
	(gr_poly
		(pts
			(xy 90.25509 -227.67671) (xy 90.155014 -227.576634) (xy 90.054938 -227.67671) (xy 90.054938 -227.724208)
			(xy 90.25509 -227.724208)
		)
		(stroke
			(width 0)
			(type solid)
		)
		(fill yes)
		(layer "In4.Cu")
		(net "M_D_CPU1_SA_DQS_DN<5>")
	)
	(gr_poly
		(pts
			(xy 90.261186 -256.432812) (xy 90.261186 -256.38506) (xy 90.061034 -256.38506) (xy 90.061034 -256.432812)
			(xy 90.16111 -256.532634)
		)
		(stroke
			(width 0)
			(type solid)
		)
		(fill yes)
		(layer "In4.Cu")
		(net "M_D_CPU1_CLK_DN<0>")
	)
	(gr_poly
		(pts
			(xy 90.261186 -255.216406) (xy 90.16111 -255.11633) (xy 90.061034 -255.216406) (xy 90.061034 -255.260856)
			(xy 90.261186 -255.260856)
		)
		(stroke
			(width 0)
			(type solid)
		)
		(fill yes)
		(layer "In4.Cu")
		(net "M_D_CPU1_SA_CA<6>")
	)
	(gr_poly
		(pts
			(xy 90.261186 -254.812546) (xy 90.261186 -254.768096) (xy 90.061034 -254.768096) (xy 90.061034 -254.812546)
			(xy 90.16111 -254.912622)
		)
		(stroke
			(width 0)
			(type solid)
		)
		(fill yes)
		(layer "In4.Cu")
		(net "M_D_CPU1_SA_CA<5>")
	)
	(gr_poly
		(pts
			(xy 90.261186 -253.596394) (xy 90.16111 -253.496318) (xy 90.061034 -253.596394) (xy 90.061034 -253.640844)
			(xy 90.261186 -253.640844)
		)
		(stroke
			(width 0)
			(type solid)
		)
		(fill yes)
		(layer "In4.Cu")
		(net "M_D_CPU1_SA_CA<2>")
	)
	(gr_poly
		(pts
			(xy 90.261186 -253.192534) (xy 90.261186 -253.148084) (xy 90.061034 -253.148084) (xy 90.061034 -253.192534)
			(xy 90.16111 -253.29261)
		)
		(stroke
			(width 0)
			(type solid)
		)
		(fill yes)
		(layer "In4.Cu")
		(net "M_D_CPU1_SA_CA<1>")
	)
	(gr_poly
		(pts
			(xy 90.261186 -251.572522) (xy 90.261186 -251.528072) (xy 90.061034 -251.528072) (xy 90.061034 -251.572522)
			(xy 90.16111 -251.672598)
		)
		(stroke
			(width 0)
			(type solid)
		)
		(fill yes)
		(layer "In4.Cu")
		(net "M_D_CPU1_SA_CS_N<0>")
	)
	(gr_poly
		(pts
			(xy 90.261186 -250.35637) (xy 90.16111 -250.256294) (xy 90.061034 -250.35637) (xy 90.061034 -250.40082)
			(xy 90.261186 -250.40082)
		)
		(stroke
			(width 0)
			(type solid)
		)
		(fill yes)
		(layer "In4.Cu")
		(net "M_D_CPU1_ALERT_R_N")
	)
	(gr_poly
		(pts
			(xy 90.261186 -248.736358) (xy 90.16111 -248.636282) (xy 90.061034 -248.736358) (xy 90.061034 -248.780808)
			(xy 90.261186 -248.780808)
		)
		(stroke
			(width 0)
			(type solid)
		)
		(fill yes)
		(layer "In4.Cu")
		(net "M_D_CPU1_SA_CB<5>")
	)
	(gr_poly
		(pts
			(xy 90.261186 -248.332498) (xy 90.261186 -248.288048) (xy 90.061034 -248.288048) (xy 90.061034 -248.332498)
			(xy 90.16111 -248.432574)
		)
		(stroke
			(width 0)
			(type solid)
		)
		(fill yes)
		(layer "In4.Cu")
		(net "M_D_CPU1_SA_CB<6>")
	)
	(gr_poly
		(pts
			(xy 90.261186 -247.116092) (xy 90.16111 -247.01627) (xy 90.061034 -247.116092) (xy 90.061034 -247.163844)
			(xy 90.261186 -247.163844)
		)
		(stroke
			(width 0)
			(type solid)
		)
		(fill yes)
		(layer "In4.Cu")
		(net "M_D_CPU1_SA_DQS_DN<9>")
	)
	(gr_poly
		(pts
			(xy 90.261186 -246.71274) (xy 90.261186 -246.664988) (xy 90.061034 -246.664988) (xy 90.061034 -246.71274)
			(xy 90.16111 -246.812562)
		)
		(stroke
			(width 0)
			(type solid)
		)
		(fill yes)
		(layer "In4.Cu")
		(net "M_D_CPU1_SA_DQS_DN<4>")
	)
	(gr_poly
		(pts
			(xy 90.261186 -245.496334) (xy 90.16111 -245.396258) (xy 90.061034 -245.496334) (xy 90.061034 -245.540784)
			(xy 90.261186 -245.540784)
		)
		(stroke
			(width 0)
			(type solid)
		)
		(fill yes)
		(layer "In4.Cu")
		(net "M_D_CPU1_SA_CB<1>")
	)
	(gr_poly
		(pts
			(xy 90.261186 -245.092474) (xy 90.261186 -245.048024) (xy 90.061034 -245.048024) (xy 90.061034 -245.092474)
			(xy 90.16111 -245.19255)
		)
		(stroke
			(width 0)
			(type solid)
		)
		(fill yes)
		(layer "In4.Cu")
		(net "M_D_CPU1_SA_CB<2>")
	)
	(gr_poly
		(pts
			(xy 90.261186 -243.876322) (xy 90.16111 -243.776246) (xy 90.061034 -243.876322) (xy 90.061034 -243.920772)
			(xy 90.261186 -243.920772)
		)
		(stroke
			(width 0)
			(type solid)
		)
		(fill yes)
		(layer "In4.Cu")
		(net "M_D_CPU1_SA_DQ<29>")
	)
	(gr_poly
		(pts
			(xy 90.261186 -243.472462) (xy 90.261186 -243.428012) (xy 90.061034 -243.428012) (xy 90.061034 -243.472462)
			(xy 90.16111 -243.572538)
		)
		(stroke
			(width 0)
			(type solid)
		)
		(fill yes)
		(layer "In4.Cu")
		(net "M_D_CPU1_SA_DQ<30>")
	)
	(gr_poly
		(pts
			(xy 90.261186 -242.256056) (xy 90.16111 -242.156234) (xy 90.061034 -242.256056) (xy 90.061034 -242.303808)
			(xy 90.261186 -242.303808)
		)
		(stroke
			(width 0)
			(type solid)
		)
		(fill yes)
		(layer "In4.Cu")
		(net "M_D_CPU1_SA_DQS_DN<8>")
	)
	(gr_poly
		(pts
			(xy 90.261186 -241.852704) (xy 90.261186 -241.804952) (xy 90.061034 -241.804952) (xy 90.061034 -241.852704)
			(xy 90.16111 -241.952526)
		)
		(stroke
			(width 0)
			(type solid)
		)
		(fill yes)
		(layer "In4.Cu")
		(net "M_D_CPU1_SA_DQS_DN<3>")
	)
	(gr_poly
		(pts
			(xy 90.261186 -240.636298) (xy 90.16111 -240.536222) (xy 90.061034 -240.636298) (xy 90.061034 -240.680748)
			(xy 90.261186 -240.680748)
		)
		(stroke
			(width 0)
			(type solid)
		)
		(fill yes)
		(layer "In4.Cu")
		(net "M_D_CPU1_SA_DQ<25>")
	)
	(gr_poly
		(pts
			(xy 90.261186 -240.232438) (xy 90.261186 -240.187988) (xy 90.061034 -240.187988) (xy 90.061034 -240.232438)
			(xy 90.16111 -240.332514)
		)
		(stroke
			(width 0)
			(type solid)
		)
		(fill yes)
		(layer "In4.Cu")
		(net "M_D_CPU1_SA_DQ<26>")
	)
	(gr_poly
		(pts
			(xy 90.261186 -239.016286) (xy 90.16111 -238.91621) (xy 90.061034 -239.016286) (xy 90.061034 -239.060736)
			(xy 90.261186 -239.060736)
		)
		(stroke
			(width 0)
			(type solid)
		)
		(fill yes)
		(layer "In4.Cu")
		(net "M_D_CPU1_SA_DQ<21>")
	)
	(gr_poly
		(pts
			(xy 90.261186 -238.612426) (xy 90.261186 -238.567976) (xy 90.061034 -238.567976) (xy 90.061034 -238.612426)
			(xy 90.16111 -238.712502)
		)
		(stroke
			(width 0)
			(type solid)
		)
		(fill yes)
		(layer "In4.Cu")
		(net "M_D_CPU1_SA_DQ<22>")
	)
	(gr_poly
		(pts
			(xy 90.261186 -237.39602) (xy 90.16111 -237.296198) (xy 90.061034 -237.39602) (xy 90.061034 -237.443772)
			(xy 90.261186 -237.443772)
		)
		(stroke
			(width 0)
			(type solid)
		)
		(fill yes)
		(layer "In4.Cu")
		(net "M_D_CPU1_SA_DQS_DN<7>")
	)
	(gr_poly
		(pts
			(xy 90.261186 -236.992668) (xy 90.261186 -236.944916) (xy 90.061034 -236.944916) (xy 90.061034 -236.992668)
			(xy 90.16111 -237.09249)
		)
		(stroke
			(width 0)
			(type solid)
		)
		(fill yes)
		(layer "In4.Cu")
		(net "M_D_CPU1_SA_DQS_DN<2>")
	)
	(gr_poly
		(pts
			(xy 90.261186 -235.776262) (xy 90.16111 -235.676186) (xy 90.061034 -235.776262) (xy 90.061034 -235.820712)
			(xy 90.261186 -235.820712)
		)
		(stroke
			(width 0)
			(type solid)
		)
		(fill yes)
		(layer "In4.Cu")
		(net "M_D_CPU1_SA_DQ<17>")
	)
	(gr_poly
		(pts
			(xy 90.261186 -235.372402) (xy 90.261186 -235.327952) (xy 90.061034 -235.327952) (xy 90.061034 -235.372402)
			(xy 90.16111 -235.472478)
		)
		(stroke
			(width 0)
			(type solid)
		)
		(fill yes)
		(layer "In4.Cu")
		(net "M_D_CPU1_SA_DQ<18>")
	)
	(gr_poly
		(pts
			(xy 90.261186 -234.15625) (xy 90.16111 -234.056174) (xy 90.061034 -234.15625) (xy 90.061034 -234.2007)
			(xy 90.261186 -234.2007)
		)
		(stroke
			(width 0)
			(type solid)
		)
		(fill yes)
		(layer "In4.Cu")
		(net "M_D_CPU1_SA_DQ<13>")
	)
	(gr_poly
		(pts
			(xy 90.261186 -233.75239) (xy 90.261186 -233.70794) (xy 90.061034 -233.70794) (xy 90.061034 -233.75239)
			(xy 90.16111 -233.852466)
		)
		(stroke
			(width 0)
			(type solid)
		)
		(fill yes)
		(layer "In4.Cu")
		(net "M_D_CPU1_SA_DQ<14>")
	)
	(gr_poly
		(pts
			(xy 90.261186 -232.535984) (xy 90.16111 -232.436162) (xy 90.061034 -232.535984) (xy 90.061034 -232.583736)
			(xy 90.261186 -232.583736)
		)
		(stroke
			(width 0)
			(type solid)
		)
		(fill yes)
		(layer "In4.Cu")
		(net "M_D_CPU1_SA_DQS_DN<6>")
	)
	(gr_poly
		(pts
			(xy 90.261186 -232.132632) (xy 90.261186 -232.08488) (xy 90.061034 -232.08488) (xy 90.061034 -232.132632)
			(xy 90.16111 -232.232454)
		)
		(stroke
			(width 0)
			(type solid)
		)
		(fill yes)
		(layer "In4.Cu")
		(net "M_D_CPU1_SA_DQS_DN<1>")
	)
	(gr_poly
		(pts
			(xy 90.261186 -230.916226) (xy 90.16111 -230.81615) (xy 90.061034 -230.916226) (xy 90.061034 -230.960676)
			(xy 90.261186 -230.960676)
		)
		(stroke
			(width 0)
			(type solid)
		)
		(fill yes)
		(layer "In4.Cu")
		(net "M_D_CPU1_SA_DQ<9>")
	)
	(gr_poly
		(pts
			(xy 90.261186 -230.51262) (xy 90.261186 -230.46817) (xy 90.061034 -230.46817) (xy 90.061034 -230.51262)
			(xy 90.16111 -230.612696)
		)
		(stroke
			(width 0)
			(type solid)
		)
		(fill yes)
		(layer "In4.Cu")
		(net "M_D_CPU1_SA_DQ<10>")
	)
	(gr_poly
		(pts
			(xy 90.261186 -229.296214) (xy 90.16111 -229.196138) (xy 90.061034 -229.296214) (xy 90.061034 -229.340664)
			(xy 90.261186 -229.340664)
		)
		(stroke
			(width 0)
			(type solid)
		)
		(fill yes)
		(layer "In4.Cu")
		(net "M_D_CPU1_SA_DQ<5>")
	)
	(gr_poly
		(pts
			(xy 90.261186 -228.892608) (xy 90.261186 -228.848158) (xy 90.061034 -228.848158) (xy 90.061034 -228.892608)
			(xy 90.16111 -228.992684)
		)
		(stroke
			(width 0)
			(type solid)
		)
		(fill yes)
		(layer "In4.Cu")
		(net "M_D_CPU1_SA_DQ<6>")
	)
	(gr_poly
		(pts
			(xy 90.261186 -227.27285) (xy 90.261186 -227.225098) (xy 90.061034 -227.225098) (xy 90.061034 -227.27285)
			(xy 90.16111 -227.372672)
		)
		(stroke
			(width 0)
			(type solid)
		)
		(fill yes)
		(layer "In4.Cu")
		(net "M_D_CPU1_SA_DQS_DN<0>")
	)
	(gr_poly
		(pts
			(xy 90.261186 -226.056444) (xy 90.16111 -225.956368) (xy 90.061034 -226.056444) (xy 90.061034 -226.100894)
			(xy 90.261186 -226.100894)
		)
		(stroke
			(width 0)
			(type solid)
		)
		(fill yes)
		(layer "In4.Cu")
		(net "M_D_CPU1_SA_DQ<1>")
	)
	(gr_poly
		(pts
			(xy 90.261186 -225.652584) (xy 90.261186 -225.608134) (xy 90.061034 -225.608134) (xy 90.061034 -225.652584)
			(xy 90.16111 -225.75266)
		)
		(stroke
			(width 0)
			(type solid)
		)
		(fill yes)
		(layer "In4.Cu")
		(net "M_D_CPU1_SA_DQ<2>")
	)
	(gr_poly
		(pts
			(xy 90.521536 -293.3319) (xy 90.525346 -293.28745) (xy 90.32621 -293.270178) (xy 90.3224 -293.314374)
			(xy 90.413332 -293.422832)
		)
		(stroke
			(width 0)
			(type solid)
		)
		(fill yes)
		(layer "In4.Cu")
		(net "M_D_CPU1_SB_DQ<31>")
	)
	(gr_poly
		(pts
			(xy 90.55481 -267.801852) (xy 90.454734 -267.701776) (xy 90.354912 -267.801852) (xy 90.354912 -267.846302)
			(xy 90.55481 -267.846302)
		)
		(stroke
			(width 0)
			(type solid)
		)
		(fill yes)
		(layer "In4.Cu")
		(net "M_D_CPU1_SB_RSP<0>")
	)
	(gr_poly
		(pts
			(xy 90.56116 -292.108128) (xy 90.461084 -292.008052) (xy 90.361008 -292.108128) (xy 90.361008 -292.152578)
			(xy 90.56116 -292.152578)
		)
		(stroke
			(width 0)
			(type solid)
		)
		(fill yes)
		(layer "In4.Cu")
		(net "M_D_CPU1_SB_DQ<28>")
	)
	(gr_poly
		(pts
			(xy 90.56116 -291.704522) (xy 90.56116 -291.65677) (xy 90.361008 -291.65677) (xy 90.361008 -291.704522)
			(xy 90.461084 -291.804344)
		)
		(stroke
			(width 0)
			(type solid)
		)
		(fill yes)
		(layer "In4.Cu")
		(net "M_D_CPU1_SB_DQS_DP<8>")
	)
	(gr_poly
		(pts
			(xy 90.56116 -290.487862) (xy 90.461084 -290.38804) (xy 90.361008 -290.487862) (xy 90.361008 -290.535614)
			(xy 90.56116 -290.535614)
		)
		(stroke
			(width 0)
			(type solid)
		)
		(fill yes)
		(layer "In4.Cu")
		(net "M_D_CPU1_SB_DQS_DP<3>")
	)
	(gr_poly
		(pts
			(xy 90.56116 -290.084256) (xy 90.56116 -290.039806) (xy 90.361008 -290.039806) (xy 90.361008 -290.084256)
			(xy 90.461084 -290.184332)
		)
		(stroke
			(width 0)
			(type solid)
		)
		(fill yes)
		(layer "In4.Cu")
		(net "M_D_CPU1_SB_DQ<27>")
	)
	(gr_poly
		(pts
			(xy 90.56116 -288.868104) (xy 90.461084 -288.768028) (xy 90.361008 -288.868104) (xy 90.361008 -288.912554)
			(xy 90.56116 -288.912554)
		)
		(stroke
			(width 0)
			(type solid)
		)
		(fill yes)
		(layer "In4.Cu")
		(net "M_D_CPU1_SB_DQ<24>")
	)
	(gr_poly
		(pts
			(xy 90.56116 -288.464498) (xy 90.56116 -288.420048) (xy 90.361008 -288.420048) (xy 90.361008 -288.464498)
			(xy 90.461084 -288.564574)
		)
		(stroke
			(width 0)
			(type solid)
		)
		(fill yes)
		(layer "In4.Cu")
		(net "M_D_CPU1_SB_DQ<23>")
	)
	(gr_poly
		(pts
			(xy 90.56116 -287.248092) (xy 90.461084 -287.148016) (xy 90.361008 -287.248092) (xy 90.361008 -287.292542)
			(xy 90.56116 -287.292542)
		)
		(stroke
			(width 0)
			(type solid)
		)
		(fill yes)
		(layer "In4.Cu")
		(net "M_D_CPU1_SB_DQ<20>")
	)
	(gr_poly
		(pts
			(xy 90.56116 -286.844486) (xy 90.56116 -286.796734) (xy 90.361008 -286.796734) (xy 90.361008 -286.844486)
			(xy 90.461084 -286.944562)
		)
		(stroke
			(width 0)
			(type solid)
		)
		(fill yes)
		(layer "In4.Cu")
		(net "M_D_CPU1_SB_DQS_DP<7>")
	)
	(gr_poly
		(pts
			(xy 90.56116 -285.62808) (xy 90.461084 -285.528258) (xy 90.361008 -285.62808) (xy 90.361008 -285.675832)
			(xy 90.56116 -285.675832)
		)
		(stroke
			(width 0)
			(type solid)
		)
		(fill yes)
		(layer "In4.Cu")
		(net "M_D_CPU1_SB_DQS_DP<2>")
	)
	(gr_poly
		(pts
			(xy 90.56116 -285.224474) (xy 90.56116 -285.180024) (xy 90.361008 -285.180024) (xy 90.361008 -285.224474)
			(xy 90.461084 -285.32455)
		)
		(stroke
			(width 0)
			(type solid)
		)
		(fill yes)
		(layer "In4.Cu")
		(net "M_D_CPU1_SB_DQ<19>")
	)
	(gr_poly
		(pts
			(xy 90.56116 -284.008322) (xy 90.461084 -283.908246) (xy 90.361008 -284.008322) (xy 90.361008 -284.052772)
			(xy 90.56116 -284.052772)
		)
		(stroke
			(width 0)
			(type solid)
		)
		(fill yes)
		(layer "In4.Cu")
		(net "M_D_CPU1_SB_DQ<16>")
	)
	(gr_poly
		(pts
			(xy 90.56116 -283.604462) (xy 90.56116 -283.560012) (xy 90.361008 -283.560012) (xy 90.361008 -283.604462)
			(xy 90.461084 -283.704538)
		)
		(stroke
			(width 0)
			(type solid)
		)
		(fill yes)
		(layer "In4.Cu")
		(net "M_D_CPU1_SB_DQ<15>")
	)
	(gr_poly
		(pts
			(xy 90.56116 -282.38831) (xy 90.461084 -282.288234) (xy 90.361008 -282.38831) (xy 90.361008 -282.43276)
			(xy 90.56116 -282.43276)
		)
		(stroke
			(width 0)
			(type solid)
		)
		(fill yes)
		(layer "In4.Cu")
		(net "M_D_CPU1_SB_DQ<12>")
	)
	(gr_poly
		(pts
			(xy 90.56116 -281.984704) (xy 90.56116 -281.936952) (xy 90.361008 -281.936952) (xy 90.361008 -281.984704)
			(xy 90.461084 -282.084526)
		)
		(stroke
			(width 0)
			(type solid)
		)
		(fill yes)
		(layer "In4.Cu")
		(net "M_D_CPU1_SB_DQS_DP<6>")
	)
	(gr_poly
		(pts
			(xy 90.56116 -280.768044) (xy 90.461084 -280.668222) (xy 90.361008 -280.768044) (xy 90.361008 -280.815796)
			(xy 90.56116 -280.815796)
		)
		(stroke
			(width 0)
			(type solid)
		)
		(fill yes)
		(layer "In4.Cu")
		(net "M_D_CPU1_SB_DQS_DP<1>")
	)
	(gr_poly
		(pts
			(xy 90.56116 -280.364438) (xy 90.56116 -280.319988) (xy 90.361008 -280.319988) (xy 90.361008 -280.364438)
			(xy 90.461084 -280.464514)
		)
		(stroke
			(width 0)
			(type solid)
		)
		(fill yes)
		(layer "In4.Cu")
		(net "M_D_CPU1_SB_DQ<11>")
	)
	(gr_poly
		(pts
			(xy 90.56116 -279.148286) (xy 90.461084 -279.04821) (xy 90.361008 -279.148286) (xy 90.361008 -279.192736)
			(xy 90.56116 -279.192736)
		)
		(stroke
			(width 0)
			(type solid)
		)
		(fill yes)
		(layer "In4.Cu")
		(net "M_D_CPU1_SB_DQ<8>")
	)
	(gr_poly
		(pts
			(xy 90.56116 -278.744426) (xy 90.56116 -278.699976) (xy 90.361008 -278.699976) (xy 90.361008 -278.744426)
			(xy 90.461084 -278.844502)
		)
		(stroke
			(width 0)
			(type solid)
		)
		(fill yes)
		(layer "In4.Cu")
		(net "M_D_CPU1_SB_DQ<7>")
	)
	(gr_poly
		(pts
			(xy 90.56116 -277.528274) (xy 90.461084 -277.428198) (xy 90.361008 -277.528274) (xy 90.361008 -277.572724)
			(xy 90.56116 -277.572724)
		)
		(stroke
			(width 0)
			(type solid)
		)
		(fill yes)
		(layer "In4.Cu")
		(net "M_D_CPU1_SB_DQ<4>")
	)
	(gr_poly
		(pts
			(xy 90.56116 -277.124668) (xy 90.56116 -277.076916) (xy 90.361008 -277.076916) (xy 90.361008 -277.124668)
			(xy 90.461084 -277.22449)
		)
		(stroke
			(width 0)
			(type solid)
		)
		(fill yes)
		(layer "In4.Cu")
		(net "M_D_CPU1_SB_DQS_DP<5>")
	)
	(gr_poly
		(pts
			(xy 90.56116 -275.908008) (xy 90.461084 -275.808186) (xy 90.361008 -275.908008) (xy 90.361008 -275.95576)
			(xy 90.56116 -275.95576)
		)
		(stroke
			(width 0)
			(type solid)
		)
		(fill yes)
		(layer "In4.Cu")
		(net "M_D_CPU1_SB_DQS_DP<0>")
	)
	(gr_poly
		(pts
			(xy 90.56116 -275.504402) (xy 90.56116 -275.459952) (xy 90.361008 -275.459952) (xy 90.361008 -275.504402)
			(xy 90.461084 -275.604478)
		)
		(stroke
			(width 0)
			(type solid)
		)
		(fill yes)
		(layer "In4.Cu")
		(net "M_D_CPU1_SB_DQ<3>")
	)
	(gr_poly
		(pts
			(xy 90.56116 -274.28825) (xy 90.461084 -274.188174) (xy 90.361008 -274.28825) (xy 90.361008 -274.3327)
			(xy 90.56116 -274.3327)
		)
		(stroke
			(width 0)
			(type solid)
		)
		(fill yes)
		(layer "In4.Cu")
		(net "M_D_CPU1_SB_DQ<0>")
	)
	(gr_poly
		(pts
			(xy 90.56116 -273.88439) (xy 90.56116 -273.83994) (xy 90.361008 -273.83994) (xy 90.361008 -273.88439)
			(xy 90.461084 -273.984466)
		)
		(stroke
			(width 0)
			(type solid)
		)
		(fill yes)
		(layer "In4.Cu")
		(net "M_D_CPU1_SB_CB<3>")
	)
	(gr_poly
		(pts
			(xy 90.56116 -272.668238) (xy 90.461084 -272.568162) (xy 90.361008 -272.668238) (xy 90.361008 -272.712688)
			(xy 90.56116 -272.712688)
		)
		(stroke
			(width 0)
			(type solid)
		)
		(fill yes)
		(layer "In4.Cu")
		(net "M_D_CPU1_SB_CB<0>")
	)
	(gr_poly
		(pts
			(xy 90.56116 -272.264632) (xy 90.56116 -272.21688) (xy 90.361008 -272.21688) (xy 90.361008 -272.264632)
			(xy 90.461084 -272.364454)
		)
		(stroke
			(width 0)
			(type solid)
		)
		(fill yes)
		(layer "In4.Cu")
		(net "M_D_CPU1_SB_DQS_DP<4>")
	)
	(gr_poly
		(pts
			(xy 90.56116 -271.047972) (xy 90.461084 -270.94815) (xy 90.361008 -271.047972) (xy 90.361008 -271.095724)
			(xy 90.56116 -271.095724)
		)
		(stroke
			(width 0)
			(type solid)
		)
		(fill yes)
		(layer "In4.Cu")
		(net "M_D_CPU1_SB_DQS_DP<9>")
	)
	(gr_poly
		(pts
			(xy 90.56116 -270.644366) (xy 90.56116 -270.599916) (xy 90.361008 -270.599916) (xy 90.361008 -270.644366)
			(xy 90.461084 -270.744442)
		)
		(stroke
			(width 0)
			(type solid)
		)
		(fill yes)
		(layer "In4.Cu")
		(net "M_D_CPU1_SB_CB<7>")
	)
	(gr_poly
		(pts
			(xy 90.56116 -269.428214) (xy 90.461084 -269.328138) (xy 90.361008 -269.428214) (xy 90.361008 -269.472664)
			(xy 90.56116 -269.472664)
		)
		(stroke
			(width 0)
			(type solid)
		)
		(fill yes)
		(layer "In4.Cu")
		(net "M_D_CPU1_SB_CB<4>")
	)
	(gr_poly
		(pts
			(xy 90.56116 -265.78433) (xy 90.56116 -265.73988) (xy 90.361008 -265.73988) (xy 90.361008 -265.78433)
			(xy 90.461084 -265.884406)
		)
		(stroke
			(width 0)
			(type solid)
		)
		(fill yes)
		(layer "In4.Cu")
		(net "M_D_CPU1_SB_CS_N<0>")
	)
	(gr_poly
		(pts
			(xy 90.56116 -264.568178) (xy 90.461084 -264.468102) (xy 90.361008 -264.568178) (xy 90.361008 -264.612628)
			(xy 90.56116 -264.612628)
		)
		(stroke
			(width 0)
			(type solid)
		)
		(fill yes)
		(layer "In4.Cu")
		(net "M_D_CPU1_SB_CA<6>")
	)
	(gr_poly
		(pts
			(xy 90.56116 -264.164318) (xy 90.56116 -264.119868) (xy 90.361008 -264.119868) (xy 90.361008 -264.164318)
			(xy 90.461084 -264.264394)
		)
		(stroke
			(width 0)
			(type solid)
		)
		(fill yes)
		(layer "In4.Cu")
		(net "M_D_CPU1_SB_CA<5>")
	)
	(gr_poly
		(pts
			(xy 90.56116 -262.948166) (xy 90.461084 -262.84809) (xy 90.361008 -262.948166) (xy 90.361008 -262.992616)
			(xy 90.56116 -262.992616)
		)
		(stroke
			(width 0)
			(type solid)
		)
		(fill yes)
		(layer "In4.Cu")
		(net "M_D_CPU1_SB_CA<2>")
	)
	(gr_poly
		(pts
			(xy 90.56116 -262.544306) (xy 90.56116 -262.499856) (xy 90.361008 -262.499856) (xy 90.361008 -262.544306)
			(xy 90.461084 -262.644382)
		)
		(stroke
			(width 0)
			(type solid)
		)
		(fill yes)
		(layer "In4.Cu")
		(net "M_D_CPU1_SB_CA<1>")
	)
	(gr_poly
		(pts
			(xy 90.68308 -246.34698) (xy 90.678762 -246.299482) (xy 90.570558 -246.20855) (xy 90.479626 -246.317008)
			(xy 90.48369 -246.364252)
		)
		(stroke
			(width 0)
			(type solid)
		)
		(fill yes)
		(layer "In4.Cu")
		(net "M_D_CPU1_SA_DQS_DP<4>")
	)
	(gr_poly
		(pts
			(xy 90.68308 -241.486944) (xy 90.678762 -241.439446) (xy 90.570558 -241.348514) (xy 90.479626 -241.456972)
			(xy 90.48369 -241.50447)
		)
		(stroke
			(width 0)
			(type solid)
		)
		(fill yes)
		(layer "In4.Cu")
		(net "M_D_CPU1_SA_DQS_DP<3>")
	)
	(gr_poly
		(pts
			(xy 90.68308 -236.626908) (xy 90.678762 -236.57941) (xy 90.570558 -236.488478) (xy 90.479626 -236.596936)
			(xy 90.48369 -236.644434)
		)
		(stroke
			(width 0)
			(type solid)
		)
		(fill yes)
		(layer "In4.Cu")
		(net "M_D_CPU1_SA_DQS_DP<2>")
	)
	(gr_poly
		(pts
			(xy 90.68308 -231.766872) (xy 90.678762 -231.719374) (xy 90.570558 -231.628442) (xy 90.479626 -231.7369)
			(xy 90.48369 -231.784144)
		)
		(stroke
			(width 0)
			(type solid)
		)
		(fill yes)
		(layer "In4.Cu")
		(net "M_D_CPU1_SA_DQS_DP<1>")
	)
	(gr_poly
		(pts
			(xy 90.68308 -226.90709) (xy 90.678762 -226.859592) (xy 90.570558 -226.76866) (xy 90.479626 -226.877118)
			(xy 90.48369 -226.924616)
		)
		(stroke
			(width 0)
			(type solid)
		)
		(fill yes)
		(layer "In4.Cu")
		(net "M_D_CPU1_SA_DQS_DP<0>")
	)
	(gr_poly
		(pts
			(xy 90.693494 -256.06629) (xy 90.68943 -256.018792) (xy 90.581226 -255.92786) (xy 90.490294 -256.036318)
			(xy 90.494358 -256.083816)
		)
		(stroke
			(width 0)
			(type solid)
		)
		(fill yes)
		(layer "In4.Cu")
		(net "M_D_CPU1_CLK_DP<0>")
	)
	(gr_poly
		(pts
			(xy 90.695526 -254.44323) (xy 90.691462 -254.39878) (xy 90.583258 -254.307848) (xy 90.492326 -254.416306)
			(xy 90.496136 -254.460502)
		)
		(stroke
			(width 0)
			(type solid)
		)
		(fill yes)
		(layer "In4.Cu")
		(net "M_D_CPU1_SA_CA<4>")
	)
	(gr_poly
		(pts
			(xy 90.695526 -252.823218) (xy 90.691462 -252.778768) (xy 90.583258 -252.687836) (xy 90.492326 -252.796294)
			(xy 90.496136 -252.84049)
		)
		(stroke
			(width 0)
			(type solid)
		)
		(fill yes)
		(layer "In4.Cu")
		(net "M_D_CPU1_SA_CA<0>")
	)
	(gr_poly
		(pts
			(xy 90.695526 -247.963182) (xy 90.691462 -247.918732) (xy 90.583258 -247.8278) (xy 90.492326 -247.936258)
			(xy 90.496136 -247.980454)
		)
		(stroke
			(width 0)
			(type solid)
		)
		(fill yes)
		(layer "In4.Cu")
		(net "M_D_CPU1_SA_CB<4>")
	)
	(gr_poly
		(pts
			(xy 90.695526 -244.723158) (xy 90.691462 -244.678708) (xy 90.583258 -244.587776) (xy 90.492326 -244.696234)
			(xy 90.496136 -244.74043)
		)
		(stroke
			(width 0)
			(type solid)
		)
		(fill yes)
		(layer "In4.Cu")
		(net "M_D_CPU1_SA_CB<0>")
	)
	(gr_poly
		(pts
			(xy 90.695526 -243.103146) (xy 90.691462 -243.058696) (xy 90.583258 -242.967764) (xy 90.492326 -243.076222)
			(xy 90.496136 -243.120418)
		)
		(stroke
			(width 0)
			(type solid)
		)
		(fill yes)
		(layer "In4.Cu")
		(net "M_D_CPU1_SA_DQ<28>")
	)
	(gr_poly
		(pts
			(xy 90.695526 -239.863122) (xy 90.691462 -239.818672) (xy 90.583258 -239.72774) (xy 90.492326 -239.836198)
			(xy 90.496136 -239.880394)
		)
		(stroke
			(width 0)
			(type solid)
		)
		(fill yes)
		(layer "In4.Cu")
		(net "M_D_CPU1_SA_DQ<24>")
	)
	(gr_poly
		(pts
			(xy 90.695526 -238.24311) (xy 90.691462 -238.19866) (xy 90.583258 -238.107728) (xy 90.492326 -238.216186)
			(xy 90.496136 -238.260382)
		)
		(stroke
			(width 0)
			(type solid)
		)
		(fill yes)
		(layer "In4.Cu")
		(net "M_D_CPU1_SA_DQ<20>")
	)
	(gr_poly
		(pts
			(xy 90.695526 -235.003086) (xy 90.691462 -234.958636) (xy 90.583258 -234.867704) (xy 90.492326 -234.976162)
			(xy 90.496136 -235.020358)
		)
		(stroke
			(width 0)
			(type solid)
		)
		(fill yes)
		(layer "In4.Cu")
		(net "M_D_CPU1_SA_DQ<16>")
	)
	(gr_poly
		(pts
			(xy 90.695526 -233.383074) (xy 90.691462 -233.338624) (xy 90.583258 -233.247692) (xy 90.492326 -233.35615)
			(xy 90.496136 -233.400346)
		)
		(stroke
			(width 0)
			(type solid)
		)
		(fill yes)
		(layer "In4.Cu")
		(net "M_D_CPU1_SA_DQ<12>")
	)
	(gr_poly
		(pts
			(xy 90.695526 -230.14305) (xy 90.691462 -230.0986) (xy 90.583258 -230.007668) (xy 90.492326 -230.116126)
			(xy 90.496136 -230.160322)
		)
		(stroke
			(width 0)
			(type solid)
		)
		(fill yes)
		(layer "In4.Cu")
		(net "M_D_CPU1_SA_DQ<8>")
	)
	(gr_poly
		(pts
			(xy 90.695526 -228.523292) (xy 90.691462 -228.478842) (xy 90.583258 -228.38791) (xy 90.492326 -228.496368)
			(xy 90.496136 -228.540564)
		)
		(stroke
			(width 0)
			(type solid)
		)
		(fill yes)
		(layer "In4.Cu")
		(net "M_D_CPU1_SA_DQ<4>")
	)
	(gr_poly
		(pts
			(xy 90.695526 -225.283268) (xy 90.691462 -225.238818) (xy 90.583258 -225.147886) (xy 90.492326 -225.256344)
			(xy 90.496136 -225.30054)
		)
		(stroke
			(width 0)
			(type solid)
		)
		(fill yes)
		(layer "In4.Cu")
		(net "M_D_CPU1_SA_DQ<0>")
	)
	(gr_poly
		(pts
			(xy 90.731086 -255.622552) (xy 90.731086 -255.578102) (xy 90.530934 -255.578102) (xy 90.530934 -255.622552)
			(xy 90.63101 -255.722628)
		)
		(stroke
			(width 0)
			(type solid)
		)
		(fill yes)
		(layer "In4.Cu")
		(net "M_D_CPU1_SA_PAR")
	)
	(gr_poly
		(pts
			(xy 90.731086 -254.00254) (xy 90.731086 -253.95809) (xy 90.530934 -253.95809) (xy 90.530934 -254.00254)
			(xy 90.63101 -254.102616)
		)
		(stroke
			(width 0)
			(type solid)
		)
		(fill yes)
		(layer "In4.Cu")
		(net "M_D_CPU1_SA_CA<3>")
	)
	(gr_poly
		(pts
			(xy 90.731086 -252.382528) (xy 90.731086 -252.338078) (xy 90.530934 -252.338078) (xy 90.530934 -252.382528)
			(xy 90.63101 -252.482604)
		)
		(stroke
			(width 0)
			(type solid)
		)
		(fill yes)
		(layer "In4.Cu")
		(net "M_D_CPU1_SA_CS_N<1>")
	)
	(gr_poly
		(pts
			(xy 90.731086 -250.762516) (xy 90.731086 -250.718066) (xy 90.530934 -250.718066) (xy 90.530934 -250.762516)
			(xy 90.63101 -250.862592)
		)
		(stroke
			(width 0)
			(type solid)
		)
		(fill yes)
		(layer "In4.Cu")
		(net "M_D_CPU1_RESET_N")
	)
	(gr_poly
		(pts
			(xy 90.731086 -249.142504) (xy 90.731086 -249.098054) (xy 90.530934 -249.098054) (xy 90.530934 -249.142504)
			(xy 90.63101 -249.24258)
		)
		(stroke
			(width 0)
			(type solid)
		)
		(fill yes)
		(layer "In4.Cu")
		(net "M_D_CPU1_SA_CB<7>")
	)
	(gr_poly
		(pts
			(xy 90.731086 -247.522746) (xy 90.731086 -247.474994) (xy 90.530934 -247.474994) (xy 90.530934 -247.522746)
			(xy 90.63101 -247.622568)
		)
		(stroke
			(width 0)
			(type solid)
		)
		(fill yes)
		(layer "In4.Cu")
		(net "M_D_CPU1_SA_DQS_DP<9>")
	)
	(gr_poly
		(pts
			(xy 90.731086 -245.90248) (xy 90.731086 -245.85803) (xy 90.530934 -245.85803) (xy 90.530934 -245.90248)
			(xy 90.63101 -246.002556)
		)
		(stroke
			(width 0)
			(type solid)
		)
		(fill yes)
		(layer "In4.Cu")
		(net "M_D_CPU1_SA_CB<3>")
	)
	(gr_poly
		(pts
			(xy 90.731086 -244.282468) (xy 90.731086 -244.238018) (xy 90.530934 -244.238018) (xy 90.530934 -244.282468)
			(xy 90.63101 -244.382544)
		)
		(stroke
			(width 0)
			(type solid)
		)
		(fill yes)
		(layer "In4.Cu")
		(net "M_D_CPU1_SA_DQ<31>")
	)
	(gr_poly
		(pts
			(xy 90.731086 -242.66271) (xy 90.731086 -242.614958) (xy 90.530934 -242.614958) (xy 90.530934 -242.66271)
			(xy 90.63101 -242.762532)
		)
		(stroke
			(width 0)
			(type solid)
		)
		(fill yes)
		(layer "In4.Cu")
		(net "M_D_CPU1_SA_DQS_DP<8>")
	)
	(gr_poly
		(pts
			(xy 90.731086 -241.042444) (xy 90.731086 -240.997994) (xy 90.530934 -240.997994) (xy 90.530934 -241.042444)
			(xy 90.63101 -241.14252)
		)
		(stroke
			(width 0)
			(type solid)
		)
		(fill yes)
		(layer "In4.Cu")
		(net "M_D_CPU1_SA_DQ<27>")
	)
	(gr_poly
		(pts
			(xy 90.731086 -239.422432) (xy 90.731086 -239.377982) (xy 90.530934 -239.377982) (xy 90.530934 -239.422432)
			(xy 90.63101 -239.522508)
		)
		(stroke
			(width 0)
			(type solid)
		)
		(fill yes)
		(layer "In4.Cu")
		(net "M_D_CPU1_SA_DQ<23>")
	)
	(gr_poly
		(pts
			(xy 90.731086 -237.802674) (xy 90.731086 -237.754922) (xy 90.530934 -237.754922) (xy 90.530934 -237.802674)
			(xy 90.63101 -237.902496)
		)
		(stroke
			(width 0)
			(type solid)
		)
		(fill yes)
		(layer "In4.Cu")
		(net "M_D_CPU1_SA_DQS_DP<7>")
	)
	(gr_poly
		(pts
			(xy 90.731086 -236.182408) (xy 90.731086 -236.137958) (xy 90.530934 -236.137958) (xy 90.530934 -236.182408)
			(xy 90.63101 -236.282484)
		)
		(stroke
			(width 0)
			(type solid)
		)
		(fill yes)
		(layer "In4.Cu")
		(net "M_D_CPU1_SA_DQ<19>")
	)
	(gr_poly
		(pts
			(xy 90.731086 -234.562396) (xy 90.731086 -234.517946) (xy 90.530934 -234.517946) (xy 90.530934 -234.562396)
			(xy 90.63101 -234.662472)
		)
		(stroke
			(width 0)
			(type solid)
		)
		(fill yes)
		(layer "In4.Cu")
		(net "M_D_CPU1_SA_DQ<15>")
	)
	(gr_poly
		(pts
			(xy 90.731086 -232.942638) (xy 90.731086 -232.894886) (xy 90.530934 -232.894886) (xy 90.530934 -232.942638)
			(xy 90.63101 -233.04246)
		)
		(stroke
			(width 0)
			(type solid)
		)
		(fill yes)
		(layer "In4.Cu")
		(net "M_D_CPU1_SA_DQS_DP<6>")
	)
	(gr_poly
		(pts
			(xy 90.731086 -231.322626) (xy 90.731086 -231.278176) (xy 90.530934 -231.278176) (xy 90.530934 -231.322626)
			(xy 90.63101 -231.422702)
		)
		(stroke
			(width 0)
			(type solid)
		)
		(fill yes)
		(layer "In4.Cu")
		(net "M_D_CPU1_SA_DQ<11>")
	)
	(gr_poly
		(pts
			(xy 90.731086 -229.702614) (xy 90.731086 -229.658164) (xy 90.530934 -229.658164) (xy 90.530934 -229.702614)
			(xy 90.63101 -229.80269)
		)
		(stroke
			(width 0)
			(type solid)
		)
		(fill yes)
		(layer "In4.Cu")
		(net "M_D_CPU1_SA_DQ<7>")
	)
	(gr_poly
		(pts
			(xy 90.731086 -228.082856) (xy 90.731086 -228.035104) (xy 90.530934 -228.035104) (xy 90.530934 -228.082856)
			(xy 90.63101 -228.182678)
		)
		(stroke
			(width 0)
			(type solid)
		)
		(fill yes)
		(layer "In4.Cu")
		(net "M_D_CPU1_SA_DQS_DP<5>")
	)
	(gr_poly
		(pts
			(xy 90.731086 -226.46259) (xy 90.731086 -226.41814) (xy 90.530934 -226.41814) (xy 90.530934 -226.46259)
			(xy 90.63101 -226.562666)
		)
		(stroke
			(width 0)
			(type solid)
		)
		(fill yes)
		(layer "In4.Cu")
		(net "M_D_CPU1_SA_DQ<3>")
	)
	(gr_poly
		(pts
			(xy 90.978482 -290.90112) (xy 90.9828 -290.853622) (xy 90.78341 -290.836096) (xy 90.779346 -290.883594)
			(xy 90.870278 -290.992052)
		)
		(stroke
			(width 0)
			(type solid)
		)
		(fill yes)
		(layer "In4.Cu")
		(net "M_D_CPU1_SB_DQS_DN<3>")
	)
	(gr_poly
		(pts
			(xy 90.978482 -286.041338) (xy 90.9828 -285.99384) (xy 90.78341 -285.976568) (xy 90.779346 -286.023812)
			(xy 90.870278 -286.13227)
		)
		(stroke
			(width 0)
			(type solid)
		)
		(fill yes)
		(layer "In4.Cu")
		(net "M_D_CPU1_SB_DQS_DN<2>")
	)
	(gr_poly
		(pts
			(xy 90.978482 -281.181302) (xy 90.9828 -281.133804) (xy 90.78341 -281.116532) (xy 90.779346 -281.163776)
			(xy 90.870278 -281.272234)
		)
		(stroke
			(width 0)
			(type solid)
		)
		(fill yes)
		(layer "In4.Cu")
		(net "M_D_CPU1_SB_DQS_DN<1>")
	)
	(gr_poly
		(pts
			(xy 90.978482 -276.321266) (xy 90.9828 -276.273768) (xy 90.78341 -276.256496) (xy 90.779346 -276.30374)
			(xy 90.870278 -276.412198)
		)
		(stroke
			(width 0)
			(type solid)
		)
		(fill yes)
		(layer "In4.Cu")
		(net "M_D_CPU1_SB_DQS_DN<0>")
	)
	(gr_poly
		(pts
			(xy 90.978482 -271.46123) (xy 90.9828 -271.413732) (xy 90.78341 -271.39646) (xy 90.779346 -271.443704)
			(xy 90.870278 -271.552162)
		)
		(stroke
			(width 0)
			(type solid)
		)
		(fill yes)
		(layer "In4.Cu")
		(net "M_D_CPU1_SB_DQS_DN<9>")
	)
	(gr_poly
		(pts
			(xy 90.991436 -292.52164) (xy 90.995246 -292.477444) (xy 90.79611 -292.460172) (xy 90.792046 -292.504368)
			(xy 90.882978 -292.612572)
		)
		(stroke
			(width 0)
			(type solid)
		)
		(fill yes)
		(layer "In4.Cu")
		(net "M_D_CPU1_SB_DQ<30>")
	)
	(gr_poly
		(pts
			(xy 90.991436 -289.281616) (xy 90.995246 -289.23742) (xy 90.79611 -289.220148) (xy 90.792046 -289.264344)
			(xy 90.882978 -289.372548)
		)
		(stroke
			(width 0)
			(type solid)
		)
		(fill yes)
		(layer "In4.Cu")
		(net "M_D_CPU1_SB_DQ<26>")
	)
	(gr_poly
		(pts
			(xy 90.991436 -287.661858) (xy 90.995246 -287.617662) (xy 90.79611 -287.600136) (xy 90.792046 -287.644586)
			(xy 90.882978 -287.75279)
		)
		(stroke
			(width 0)
			(type solid)
		)
		(fill yes)
		(layer "In4.Cu")
		(net "M_D_CPU1_SB_DQ<22>")
	)
	(gr_poly
		(pts
			(xy 90.991436 -284.422088) (xy 90.995246 -284.377638) (xy 90.79611 -284.360366) (xy 90.792046 -284.404562)
			(xy 90.882978 -284.512766)
		)
		(stroke
			(width 0)
			(type solid)
		)
		(fill yes)
		(layer "In4.Cu")
		(net "M_D_CPU1_SB_DQ<18>")
	)
	(gr_poly
		(pts
			(xy 90.991436 -282.802076) (xy 90.995246 -282.757626) (xy 90.79611 -282.740354) (xy 90.792046 -282.78455)
			(xy 90.882978 -282.892754)
		)
		(stroke
			(width 0)
			(type solid)
		)
		(fill yes)
		(layer "In4.Cu")
		(net "M_D_CPU1_SB_DQ<14>")
	)
	(gr_poly
		(pts
			(xy 90.991436 -279.562052) (xy 90.995246 -279.517602) (xy 90.79611 -279.50033) (xy 90.792046 -279.544526)
			(xy 90.882978 -279.65273)
		)
		(stroke
			(width 0)
			(type solid)
		)
		(fill yes)
		(layer "In4.Cu")
		(net "M_D_CPU1_SB_DQ<10>")
	)
	(gr_poly
		(pts
			(xy 90.991436 -277.94204) (xy 90.995246 -277.89759) (xy 90.79611 -277.880318) (xy 90.792046 -277.924514)
			(xy 90.882978 -278.032718)
		)
		(stroke
			(width 0)
			(type solid)
		)
		(fill yes)
		(layer "In4.Cu")
		(net "M_D_CPU1_SB_DQ<6>")
	)
	(gr_poly
		(pts
			(xy 90.991436 -274.702016) (xy 90.995246 -274.657566) (xy 90.79611 -274.640294) (xy 90.792046 -274.68449)
			(xy 90.882978 -274.792694)
		)
		(stroke
			(width 0)
			(type solid)
		)
		(fill yes)
		(layer "In4.Cu")
		(net "M_D_CPU1_SB_DQ<2>")
	)
	(gr_poly
		(pts
			(xy 90.991436 -273.082004) (xy 90.995246 -273.037554) (xy 90.79611 -273.020282) (xy 90.792046 -273.064478)
			(xy 90.882978 -273.172682)
		)
		(stroke
			(width 0)
			(type solid)
		)
		(fill yes)
		(layer "In4.Cu")
		(net "M_D_CPU1_SB_CB<2>")
	)
	(gr_poly
		(pts
			(xy 90.991436 -269.84198) (xy 90.995246 -269.79753) (xy 90.79611 -269.780258) (xy 90.792046 -269.824454)
			(xy 90.882978 -269.932658)
		)
		(stroke
			(width 0)
			(type solid)
		)
		(fill yes)
		(layer "In4.Cu")
		(net "M_D_CPU1_SB_CB<6>")
	)
	(gr_poly
		(pts
			(xy 90.991436 -266.601956) (xy 90.995246 -266.557506) (xy 90.79611 -266.540234) (xy 90.792046 -266.58443)
			(xy 90.882978 -266.692634)
		)
		(stroke
			(width 0)
			(type solid)
		)
		(fill yes)
		(layer "In4.Cu")
		(net "M_D_CPU1_SB_CS_N<1>")
	)
	(gr_poly
		(pts
			(xy 90.991436 -264.981944) (xy 90.995246 -264.937494) (xy 90.79611 -264.920222) (xy 90.792046 -264.964418)
			(xy 90.882978 -265.072622)
		)
		(stroke
			(width 0)
			(type solid)
		)
		(fill yes)
		(layer "In4.Cu")
		(net "M_D_CPU1_SB_PAR")
	)
	(gr_poly
		(pts
			(xy 90.991436 -263.361932) (xy 90.995246 -263.317482) (xy 90.79611 -263.30021) (xy 90.792046 -263.344406)
			(xy 90.882978 -263.45261)
		)
		(stroke
			(width 0)
			(type solid)
		)
		(fill yes)
		(layer "In4.Cu")
		(net "M_D_CPU1_SB_CA<3>")
	)
	(gr_poly
		(pts
			(xy 91.03106 -292.918134) (xy 90.930984 -292.818058) (xy 90.830908 -292.918134) (xy 90.830908 -292.962584)
			(xy 91.03106 -292.962584)
		)
		(stroke
			(width 0)
			(type solid)
		)
		(fill yes)
		(layer "In4.Cu")
		(net "M_D_CPU1_SB_DQ<29>")
	)
	(gr_poly
		(pts
			(xy 91.03106 -291.297868) (xy 90.930984 -291.198046) (xy 90.830908 -291.297868) (xy 90.830908 -291.34562)
			(xy 91.03106 -291.34562)
		)
		(stroke
			(width 0)
			(type solid)
		)
		(fill yes)
		(layer "In4.Cu")
		(net "M_D_CPU1_SB_DQS_DN<8>")
	)
	(gr_poly
		(pts
			(xy 91.03106 -289.67811) (xy 90.930984 -289.578034) (xy 90.830908 -289.67811) (xy 90.830908 -289.72256)
			(xy 91.03106 -289.72256)
		)
		(stroke
			(width 0)
			(type solid)
		)
		(fill yes)
		(layer "In4.Cu")
		(net "M_D_CPU1_SB_DQ<25>")
	)
	(gr_poly
		(pts
			(xy 91.03106 -288.058098) (xy 90.930984 -287.958022) (xy 90.830908 -288.058098) (xy 90.830908 -288.102548)
			(xy 91.03106 -288.102548)
		)
		(stroke
			(width 0)
			(type solid)
		)
		(fill yes)
		(layer "In4.Cu")
		(net "M_D_CPU1_SB_DQ<21>")
	)
	(gr_poly
		(pts
			(xy 91.03106 -286.438086) (xy 90.930984 -286.33801) (xy 90.830908 -286.438086) (xy 90.830908 -286.485838)
			(xy 91.03106 -286.485838)
		)
		(stroke
			(width 0)
			(type solid)
		)
		(fill yes)
		(layer "In4.Cu")
		(net "M_D_CPU1_SB_DQS_DN<7>")
	)
	(gr_poly
		(pts
			(xy 91.03106 -284.818328) (xy 90.930984 -284.718252) (xy 90.830908 -284.818328) (xy 90.830908 -284.862778)
			(xy 91.03106 -284.862778)
		)
		(stroke
			(width 0)
			(type solid)
		)
		(fill yes)
		(layer "In4.Cu")
		(net "M_D_CPU1_SB_DQ<17>")
	)
	(gr_poly
		(pts
			(xy 91.03106 -283.198316) (xy 90.930984 -283.09824) (xy 90.830908 -283.198316) (xy 90.830908 -283.242766)
			(xy 91.03106 -283.242766)
		)
		(stroke
			(width 0)
			(type solid)
		)
		(fill yes)
		(layer "In4.Cu")
		(net "M_D_CPU1_SB_DQ<13>")
	)
	(gr_poly
		(pts
			(xy 91.03106 -281.57805) (xy 90.930984 -281.478228) (xy 90.830908 -281.57805) (xy 90.830908 -281.625802)
			(xy 91.03106 -281.625802)
		)
		(stroke
			(width 0)
			(type solid)
		)
		(fill yes)
		(layer "In4.Cu")
		(net "M_D_CPU1_SB_DQS_DN<6>")
	)
	(gr_poly
		(pts
			(xy 91.03106 -279.958292) (xy 90.930984 -279.858216) (xy 90.830908 -279.958292) (xy 90.830908 -280.002742)
			(xy 91.03106 -280.002742)
		)
		(stroke
			(width 0)
			(type solid)
		)
		(fill yes)
		(layer "In4.Cu")
		(net "M_D_CPU1_SB_DQ<9>")
	)
	(gr_poly
		(pts
			(xy 91.03106 -278.33828) (xy 90.930984 -278.238204) (xy 90.830908 -278.33828) (xy 90.830908 -278.38273)
			(xy 91.03106 -278.38273)
		)
		(stroke
			(width 0)
			(type solid)
		)
		(fill yes)
		(layer "In4.Cu")
		(net "M_D_CPU1_SB_DQ<5>")
	)
	(gr_poly
		(pts
			(xy 91.03106 -275.098256) (xy 90.930984 -274.99818) (xy 90.830908 -275.098256) (xy 90.830908 -275.142706)
			(xy 91.03106 -275.142706)
		)
		(stroke
			(width 0)
			(type solid)
		)
		(fill yes)
		(layer "In4.Cu")
		(net "M_D_CPU1_SB_DQ<1>")
	)
	(gr_poly
		(pts
			(xy 91.03106 -273.478244) (xy 90.930984 -273.378168) (xy 90.830908 -273.478244) (xy 90.830908 -273.522694)
			(xy 91.03106 -273.522694)
		)
		(stroke
			(width 0)
			(type solid)
		)
		(fill yes)
		(layer "In4.Cu")
		(net "M_D_CPU1_SB_CB<1>")
	)
	(gr_poly
		(pts
			(xy 91.03106 -271.857978) (xy 90.930984 -271.758156) (xy 90.830908 -271.857978) (xy 90.830908 -271.90573)
			(xy 91.03106 -271.90573)
		)
		(stroke
			(width 0)
			(type solid)
		)
		(fill yes)
		(layer "In4.Cu")
		(net "M_D_CPU1_SB_DQS_DN<4>")
	)
	(gr_poly
		(pts
			(xy 91.03106 -270.23822) (xy 90.930984 -270.138144) (xy 90.830908 -270.23822) (xy 90.830908 -270.28267)
			(xy 91.03106 -270.28267)
		)
		(stroke
			(width 0)
			(type solid)
		)
		(fill yes)
		(layer "In4.Cu")
		(net "M_D_CPU1_SB_CB<5>")
	)
	(gr_poly
		(pts
			(xy 91.03106 -263.758172) (xy 90.930984 -263.658096) (xy 90.830908 -263.758172) (xy 90.830908 -263.802622)
			(xy 91.03106 -263.802622)
		)
		(stroke
			(width 0)
			(type solid)
		)
		(fill yes)
		(layer "In4.Cu")
		(net "M_D_CPU1_SB_CA<4>")
	)
	(gr_poly
		(pts
			(xy 91.03106 -262.13816) (xy 90.930984 -262.038084) (xy 90.830908 -262.13816) (xy 90.830908 -262.18261)
			(xy 91.03106 -262.18261)
		)
		(stroke
			(width 0)
			(type solid)
		)
		(fill yes)
		(layer "In4.Cu")
		(net "M_D_CPU1_SB_CA<0>")
	)
	(gr_poly
		(pts
			(xy 91.037156 -266.991846) (xy 90.937334 -266.89177) (xy 90.837258 -266.991846) (xy 90.837258 -267.036296)
			(xy 91.037156 -267.036296)
		)
		(stroke
			(width 0)
			(type solid)
		)
		(fill yes)
		(layer "In4.Cu")
		(net "M_D_CPU1_SA_RSP<0>")
	)
	(gr_poly
		(pts
			(xy 91.038426 -276.718268) (xy 90.93835 -276.618192) (xy 90.838274 -276.718268) (xy 90.838274 -276.765766)
			(xy 91.038426 -276.765766)
		)
		(stroke
			(width 0)
			(type solid)
		)
		(fill yes)
		(layer "In4.Cu")
		(net "M_D_CPU1_SB_DQS_DN<5>")
	)
	(gr_poly
		(pts
			(xy 91.200986 -255.216406) (xy 91.10091 -255.11633) (xy 91.000834 -255.216406) (xy 91.000834 -255.260856)
			(xy 91.200986 -255.260856)
		)
		(stroke
			(width 0)
			(type solid)
		)
		(fill yes)
		(layer "In4.Cu")
		(net "M_D_CPU1_SA_CA<6>")
	)
	(gr_poly
		(pts
			(xy 91.200986 -253.596394) (xy 91.10091 -253.496318) (xy 91.000834 -253.596394) (xy 91.000834 -253.640844)
			(xy 91.200986 -253.640844)
		)
		(stroke
			(width 0)
			(type solid)
		)
		(fill yes)
		(layer "In4.Cu")
		(net "M_D_CPU1_SA_CA<2>")
	)
	(gr_poly
		(pts
			(xy 91.200986 -248.736358) (xy 91.10091 -248.636282) (xy 91.000834 -248.736358) (xy 91.000834 -248.780808)
			(xy 91.200986 -248.780808)
		)
		(stroke
			(width 0)
			(type solid)
		)
		(fill yes)
		(layer "In4.Cu")
		(net "M_D_CPU1_SA_CB<5>")
	)
	(gr_poly
		(pts
			(xy 91.200986 -247.116092) (xy 91.10091 -247.01627) (xy 91.000834 -247.116092) (xy 91.000834 -247.163844)
			(xy 91.200986 -247.163844)
		)
		(stroke
			(width 0)
			(type solid)
		)
		(fill yes)
		(layer "In4.Cu")
		(net "M_D_CPU1_SA_DQS_DN<9>")
	)
	(gr_poly
		(pts
			(xy 91.200986 -245.496334) (xy 91.10091 -245.396258) (xy 91.000834 -245.496334) (xy 91.000834 -245.540784)
			(xy 91.200986 -245.540784)
		)
		(stroke
			(width 0)
			(type solid)
		)
		(fill yes)
		(layer "In4.Cu")
		(net "M_D_CPU1_SA_CB<1>")
	)
	(gr_poly
		(pts
			(xy 91.200986 -243.876322) (xy 91.10091 -243.776246) (xy 91.000834 -243.876322) (xy 91.000834 -243.920772)
			(xy 91.200986 -243.920772)
		)
		(stroke
			(width 0)
			(type solid)
		)
		(fill yes)
		(layer "In4.Cu")
		(net "M_D_CPU1_SA_DQ<29>")
	)
	(gr_poly
		(pts
			(xy 91.200986 -242.256056) (xy 91.10091 -242.156234) (xy 91.000834 -242.256056) (xy 91.000834 -242.303808)
			(xy 91.200986 -242.303808)
		)
		(stroke
			(width 0)
			(type solid)
		)
		(fill yes)
		(layer "In4.Cu")
		(net "M_D_CPU1_SA_DQS_DN<8>")
	)
	(gr_poly
		(pts
			(xy 91.200986 -240.636298) (xy 91.10091 -240.536222) (xy 91.000834 -240.636298) (xy 91.000834 -240.680748)
			(xy 91.200986 -240.680748)
		)
		(stroke
			(width 0)
			(type solid)
		)
		(fill yes)
		(layer "In4.Cu")
		(net "M_D_CPU1_SA_DQ<25>")
	)
	(gr_poly
		(pts
			(xy 91.200986 -239.016286) (xy 91.10091 -238.91621) (xy 91.000834 -239.016286) (xy 91.000834 -239.060736)
			(xy 91.200986 -239.060736)
		)
		(stroke
			(width 0)
			(type solid)
		)
		(fill yes)
		(layer "In4.Cu")
		(net "M_D_CPU1_SA_DQ<21>")
	)
	(gr_poly
		(pts
			(xy 91.200986 -237.39602) (xy 91.10091 -237.296198) (xy 91.000834 -237.39602) (xy 91.000834 -237.443772)
			(xy 91.200986 -237.443772)
		)
		(stroke
			(width 0)
			(type solid)
		)
		(fill yes)
		(layer "In4.Cu")
		(net "M_D_CPU1_SA_DQS_DN<7>")
	)
	(gr_poly
		(pts
			(xy 91.200986 -235.776262) (xy 91.10091 -235.676186) (xy 91.000834 -235.776262) (xy 91.000834 -235.820712)
			(xy 91.200986 -235.820712)
		)
		(stroke
			(width 0)
			(type solid)
		)
		(fill yes)
		(layer "In4.Cu")
		(net "M_D_CPU1_SA_DQ<17>")
	)
	(gr_poly
		(pts
			(xy 91.200986 -234.15625) (xy 91.10091 -234.056174) (xy 91.000834 -234.15625) (xy 91.000834 -234.2007)
			(xy 91.200986 -234.2007)
		)
		(stroke
			(width 0)
			(type solid)
		)
		(fill yes)
		(layer "In4.Cu")
		(net "M_D_CPU1_SA_DQ<13>")
	)
	(gr_poly
		(pts
			(xy 91.200986 -232.535984) (xy 91.10091 -232.436162) (xy 91.000834 -232.535984) (xy 91.000834 -232.583736)
			(xy 91.200986 -232.583736)
		)
		(stroke
			(width 0)
			(type solid)
		)
		(fill yes)
		(layer "In4.Cu")
		(net "M_D_CPU1_SA_DQS_DN<6>")
	)
	(gr_poly
		(pts
			(xy 91.200986 -230.916226) (xy 91.10091 -230.81615) (xy 91.000834 -230.916226) (xy 91.000834 -230.960676)
			(xy 91.200986 -230.960676)
		)
		(stroke
			(width 0)
			(type solid)
		)
		(fill yes)
		(layer "In4.Cu")
		(net "M_D_CPU1_SA_DQ<9>")
	)
	(gr_poly
		(pts
			(xy 91.200986 -229.296214) (xy 91.10091 -229.196138) (xy 91.000834 -229.296214) (xy 91.000834 -229.340664)
			(xy 91.200986 -229.340664)
		)
		(stroke
			(width 0)
			(type solid)
		)
		(fill yes)
		(layer "In4.Cu")
		(net "M_D_CPU1_SA_DQ<5>")
	)
	(gr_poly
		(pts
			(xy 91.200986 -226.056444) (xy 91.10091 -225.956368) (xy 91.000834 -226.056444) (xy 91.000834 -226.100894)
			(xy 91.200986 -226.100894)
		)
		(stroke
			(width 0)
			(type solid)
		)
		(fill yes)
		(layer "In4.Cu")
		(net "M_D_CPU1_SA_DQ<1>")
	)
	(gr_poly
		(pts
			(xy 91.20124 -250.35637) (xy 91.101164 -250.256294) (xy 91.001088 -250.35637) (xy 91.001088 -250.40082)
			(xy 91.20124 -250.40082)
		)
		(stroke
			(width 0)
			(type solid)
		)
		(fill yes)
		(layer "In4.Cu")
		(net "M_D_CPU1_ALERT_R_N")
	)
	(gr_poly
		(pts
			(xy 91.207082 -227.67671) (xy 91.107006 -227.576634) (xy 91.00693 -227.67671) (xy 91.00693 -227.724208)
			(xy 91.207082 -227.724208)
		)
		(stroke
			(width 0)
			(type solid)
		)
		(fill yes)
		(layer "In4.Cu")
		(net "M_D_CPU1_SA_DQS_DN<5>")
	)
	(gr_poly
		(pts
			(xy 91.501214 -291.704522) (xy 91.501214 -291.65677) (xy 91.301062 -291.65677) (xy 91.301062 -291.704522)
			(xy 91.401138 -291.804344)
		)
		(stroke
			(width 0)
			(type solid)
		)
		(fill yes)
		(layer "In4.Cu")
		(net "M_D_CPU1_SB_DQS_DP<8>")
	)
	(gr_poly
		(pts
			(xy 91.501214 -290.084256) (xy 91.501214 -290.039806) (xy 91.301062 -290.039806) (xy 91.301062 -290.084256)
			(xy 91.401138 -290.184332)
		)
		(stroke
			(width 0)
			(type solid)
		)
		(fill yes)
		(layer "In4.Cu")
		(net "M_D_CPU1_SB_DQ<27>")
	)
	(gr_poly
		(pts
			(xy 91.501214 -288.464498) (xy 91.501214 -288.420048) (xy 91.301062 -288.420048) (xy 91.301062 -288.464498)
			(xy 91.401138 -288.564574)
		)
		(stroke
			(width 0)
			(type solid)
		)
		(fill yes)
		(layer "In4.Cu")
		(net "M_D_CPU1_SB_DQ<23>")
	)
	(gr_poly
		(pts
			(xy 91.501214 -286.844486) (xy 91.501214 -286.796734) (xy 91.301062 -286.796734) (xy 91.301062 -286.844486)
			(xy 91.401138 -286.944562)
		)
		(stroke
			(width 0)
			(type solid)
		)
		(fill yes)
		(layer "In4.Cu")
		(net "M_D_CPU1_SB_DQS_DP<7>")
	)
	(gr_poly
		(pts
			(xy 91.501214 -285.224474) (xy 91.501214 -285.180024) (xy 91.301062 -285.180024) (xy 91.301062 -285.224474)
			(xy 91.401138 -285.32455)
		)
		(stroke
			(width 0)
			(type solid)
		)
		(fill yes)
		(layer "In4.Cu")
		(net "M_D_CPU1_SB_DQ<19>")
	)
	(gr_poly
		(pts
			(xy 91.501214 -283.604462) (xy 91.501214 -283.560012) (xy 91.301062 -283.560012) (xy 91.301062 -283.604462)
			(xy 91.401138 -283.704538)
		)
		(stroke
			(width 0)
			(type solid)
		)
		(fill yes)
		(layer "In4.Cu")
		(net "M_D_CPU1_SB_DQ<15>")
	)
	(gr_poly
		(pts
			(xy 91.501214 -281.984704) (xy 91.501214 -281.936952) (xy 91.301062 -281.936952) (xy 91.301062 -281.984704)
			(xy 91.401138 -282.084526)
		)
		(stroke
			(width 0)
			(type solid)
		)
		(fill yes)
		(layer "In4.Cu")
		(net "M_D_CPU1_SB_DQS_DP<6>")
	)
	(gr_poly
		(pts
			(xy 91.501214 -280.364438) (xy 91.501214 -280.319988) (xy 91.301062 -280.319988) (xy 91.301062 -280.364438)
			(xy 91.401138 -280.464514)
		)
		(stroke
			(width 0)
			(type solid)
		)
		(fill yes)
		(layer "In4.Cu")
		(net "M_D_CPU1_SB_DQ<11>")
	)
	(gr_poly
		(pts
			(xy 91.501214 -278.744426) (xy 91.501214 -278.699976) (xy 91.301062 -278.699976) (xy 91.301062 -278.744426)
			(xy 91.401138 -278.844502)
		)
		(stroke
			(width 0)
			(type solid)
		)
		(fill yes)
		(layer "In4.Cu")
		(net "M_D_CPU1_SB_DQ<7>")
	)
	(gr_poly
		(pts
			(xy 91.501214 -277.124668) (xy 91.501214 -277.076916) (xy 91.301062 -277.076916) (xy 91.301062 -277.124668)
			(xy 91.401138 -277.22449)
		)
		(stroke
			(width 0)
			(type solid)
		)
		(fill yes)
		(layer "In4.Cu")
		(net "M_D_CPU1_SB_DQS_DP<5>")
	)
	(gr_poly
		(pts
			(xy 91.501214 -275.504402) (xy 91.501214 -275.459952) (xy 91.301062 -275.459952) (xy 91.301062 -275.504402)
			(xy 91.401138 -275.604478)
		)
		(stroke
			(width 0)
			(type solid)
		)
		(fill yes)
		(layer "In4.Cu")
		(net "M_D_CPU1_SB_DQ<3>")
	)
	(gr_poly
		(pts
			(xy 91.501214 -273.88439) (xy 91.501214 -273.83994) (xy 91.301062 -273.83994) (xy 91.301062 -273.88439)
			(xy 91.401138 -273.984466)
		)
		(stroke
			(width 0)
			(type solid)
		)
		(fill yes)
		(layer "In4.Cu")
		(net "M_D_CPU1_SB_CB<3>")
	)
	(gr_poly
		(pts
			(xy 91.501214 -272.264632) (xy 91.501214 -272.21688) (xy 91.301062 -272.21688) (xy 91.301062 -272.264632)
			(xy 91.401138 -272.364454)
		)
		(stroke
			(width 0)
			(type solid)
		)
		(fill yes)
		(layer "In4.Cu")
		(net "M_D_CPU1_SB_DQS_DP<4>")
	)
	(gr_poly
		(pts
			(xy 91.501214 -270.644366) (xy 91.501214 -270.599916) (xy 91.301062 -270.599916) (xy 91.301062 -270.644366)
			(xy 91.401138 -270.744442)
		)
		(stroke
			(width 0)
			(type solid)
		)
		(fill yes)
		(layer "In4.Cu")
		(net "M_D_CPU1_SB_CB<7>")
	)
	(gr_poly
		(pts
			(xy 91.501214 -265.78433) (xy 91.501214 -265.73988) (xy 91.301062 -265.73988) (xy 91.301062 -265.78433)
			(xy 91.401138 -265.884406)
		)
		(stroke
			(width 0)
			(type solid)
		)
		(fill yes)
		(layer "In4.Cu")
		(net "M_D_CPU1_SB_CS_N<0>")
	)
	(gr_poly
		(pts
			(xy 91.501214 -264.164318) (xy 91.501214 -264.119868) (xy 91.301062 -264.119868) (xy 91.301062 -264.164318)
			(xy 91.401138 -264.264394)
		)
		(stroke
			(width 0)
			(type solid)
		)
		(fill yes)
		(layer "In4.Cu")
		(net "M_D_CPU1_SB_CA<5>")
	)
	(gr_poly
		(pts
			(xy 91.501214 -262.544306) (xy 91.501214 -262.499856) (xy 91.301062 -262.499856) (xy 91.301062 -262.544306)
			(xy 91.401138 -262.644382)
		)
		(stroke
			(width 0)
			(type solid)
		)
		(fill yes)
		(layer "In4.Cu")
		(net "M_D_CPU1_SB_CA<1>")
	)
	(gr_poly
		(pts
			(xy 91.67114 -255.622552) (xy 91.67114 -255.578102) (xy 91.470988 -255.578102) (xy 91.470988 -255.622552)
			(xy 91.571064 -255.722628)
		)
		(stroke
			(width 0)
			(type solid)
		)
		(fill yes)
		(layer "In4.Cu")
		(net "M_D_CPU1_SA_PAR")
	)
	(gr_poly
		(pts
			(xy 91.67114 -254.00254) (xy 91.67114 -253.95809) (xy 91.470988 -253.95809) (xy 91.470988 -254.00254)
			(xy 91.571064 -254.102616)
		)
		(stroke
			(width 0)
			(type solid)
		)
		(fill yes)
		(layer "In4.Cu")
		(net "M_D_CPU1_SA_CA<3>")
	)
	(gr_poly
		(pts
			(xy 91.67114 -252.382528) (xy 91.67114 -252.338078) (xy 91.470988 -252.338078) (xy 91.470988 -252.382528)
			(xy 91.571064 -252.482604)
		)
		(stroke
			(width 0)
			(type solid)
		)
		(fill yes)
		(layer "In4.Cu")
		(net "M_D_CPU1_SA_CS_N<1>")
	)
	(gr_poly
		(pts
			(xy 91.67114 -250.762516) (xy 91.67114 -250.718066) (xy 91.470988 -250.718066) (xy 91.470988 -250.762516)
			(xy 91.571064 -250.862592)
		)
		(stroke
			(width 0)
			(type solid)
		)
		(fill yes)
		(layer "In4.Cu")
		(net "M_D_CPU1_RESET_N")
	)
	(gr_poly
		(pts
			(xy 91.67114 -249.142504) (xy 91.67114 -249.098054) (xy 91.470988 -249.098054) (xy 91.470988 -249.142504)
			(xy 91.571064 -249.24258)
		)
		(stroke
			(width 0)
			(type solid)
		)
		(fill yes)
		(layer "In4.Cu")
		(net "M_D_CPU1_SA_CB<7>")
	)
	(gr_poly
		(pts
			(xy 91.67114 -247.522746) (xy 91.67114 -247.474994) (xy 91.470988 -247.474994) (xy 91.470988 -247.522746)
			(xy 91.571064 -247.622568)
		)
		(stroke
			(width 0)
			(type solid)
		)
		(fill yes)
		(layer "In4.Cu")
		(net "M_D_CPU1_SA_DQS_DP<9>")
	)
	(gr_poly
		(pts
			(xy 91.67114 -245.90248) (xy 91.67114 -245.85803) (xy 91.470988 -245.85803) (xy 91.470988 -245.90248)
			(xy 91.571064 -246.002556)
		)
		(stroke
			(width 0)
			(type solid)
		)
		(fill yes)
		(layer "In4.Cu")
		(net "M_D_CPU1_SA_CB<3>")
	)
	(gr_poly
		(pts
			(xy 91.67114 -244.282468) (xy 91.67114 -244.238018) (xy 91.470988 -244.238018) (xy 91.470988 -244.282468)
			(xy 91.571064 -244.382544)
		)
		(stroke
			(width 0)
			(type solid)
		)
		(fill yes)
		(layer "In4.Cu")
		(net "M_D_CPU1_SA_DQ<31>")
	)
	(gr_poly
		(pts
			(xy 91.67114 -242.66271) (xy 91.67114 -242.614958) (xy 91.470988 -242.614958) (xy 91.470988 -242.66271)
			(xy 91.571064 -242.762532)
		)
		(stroke
			(width 0)
			(type solid)
		)
		(fill yes)
		(layer "In4.Cu")
		(net "M_D_CPU1_SA_DQS_DP<8>")
	)
	(gr_poly
		(pts
			(xy 91.67114 -241.042444) (xy 91.67114 -240.997994) (xy 91.470988 -240.997994) (xy 91.470988 -241.042444)
			(xy 91.571064 -241.14252)
		)
		(stroke
			(width 0)
			(type solid)
		)
		(fill yes)
		(layer "In4.Cu")
		(net "M_D_CPU1_SA_DQ<27>")
	)
	(gr_poly
		(pts
			(xy 91.67114 -239.422432) (xy 91.67114 -239.377982) (xy 91.470988 -239.377982) (xy 91.470988 -239.422432)
			(xy 91.571064 -239.522508)
		)
		(stroke
			(width 0)
			(type solid)
		)
		(fill yes)
		(layer "In4.Cu")
		(net "M_D_CPU1_SA_DQ<23>")
	)
	(gr_poly
		(pts
			(xy 91.67114 -237.802674) (xy 91.67114 -237.754922) (xy 91.470988 -237.754922) (xy 91.470988 -237.802674)
			(xy 91.571064 -237.902496)
		)
		(stroke
			(width 0)
			(type solid)
		)
		(fill yes)
		(layer "In4.Cu")
		(net "M_D_CPU1_SA_DQS_DP<7>")
	)
	(gr_poly
		(pts
			(xy 91.67114 -236.182408) (xy 91.67114 -236.137958) (xy 91.470988 -236.137958) (xy 91.470988 -236.182408)
			(xy 91.571064 -236.282484)
		)
		(stroke
			(width 0)
			(type solid)
		)
		(fill yes)
		(layer "In4.Cu")
		(net "M_D_CPU1_SA_DQ<19>")
	)
	(gr_poly
		(pts
			(xy 91.67114 -234.562396) (xy 91.67114 -234.517946) (xy 91.470988 -234.517946) (xy 91.470988 -234.562396)
			(xy 91.571064 -234.662472)
		)
		(stroke
			(width 0)
			(type solid)
		)
		(fill yes)
		(layer "In4.Cu")
		(net "M_D_CPU1_SA_DQ<15>")
	)
)
